(kicad_pcb
	(version 20260206)
	(generator "pcbnew")
	(generator_version "10.0")
	(general
		(thickness 1.6)
		(legacy_teardrops no)
	)
	(paper "A4")
	(layers
		(0 "F.Cu" signal "TOP")
		(4 "In1.Cu" signal "GND")
		(6 "In2.Cu" signal "VCC")
		(8 "In3.Cu" signal "VCC1")
		(10 "In4.Cu" signal "GND1")
		(12 "In5.Cu" signal "IN1")
		(14 "In6.Cu" signal "GND2")
		(16 "In7.Cu" signal "IN2")
		(18 "In8.Cu" signal "GND3")
		(20 "In9.Cu" signal "IN3")
		(22 "In10.Cu" signal "GND4")
		(24 "In11.Cu" signal "IN4")
		(26 "In12.Cu" signal "GND5")
		(28 "In13.Cu" signal "IN5")
		(30 "In14.Cu" signal "GND6")
		(32 "In15.Cu" signal "IN6")
		(34 "In16.Cu" signal "GND7")
		(2 "B.Cu" signal "BOTTOM")
		(9 "F.Adhes" user "F.Adhesive")
		(11 "B.Adhes" user "B.Adhesive")
		(13 "F.Paste" user "Package Geometry/Pastemask Top")
		(15 "B.Paste" user "Package Geometry/Pastemask Bottom")
		(5 "F.SilkS" user "Ref Des/Silkscreen Top")
		(7 "B.SilkS" user "Ref Des/Silkscreen Bottom")
		(1 "F.Mask" user "Board Geometry/Soldermask Top")
		(3 "B.Mask" user "Board Geometry/Soldermask Bottom")
		(17 "Dwgs.User" user "User.Drawings")
		(19 "Cmts.User" user "User.Comments")
		(21 "Eco1.User" user "User.Eco1")
		(23 "Eco2.User" user "User.Eco2")
		(25 "Edge.Cuts" user "Board Geometry/Outline")
		(27 "Margin" user)
		(31 "F.CrtYd" user "Package Geometry/Place Bound Top")
		(29 "B.CrtYd" user "Package Geometry/Place Bound Bottom")
		(35 "F.Fab" user "Ref Des/Assembly Top")
		(33 "B.Fab" user "Ref Des/Assembly Bottom")
	)
	(setup
		(pad_to_mask_clearance 0)
		(allow_soldermask_bridges_in_footprints no)
		(tenting
			(front yes)
			(back yes)
		)
		(covering
			(front no)
			(back no)
		)
		(plugging
			(front no)
			(back no)
		)
		(capping no)
		(filling no)
		(pcbplotparams
			(layerselection 0x00000000_00000000_55555555_5755f5ff)
			(plot_on_all_layers_selection 0x00000000_00000000_00000000_00000000)
			(disableapertmacros no)
			(usegerberextensions no)
			(usegerberattributes yes)
			(usegerberadvancedattributes yes)
			(creategerberjobfile yes)
			(dashed_line_dash_ratio 12)
			(dashed_line_gap_ratio 3)
			(svgprecision 4)
			(plotframeref no)
			(mode 1)
			(useauxorigin no)
			(pdf_front_fp_property_popups yes)
			(pdf_back_fp_property_popups yes)
			(pdf_metadata yes)
			(pdf_single_document no)
			(dxfpolygonmode yes)
			(dxfimperialunits yes)
			(dxfusepcbnewfont yes)
			(psnegative no)
			(psa4output no)
			(plot_black_and_white yes)
			(sketchpadsonfab no)
			(plotpadnumbers no)
			(hidednponfab no)
			(sketchdnponfab yes)
			(crossoutdnponfab yes)
			(subtractmaskfromsilk no)
			(outputformat 1)
			(mirror no)
			(drillshape 1)
			(scaleselection 1)
			(outputdirectory "")
		)
	)
	(gr_poly
		(pts
			(xy 408.031696 -310.636412) (xy 408.042624 -310.635889) (xy 408.062501 -310.626804) (xy 408.07005 -310.618886)
			(xy 408.093672 -310.592724) (xy 408.111198 -310.574436) (xy 408.111452 -310.574182) (xy 408.11577 -310.56961)
			(xy 408.129486 -310.547004) (xy 408.131264 -310.5404) (xy 408.134899 -310.528212) (xy 408.143926 -310.504431)
			(xy 408.149298 -310.492902) (xy 408.153355 -310.48323) (xy 408.154089 -310.462291) (xy 408.146395 -310.442804)
			(xy 408.131556 -310.428013) (xy 408.112044 -310.420383) (xy 408.091108 -310.421186) (xy 408.08148 -310.425338)
			(xy 408.060828 -310.434715) (xy 408.017446 -310.447952) (xy 407.972586 -310.454637) (xy 407.949908 -310.455056)
			(xy 407.924646 -310.454564) (xy 407.874811 -310.446249) (xy 407.827024 -310.429845) (xy 407.782588 -310.405799)
			(xy 407.742717 -310.374767) (xy 407.708498 -310.337595) (xy 407.680863 -310.295298) (xy 407.660567 -310.24903)
			(xy 407.648164 -310.200052) (xy 407.643992 -310.1497) (xy 407.648164 -310.099348) (xy 407.660567 -310.05037)
			(xy 407.680863 -310.004102) (xy 407.708498 -309.961805) (xy 407.742717 -309.924633) (xy 407.782588 -309.893601)
			(xy 407.827024 -309.869555) (xy 407.874811 -309.853151) (xy 407.924646 -309.844836) (xy 407.949908 -309.84444)
			(xy 407.96409 -309.844627) (xy 407.99233 -309.847301) (xy 408.006296 -309.849774) (xy 408.018742 -309.85206)
			(xy 408.042364 -309.844694) (xy 408.119834 -309.767224) (xy 408.1272 -309.743602) (xy 408.124914 -309.731156)
			(xy 408.12243 -309.717191) (xy 408.119761 -309.688951) (xy 408.11958 -309.674768) (xy 408.120053 -309.650778)
			(xy 408.127563 -309.60339) (xy 408.142393 -309.557759) (xy 408.164178 -309.51501) (xy 408.192382 -309.476195)
			(xy 408.22631 -309.442269) (xy 408.265127 -309.414068) (xy 408.307878 -309.392285) (xy 408.353509 -309.377458)
			(xy 408.400898 -309.369951) (xy 408.424888 -309.36946) (xy 408.439071 -309.369646) (xy 408.46731 -309.372318)
			(xy 408.481276 -309.374794) (xy 408.493722 -309.37708) (xy 408.517344 -309.369714) (xy 408.594814 -309.292244)
			(xy 408.60218 -309.268622) (xy 408.599894 -309.256176) (xy 408.59741 -309.242211) (xy 408.594739 -309.213971)
			(xy 408.59456 -309.199788) (xy 408.594747 -309.185606) (xy 408.597421 -309.157366) (xy 408.599894 -309.1434)
			(xy 408.60218 -309.130954) (xy 408.594814 -309.107332) (xy 408.517344 -309.029862) (xy 408.493722 -309.022496)
			(xy 408.481276 -309.024782) (xy 408.467311 -309.027267) (xy 408.439071 -309.029938) (xy 408.424888 -309.030116)
			(xy 408.400067 -309.029629) (xy 408.351078 -309.021596) (xy 408.304034 -309.005743) (xy 408.260175 -308.982488)
			(xy 408.220656 -308.952444) (xy 408.186518 -308.916402) (xy 408.158661 -308.875313) (xy 408.137818 -308.830257)
			(xy 408.124538 -308.782423) (xy 408.119173 -308.733071) (xy 408.121862 -308.683501) (xy 408.132536 -308.635019)
			(xy 408.150912 -308.588903) (xy 408.176507 -308.546367) (xy 408.208646 -308.508532) (xy 408.246483 -308.476395)
			(xy 408.289021 -308.450803) (xy 408.335139 -308.43243) (xy 408.383621 -308.421759) (xy 408.433191 -308.419073)
			(xy 408.482543 -308.424442) (xy 408.530376 -308.437725) (xy 408.57543 -308.45857) (xy 408.616518 -308.48643)
			(xy 408.652558 -308.520571) (xy 408.682599 -308.560092) (xy 408.705851 -308.603953) (xy 408.721701 -308.650997)
			(xy 408.729731 -308.699987) (xy 408.730196 -308.724808) (xy 408.730009 -308.73899) (xy 408.727335 -308.76723)
			(xy 408.724862 -308.781196) (xy 408.722576 -308.793642) (xy 408.729942 -308.817264) (xy 408.807412 -308.894734)
			(xy 408.831034 -308.9021) (xy 408.84348 -308.899814) (xy 408.857445 -308.897327) (xy 408.885685 -308.894652)
			(xy 408.899868 -308.89448) (xy 408.914051 -308.894665) (xy 408.94229 -308.897336) (xy 408.956256 -308.899814)
			(xy 408.968702 -308.9021) (xy 408.992324 -308.894734) (xy 409.069794 -308.817264) (xy 409.07716 -308.793642)
			(xy 409.074874 -308.781196) (xy 409.072388 -308.767231) (xy 409.069715 -308.738991) (xy 409.06954 -308.724808)
			(xy 409.070062 -308.699553) (xy 409.078375 -308.649731) (xy 409.094776 -308.601957) (xy 409.118817 -308.557534)
			(xy 409.149841 -308.517674) (xy 409.187003 -308.483464) (xy 409.229289 -308.455838) (xy 409.275545 -308.435548)
			(xy 409.32451 -308.423148) (xy 409.374848 -308.418977) (xy 409.425186 -308.423148) (xy 409.474151 -308.435548)
			(xy 409.520407 -308.455838) (xy 409.562693 -308.483464) (xy 409.599855 -308.517674) (xy 409.630879 -308.557534)
			(xy 409.65492 -308.601957) (xy 409.671321 -308.649731) (xy 409.679634 -308.699553) (xy 409.680156 -308.724808)
			(xy 409.679969 -308.73899) (xy 409.677295 -308.76723) (xy 409.674822 -308.781196) (xy 409.672536 -308.793642)
			(xy 409.679902 -308.817264) (xy 409.757372 -308.894734) (xy 409.780994 -308.9021) (xy 409.79344 -308.899814)
			(xy 409.807405 -308.89733) (xy 409.835645 -308.894661) (xy 409.849828 -308.89448) (xy 409.864011 -308.894663)
			(xy 409.892251 -308.89733) (xy 409.906216 -308.899814) (xy 409.918662 -308.9021) (xy 409.942284 -308.894734)
			(xy 410.019754 -308.817264) (xy 410.02712 -308.793642) (xy 410.024834 -308.781196) (xy 410.022348 -308.767231)
			(xy 410.019675 -308.738991) (xy 410.0195 -308.724808) (xy 410.019985 -308.699988) (xy 410.028015 -308.651001)
			(xy 410.043864 -308.603959) (xy 410.067115 -308.5601) (xy 410.097155 -308.520581) (xy 410.133193 -308.486442)
			(xy 410.174279 -308.458584) (xy 410.219331 -308.437739) (xy 410.267161 -308.424458) (xy 410.31651 -308.419089)
			(xy 410.366078 -308.421776) (xy 410.414558 -308.432445) (xy 410.460674 -308.450818) (xy 410.503209 -308.476409)
			(xy 410.541044 -308.508545) (xy 410.573181 -308.546378) (xy 410.598775 -308.588912) (xy 410.61715 -308.635026)
			(xy 410.627822 -308.683506) (xy 410.630049 -308.724554) (xy 410.968964 -308.724554) (xy 410.972924 -308.6755)
			(xy 410.984701 -308.627716) (xy 411.003992 -308.58244) (xy 411.030295 -308.540844) (xy 411.06293 -308.504007)
			(xy 411.101051 -308.472882) (xy 411.143672 -308.448275) (xy 411.189688 -308.430823) (xy 411.237907 -308.420979)
			(xy 411.287082 -308.418998) (xy 411.335937 -308.42493) (xy 411.383208 -308.438622) (xy 411.42767 -308.45972)
			(xy 411.468173 -308.487676) (xy 411.503666 -308.521768) (xy 411.533231 -308.561112) (xy 411.556102 -308.604689)
			(xy 411.571686 -308.65137) (xy 411.579581 -308.699947) (xy 411.580076 -308.724554) (xy 411.580071 -308.724808)
			(xy 411.919178 -308.724808) (xy 411.923138 -308.675754) (xy 411.934915 -308.62797) (xy 411.954206 -308.582694)
			(xy 411.980509 -308.541098) (xy 412.013144 -308.504261) (xy 412.051265 -308.473136) (xy 412.093886 -308.448529)
			(xy 412.139902 -308.431077) (xy 412.188121 -308.421233) (xy 412.237296 -308.419252) (xy 412.286151 -308.425184)
			(xy 412.333422 -308.438876) (xy 412.377884 -308.459974) (xy 412.418387 -308.48793) (xy 412.45388 -308.522022)
			(xy 412.483445 -308.561366) (xy 412.506316 -308.604943) (xy 412.5219 -308.651624) (xy 412.529795 -308.700201)
			(xy 412.53029 -308.724808) (xy 412.869138 -308.724808) (xy 412.873098 -308.675754) (xy 412.884875 -308.62797)
			(xy 412.904166 -308.582694) (xy 412.930469 -308.541098) (xy 412.963104 -308.504261) (xy 413.001225 -308.473136)
			(xy 413.043846 -308.448529) (xy 413.089862 -308.431077) (xy 413.138081 -308.421233) (xy 413.187256 -308.419252)
			(xy 413.236111 -308.425184) (xy 413.283382 -308.438876) (xy 413.327844 -308.459974) (xy 413.368347 -308.48793)
			(xy 413.40384 -308.522022) (xy 413.433405 -308.561366) (xy 413.456276 -308.604943) (xy 413.47186 -308.651624)
			(xy 413.479755 -308.700201) (xy 413.48025 -308.724808) (xy 413.819098 -308.724808) (xy 413.823058 -308.675754)
			(xy 413.834835 -308.62797) (xy 413.854126 -308.582694) (xy 413.880429 -308.541098) (xy 413.913064 -308.504261)
			(xy 413.951185 -308.473136) (xy 413.993806 -308.448529) (xy 414.039822 -308.431077) (xy 414.088041 -308.421233)
			(xy 414.137216 -308.419252) (xy 414.186071 -308.425184) (xy 414.233342 -308.438876) (xy 414.277804 -308.459974)
			(xy 414.318307 -308.48793) (xy 414.3538 -308.522022) (xy 414.383365 -308.561366) (xy 414.406236 -308.604943)
			(xy 414.42182 -308.651624) (xy 414.429715 -308.700201) (xy 414.43021 -308.724808) (xy 414.769058 -308.724808)
			(xy 414.773018 -308.675754) (xy 414.784795 -308.62797) (xy 414.804086 -308.582694) (xy 414.830389 -308.541098)
			(xy 414.863024 -308.504261) (xy 414.901145 -308.473136) (xy 414.943766 -308.448529) (xy 414.989782 -308.431077)
			(xy 415.038001 -308.421233) (xy 415.087176 -308.419252) (xy 415.136031 -308.425184) (xy 415.183302 -308.438876)
			(xy 415.227764 -308.459974) (xy 415.268267 -308.48793) (xy 415.30376 -308.522022) (xy 415.333325 -308.561366)
			(xy 415.356196 -308.604943) (xy 415.37178 -308.651624) (xy 415.379675 -308.700201) (xy 415.38017 -308.724808)
			(xy 415.719018 -308.724808) (xy 415.722978 -308.675754) (xy 415.734755 -308.62797) (xy 415.754046 -308.582694)
			(xy 415.780349 -308.541098) (xy 415.812984 -308.504261) (xy 415.851105 -308.473136) (xy 415.893726 -308.448529)
			(xy 415.939742 -308.431077) (xy 415.987961 -308.421233) (xy 416.037136 -308.419252) (xy 416.085991 -308.425184)
			(xy 416.133262 -308.438876) (xy 416.177724 -308.459974) (xy 416.218227 -308.48793) (xy 416.25372 -308.522022)
			(xy 416.283285 -308.561366) (xy 416.306156 -308.604943) (xy 416.32174 -308.651624) (xy 416.329635 -308.700201)
			(xy 416.33013 -308.724808) (xy 416.669232 -308.724808) (xy 416.673192 -308.675754) (xy 416.684969 -308.62797)
			(xy 416.70426 -308.582694) (xy 416.730563 -308.541098) (xy 416.763198 -308.504261) (xy 416.801319 -308.473136)
			(xy 416.84394 -308.448529) (xy 416.889956 -308.431077) (xy 416.938175 -308.421233) (xy 416.98735 -308.419252)
			(xy 417.036205 -308.425184) (xy 417.083476 -308.438876) (xy 417.127938 -308.459974) (xy 417.168441 -308.48793)
			(xy 417.203934 -308.522022) (xy 417.233499 -308.561366) (xy 417.25637 -308.604943) (xy 417.271954 -308.651624)
			(xy 417.279849 -308.700201) (xy 417.280344 -308.724808) (xy 417.619192 -308.724808) (xy 417.623152 -308.675754)
			(xy 417.634929 -308.62797) (xy 417.65422 -308.582694) (xy 417.680523 -308.541098) (xy 417.713158 -308.504261)
			(xy 417.751279 -308.473136) (xy 417.7939 -308.448529) (xy 417.839916 -308.431077) (xy 417.888135 -308.421233)
			(xy 417.93731 -308.419252) (xy 417.986165 -308.425184) (xy 418.033436 -308.438876) (xy 418.077898 -308.459974)
			(xy 418.118401 -308.48793) (xy 418.153894 -308.522022) (xy 418.183459 -308.561366) (xy 418.20633 -308.604943)
			(xy 418.221914 -308.651624) (xy 418.229809 -308.700201) (xy 418.230304 -308.724808) (xy 418.569152 -308.724808)
			(xy 418.573112 -308.675754) (xy 418.584889 -308.62797) (xy 418.60418 -308.582694) (xy 418.630483 -308.541098)
			(xy 418.663118 -308.504261) (xy 418.701239 -308.473136) (xy 418.74386 -308.448529) (xy 418.789876 -308.431077)
			(xy 418.838095 -308.421233) (xy 418.88727 -308.419252) (xy 418.936125 -308.425184) (xy 418.983396 -308.438876)
			(xy 419.027858 -308.459974) (xy 419.068361 -308.48793) (xy 419.103854 -308.522022) (xy 419.133419 -308.561366)
			(xy 419.15629 -308.604943) (xy 419.171874 -308.651624) (xy 419.179769 -308.700201) (xy 419.180264 -308.724808)
			(xy 419.519112 -308.724808) (xy 419.523072 -308.675754) (xy 419.534849 -308.62797) (xy 419.55414 -308.582694)
			(xy 419.580443 -308.541098) (xy 419.613078 -308.504261) (xy 419.651199 -308.473136) (xy 419.69382 -308.448529)
			(xy 419.739836 -308.431077) (xy 419.788055 -308.421233) (xy 419.83723 -308.419252) (xy 419.886085 -308.425184)
			(xy 419.933356 -308.438876) (xy 419.977818 -308.459974) (xy 420.018321 -308.48793) (xy 420.053814 -308.522022)
			(xy 420.083379 -308.561366) (xy 420.10625 -308.604943) (xy 420.121834 -308.651624) (xy 420.129729 -308.700201)
			(xy 420.130224 -308.724808) (xy 420.469072 -308.724808) (xy 420.473032 -308.675754) (xy 420.484809 -308.62797)
			(xy 420.5041 -308.582694) (xy 420.530403 -308.541098) (xy 420.563038 -308.504261) (xy 420.601159 -308.473136)
			(xy 420.64378 -308.448529) (xy 420.689796 -308.431077) (xy 420.738015 -308.421233) (xy 420.78719 -308.419252)
			(xy 420.836045 -308.425184) (xy 420.883316 -308.438876) (xy 420.927778 -308.459974) (xy 420.968281 -308.48793)
			(xy 421.003774 -308.522022) (xy 421.033339 -308.561366) (xy 421.05621 -308.604943) (xy 421.071794 -308.651624)
			(xy 421.079689 -308.700201) (xy 421.080184 -308.724808) (xy 421.419032 -308.724808) (xy 421.422992 -308.675754)
			(xy 421.434769 -308.62797) (xy 421.45406 -308.582694) (xy 421.480363 -308.541098) (xy 421.512998 -308.504261)
			(xy 421.551119 -308.473136) (xy 421.59374 -308.448529) (xy 421.639756 -308.431077) (xy 421.687975 -308.421233)
			(xy 421.73715 -308.419252) (xy 421.786005 -308.425184) (xy 421.833276 -308.438876) (xy 421.877738 -308.459974)
			(xy 421.918241 -308.48793) (xy 421.953734 -308.522022) (xy 421.983299 -308.561366) (xy 422.00617 -308.604943)
			(xy 422.021754 -308.651624) (xy 422.029649 -308.700201) (xy 422.030144 -308.724808) (xy 422.029649 -308.749415)
			(xy 422.021754 -308.797992) (xy 422.00617 -308.844673) (xy 421.983299 -308.88825) (xy 421.953734 -308.927594)
			(xy 421.918241 -308.961686) (xy 421.877738 -308.989642) (xy 421.833276 -309.01074) (xy 421.786005 -309.024432)
			(xy 421.73715 -309.030364) (xy 421.687975 -309.028383) (xy 421.639756 -309.018539) (xy 421.59374 -309.001087)
			(xy 421.551119 -308.97648) (xy 421.512998 -308.945355) (xy 421.480363 -308.908518) (xy 421.45406 -308.866922)
			(xy 421.434769 -308.821646) (xy 421.422992 -308.773862) (xy 421.419032 -308.724808) (xy 421.080184 -308.724808)
			(xy 421.079689 -308.749415) (xy 421.071794 -308.797992) (xy 421.05621 -308.844673) (xy 421.033339 -308.88825)
			(xy 421.003774 -308.927594) (xy 420.968281 -308.961686) (xy 420.927778 -308.989642) (xy 420.883316 -309.01074)
			(xy 420.836045 -309.024432) (xy 420.78719 -309.030364) (xy 420.738015 -309.028383) (xy 420.689796 -309.018539)
			(xy 420.64378 -309.001087) (xy 420.601159 -308.97648) (xy 420.563038 -308.945355) (xy 420.530403 -308.908518)
			(xy 420.5041 -308.866922) (xy 420.484809 -308.821646) (xy 420.473032 -308.773862) (xy 420.469072 -308.724808)
			(xy 420.130224 -308.724808) (xy 420.129729 -308.749415) (xy 420.121834 -308.797992) (xy 420.10625 -308.844673)
			(xy 420.083379 -308.88825) (xy 420.053814 -308.927594) (xy 420.018321 -308.961686) (xy 419.977818 -308.989642)
			(xy 419.933356 -309.01074) (xy 419.886085 -309.024432) (xy 419.83723 -309.030364) (xy 419.788055 -309.028383)
			(xy 419.739836 -309.018539) (xy 419.69382 -309.001087) (xy 419.651199 -308.97648) (xy 419.613078 -308.945355)
			(xy 419.580443 -308.908518) (xy 419.55414 -308.866922) (xy 419.534849 -308.821646) (xy 419.523072 -308.773862)
			(xy 419.519112 -308.724808) (xy 419.180264 -308.724808) (xy 419.179769 -308.749415) (xy 419.171874 -308.797992)
			(xy 419.15629 -308.844673) (xy 419.133419 -308.88825) (xy 419.103854 -308.927594) (xy 419.068361 -308.961686)
			(xy 419.027858 -308.989642) (xy 418.983396 -309.01074) (xy 418.936125 -309.024432) (xy 418.88727 -309.030364)
			(xy 418.838095 -309.028383) (xy 418.789876 -309.018539) (xy 418.74386 -309.001087) (xy 418.701239 -308.97648)
			(xy 418.663118 -308.945355) (xy 418.630483 -308.908518) (xy 418.60418 -308.866922) (xy 418.584889 -308.821646)
			(xy 418.573112 -308.773862) (xy 418.569152 -308.724808) (xy 418.230304 -308.724808) (xy 418.229809 -308.749415)
			(xy 418.221914 -308.797992) (xy 418.20633 -308.844673) (xy 418.183459 -308.88825) (xy 418.153894 -308.927594)
			(xy 418.118401 -308.961686) (xy 418.077898 -308.989642) (xy 418.033436 -309.01074) (xy 417.986165 -309.024432)
			(xy 417.93731 -309.030364) (xy 417.888135 -309.028383) (xy 417.839916 -309.018539) (xy 417.7939 -309.001087)
			(xy 417.751279 -308.97648) (xy 417.713158 -308.945355) (xy 417.680523 -308.908518) (xy 417.65422 -308.866922)
			(xy 417.634929 -308.821646) (xy 417.623152 -308.773862) (xy 417.619192 -308.724808) (xy 417.280344 -308.724808)
			(xy 417.279849 -308.749415) (xy 417.271954 -308.797992) (xy 417.25637 -308.844673) (xy 417.233499 -308.88825)
			(xy 417.203934 -308.927594) (xy 417.168441 -308.961686) (xy 417.127938 -308.989642) (xy 417.083476 -309.01074)
			(xy 417.036205 -309.024432) (xy 416.98735 -309.030364) (xy 416.938175 -309.028383) (xy 416.889956 -309.018539)
			(xy 416.84394 -309.001087) (xy 416.801319 -308.97648) (xy 416.763198 -308.945355) (xy 416.730563 -308.908518)
			(xy 416.70426 -308.866922) (xy 416.684969 -308.821646) (xy 416.673192 -308.773862) (xy 416.669232 -308.724808)
			(xy 416.33013 -308.724808) (xy 416.329635 -308.749415) (xy 416.32174 -308.797992) (xy 416.306156 -308.844673)
			(xy 416.283285 -308.88825) (xy 416.25372 -308.927594) (xy 416.218227 -308.961686) (xy 416.177724 -308.989642)
			(xy 416.133262 -309.01074) (xy 416.085991 -309.024432) (xy 416.037136 -309.030364) (xy 415.987961 -309.028383)
			(xy 415.939742 -309.018539) (xy 415.893726 -309.001087) (xy 415.851105 -308.97648) (xy 415.812984 -308.945355)
			(xy 415.780349 -308.908518) (xy 415.754046 -308.866922) (xy 415.734755 -308.821646) (xy 415.722978 -308.773862)
			(xy 415.719018 -308.724808) (xy 415.38017 -308.724808) (xy 415.379675 -308.749415) (xy 415.37178 -308.797992)
			(xy 415.356196 -308.844673) (xy 415.333325 -308.88825) (xy 415.30376 -308.927594) (xy 415.268267 -308.961686)
			(xy 415.227764 -308.989642) (xy 415.183302 -309.01074) (xy 415.136031 -309.024432) (xy 415.087176 -309.030364)
			(xy 415.038001 -309.028383) (xy 414.989782 -309.018539) (xy 414.943766 -309.001087) (xy 414.901145 -308.97648)
			(xy 414.863024 -308.945355) (xy 414.830389 -308.908518) (xy 414.804086 -308.866922) (xy 414.784795 -308.821646)
			(xy 414.773018 -308.773862) (xy 414.769058 -308.724808) (xy 414.43021 -308.724808) (xy 414.429715 -308.749415)
			(xy 414.42182 -308.797992) (xy 414.406236 -308.844673) (xy 414.383365 -308.88825) (xy 414.3538 -308.927594)
			(xy 414.318307 -308.961686) (xy 414.277804 -308.989642) (xy 414.233342 -309.01074) (xy 414.186071 -309.024432)
			(xy 414.137216 -309.030364) (xy 414.088041 -309.028383) (xy 414.039822 -309.018539) (xy 413.993806 -309.001087)
			(xy 413.951185 -308.97648) (xy 413.913064 -308.945355) (xy 413.880429 -308.908518) (xy 413.854126 -308.866922)
			(xy 413.834835 -308.821646) (xy 413.823058 -308.773862) (xy 413.819098 -308.724808) (xy 413.48025 -308.724808)
			(xy 413.479755 -308.749415) (xy 413.47186 -308.797992) (xy 413.456276 -308.844673) (xy 413.433405 -308.88825)
			(xy 413.40384 -308.927594) (xy 413.368347 -308.961686) (xy 413.327844 -308.989642) (xy 413.283382 -309.01074)
			(xy 413.236111 -309.024432) (xy 413.187256 -309.030364) (xy 413.138081 -309.028383) (xy 413.089862 -309.018539)
			(xy 413.043846 -309.001087) (xy 413.001225 -308.97648) (xy 412.963104 -308.945355) (xy 412.930469 -308.908518)
			(xy 412.904166 -308.866922) (xy 412.884875 -308.821646) (xy 412.873098 -308.773862) (xy 412.869138 -308.724808)
			(xy 412.53029 -308.724808) (xy 412.529795 -308.749415) (xy 412.5219 -308.797992) (xy 412.506316 -308.844673)
			(xy 412.483445 -308.88825) (xy 412.45388 -308.927594) (xy 412.418387 -308.961686) (xy 412.377884 -308.989642)
			(xy 412.333422 -309.01074) (xy 412.286151 -309.024432) (xy 412.237296 -309.030364) (xy 412.188121 -309.028383)
			(xy 412.139902 -309.018539) (xy 412.093886 -309.001087) (xy 412.051265 -308.97648) (xy 412.013144 -308.945355)
			(xy 411.980509 -308.908518) (xy 411.954206 -308.866922) (xy 411.934915 -308.821646) (xy 411.923138 -308.773862)
			(xy 411.919178 -308.724808) (xy 411.580071 -308.724808) (xy 411.579581 -308.749161) (xy 411.571686 -308.797738)
			(xy 411.556102 -308.844419) (xy 411.533231 -308.887996) (xy 411.503666 -308.92734) (xy 411.468173 -308.961432)
			(xy 411.42767 -308.989388) (xy 411.383208 -309.010486) (xy 411.335937 -309.024178) (xy 411.287082 -309.03011)
			(xy 411.237907 -309.028129) (xy 411.189688 -309.018285) (xy 411.143672 -309.000833) (xy 411.101051 -308.976226)
			(xy 411.06293 -308.945101) (xy 411.030295 -308.908264) (xy 411.003992 -308.866668) (xy 410.984701 -308.821392)
			(xy 410.972924 -308.773608) (xy 410.968964 -308.724554) (xy 410.630049 -308.724554) (xy 410.630511 -308.733073)
			(xy 410.625145 -308.782423) (xy 410.611866 -308.830254) (xy 410.591024 -308.875307) (xy 410.563168 -308.916395)
			(xy 410.529031 -308.952435) (xy 410.489513 -308.982477) (xy 410.445656 -309.00573) (xy 410.398614 -309.021581)
			(xy 410.349628 -309.029613) (xy 410.324808 -309.030116) (xy 410.310626 -309.02993) (xy 410.282386 -309.027257)
			(xy 410.26842 -309.024782) (xy 410.255974 -309.022496) (xy 410.232352 -309.029862) (xy 410.154882 -309.107332)
			(xy 410.147516 -309.130954) (xy 410.149802 -309.1434) (xy 410.152288 -309.157365) (xy 410.154961 -309.185605)
			(xy 410.155136 -309.199788) (xy 422.844226 -309.199788) (xy 422.848186 -309.150734) (xy 422.859963 -309.10295)
			(xy 422.879254 -309.057674) (xy 422.905557 -309.016078) (xy 422.938192 -308.979241) (xy 422.976313 -308.948116)
			(xy 423.018934 -308.923509) (xy 423.06495 -308.906057) (xy 423.113169 -308.896213) (xy 423.162344 -308.894232)
			(xy 423.211199 -308.900164) (xy 423.25847 -308.913856) (xy 423.302932 -308.934954) (xy 423.343435 -308.96291)
			(xy 423.378928 -308.997002) (xy 423.408493 -309.036346) (xy 423.431364 -309.079923) (xy 423.446948 -309.126604)
			(xy 423.454843 -309.175181) (xy 423.455338 -309.199788) (xy 423.794186 -309.199788) (xy 423.798146 -309.150734)
			(xy 423.809923 -309.10295) (xy 423.829214 -309.057674) (xy 423.855517 -309.016078) (xy 423.888152 -308.979241)
			(xy 423.926273 -308.948116) (xy 423.968894 -308.923509) (xy 424.01491 -308.906057) (xy 424.063129 -308.896213)
			(xy 424.112304 -308.894232) (xy 424.161159 -308.900164) (xy 424.20843 -308.913856) (xy 424.252892 -308.934954)
			(xy 424.293395 -308.96291) (xy 424.328888 -308.997002) (xy 424.358453 -309.036346) (xy 424.381324 -309.079923)
			(xy 424.396908 -309.126604) (xy 424.404803 -309.175181) (xy 424.405298 -309.199788) (xy 424.404803 -309.224395)
			(xy 424.404624 -309.225496) (xy 424.723302 -309.225496) (xy 424.723302 -309.17408) (xy 424.731345 -309.123298)
			(xy 424.747233 -309.074399) (xy 424.770576 -309.028587) (xy 424.800797 -308.986991) (xy 424.837153 -308.950635)
			(xy 424.878749 -308.920414) (xy 424.924561 -308.897071) (xy 424.97346 -308.881183) (xy 425.024242 -308.87314)
			(xy 425.075658 -308.87314) (xy 425.12644 -308.881183) (xy 425.175339 -308.897071) (xy 425.221151 -308.920414)
			(xy 425.262747 -308.950635) (xy 425.299103 -308.986991) (xy 425.329324 -309.028587) (xy 425.352667 -309.074399)
			(xy 425.368555 -309.123298) (xy 425.376598 -309.17408) (xy 425.377102 -309.199788) (xy 425.376598 -309.225496)
			(xy 425.673262 -309.225496) (xy 425.673262 -309.17408) (xy 425.681305 -309.123298) (xy 425.697193 -309.074399)
			(xy 425.720536 -309.028587) (xy 425.750757 -308.986991) (xy 425.787113 -308.950635) (xy 425.828709 -308.920414)
			(xy 425.874521 -308.897071) (xy 425.92342 -308.881183) (xy 425.974202 -308.87314) (xy 426.025618 -308.87314)
			(xy 426.0764 -308.881183) (xy 426.125299 -308.897071) (xy 426.171111 -308.920414) (xy 426.212707 -308.950635)
			(xy 426.249063 -308.986991) (xy 426.279284 -309.028587) (xy 426.302627 -309.074399) (xy 426.318515 -309.123298)
			(xy 426.326558 -309.17408) (xy 426.327062 -309.199788) (xy 426.644066 -309.199788) (xy 426.648026 -309.150734)
			(xy 426.659803 -309.10295) (xy 426.679094 -309.057674) (xy 426.705397 -309.016078) (xy 426.738032 -308.979241)
			(xy 426.776153 -308.948116) (xy 426.818774 -308.923509) (xy 426.86479 -308.906057) (xy 426.913009 -308.896213)
			(xy 426.962184 -308.894232) (xy 427.011039 -308.900164) (xy 427.05831 -308.913856) (xy 427.102772 -308.934954)
			(xy 427.143275 -308.96291) (xy 427.178768 -308.997002) (xy 427.208333 -309.036346) (xy 427.231204 -309.079923)
			(xy 427.246788 -309.126604) (xy 427.254683 -309.175181) (xy 427.255178 -309.199788) (xy 427.254683 -309.224395)
			(xy 427.254504 -309.225496) (xy 427.573182 -309.225496) (xy 427.573182 -309.17408) (xy 427.581225 -309.123298)
			(xy 427.597113 -309.074399) (xy 427.620456 -309.028587) (xy 427.650677 -308.986991) (xy 427.687033 -308.950635)
			(xy 427.728629 -308.920414) (xy 427.774441 -308.897071) (xy 427.82334 -308.881183) (xy 427.874122 -308.87314)
			(xy 427.925538 -308.87314) (xy 427.97632 -308.881183) (xy 428.025219 -308.897071) (xy 428.071031 -308.920414)
			(xy 428.112627 -308.950635) (xy 428.148983 -308.986991) (xy 428.179204 -309.028587) (xy 428.202547 -309.074399)
			(xy 428.218435 -309.123298) (xy 428.226478 -309.17408) (xy 428.226982 -309.199788) (xy 428.226478 -309.225496)
			(xy 428.523142 -309.225496) (xy 428.523142 -309.17408) (xy 428.531185 -309.123298) (xy 428.547073 -309.074399)
			(xy 428.570416 -309.028587) (xy 428.600637 -308.986991) (xy 428.636993 -308.950635) (xy 428.678589 -308.920414)
			(xy 428.724401 -308.897071) (xy 428.7733 -308.881183) (xy 428.824082 -308.87314) (xy 428.875498 -308.87314)
			(xy 428.92628 -308.881183) (xy 428.975179 -308.897071) (xy 429.020991 -308.920414) (xy 429.062587 -308.950635)
			(xy 429.098943 -308.986991) (xy 429.129164 -309.028587) (xy 429.152507 -309.074399) (xy 429.168395 -309.123298)
			(xy 429.176438 -309.17408) (xy 429.176942 -309.199788) (xy 429.4942 -309.199788) (xy 429.49816 -309.150734)
			(xy 429.509937 -309.10295) (xy 429.529228 -309.057674) (xy 429.555531 -309.016078) (xy 429.588166 -308.979241)
			(xy 429.626287 -308.948116) (xy 429.668908 -308.923509) (xy 429.714924 -308.906057) (xy 429.763143 -308.896213)
			(xy 429.812318 -308.894232) (xy 429.861173 -308.900164) (xy 429.908444 -308.913856) (xy 429.952906 -308.934954)
			(xy 429.993409 -308.96291) (xy 430.028902 -308.997002) (xy 430.058467 -309.036346) (xy 430.081338 -309.079923)
			(xy 430.096922 -309.126604) (xy 430.104817 -309.175181) (xy 430.105312 -309.199788) (xy 430.44416 -309.199788)
			(xy 430.44812 -309.150734) (xy 430.459897 -309.10295) (xy 430.479188 -309.057674) (xy 430.505491 -309.016078)
			(xy 430.538126 -308.979241) (xy 430.576247 -308.948116) (xy 430.618868 -308.923509) (xy 430.664884 -308.906057)
			(xy 430.713103 -308.896213) (xy 430.762278 -308.894232) (xy 430.811133 -308.900164) (xy 430.858404 -308.913856)
			(xy 430.902866 -308.934954) (xy 430.943369 -308.96291) (xy 430.978862 -308.997002) (xy 431.008427 -309.036346)
			(xy 431.031298 -309.079923) (xy 431.046882 -309.126604) (xy 431.054777 -309.175181) (xy 431.054792 -309.175912)
			(xy 436.634126 -309.175912) (xy 436.638197 -309.12029) (xy 436.650323 -309.065853) (xy 436.670246 -309.013762)
			(xy 436.697542 -308.965127) (xy 436.731628 -308.920984) (xy 436.771777 -308.882275) (xy 436.817135 -308.849824)
			(xy 436.866735 -308.824323) (xy 436.919519 -308.806316) (xy 436.974362 -308.796186) (xy 437.030096 -308.794149)
			(xy 437.085533 -308.800249) (xy 437.13949 -308.814355) (xy 437.190819 -308.836167) (xy 437.238425 -308.865221)
			(xy 437.281293 -308.900896) (xy 437.31851 -308.942433) (xy 437.349283 -308.988946) (xy 437.372955 -309.039443)
			(xy 437.389023 -309.09285) (xy 437.397143 -309.148026) (xy 437.397652 -309.175912) (xy 437.397143 -309.203798)
			(xy 437.389023 -309.258974) (xy 437.372955 -309.312381) (xy 437.349283 -309.362878) (xy 437.31851 -309.409391)
			(xy 437.281293 -309.450928) (xy 437.238425 -309.486603) (xy 437.190819 -309.515657) (xy 437.13949 -309.537469)
			(xy 437.085533 -309.551575) (xy 437.030096 -309.557675) (xy 436.974362 -309.555638) (xy 436.919519 -309.545508)
			(xy 436.866735 -309.527501) (xy 436.817135 -309.502) (xy 436.771777 -309.469549) (xy 436.731628 -309.43084)
			(xy 436.697542 -309.386697) (xy 436.670246 -309.338062) (xy 436.650323 -309.285971) (xy 436.638197 -309.231534)
			(xy 436.634126 -309.175912) (xy 431.054792 -309.175912) (xy 431.055272 -309.199788) (xy 431.054777 -309.224395)
			(xy 431.046882 -309.272972) (xy 431.031298 -309.319653) (xy 431.008427 -309.36323) (xy 430.978862 -309.402574)
			(xy 430.943369 -309.436666) (xy 430.902866 -309.464622) (xy 430.858404 -309.48572) (xy 430.811133 -309.499412)
			(xy 430.762278 -309.505344) (xy 430.713103 -309.503363) (xy 430.664884 -309.493519) (xy 430.618868 -309.476067)
			(xy 430.576247 -309.45146) (xy 430.538126 -309.420335) (xy 430.505491 -309.383498) (xy 430.479188 -309.341902)
			(xy 430.459897 -309.296626) (xy 430.44812 -309.248842) (xy 430.44416 -309.199788) (xy 430.105312 -309.199788)
			(xy 430.104817 -309.224395) (xy 430.096922 -309.272972) (xy 430.081338 -309.319653) (xy 430.058467 -309.36323)
			(xy 430.028902 -309.402574) (xy 429.993409 -309.436666) (xy 429.952906 -309.464622) (xy 429.908444 -309.48572)
			(xy 429.861173 -309.499412) (xy 429.812318 -309.505344) (xy 429.763143 -309.503363) (xy 429.714924 -309.493519)
			(xy 429.668908 -309.476067) (xy 429.626287 -309.45146) (xy 429.588166 -309.420335) (xy 429.555531 -309.383498)
			(xy 429.529228 -309.341902) (xy 429.509937 -309.296626) (xy 429.49816 -309.248842) (xy 429.4942 -309.199788)
			(xy 429.176942 -309.199788) (xy 429.176438 -309.225496) (xy 429.168395 -309.276278) (xy 429.152507 -309.325177)
			(xy 429.129164 -309.370989) (xy 429.098943 -309.412585) (xy 429.062587 -309.448941) (xy 429.020991 -309.479162)
			(xy 428.975179 -309.502505) (xy 428.92628 -309.518393) (xy 428.875498 -309.526436) (xy 428.824082 -309.526436)
			(xy 428.7733 -309.518393) (xy 428.724401 -309.502505) (xy 428.678589 -309.479162) (xy 428.636993 -309.448941)
			(xy 428.600637 -309.412585) (xy 428.570416 -309.370989) (xy 428.547073 -309.325177) (xy 428.531185 -309.276278)
			(xy 428.523142 -309.225496) (xy 428.226478 -309.225496) (xy 428.218435 -309.276278) (xy 428.202547 -309.325177)
			(xy 428.179204 -309.370989) (xy 428.148983 -309.412585) (xy 428.112627 -309.448941) (xy 428.071031 -309.479162)
			(xy 428.025219 -309.502505) (xy 427.97632 -309.518393) (xy 427.925538 -309.526436) (xy 427.874122 -309.526436)
			(xy 427.82334 -309.518393) (xy 427.774441 -309.502505) (xy 427.728629 -309.479162) (xy 427.687033 -309.448941)
			(xy 427.650677 -309.412585) (xy 427.620456 -309.370989) (xy 427.597113 -309.325177) (xy 427.581225 -309.276278)
			(xy 427.573182 -309.225496) (xy 427.254504 -309.225496) (xy 427.246788 -309.272972) (xy 427.231204 -309.319653)
			(xy 427.208333 -309.36323) (xy 427.178768 -309.402574) (xy 427.143275 -309.436666) (xy 427.102772 -309.464622)
			(xy 427.05831 -309.48572) (xy 427.011039 -309.499412) (xy 426.962184 -309.505344) (xy 426.913009 -309.503363)
			(xy 426.86479 -309.493519) (xy 426.818774 -309.476067) (xy 426.776153 -309.45146) (xy 426.738032 -309.420335)
			(xy 426.705397 -309.383498) (xy 426.679094 -309.341902) (xy 426.659803 -309.296626) (xy 426.648026 -309.248842)
			(xy 426.644066 -309.199788) (xy 426.327062 -309.199788) (xy 426.326558 -309.225496) (xy 426.318515 -309.276278)
			(xy 426.302627 -309.325177) (xy 426.279284 -309.370989) (xy 426.249063 -309.412585) (xy 426.212707 -309.448941)
			(xy 426.171111 -309.479162) (xy 426.125299 -309.502505) (xy 426.0764 -309.518393) (xy 426.025618 -309.526436)
			(xy 425.974202 -309.526436) (xy 425.92342 -309.518393) (xy 425.874521 -309.502505) (xy 425.828709 -309.479162)
			(xy 425.787113 -309.448941) (xy 425.750757 -309.412585) (xy 425.720536 -309.370989) (xy 425.697193 -309.325177)
			(xy 425.681305 -309.276278) (xy 425.673262 -309.225496) (xy 425.376598 -309.225496) (xy 425.368555 -309.276278)
			(xy 425.352667 -309.325177) (xy 425.329324 -309.370989) (xy 425.299103 -309.412585) (xy 425.262747 -309.448941)
			(xy 425.221151 -309.479162) (xy 425.175339 -309.502505) (xy 425.12644 -309.518393) (xy 425.075658 -309.526436)
			(xy 425.024242 -309.526436) (xy 424.97346 -309.518393) (xy 424.924561 -309.502505) (xy 424.878749 -309.479162)
			(xy 424.837153 -309.448941) (xy 424.800797 -309.412585) (xy 424.770576 -309.370989) (xy 424.747233 -309.325177)
			(xy 424.731345 -309.276278) (xy 424.723302 -309.225496) (xy 424.404624 -309.225496) (xy 424.396908 -309.272972)
			(xy 424.381324 -309.319653) (xy 424.358453 -309.36323) (xy 424.328888 -309.402574) (xy 424.293395 -309.436666)
			(xy 424.252892 -309.464622) (xy 424.20843 -309.48572) (xy 424.161159 -309.499412) (xy 424.112304 -309.505344)
			(xy 424.063129 -309.503363) (xy 424.01491 -309.493519) (xy 423.968894 -309.476067) (xy 423.926273 -309.45146)
			(xy 423.888152 -309.420335) (xy 423.855517 -309.383498) (xy 423.829214 -309.341902) (xy 423.809923 -309.296626)
			(xy 423.798146 -309.248842) (xy 423.794186 -309.199788) (xy 423.455338 -309.199788) (xy 423.454843 -309.224395)
			(xy 423.446948 -309.272972) (xy 423.431364 -309.319653) (xy 423.408493 -309.36323) (xy 423.378928 -309.402574)
			(xy 423.343435 -309.436666) (xy 423.302932 -309.464622) (xy 423.25847 -309.48572) (xy 423.211199 -309.499412)
			(xy 423.162344 -309.505344) (xy 423.113169 -309.503363) (xy 423.06495 -309.493519) (xy 423.018934 -309.476067)
			(xy 422.976313 -309.45146) (xy 422.938192 -309.420335) (xy 422.905557 -309.383498) (xy 422.879254 -309.341902)
			(xy 422.859963 -309.296626) (xy 422.848186 -309.248842) (xy 422.844226 -309.199788) (xy 410.155136 -309.199788)
			(xy 410.15495 -309.213971) (xy 410.152278 -309.24221) (xy 410.149802 -309.256176) (xy 410.147516 -309.268622)
			(xy 410.154882 -309.292244) (xy 410.232352 -309.369714) (xy 410.255974 -309.37708) (xy 410.26842 -309.374794)
			(xy 410.282385 -309.372309) (xy 410.310625 -309.369638) (xy 410.324808 -309.36946) (xy 410.3488 -309.369931)
			(xy 410.396192 -309.377438) (xy 410.441827 -309.392266) (xy 410.484581 -309.414049) (xy 410.523401 -309.442252)
			(xy 410.557332 -309.47618) (xy 410.585538 -309.514998) (xy 410.607325 -309.55775) (xy 410.622156 -309.603384)
			(xy 410.629667 -309.650776) (xy 410.630116 -309.674768) (xy 410.6291 -309.700168) (xy 410.62783 -309.714392)
			(xy 410.64053 -309.739538) (xy 410.691076 -309.771288) (xy 410.741876 -309.802784) (xy 410.77007 -309.803038)
			(xy 410.782516 -309.795672) (xy 410.80183 -309.784336) (xy 410.841344 -309.763247) (xy 410.86151 -309.753508)
			(xy 410.862018 -309.753508) (xy 410.877512 -309.746142) (xy 410.878528 -309.74538) (xy 410.922216 -309.727092)
			(xy 410.929328 -309.724298) (xy 410.941012 -309.7149) (xy 410.96057 -309.68696) (xy 410.964222 -309.681343)
			(xy 410.968715 -309.668727) (xy 410.96946 -309.662068) (xy 410.969714 -309.66029) (xy 410.969714 -309.659528)
			(xy 410.971566 -309.633775) (xy 410.98282 -309.58339) (xy 411.002378 -309.535611) (xy 411.029684 -309.491797)
			(xy 411.063962 -309.453192) (xy 411.104239 -309.420894) (xy 411.149368 -309.395821) (xy 411.198068 -309.378685)
			(xy 411.248955 -309.369974) (xy 411.274768 -309.36946) (xy 411.300612 -309.370006) (xy 411.35156 -309.378714)
			(xy 411.400317 -309.395871) (xy 411.445492 -309.420987) (xy 411.485797 -309.453346) (xy 411.520083 -309.492025)
			(xy 411.547372 -309.535922) (xy 411.566885 -309.583784) (xy 411.578067 -309.634247) (xy 411.579822 -309.660036)
			(xy 411.580076 -309.667402) (xy 411.582362 -309.67426) (xy 411.584648 -309.681372) (xy 411.60573 -309.711852)
			(xy 411.610556 -309.715916) (xy 411.611572 -309.716932) (xy 411.615077 -309.720037) (xy 411.623005 -309.725019)
			(xy 411.62732 -309.726838) (xy 411.663552 -309.741534) (xy 411.733742 -309.775995) (xy 411.767528 -309.795672)
			(xy 411.775724 -309.800047) (xy 411.794016 -309.803209) (xy 411.812241 -309.799682) (xy 411.82036 -309.795164)
			(xy 411.838648 -309.783734) (xy 411.909006 -309.739538) (xy 411.921452 -309.714646) (xy 411.920436 -309.700422)
			(xy 411.919674 -309.68061) (xy 411.919674 -309.673752) (xy 411.920275 -309.648552) (xy 411.928719 -309.59886)
			(xy 411.945211 -309.55123) (xy 411.969301 -309.506956) (xy 412.000337 -309.467239) (xy 412.037474 -309.43316)
			(xy 412.079704 -309.405643) (xy 412.125881 -309.385437) (xy 412.174749 -309.373089) (xy 412.224982 -309.368935)
			(xy 412.275215 -309.373089) (xy 412.324083 -309.385437) (xy 412.37026 -309.405643) (xy 412.41249 -309.43316)
			(xy 412.449627 -309.467239) (xy 412.480663 -309.506956) (xy 412.504753 -309.55123) (xy 412.521245 -309.59886)
			(xy 412.529689 -309.648552) (xy 412.53029 -309.673752) (xy 412.53029 -309.68061) (xy 412.529274 -309.69966)
			(xy 412.528004 -309.714138) (xy 412.540704 -309.739284) (xy 412.641796 -309.802784) (xy 412.66999 -309.803038)
			(xy 412.682436 -309.795672) (xy 412.706898 -309.781373) (xy 412.757223 -309.755323) (xy 412.78302 -309.743602)
			(xy 412.824168 -309.72633) (xy 412.831534 -309.723282) (xy 412.843218 -309.713884) (xy 412.85668 -309.693818)
			(xy 412.860495 -309.687733) (xy 412.86488 -309.674063) (xy 412.865316 -309.666894) (xy 412.866452 -309.641708)
			(xy 412.875879 -309.592183) (xy 412.893202 -309.544839) (xy 412.917964 -309.500925) (xy 412.949511 -309.461601)
			(xy 412.98701 -309.427906) (xy 413.029472 -309.400729) (xy 413.075774 -309.380787) (xy 413.124695 -309.368607)
			(xy 413.174942 -309.364511) (xy 413.225189 -309.368607) (xy 413.27411 -309.380787) (xy 413.320412 -309.400729)
			(xy 413.362874 -309.427906) (xy 413.400373 -309.461601) (xy 413.43192 -309.500925) (xy 413.456682 -309.544839)
			(xy 413.474005 -309.592183) (xy 413.483432 -309.641708) (xy 413.484568 -309.666894) (xy 413.485028 -309.674059)
			(xy 413.489405 -309.687726) (xy 413.493204 -309.693818) (xy 413.515556 -309.726838) (xy 413.521148 -309.734508)
			(xy 413.536697 -309.74537) (xy 413.55513 -309.749841) (xy 413.564578 -309.748936) (xy 413.5755 -309.747412)
			(xy 413.597576 -309.757692) (xy 413.640776 -309.780183) (xy 413.66186 -309.79237) (xy 413.667448 -309.795672)
			(xy 413.687514 -309.80126) (xy 413.695642 -309.80126) (xy 413.702594 -309.801024) (xy 413.715989 -309.797293)
			(xy 413.722058 -309.793894) (xy 413.72917 -309.789576) (xy 413.808926 -309.739538) (xy 413.821372 -309.714646)
			(xy 413.820356 -309.700422) (xy 413.819594 -309.68061) (xy 413.819594 -309.673752) (xy 413.820195 -309.648552)
			(xy 413.828639 -309.59886) (xy 413.845131 -309.55123) (xy 413.869221 -309.506956) (xy 413.900257 -309.467239)
			(xy 413.937394 -309.43316) (xy 413.979624 -309.405643) (xy 414.025801 -309.385437) (xy 414.074669 -309.373089)
			(xy 414.124902 -309.368935) (xy 414.175135 -309.373089) (xy 414.224003 -309.385437) (xy 414.27018 -309.405643)
			(xy 414.31241 -309.43316) (xy 414.349547 -309.467239) (xy 414.380583 -309.506956) (xy 414.404673 -309.55123)
			(xy 414.421165 -309.59886) (xy 414.429609 -309.648552) (xy 414.43021 -309.673752) (xy 414.43021 -309.675022)
			(xy 414.429448 -309.697882) (xy 414.428666 -309.707554) (xy 414.433563 -309.726315) (xy 414.445068 -309.741922)
			(xy 414.45307 -309.747412) (xy 414.515808 -309.786528) (xy 414.541716 -309.802784) (xy 414.56991 -309.803038)
			(xy 414.582356 -309.795672) (xy 414.619402 -309.774216) (xy 414.696606 -309.737204) (xy 414.736534 -309.721758)
			(xy 414.746003 -309.717692) (xy 414.760891 -309.70347) (xy 414.769017 -309.684553) (xy 414.769554 -309.67426)
			(xy 414.770115 -309.649032) (xy 414.778494 -309.599275) (xy 414.794941 -309.551574) (xy 414.819006 -309.507225)
			(xy 414.850036 -309.467437) (xy 414.887186 -309.433292) (xy 414.929444 -309.405721) (xy 414.97566 -309.385473)
			(xy 415.024577 -309.373099) (xy 415.074862 -309.368937) (xy 415.125147 -309.373099) (xy 415.174064 -309.385473)
			(xy 415.22028 -309.405721) (xy 415.262538 -309.433292) (xy 415.299688 -309.467437) (xy 415.330718 -309.507225)
			(xy 415.354783 -309.551574) (xy 415.37123 -309.599275) (xy 415.379609 -309.649032) (xy 415.38017 -309.67426)
			(xy 415.380647 -309.684563) (xy 415.38877 -309.703498) (xy 415.403712 -309.717685) (xy 415.41319 -309.721758)
			(xy 415.453118 -309.737203) (xy 415.530321 -309.774216) (xy 415.567368 -309.795672) (xy 415.579814 -309.803038)
			(xy 415.608008 -309.802784) (xy 415.696908 -309.747412) (xy 415.704756 -309.742079) (xy 415.71611 -309.726896)
			(xy 415.721151 -309.708618) (xy 415.72053 -309.699152) (xy 415.720276 -309.697882) (xy 415.719514 -309.676292)
			(xy 415.719514 -309.673752) (xy 415.720115 -309.648552) (xy 415.728559 -309.59886) (xy 415.745051 -309.55123)
			(xy 415.769141 -309.506956) (xy 415.800177 -309.467239) (xy 415.837314 -309.43316) (xy 415.879544 -309.405643)
			(xy 415.925721 -309.385437) (xy 415.974589 -309.373089) (xy 416.024822 -309.368935) (xy 416.075055 -309.373089)
			(xy 416.123923 -309.385437) (xy 416.1701 -309.405643) (xy 416.21233 -309.43316) (xy 416.249467 -309.467239)
			(xy 416.280503 -309.506956) (xy 416.304593 -309.55123) (xy 416.321085 -309.59886) (xy 416.329529 -309.648552)
			(xy 416.33013 -309.673752) (xy 416.33013 -309.675022) (xy 416.329368 -309.697882) (xy 416.329114 -309.699152)
			(xy 416.328489 -309.709283) (xy 416.334341 -309.728701) (xy 416.34727 -309.744328) (xy 416.356038 -309.749444)
			(xy 416.431476 -309.796434) (xy 416.439658 -309.800515) (xy 416.457729 -309.803208) (xy 416.47561 -309.799451)
			(xy 416.483546 -309.79491) (xy 416.485324 -309.793894) (xy 416.52174 -309.772998) (xy 416.597542 -309.736883)
			(xy 416.636708 -309.721758) (xy 416.646181 -309.717695) (xy 416.661076 -309.703475) (xy 416.669207 -309.684555)
			(xy 416.669728 -309.67426) (xy 416.670239 -309.650298) (xy 416.677812 -309.602973) (xy 416.692688 -309.557414)
			(xy 416.7145 -309.514739) (xy 416.742714 -309.475996) (xy 416.776635 -309.442139) (xy 416.81543 -309.413999)
			(xy 416.858147 -309.392267) (xy 416.903734 -309.377477) (xy 416.951073 -309.369993) (xy 416.975036 -309.36946)
			(xy 416.999014 -309.369932) (xy 417.046378 -309.377435) (xy 417.091988 -309.392249) (xy 417.134721 -309.414012)
			(xy 417.173526 -309.442188) (xy 417.207449 -309.476084) (xy 417.235657 -309.514866) (xy 417.257455 -309.557581)
			(xy 417.272307 -309.603178) (xy 417.279848 -309.650537) (xy 417.280344 -309.674514) (xy 417.280812 -309.684823)
			(xy 417.288924 -309.703777) (xy 417.303863 -309.717985) (xy 417.313364 -309.722012) (xy 417.351437 -309.736725)
			(xy 417.425197 -309.771695) (xy 417.460684 -309.791862) (xy 417.467542 -309.795926) (xy 417.481258 -309.799736)
			(xy 417.491619 -309.802088) (xy 417.512625 -309.799076) (xy 417.521898 -309.793894) (xy 417.609274 -309.739538)
			(xy 417.621974 -309.714392) (xy 417.620704 -309.699914) (xy 417.619688 -309.674768) (xy 417.620161 -309.650778)
			(xy 417.627671 -309.60339) (xy 417.642501 -309.55776) (xy 417.664286 -309.515012) (xy 417.69249 -309.476197)
			(xy 417.726418 -309.442272) (xy 417.765236 -309.414072) (xy 417.807986 -309.392291) (xy 417.853618 -309.377465)
			(xy 417.901006 -309.369959) (xy 417.924996 -309.36946) (xy 417.948938 -309.369926) (xy 417.996234 -309.3774)
			(xy 418.041784 -309.392165) (xy 418.084471 -309.413859) (xy 418.123248 -309.441951) (xy 418.157165 -309.475751)
			(xy 418.18539 -309.514431) (xy 418.207231 -309.557043) (xy 418.222153 -309.602542) (xy 418.229789 -309.649812)
			(xy 418.230304 -309.673752) (xy 418.230304 -309.675022) (xy 418.229542 -309.697882) (xy 418.22876 -309.707554)
			(xy 418.233656 -309.726315) (xy 418.245161 -309.741923) (xy 418.253164 -309.747412) (xy 418.315902 -309.786528)
			(xy 418.34181 -309.802784) (xy 418.370004 -309.803038) (xy 418.38245 -309.795672) (xy 418.419496 -309.774216)
			(xy 418.4967 -309.737203) (xy 418.536628 -309.721758) (xy 418.546098 -309.717693) (xy 418.560988 -309.703472)
			(xy 418.569115 -309.684553) (xy 418.569648 -309.67426) (xy 418.570209 -309.649032) (xy 418.578588 -309.599275)
			(xy 418.595035 -309.551574) (xy 418.6191 -309.507225) (xy 418.65013 -309.467437) (xy 418.68728 -309.433292)
			(xy 418.729538 -309.405721) (xy 418.775754 -309.385473) (xy 418.824671 -309.373099) (xy 418.874956 -309.368937)
			(xy 418.925241 -309.373099) (xy 418.974158 -309.385473) (xy 419.020374 -309.405721) (xy 419.062632 -309.433292)
			(xy 419.099782 -309.467437) (xy 419.130812 -309.507225) (xy 419.154877 -309.551574) (xy 419.171324 -309.599275)
			(xy 419.179703 -309.649032) (xy 419.180264 -309.67426) (xy 419.180741 -309.684563) (xy 419.188863 -309.703499)
			(xy 419.203804 -309.717688) (xy 419.213284 -309.721758) (xy 419.253212 -309.737203) (xy 419.330416 -309.774216)
			(xy 419.367462 -309.795672) (xy 419.379908 -309.803038) (xy 419.408102 -309.802784) (xy 419.497002 -309.747412)
			(xy 419.50485 -309.74208) (xy 419.516206 -309.726896) (xy 419.521248 -309.708619) (xy 419.520624 -309.699152)
			(xy 419.52037 -309.697882) (xy 419.519608 -309.676292) (xy 419.519608 -309.673752) (xy 419.520209 -309.648552)
			(xy 419.528653 -309.59886) (xy 419.545145 -309.55123) (xy 419.569235 -309.506956) (xy 419.600271 -309.467239)
			(xy 419.637408 -309.43316) (xy 419.679638 -309.405643) (xy 419.725815 -309.385437) (xy 419.774683 -309.373089)
			(xy 419.824916 -309.368935) (xy 419.875149 -309.373089) (xy 419.924017 -309.385437) (xy 419.970194 -309.405643)
			(xy 420.012424 -309.43316) (xy 420.049561 -309.467239) (xy 420.080597 -309.506956) (xy 420.104687 -309.55123)
			(xy 420.121179 -309.59886) (xy 420.129623 -309.648552) (xy 420.130224 -309.673752) (xy 420.130224 -309.675022)
			(xy 420.129462 -309.697882) (xy 420.128679 -309.707557) (xy 420.133571 -309.726324) (xy 420.145065 -309.741945)
			(xy 420.153084 -309.747412) (xy 420.215822 -309.786528) (xy 420.24173 -309.802784) (xy 420.269924 -309.803038)
			(xy 420.28237 -309.795672) (xy 420.319417 -309.774216) (xy 420.396621 -309.737205) (xy 420.436548 -309.721758)
			(xy 420.446015 -309.71769) (xy 420.460899 -309.703468) (xy 420.469023 -309.684552) (xy 420.469568 -309.67426)
			(xy 420.470129 -309.649032) (xy 420.478508 -309.599275) (xy 420.494955 -309.551574) (xy 420.51902 -309.507225)
			(xy 420.55005 -309.467437) (xy 420.5872 -309.433292) (xy 420.629458 -309.405721) (xy 420.675674 -309.385473)
			(xy 420.724591 -309.373099) (xy 420.774876 -309.368937) (xy 420.825161 -309.373099) (xy 420.874078 -309.385473)
			(xy 420.920294 -309.405721) (xy 420.962552 -309.433292) (xy 420.999702 -309.467437) (xy 421.030732 -309.507225)
			(xy 421.054797 -309.551574) (xy 421.071244 -309.599275) (xy 421.079623 -309.649032) (xy 421.080184 -309.67426)
			(xy 421.080659 -309.684567) (xy 421.088775 -309.703514) (xy 421.103708 -309.717723) (xy 421.113204 -309.721758)
			(xy 421.153132 -309.737204) (xy 421.230334 -309.774218) (xy 421.267382 -309.795672) (xy 421.279828 -309.803038)
			(xy 421.308022 -309.802784) (xy 421.396922 -309.747412) (xy 421.404768 -309.742078) (xy 421.416119 -309.726894)
			(xy 421.421159 -309.708618) (xy 421.420544 -309.699152) (xy 421.42029 -309.697882) (xy 421.419528 -309.676292)
			(xy 421.419528 -309.673752) (xy 421.420077 -309.649816) (xy 421.427713 -309.602553) (xy 421.442633 -309.557061)
			(xy 421.464473 -309.514456) (xy 421.492695 -309.475783) (xy 421.526608 -309.44199) (xy 421.565382 -309.413905)
			(xy 421.608064 -309.392217) (xy 421.653608 -309.377458) (xy 421.700898 -309.36999) (xy 421.724836 -309.36946)
			(xy 421.748826 -309.369933) (xy 421.796216 -309.377444) (xy 421.841847 -309.392274) (xy 421.884597 -309.414059)
			(xy 421.923413 -309.442262) (xy 421.95734 -309.47619) (xy 421.985543 -309.515007) (xy 422.007328 -309.557757)
			(xy 422.022157 -309.603388) (xy 422.029667 -309.650778) (xy 422.030144 -309.674768) (xy 422.029959 -309.688951)
			(xy 422.027289 -309.71719) (xy 422.02481 -309.731156) (xy 422.022524 -309.743602) (xy 422.02989 -309.767224)
			(xy 422.10736 -309.844694) (xy 422.130982 -309.85206) (xy 422.143428 -309.849774) (xy 422.157393 -309.847289)
			(xy 422.185633 -309.844618) (xy 422.199816 -309.84444) (xy 422.223807 -309.844887) (xy 422.271198 -309.852396)
			(xy 422.31683 -309.867227) (xy 422.359581 -309.889014) (xy 422.398396 -309.917221) (xy 422.432321 -309.951153)
			(xy 422.46052 -309.989974) (xy 422.482297 -310.032729) (xy 422.497119 -310.078365) (xy 422.504618 -310.125757)
			(xy 422.505124 -310.149748) (xy 422.505078 -310.158785) (xy 422.504063 -310.176831) (xy 422.503092 -310.185816)
			(xy 422.501568 -310.198008) (xy 422.509442 -310.220106) (xy 422.585896 -310.293004) (xy 422.608502 -310.300116)
			(xy 422.620694 -310.298084) (xy 422.634182 -310.295956) (xy 422.661396 -310.29367) (xy 422.67505 -310.293512)
			(xy 422.688704 -310.293673) (xy 422.715917 -310.295961) (xy 422.729406 -310.298084) (xy 422.741344 -310.299862)
			(xy 422.76395 -310.293004) (xy 422.840404 -310.220106) (xy 422.848278 -310.197754) (xy 422.846754 -310.185816)
			(xy 422.845772 -310.176832) (xy 422.844755 -310.158786) (xy 422.844722 -310.149748) (xy 422.845244 -310.124493)
			(xy 422.853557 -310.074671) (xy 422.869958 -310.026897) (xy 422.893999 -309.982474) (xy 422.925023 -309.942614)
			(xy 422.962185 -309.908404) (xy 423.004471 -309.880778) (xy 423.050727 -309.860488) (xy 423.099692 -309.848088)
			(xy 423.15003 -309.843917) (xy 423.200368 -309.848088) (xy 423.249333 -309.860488) (xy 423.295589 -309.880778)
			(xy 423.337875 -309.908404) (xy 423.375037 -309.942614) (xy 423.406061 -309.982474) (xy 423.430102 -310.026897)
			(xy 423.446503 -310.074671) (xy 423.454816 -310.124493) (xy 423.455338 -310.149748) (xy 423.455216 -310.163862)
			(xy 423.452672 -310.191975) (xy 423.450258 -310.205882) (xy 423.447718 -310.218328) (xy 423.455084 -310.24195)
			(xy 423.532554 -310.31942) (xy 423.556176 -310.326532) (xy 423.568622 -310.324246) (xy 423.59663 -310.319623)
			(xy 423.65339 -310.319623) (xy 423.681398 -310.324246) (xy 423.693844 -310.326532) (xy 423.717466 -310.31942)
			(xy 423.794936 -310.24195) (xy 423.802302 -310.218328) (xy 423.799762 -310.205882) (xy 423.797363 -310.191973)
			(xy 423.794817 -310.163862) (xy 423.794682 -310.149748) (xy 423.795204 -310.124493) (xy 423.803517 -310.074671)
			(xy 423.819918 -310.026897) (xy 423.843959 -309.982474) (xy 423.874983 -309.942614) (xy 423.912145 -309.908404)
			(xy 423.954431 -309.880778) (xy 424.000687 -309.860488) (xy 424.049652 -309.848088) (xy 424.09999 -309.843917)
			(xy 424.150328 -309.848088) (xy 424.199293 -309.860488) (xy 424.245549 -309.880778) (xy 424.287835 -309.908404)
			(xy 424.324997 -309.942614) (xy 424.356021 -309.982474) (xy 424.380062 -310.026897) (xy 424.396463 -310.074671)
			(xy 424.404776 -310.124493) (xy 424.405298 -310.149748) (xy 424.405252 -310.158785) (xy 424.404237 -310.176831)
			(xy 424.403266 -310.185816) (xy 424.401742 -310.197754) (xy 424.409616 -310.220106) (xy 424.48607 -310.293004)
			(xy 424.508676 -310.299862) (xy 424.520614 -310.298084) (xy 424.534102 -310.295953) (xy 424.561315 -310.29366)
			(xy 424.57497 -310.293512) (xy 424.588624 -310.293674) (xy 424.615837 -310.295964) (xy 424.629326 -310.298084)
			(xy 424.641264 -310.299862) (xy 424.66387 -310.293004) (xy 424.740324 -310.220106) (xy 424.748198 -310.197754)
			(xy 424.746674 -310.185816) (xy 424.745692 -310.176832) (xy 424.744675 -310.158786) (xy 424.744642 -310.149748)
			(xy 424.745164 -310.124493) (xy 424.753477 -310.074671) (xy 424.769878 -310.026897) (xy 424.793919 -309.982474)
			(xy 424.824943 -309.942614) (xy 424.862105 -309.908404) (xy 424.904391 -309.880778) (xy 424.950647 -309.860488)
			(xy 424.999612 -309.848088) (xy 425.04995 -309.843917) (xy 425.100288 -309.848088) (xy 425.149253 -309.860488)
			(xy 425.195509 -309.880778) (xy 425.237795 -309.908404) (xy 425.274957 -309.942614) (xy 425.305981 -309.982474)
			(xy 425.330022 -310.026897) (xy 425.346423 -310.074671) (xy 425.354736 -310.124493) (xy 425.355258 -310.149748)
			(xy 425.355136 -310.163862) (xy 425.352592 -310.191975) (xy 425.350178 -310.205882) (xy 425.347638 -310.218328)
			(xy 425.355004 -310.24195) (xy 425.432474 -310.31942) (xy 425.456096 -310.326532) (xy 425.468542 -310.324246)
			(xy 425.49655 -310.319623) (xy 425.55331 -310.319623) (xy 425.581318 -310.324246) (xy 425.593764 -310.326532)
			(xy 425.617386 -310.31942) (xy 425.694856 -310.24195) (xy 425.702222 -310.218328) (xy 425.699682 -310.205882)
			(xy 425.697284 -310.191973) (xy 425.694738 -310.163862) (xy 425.694602 -310.149748) (xy 425.695124 -310.124493)
			(xy 425.703437 -310.074671) (xy 425.719838 -310.026897) (xy 425.743879 -309.982474) (xy 425.774903 -309.942614)
			(xy 425.812065 -309.908404) (xy 425.854351 -309.880778) (xy 425.900607 -309.860488) (xy 425.949572 -309.848088)
			(xy 425.99991 -309.843917) (xy 426.050248 -309.848088) (xy 426.099213 -309.860488) (xy 426.145469 -309.880778)
			(xy 426.187755 -309.908404) (xy 426.224917 -309.942614) (xy 426.255941 -309.982474) (xy 426.279982 -310.026897)
			(xy 426.296383 -310.074671) (xy 426.304696 -310.124493) (xy 426.305218 -310.149748) (xy 426.305172 -310.158785)
			(xy 426.304157 -310.176831) (xy 426.303186 -310.185816) (xy 426.301662 -310.197754) (xy 426.309536 -310.220106)
			(xy 426.38599 -310.293004) (xy 426.408596 -310.299862) (xy 426.420534 -310.298084) (xy 426.434022 -310.295953)
			(xy 426.461235 -310.293662) (xy 426.47489 -310.293512) (xy 426.488544 -310.293675) (xy 426.515756 -310.295966)
			(xy 426.529246 -310.298084) (xy 426.541184 -310.299862) (xy 426.56379 -310.293004) (xy 426.640244 -310.220106)
			(xy 426.648118 -310.197754) (xy 426.646594 -310.185816) (xy 426.645612 -310.176832) (xy 426.644595 -310.158786)
			(xy 426.644562 -310.149748) (xy 426.645084 -310.124493) (xy 426.653397 -310.074671) (xy 426.669798 -310.026897)
			(xy 426.693839 -309.982474) (xy 426.724863 -309.942614) (xy 426.762025 -309.908404) (xy 426.804311 -309.880778)
			(xy 426.850567 -309.860488) (xy 426.899532 -309.848088) (xy 426.94987 -309.843917) (xy 427.000208 -309.848088)
			(xy 427.049173 -309.860488) (xy 427.095429 -309.880778) (xy 427.137715 -309.908404) (xy 427.174877 -309.942614)
			(xy 427.205901 -309.982474) (xy 427.229942 -310.026897) (xy 427.246343 -310.074671) (xy 427.254656 -310.124493)
			(xy 427.255178 -310.149748) (xy 427.255056 -310.163862) (xy 427.252512 -310.191975) (xy 427.250098 -310.205882)
			(xy 427.247558 -310.218328) (xy 427.254924 -310.24195) (xy 427.332394 -310.31942) (xy 427.356016 -310.326532)
			(xy 427.368462 -310.324246) (xy 427.39647 -310.319623) (xy 427.45323 -310.319623) (xy 427.481238 -310.324246)
			(xy 427.493684 -310.326532) (xy 427.517306 -310.31942) (xy 427.594776 -310.24195) (xy 427.602142 -310.218328)
			(xy 427.599602 -310.205882) (xy 427.597203 -310.191973) (xy 427.594658 -310.163862) (xy 427.594522 -310.149748)
			(xy 427.595044 -310.124493) (xy 427.603357 -310.074671) (xy 427.619758 -310.026897) (xy 427.643799 -309.982474)
			(xy 427.674823 -309.942614) (xy 427.711985 -309.908404) (xy 427.754271 -309.880778) (xy 427.800527 -309.860488)
			(xy 427.849492 -309.848088) (xy 427.89983 -309.843917) (xy 427.950168 -309.848088) (xy 427.999133 -309.860488)
			(xy 428.045389 -309.880778) (xy 428.087675 -309.908404) (xy 428.124837 -309.942614) (xy 428.155861 -309.982474)
			(xy 428.179902 -310.026897) (xy 428.196303 -310.074671) (xy 428.204616 -310.124493) (xy 428.205138 -310.149748)
			(xy 428.205092 -310.158785) (xy 428.204077 -310.176831) (xy 428.203106 -310.185816) (xy 428.201582 -310.197754)
			(xy 428.209456 -310.220106) (xy 428.28591 -310.293004) (xy 428.308516 -310.299862) (xy 428.320454 -310.298084)
			(xy 428.333942 -310.295954) (xy 428.361155 -310.293665) (xy 428.37481 -310.293512) (xy 428.388464 -310.293676)
			(xy 428.415676 -310.295969) (xy 428.429166 -310.298084) (xy 428.441104 -310.299862) (xy 428.46371 -310.293004)
			(xy 428.540164 -310.220106) (xy 428.548038 -310.197754) (xy 428.546514 -310.185816) (xy 428.545532 -310.176832)
			(xy 428.544516 -310.158786) (xy 428.544482 -310.149748) (xy 428.545004 -310.124493) (xy 428.553317 -310.074671)
			(xy 428.569718 -310.026897) (xy 428.593759 -309.982474) (xy 428.624783 -309.942614) (xy 428.661945 -309.908404)
			(xy 428.704231 -309.880778) (xy 428.750487 -309.860488) (xy 428.799452 -309.848088) (xy 428.84979 -309.843917)
			(xy 428.900128 -309.848088) (xy 428.949093 -309.860488) (xy 428.995349 -309.880778) (xy 429.037635 -309.908404)
			(xy 429.074797 -309.942614) (xy 429.105821 -309.982474) (xy 429.129862 -310.026897) (xy 429.146263 -310.074671)
			(xy 429.154576 -310.124493) (xy 429.155098 -310.149748) (xy 429.154976 -310.163862) (xy 429.152431 -310.191975)
			(xy 429.150018 -310.205882) (xy 429.147478 -310.218328) (xy 429.154844 -310.24195) (xy 429.232314 -310.31942)
			(xy 429.255936 -310.326786) (xy 429.268636 -310.324246) (xy 429.292374 -310.320291) (xy 429.340479 -310.319018)
			(xy 429.364394 -310.321706) (xy 429.376332 -310.32323) (xy 429.398938 -310.315102) (xy 429.472344 -310.238902)
			(xy 429.479456 -310.216042) (xy 429.477424 -310.204104) (xy 429.475278 -310.190618) (xy 429.472987 -310.163403)
			(xy 429.472852 -310.149748) (xy 429.473356 -310.12404) (xy 429.481399 -310.073258) (xy 429.497287 -310.024359)
			(xy 429.52063 -309.978547) (xy 429.550851 -309.936951) (xy 429.587207 -309.900595) (xy 429.628803 -309.870374)
			(xy 429.674615 -309.847031) (xy 429.723514 -309.831143) (xy 429.774296 -309.8231) (xy 429.825712 -309.8231)
			(xy 429.876494 -309.831143) (xy 429.925393 -309.847031) (xy 429.971205 -309.870374) (xy 430.012801 -309.900595)
			(xy 430.049157 -309.936951) (xy 430.079378 -309.978547) (xy 430.102721 -310.024359) (xy 430.118609 -310.073258)
			(xy 430.126652 -310.12404) (xy 430.127156 -310.149748) (xy 430.126963 -310.163472) (xy 430.124546 -310.190813)
			(xy 430.12233 -310.204358) (xy 430.120298 -310.21655) (xy 430.12741 -310.23941) (xy 430.200816 -310.315864)
			(xy 430.223676 -310.323738) (xy 430.235614 -310.322214) (xy 430.255237 -310.319977) (xy 430.294731 -310.319977)
			(xy 430.314354 -310.322214) (xy 430.326292 -310.323738) (xy 430.349152 -310.315864) (xy 430.422558 -310.23941)
			(xy 430.42967 -310.21655) (xy 430.427638 -310.204358) (xy 430.425437 -310.190811) (xy 430.42302 -310.163471)
			(xy 430.422812 -310.149748) (xy 430.423316 -310.12404) (xy 430.431359 -310.073258) (xy 430.447247 -310.024359)
			(xy 430.47059 -309.978547) (xy 430.500811 -309.936951) (xy 430.537167 -309.900595) (xy 430.578763 -309.870374)
			(xy 430.624575 -309.847031) (xy 430.673474 -309.831143) (xy 430.724256 -309.8231) (xy 430.775672 -309.8231)
			(xy 430.826454 -309.831143) (xy 430.875353 -309.847031) (xy 430.921165 -309.870374) (xy 430.962761 -309.900595)
			(xy 430.999117 -309.936951) (xy 431.029338 -309.978547) (xy 431.052681 -310.024359) (xy 431.068569 -310.073258)
			(xy 431.076612 -310.12404) (xy 431.077116 -310.149748) (xy 431.076923 -310.163472) (xy 431.074506 -310.190813)
			(xy 431.07229 -310.204358) (xy 431.070258 -310.21655) (xy 431.07737 -310.23941) (xy 431.150776 -310.315864)
			(xy 431.173636 -310.323738) (xy 431.185574 -310.322214) (xy 431.209561 -310.319576) (xy 431.257795 -310.320974)
			(xy 431.281586 -310.325008) (xy 431.293778 -310.327294) (xy 431.317908 -310.319928) (xy 431.395124 -310.242712)
			(xy 431.40249 -310.218582) (xy 431.400204 -310.20639) (xy 431.397704 -310.192363) (xy 431.395031 -310.163995)
			(xy 431.39487 -310.149748) (xy 431.395352 -310.124924) (xy 431.403377 -310.075929) (xy 431.419223 -310.028878)
			(xy 431.442472 -309.985011) (xy 431.472513 -309.945483) (xy 431.508553 -309.911336) (xy 431.549643 -309.88347)
			(xy 431.5947 -309.862619) (xy 431.642536 -309.849332) (xy 431.691893 -309.84396) (xy 431.741468 -309.846644)
			(xy 431.771854 -309.85333) (xy 437.310782 -309.85333) (xy 437.314853 -309.797708) (xy 437.326979 -309.743271)
			(xy 437.346902 -309.69118) (xy 437.374198 -309.642545) (xy 437.408284 -309.598402) (xy 437.448433 -309.559693)
			(xy 437.493791 -309.527242) (xy 437.543391 -309.501741) (xy 437.596175 -309.483734) (xy 437.651018 -309.473604)
			(xy 437.706752 -309.471567) (xy 437.762189 -309.477667) (xy 437.816146 -309.491773) (xy 437.867475 -309.513585)
			(xy 437.915081 -309.542639) (xy 437.957949 -309.578314) (xy 437.995166 -309.619851) (xy 438.025939 -309.666364)
			(xy 438.037261 -309.690516) (xy 441.777372 -309.690516) (xy 441.781443 -309.634894) (xy 441.793569 -309.580457)
			(xy 441.813492 -309.528366) (xy 441.840788 -309.479731) (xy 441.874874 -309.435588) (xy 441.915023 -309.396879)
			(xy 441.960381 -309.364428) (xy 442.009981 -309.338927) (xy 442.062765 -309.32092) (xy 442.117608 -309.31079)
			(xy 442.173342 -309.308753) (xy 442.228779 -309.314853) (xy 442.282736 -309.328959) (xy 442.334065 -309.350771)
			(xy 442.381671 -309.379825) (xy 442.424539 -309.4155) (xy 442.461756 -309.457037) (xy 442.492529 -309.50355)
			(xy 442.516201 -309.554047) (xy 442.532269 -309.607454) (xy 442.540389 -309.66263) (xy 442.540898 -309.690516)
			(xy 442.540389 -309.718402) (xy 442.532269 -309.773578) (xy 442.516201 -309.826985) (xy 442.492529 -309.877482)
			(xy 442.461756 -309.923995) (xy 442.424539 -309.965532) (xy 442.381671 -310.001207) (xy 442.334065 -310.030261)
			(xy 442.282736 -310.052073) (xy 442.228779 -310.066179) (xy 442.173342 -310.072279) (xy 442.117608 -310.070242)
			(xy 442.062765 -310.060112) (xy 442.009981 -310.042105) (xy 441.960381 -310.016604) (xy 441.915023 -309.984153)
			(xy 441.874874 -309.945444) (xy 441.840788 -309.901301) (xy 441.813492 -309.852666) (xy 441.793569 -309.800575)
			(xy 441.781443 -309.746138) (xy 441.777372 -309.690516) (xy 438.037261 -309.690516) (xy 438.049611 -309.716861)
			(xy 438.065679 -309.770268) (xy 438.073799 -309.825444) (xy 438.074308 -309.85333) (xy 438.073799 -309.881216)
			(xy 438.065679 -309.936392) (xy 438.049611 -309.989799) (xy 438.025939 -310.040296) (xy 437.995166 -310.086809)
			(xy 437.957949 -310.128346) (xy 437.915081 -310.164021) (xy 437.867475 -310.193075) (xy 437.816146 -310.214887)
			(xy 437.762189 -310.228993) (xy 437.706752 -310.235093) (xy 437.651018 -310.233056) (xy 437.596175 -310.222926)
			(xy 437.543391 -310.204919) (xy 437.493791 -310.179418) (xy 437.448433 -310.146967) (xy 437.408284 -310.108258)
			(xy 437.374198 -310.064115) (xy 437.346902 -310.01548) (xy 437.326979 -309.963389) (xy 437.314853 -309.908952)
			(xy 437.310782 -309.85333) (xy 431.771854 -309.85333) (xy 431.789955 -309.857313) (xy 431.836078 -309.875687)
			(xy 431.87862 -309.901281) (xy 431.916462 -309.93342) (xy 431.948604 -309.971258) (xy 431.974202 -310.013799)
			(xy 431.992579 -310.05992) (xy 432.003253 -310.108407) (xy 432.005941 -310.157981) (xy 432.000573 -310.207338)
			(xy 431.98729 -310.255176) (xy 431.966443 -310.300235) (xy 431.93858 -310.341327) (xy 431.904437 -310.37737)
			(xy 431.864911 -310.407414) (xy 431.821046 -310.430667) (xy 431.773996 -310.446517) (xy 431.725002 -310.454546)
			(xy 431.700178 -310.455056) (xy 431.685996 -310.454869) (xy 431.657757 -310.452193) (xy 431.64379 -310.449722)
			(xy 431.631344 -310.447436) (xy 431.607214 -310.454802) (xy 431.530252 -310.532018) (xy 431.522632 -310.556148)
			(xy 431.525172 -310.568594) (xy 431.527966 -310.587644) (xy 431.528474 -310.5912) (xy 431.530506 -310.59882)
			(xy 431.533941 -310.609415) (xy 431.548247 -310.626452) (xy 431.568405 -310.635865) (xy 431.579528 -310.636412)
			(xy 438.103772 -310.636412) (xy 438.11444 -310.635396) (xy 438.11444 -310.635142) (xy 438.123609 -310.632761)
			(xy 438.139405 -310.622326) (xy 438.150364 -310.606889) (xy 438.153048 -310.597804) (xy 438.153302 -310.597296)
			(xy 438.153302 -310.597042) (xy 438.160347 -310.569533) (xy 438.181468 -310.516822) (xy 438.210168 -310.467823)
			(xy 438.245813 -310.423619) (xy 438.287616 -310.385186) (xy 438.334653 -310.353374) (xy 438.385885 -310.328883)
			(xy 438.440181 -310.312256) (xy 438.496342 -310.30386) (xy 438.553127 -310.30388) (xy 438.609282 -310.312316)
			(xy 438.663567 -310.328981) (xy 438.714782 -310.353508) (xy 438.761796 -310.385354) (xy 438.803572 -310.423817)
			(xy 438.839185 -310.468046) (xy 438.867851 -310.517065) (xy 438.888934 -310.56979) (xy 438.895998 -310.597296)
			(xy 438.900062 -310.614568) (xy 438.927748 -310.636412) (xy 444.550546 -310.636412) (xy 444.559723 -310.636042)
			(xy 444.576899 -310.62958) (xy 444.590662 -310.617442) (xy 444.59525 -310.609488) (xy 444.615316 -310.57215)
			(xy 444.636144 -310.533288) (xy 444.640567 -310.524224) (xy 444.642553 -310.50417) (xy 444.639954 -310.494426)
			(xy 444.635128 -310.478678) (xy 444.631064 -310.472582) (xy 444.58616 -310.403724) (xy 444.502299 -310.262312)
			(xy 444.425416 -310.116988) (xy 444.355693 -309.968096) (xy 444.293294 -309.815989) (xy 444.238369 -309.661027)
			(xy 444.191046 -309.503577) (xy 444.151438 -309.344011) (xy 444.119638 -309.182707) (xy 444.095722 -309.020048)
			(xy 444.079747 -308.856418) (xy 444.07175 -308.692204) (xy 444.071248 -308.61) (xy 444.071757 -308.527069)
			(xy 444.079895 -308.361408) (xy 444.096152 -308.196346) (xy 444.120489 -308.03228) (xy 444.152846 -307.869606)
			(xy 444.193147 -307.708715) (xy 444.241294 -307.549996) (xy 444.29717 -307.39383) (xy 444.360642 -307.240595)
			(xy 444.431556 -307.090658) (xy 444.509742 -306.944381) (xy 444.595011 -306.802117) (xy 444.687158 -306.664208)
			(xy 444.78596 -306.530987) (xy 444.891181 -306.402774) (xy 445.002565 -306.279878) (xy 445.119846 -306.162596)
			(xy 445.24274 -306.051209) (xy 445.370952 -305.945987) (xy 445.504172 -305.847183) (xy 445.64208 -305.755034)
			(xy 445.784343 -305.669764) (xy 445.930618 -305.591576) (xy 446.080554 -305.52066) (xy 446.233789 -305.457186)
			(xy 446.389954 -305.401307) (xy 446.548673 -305.353159) (xy 446.709563 -305.312856) (xy 446.872237 -305.280496)
			(xy 447.036302 -305.256158) (xy 447.201364 -305.239898) (xy 447.367025 -305.231758) (xy 447.449956 -305.231292)
			(xy 448.239388 -305.231292) (xy 448.249259 -305.230819) (xy 448.267539 -305.223357) (xy 448.274948 -305.216814)
			(xy 448.275202 -305.21656) (xy 449.604892 -303.88687) (xy 449.612287 -303.880015) (xy 449.630885 -303.872266)
			(xy 449.64096 -303.871884) (xy 463.699352 -303.871884) (xy 463.709226 -303.871418) (xy 463.727514 -303.863964)
			(xy 463.734912 -303.857406) (xy 463.735166 -303.857152) (xy 464.43646 -303.155858) (xy 464.436968 -303.15535)
			(xy 464.443549 -303.147968) (xy 464.450998 -303.129669) (xy 464.451446 -303.11979) (xy 464.451446 -283.526992)
			(xy 464.45102 -283.516924) (xy 464.443297 -283.498326) (xy 464.43646 -283.490924) (xy 462.352898 -281.407362)
			(xy 462.346058 -281.399961) (xy 462.338338 -281.381363) (xy 462.337912 -281.371294) (xy 462.337912 -260.05917)
			(xy 462.337484 -260.049102) (xy 462.329763 -260.030504) (xy 462.322926 -260.023102) (xy 457.08189 -254.782066)
			(xy 457.074778 -254.7747) (xy 457.055982 -254.76708) (xy 398.629632 -254.76708) (xy 398.619567 -254.767515)
			(xy 398.600978 -254.775244) (xy 398.593564 -254.782066) (xy 397.610076 -255.765554) (xy 397.60271 -255.772666)
			(xy 397.59509 -255.791462) (xy 397.59509 -261.550912) (xy 397.595001 -261.555932) (xy 397.593088 -261.565786)
			(xy 397.59128 -261.57047) (xy 397.583914 -261.587742) (xy 397.582119 -261.592429) (xy 397.580209 -261.602281)
			(xy 397.580104 -261.6073) (xy 397.580104 -270.89989) (xy 433.198785 -270.89989) (xy 433.202791 -270.704835)
			(xy 433.214801 -270.510109) (xy 433.234796 -270.31604) (xy 433.262741 -270.122956) (xy 433.29859 -269.931181)
			(xy 433.342282 -269.741041) (xy 433.393743 -269.552854) (xy 433.452887 -269.366939) (xy 433.519614 -269.183608)
			(xy 433.593811 -269.003172) (xy 433.675353 -268.825934) (xy 433.764104 -268.652193) (xy 433.859912 -268.482242)
			(xy 433.962617 -268.316368) (xy 434.072045 -268.15485) (xy 434.188012 -267.997961) (xy 434.310323 -267.845966)
			(xy 434.43877 -267.69912) (xy 434.573138 -267.557671) (xy 434.7132 -267.421858) (xy 434.858719 -267.291909)
			(xy 435.009451 -267.168045) (xy 435.165141 -267.050473) (xy 435.325527 -266.939393) (xy 435.490338 -266.83499)
			(xy 435.659296 -266.737442) (xy 435.832117 -266.646913) (xy 436.008509 -266.563555) (xy 436.188174 -266.487509)
			(xy 436.370809 -266.418904) (xy 436.556108 -266.357854) (xy 436.743756 -266.304464) (xy 436.933438 -266.258822)
			(xy 437.124835 -266.221006) (xy 437.317622 -266.19108) (xy 437.511475 -266.169094) (xy 437.706068 -266.155085)
			(xy 437.901071 -266.149077) (xy 438.096157 -266.15108) (xy 438.290996 -266.161091) (xy 438.48526 -266.179092)
			(xy 438.678621 -266.205054) (xy 438.870754 -266.238932) (xy 439.061333 -266.280669) (xy 439.250038 -266.330196)
			(xy 439.436551 -266.387428) (xy 439.620557 -266.452269) (xy 439.801745 -266.52461) (xy 439.979811 -266.604328)
			(xy 440.154454 -266.69129) (xy 440.32538 -266.785349) (xy 440.492299 -266.886345) (xy 440.654932 -266.99411)
			(xy 440.813003 -267.10846) (xy 440.966246 -267.229203) (xy 441.114403 -267.356137) (xy 441.257224 -267.489045)
			(xy 441.394468 -267.627705) (xy 441.525904 -267.771883) (xy 441.651309 -267.921336) (xy 441.770473 -268.07581)
			(xy 441.883194 -268.235047) (xy 441.989283 -268.398778) (xy 442.088561 -268.566725) (xy 442.180859 -268.738608)
			(xy 442.266024 -268.914134) (xy 442.34391 -269.093009) (xy 442.414387 -269.274931) (xy 442.477335 -269.459593)
			(xy 442.53265 -269.646683) (xy 442.580236 -269.835887) (xy 442.620015 -270.026884) (xy 442.651919 -270.219354)
			(xy 442.675894 -270.412972) (xy 442.6919 -270.60741) (xy 442.699909 -270.802342) (xy 442.70041 -270.89989)
			(xy 442.699909 -270.997438) (xy 442.6919 -271.19237) (xy 442.675894 -271.386808) (xy 442.651919 -271.580426)
			(xy 442.620015 -271.772896) (xy 442.580236 -271.963893) (xy 442.53265 -272.153097) (xy 442.477335 -272.340187)
			(xy 442.414387 -272.524849) (xy 442.34391 -272.706771) (xy 442.266024 -272.885646) (xy 442.222389 -272.975578)
			(xy 450.721984 -272.975578) (xy 450.722417 -272.948206) (xy 450.730239 -272.894025) (xy 450.745735 -272.841521)
			(xy 450.768585 -272.791774) (xy 450.798318 -272.74581) (xy 450.815964 -272.72488) (xy 450.82206 -272.717768)
			(xy 450.82841 -272.70075) (xy 450.82841 -272.615406) (xy 450.82206 -272.598388) (xy 450.815964 -272.591276)
			(xy 450.798341 -272.570331) (xy 450.768628 -272.524361) (xy 450.74579 -272.474617) (xy 450.730295 -272.422119)
			(xy 450.722461 -272.367946) (xy 450.721984 -272.340578) (xy 450.722457 -272.313327) (xy 450.730217 -272.259379)
			(xy 450.745574 -272.207084) (xy 450.768217 -272.157508) (xy 450.797685 -272.111658) (xy 450.833378 -272.070468)
			(xy 450.874569 -272.034777) (xy 450.92042 -272.005311) (xy 450.969997 -271.982669) (xy 451.022293 -271.967314)
			(xy 451.076241 -271.959556) (xy 451.103492 -271.95907) (xy 451.13223 -271.959607) (xy 451.189057 -271.968227)
			(xy 451.243947 -271.985275) (xy 451.295659 -272.010363) (xy 451.343022 -272.042925) (xy 451.36435 -272.062194)
			(xy 451.371462 -272.068798) (xy 451.388988 -272.07591) (xy 451.478396 -272.07591) (xy 451.495922 -272.068798)
			(xy 451.503034 -272.062194) (xy 451.524361 -272.042924) (xy 451.571724 -272.010359) (xy 451.623435 -271.985268)
			(xy 451.678326 -271.968218) (xy 451.735153 -271.959596) (xy 451.792631 -271.959596) (xy 451.849458 -271.968218)
			(xy 451.904349 -271.985268) (xy 451.95606 -272.010359) (xy 452.003423 -272.042924) (xy 452.02475 -272.062194)
			(xy 452.031862 -272.068798) (xy 452.049388 -272.07591) (xy 452.138796 -272.07591) (xy 452.156322 -272.068798)
			(xy 452.163434 -272.062194) (xy 452.184761 -272.042924) (xy 452.232124 -272.010359) (xy 452.283835 -271.985268)
			(xy 452.338726 -271.968218) (xy 452.395553 -271.959596) (xy 452.453031 -271.959596) (xy 452.509858 -271.968218)
			(xy 452.564749 -271.985268) (xy 452.61646 -272.010359) (xy 452.663823 -272.042924) (xy 452.68515 -272.062194)
			(xy 452.692262 -272.068798) (xy 452.709788 -272.07591) (xy 452.799196 -272.07591) (xy 452.816722 -272.068798)
			(xy 452.823834 -272.062194) (xy 452.845173 -272.042937) (xy 452.892531 -272.010367) (xy 452.944239 -271.985271)
			(xy 452.999128 -271.968217) (xy 453.055954 -271.959592) (xy 453.084692 -271.95907) (xy 453.111942 -271.959585)
			(xy 453.165888 -271.96734) (xy 453.21818 -271.982693) (xy 453.267756 -272.005332) (xy 453.313606 -272.034795)
			(xy 453.354795 -272.070483) (xy 453.390487 -272.11167) (xy 453.419954 -272.157517) (xy 453.442596 -272.207091)
			(xy 453.457954 -272.259383) (xy 453.465713 -272.313328) (xy 453.4662 -272.340578) (xy 453.465721 -272.367948)
			(xy 453.457906 -272.422126) (xy 453.44242 -272.474629) (xy 453.419581 -272.524376) (xy 453.38986 -272.570344)
			(xy 453.37222 -272.591276) (xy 453.366124 -272.598388) (xy 453.359774 -272.615406) (xy 453.359774 -272.70075)
			(xy 453.366124 -272.717768) (xy 453.37222 -272.72488) (xy 453.389866 -272.745806) (xy 453.419576 -272.791781)
			(xy 453.442411 -272.84153) (xy 453.4579 -272.894032) (xy 453.465388 -272.94586) (xy 454.465436 -272.94586)
			(xy 454.465928 -272.918491) (xy 454.473739 -272.864312) (xy 454.489221 -272.811809) (xy 454.512057 -272.762062)
			(xy 454.541777 -272.716094) (xy 454.559416 -272.695162) (xy 454.565512 -272.68805) (xy 454.571862 -272.671032)
			(xy 454.571862 -272.585688) (xy 454.565512 -272.56867) (xy 454.559416 -272.561558) (xy 454.541793 -272.540613)
			(xy 454.512078 -272.494644) (xy 454.489239 -272.4449) (xy 454.473744 -272.392402) (xy 454.465912 -272.338228)
			(xy 454.465436 -272.31086) (xy 454.465818 -272.283604) (xy 454.473581 -272.229648) (xy 454.488945 -272.177346)
			(xy 454.511595 -272.127763) (xy 454.541071 -272.081907) (xy 454.576774 -272.040714) (xy 454.617975 -272.005021)
			(xy 454.663836 -271.975555) (xy 454.713425 -271.952915) (xy 454.76573 -271.937563) (xy 454.819688 -271.929812)
			(xy 454.846944 -271.929352) (xy 454.875683 -271.929862) (xy 454.932511 -271.93849) (xy 454.987401 -271.955544)
			(xy 455.039113 -271.980638) (xy 455.086475 -272.013205) (xy 455.107802 -272.032476) (xy 455.114914 -272.03908)
			(xy 455.13244 -272.046192) (xy 455.221848 -272.046192) (xy 455.239374 -272.03908) (xy 455.246486 -272.032476)
			(xy 455.267813 -272.013206) (xy 455.315176 -271.980641) (xy 455.366887 -271.95555) (xy 455.421778 -271.9385)
			(xy 455.478605 -271.929878) (xy 455.536083 -271.929878) (xy 455.59291 -271.9385) (xy 455.647801 -271.95555)
			(xy 455.699512 -271.980641) (xy 455.746875 -272.013206) (xy 455.768202 -272.032476) (xy 455.775314 -272.03908)
			(xy 455.79284 -272.046192) (xy 455.882248 -272.046192) (xy 455.899774 -272.03908) (xy 455.906886 -272.032476)
			(xy 455.928213 -272.013206) (xy 455.975576 -271.980641) (xy 456.027287 -271.95555) (xy 456.082178 -271.9385)
			(xy 456.139005 -271.929878) (xy 456.196483 -271.929878) (xy 456.25331 -271.9385) (xy 456.308201 -271.95555)
			(xy 456.359912 -271.980641) (xy 456.407275 -272.013206) (xy 456.428602 -272.032476) (xy 456.435714 -272.03908)
			(xy 456.45324 -272.046192) (xy 456.542648 -272.046192) (xy 456.560174 -272.03908) (xy 456.567286 -272.032476)
			(xy 456.588601 -272.013191) (xy 456.635965 -271.980625) (xy 456.68768 -271.955535) (xy 456.742574 -271.938488)
			(xy 456.799404 -271.92987) (xy 456.828144 -271.929352) (xy 456.855395 -271.929837) (xy 456.90934 -271.937598)
			(xy 456.961632 -271.952957) (xy 457.011207 -271.9756) (xy 457.057055 -272.005067) (xy 457.098244 -272.040759)
			(xy 457.133935 -272.081948) (xy 457.163402 -272.127796) (xy 457.186044 -272.177371) (xy 457.201403 -272.229664)
			(xy 457.209164 -272.283609) (xy 457.209652 -272.31086) (xy 457.209174 -272.33823) (xy 457.201361 -272.392409)
			(xy 457.185875 -272.444912) (xy 457.163036 -272.49466) (xy 457.133313 -272.540626) (xy 457.115672 -272.561558)
			(xy 457.109576 -272.56867) (xy 457.103226 -272.585688) (xy 457.103226 -272.671032) (xy 457.109576 -272.68805)
			(xy 457.115672 -272.695162) (xy 457.133302 -272.716101) (xy 457.163016 -272.762072) (xy 457.185855 -272.811817)
			(xy 457.201348 -272.864317) (xy 457.209177 -272.918491) (xy 457.209652 -272.94586) (xy 457.209085 -272.973108)
			(xy 457.201335 -273.027051) (xy 457.185987 -273.079341) (xy 457.163354 -273.128915) (xy 457.133896 -273.174764)
			(xy 457.098213 -273.215953) (xy 457.088061 -273.224752) (xy 459.941166 -273.224752) (xy 459.945237 -273.16913)
			(xy 459.957363 -273.114693) (xy 459.977286 -273.062602) (xy 460.004582 -273.013967) (xy 460.038668 -272.969824)
			(xy 460.078817 -272.931115) (xy 460.124175 -272.898664) (xy 460.173775 -272.873163) (xy 460.226559 -272.855156)
			(xy 460.281402 -272.845026) (xy 460.337136 -272.842989) (xy 460.392573 -272.849089) (xy 460.44653 -272.863195)
			(xy 460.497859 -272.885007) (xy 460.545465 -272.914061) (xy 460.588333 -272.949736) (xy 460.62555 -272.991273)
			(xy 460.656323 -273.037786) (xy 460.679995 -273.088283) (xy 460.696063 -273.14169) (xy 460.704183 -273.196866)
			(xy 460.704692 -273.224752) (xy 460.704183 -273.252638) (xy 460.696063 -273.307814) (xy 460.679995 -273.361221)
			(xy 460.656323 -273.411718) (xy 460.62555 -273.458231) (xy 460.588333 -273.499768) (xy 460.545465 -273.535443)
			(xy 460.497859 -273.564497) (xy 460.44653 -273.586309) (xy 460.392573 -273.600415) (xy 460.337136 -273.606515)
			(xy 460.281402 -273.604478) (xy 460.226559 -273.594348) (xy 460.173775 -273.576341) (xy 460.124175 -273.55084)
			(xy 460.078817 -273.518389) (xy 460.038668 -273.47968) (xy 460.004582 -273.435537) (xy 459.977286 -273.386902)
			(xy 459.957363 -273.334811) (xy 459.945237 -273.280374) (xy 459.941166 -273.224752) (xy 457.088061 -273.224752)
			(xy 457.057031 -273.251645) (xy 457.011189 -273.281113) (xy 456.96162 -273.303758) (xy 456.909333 -273.319117)
			(xy 456.855392 -273.326879) (xy 456.828144 -273.327368) (xy 456.799405 -273.32686) (xy 456.742577 -273.318231)
			(xy 456.687687 -273.301176) (xy 456.635976 -273.276082) (xy 456.588613 -273.243515) (xy 456.567286 -273.224244)
			(xy 456.560174 -273.21764) (xy 456.542648 -273.210528) (xy 456.45324 -273.210528) (xy 456.435714 -273.21764)
			(xy 456.428602 -273.224244) (xy 456.407275 -273.243514) (xy 456.359912 -273.276079) (xy 456.308201 -273.30117)
			(xy 456.25331 -273.31822) (xy 456.196483 -273.326842) (xy 456.139005 -273.326842) (xy 456.082178 -273.31822)
			(xy 456.027287 -273.30117) (xy 455.975576 -273.276079) (xy 455.928213 -273.243514) (xy 455.906886 -273.224244)
			(xy 455.899774 -273.21764) (xy 455.882248 -273.210528) (xy 455.79284 -273.210528) (xy 455.775314 -273.21764)
			(xy 455.768202 -273.224244) (xy 455.746875 -273.243514) (xy 455.699512 -273.276079) (xy 455.647801 -273.30117)
			(xy 455.59291 -273.31822) (xy 455.536083 -273.326842) (xy 455.478605 -273.326842) (xy 455.421778 -273.31822)
			(xy 455.366887 -273.30117) (xy 455.315176 -273.276079) (xy 455.267813 -273.243514) (xy 455.246486 -273.224244)
			(xy 455.239374 -273.21764) (xy 455.221848 -273.210528) (xy 455.13244 -273.210528) (xy 455.114914 -273.21764)
			(xy 455.107802 -273.224244) (xy 455.086495 -273.243538) (xy 455.039128 -273.276102) (xy 454.987411 -273.30119)
			(xy 454.932516 -273.318235) (xy 454.875684 -273.326851) (xy 454.846944 -273.327368) (xy 454.81969 -273.326904)
			(xy 454.765737 -273.319152) (xy 454.713437 -273.303799) (xy 454.663855 -273.281159) (xy 454.617999 -273.251692)
			(xy 454.576805 -273.215998) (xy 454.541111 -273.174804) (xy 454.511643 -273.128949) (xy 454.489002 -273.079367)
			(xy 454.473649 -273.027066) (xy 454.465897 -272.973114) (xy 454.465436 -272.94586) (xy 453.465388 -272.94586)
			(xy 453.465727 -272.948208) (xy 453.4662 -272.975578) (xy 453.465724 -273.002831) (xy 453.45797 -273.056782)
			(xy 453.442616 -273.10908) (xy 453.419976 -273.15866) (xy 453.390509 -273.204514) (xy 453.354817 -273.245707)
			(xy 453.313625 -273.281401) (xy 453.267773 -273.310869) (xy 453.218193 -273.333511) (xy 453.165895 -273.348867)
			(xy 453.111945 -273.356623) (xy 453.084692 -273.357086) (xy 453.055954 -273.356544) (xy 452.999129 -273.347922)
			(xy 452.944239 -273.330875) (xy 452.892527 -273.305788) (xy 452.845163 -273.273229) (xy 452.823834 -273.253962)
			(xy 452.816722 -273.247358) (xy 452.799196 -273.240246) (xy 452.709788 -273.240246) (xy 452.692262 -273.247358)
			(xy 452.68515 -273.253962) (xy 452.663823 -273.273232) (xy 452.61646 -273.305797) (xy 452.564749 -273.330888)
			(xy 452.509858 -273.347938) (xy 452.453031 -273.35656) (xy 452.395553 -273.35656) (xy 452.338726 -273.347938)
			(xy 452.283835 -273.330888) (xy 452.232124 -273.305797) (xy 452.184761 -273.273232) (xy 452.163434 -273.253962)
			(xy 452.156322 -273.247358) (xy 452.138796 -273.240246) (xy 452.049388 -273.240246) (xy 452.031862 -273.247358)
			(xy 452.02475 -273.253962) (xy 452.003423 -273.273232) (xy 451.95606 -273.305797) (xy 451.904349 -273.330888)
			(xy 451.849458 -273.347938) (xy 451.792631 -273.35656) (xy 451.735153 -273.35656) (xy 451.678326 -273.347938)
			(xy 451.623435 -273.330888) (xy 451.571724 -273.305797) (xy 451.524361 -273.273232) (xy 451.503034 -273.253962)
			(xy 451.495922 -273.247358) (xy 451.478396 -273.240246) (xy 451.388988 -273.240246) (xy 451.371462 -273.247358)
			(xy 451.36435 -273.253962) (xy 451.343026 -273.273236) (xy 451.295663 -273.305802) (xy 451.243951 -273.330894)
			(xy 451.189059 -273.347944) (xy 451.132231 -273.356566) (xy 451.103492 -273.357086) (xy 451.076238 -273.356652)
			(xy 451.022285 -273.348893) (xy 450.969985 -273.333535) (xy 450.920403 -273.31089) (xy 450.874549 -273.281419)
			(xy 450.833356 -273.245723) (xy 450.797663 -273.204527) (xy 450.768195 -273.15867) (xy 450.745554 -273.109087)
			(xy 450.7302 -273.056786) (xy 450.722446 -273.002832) (xy 450.721984 -272.975578) (xy 442.222389 -272.975578)
			(xy 442.180859 -273.061172) (xy 442.088561 -273.233055) (xy 441.989283 -273.401002) (xy 441.883194 -273.564733)
			(xy 441.770473 -273.72397) (xy 441.651309 -273.878444) (xy 441.525904 -274.027897) (xy 441.394468 -274.172075)
			(xy 441.257224 -274.310735) (xy 441.114403 -274.443643) (xy 440.966246 -274.570577) (xy 440.813003 -274.69132)
			(xy 440.654932 -274.80567) (xy 440.492299 -274.913435) (xy 440.32538 -275.014431) (xy 440.154454 -275.10849)
			(xy 439.979811 -275.195452) (xy 439.801745 -275.27517) (xy 439.620557 -275.347511) (xy 439.436551 -275.412352)
			(xy 439.250038 -275.469584) (xy 439.061333 -275.519111) (xy 438.870754 -275.560848) (xy 438.678621 -275.594726)
			(xy 438.48526 -275.620688) (xy 438.399789 -275.628608) (xy 454.42378 -275.628608) (xy 454.424296 -275.599308)
			(xy 454.433244 -275.541395) (xy 454.450947 -275.485532) (xy 454.476987 -275.433036) (xy 454.510752 -275.385141)
			(xy 454.530714 -275.363686) (xy 454.537318 -275.356828) (xy 454.544684 -275.339556) (xy 454.54697 -275.251672)
			(xy 454.54062 -275.233892) (xy 454.53427 -275.22678) (xy 454.516712 -275.205871) (xy 454.487157 -275.159963)
			(xy 454.464446 -275.110312) (xy 454.449043 -275.057931) (xy 454.441263 -275.003889) (xy 454.440798 -274.97659)
			(xy 454.441284 -274.949339) (xy 454.44904 -274.895391) (xy 454.464395 -274.843096) (xy 454.487037 -274.793519)
			(xy 454.516503 -274.747669) (xy 454.552194 -274.706478) (xy 454.593385 -274.670787) (xy 454.639235 -274.641321)
			(xy 454.688812 -274.618679) (xy 454.741107 -274.603324) (xy 454.795055 -274.595568) (xy 454.849557 -274.595568)
			(xy 454.903505 -274.603324) (xy 454.9558 -274.618679) (xy 455.005377 -274.641321) (xy 455.051227 -274.670787)
			(xy 455.092418 -274.706478) (xy 455.128109 -274.747669) (xy 455.133539 -274.756118) (xy 457.316076 -274.756118)
			(xy 457.320147 -274.700496) (xy 457.332273 -274.646059) (xy 457.352196 -274.593968) (xy 457.379492 -274.545333)
			(xy 457.413578 -274.50119) (xy 457.453727 -274.462481) (xy 457.499085 -274.43003) (xy 457.548685 -274.404529)
			(xy 457.601469 -274.386522) (xy 457.656312 -274.376392) (xy 457.712046 -274.374355) (xy 457.767483 -274.380455)
			(xy 457.82144 -274.394561) (xy 457.872769 -274.416373) (xy 457.920375 -274.445427) (xy 457.963243 -274.481102)
			(xy 458.00046 -274.522639) (xy 458.031233 -274.569152) (xy 458.054905 -274.619649) (xy 458.070973 -274.673056)
			(xy 458.079093 -274.728232) (xy 458.079602 -274.756118) (xy 458.079093 -274.784004) (xy 458.070973 -274.83918)
			(xy 458.055232 -274.8915) (xy 459.445866 -274.8915) (xy 459.449937 -274.835878) (xy 459.462063 -274.781441)
			(xy 459.481986 -274.72935) (xy 459.509282 -274.680715) (xy 459.543368 -274.636572) (xy 459.583517 -274.597863)
			(xy 459.628875 -274.565412) (xy 459.678475 -274.539911) (xy 459.731259 -274.521904) (xy 459.786102 -274.511774)
			(xy 459.841836 -274.509737) (xy 459.897273 -274.515837) (xy 459.95123 -274.529943) (xy 460.002559 -274.551755)
			(xy 460.050165 -274.580809) (xy 460.093033 -274.616484) (xy 460.13025 -274.658021) (xy 460.161023 -274.704534)
			(xy 460.184695 -274.755031) (xy 460.200763 -274.808438) (xy 460.208883 -274.863614) (xy 460.209392 -274.8915)
			(xy 460.208883 -274.919386) (xy 460.200763 -274.974562) (xy 460.184695 -275.027969) (xy 460.161023 -275.078466)
			(xy 460.13025 -275.124979) (xy 460.093033 -275.166516) (xy 460.050165 -275.202191) (xy 460.002559 -275.231245)
			(xy 459.95123 -275.253057) (xy 459.897273 -275.267163) (xy 459.841836 -275.273263) (xy 459.786102 -275.271226)
			(xy 459.731259 -275.261096) (xy 459.678475 -275.243089) (xy 459.628875 -275.217588) (xy 459.583517 -275.185137)
			(xy 459.543368 -275.146428) (xy 459.509282 -275.102285) (xy 459.481986 -275.05365) (xy 459.462063 -275.001559)
			(xy 459.449937 -274.947122) (xy 459.445866 -274.8915) (xy 458.055232 -274.8915) (xy 458.054905 -274.892587)
			(xy 458.031233 -274.943084) (xy 458.00046 -274.989597) (xy 457.963243 -275.031134) (xy 457.920375 -275.066809)
			(xy 457.872769 -275.095863) (xy 457.82144 -275.117675) (xy 457.767483 -275.131781) (xy 457.712046 -275.137881)
			(xy 457.656312 -275.135844) (xy 457.601469 -275.125714) (xy 457.548685 -275.107707) (xy 457.499085 -275.082206)
			(xy 457.453727 -275.049755) (xy 457.413578 -275.011046) (xy 457.379492 -274.966903) (xy 457.352196 -274.918268)
			(xy 457.332273 -274.866177) (xy 457.320147 -274.81174) (xy 457.316076 -274.756118) (xy 455.133539 -274.756118)
			(xy 455.157575 -274.793519) (xy 455.180217 -274.843096) (xy 455.195572 -274.895391) (xy 455.203328 -274.949339)
			(xy 455.203814 -274.97659) (xy 455.203299 -275.00589) (xy 455.19435 -275.063803) (xy 455.176648 -275.119666)
			(xy 455.150607 -275.172162) (xy 455.116842 -275.220057) (xy 455.09688 -275.241512) (xy 455.090276 -275.24837)
			(xy 455.08291 -275.265642) (xy 455.081278 -275.32838) (xy 460.941672 -275.32838) (xy 460.945743 -275.272758)
			(xy 460.957869 -275.218321) (xy 460.977792 -275.16623) (xy 461.005088 -275.117595) (xy 461.039174 -275.073452)
			(xy 461.079323 -275.034743) (xy 461.124681 -275.002292) (xy 461.174281 -274.976791) (xy 461.227065 -274.958784)
			(xy 461.281908 -274.948654) (xy 461.337642 -274.946617) (xy 461.393079 -274.952717) (xy 461.447036 -274.966823)
			(xy 461.498365 -274.988635) (xy 461.545971 -275.017689) (xy 461.588839 -275.053364) (xy 461.626056 -275.094901)
			(xy 461.656829 -275.141414) (xy 461.680501 -275.191911) (xy 461.696569 -275.245318) (xy 461.704689 -275.300494)
			(xy 461.705198 -275.32838) (xy 461.704689 -275.356266) (xy 461.696569 -275.411442) (xy 461.680501 -275.464849)
			(xy 461.656829 -275.515346) (xy 461.626056 -275.561859) (xy 461.588839 -275.603396) (xy 461.545971 -275.639071)
			(xy 461.498365 -275.668125) (xy 461.447036 -275.689937) (xy 461.393079 -275.704043) (xy 461.337642 -275.710143)
			(xy 461.281908 -275.708106) (xy 461.227065 -275.697976) (xy 461.174281 -275.679969) (xy 461.124681 -275.654468)
			(xy 461.079323 -275.622017) (xy 461.039174 -275.583308) (xy 461.005088 -275.539165) (xy 460.977792 -275.49053)
			(xy 460.957869 -275.438439) (xy 460.945743 -275.384002) (xy 460.941672 -275.32838) (xy 455.081278 -275.32838)
			(xy 455.080624 -275.353526) (xy 455.086974 -275.371306) (xy 455.093324 -275.378418) (xy 455.11088 -275.399329)
			(xy 455.140436 -275.445236) (xy 455.163147 -275.494886) (xy 455.17855 -275.547267) (xy 455.186331 -275.601309)
			(xy 455.186796 -275.628608) (xy 455.18631 -275.655859) (xy 455.178554 -275.709807) (xy 455.163199 -275.762102)
			(xy 455.140557 -275.811679) (xy 455.111091 -275.857529) (xy 455.0754 -275.89872) (xy 455.034209 -275.934411)
			(xy 454.988359 -275.963877) (xy 454.938782 -275.986519) (xy 454.886487 -276.001874) (xy 454.832539 -276.00963)
			(xy 454.778037 -276.00963) (xy 454.724089 -276.001874) (xy 454.671794 -275.986519) (xy 454.622217 -275.963877)
			(xy 454.576367 -275.934411) (xy 454.535176 -275.89872) (xy 454.499485 -275.857529) (xy 454.470019 -275.811679)
			(xy 454.447377 -275.762102) (xy 454.432022 -275.709807) (xy 454.424266 -275.655859) (xy 454.42378 -275.628608)
			(xy 438.399789 -275.628608) (xy 438.290996 -275.638689) (xy 438.096157 -275.6487) (xy 437.901071 -275.650703)
			(xy 437.706068 -275.644695) (xy 437.511475 -275.630686) (xy 437.317622 -275.6087) (xy 437.124835 -275.578774)
			(xy 436.933438 -275.540958) (xy 436.743756 -275.495316) (xy 436.556108 -275.441926) (xy 436.370809 -275.380876)
			(xy 436.188174 -275.312271) (xy 436.008509 -275.236225) (xy 435.832117 -275.152867) (xy 435.659296 -275.062338)
			(xy 435.490338 -274.96479) (xy 435.325527 -274.860387) (xy 435.165141 -274.749307) (xy 435.009451 -274.631735)
			(xy 434.858719 -274.507871) (xy 434.7132 -274.377922) (xy 434.573138 -274.242109) (xy 434.43877 -274.10066)
			(xy 434.310323 -273.953814) (xy 434.188012 -273.801819) (xy 434.072045 -273.64493) (xy 433.962617 -273.483412)
			(xy 433.859912 -273.317538) (xy 433.764104 -273.147587) (xy 433.675353 -272.973846) (xy 433.593811 -272.796608)
			(xy 433.519614 -272.616172) (xy 433.452887 -272.432841) (xy 433.393743 -272.246926) (xy 433.342282 -272.058739)
			(xy 433.29859 -271.868599) (xy 433.262741 -271.676824) (xy 433.234796 -271.48374) (xy 433.214801 -271.289671)
			(xy 433.202791 -271.094945) (xy 433.198785 -270.89989) (xy 397.580104 -270.89989) (xy 397.580104 -271.707356)
			(xy 397.580535 -271.717432) (xy 397.588315 -271.73602) (xy 397.60268 -271.750151) (xy 397.611854 -271.754346)
			(xy 397.713962 -271.795494) (xy 397.744188 -271.789144) (xy 397.75511 -271.777714) (xy 397.772509 -271.76041)
			(xy 397.811805 -271.731025) (xy 397.855292 -271.708296) (xy 397.901851 -271.692807) (xy 397.950286 -271.684955)
			(xy 397.97482 -271.684496) (xy 398.001405 -271.685065) (xy 398.053772 -271.694264) (xy 398.103754 -271.712398)
			(xy 398.149837 -271.738918) (xy 398.190628 -271.773023) (xy 398.224892 -271.813679) (xy 398.238726 -271.836388)
			(xy 398.243679 -271.844098) (xy 398.25787 -271.855673) (xy 398.266412 -271.858994) (xy 398.296384 -271.8689)
			(xy 398.305211 -271.871474) (xy 398.323572 -271.870816) (xy 398.332198 -271.86763) (xy 398.360299 -271.856724)
			(xy 398.419411 -271.844962) (xy 398.449546 -271.844262) (xy 398.474801 -271.844787) (xy 398.524622 -271.853108)
			(xy 398.572394 -271.869514) (xy 398.616814 -271.893559) (xy 398.656672 -271.924587) (xy 398.690879 -271.961752)
			(xy 398.718504 -272.004039) (xy 398.738792 -272.050296) (xy 398.75119 -272.099262) (xy 398.755359 -272.14957)
			(xy 400.043916 -272.14957) (xy 400.047876 -272.100516) (xy 400.059653 -272.052732) (xy 400.078944 -272.007456)
			(xy 400.105247 -271.96586) (xy 400.137882 -271.929023) (xy 400.176003 -271.897898) (xy 400.218624 -271.873291)
			(xy 400.26464 -271.855839) (xy 400.312859 -271.845995) (xy 400.362034 -271.844014) (xy 400.410889 -271.849946)
			(xy 400.45816 -271.863638) (xy 400.502622 -271.884736) (xy 400.543125 -271.912692) (xy 400.578618 -271.946784)
			(xy 400.608183 -271.986128) (xy 400.631054 -272.029705) (xy 400.646638 -272.076386) (xy 400.654533 -272.124963)
			(xy 400.655028 -272.14957) (xy 401.943836 -272.14957) (xy 401.947796 -272.100516) (xy 401.959573 -272.052732)
			(xy 401.978864 -272.007456) (xy 402.005167 -271.96586) (xy 402.037802 -271.929023) (xy 402.075923 -271.897898)
			(xy 402.118544 -271.873291) (xy 402.16456 -271.855839) (xy 402.212779 -271.845995) (xy 402.261954 -271.844014)
			(xy 402.310809 -271.849946) (xy 402.35808 -271.863638) (xy 402.402542 -271.884736) (xy 402.443045 -271.912692)
			(xy 402.478538 -271.946784) (xy 402.508103 -271.986128) (xy 402.530974 -272.029705) (xy 402.546558 -272.076386)
			(xy 402.554453 -272.124963) (xy 402.554948 -272.14957) (xy 403.843756 -272.14957) (xy 403.847716 -272.100516)
			(xy 403.859493 -272.052732) (xy 403.878784 -272.007456) (xy 403.905087 -271.96586) (xy 403.937722 -271.929023)
			(xy 403.975843 -271.897898) (xy 404.018464 -271.873291) (xy 404.06448 -271.855839) (xy 404.112699 -271.845995)
			(xy 404.161874 -271.844014) (xy 404.210729 -271.849946) (xy 404.258 -271.863638) (xy 404.302462 -271.884736)
			(xy 404.342965 -271.912692) (xy 404.378458 -271.946784) (xy 404.408023 -271.986128) (xy 404.430894 -272.029705)
			(xy 404.446478 -272.076386) (xy 404.454373 -272.124963) (xy 404.454868 -272.14957) (xy 405.74393 -272.14957)
			(xy 405.74789 -272.100516) (xy 405.759667 -272.052732) (xy 405.778958 -272.007456) (xy 405.805261 -271.96586)
			(xy 405.837896 -271.929023) (xy 405.876017 -271.897898) (xy 405.918638 -271.873291) (xy 405.964654 -271.855839)
			(xy 406.012873 -271.845995) (xy 406.062048 -271.844014) (xy 406.110903 -271.849946) (xy 406.158174 -271.863638)
			(xy 406.202636 -271.884736) (xy 406.243139 -271.912692) (xy 406.278632 -271.946784) (xy 406.308197 -271.986128)
			(xy 406.331068 -272.029705) (xy 406.346652 -272.076386) (xy 406.354547 -272.124963) (xy 406.355037 -272.149316)
			(xy 407.64385 -272.149316) (xy 407.64781 -272.100262) (xy 407.659587 -272.052478) (xy 407.678878 -272.007202)
			(xy 407.705181 -271.965606) (xy 407.737816 -271.928769) (xy 407.775937 -271.897644) (xy 407.818558 -271.873037)
			(xy 407.864574 -271.855585) (xy 407.912793 -271.845741) (xy 407.961968 -271.84376) (xy 408.010823 -271.849692)
			(xy 408.058094 -271.863384) (xy 408.102556 -271.884482) (xy 408.143059 -271.912438) (xy 408.178552 -271.94653)
			(xy 408.208117 -271.985874) (xy 408.230988 -272.029451) (xy 408.246572 -272.076132) (xy 408.254467 -272.124709)
			(xy 408.254962 -272.149316) (xy 408.254957 -272.14957) (xy 409.54377 -272.14957) (xy 409.54773 -272.100516)
			(xy 409.559507 -272.052732) (xy 409.578798 -272.007456) (xy 409.605101 -271.96586) (xy 409.637736 -271.929023)
			(xy 409.675857 -271.897898) (xy 409.718478 -271.873291) (xy 409.764494 -271.855839) (xy 409.812713 -271.845995)
			(xy 409.861888 -271.844014) (xy 409.910743 -271.849946) (xy 409.958014 -271.863638) (xy 410.002476 -271.884736)
			(xy 410.042979 -271.912692) (xy 410.078472 -271.946784) (xy 410.108037 -271.986128) (xy 410.130908 -272.029705)
			(xy 410.146492 -272.076386) (xy 410.154387 -272.124963) (xy 410.154882 -272.14957) (xy 411.443944 -272.14957)
			(xy 411.447904 -272.100516) (xy 411.459681 -272.052732) (xy 411.478972 -272.007456) (xy 411.505275 -271.96586)
			(xy 411.53791 -271.929023) (xy 411.576031 -271.897898) (xy 411.618652 -271.873291) (xy 411.664668 -271.855839)
			(xy 411.712887 -271.845995) (xy 411.762062 -271.844014) (xy 411.810917 -271.849946) (xy 411.858188 -271.863638)
			(xy 411.90265 -271.884736) (xy 411.943153 -271.912692) (xy 411.978646 -271.946784) (xy 412.008211 -271.986128)
			(xy 412.031082 -272.029705) (xy 412.046666 -272.076386) (xy 412.054561 -272.124963) (xy 412.055056 -272.14957)
			(xy 413.343864 -272.14957) (xy 413.347824 -272.100516) (xy 413.359601 -272.052732) (xy 413.378892 -272.007456)
			(xy 413.405195 -271.96586) (xy 413.43783 -271.929023) (xy 413.475951 -271.897898) (xy 413.518572 -271.873291)
			(xy 413.564588 -271.855839) (xy 413.612807 -271.845995) (xy 413.661982 -271.844014) (xy 413.710837 -271.849946)
			(xy 413.758108 -271.863638) (xy 413.80257 -271.884736) (xy 413.843073 -271.912692) (xy 413.878566 -271.946784)
			(xy 413.908131 -271.986128) (xy 413.931002 -272.029705) (xy 413.946586 -272.076386) (xy 413.954481 -272.124963)
			(xy 413.954976 -272.14957) (xy 415.243784 -272.14957) (xy 415.247744 -272.100516) (xy 415.259521 -272.052732)
			(xy 415.278812 -272.007456) (xy 415.305115 -271.96586) (xy 415.33775 -271.929023) (xy 415.375871 -271.897898)
			(xy 415.418492 -271.873291) (xy 415.464508 -271.855839) (xy 415.512727 -271.845995) (xy 415.561902 -271.844014)
			(xy 415.610757 -271.849946) (xy 415.658028 -271.863638) (xy 415.70249 -271.884736) (xy 415.742993 -271.912692)
			(xy 415.778486 -271.946784) (xy 415.808051 -271.986128) (xy 415.830922 -272.029705) (xy 415.846506 -272.076386)
			(xy 415.854401 -272.124963) (xy 415.854896 -272.14957) (xy 417.143958 -272.14957) (xy 417.147918 -272.100516)
			(xy 417.159695 -272.052732) (xy 417.178986 -272.007456) (xy 417.205289 -271.96586) (xy 417.237924 -271.929023)
			(xy 417.276045 -271.897898) (xy 417.318666 -271.873291) (xy 417.364682 -271.855839) (xy 417.412901 -271.845995)
			(xy 417.462076 -271.844014) (xy 417.510931 -271.849946) (xy 417.558202 -271.863638) (xy 417.602664 -271.884736)
			(xy 417.643167 -271.912692) (xy 417.67866 -271.946784) (xy 417.708225 -271.986128) (xy 417.731096 -272.029705)
			(xy 417.74668 -272.076386) (xy 417.754575 -272.124963) (xy 417.75507 -272.14957) (xy 419.043878 -272.14957)
			(xy 419.047838 -272.100516) (xy 419.059615 -272.052732) (xy 419.078906 -272.007456) (xy 419.105209 -271.96586)
			(xy 419.137844 -271.929023) (xy 419.175965 -271.897898) (xy 419.218586 -271.873291) (xy 419.264602 -271.855839)
			(xy 419.312821 -271.845995) (xy 419.361996 -271.844014) (xy 419.410851 -271.849946) (xy 419.458122 -271.863638)
			(xy 419.502584 -271.884736) (xy 419.543087 -271.912692) (xy 419.57858 -271.946784) (xy 419.608145 -271.986128)
			(xy 419.631016 -272.029705) (xy 419.6466 -272.076386) (xy 419.654495 -272.124963) (xy 419.65499 -272.14957)
			(xy 420.943798 -272.14957) (xy 420.947758 -272.100516) (xy 420.959535 -272.052732) (xy 420.978826 -272.007456)
			(xy 421.005129 -271.96586) (xy 421.037764 -271.929023) (xy 421.075885 -271.897898) (xy 421.118506 -271.873291)
			(xy 421.164522 -271.855839) (xy 421.212741 -271.845995) (xy 421.261916 -271.844014) (xy 421.310771 -271.849946)
			(xy 421.358042 -271.863638) (xy 421.402504 -271.884736) (xy 421.443007 -271.912692) (xy 421.4785 -271.946784)
			(xy 421.508065 -271.986128) (xy 421.530936 -272.029705) (xy 421.54652 -272.076386) (xy 421.554415 -272.124963)
			(xy 421.55491 -272.14957) (xy 422.843972 -272.14957) (xy 422.847932 -272.100516) (xy 422.859709 -272.052732)
			(xy 422.879 -272.007456) (xy 422.905303 -271.96586) (xy 422.937938 -271.929023) (xy 422.976059 -271.897898)
			(xy 423.01868 -271.873291) (xy 423.064696 -271.855839) (xy 423.112915 -271.845995) (xy 423.16209 -271.844014)
			(xy 423.210945 -271.849946) (xy 423.258216 -271.863638) (xy 423.302678 -271.884736) (xy 423.343181 -271.912692)
			(xy 423.378674 -271.946784) (xy 423.408239 -271.986128) (xy 423.43111 -272.029705) (xy 423.446694 -272.076386)
			(xy 423.454589 -272.124963) (xy 423.455084 -272.14957) (xy 424.744146 -272.14957) (xy 424.748106 -272.100516)
			(xy 424.759883 -272.052732) (xy 424.779174 -272.007456) (xy 424.805477 -271.96586) (xy 424.838112 -271.929023)
			(xy 424.876233 -271.897898) (xy 424.918854 -271.873291) (xy 424.96487 -271.855839) (xy 425.013089 -271.845995)
			(xy 425.062264 -271.844014) (xy 425.111119 -271.849946) (xy 425.15839 -271.863638) (xy 425.202852 -271.884736)
			(xy 425.243355 -271.912692) (xy 425.278848 -271.946784) (xy 425.308413 -271.986128) (xy 425.331284 -272.029705)
			(xy 425.346868 -272.076386) (xy 425.354763 -272.124963) (xy 425.355258 -272.14957) (xy 426.644066 -272.14957)
			(xy 426.648026 -272.100516) (xy 426.659803 -272.052732) (xy 426.679094 -272.007456) (xy 426.705397 -271.96586)
			(xy 426.738032 -271.929023) (xy 426.776153 -271.897898) (xy 426.818774 -271.873291) (xy 426.86479 -271.855839)
			(xy 426.913009 -271.845995) (xy 426.962184 -271.844014) (xy 427.011039 -271.849946) (xy 427.05831 -271.863638)
			(xy 427.102772 -271.884736) (xy 427.143275 -271.912692) (xy 427.178768 -271.946784) (xy 427.208333 -271.986128)
			(xy 427.231204 -272.029705) (xy 427.246788 -272.076386) (xy 427.254683 -272.124963) (xy 427.255178 -272.14957)
			(xy 428.543986 -272.14957) (xy 428.547946 -272.100516) (xy 428.559723 -272.052732) (xy 428.579014 -272.007456)
			(xy 428.605317 -271.96586) (xy 428.637952 -271.929023) (xy 428.676073 -271.897898) (xy 428.718694 -271.873291)
			(xy 428.76471 -271.855839) (xy 428.812929 -271.845995) (xy 428.862104 -271.844014) (xy 428.910959 -271.849946)
			(xy 428.95823 -271.863638) (xy 429.002692 -271.884736) (xy 429.043195 -271.912692) (xy 429.078688 -271.946784)
			(xy 429.108253 -271.986128) (xy 429.131124 -272.029705) (xy 429.146708 -272.076386) (xy 429.154603 -272.124963)
			(xy 429.155098 -272.14957) (xy 429.154603 -272.174177) (xy 429.146708 -272.222754) (xy 429.131124 -272.269435)
			(xy 429.108253 -272.313012) (xy 429.078688 -272.352356) (xy 429.043195 -272.386448) (xy 429.002692 -272.414404)
			(xy 428.95823 -272.435502) (xy 428.910959 -272.449194) (xy 428.862104 -272.455126) (xy 428.812929 -272.453145)
			(xy 428.76471 -272.443301) (xy 428.718694 -272.425849) (xy 428.676073 -272.401242) (xy 428.637952 -272.370117)
			(xy 428.605317 -272.33328) (xy 428.579014 -272.291684) (xy 428.559723 -272.246408) (xy 428.547946 -272.198624)
			(xy 428.543986 -272.14957) (xy 427.255178 -272.14957) (xy 427.254683 -272.174177) (xy 427.246788 -272.222754)
			(xy 427.231204 -272.269435) (xy 427.208333 -272.313012) (xy 427.178768 -272.352356) (xy 427.143275 -272.386448)
			(xy 427.102772 -272.414404) (xy 427.05831 -272.435502) (xy 427.011039 -272.449194) (xy 426.962184 -272.455126)
			(xy 426.913009 -272.453145) (xy 426.86479 -272.443301) (xy 426.818774 -272.425849) (xy 426.776153 -272.401242)
			(xy 426.738032 -272.370117) (xy 426.705397 -272.33328) (xy 426.679094 -272.291684) (xy 426.659803 -272.246408)
			(xy 426.648026 -272.198624) (xy 426.644066 -272.14957) (xy 425.355258 -272.14957) (xy 425.354763 -272.174177)
			(xy 425.346868 -272.222754) (xy 425.331284 -272.269435) (xy 425.308413 -272.313012) (xy 425.278848 -272.352356)
			(xy 425.243355 -272.386448) (xy 425.202852 -272.414404) (xy 425.15839 -272.435502) (xy 425.111119 -272.449194)
			(xy 425.062264 -272.455126) (xy 425.013089 -272.453145) (xy 424.96487 -272.443301) (xy 424.918854 -272.425849)
			(xy 424.876233 -272.401242) (xy 424.838112 -272.370117) (xy 424.805477 -272.33328) (xy 424.779174 -272.291684)
			(xy 424.759883 -272.246408) (xy 424.748106 -272.198624) (xy 424.744146 -272.14957) (xy 423.455084 -272.14957)
			(xy 423.454589 -272.174177) (xy 423.446694 -272.222754) (xy 423.43111 -272.269435) (xy 423.408239 -272.313012)
			(xy 423.378674 -272.352356) (xy 423.343181 -272.386448) (xy 423.302678 -272.414404) (xy 423.258216 -272.435502)
			(xy 423.210945 -272.449194) (xy 423.16209 -272.455126) (xy 423.112915 -272.453145) (xy 423.064696 -272.443301)
			(xy 423.01868 -272.425849) (xy 422.976059 -272.401242) (xy 422.937938 -272.370117) (xy 422.905303 -272.33328)
			(xy 422.879 -272.291684) (xy 422.859709 -272.246408) (xy 422.847932 -272.198624) (xy 422.843972 -272.14957)
			(xy 421.55491 -272.14957) (xy 421.554415 -272.174177) (xy 421.54652 -272.222754) (xy 421.530936 -272.269435)
			(xy 421.508065 -272.313012) (xy 421.4785 -272.352356) (xy 421.443007 -272.386448) (xy 421.402504 -272.414404)
			(xy 421.358042 -272.435502) (xy 421.310771 -272.449194) (xy 421.261916 -272.455126) (xy 421.212741 -272.453145)
			(xy 421.164522 -272.443301) (xy 421.118506 -272.425849) (xy 421.075885 -272.401242) (xy 421.037764 -272.370117)
			(xy 421.005129 -272.33328) (xy 420.978826 -272.291684) (xy 420.959535 -272.246408) (xy 420.947758 -272.198624)
			(xy 420.943798 -272.14957) (xy 419.65499 -272.14957) (xy 419.654495 -272.174177) (xy 419.6466 -272.222754)
			(xy 419.631016 -272.269435) (xy 419.608145 -272.313012) (xy 419.57858 -272.352356) (xy 419.543087 -272.386448)
			(xy 419.502584 -272.414404) (xy 419.458122 -272.435502) (xy 419.410851 -272.449194) (xy 419.361996 -272.455126)
			(xy 419.312821 -272.453145) (xy 419.264602 -272.443301) (xy 419.218586 -272.425849) (xy 419.175965 -272.401242)
			(xy 419.137844 -272.370117) (xy 419.105209 -272.33328) (xy 419.078906 -272.291684) (xy 419.059615 -272.246408)
			(xy 419.047838 -272.198624) (xy 419.043878 -272.14957) (xy 417.75507 -272.14957) (xy 417.754575 -272.174177)
			(xy 417.74668 -272.222754) (xy 417.731096 -272.269435) (xy 417.708225 -272.313012) (xy 417.67866 -272.352356)
			(xy 417.643167 -272.386448) (xy 417.602664 -272.414404) (xy 417.558202 -272.435502) (xy 417.510931 -272.449194)
			(xy 417.462076 -272.455126) (xy 417.412901 -272.453145) (xy 417.364682 -272.443301) (xy 417.318666 -272.425849)
			(xy 417.276045 -272.401242) (xy 417.237924 -272.370117) (xy 417.205289 -272.33328) (xy 417.178986 -272.291684)
			(xy 417.159695 -272.246408) (xy 417.147918 -272.198624) (xy 417.143958 -272.14957) (xy 415.854896 -272.14957)
			(xy 415.854401 -272.174177) (xy 415.846506 -272.222754) (xy 415.830922 -272.269435) (xy 415.808051 -272.313012)
			(xy 415.778486 -272.352356) (xy 415.742993 -272.386448) (xy 415.70249 -272.414404) (xy 415.658028 -272.435502)
			(xy 415.610757 -272.449194) (xy 415.561902 -272.455126) (xy 415.512727 -272.453145) (xy 415.464508 -272.443301)
			(xy 415.418492 -272.425849) (xy 415.375871 -272.401242) (xy 415.33775 -272.370117) (xy 415.305115 -272.33328)
			(xy 415.278812 -272.291684) (xy 415.259521 -272.246408) (xy 415.247744 -272.198624) (xy 415.243784 -272.14957)
			(xy 413.954976 -272.14957) (xy 413.954481 -272.174177) (xy 413.946586 -272.222754) (xy 413.931002 -272.269435)
			(xy 413.908131 -272.313012) (xy 413.878566 -272.352356) (xy 413.843073 -272.386448) (xy 413.80257 -272.414404)
			(xy 413.758108 -272.435502) (xy 413.710837 -272.449194) (xy 413.661982 -272.455126) (xy 413.612807 -272.453145)
			(xy 413.564588 -272.443301) (xy 413.518572 -272.425849) (xy 413.475951 -272.401242) (xy 413.43783 -272.370117)
			(xy 413.405195 -272.33328) (xy 413.378892 -272.291684) (xy 413.359601 -272.246408) (xy 413.347824 -272.198624)
			(xy 413.343864 -272.14957) (xy 412.055056 -272.14957) (xy 412.054561 -272.174177) (xy 412.046666 -272.222754)
			(xy 412.031082 -272.269435) (xy 412.008211 -272.313012) (xy 411.978646 -272.352356) (xy 411.943153 -272.386448)
			(xy 411.90265 -272.414404) (xy 411.858188 -272.435502) (xy 411.810917 -272.449194) (xy 411.762062 -272.455126)
			(xy 411.712887 -272.453145) (xy 411.664668 -272.443301) (xy 411.618652 -272.425849) (xy 411.576031 -272.401242)
			(xy 411.53791 -272.370117) (xy 411.505275 -272.33328) (xy 411.478972 -272.291684) (xy 411.459681 -272.246408)
			(xy 411.447904 -272.198624) (xy 411.443944 -272.14957) (xy 410.154882 -272.14957) (xy 410.154387 -272.174177)
			(xy 410.146492 -272.222754) (xy 410.130908 -272.269435) (xy 410.108037 -272.313012) (xy 410.078472 -272.352356)
			(xy 410.042979 -272.386448) (xy 410.002476 -272.414404) (xy 409.958014 -272.435502) (xy 409.910743 -272.449194)
			(xy 409.861888 -272.455126) (xy 409.812713 -272.453145) (xy 409.764494 -272.443301) (xy 409.718478 -272.425849)
			(xy 409.675857 -272.401242) (xy 409.637736 -272.370117) (xy 409.605101 -272.33328) (xy 409.578798 -272.291684)
			(xy 409.559507 -272.246408) (xy 409.54773 -272.198624) (xy 409.54377 -272.14957) (xy 408.254957 -272.14957)
			(xy 408.254467 -272.173923) (xy 408.246572 -272.2225) (xy 408.230988 -272.269181) (xy 408.208117 -272.312758)
			(xy 408.178552 -272.352102) (xy 408.143059 -272.386194) (xy 408.102556 -272.41415) (xy 408.058094 -272.435248)
			(xy 408.010823 -272.44894) (xy 407.961968 -272.454872) (xy 407.912793 -272.452891) (xy 407.864574 -272.443047)
			(xy 407.818558 -272.425595) (xy 407.775937 -272.400988) (xy 407.737816 -272.369863) (xy 407.705181 -272.333026)
			(xy 407.678878 -272.29143) (xy 407.659587 -272.246154) (xy 407.64781 -272.19837) (xy 407.64385 -272.149316)
			(xy 406.355037 -272.149316) (xy 406.355042 -272.14957) (xy 406.354547 -272.174177) (xy 406.346652 -272.222754)
			(xy 406.331068 -272.269435) (xy 406.308197 -272.313012) (xy 406.278632 -272.352356) (xy 406.243139 -272.386448)
			(xy 406.202636 -272.414404) (xy 406.158174 -272.435502) (xy 406.110903 -272.449194) (xy 406.062048 -272.455126)
			(xy 406.012873 -272.453145) (xy 405.964654 -272.443301) (xy 405.918638 -272.425849) (xy 405.876017 -272.401242)
			(xy 405.837896 -272.370117) (xy 405.805261 -272.33328) (xy 405.778958 -272.291684) (xy 405.759667 -272.246408)
			(xy 405.74789 -272.198624) (xy 405.74393 -272.14957) (xy 404.454868 -272.14957) (xy 404.454373 -272.174177)
			(xy 404.446478 -272.222754) (xy 404.430894 -272.269435) (xy 404.408023 -272.313012) (xy 404.378458 -272.352356)
			(xy 404.342965 -272.386448) (xy 404.302462 -272.414404) (xy 404.258 -272.435502) (xy 404.210729 -272.449194)
			(xy 404.161874 -272.455126) (xy 404.112699 -272.453145) (xy 404.06448 -272.443301) (xy 404.018464 -272.425849)
			(xy 403.975843 -272.401242) (xy 403.937722 -272.370117) (xy 403.905087 -272.33328) (xy 403.878784 -272.291684)
			(xy 403.859493 -272.246408) (xy 403.847716 -272.198624) (xy 403.843756 -272.14957) (xy 402.554948 -272.14957)
			(xy 402.554453 -272.174177) (xy 402.546558 -272.222754) (xy 402.530974 -272.269435) (xy 402.508103 -272.313012)
			(xy 402.478538 -272.352356) (xy 402.443045 -272.386448) (xy 402.402542 -272.414404) (xy 402.35808 -272.435502)
			(xy 402.310809 -272.449194) (xy 402.261954 -272.455126) (xy 402.212779 -272.453145) (xy 402.16456 -272.443301)
			(xy 402.118544 -272.425849) (xy 402.075923 -272.401242) (xy 402.037802 -272.370117) (xy 402.005167 -272.33328)
			(xy 401.978864 -272.291684) (xy 401.959573 -272.246408) (xy 401.947796 -272.198624) (xy 401.943836 -272.14957)
			(xy 400.655028 -272.14957) (xy 400.654533 -272.174177) (xy 400.646638 -272.222754) (xy 400.631054 -272.269435)
			(xy 400.608183 -272.313012) (xy 400.578618 -272.352356) (xy 400.543125 -272.386448) (xy 400.502622 -272.414404)
			(xy 400.45816 -272.435502) (xy 400.410889 -272.449194) (xy 400.362034 -272.455126) (xy 400.312859 -272.453145)
			(xy 400.26464 -272.443301) (xy 400.218624 -272.425849) (xy 400.176003 -272.401242) (xy 400.137882 -272.370117)
			(xy 400.105247 -272.33328) (xy 400.078944 -272.291684) (xy 400.059653 -272.246408) (xy 400.047876 -272.198624)
			(xy 400.043916 -272.14957) (xy 398.755359 -272.14957) (xy 398.755361 -272.1496) (xy 398.75119 -272.199938)
			(xy 398.738792 -272.248904) (xy 398.718504 -272.295161) (xy 398.690879 -272.337448) (xy 398.656672 -272.374613)
			(xy 398.616814 -272.405641) (xy 398.572394 -272.429686) (xy 398.524622 -272.446092) (xy 398.474801 -272.454413)
			(xy 398.449546 -272.454878) (xy 398.440442 -272.45478) (xy 398.422269 -272.453635) (xy 398.413224 -272.452592)
			(xy 398.401032 -272.451322) (xy 398.378934 -272.459196) (xy 398.306036 -272.53565) (xy 398.298924 -272.558256)
			(xy 398.300956 -272.570448) (xy 398.303073 -272.583874) (xy 398.305362 -272.610959) (xy 398.305528 -272.62455)
			(xy 398.305528 -272.673318) (xy 398.305992 -272.683975) (xy 398.314682 -272.703434) (xy 398.322292 -272.71091)
			(xy 398.386046 -272.768822) (xy 398.406366 -272.775426) (xy 398.417288 -272.77441) (xy 398.4498 -272.772632)
			(xy 398.475509 -272.773136) (xy 398.526294 -272.78118) (xy 398.575195 -272.797069) (xy 398.621009 -272.820412)
			(xy 398.662607 -272.850635) (xy 398.698965 -272.886993) (xy 398.729188 -272.928591) (xy 398.752531 -272.974405)
			(xy 398.76842 -273.023306) (xy 398.776464 -273.074091) (xy 398.776464 -273.099784) (xy 399.09421 -273.099784)
			(xy 399.09817 -273.05073) (xy 399.109947 -273.002946) (xy 399.129238 -272.95767) (xy 399.155541 -272.916074)
			(xy 399.188176 -272.879237) (xy 399.226297 -272.848112) (xy 399.268918 -272.823505) (xy 399.314934 -272.806053)
			(xy 399.363153 -272.796209) (xy 399.412328 -272.794228) (xy 399.461183 -272.80016) (xy 399.508454 -272.813852)
			(xy 399.552916 -272.83495) (xy 399.593419 -272.862906) (xy 399.628912 -272.896998) (xy 399.658477 -272.936342)
			(xy 399.681348 -272.979919) (xy 399.696932 -273.0266) (xy 399.704827 -273.075177) (xy 399.705322 -273.099784)
			(xy 399.704827 -273.124391) (xy 399.704648 -273.125492) (xy 400.023326 -273.125492) (xy 400.023326 -273.074076)
			(xy 400.031369 -273.023294) (xy 400.047257 -272.974395) (xy 400.0706 -272.928583) (xy 400.100821 -272.886987)
			(xy 400.137177 -272.850631) (xy 400.178773 -272.82041) (xy 400.224585 -272.797067) (xy 400.273484 -272.781179)
			(xy 400.324266 -272.773136) (xy 400.375682 -272.773136) (xy 400.426464 -272.781179) (xy 400.475363 -272.797067)
			(xy 400.521175 -272.82041) (xy 400.562771 -272.850631) (xy 400.599127 -272.886987) (xy 400.629348 -272.928583)
			(xy 400.652691 -272.974395) (xy 400.668579 -273.023294) (xy 400.676622 -273.074076) (xy 400.677126 -273.099784)
			(xy 400.99413 -273.099784) (xy 400.99809 -273.05073) (xy 401.009867 -273.002946) (xy 401.029158 -272.95767)
			(xy 401.055461 -272.916074) (xy 401.088096 -272.879237) (xy 401.126217 -272.848112) (xy 401.168838 -272.823505)
			(xy 401.214854 -272.806053) (xy 401.263073 -272.796209) (xy 401.312248 -272.794228) (xy 401.361103 -272.80016)
			(xy 401.408374 -272.813852) (xy 401.452836 -272.83495) (xy 401.493339 -272.862906) (xy 401.528832 -272.896998)
			(xy 401.558397 -272.936342) (xy 401.581268 -272.979919) (xy 401.596852 -273.0266) (xy 401.604747 -273.075177)
			(xy 401.605242 -273.099784) (xy 401.604747 -273.124391) (xy 401.604568 -273.125492) (xy 401.923246 -273.125492)
			(xy 401.923246 -273.074076) (xy 401.931289 -273.023294) (xy 401.947177 -272.974395) (xy 401.97052 -272.928583)
			(xy 402.000741 -272.886987) (xy 402.037097 -272.850631) (xy 402.078693 -272.82041) (xy 402.124505 -272.797067)
			(xy 402.173404 -272.781179) (xy 402.224186 -272.773136) (xy 402.275602 -272.773136) (xy 402.326384 -272.781179)
			(xy 402.375283 -272.797067) (xy 402.421095 -272.82041) (xy 402.462691 -272.850631) (xy 402.499047 -272.886987)
			(xy 402.529268 -272.928583) (xy 402.552611 -272.974395) (xy 402.568499 -273.023294) (xy 402.576542 -273.074076)
			(xy 402.577046 -273.099784) (xy 402.89405 -273.099784) (xy 402.89801 -273.05073) (xy 402.909787 -273.002946)
			(xy 402.929078 -272.95767) (xy 402.955381 -272.916074) (xy 402.988016 -272.879237) (xy 403.026137 -272.848112)
			(xy 403.068758 -272.823505) (xy 403.114774 -272.806053) (xy 403.162993 -272.796209) (xy 403.212168 -272.794228)
			(xy 403.261023 -272.80016) (xy 403.308294 -272.813852) (xy 403.352756 -272.83495) (xy 403.393259 -272.862906)
			(xy 403.428752 -272.896998) (xy 403.458317 -272.936342) (xy 403.481188 -272.979919) (xy 403.496772 -273.0266)
			(xy 403.504667 -273.075177) (xy 403.505162 -273.099784) (xy 403.504667 -273.124391) (xy 403.504488 -273.125492)
			(xy 403.823166 -273.125492) (xy 403.823166 -273.074076) (xy 403.831209 -273.023294) (xy 403.847097 -272.974395)
			(xy 403.87044 -272.928583) (xy 403.900661 -272.886987) (xy 403.937017 -272.850631) (xy 403.978613 -272.82041)
			(xy 404.024425 -272.797067) (xy 404.073324 -272.781179) (xy 404.124106 -272.773136) (xy 404.175522 -272.773136)
			(xy 404.226304 -272.781179) (xy 404.275203 -272.797067) (xy 404.321015 -272.82041) (xy 404.362611 -272.850631)
			(xy 404.398967 -272.886987) (xy 404.429188 -272.928583) (xy 404.452531 -272.974395) (xy 404.468419 -273.023294)
			(xy 404.476462 -273.074076) (xy 404.476966 -273.099784) (xy 404.794224 -273.099784) (xy 404.798184 -273.05073)
			(xy 404.809961 -273.002946) (xy 404.829252 -272.95767) (xy 404.855555 -272.916074) (xy 404.88819 -272.879237)
			(xy 404.926311 -272.848112) (xy 404.968932 -272.823505) (xy 405.014948 -272.806053) (xy 405.063167 -272.796209)
			(xy 405.112342 -272.794228) (xy 405.161197 -272.80016) (xy 405.208468 -272.813852) (xy 405.25293 -272.83495)
			(xy 405.293433 -272.862906) (xy 405.328926 -272.896998) (xy 405.358491 -272.936342) (xy 405.381362 -272.979919)
			(xy 405.396946 -273.0266) (xy 405.404841 -273.075177) (xy 405.405336 -273.099784) (xy 405.404841 -273.124391)
			(xy 405.404662 -273.125492) (xy 405.72334 -273.125492) (xy 405.72334 -273.074076) (xy 405.731383 -273.023294)
			(xy 405.747271 -272.974395) (xy 405.770614 -272.928583) (xy 405.800835 -272.886987) (xy 405.837191 -272.850631)
			(xy 405.878787 -272.82041) (xy 405.924599 -272.797067) (xy 405.973498 -272.781179) (xy 406.02428 -272.773136)
			(xy 406.075696 -272.773136) (xy 406.126478 -272.781179) (xy 406.175377 -272.797067) (xy 406.221189 -272.82041)
			(xy 406.262785 -272.850631) (xy 406.299141 -272.886987) (xy 406.329362 -272.928583) (xy 406.352705 -272.974395)
			(xy 406.368593 -273.023294) (xy 406.376636 -273.074076) (xy 406.37714 -273.099784) (xy 406.694144 -273.099784)
			(xy 406.698104 -273.05073) (xy 406.709881 -273.002946) (xy 406.729172 -272.95767) (xy 406.755475 -272.916074)
			(xy 406.78811 -272.879237) (xy 406.826231 -272.848112) (xy 406.868852 -272.823505) (xy 406.914868 -272.806053)
			(xy 406.963087 -272.796209) (xy 407.012262 -272.794228) (xy 407.061117 -272.80016) (xy 407.108388 -272.813852)
			(xy 407.15285 -272.83495) (xy 407.193353 -272.862906) (xy 407.228846 -272.896998) (xy 407.258411 -272.936342)
			(xy 407.281282 -272.979919) (xy 407.296866 -273.0266) (xy 407.304761 -273.075177) (xy 407.305256 -273.099784)
			(xy 407.304761 -273.124391) (xy 407.304623 -273.125238) (xy 407.623006 -273.125238) (xy 407.623006 -273.073822)
			(xy 407.631049 -273.02304) (xy 407.646937 -272.974141) (xy 407.67028 -272.928329) (xy 407.700501 -272.886733)
			(xy 407.736857 -272.850377) (xy 407.778453 -272.820156) (xy 407.824265 -272.796813) (xy 407.873164 -272.780925)
			(xy 407.923946 -272.772882) (xy 407.975362 -272.772882) (xy 408.026144 -272.780925) (xy 408.075043 -272.796813)
			(xy 408.120855 -272.820156) (xy 408.162451 -272.850377) (xy 408.198807 -272.886733) (xy 408.229028 -272.928329)
			(xy 408.252371 -272.974141) (xy 408.268259 -273.02304) (xy 408.276302 -273.073822) (xy 408.276806 -273.09953)
			(xy 408.276801 -273.099784) (xy 408.594064 -273.099784) (xy 408.598024 -273.05073) (xy 408.609801 -273.002946)
			(xy 408.629092 -272.95767) (xy 408.655395 -272.916074) (xy 408.68803 -272.879237) (xy 408.726151 -272.848112)
			(xy 408.768772 -272.823505) (xy 408.814788 -272.806053) (xy 408.863007 -272.796209) (xy 408.912182 -272.794228)
			(xy 408.961037 -272.80016) (xy 409.008308 -272.813852) (xy 409.05277 -272.83495) (xy 409.093273 -272.862906)
			(xy 409.128766 -272.896998) (xy 409.158331 -272.936342) (xy 409.181202 -272.979919) (xy 409.196786 -273.0266)
			(xy 409.204681 -273.075177) (xy 409.205176 -273.099784) (xy 409.204681 -273.124391) (xy 409.204502 -273.125492)
			(xy 409.522926 -273.125492) (xy 409.522926 -273.074076) (xy 409.530969 -273.023294) (xy 409.546857 -272.974395)
			(xy 409.5702 -272.928583) (xy 409.600421 -272.886987) (xy 409.636777 -272.850631) (xy 409.678373 -272.82041)
			(xy 409.724185 -272.797067) (xy 409.773084 -272.781179) (xy 409.823866 -272.773136) (xy 409.875282 -272.773136)
			(xy 409.926064 -272.781179) (xy 409.974963 -272.797067) (xy 410.020775 -272.82041) (xy 410.062371 -272.850631)
			(xy 410.098727 -272.886987) (xy 410.128948 -272.928583) (xy 410.152291 -272.974395) (xy 410.168179 -273.023294)
			(xy 410.176222 -273.074076) (xy 410.176726 -273.099784) (xy 410.493984 -273.099784) (xy 410.497944 -273.05073)
			(xy 410.509721 -273.002946) (xy 410.529012 -272.95767) (xy 410.555315 -272.916074) (xy 410.58795 -272.879237)
			(xy 410.626071 -272.848112) (xy 410.668692 -272.823505) (xy 410.714708 -272.806053) (xy 410.762927 -272.796209)
			(xy 410.812102 -272.794228) (xy 410.860957 -272.80016) (xy 410.908228 -272.813852) (xy 410.95269 -272.83495)
			(xy 410.993193 -272.862906) (xy 411.028686 -272.896998) (xy 411.058251 -272.936342) (xy 411.081122 -272.979919)
			(xy 411.096706 -273.0266) (xy 411.104601 -273.075177) (xy 411.105096 -273.099784) (xy 411.104601 -273.124391)
			(xy 411.104422 -273.125492) (xy 411.4231 -273.125492) (xy 411.4231 -273.074076) (xy 411.431143 -273.023294)
			(xy 411.447031 -272.974395) (xy 411.470374 -272.928583) (xy 411.500595 -272.886987) (xy 411.536951 -272.850631)
			(xy 411.578547 -272.82041) (xy 411.624359 -272.797067) (xy 411.673258 -272.781179) (xy 411.72404 -272.773136)
			(xy 411.775456 -272.773136) (xy 411.826238 -272.781179) (xy 411.875137 -272.797067) (xy 411.920949 -272.82041)
			(xy 411.962545 -272.850631) (xy 411.998901 -272.886987) (xy 412.029122 -272.928583) (xy 412.052465 -272.974395)
			(xy 412.068353 -273.023294) (xy 412.076396 -273.074076) (xy 412.0769 -273.099784) (xy 412.394158 -273.099784)
			(xy 412.398118 -273.05073) (xy 412.409895 -273.002946) (xy 412.429186 -272.95767) (xy 412.455489 -272.916074)
			(xy 412.488124 -272.879237) (xy 412.526245 -272.848112) (xy 412.568866 -272.823505) (xy 412.614882 -272.806053)
			(xy 412.663101 -272.796209) (xy 412.712276 -272.794228) (xy 412.761131 -272.80016) (xy 412.808402 -272.813852)
			(xy 412.852864 -272.83495) (xy 412.893367 -272.862906) (xy 412.92886 -272.896998) (xy 412.958425 -272.936342)
			(xy 412.981296 -272.979919) (xy 412.99688 -273.0266) (xy 413.004775 -273.075177) (xy 413.00527 -273.099784)
			(xy 413.004775 -273.124391) (xy 413.004596 -273.125492) (xy 413.32302 -273.125492) (xy 413.32302 -273.074076)
			(xy 413.331063 -273.023294) (xy 413.346951 -272.974395) (xy 413.370294 -272.928583) (xy 413.400515 -272.886987)
			(xy 413.436871 -272.850631) (xy 413.478467 -272.82041) (xy 413.524279 -272.797067) (xy 413.573178 -272.781179)
			(xy 413.62396 -272.773136) (xy 413.675376 -272.773136) (xy 413.726158 -272.781179) (xy 413.775057 -272.797067)
			(xy 413.820869 -272.82041) (xy 413.862465 -272.850631) (xy 413.898821 -272.886987) (xy 413.929042 -272.928583)
			(xy 413.952385 -272.974395) (xy 413.968273 -273.023294) (xy 413.976316 -273.074076) (xy 413.97682 -273.099784)
			(xy 414.294078 -273.099784) (xy 414.298038 -273.05073) (xy 414.309815 -273.002946) (xy 414.329106 -272.95767)
			(xy 414.355409 -272.916074) (xy 414.388044 -272.879237) (xy 414.426165 -272.848112) (xy 414.468786 -272.823505)
			(xy 414.514802 -272.806053) (xy 414.563021 -272.796209) (xy 414.612196 -272.794228) (xy 414.661051 -272.80016)
			(xy 414.708322 -272.813852) (xy 414.752784 -272.83495) (xy 414.793287 -272.862906) (xy 414.82878 -272.896998)
			(xy 414.858345 -272.936342) (xy 414.881216 -272.979919) (xy 414.8968 -273.0266) (xy 414.904695 -273.075177)
			(xy 414.90519 -273.099784) (xy 414.904695 -273.124391) (xy 414.904516 -273.125492) (xy 415.22294 -273.125492)
			(xy 415.22294 -273.074076) (xy 415.230983 -273.023294) (xy 415.246871 -272.974395) (xy 415.270214 -272.928583)
			(xy 415.300435 -272.886987) (xy 415.336791 -272.850631) (xy 415.378387 -272.82041) (xy 415.424199 -272.797067)
			(xy 415.473098 -272.781179) (xy 415.52388 -272.773136) (xy 415.575296 -272.773136) (xy 415.626078 -272.781179)
			(xy 415.674977 -272.797067) (xy 415.720789 -272.82041) (xy 415.762385 -272.850631) (xy 415.798741 -272.886987)
			(xy 415.828962 -272.928583) (xy 415.852305 -272.974395) (xy 415.868193 -273.023294) (xy 415.876236 -273.074076)
			(xy 415.87674 -273.099784) (xy 416.193998 -273.099784) (xy 416.197958 -273.05073) (xy 416.209735 -273.002946)
			(xy 416.229026 -272.95767) (xy 416.255329 -272.916074) (xy 416.287964 -272.879237) (xy 416.326085 -272.848112)
			(xy 416.368706 -272.823505) (xy 416.414722 -272.806053) (xy 416.462941 -272.796209) (xy 416.512116 -272.794228)
			(xy 416.560971 -272.80016) (xy 416.608242 -272.813852) (xy 416.652704 -272.83495) (xy 416.693207 -272.862906)
			(xy 416.7287 -272.896998) (xy 416.758265 -272.936342) (xy 416.781136 -272.979919) (xy 416.79672 -273.0266)
			(xy 416.804615 -273.075177) (xy 416.80511 -273.099784) (xy 416.804615 -273.124391) (xy 416.804436 -273.125492)
			(xy 417.123114 -273.125492) (xy 417.123114 -273.074076) (xy 417.131157 -273.023294) (xy 417.147045 -272.974395)
			(xy 417.170388 -272.928583) (xy 417.200609 -272.886987) (xy 417.236965 -272.850631) (xy 417.278561 -272.82041)
			(xy 417.324373 -272.797067) (xy 417.373272 -272.781179) (xy 417.424054 -272.773136) (xy 417.47547 -272.773136)
			(xy 417.526252 -272.781179) (xy 417.575151 -272.797067) (xy 417.620963 -272.82041) (xy 417.662559 -272.850631)
			(xy 417.698915 -272.886987) (xy 417.729136 -272.928583) (xy 417.752479 -272.974395) (xy 417.768367 -273.023294)
			(xy 417.77641 -273.074076) (xy 417.776914 -273.099784) (xy 418.094172 -273.099784) (xy 418.098132 -273.05073)
			(xy 418.109909 -273.002946) (xy 418.1292 -272.95767) (xy 418.155503 -272.916074) (xy 418.188138 -272.879237)
			(xy 418.226259 -272.848112) (xy 418.26888 -272.823505) (xy 418.314896 -272.806053) (xy 418.363115 -272.796209)
			(xy 418.41229 -272.794228) (xy 418.461145 -272.80016) (xy 418.508416 -272.813852) (xy 418.552878 -272.83495)
			(xy 418.593381 -272.862906) (xy 418.628874 -272.896998) (xy 418.658439 -272.936342) (xy 418.68131 -272.979919)
			(xy 418.696894 -273.0266) (xy 418.704789 -273.075177) (xy 418.705284 -273.099784) (xy 418.704789 -273.124391)
			(xy 418.70461 -273.125492) (xy 419.023034 -273.125492) (xy 419.023034 -273.074076) (xy 419.031077 -273.023294)
			(xy 419.046965 -272.974395) (xy 419.070308 -272.928583) (xy 419.100529 -272.886987) (xy 419.136885 -272.850631)
			(xy 419.178481 -272.82041) (xy 419.224293 -272.797067) (xy 419.273192 -272.781179) (xy 419.323974 -272.773136)
			(xy 419.37539 -272.773136) (xy 419.426172 -272.781179) (xy 419.475071 -272.797067) (xy 419.520883 -272.82041)
			(xy 419.562479 -272.850631) (xy 419.598835 -272.886987) (xy 419.629056 -272.928583) (xy 419.652399 -272.974395)
			(xy 419.668287 -273.023294) (xy 419.67633 -273.074076) (xy 419.676834 -273.099784) (xy 419.994092 -273.099784)
			(xy 419.998052 -273.05073) (xy 420.009829 -273.002946) (xy 420.02912 -272.95767) (xy 420.055423 -272.916074)
			(xy 420.088058 -272.879237) (xy 420.126179 -272.848112) (xy 420.1688 -272.823505) (xy 420.214816 -272.806053)
			(xy 420.263035 -272.796209) (xy 420.31221 -272.794228) (xy 420.361065 -272.80016) (xy 420.408336 -272.813852)
			(xy 420.452798 -272.83495) (xy 420.493301 -272.862906) (xy 420.528794 -272.896998) (xy 420.558359 -272.936342)
			(xy 420.58123 -272.979919) (xy 420.596814 -273.0266) (xy 420.604709 -273.075177) (xy 420.605204 -273.099784)
			(xy 420.604709 -273.124391) (xy 420.60453 -273.125492) (xy 420.922954 -273.125492) (xy 420.922954 -273.074076)
			(xy 420.930997 -273.023294) (xy 420.946885 -272.974395) (xy 420.970228 -272.928583) (xy 421.000449 -272.886987)
			(xy 421.036805 -272.850631) (xy 421.078401 -272.82041) (xy 421.124213 -272.797067) (xy 421.173112 -272.781179)
			(xy 421.223894 -272.773136) (xy 421.27531 -272.773136) (xy 421.326092 -272.781179) (xy 421.374991 -272.797067)
			(xy 421.420803 -272.82041) (xy 421.462399 -272.850631) (xy 421.498755 -272.886987) (xy 421.528976 -272.928583)
			(xy 421.552319 -272.974395) (xy 421.568207 -273.023294) (xy 421.57625 -273.074076) (xy 421.576754 -273.099784)
			(xy 421.894012 -273.099784) (xy 421.897972 -273.05073) (xy 421.909749 -273.002946) (xy 421.92904 -272.95767)
			(xy 421.955343 -272.916074) (xy 421.987978 -272.879237) (xy 422.026099 -272.848112) (xy 422.06872 -272.823505)
			(xy 422.114736 -272.806053) (xy 422.162955 -272.796209) (xy 422.21213 -272.794228) (xy 422.260985 -272.80016)
			(xy 422.308256 -272.813852) (xy 422.352718 -272.83495) (xy 422.393221 -272.862906) (xy 422.428714 -272.896998)
			(xy 422.458279 -272.936342) (xy 422.48115 -272.979919) (xy 422.496734 -273.0266) (xy 422.504629 -273.075177)
			(xy 422.505124 -273.099784) (xy 422.504629 -273.124391) (xy 422.50445 -273.125492) (xy 422.823128 -273.125492)
			(xy 422.823128 -273.074076) (xy 422.831171 -273.023294) (xy 422.847059 -272.974395) (xy 422.870402 -272.928583)
			(xy 422.900623 -272.886987) (xy 422.936979 -272.850631) (xy 422.978575 -272.82041) (xy 423.024387 -272.797067)
			(xy 423.073286 -272.781179) (xy 423.124068 -272.773136) (xy 423.175484 -272.773136) (xy 423.226266 -272.781179)
			(xy 423.275165 -272.797067) (xy 423.320977 -272.82041) (xy 423.362573 -272.850631) (xy 423.398929 -272.886987)
			(xy 423.42915 -272.928583) (xy 423.452493 -272.974395) (xy 423.468381 -273.023294) (xy 423.476424 -273.074076)
			(xy 423.476928 -273.099784) (xy 423.794186 -273.099784) (xy 423.798146 -273.05073) (xy 423.809923 -273.002946)
			(xy 423.829214 -272.95767) (xy 423.855517 -272.916074) (xy 423.888152 -272.879237) (xy 423.926273 -272.848112)
			(xy 423.968894 -272.823505) (xy 424.01491 -272.806053) (xy 424.063129 -272.796209) (xy 424.112304 -272.794228)
			(xy 424.161159 -272.80016) (xy 424.20843 -272.813852) (xy 424.252892 -272.83495) (xy 424.293395 -272.862906)
			(xy 424.328888 -272.896998) (xy 424.358453 -272.936342) (xy 424.381324 -272.979919) (xy 424.396908 -273.0266)
			(xy 424.404803 -273.075177) (xy 424.405298 -273.099784) (xy 424.404803 -273.124391) (xy 424.404624 -273.125492)
			(xy 424.723048 -273.125492) (xy 424.723048 -273.074076) (xy 424.731091 -273.023294) (xy 424.746979 -272.974395)
			(xy 424.770322 -272.928583) (xy 424.800543 -272.886987) (xy 424.836899 -272.850631) (xy 424.878495 -272.82041)
			(xy 424.924307 -272.797067) (xy 424.973206 -272.781179) (xy 425.023988 -272.773136) (xy 425.075404 -272.773136)
			(xy 425.126186 -272.781179) (xy 425.175085 -272.797067) (xy 425.220897 -272.82041) (xy 425.262493 -272.850631)
			(xy 425.298849 -272.886987) (xy 425.32907 -272.928583) (xy 425.352413 -272.974395) (xy 425.368301 -273.023294)
			(xy 425.376344 -273.074076) (xy 425.376848 -273.099784) (xy 425.69436 -273.099784) (xy 425.69832 -273.05073)
			(xy 425.710097 -273.002946) (xy 425.729388 -272.95767) (xy 425.755691 -272.916074) (xy 425.788326 -272.879237)
			(xy 425.826447 -272.848112) (xy 425.869068 -272.823505) (xy 425.915084 -272.806053) (xy 425.963303 -272.796209)
			(xy 426.012478 -272.794228) (xy 426.061333 -272.80016) (xy 426.108604 -272.813852) (xy 426.153066 -272.83495)
			(xy 426.193569 -272.862906) (xy 426.229062 -272.896998) (xy 426.258627 -272.936342) (xy 426.281498 -272.979919)
			(xy 426.297082 -273.0266) (xy 426.304977 -273.075177) (xy 426.305472 -273.099784) (xy 426.304977 -273.124391)
			(xy 426.304798 -273.125492) (xy 426.622968 -273.125492) (xy 426.622968 -273.074076) (xy 426.631011 -273.023294)
			(xy 426.646899 -272.974395) (xy 426.670242 -272.928583) (xy 426.700463 -272.886987) (xy 426.736819 -272.850631)
			(xy 426.778415 -272.82041) (xy 426.824227 -272.797067) (xy 426.873126 -272.781179) (xy 426.923908 -272.773136)
			(xy 426.975324 -272.773136) (xy 427.026106 -272.781179) (xy 427.075005 -272.797067) (xy 427.120817 -272.82041)
			(xy 427.162413 -272.850631) (xy 427.198769 -272.886987) (xy 427.22899 -272.928583) (xy 427.252333 -272.974395)
			(xy 427.268221 -273.023294) (xy 427.276264 -273.074076) (xy 427.276768 -273.099784) (xy 427.59428 -273.099784)
			(xy 427.59824 -273.05073) (xy 427.610017 -273.002946) (xy 427.629308 -272.95767) (xy 427.655611 -272.916074)
			(xy 427.688246 -272.879237) (xy 427.726367 -272.848112) (xy 427.768988 -272.823505) (xy 427.815004 -272.806053)
			(xy 427.863223 -272.796209) (xy 427.912398 -272.794228) (xy 427.961253 -272.80016) (xy 428.008524 -272.813852)
			(xy 428.052986 -272.83495) (xy 428.093489 -272.862906) (xy 428.128982 -272.896998) (xy 428.158547 -272.936342)
			(xy 428.181418 -272.979919) (xy 428.197002 -273.0266) (xy 428.204897 -273.075177) (xy 428.205392 -273.099784)
			(xy 428.204897 -273.124391) (xy 428.204718 -273.125492) (xy 428.522888 -273.125492) (xy 428.522888 -273.074076)
			(xy 428.530931 -273.023294) (xy 428.546819 -272.974395) (xy 428.570162 -272.928583) (xy 428.600383 -272.886987)
			(xy 428.636739 -272.850631) (xy 428.678335 -272.82041) (xy 428.724147 -272.797067) (xy 428.773046 -272.781179)
			(xy 428.823828 -272.773136) (xy 428.875244 -272.773136) (xy 428.926026 -272.781179) (xy 428.974925 -272.797067)
			(xy 429.020737 -272.82041) (xy 429.062333 -272.850631) (xy 429.098689 -272.886987) (xy 429.12891 -272.928583)
			(xy 429.152253 -272.974395) (xy 429.168141 -273.023294) (xy 429.176184 -273.074076) (xy 429.176688 -273.099784)
			(xy 429.4942 -273.099784) (xy 429.49816 -273.05073) (xy 429.509937 -273.002946) (xy 429.529228 -272.95767)
			(xy 429.555531 -272.916074) (xy 429.588166 -272.879237) (xy 429.626287 -272.848112) (xy 429.668908 -272.823505)
			(xy 429.714924 -272.806053) (xy 429.763143 -272.796209) (xy 429.812318 -272.794228) (xy 429.861173 -272.80016)
			(xy 429.908444 -272.813852) (xy 429.952906 -272.83495) (xy 429.993409 -272.862906) (xy 430.028902 -272.896998)
			(xy 430.058467 -272.936342) (xy 430.081338 -272.979919) (xy 430.096922 -273.0266) (xy 430.104817 -273.075177)
			(xy 430.105312 -273.099784) (xy 430.104817 -273.124391) (xy 430.096922 -273.172968) (xy 430.081338 -273.219649)
			(xy 430.058467 -273.263226) (xy 430.028902 -273.30257) (xy 429.993409 -273.336662) (xy 429.952906 -273.364618)
			(xy 429.908444 -273.385716) (xy 429.861173 -273.399408) (xy 429.812318 -273.40534) (xy 429.763143 -273.403359)
			(xy 429.714924 -273.393515) (xy 429.668908 -273.376063) (xy 429.626287 -273.351456) (xy 429.588166 -273.320331)
			(xy 429.555531 -273.283494) (xy 429.529228 -273.241898) (xy 429.509937 -273.196622) (xy 429.49816 -273.148838)
			(xy 429.4942 -273.099784) (xy 429.176688 -273.099784) (xy 429.176184 -273.125492) (xy 429.168141 -273.176274)
			(xy 429.152253 -273.225173) (xy 429.12891 -273.270985) (xy 429.098689 -273.312581) (xy 429.062333 -273.348937)
			(xy 429.020737 -273.379158) (xy 428.974925 -273.402501) (xy 428.926026 -273.418389) (xy 428.875244 -273.426432)
			(xy 428.823828 -273.426432) (xy 428.773046 -273.418389) (xy 428.724147 -273.402501) (xy 428.678335 -273.379158)
			(xy 428.636739 -273.348937) (xy 428.600383 -273.312581) (xy 428.570162 -273.270985) (xy 428.546819 -273.225173)
			(xy 428.530931 -273.176274) (xy 428.522888 -273.125492) (xy 428.204718 -273.125492) (xy 428.197002 -273.172968)
			(xy 428.181418 -273.219649) (xy 428.158547 -273.263226) (xy 428.128982 -273.30257) (xy 428.093489 -273.336662)
			(xy 428.052986 -273.364618) (xy 428.008524 -273.385716) (xy 427.961253 -273.399408) (xy 427.912398 -273.40534)
			(xy 427.863223 -273.403359) (xy 427.815004 -273.393515) (xy 427.768988 -273.376063) (xy 427.726367 -273.351456)
			(xy 427.688246 -273.320331) (xy 427.655611 -273.283494) (xy 427.629308 -273.241898) (xy 427.610017 -273.196622)
			(xy 427.59824 -273.148838) (xy 427.59428 -273.099784) (xy 427.276768 -273.099784) (xy 427.276264 -273.125492)
			(xy 427.268221 -273.176274) (xy 427.252333 -273.225173) (xy 427.22899 -273.270985) (xy 427.198769 -273.312581)
			(xy 427.162413 -273.348937) (xy 427.120817 -273.379158) (xy 427.075005 -273.402501) (xy 427.026106 -273.418389)
			(xy 426.975324 -273.426432) (xy 426.923908 -273.426432) (xy 426.873126 -273.418389) (xy 426.824227 -273.402501)
			(xy 426.778415 -273.379158) (xy 426.736819 -273.348937) (xy 426.700463 -273.312581) (xy 426.670242 -273.270985)
			(xy 426.646899 -273.225173) (xy 426.631011 -273.176274) (xy 426.622968 -273.125492) (xy 426.304798 -273.125492)
			(xy 426.297082 -273.172968) (xy 426.281498 -273.219649) (xy 426.258627 -273.263226) (xy 426.229062 -273.30257)
			(xy 426.193569 -273.336662) (xy 426.153066 -273.364618) (xy 426.108604 -273.385716) (xy 426.061333 -273.399408)
			(xy 426.012478 -273.40534) (xy 425.963303 -273.403359) (xy 425.915084 -273.393515) (xy 425.869068 -273.376063)
			(xy 425.826447 -273.351456) (xy 425.788326 -273.320331) (xy 425.755691 -273.283494) (xy 425.729388 -273.241898)
			(xy 425.710097 -273.196622) (xy 425.69832 -273.148838) (xy 425.69436 -273.099784) (xy 425.376848 -273.099784)
			(xy 425.376344 -273.125492) (xy 425.368301 -273.176274) (xy 425.352413 -273.225173) (xy 425.32907 -273.270985)
			(xy 425.298849 -273.312581) (xy 425.262493 -273.348937) (xy 425.220897 -273.379158) (xy 425.175085 -273.402501)
			(xy 425.126186 -273.418389) (xy 425.075404 -273.426432) (xy 425.023988 -273.426432) (xy 424.973206 -273.418389)
			(xy 424.924307 -273.402501) (xy 424.878495 -273.379158) (xy 424.836899 -273.348937) (xy 424.800543 -273.312581)
			(xy 424.770322 -273.270985) (xy 424.746979 -273.225173) (xy 424.731091 -273.176274) (xy 424.723048 -273.125492)
			(xy 424.404624 -273.125492) (xy 424.396908 -273.172968) (xy 424.381324 -273.219649) (xy 424.358453 -273.263226)
			(xy 424.328888 -273.30257) (xy 424.293395 -273.336662) (xy 424.252892 -273.364618) (xy 424.20843 -273.385716)
			(xy 424.161159 -273.399408) (xy 424.112304 -273.40534) (xy 424.063129 -273.403359) (xy 424.01491 -273.393515)
			(xy 423.968894 -273.376063) (xy 423.926273 -273.351456) (xy 423.888152 -273.320331) (xy 423.855517 -273.283494)
			(xy 423.829214 -273.241898) (xy 423.809923 -273.196622) (xy 423.798146 -273.148838) (xy 423.794186 -273.099784)
			(xy 423.476928 -273.099784) (xy 423.476424 -273.125492) (xy 423.468381 -273.176274) (xy 423.452493 -273.225173)
			(xy 423.42915 -273.270985) (xy 423.398929 -273.312581) (xy 423.362573 -273.348937) (xy 423.320977 -273.379158)
			(xy 423.275165 -273.402501) (xy 423.226266 -273.418389) (xy 423.175484 -273.426432) (xy 423.124068 -273.426432)
			(xy 423.073286 -273.418389) (xy 423.024387 -273.402501) (xy 422.978575 -273.379158) (xy 422.936979 -273.348937)
			(xy 422.900623 -273.312581) (xy 422.870402 -273.270985) (xy 422.847059 -273.225173) (xy 422.831171 -273.176274)
			(xy 422.823128 -273.125492) (xy 422.50445 -273.125492) (xy 422.496734 -273.172968) (xy 422.48115 -273.219649)
			(xy 422.458279 -273.263226) (xy 422.428714 -273.30257) (xy 422.393221 -273.336662) (xy 422.352718 -273.364618)
			(xy 422.308256 -273.385716) (xy 422.260985 -273.399408) (xy 422.21213 -273.40534) (xy 422.162955 -273.403359)
			(xy 422.114736 -273.393515) (xy 422.06872 -273.376063) (xy 422.026099 -273.351456) (xy 421.987978 -273.320331)
			(xy 421.955343 -273.283494) (xy 421.92904 -273.241898) (xy 421.909749 -273.196622) (xy 421.897972 -273.148838)
			(xy 421.894012 -273.099784) (xy 421.576754 -273.099784) (xy 421.57625 -273.125492) (xy 421.568207 -273.176274)
			(xy 421.552319 -273.225173) (xy 421.528976 -273.270985) (xy 421.498755 -273.312581) (xy 421.462399 -273.348937)
			(xy 421.420803 -273.379158) (xy 421.374991 -273.402501) (xy 421.326092 -273.418389) (xy 421.27531 -273.426432)
			(xy 421.223894 -273.426432) (xy 421.173112 -273.418389) (xy 421.124213 -273.402501) (xy 421.078401 -273.379158)
			(xy 421.036805 -273.348937) (xy 421.000449 -273.312581) (xy 420.970228 -273.270985) (xy 420.946885 -273.225173)
			(xy 420.930997 -273.176274) (xy 420.922954 -273.125492) (xy 420.60453 -273.125492) (xy 420.596814 -273.172968)
			(xy 420.58123 -273.219649) (xy 420.558359 -273.263226) (xy 420.528794 -273.30257) (xy 420.493301 -273.336662)
			(xy 420.452798 -273.364618) (xy 420.408336 -273.385716) (xy 420.361065 -273.399408) (xy 420.31221 -273.40534)
			(xy 420.263035 -273.403359) (xy 420.214816 -273.393515) (xy 420.1688 -273.376063) (xy 420.126179 -273.351456)
			(xy 420.088058 -273.320331) (xy 420.055423 -273.283494) (xy 420.02912 -273.241898) (xy 420.009829 -273.196622)
			(xy 419.998052 -273.148838) (xy 419.994092 -273.099784) (xy 419.676834 -273.099784) (xy 419.67633 -273.125492)
			(xy 419.668287 -273.176274) (xy 419.652399 -273.225173) (xy 419.629056 -273.270985) (xy 419.598835 -273.312581)
			(xy 419.562479 -273.348937) (xy 419.520883 -273.379158) (xy 419.475071 -273.402501) (xy 419.426172 -273.418389)
			(xy 419.37539 -273.426432) (xy 419.323974 -273.426432) (xy 419.273192 -273.418389) (xy 419.224293 -273.402501)
			(xy 419.178481 -273.379158) (xy 419.136885 -273.348937) (xy 419.100529 -273.312581) (xy 419.070308 -273.270985)
			(xy 419.046965 -273.225173) (xy 419.031077 -273.176274) (xy 419.023034 -273.125492) (xy 418.70461 -273.125492)
			(xy 418.696894 -273.172968) (xy 418.68131 -273.219649) (xy 418.658439 -273.263226) (xy 418.628874 -273.30257)
			(xy 418.593381 -273.336662) (xy 418.552878 -273.364618) (xy 418.508416 -273.385716) (xy 418.461145 -273.399408)
			(xy 418.41229 -273.40534) (xy 418.363115 -273.403359) (xy 418.314896 -273.393515) (xy 418.26888 -273.376063)
			(xy 418.226259 -273.351456) (xy 418.188138 -273.320331) (xy 418.155503 -273.283494) (xy 418.1292 -273.241898)
			(xy 418.109909 -273.196622) (xy 418.098132 -273.148838) (xy 418.094172 -273.099784) (xy 417.776914 -273.099784)
			(xy 417.77641 -273.125492) (xy 417.768367 -273.176274) (xy 417.752479 -273.225173) (xy 417.729136 -273.270985)
			(xy 417.698915 -273.312581) (xy 417.662559 -273.348937) (xy 417.620963 -273.379158) (xy 417.575151 -273.402501)
			(xy 417.526252 -273.418389) (xy 417.47547 -273.426432) (xy 417.424054 -273.426432) (xy 417.373272 -273.418389)
			(xy 417.324373 -273.402501) (xy 417.278561 -273.379158) (xy 417.236965 -273.348937) (xy 417.200609 -273.312581)
			(xy 417.170388 -273.270985) (xy 417.147045 -273.225173) (xy 417.131157 -273.176274) (xy 417.123114 -273.125492)
			(xy 416.804436 -273.125492) (xy 416.79672 -273.172968) (xy 416.781136 -273.219649) (xy 416.758265 -273.263226)
			(xy 416.7287 -273.30257) (xy 416.693207 -273.336662) (xy 416.652704 -273.364618) (xy 416.608242 -273.385716)
			(xy 416.560971 -273.399408) (xy 416.512116 -273.40534) (xy 416.462941 -273.403359) (xy 416.414722 -273.393515)
			(xy 416.368706 -273.376063) (xy 416.326085 -273.351456) (xy 416.287964 -273.320331) (xy 416.255329 -273.283494)
			(xy 416.229026 -273.241898) (xy 416.209735 -273.196622) (xy 416.197958 -273.148838) (xy 416.193998 -273.099784)
			(xy 415.87674 -273.099784) (xy 415.876236 -273.125492) (xy 415.868193 -273.176274) (xy 415.852305 -273.225173)
			(xy 415.828962 -273.270985) (xy 415.798741 -273.312581) (xy 415.762385 -273.348937) (xy 415.720789 -273.379158)
			(xy 415.674977 -273.402501) (xy 415.626078 -273.418389) (xy 415.575296 -273.426432) (xy 415.52388 -273.426432)
			(xy 415.473098 -273.418389) (xy 415.424199 -273.402501) (xy 415.378387 -273.379158) (xy 415.336791 -273.348937)
			(xy 415.300435 -273.312581) (xy 415.270214 -273.270985) (xy 415.246871 -273.225173) (xy 415.230983 -273.176274)
			(xy 415.22294 -273.125492) (xy 414.904516 -273.125492) (xy 414.8968 -273.172968) (xy 414.881216 -273.219649)
			(xy 414.858345 -273.263226) (xy 414.82878 -273.30257) (xy 414.793287 -273.336662) (xy 414.752784 -273.364618)
			(xy 414.708322 -273.385716) (xy 414.661051 -273.399408) (xy 414.612196 -273.40534) (xy 414.563021 -273.403359)
			(xy 414.514802 -273.393515) (xy 414.468786 -273.376063) (xy 414.426165 -273.351456) (xy 414.388044 -273.320331)
			(xy 414.355409 -273.283494) (xy 414.329106 -273.241898) (xy 414.309815 -273.196622) (xy 414.298038 -273.148838)
			(xy 414.294078 -273.099784) (xy 413.97682 -273.099784) (xy 413.976316 -273.125492) (xy 413.968273 -273.176274)
			(xy 413.952385 -273.225173) (xy 413.929042 -273.270985) (xy 413.898821 -273.312581) (xy 413.862465 -273.348937)
			(xy 413.820869 -273.379158) (xy 413.775057 -273.402501) (xy 413.726158 -273.418389) (xy 413.675376 -273.426432)
			(xy 413.62396 -273.426432) (xy 413.573178 -273.418389) (xy 413.524279 -273.402501) (xy 413.478467 -273.379158)
			(xy 413.436871 -273.348937) (xy 413.400515 -273.312581) (xy 413.370294 -273.270985) (xy 413.346951 -273.225173)
			(xy 413.331063 -273.176274) (xy 413.32302 -273.125492) (xy 413.004596 -273.125492) (xy 412.99688 -273.172968)
			(xy 412.981296 -273.219649) (xy 412.958425 -273.263226) (xy 412.92886 -273.30257) (xy 412.893367 -273.336662)
			(xy 412.852864 -273.364618) (xy 412.808402 -273.385716) (xy 412.761131 -273.399408) (xy 412.712276 -273.40534)
			(xy 412.663101 -273.403359) (xy 412.614882 -273.393515) (xy 412.568866 -273.376063) (xy 412.526245 -273.351456)
			(xy 412.488124 -273.320331) (xy 412.455489 -273.283494) (xy 412.429186 -273.241898) (xy 412.409895 -273.196622)
			(xy 412.398118 -273.148838) (xy 412.394158 -273.099784) (xy 412.0769 -273.099784) (xy 412.076396 -273.125492)
			(xy 412.068353 -273.176274) (xy 412.052465 -273.225173) (xy 412.029122 -273.270985) (xy 411.998901 -273.312581)
			(xy 411.962545 -273.348937) (xy 411.920949 -273.379158) (xy 411.875137 -273.402501) (xy 411.826238 -273.418389)
			(xy 411.775456 -273.426432) (xy 411.72404 -273.426432) (xy 411.673258 -273.418389) (xy 411.624359 -273.402501)
			(xy 411.578547 -273.379158) (xy 411.536951 -273.348937) (xy 411.500595 -273.312581) (xy 411.470374 -273.270985)
			(xy 411.447031 -273.225173) (xy 411.431143 -273.176274) (xy 411.4231 -273.125492) (xy 411.104422 -273.125492)
			(xy 411.096706 -273.172968) (xy 411.081122 -273.219649) (xy 411.058251 -273.263226) (xy 411.028686 -273.30257)
			(xy 410.993193 -273.336662) (xy 410.95269 -273.364618) (xy 410.908228 -273.385716) (xy 410.860957 -273.399408)
			(xy 410.812102 -273.40534) (xy 410.762927 -273.403359) (xy 410.714708 -273.393515) (xy 410.668692 -273.376063)
			(xy 410.626071 -273.351456) (xy 410.58795 -273.320331) (xy 410.555315 -273.283494) (xy 410.529012 -273.241898)
			(xy 410.509721 -273.196622) (xy 410.497944 -273.148838) (xy 410.493984 -273.099784) (xy 410.176726 -273.099784)
			(xy 410.176222 -273.125492) (xy 410.168179 -273.176274) (xy 410.152291 -273.225173) (xy 410.128948 -273.270985)
			(xy 410.098727 -273.312581) (xy 410.062371 -273.348937) (xy 410.020775 -273.379158) (xy 409.974963 -273.402501)
			(xy 409.926064 -273.418389) (xy 409.875282 -273.426432) (xy 409.823866 -273.426432) (xy 409.773084 -273.418389)
			(xy 409.724185 -273.402501) (xy 409.678373 -273.379158) (xy 409.636777 -273.348937) (xy 409.600421 -273.312581)
			(xy 409.5702 -273.270985) (xy 409.546857 -273.225173) (xy 409.530969 -273.176274) (xy 409.522926 -273.125492)
			(xy 409.204502 -273.125492) (xy 409.196786 -273.172968) (xy 409.181202 -273.219649) (xy 409.158331 -273.263226)
			(xy 409.128766 -273.30257) (xy 409.093273 -273.336662) (xy 409.05277 -273.364618) (xy 409.008308 -273.385716)
			(xy 408.961037 -273.399408) (xy 408.912182 -273.40534) (xy 408.863007 -273.403359) (xy 408.814788 -273.393515)
			(xy 408.768772 -273.376063) (xy 408.726151 -273.351456) (xy 408.68803 -273.320331) (xy 408.655395 -273.283494)
			(xy 408.629092 -273.241898) (xy 408.609801 -273.196622) (xy 408.598024 -273.148838) (xy 408.594064 -273.099784)
			(xy 408.276801 -273.099784) (xy 408.276302 -273.125238) (xy 408.268259 -273.17602) (xy 408.252371 -273.224919)
			(xy 408.229028 -273.270731) (xy 408.198807 -273.312327) (xy 408.162451 -273.348683) (xy 408.120855 -273.378904)
			(xy 408.075043 -273.402247) (xy 408.026144 -273.418135) (xy 407.975362 -273.426178) (xy 407.923946 -273.426178)
			(xy 407.873164 -273.418135) (xy 407.824265 -273.402247) (xy 407.778453 -273.378904) (xy 407.736857 -273.348683)
			(xy 407.700501 -273.312327) (xy 407.67028 -273.270731) (xy 407.646937 -273.224919) (xy 407.631049 -273.17602)
			(xy 407.623006 -273.125238) (xy 407.304623 -273.125238) (xy 407.296866 -273.172968) (xy 407.281282 -273.219649)
			(xy 407.258411 -273.263226) (xy 407.228846 -273.30257) (xy 407.193353 -273.336662) (xy 407.15285 -273.364618)
			(xy 407.108388 -273.385716) (xy 407.061117 -273.399408) (xy 407.012262 -273.40534) (xy 406.963087 -273.403359)
			(xy 406.914868 -273.393515) (xy 406.868852 -273.376063) (xy 406.826231 -273.351456) (xy 406.78811 -273.320331)
			(xy 406.755475 -273.283494) (xy 406.729172 -273.241898) (xy 406.709881 -273.196622) (xy 406.698104 -273.148838)
			(xy 406.694144 -273.099784) (xy 406.37714 -273.099784) (xy 406.376636 -273.125492) (xy 406.368593 -273.176274)
			(xy 406.352705 -273.225173) (xy 406.329362 -273.270985) (xy 406.299141 -273.312581) (xy 406.262785 -273.348937)
			(xy 406.221189 -273.379158) (xy 406.175377 -273.402501) (xy 406.126478 -273.418389) (xy 406.075696 -273.426432)
			(xy 406.02428 -273.426432) (xy 405.973498 -273.418389) (xy 405.924599 -273.402501) (xy 405.878787 -273.379158)
			(xy 405.837191 -273.348937) (xy 405.800835 -273.312581) (xy 405.770614 -273.270985) (xy 405.747271 -273.225173)
			(xy 405.731383 -273.176274) (xy 405.72334 -273.125492) (xy 405.404662 -273.125492) (xy 405.396946 -273.172968)
			(xy 405.381362 -273.219649) (xy 405.358491 -273.263226) (xy 405.328926 -273.30257) (xy 405.293433 -273.336662)
			(xy 405.25293 -273.364618) (xy 405.208468 -273.385716) (xy 405.161197 -273.399408) (xy 405.112342 -273.40534)
			(xy 405.063167 -273.403359) (xy 405.014948 -273.393515) (xy 404.968932 -273.376063) (xy 404.926311 -273.351456)
			(xy 404.88819 -273.320331) (xy 404.855555 -273.283494) (xy 404.829252 -273.241898) (xy 404.809961 -273.196622)
			(xy 404.798184 -273.148838) (xy 404.794224 -273.099784) (xy 404.476966 -273.099784) (xy 404.476462 -273.125492)
			(xy 404.468419 -273.176274) (xy 404.452531 -273.225173) (xy 404.429188 -273.270985) (xy 404.398967 -273.312581)
			(xy 404.362611 -273.348937) (xy 404.321015 -273.379158) (xy 404.275203 -273.402501) (xy 404.226304 -273.418389)
			(xy 404.175522 -273.426432) (xy 404.124106 -273.426432) (xy 404.073324 -273.418389) (xy 404.024425 -273.402501)
			(xy 403.978613 -273.379158) (xy 403.937017 -273.348937) (xy 403.900661 -273.312581) (xy 403.87044 -273.270985)
			(xy 403.847097 -273.225173) (xy 403.831209 -273.176274) (xy 403.823166 -273.125492) (xy 403.504488 -273.125492)
			(xy 403.496772 -273.172968) (xy 403.481188 -273.219649) (xy 403.458317 -273.263226) (xy 403.428752 -273.30257)
			(xy 403.393259 -273.336662) (xy 403.352756 -273.364618) (xy 403.308294 -273.385716) (xy 403.261023 -273.399408)
			(xy 403.212168 -273.40534) (xy 403.162993 -273.403359) (xy 403.114774 -273.393515) (xy 403.068758 -273.376063)
			(xy 403.026137 -273.351456) (xy 402.988016 -273.320331) (xy 402.955381 -273.283494) (xy 402.929078 -273.241898)
			(xy 402.909787 -273.196622) (xy 402.89801 -273.148838) (xy 402.89405 -273.099784) (xy 402.577046 -273.099784)
			(xy 402.576542 -273.125492) (xy 402.568499 -273.176274) (xy 402.552611 -273.225173) (xy 402.529268 -273.270985)
			(xy 402.499047 -273.312581) (xy 402.462691 -273.348937) (xy 402.421095 -273.379158) (xy 402.375283 -273.402501)
			(xy 402.326384 -273.418389) (xy 402.275602 -273.426432) (xy 402.224186 -273.426432) (xy 402.173404 -273.418389)
			(xy 402.124505 -273.402501) (xy 402.078693 -273.379158) (xy 402.037097 -273.348937) (xy 402.000741 -273.312581)
			(xy 401.97052 -273.270985) (xy 401.947177 -273.225173) (xy 401.931289 -273.176274) (xy 401.923246 -273.125492)
			(xy 401.604568 -273.125492) (xy 401.596852 -273.172968) (xy 401.581268 -273.219649) (xy 401.558397 -273.263226)
			(xy 401.528832 -273.30257) (xy 401.493339 -273.336662) (xy 401.452836 -273.364618) (xy 401.408374 -273.385716)
			(xy 401.361103 -273.399408) (xy 401.312248 -273.40534) (xy 401.263073 -273.403359) (xy 401.214854 -273.393515)
			(xy 401.168838 -273.376063) (xy 401.126217 -273.351456) (xy 401.088096 -273.320331) (xy 401.055461 -273.283494)
			(xy 401.029158 -273.241898) (xy 401.009867 -273.196622) (xy 400.99809 -273.148838) (xy 400.99413 -273.099784)
			(xy 400.677126 -273.099784) (xy 400.676622 -273.125492) (xy 400.668579 -273.176274) (xy 400.652691 -273.225173)
			(xy 400.629348 -273.270985) (xy 400.599127 -273.312581) (xy 400.562771 -273.348937) (xy 400.521175 -273.379158)
			(xy 400.475363 -273.402501) (xy 400.426464 -273.418389) (xy 400.375682 -273.426432) (xy 400.324266 -273.426432)
			(xy 400.273484 -273.418389) (xy 400.224585 -273.402501) (xy 400.178773 -273.379158) (xy 400.137177 -273.348937)
			(xy 400.100821 -273.312581) (xy 400.0706 -273.270985) (xy 400.047257 -273.225173) (xy 400.031369 -273.176274)
			(xy 400.023326 -273.125492) (xy 399.704648 -273.125492) (xy 399.696932 -273.172968) (xy 399.681348 -273.219649)
			(xy 399.658477 -273.263226) (xy 399.628912 -273.30257) (xy 399.593419 -273.336662) (xy 399.552916 -273.364618)
			(xy 399.508454 -273.385716) (xy 399.461183 -273.399408) (xy 399.412328 -273.40534) (xy 399.363153 -273.403359)
			(xy 399.314934 -273.393515) (xy 399.268918 -273.376063) (xy 399.226297 -273.351456) (xy 399.188176 -273.320331)
			(xy 399.155541 -273.283494) (xy 399.129238 -273.241898) (xy 399.109947 -273.196622) (xy 399.09817 -273.148838)
			(xy 399.09421 -273.099784) (xy 398.776464 -273.099784) (xy 398.776464 -273.125509) (xy 398.76842 -273.176294)
			(xy 398.752531 -273.225195) (xy 398.729188 -273.271009) (xy 398.698965 -273.312607) (xy 398.662607 -273.348965)
			(xy 398.621009 -273.379188) (xy 398.575195 -273.402531) (xy 398.526294 -273.41842) (xy 398.475509 -273.426464)
			(xy 398.4498 -273.426936) (xy 398.417288 -273.425158) (xy 398.406366 -273.424142) (xy 398.386046 -273.430746)
			(xy 398.322292 -273.488658) (xy 398.314782 -273.496203) (xy 398.306115 -273.515621) (xy 398.305528 -273.52625)
			(xy 398.305528 -273.574764) (xy 398.305486 -273.584118) (xy 398.304472 -273.602799) (xy 398.303496 -273.612102)
			(xy 398.301972 -273.623786) (xy 398.309592 -273.645376) (xy 398.381982 -273.71802) (xy 398.403572 -273.725894)
			(xy 398.415256 -273.724624) (xy 398.4498 -273.722592) (xy 398.475504 -273.723096) (xy 398.52628 -273.731138)
			(xy 398.575172 -273.747025) (xy 398.620978 -273.770364) (xy 398.662568 -273.800581) (xy 398.698919 -273.836932)
			(xy 398.729136 -273.878522) (xy 398.752475 -273.924328) (xy 398.768362 -273.97322) (xy 398.776404 -274.023996)
			(xy 398.776404 -274.049744) (xy 399.09421 -274.049744) (xy 399.09817 -274.00069) (xy 399.109947 -273.952906)
			(xy 399.129238 -273.90763) (xy 399.155541 -273.866034) (xy 399.188176 -273.829197) (xy 399.226297 -273.798072)
			(xy 399.268918 -273.773465) (xy 399.314934 -273.756013) (xy 399.363153 -273.746169) (xy 399.412328 -273.744188)
			(xy 399.461183 -273.75012) (xy 399.508454 -273.763812) (xy 399.552916 -273.78491) (xy 399.593419 -273.812866)
			(xy 399.628912 -273.846958) (xy 399.658477 -273.886302) (xy 399.681348 -273.929879) (xy 399.696932 -273.97656)
			(xy 399.704827 -274.025137) (xy 399.705322 -274.049744) (xy 399.704827 -274.074351) (xy 399.704648 -274.075452)
			(xy 400.023326 -274.075452) (xy 400.023326 -274.024036) (xy 400.031369 -273.973254) (xy 400.047257 -273.924355)
			(xy 400.0706 -273.878543) (xy 400.100821 -273.836947) (xy 400.137177 -273.800591) (xy 400.178773 -273.77037)
			(xy 400.224585 -273.747027) (xy 400.273484 -273.731139) (xy 400.324266 -273.723096) (xy 400.375682 -273.723096)
			(xy 400.426464 -273.731139) (xy 400.475363 -273.747027) (xy 400.521175 -273.77037) (xy 400.562771 -273.800591)
			(xy 400.599127 -273.836947) (xy 400.629348 -273.878543) (xy 400.652691 -273.924355) (xy 400.668579 -273.973254)
			(xy 400.676622 -274.024036) (xy 400.677126 -274.049744) (xy 400.99413 -274.049744) (xy 400.99809 -274.00069)
			(xy 401.009867 -273.952906) (xy 401.029158 -273.90763) (xy 401.055461 -273.866034) (xy 401.088096 -273.829197)
			(xy 401.126217 -273.798072) (xy 401.168838 -273.773465) (xy 401.214854 -273.756013) (xy 401.263073 -273.746169)
			(xy 401.312248 -273.744188) (xy 401.361103 -273.75012) (xy 401.408374 -273.763812) (xy 401.452836 -273.78491)
			(xy 401.493339 -273.812866) (xy 401.528832 -273.846958) (xy 401.558397 -273.886302) (xy 401.581268 -273.929879)
			(xy 401.596852 -273.97656) (xy 401.604747 -274.025137) (xy 401.605242 -274.049744) (xy 401.604747 -274.074351)
			(xy 401.604568 -274.075452) (xy 401.923246 -274.075452) (xy 401.923246 -274.024036) (xy 401.931289 -273.973254)
			(xy 401.947177 -273.924355) (xy 401.97052 -273.878543) (xy 402.000741 -273.836947) (xy 402.037097 -273.800591)
			(xy 402.078693 -273.77037) (xy 402.124505 -273.747027) (xy 402.173404 -273.731139) (xy 402.224186 -273.723096)
			(xy 402.275602 -273.723096) (xy 402.326384 -273.731139) (xy 402.375283 -273.747027) (xy 402.421095 -273.77037)
			(xy 402.462691 -273.800591) (xy 402.499047 -273.836947) (xy 402.529268 -273.878543) (xy 402.552611 -273.924355)
			(xy 402.568499 -273.973254) (xy 402.576542 -274.024036) (xy 402.577046 -274.049744) (xy 402.89405 -274.049744)
			(xy 402.89801 -274.00069) (xy 402.909787 -273.952906) (xy 402.929078 -273.90763) (xy 402.955381 -273.866034)
			(xy 402.988016 -273.829197) (xy 403.026137 -273.798072) (xy 403.068758 -273.773465) (xy 403.114774 -273.756013)
			(xy 403.162993 -273.746169) (xy 403.212168 -273.744188) (xy 403.261023 -273.75012) (xy 403.308294 -273.763812)
			(xy 403.352756 -273.78491) (xy 403.393259 -273.812866) (xy 403.428752 -273.846958) (xy 403.458317 -273.886302)
			(xy 403.481188 -273.929879) (xy 403.496772 -273.97656) (xy 403.504667 -274.025137) (xy 403.505162 -274.049744)
			(xy 403.504667 -274.074351) (xy 403.504488 -274.075452) (xy 403.823166 -274.075452) (xy 403.823166 -274.024036)
			(xy 403.831209 -273.973254) (xy 403.847097 -273.924355) (xy 403.87044 -273.878543) (xy 403.900661 -273.836947)
			(xy 403.937017 -273.800591) (xy 403.978613 -273.77037) (xy 404.024425 -273.747027) (xy 404.073324 -273.731139)
			(xy 404.124106 -273.723096) (xy 404.175522 -273.723096) (xy 404.226304 -273.731139) (xy 404.275203 -273.747027)
			(xy 404.321015 -273.77037) (xy 404.362611 -273.800591) (xy 404.398967 -273.836947) (xy 404.429188 -273.878543)
			(xy 404.452531 -273.924355) (xy 404.468419 -273.973254) (xy 404.476462 -274.024036) (xy 404.476966 -274.049744)
			(xy 404.794224 -274.049744) (xy 404.798184 -274.00069) (xy 404.809961 -273.952906) (xy 404.829252 -273.90763)
			(xy 404.855555 -273.866034) (xy 404.88819 -273.829197) (xy 404.926311 -273.798072) (xy 404.968932 -273.773465)
			(xy 405.014948 -273.756013) (xy 405.063167 -273.746169) (xy 405.112342 -273.744188) (xy 405.161197 -273.75012)
			(xy 405.208468 -273.763812) (xy 405.25293 -273.78491) (xy 405.293433 -273.812866) (xy 405.328926 -273.846958)
			(xy 405.358491 -273.886302) (xy 405.381362 -273.929879) (xy 405.396946 -273.97656) (xy 405.404841 -274.025137)
			(xy 405.405336 -274.049744) (xy 405.404841 -274.074351) (xy 405.404662 -274.075452) (xy 405.72334 -274.075452)
			(xy 405.72334 -274.024036) (xy 405.731383 -273.973254) (xy 405.747271 -273.924355) (xy 405.770614 -273.878543)
			(xy 405.800835 -273.836947) (xy 405.837191 -273.800591) (xy 405.878787 -273.77037) (xy 405.924599 -273.747027)
			(xy 405.973498 -273.731139) (xy 406.02428 -273.723096) (xy 406.075696 -273.723096) (xy 406.126478 -273.731139)
			(xy 406.175377 -273.747027) (xy 406.221189 -273.77037) (xy 406.262785 -273.800591) (xy 406.299141 -273.836947)
			(xy 406.329362 -273.878543) (xy 406.352705 -273.924355) (xy 406.368593 -273.973254) (xy 406.376636 -274.024036)
			(xy 406.37714 -274.049744) (xy 406.694144 -274.049744) (xy 406.698104 -274.00069) (xy 406.709881 -273.952906)
			(xy 406.729172 -273.90763) (xy 406.755475 -273.866034) (xy 406.78811 -273.829197) (xy 406.826231 -273.798072)
			(xy 406.868852 -273.773465) (xy 406.914868 -273.756013) (xy 406.963087 -273.746169) (xy 407.012262 -273.744188)
			(xy 407.061117 -273.75012) (xy 407.108388 -273.763812) (xy 407.15285 -273.78491) (xy 407.193353 -273.812866)
			(xy 407.228846 -273.846958) (xy 407.258411 -273.886302) (xy 407.281282 -273.929879) (xy 407.296866 -273.97656)
			(xy 407.304761 -274.025137) (xy 407.305256 -274.049744) (xy 407.304761 -274.074351) (xy 407.304623 -274.075198)
			(xy 407.623006 -274.075198) (xy 407.623006 -274.023782) (xy 407.631049 -273.973) (xy 407.646937 -273.924101)
			(xy 407.67028 -273.878289) (xy 407.700501 -273.836693) (xy 407.736857 -273.800337) (xy 407.778453 -273.770116)
			(xy 407.824265 -273.746773) (xy 407.873164 -273.730885) (xy 407.923946 -273.722842) (xy 407.975362 -273.722842)
			(xy 408.026144 -273.730885) (xy 408.075043 -273.746773) (xy 408.120855 -273.770116) (xy 408.162451 -273.800337)
			(xy 408.198807 -273.836693) (xy 408.229028 -273.878289) (xy 408.252371 -273.924101) (xy 408.268259 -273.973)
			(xy 408.276302 -274.023782) (xy 408.276806 -274.04949) (xy 408.276801 -274.049744) (xy 408.594064 -274.049744)
			(xy 408.598024 -274.00069) (xy 408.609801 -273.952906) (xy 408.629092 -273.90763) (xy 408.655395 -273.866034)
			(xy 408.68803 -273.829197) (xy 408.726151 -273.798072) (xy 408.768772 -273.773465) (xy 408.814788 -273.756013)
			(xy 408.863007 -273.746169) (xy 408.912182 -273.744188) (xy 408.961037 -273.75012) (xy 409.008308 -273.763812)
			(xy 409.05277 -273.78491) (xy 409.093273 -273.812866) (xy 409.128766 -273.846958) (xy 409.158331 -273.886302)
			(xy 409.181202 -273.929879) (xy 409.196786 -273.97656) (xy 409.204681 -274.025137) (xy 409.205176 -274.049744)
			(xy 409.204681 -274.074351) (xy 409.204502 -274.075452) (xy 409.522926 -274.075452) (xy 409.522926 -274.024036)
			(xy 409.530969 -273.973254) (xy 409.546857 -273.924355) (xy 409.5702 -273.878543) (xy 409.600421 -273.836947)
			(xy 409.636777 -273.800591) (xy 409.678373 -273.77037) (xy 409.724185 -273.747027) (xy 409.773084 -273.731139)
			(xy 409.823866 -273.723096) (xy 409.875282 -273.723096) (xy 409.926064 -273.731139) (xy 409.974963 -273.747027)
			(xy 410.020775 -273.77037) (xy 410.062371 -273.800591) (xy 410.098727 -273.836947) (xy 410.128948 -273.878543)
			(xy 410.152291 -273.924355) (xy 410.168179 -273.973254) (xy 410.176222 -274.024036) (xy 410.176726 -274.049744)
			(xy 410.493984 -274.049744) (xy 410.497944 -274.00069) (xy 410.509721 -273.952906) (xy 410.529012 -273.90763)
			(xy 410.555315 -273.866034) (xy 410.58795 -273.829197) (xy 410.626071 -273.798072) (xy 410.668692 -273.773465)
			(xy 410.714708 -273.756013) (xy 410.762927 -273.746169) (xy 410.812102 -273.744188) (xy 410.860957 -273.75012)
			(xy 410.908228 -273.763812) (xy 410.95269 -273.78491) (xy 410.993193 -273.812866) (xy 411.028686 -273.846958)
			(xy 411.058251 -273.886302) (xy 411.081122 -273.929879) (xy 411.096706 -273.97656) (xy 411.104601 -274.025137)
			(xy 411.105096 -274.049744) (xy 411.104601 -274.074351) (xy 411.104422 -274.075452) (xy 411.4231 -274.075452)
			(xy 411.4231 -274.024036) (xy 411.431143 -273.973254) (xy 411.447031 -273.924355) (xy 411.470374 -273.878543)
			(xy 411.500595 -273.836947) (xy 411.536951 -273.800591) (xy 411.578547 -273.77037) (xy 411.624359 -273.747027)
			(xy 411.673258 -273.731139) (xy 411.72404 -273.723096) (xy 411.775456 -273.723096) (xy 411.826238 -273.731139)
			(xy 411.875137 -273.747027) (xy 411.920949 -273.77037) (xy 411.962545 -273.800591) (xy 411.998901 -273.836947)
			(xy 412.029122 -273.878543) (xy 412.052465 -273.924355) (xy 412.068353 -273.973254) (xy 412.076396 -274.024036)
			(xy 412.0769 -274.049744) (xy 412.394158 -274.049744) (xy 412.398118 -274.00069) (xy 412.409895 -273.952906)
			(xy 412.429186 -273.90763) (xy 412.455489 -273.866034) (xy 412.488124 -273.829197) (xy 412.526245 -273.798072)
			(xy 412.568866 -273.773465) (xy 412.614882 -273.756013) (xy 412.663101 -273.746169) (xy 412.712276 -273.744188)
			(xy 412.761131 -273.75012) (xy 412.808402 -273.763812) (xy 412.852864 -273.78491) (xy 412.893367 -273.812866)
			(xy 412.92886 -273.846958) (xy 412.958425 -273.886302) (xy 412.981296 -273.929879) (xy 412.99688 -273.97656)
			(xy 413.004775 -274.025137) (xy 413.00527 -274.049744) (xy 413.004775 -274.074351) (xy 413.004596 -274.075452)
			(xy 413.32302 -274.075452) (xy 413.32302 -274.024036) (xy 413.331063 -273.973254) (xy 413.346951 -273.924355)
			(xy 413.370294 -273.878543) (xy 413.400515 -273.836947) (xy 413.436871 -273.800591) (xy 413.478467 -273.77037)
			(xy 413.524279 -273.747027) (xy 413.573178 -273.731139) (xy 413.62396 -273.723096) (xy 413.675376 -273.723096)
			(xy 413.726158 -273.731139) (xy 413.775057 -273.747027) (xy 413.820869 -273.77037) (xy 413.862465 -273.800591)
			(xy 413.898821 -273.836947) (xy 413.929042 -273.878543) (xy 413.952385 -273.924355) (xy 413.968273 -273.973254)
			(xy 413.976316 -274.024036) (xy 413.97682 -274.049744) (xy 414.294078 -274.049744) (xy 414.298038 -274.00069)
			(xy 414.309815 -273.952906) (xy 414.329106 -273.90763) (xy 414.355409 -273.866034) (xy 414.388044 -273.829197)
			(xy 414.426165 -273.798072) (xy 414.468786 -273.773465) (xy 414.514802 -273.756013) (xy 414.563021 -273.746169)
			(xy 414.612196 -273.744188) (xy 414.661051 -273.75012) (xy 414.708322 -273.763812) (xy 414.752784 -273.78491)
			(xy 414.793287 -273.812866) (xy 414.82878 -273.846958) (xy 414.858345 -273.886302) (xy 414.881216 -273.929879)
			(xy 414.8968 -273.97656) (xy 414.904695 -274.025137) (xy 414.90519 -274.049744) (xy 414.904695 -274.074351)
			(xy 414.904516 -274.075452) (xy 415.22294 -274.075452) (xy 415.22294 -274.024036) (xy 415.230983 -273.973254)
			(xy 415.246871 -273.924355) (xy 415.270214 -273.878543) (xy 415.300435 -273.836947) (xy 415.336791 -273.800591)
			(xy 415.378387 -273.77037) (xy 415.424199 -273.747027) (xy 415.473098 -273.731139) (xy 415.52388 -273.723096)
			(xy 415.575296 -273.723096) (xy 415.626078 -273.731139) (xy 415.674977 -273.747027) (xy 415.720789 -273.77037)
			(xy 415.762385 -273.800591) (xy 415.798741 -273.836947) (xy 415.828962 -273.878543) (xy 415.852305 -273.924355)
			(xy 415.868193 -273.973254) (xy 415.876236 -274.024036) (xy 415.87674 -274.049744) (xy 416.193998 -274.049744)
			(xy 416.197958 -274.00069) (xy 416.209735 -273.952906) (xy 416.229026 -273.90763) (xy 416.255329 -273.866034)
			(xy 416.287964 -273.829197) (xy 416.326085 -273.798072) (xy 416.368706 -273.773465) (xy 416.414722 -273.756013)
			(xy 416.462941 -273.746169) (xy 416.512116 -273.744188) (xy 416.560971 -273.75012) (xy 416.608242 -273.763812)
			(xy 416.652704 -273.78491) (xy 416.693207 -273.812866) (xy 416.7287 -273.846958) (xy 416.758265 -273.886302)
			(xy 416.781136 -273.929879) (xy 416.79672 -273.97656) (xy 416.804615 -274.025137) (xy 416.80511 -274.049744)
			(xy 416.804615 -274.074351) (xy 416.804436 -274.075452) (xy 417.123114 -274.075452) (xy 417.123114 -274.024036)
			(xy 417.131157 -273.973254) (xy 417.147045 -273.924355) (xy 417.170388 -273.878543) (xy 417.200609 -273.836947)
			(xy 417.236965 -273.800591) (xy 417.278561 -273.77037) (xy 417.324373 -273.747027) (xy 417.373272 -273.731139)
			(xy 417.424054 -273.723096) (xy 417.47547 -273.723096) (xy 417.526252 -273.731139) (xy 417.575151 -273.747027)
			(xy 417.620963 -273.77037) (xy 417.662559 -273.800591) (xy 417.698915 -273.836947) (xy 417.729136 -273.878543)
			(xy 417.752479 -273.924355) (xy 417.768367 -273.973254) (xy 417.77641 -274.024036) (xy 417.776914 -274.049744)
			(xy 418.094172 -274.049744) (xy 418.098132 -274.00069) (xy 418.109909 -273.952906) (xy 418.1292 -273.90763)
			(xy 418.155503 -273.866034) (xy 418.188138 -273.829197) (xy 418.226259 -273.798072) (xy 418.26888 -273.773465)
			(xy 418.314896 -273.756013) (xy 418.363115 -273.746169) (xy 418.41229 -273.744188) (xy 418.461145 -273.75012)
			(xy 418.508416 -273.763812) (xy 418.552878 -273.78491) (xy 418.593381 -273.812866) (xy 418.628874 -273.846958)
			(xy 418.658439 -273.886302) (xy 418.68131 -273.929879) (xy 418.696894 -273.97656) (xy 418.704789 -274.025137)
			(xy 418.705284 -274.049744) (xy 418.704789 -274.074351) (xy 418.70461 -274.075452) (xy 419.023034 -274.075452)
			(xy 419.023034 -274.024036) (xy 419.031077 -273.973254) (xy 419.046965 -273.924355) (xy 419.070308 -273.878543)
			(xy 419.100529 -273.836947) (xy 419.136885 -273.800591) (xy 419.178481 -273.77037) (xy 419.224293 -273.747027)
			(xy 419.273192 -273.731139) (xy 419.323974 -273.723096) (xy 419.37539 -273.723096) (xy 419.426172 -273.731139)
			(xy 419.475071 -273.747027) (xy 419.520883 -273.77037) (xy 419.562479 -273.800591) (xy 419.598835 -273.836947)
			(xy 419.629056 -273.878543) (xy 419.652399 -273.924355) (xy 419.668287 -273.973254) (xy 419.67633 -274.024036)
			(xy 419.676834 -274.049744) (xy 419.994092 -274.049744) (xy 419.998052 -274.00069) (xy 420.009829 -273.952906)
			(xy 420.02912 -273.90763) (xy 420.055423 -273.866034) (xy 420.088058 -273.829197) (xy 420.126179 -273.798072)
			(xy 420.1688 -273.773465) (xy 420.214816 -273.756013) (xy 420.263035 -273.746169) (xy 420.31221 -273.744188)
			(xy 420.361065 -273.75012) (xy 420.408336 -273.763812) (xy 420.452798 -273.78491) (xy 420.493301 -273.812866)
			(xy 420.528794 -273.846958) (xy 420.558359 -273.886302) (xy 420.58123 -273.929879) (xy 420.596814 -273.97656)
			(xy 420.604709 -274.025137) (xy 420.605204 -274.049744) (xy 420.604709 -274.074351) (xy 420.60453 -274.075452)
			(xy 420.922954 -274.075452) (xy 420.922954 -274.024036) (xy 420.930997 -273.973254) (xy 420.946885 -273.924355)
			(xy 420.970228 -273.878543) (xy 421.000449 -273.836947) (xy 421.036805 -273.800591) (xy 421.078401 -273.77037)
			(xy 421.124213 -273.747027) (xy 421.173112 -273.731139) (xy 421.223894 -273.723096) (xy 421.27531 -273.723096)
			(xy 421.326092 -273.731139) (xy 421.374991 -273.747027) (xy 421.420803 -273.77037) (xy 421.462399 -273.800591)
			(xy 421.498755 -273.836947) (xy 421.528976 -273.878543) (xy 421.552319 -273.924355) (xy 421.568207 -273.973254)
			(xy 421.57625 -274.024036) (xy 421.576754 -274.049744) (xy 421.894012 -274.049744) (xy 421.897972 -274.00069)
			(xy 421.909749 -273.952906) (xy 421.92904 -273.90763) (xy 421.955343 -273.866034) (xy 421.987978 -273.829197)
			(xy 422.026099 -273.798072) (xy 422.06872 -273.773465) (xy 422.114736 -273.756013) (xy 422.162955 -273.746169)
			(xy 422.21213 -273.744188) (xy 422.260985 -273.75012) (xy 422.308256 -273.763812) (xy 422.352718 -273.78491)
			(xy 422.393221 -273.812866) (xy 422.428714 -273.846958) (xy 422.458279 -273.886302) (xy 422.48115 -273.929879)
			(xy 422.496734 -273.97656) (xy 422.504629 -274.025137) (xy 422.505124 -274.049744) (xy 422.504629 -274.074351)
			(xy 422.50445 -274.075452) (xy 422.823128 -274.075452) (xy 422.823128 -274.024036) (xy 422.831171 -273.973254)
			(xy 422.847059 -273.924355) (xy 422.870402 -273.878543) (xy 422.900623 -273.836947) (xy 422.936979 -273.800591)
			(xy 422.978575 -273.77037) (xy 423.024387 -273.747027) (xy 423.073286 -273.731139) (xy 423.124068 -273.723096)
			(xy 423.175484 -273.723096) (xy 423.226266 -273.731139) (xy 423.275165 -273.747027) (xy 423.320977 -273.77037)
			(xy 423.362573 -273.800591) (xy 423.398929 -273.836947) (xy 423.42915 -273.878543) (xy 423.452493 -273.924355)
			(xy 423.468381 -273.973254) (xy 423.476424 -274.024036) (xy 423.476928 -274.049744) (xy 423.79444 -274.049744)
			(xy 423.7984 -274.00069) (xy 423.810177 -273.952906) (xy 423.829468 -273.90763) (xy 423.855771 -273.866034)
			(xy 423.888406 -273.829197) (xy 423.926527 -273.798072) (xy 423.969148 -273.773465) (xy 424.015164 -273.756013)
			(xy 424.063383 -273.746169) (xy 424.112558 -273.744188) (xy 424.161413 -273.75012) (xy 424.208684 -273.763812)
			(xy 424.253146 -273.78491) (xy 424.293649 -273.812866) (xy 424.329142 -273.846958) (xy 424.358707 -273.886302)
			(xy 424.381578 -273.929879) (xy 424.397162 -273.97656) (xy 424.405057 -274.025137) (xy 424.405552 -274.049744)
			(xy 424.405057 -274.074351) (xy 424.404878 -274.075452) (xy 424.723048 -274.075452) (xy 424.723048 -274.024036)
			(xy 424.731091 -273.973254) (xy 424.746979 -273.924355) (xy 424.770322 -273.878543) (xy 424.800543 -273.836947)
			(xy 424.836899 -273.800591) (xy 424.878495 -273.77037) (xy 424.924307 -273.747027) (xy 424.973206 -273.731139)
			(xy 425.023988 -273.723096) (xy 425.075404 -273.723096) (xy 425.126186 -273.731139) (xy 425.175085 -273.747027)
			(xy 425.220897 -273.77037) (xy 425.262493 -273.800591) (xy 425.298849 -273.836947) (xy 425.32907 -273.878543)
			(xy 425.352413 -273.924355) (xy 425.368301 -273.973254) (xy 425.376344 -274.024036) (xy 425.376848 -274.049744)
			(xy 425.69436 -274.049744) (xy 425.69832 -274.00069) (xy 425.710097 -273.952906) (xy 425.729388 -273.90763)
			(xy 425.755691 -273.866034) (xy 425.788326 -273.829197) (xy 425.826447 -273.798072) (xy 425.869068 -273.773465)
			(xy 425.915084 -273.756013) (xy 425.963303 -273.746169) (xy 426.012478 -273.744188) (xy 426.061333 -273.75012)
			(xy 426.108604 -273.763812) (xy 426.153066 -273.78491) (xy 426.193569 -273.812866) (xy 426.229062 -273.846958)
			(xy 426.258627 -273.886302) (xy 426.281498 -273.929879) (xy 426.297082 -273.97656) (xy 426.304977 -274.025137)
			(xy 426.305472 -274.049744) (xy 426.304977 -274.074351) (xy 426.304798 -274.075452) (xy 426.622968 -274.075452)
			(xy 426.622968 -274.024036) (xy 426.631011 -273.973254) (xy 426.646899 -273.924355) (xy 426.670242 -273.878543)
			(xy 426.700463 -273.836947) (xy 426.736819 -273.800591) (xy 426.778415 -273.77037) (xy 426.824227 -273.747027)
			(xy 426.873126 -273.731139) (xy 426.923908 -273.723096) (xy 426.975324 -273.723096) (xy 427.026106 -273.731139)
			(xy 427.075005 -273.747027) (xy 427.120817 -273.77037) (xy 427.162413 -273.800591) (xy 427.198769 -273.836947)
			(xy 427.22899 -273.878543) (xy 427.252333 -273.924355) (xy 427.268221 -273.973254) (xy 427.276264 -274.024036)
			(xy 427.276768 -274.049744) (xy 427.59428 -274.049744) (xy 427.59824 -274.00069) (xy 427.610017 -273.952906)
			(xy 427.629308 -273.90763) (xy 427.655611 -273.866034) (xy 427.688246 -273.829197) (xy 427.726367 -273.798072)
			(xy 427.768988 -273.773465) (xy 427.815004 -273.756013) (xy 427.863223 -273.746169) (xy 427.912398 -273.744188)
			(xy 427.961253 -273.75012) (xy 428.008524 -273.763812) (xy 428.052986 -273.78491) (xy 428.093489 -273.812866)
			(xy 428.128982 -273.846958) (xy 428.158547 -273.886302) (xy 428.181418 -273.929879) (xy 428.197002 -273.97656)
			(xy 428.204897 -274.025137) (xy 428.205392 -274.049744) (xy 428.204897 -274.074351) (xy 428.204718 -274.075452)
			(xy 428.522888 -274.075452) (xy 428.522888 -274.024036) (xy 428.530931 -273.973254) (xy 428.546819 -273.924355)
			(xy 428.570162 -273.878543) (xy 428.600383 -273.836947) (xy 428.636739 -273.800591) (xy 428.678335 -273.77037)
			(xy 428.724147 -273.747027) (xy 428.773046 -273.731139) (xy 428.823828 -273.723096) (xy 428.875244 -273.723096)
			(xy 428.926026 -273.731139) (xy 428.974925 -273.747027) (xy 429.020737 -273.77037) (xy 429.062333 -273.800591)
			(xy 429.098689 -273.836947) (xy 429.12891 -273.878543) (xy 429.152253 -273.924355) (xy 429.168141 -273.973254)
			(xy 429.176184 -274.024036) (xy 429.176688 -274.049744) (xy 429.4942 -274.049744) (xy 429.49816 -274.00069)
			(xy 429.509937 -273.952906) (xy 429.529228 -273.90763) (xy 429.555531 -273.866034) (xy 429.588166 -273.829197)
			(xy 429.626287 -273.798072) (xy 429.668908 -273.773465) (xy 429.714924 -273.756013) (xy 429.763143 -273.746169)
			(xy 429.812318 -273.744188) (xy 429.861173 -273.75012) (xy 429.908444 -273.763812) (xy 429.952906 -273.78491)
			(xy 429.993409 -273.812866) (xy 430.028902 -273.846958) (xy 430.058467 -273.886302) (xy 430.081338 -273.929879)
			(xy 430.096922 -273.97656) (xy 430.104817 -274.025137) (xy 430.105312 -274.049744) (xy 430.44416 -274.049744)
			(xy 430.44812 -274.00069) (xy 430.459897 -273.952906) (xy 430.479188 -273.90763) (xy 430.505491 -273.866034)
			(xy 430.538126 -273.829197) (xy 430.576247 -273.798072) (xy 430.618868 -273.773465) (xy 430.664884 -273.756013)
			(xy 430.713103 -273.746169) (xy 430.762278 -273.744188) (xy 430.811133 -273.75012) (xy 430.858404 -273.763812)
			(xy 430.902866 -273.78491) (xy 430.943369 -273.812866) (xy 430.978862 -273.846958) (xy 431.008427 -273.886302)
			(xy 431.031298 -273.929879) (xy 431.046882 -273.97656) (xy 431.054777 -274.025137) (xy 431.055272 -274.049744)
			(xy 431.054777 -274.074351) (xy 431.046882 -274.122928) (xy 431.031298 -274.169609) (xy 431.008427 -274.213186)
			(xy 430.978862 -274.25253) (xy 430.943369 -274.286622) (xy 430.902866 -274.314578) (xy 430.858404 -274.335676)
			(xy 430.811133 -274.349368) (xy 430.762278 -274.3553) (xy 430.713103 -274.353319) (xy 430.664884 -274.343475)
			(xy 430.618868 -274.326023) (xy 430.576247 -274.301416) (xy 430.538126 -274.270291) (xy 430.505491 -274.233454)
			(xy 430.479188 -274.191858) (xy 430.459897 -274.146582) (xy 430.44812 -274.098798) (xy 430.44416 -274.049744)
			(xy 430.105312 -274.049744) (xy 430.104817 -274.074351) (xy 430.096922 -274.122928) (xy 430.081338 -274.169609)
			(xy 430.058467 -274.213186) (xy 430.028902 -274.25253) (xy 429.993409 -274.286622) (xy 429.952906 -274.314578)
			(xy 429.908444 -274.335676) (xy 429.861173 -274.349368) (xy 429.812318 -274.3553) (xy 429.763143 -274.353319)
			(xy 429.714924 -274.343475) (xy 429.668908 -274.326023) (xy 429.626287 -274.301416) (xy 429.588166 -274.270291)
			(xy 429.555531 -274.233454) (xy 429.529228 -274.191858) (xy 429.509937 -274.146582) (xy 429.49816 -274.098798)
			(xy 429.4942 -274.049744) (xy 429.176688 -274.049744) (xy 429.176184 -274.075452) (xy 429.168141 -274.126234)
			(xy 429.152253 -274.175133) (xy 429.12891 -274.220945) (xy 429.098689 -274.262541) (xy 429.062333 -274.298897)
			(xy 429.020737 -274.329118) (xy 428.974925 -274.352461) (xy 428.926026 -274.368349) (xy 428.875244 -274.376392)
			(xy 428.823828 -274.376392) (xy 428.773046 -274.368349) (xy 428.724147 -274.352461) (xy 428.678335 -274.329118)
			(xy 428.636739 -274.298897) (xy 428.600383 -274.262541) (xy 428.570162 -274.220945) (xy 428.546819 -274.175133)
			(xy 428.530931 -274.126234) (xy 428.522888 -274.075452) (xy 428.204718 -274.075452) (xy 428.197002 -274.122928)
			(xy 428.181418 -274.169609) (xy 428.158547 -274.213186) (xy 428.128982 -274.25253) (xy 428.093489 -274.286622)
			(xy 428.052986 -274.314578) (xy 428.008524 -274.335676) (xy 427.961253 -274.349368) (xy 427.912398 -274.3553)
			(xy 427.863223 -274.353319) (xy 427.815004 -274.343475) (xy 427.768988 -274.326023) (xy 427.726367 -274.301416)
			(xy 427.688246 -274.270291) (xy 427.655611 -274.233454) (xy 427.629308 -274.191858) (xy 427.610017 -274.146582)
			(xy 427.59824 -274.098798) (xy 427.59428 -274.049744) (xy 427.276768 -274.049744) (xy 427.276264 -274.075452)
			(xy 427.268221 -274.126234) (xy 427.252333 -274.175133) (xy 427.22899 -274.220945) (xy 427.198769 -274.262541)
			(xy 427.162413 -274.298897) (xy 427.120817 -274.329118) (xy 427.075005 -274.352461) (xy 427.026106 -274.368349)
			(xy 426.975324 -274.376392) (xy 426.923908 -274.376392) (xy 426.873126 -274.368349) (xy 426.824227 -274.352461)
			(xy 426.778415 -274.329118) (xy 426.736819 -274.298897) (xy 426.700463 -274.262541) (xy 426.670242 -274.220945)
			(xy 426.646899 -274.175133) (xy 426.631011 -274.126234) (xy 426.622968 -274.075452) (xy 426.304798 -274.075452)
			(xy 426.297082 -274.122928) (xy 426.281498 -274.169609) (xy 426.258627 -274.213186) (xy 426.229062 -274.25253)
			(xy 426.193569 -274.286622) (xy 426.153066 -274.314578) (xy 426.108604 -274.335676) (xy 426.061333 -274.349368)
			(xy 426.012478 -274.3553) (xy 425.963303 -274.353319) (xy 425.915084 -274.343475) (xy 425.869068 -274.326023)
			(xy 425.826447 -274.301416) (xy 425.788326 -274.270291) (xy 425.755691 -274.233454) (xy 425.729388 -274.191858)
			(xy 425.710097 -274.146582) (xy 425.69832 -274.098798) (xy 425.69436 -274.049744) (xy 425.376848 -274.049744)
			(xy 425.376344 -274.075452) (xy 425.368301 -274.126234) (xy 425.352413 -274.175133) (xy 425.32907 -274.220945)
			(xy 425.298849 -274.262541) (xy 425.262493 -274.298897) (xy 425.220897 -274.329118) (xy 425.175085 -274.352461)
			(xy 425.126186 -274.368349) (xy 425.075404 -274.376392) (xy 425.023988 -274.376392) (xy 424.973206 -274.368349)
			(xy 424.924307 -274.352461) (xy 424.878495 -274.329118) (xy 424.836899 -274.298897) (xy 424.800543 -274.262541)
			(xy 424.770322 -274.220945) (xy 424.746979 -274.175133) (xy 424.731091 -274.126234) (xy 424.723048 -274.075452)
			(xy 424.404878 -274.075452) (xy 424.397162 -274.122928) (xy 424.381578 -274.169609) (xy 424.358707 -274.213186)
			(xy 424.329142 -274.25253) (xy 424.293649 -274.286622) (xy 424.253146 -274.314578) (xy 424.208684 -274.335676)
			(xy 424.161413 -274.349368) (xy 424.112558 -274.3553) (xy 424.063383 -274.353319) (xy 424.015164 -274.343475)
			(xy 423.969148 -274.326023) (xy 423.926527 -274.301416) (xy 423.888406 -274.270291) (xy 423.855771 -274.233454)
			(xy 423.829468 -274.191858) (xy 423.810177 -274.146582) (xy 423.7984 -274.098798) (xy 423.79444 -274.049744)
			(xy 423.476928 -274.049744) (xy 423.476424 -274.075452) (xy 423.468381 -274.126234) (xy 423.452493 -274.175133)
			(xy 423.42915 -274.220945) (xy 423.398929 -274.262541) (xy 423.362573 -274.298897) (xy 423.320977 -274.329118)
			(xy 423.275165 -274.352461) (xy 423.226266 -274.368349) (xy 423.175484 -274.376392) (xy 423.124068 -274.376392)
			(xy 423.073286 -274.368349) (xy 423.024387 -274.352461) (xy 422.978575 -274.329118) (xy 422.936979 -274.298897)
			(xy 422.900623 -274.262541) (xy 422.870402 -274.220945) (xy 422.847059 -274.175133) (xy 422.831171 -274.126234)
			(xy 422.823128 -274.075452) (xy 422.50445 -274.075452) (xy 422.496734 -274.122928) (xy 422.48115 -274.169609)
			(xy 422.458279 -274.213186) (xy 422.428714 -274.25253) (xy 422.393221 -274.286622) (xy 422.352718 -274.314578)
			(xy 422.308256 -274.335676) (xy 422.260985 -274.349368) (xy 422.21213 -274.3553) (xy 422.162955 -274.353319)
			(xy 422.114736 -274.343475) (xy 422.06872 -274.326023) (xy 422.026099 -274.301416) (xy 421.987978 -274.270291)
			(xy 421.955343 -274.233454) (xy 421.92904 -274.191858) (xy 421.909749 -274.146582) (xy 421.897972 -274.098798)
			(xy 421.894012 -274.049744) (xy 421.576754 -274.049744) (xy 421.57625 -274.075452) (xy 421.568207 -274.126234)
			(xy 421.552319 -274.175133) (xy 421.528976 -274.220945) (xy 421.498755 -274.262541) (xy 421.462399 -274.298897)
			(xy 421.420803 -274.329118) (xy 421.374991 -274.352461) (xy 421.326092 -274.368349) (xy 421.27531 -274.376392)
			(xy 421.223894 -274.376392) (xy 421.173112 -274.368349) (xy 421.124213 -274.352461) (xy 421.078401 -274.329118)
			(xy 421.036805 -274.298897) (xy 421.000449 -274.262541) (xy 420.970228 -274.220945) (xy 420.946885 -274.175133)
			(xy 420.930997 -274.126234) (xy 420.922954 -274.075452) (xy 420.60453 -274.075452) (xy 420.596814 -274.122928)
			(xy 420.58123 -274.169609) (xy 420.558359 -274.213186) (xy 420.528794 -274.25253) (xy 420.493301 -274.286622)
			(xy 420.452798 -274.314578) (xy 420.408336 -274.335676) (xy 420.361065 -274.349368) (xy 420.31221 -274.3553)
			(xy 420.263035 -274.353319) (xy 420.214816 -274.343475) (xy 420.1688 -274.326023) (xy 420.126179 -274.301416)
			(xy 420.088058 -274.270291) (xy 420.055423 -274.233454) (xy 420.02912 -274.191858) (xy 420.009829 -274.146582)
			(xy 419.998052 -274.098798) (xy 419.994092 -274.049744) (xy 419.676834 -274.049744) (xy 419.67633 -274.075452)
			(xy 419.668287 -274.126234) (xy 419.652399 -274.175133) (xy 419.629056 -274.220945) (xy 419.598835 -274.262541)
			(xy 419.562479 -274.298897) (xy 419.520883 -274.329118) (xy 419.475071 -274.352461) (xy 419.426172 -274.368349)
			(xy 419.37539 -274.376392) (xy 419.323974 -274.376392) (xy 419.273192 -274.368349) (xy 419.224293 -274.352461)
			(xy 419.178481 -274.329118) (xy 419.136885 -274.298897) (xy 419.100529 -274.262541) (xy 419.070308 -274.220945)
			(xy 419.046965 -274.175133) (xy 419.031077 -274.126234) (xy 419.023034 -274.075452) (xy 418.70461 -274.075452)
			(xy 418.696894 -274.122928) (xy 418.68131 -274.169609) (xy 418.658439 -274.213186) (xy 418.628874 -274.25253)
			(xy 418.593381 -274.286622) (xy 418.552878 -274.314578) (xy 418.508416 -274.335676) (xy 418.461145 -274.349368)
			(xy 418.41229 -274.3553) (xy 418.363115 -274.353319) (xy 418.314896 -274.343475) (xy 418.26888 -274.326023)
			(xy 418.226259 -274.301416) (xy 418.188138 -274.270291) (xy 418.155503 -274.233454) (xy 418.1292 -274.191858)
			(xy 418.109909 -274.146582) (xy 418.098132 -274.098798) (xy 418.094172 -274.049744) (xy 417.776914 -274.049744)
			(xy 417.77641 -274.075452) (xy 417.768367 -274.126234) (xy 417.752479 -274.175133) (xy 417.729136 -274.220945)
			(xy 417.698915 -274.262541) (xy 417.662559 -274.298897) (xy 417.620963 -274.329118) (xy 417.575151 -274.352461)
			(xy 417.526252 -274.368349) (xy 417.47547 -274.376392) (xy 417.424054 -274.376392) (xy 417.373272 -274.368349)
			(xy 417.324373 -274.352461) (xy 417.278561 -274.329118) (xy 417.236965 -274.298897) (xy 417.200609 -274.262541)
			(xy 417.170388 -274.220945) (xy 417.147045 -274.175133) (xy 417.131157 -274.126234) (xy 417.123114 -274.075452)
			(xy 416.804436 -274.075452) (xy 416.79672 -274.122928) (xy 416.781136 -274.169609) (xy 416.758265 -274.213186)
			(xy 416.7287 -274.25253) (xy 416.693207 -274.286622) (xy 416.652704 -274.314578) (xy 416.608242 -274.335676)
			(xy 416.560971 -274.349368) (xy 416.512116 -274.3553) (xy 416.462941 -274.353319) (xy 416.414722 -274.343475)
			(xy 416.368706 -274.326023) (xy 416.326085 -274.301416) (xy 416.287964 -274.270291) (xy 416.255329 -274.233454)
			(xy 416.229026 -274.191858) (xy 416.209735 -274.146582) (xy 416.197958 -274.098798) (xy 416.193998 -274.049744)
			(xy 415.87674 -274.049744) (xy 415.876236 -274.075452) (xy 415.868193 -274.126234) (xy 415.852305 -274.175133)
			(xy 415.828962 -274.220945) (xy 415.798741 -274.262541) (xy 415.762385 -274.298897) (xy 415.720789 -274.329118)
			(xy 415.674977 -274.352461) (xy 415.626078 -274.368349) (xy 415.575296 -274.376392) (xy 415.52388 -274.376392)
			(xy 415.473098 -274.368349) (xy 415.424199 -274.352461) (xy 415.378387 -274.329118) (xy 415.336791 -274.298897)
			(xy 415.300435 -274.262541) (xy 415.270214 -274.220945) (xy 415.246871 -274.175133) (xy 415.230983 -274.126234)
			(xy 415.22294 -274.075452) (xy 414.904516 -274.075452) (xy 414.8968 -274.122928) (xy 414.881216 -274.169609)
			(xy 414.858345 -274.213186) (xy 414.82878 -274.25253) (xy 414.793287 -274.286622) (xy 414.752784 -274.314578)
			(xy 414.708322 -274.335676) (xy 414.661051 -274.349368) (xy 414.612196 -274.3553) (xy 414.563021 -274.353319)
			(xy 414.514802 -274.343475) (xy 414.468786 -274.326023) (xy 414.426165 -274.301416) (xy 414.388044 -274.270291)
			(xy 414.355409 -274.233454) (xy 414.329106 -274.191858) (xy 414.309815 -274.146582) (xy 414.298038 -274.098798)
			(xy 414.294078 -274.049744) (xy 413.97682 -274.049744) (xy 413.976316 -274.075452) (xy 413.968273 -274.126234)
			(xy 413.952385 -274.175133) (xy 413.929042 -274.220945) (xy 413.898821 -274.262541) (xy 413.862465 -274.298897)
			(xy 413.820869 -274.329118) (xy 413.775057 -274.352461) (xy 413.726158 -274.368349) (xy 413.675376 -274.376392)
			(xy 413.62396 -274.376392) (xy 413.573178 -274.368349) (xy 413.524279 -274.352461) (xy 413.478467 -274.329118)
			(xy 413.436871 -274.298897) (xy 413.400515 -274.262541) (xy 413.370294 -274.220945) (xy 413.346951 -274.175133)
			(xy 413.331063 -274.126234) (xy 413.32302 -274.075452) (xy 413.004596 -274.075452) (xy 412.99688 -274.122928)
			(xy 412.981296 -274.169609) (xy 412.958425 -274.213186) (xy 412.92886 -274.25253) (xy 412.893367 -274.286622)
			(xy 412.852864 -274.314578) (xy 412.808402 -274.335676) (xy 412.761131 -274.349368) (xy 412.712276 -274.3553)
			(xy 412.663101 -274.353319) (xy 412.614882 -274.343475) (xy 412.568866 -274.326023) (xy 412.526245 -274.301416)
			(xy 412.488124 -274.270291) (xy 412.455489 -274.233454) (xy 412.429186 -274.191858) (xy 412.409895 -274.146582)
			(xy 412.398118 -274.098798) (xy 412.394158 -274.049744) (xy 412.0769 -274.049744) (xy 412.076396 -274.075452)
			(xy 412.068353 -274.126234) (xy 412.052465 -274.175133) (xy 412.029122 -274.220945) (xy 411.998901 -274.262541)
			(xy 411.962545 -274.298897) (xy 411.920949 -274.329118) (xy 411.875137 -274.352461) (xy 411.826238 -274.368349)
			(xy 411.775456 -274.376392) (xy 411.72404 -274.376392) (xy 411.673258 -274.368349) (xy 411.624359 -274.352461)
			(xy 411.578547 -274.329118) (xy 411.536951 -274.298897) (xy 411.500595 -274.262541) (xy 411.470374 -274.220945)
			(xy 411.447031 -274.175133) (xy 411.431143 -274.126234) (xy 411.4231 -274.075452) (xy 411.104422 -274.075452)
			(xy 411.096706 -274.122928) (xy 411.081122 -274.169609) (xy 411.058251 -274.213186) (xy 411.028686 -274.25253)
			(xy 410.993193 -274.286622) (xy 410.95269 -274.314578) (xy 410.908228 -274.335676) (xy 410.860957 -274.349368)
			(xy 410.812102 -274.3553) (xy 410.762927 -274.353319) (xy 410.714708 -274.343475) (xy 410.668692 -274.326023)
			(xy 410.626071 -274.301416) (xy 410.58795 -274.270291) (xy 410.555315 -274.233454) (xy 410.529012 -274.191858)
			(xy 410.509721 -274.146582) (xy 410.497944 -274.098798) (xy 410.493984 -274.049744) (xy 410.176726 -274.049744)
			(xy 410.176222 -274.075452) (xy 410.168179 -274.126234) (xy 410.152291 -274.175133) (xy 410.128948 -274.220945)
			(xy 410.098727 -274.262541) (xy 410.062371 -274.298897) (xy 410.020775 -274.329118) (xy 409.974963 -274.352461)
			(xy 409.926064 -274.368349) (xy 409.875282 -274.376392) (xy 409.823866 -274.376392) (xy 409.773084 -274.368349)
			(xy 409.724185 -274.352461) (xy 409.678373 -274.329118) (xy 409.636777 -274.298897) (xy 409.600421 -274.262541)
			(xy 409.5702 -274.220945) (xy 409.546857 -274.175133) (xy 409.530969 -274.126234) (xy 409.522926 -274.075452)
			(xy 409.204502 -274.075452) (xy 409.196786 -274.122928) (xy 409.181202 -274.169609) (xy 409.158331 -274.213186)
			(xy 409.128766 -274.25253) (xy 409.093273 -274.286622) (xy 409.05277 -274.314578) (xy 409.008308 -274.335676)
			(xy 408.961037 -274.349368) (xy 408.912182 -274.3553) (xy 408.863007 -274.353319) (xy 408.814788 -274.343475)
			(xy 408.768772 -274.326023) (xy 408.726151 -274.301416) (xy 408.68803 -274.270291) (xy 408.655395 -274.233454)
			(xy 408.629092 -274.191858) (xy 408.609801 -274.146582) (xy 408.598024 -274.098798) (xy 408.594064 -274.049744)
			(xy 408.276801 -274.049744) (xy 408.276302 -274.075198) (xy 408.268259 -274.12598) (xy 408.252371 -274.174879)
			(xy 408.229028 -274.220691) (xy 408.198807 -274.262287) (xy 408.162451 -274.298643) (xy 408.120855 -274.328864)
			(xy 408.075043 -274.352207) (xy 408.026144 -274.368095) (xy 407.975362 -274.376138) (xy 407.923946 -274.376138)
			(xy 407.873164 -274.368095) (xy 407.824265 -274.352207) (xy 407.778453 -274.328864) (xy 407.736857 -274.298643)
			(xy 407.700501 -274.262287) (xy 407.67028 -274.220691) (xy 407.646937 -274.174879) (xy 407.631049 -274.12598)
			(xy 407.623006 -274.075198) (xy 407.304623 -274.075198) (xy 407.296866 -274.122928) (xy 407.281282 -274.169609)
			(xy 407.258411 -274.213186) (xy 407.228846 -274.25253) (xy 407.193353 -274.286622) (xy 407.15285 -274.314578)
			(xy 407.108388 -274.335676) (xy 407.061117 -274.349368) (xy 407.012262 -274.3553) (xy 406.963087 -274.353319)
			(xy 406.914868 -274.343475) (xy 406.868852 -274.326023) (xy 406.826231 -274.301416) (xy 406.78811 -274.270291)
			(xy 406.755475 -274.233454) (xy 406.729172 -274.191858) (xy 406.709881 -274.146582) (xy 406.698104 -274.098798)
			(xy 406.694144 -274.049744) (xy 406.37714 -274.049744) (xy 406.376636 -274.075452) (xy 406.368593 -274.126234)
			(xy 406.352705 -274.175133) (xy 406.329362 -274.220945) (xy 406.299141 -274.262541) (xy 406.262785 -274.298897)
			(xy 406.221189 -274.329118) (xy 406.175377 -274.352461) (xy 406.126478 -274.368349) (xy 406.075696 -274.376392)
			(xy 406.02428 -274.376392) (xy 405.973498 -274.368349) (xy 405.924599 -274.352461) (xy 405.878787 -274.329118)
			(xy 405.837191 -274.298897) (xy 405.800835 -274.262541) (xy 405.770614 -274.220945) (xy 405.747271 -274.175133)
			(xy 405.731383 -274.126234) (xy 405.72334 -274.075452) (xy 405.404662 -274.075452) (xy 405.396946 -274.122928)
			(xy 405.381362 -274.169609) (xy 405.358491 -274.213186) (xy 405.328926 -274.25253) (xy 405.293433 -274.286622)
			(xy 405.25293 -274.314578) (xy 405.208468 -274.335676) (xy 405.161197 -274.349368) (xy 405.112342 -274.3553)
			(xy 405.063167 -274.353319) (xy 405.014948 -274.343475) (xy 404.968932 -274.326023) (xy 404.926311 -274.301416)
			(xy 404.88819 -274.270291) (xy 404.855555 -274.233454) (xy 404.829252 -274.191858) (xy 404.809961 -274.146582)
			(xy 404.798184 -274.098798) (xy 404.794224 -274.049744) (xy 404.476966 -274.049744) (xy 404.476462 -274.075452)
			(xy 404.468419 -274.126234) (xy 404.452531 -274.175133) (xy 404.429188 -274.220945) (xy 404.398967 -274.262541)
			(xy 404.362611 -274.298897) (xy 404.321015 -274.329118) (xy 404.275203 -274.352461) (xy 404.226304 -274.368349)
			(xy 404.175522 -274.376392) (xy 404.124106 -274.376392) (xy 404.073324 -274.368349) (xy 404.024425 -274.352461)
			(xy 403.978613 -274.329118) (xy 403.937017 -274.298897) (xy 403.900661 -274.262541) (xy 403.87044 -274.220945)
			(xy 403.847097 -274.175133) (xy 403.831209 -274.126234) (xy 403.823166 -274.075452) (xy 403.504488 -274.075452)
			(xy 403.496772 -274.122928) (xy 403.481188 -274.169609) (xy 403.458317 -274.213186) (xy 403.428752 -274.25253)
			(xy 403.393259 -274.286622) (xy 403.352756 -274.314578) (xy 403.308294 -274.335676) (xy 403.261023 -274.349368)
			(xy 403.212168 -274.3553) (xy 403.162993 -274.353319) (xy 403.114774 -274.343475) (xy 403.068758 -274.326023)
			(xy 403.026137 -274.301416) (xy 402.988016 -274.270291) (xy 402.955381 -274.233454) (xy 402.929078 -274.191858)
			(xy 402.909787 -274.146582) (xy 402.89801 -274.098798) (xy 402.89405 -274.049744) (xy 402.577046 -274.049744)
			(xy 402.576542 -274.075452) (xy 402.568499 -274.126234) (xy 402.552611 -274.175133) (xy 402.529268 -274.220945)
			(xy 402.499047 -274.262541) (xy 402.462691 -274.298897) (xy 402.421095 -274.329118) (xy 402.375283 -274.352461)
			(xy 402.326384 -274.368349) (xy 402.275602 -274.376392) (xy 402.224186 -274.376392) (xy 402.173404 -274.368349)
			(xy 402.124505 -274.352461) (xy 402.078693 -274.329118) (xy 402.037097 -274.298897) (xy 402.000741 -274.262541)
			(xy 401.97052 -274.220945) (xy 401.947177 -274.175133) (xy 401.931289 -274.126234) (xy 401.923246 -274.075452)
			(xy 401.604568 -274.075452) (xy 401.596852 -274.122928) (xy 401.581268 -274.169609) (xy 401.558397 -274.213186)
			(xy 401.528832 -274.25253) (xy 401.493339 -274.286622) (xy 401.452836 -274.314578) (xy 401.408374 -274.335676)
			(xy 401.361103 -274.349368) (xy 401.312248 -274.3553) (xy 401.263073 -274.353319) (xy 401.214854 -274.343475)
			(xy 401.168838 -274.326023) (xy 401.126217 -274.301416) (xy 401.088096 -274.270291) (xy 401.055461 -274.233454)
			(xy 401.029158 -274.191858) (xy 401.009867 -274.146582) (xy 400.99809 -274.098798) (xy 400.99413 -274.049744)
			(xy 400.677126 -274.049744) (xy 400.676622 -274.075452) (xy 400.668579 -274.126234) (xy 400.652691 -274.175133)
			(xy 400.629348 -274.220945) (xy 400.599127 -274.262541) (xy 400.562771 -274.298897) (xy 400.521175 -274.329118)
			(xy 400.475363 -274.352461) (xy 400.426464 -274.368349) (xy 400.375682 -274.376392) (xy 400.324266 -274.376392)
			(xy 400.273484 -274.368349) (xy 400.224585 -274.352461) (xy 400.178773 -274.329118) (xy 400.137177 -274.298897)
			(xy 400.100821 -274.262541) (xy 400.0706 -274.220945) (xy 400.047257 -274.175133) (xy 400.031369 -274.126234)
			(xy 400.023326 -274.075452) (xy 399.704648 -274.075452) (xy 399.696932 -274.122928) (xy 399.681348 -274.169609)
			(xy 399.658477 -274.213186) (xy 399.628912 -274.25253) (xy 399.593419 -274.286622) (xy 399.552916 -274.314578)
			(xy 399.508454 -274.335676) (xy 399.461183 -274.349368) (xy 399.412328 -274.3553) (xy 399.363153 -274.353319)
			(xy 399.314934 -274.343475) (xy 399.268918 -274.326023) (xy 399.226297 -274.301416) (xy 399.188176 -274.270291)
			(xy 399.155541 -274.233454) (xy 399.129238 -274.191858) (xy 399.109947 -274.146582) (xy 399.09817 -274.098798)
			(xy 399.09421 -274.049744) (xy 398.776404 -274.049744) (xy 398.776404 -274.075404) (xy 398.768362 -274.12618)
			(xy 398.752475 -274.175072) (xy 398.729136 -274.220878) (xy 398.698919 -274.262468) (xy 398.662568 -274.298819)
			(xy 398.620978 -274.329036) (xy 398.575172 -274.352375) (xy 398.52628 -274.368262) (xy 398.475504 -274.376304)
			(xy 398.4498 -274.376896) (xy 398.436076 -274.376705) (xy 398.408734 -274.374292) (xy 398.39519 -274.37207)
			(xy 398.383252 -274.370038) (xy 398.360392 -274.37715) (xy 398.283938 -274.45081) (xy 398.276064 -274.473416)
			(xy 398.277588 -274.485608) (xy 398.278785 -274.495406) (xy 398.280057 -274.515107) (xy 398.280128 -274.524978)
			(xy 398.279942 -274.539161) (xy 398.277271 -274.5674) (xy 398.274794 -274.581366) (xy 398.272508 -274.593812)
			(xy 398.279874 -274.617434) (xy 398.357344 -274.694904) (xy 398.380966 -274.70227) (xy 398.393412 -274.699984)
			(xy 398.407377 -274.697499) (xy 398.435617 -274.694827) (xy 398.4498 -274.69465) (xy 398.475059 -274.695172)
			(xy 398.524887 -274.703487) (xy 398.572668 -274.71989) (xy 398.617097 -274.743933) (xy 398.656962 -274.774962)
			(xy 398.691177 -274.812129) (xy 398.718807 -274.854421) (xy 398.7391 -274.900683) (xy 398.751501 -274.949655)
			(xy 398.755673 -275) (xy 398.753546 -275.025666) (xy 399.073366 -275.025666) (xy 399.073366 -274.97425)
			(xy 399.081409 -274.923468) (xy 399.097297 -274.874569) (xy 399.12064 -274.828757) (xy 399.150861 -274.787161)
			(xy 399.187217 -274.750805) (xy 399.228813 -274.720584) (xy 399.274625 -274.697241) (xy 399.323524 -274.681353)
			(xy 399.374306 -274.67331) (xy 399.425722 -274.67331) (xy 399.476504 -274.681353) (xy 399.525403 -274.697241)
			(xy 399.571215 -274.720584) (xy 399.612811 -274.750805) (xy 399.649167 -274.787161) (xy 399.679388 -274.828757)
			(xy 399.702731 -274.874569) (xy 399.718619 -274.923468) (xy 399.726662 -274.97425) (xy 399.727166 -274.999958)
			(xy 400.04417 -274.999958) (xy 400.04813 -274.950904) (xy 400.059907 -274.90312) (xy 400.079198 -274.857844)
			(xy 400.105501 -274.816248) (xy 400.138136 -274.779411) (xy 400.176257 -274.748286) (xy 400.218878 -274.723679)
			(xy 400.264894 -274.706227) (xy 400.313113 -274.696383) (xy 400.362288 -274.694402) (xy 400.411143 -274.700334)
			(xy 400.458414 -274.714026) (xy 400.502876 -274.735124) (xy 400.543379 -274.76308) (xy 400.578872 -274.797172)
			(xy 400.608437 -274.836516) (xy 400.631308 -274.880093) (xy 400.646892 -274.926774) (xy 400.654787 -274.975351)
			(xy 400.655282 -274.999958) (xy 400.654787 -275.024565) (xy 400.654608 -275.025666) (xy 400.973286 -275.025666)
			(xy 400.973286 -274.97425) (xy 400.981329 -274.923468) (xy 400.997217 -274.874569) (xy 401.02056 -274.828757)
			(xy 401.050781 -274.787161) (xy 401.087137 -274.750805) (xy 401.128733 -274.720584) (xy 401.174545 -274.697241)
			(xy 401.223444 -274.681353) (xy 401.274226 -274.67331) (xy 401.325642 -274.67331) (xy 401.376424 -274.681353)
			(xy 401.425323 -274.697241) (xy 401.471135 -274.720584) (xy 401.512731 -274.750805) (xy 401.549087 -274.787161)
			(xy 401.579308 -274.828757) (xy 401.602651 -274.874569) (xy 401.618539 -274.923468) (xy 401.626582 -274.97425)
			(xy 401.627086 -274.999958) (xy 401.94409 -274.999958) (xy 401.94805 -274.950904) (xy 401.959827 -274.90312)
			(xy 401.979118 -274.857844) (xy 402.005421 -274.816248) (xy 402.038056 -274.779411) (xy 402.076177 -274.748286)
			(xy 402.118798 -274.723679) (xy 402.164814 -274.706227) (xy 402.213033 -274.696383) (xy 402.262208 -274.694402)
			(xy 402.311063 -274.700334) (xy 402.358334 -274.714026) (xy 402.402796 -274.735124) (xy 402.443299 -274.76308)
			(xy 402.478792 -274.797172) (xy 402.508357 -274.836516) (xy 402.531228 -274.880093) (xy 402.546812 -274.926774)
			(xy 402.554707 -274.975351) (xy 402.555202 -274.999958) (xy 402.554707 -275.024565) (xy 402.554528 -275.025666)
			(xy 402.873206 -275.025666) (xy 402.873206 -274.97425) (xy 402.881249 -274.923468) (xy 402.897137 -274.874569)
			(xy 402.92048 -274.828757) (xy 402.950701 -274.787161) (xy 402.987057 -274.750805) (xy 403.028653 -274.720584)
			(xy 403.074465 -274.697241) (xy 403.123364 -274.681353) (xy 403.174146 -274.67331) (xy 403.225562 -274.67331)
			(xy 403.276344 -274.681353) (xy 403.325243 -274.697241) (xy 403.371055 -274.720584) (xy 403.412651 -274.750805)
			(xy 403.449007 -274.787161) (xy 403.479228 -274.828757) (xy 403.502571 -274.874569) (xy 403.518459 -274.923468)
			(xy 403.526502 -274.97425) (xy 403.527006 -274.999958) (xy 403.84401 -274.999958) (xy 403.84797 -274.950904)
			(xy 403.859747 -274.90312) (xy 403.879038 -274.857844) (xy 403.905341 -274.816248) (xy 403.937976 -274.779411)
			(xy 403.976097 -274.748286) (xy 404.018718 -274.723679) (xy 404.064734 -274.706227) (xy 404.112953 -274.696383)
			(xy 404.162128 -274.694402) (xy 404.210983 -274.700334) (xy 404.258254 -274.714026) (xy 404.302716 -274.735124)
			(xy 404.343219 -274.76308) (xy 404.378712 -274.797172) (xy 404.408277 -274.836516) (xy 404.431148 -274.880093)
			(xy 404.446732 -274.926774) (xy 404.454627 -274.975351) (xy 404.455122 -274.999958) (xy 404.454627 -275.024565)
			(xy 404.454448 -275.025666) (xy 404.77338 -275.025666) (xy 404.77338 -274.97425) (xy 404.781423 -274.923468)
			(xy 404.797311 -274.874569) (xy 404.820654 -274.828757) (xy 404.850875 -274.787161) (xy 404.887231 -274.750805)
			(xy 404.928827 -274.720584) (xy 404.974639 -274.697241) (xy 405.023538 -274.681353) (xy 405.07432 -274.67331)
			(xy 405.125736 -274.67331) (xy 405.176518 -274.681353) (xy 405.225417 -274.697241) (xy 405.271229 -274.720584)
			(xy 405.312825 -274.750805) (xy 405.349181 -274.787161) (xy 405.379402 -274.828757) (xy 405.402745 -274.874569)
			(xy 405.418633 -274.923468) (xy 405.426676 -274.97425) (xy 405.42718 -274.999958) (xy 405.744184 -274.999958)
			(xy 405.748144 -274.950904) (xy 405.759921 -274.90312) (xy 405.779212 -274.857844) (xy 405.805515 -274.816248)
			(xy 405.83815 -274.779411) (xy 405.876271 -274.748286) (xy 405.918892 -274.723679) (xy 405.964908 -274.706227)
			(xy 406.013127 -274.696383) (xy 406.062302 -274.694402) (xy 406.111157 -274.700334) (xy 406.158428 -274.714026)
			(xy 406.20289 -274.735124) (xy 406.243393 -274.76308) (xy 406.278886 -274.797172) (xy 406.308451 -274.836516)
			(xy 406.331322 -274.880093) (xy 406.346906 -274.926774) (xy 406.354801 -274.975351) (xy 406.355296 -274.999958)
			(xy 406.354801 -275.024565) (xy 406.354622 -275.025666) (xy 406.6733 -275.025666) (xy 406.6733 -274.97425)
			(xy 406.681343 -274.923468) (xy 406.697231 -274.874569) (xy 406.720574 -274.828757) (xy 406.750795 -274.787161)
			(xy 406.787151 -274.750805) (xy 406.828747 -274.720584) (xy 406.874559 -274.697241) (xy 406.923458 -274.681353)
			(xy 406.97424 -274.67331) (xy 407.025656 -274.67331) (xy 407.076438 -274.681353) (xy 407.125337 -274.697241)
			(xy 407.171149 -274.720584) (xy 407.212745 -274.750805) (xy 407.249101 -274.787161) (xy 407.279322 -274.828757)
			(xy 407.302665 -274.874569) (xy 407.318553 -274.923468) (xy 407.326596 -274.97425) (xy 407.3271 -274.999958)
			(xy 407.644104 -274.999958) (xy 407.648064 -274.950904) (xy 407.659841 -274.90312) (xy 407.679132 -274.857844)
			(xy 407.705435 -274.816248) (xy 407.73807 -274.779411) (xy 407.776191 -274.748286) (xy 407.818812 -274.723679)
			(xy 407.864828 -274.706227) (xy 407.913047 -274.696383) (xy 407.962222 -274.694402) (xy 408.011077 -274.700334)
			(xy 408.058348 -274.714026) (xy 408.10281 -274.735124) (xy 408.143313 -274.76308) (xy 408.178806 -274.797172)
			(xy 408.208371 -274.836516) (xy 408.231242 -274.880093) (xy 408.246826 -274.926774) (xy 408.254721 -274.975351)
			(xy 408.255216 -274.999958) (xy 408.254721 -275.024565) (xy 408.254583 -275.025412) (xy 408.572966 -275.025412)
			(xy 408.572966 -274.973996) (xy 408.581009 -274.923214) (xy 408.596897 -274.874315) (xy 408.62024 -274.828503)
			(xy 408.650461 -274.786907) (xy 408.686817 -274.750551) (xy 408.728413 -274.72033) (xy 408.774225 -274.696987)
			(xy 408.823124 -274.681099) (xy 408.873906 -274.673056) (xy 408.925322 -274.673056) (xy 408.976104 -274.681099)
			(xy 409.025003 -274.696987) (xy 409.070815 -274.72033) (xy 409.112411 -274.750551) (xy 409.148767 -274.786907)
			(xy 409.178988 -274.828503) (xy 409.202331 -274.874315) (xy 409.218219 -274.923214) (xy 409.226262 -274.973996)
			(xy 409.226766 -274.999704) (xy 409.226761 -274.999958) (xy 409.544024 -274.999958) (xy 409.547984 -274.950904)
			(xy 409.559761 -274.90312) (xy 409.579052 -274.857844) (xy 409.605355 -274.816248) (xy 409.63799 -274.779411)
			(xy 409.676111 -274.748286) (xy 409.718732 -274.723679) (xy 409.764748 -274.706227) (xy 409.812967 -274.696383)
			(xy 409.862142 -274.694402) (xy 409.910997 -274.700334) (xy 409.958268 -274.714026) (xy 410.00273 -274.735124)
			(xy 410.043233 -274.76308) (xy 410.078726 -274.797172) (xy 410.108291 -274.836516) (xy 410.131162 -274.880093)
			(xy 410.146746 -274.926774) (xy 410.154641 -274.975351) (xy 410.155136 -274.999958) (xy 410.154641 -275.024565)
			(xy 410.154462 -275.025666) (xy 410.472886 -275.025666) (xy 410.472886 -274.97425) (xy 410.480929 -274.923468)
			(xy 410.496817 -274.874569) (xy 410.52016 -274.828757) (xy 410.550381 -274.787161) (xy 410.586737 -274.750805)
			(xy 410.628333 -274.720584) (xy 410.674145 -274.697241) (xy 410.723044 -274.681353) (xy 410.773826 -274.67331)
			(xy 410.825242 -274.67331) (xy 410.876024 -274.681353) (xy 410.924923 -274.697241) (xy 410.970735 -274.720584)
			(xy 411.012331 -274.750805) (xy 411.048687 -274.787161) (xy 411.078908 -274.828757) (xy 411.102251 -274.874569)
			(xy 411.118139 -274.923468) (xy 411.126182 -274.97425) (xy 411.126686 -274.999958) (xy 411.444198 -274.999958)
			(xy 411.448158 -274.950904) (xy 411.459935 -274.90312) (xy 411.479226 -274.857844) (xy 411.505529 -274.816248)
			(xy 411.538164 -274.779411) (xy 411.576285 -274.748286) (xy 411.618906 -274.723679) (xy 411.664922 -274.706227)
			(xy 411.713141 -274.696383) (xy 411.762316 -274.694402) (xy 411.811171 -274.700334) (xy 411.858442 -274.714026)
			(xy 411.902904 -274.735124) (xy 411.943407 -274.76308) (xy 411.9789 -274.797172) (xy 412.008465 -274.836516)
			(xy 412.031336 -274.880093) (xy 412.04692 -274.926774) (xy 412.054815 -274.975351) (xy 412.05531 -274.999958)
			(xy 412.054815 -275.024565) (xy 412.054677 -275.025412) (xy 412.37306 -275.025412) (xy 412.37306 -274.973996)
			(xy 412.381103 -274.923214) (xy 412.396991 -274.874315) (xy 412.420334 -274.828503) (xy 412.450555 -274.786907)
			(xy 412.486911 -274.750551) (xy 412.528507 -274.72033) (xy 412.574319 -274.696987) (xy 412.623218 -274.681099)
			(xy 412.674 -274.673056) (xy 412.725416 -274.673056) (xy 412.776198 -274.681099) (xy 412.825097 -274.696987)
			(xy 412.870909 -274.72033) (xy 412.912505 -274.750551) (xy 412.948861 -274.786907) (xy 412.979082 -274.828503)
			(xy 413.002425 -274.874315) (xy 413.018313 -274.923214) (xy 413.026356 -274.973996) (xy 413.02686 -274.999704)
			(xy 413.026855 -274.999958) (xy 413.344118 -274.999958) (xy 413.348078 -274.950904) (xy 413.359855 -274.90312)
			(xy 413.379146 -274.857844) (xy 413.405449 -274.816248) (xy 413.438084 -274.779411) (xy 413.476205 -274.748286)
			(xy 413.518826 -274.723679) (xy 413.564842 -274.706227) (xy 413.613061 -274.696383) (xy 413.662236 -274.694402)
			(xy 413.711091 -274.700334) (xy 413.758362 -274.714026) (xy 413.802824 -274.735124) (xy 413.843327 -274.76308)
			(xy 413.87882 -274.797172) (xy 413.908385 -274.836516) (xy 413.931256 -274.880093) (xy 413.94684 -274.926774)
			(xy 413.954735 -274.975351) (xy 413.95523 -274.999958) (xy 413.954735 -275.024565) (xy 413.954556 -275.025666)
			(xy 414.27298 -275.025666) (xy 414.27298 -274.97425) (xy 414.281023 -274.923468) (xy 414.296911 -274.874569)
			(xy 414.320254 -274.828757) (xy 414.350475 -274.787161) (xy 414.386831 -274.750805) (xy 414.428427 -274.720584)
			(xy 414.474239 -274.697241) (xy 414.523138 -274.681353) (xy 414.57392 -274.67331) (xy 414.625336 -274.67331)
			(xy 414.676118 -274.681353) (xy 414.725017 -274.697241) (xy 414.770829 -274.720584) (xy 414.812425 -274.750805)
			(xy 414.848781 -274.787161) (xy 414.879002 -274.828757) (xy 414.902345 -274.874569) (xy 414.918233 -274.923468)
			(xy 414.926276 -274.97425) (xy 414.92678 -274.999958) (xy 415.244038 -274.999958) (xy 415.247998 -274.950904)
			(xy 415.259775 -274.90312) (xy 415.279066 -274.857844) (xy 415.305369 -274.816248) (xy 415.338004 -274.779411)
			(xy 415.376125 -274.748286) (xy 415.418746 -274.723679) (xy 415.464762 -274.706227) (xy 415.512981 -274.696383)
			(xy 415.562156 -274.694402) (xy 415.611011 -274.700334) (xy 415.658282 -274.714026) (xy 415.702744 -274.735124)
			(xy 415.743247 -274.76308) (xy 415.77874 -274.797172) (xy 415.808305 -274.836516) (xy 415.831176 -274.880093)
			(xy 415.84676 -274.926774) (xy 415.854655 -274.975351) (xy 415.85515 -274.999958) (xy 415.854655 -275.024565)
			(xy 415.854517 -275.025412) (xy 416.1729 -275.025412) (xy 416.1729 -274.973996) (xy 416.180943 -274.923214)
			(xy 416.196831 -274.874315) (xy 416.220174 -274.828503) (xy 416.250395 -274.786907) (xy 416.286751 -274.750551)
			(xy 416.328347 -274.72033) (xy 416.374159 -274.696987) (xy 416.423058 -274.681099) (xy 416.47384 -274.673056)
			(xy 416.525256 -274.673056) (xy 416.576038 -274.681099) (xy 416.624937 -274.696987) (xy 416.670749 -274.72033)
			(xy 416.712345 -274.750551) (xy 416.748701 -274.786907) (xy 416.778922 -274.828503) (xy 416.802265 -274.874315)
			(xy 416.818153 -274.923214) (xy 416.826196 -274.973996) (xy 416.8267 -274.999704) (xy 416.826695 -274.999958)
			(xy 417.144212 -274.999958) (xy 417.148172 -274.950904) (xy 417.159949 -274.90312) (xy 417.17924 -274.857844)
			(xy 417.205543 -274.816248) (xy 417.238178 -274.779411) (xy 417.276299 -274.748286) (xy 417.31892 -274.723679)
			(xy 417.364936 -274.706227) (xy 417.413155 -274.696383) (xy 417.46233 -274.694402) (xy 417.511185 -274.700334)
			(xy 417.558456 -274.714026) (xy 417.602918 -274.735124) (xy 417.643421 -274.76308) (xy 417.678914 -274.797172)
			(xy 417.708479 -274.836516) (xy 417.73135 -274.880093) (xy 417.746934 -274.926774) (xy 417.754829 -274.975351)
			(xy 417.755324 -274.999958) (xy 417.754829 -275.024565) (xy 417.75465 -275.025666) (xy 418.07282 -275.025666)
			(xy 418.07282 -274.97425) (xy 418.080863 -274.923468) (xy 418.096751 -274.874569) (xy 418.120094 -274.828757)
			(xy 418.150315 -274.787161) (xy 418.186671 -274.750805) (xy 418.228267 -274.720584) (xy 418.274079 -274.697241)
			(xy 418.322978 -274.681353) (xy 418.37376 -274.67331) (xy 418.425176 -274.67331) (xy 418.475958 -274.681353)
			(xy 418.524857 -274.697241) (xy 418.570669 -274.720584) (xy 418.612265 -274.750805) (xy 418.648621 -274.787161)
			(xy 418.678842 -274.828757) (xy 418.702185 -274.874569) (xy 418.718073 -274.923468) (xy 418.726116 -274.97425)
			(xy 418.72662 -274.999958) (xy 419.044132 -274.999958) (xy 419.048092 -274.950904) (xy 419.059869 -274.90312)
			(xy 419.07916 -274.857844) (xy 419.105463 -274.816248) (xy 419.138098 -274.779411) (xy 419.176219 -274.748286)
			(xy 419.21884 -274.723679) (xy 419.264856 -274.706227) (xy 419.313075 -274.696383) (xy 419.36225 -274.694402)
			(xy 419.411105 -274.700334) (xy 419.458376 -274.714026) (xy 419.502838 -274.735124) (xy 419.543341 -274.76308)
			(xy 419.578834 -274.797172) (xy 419.608399 -274.836516) (xy 419.63127 -274.880093) (xy 419.646854 -274.926774)
			(xy 419.654749 -274.975351) (xy 419.655244 -274.999958) (xy 419.654749 -275.024565) (xy 419.654611 -275.025412)
			(xy 419.972994 -275.025412) (xy 419.972994 -274.973996) (xy 419.981037 -274.923214) (xy 419.996925 -274.874315)
			(xy 420.020268 -274.828503) (xy 420.050489 -274.786907) (xy 420.086845 -274.750551) (xy 420.128441 -274.72033)
			(xy 420.174253 -274.696987) (xy 420.223152 -274.681099) (xy 420.273934 -274.673056) (xy 420.32535 -274.673056)
			(xy 420.376132 -274.681099) (xy 420.425031 -274.696987) (xy 420.470843 -274.72033) (xy 420.512439 -274.750551)
			(xy 420.548795 -274.786907) (xy 420.579016 -274.828503) (xy 420.602359 -274.874315) (xy 420.618247 -274.923214)
			(xy 420.62629 -274.973996) (xy 420.626794 -274.999704) (xy 420.626789 -274.999958) (xy 420.944052 -274.999958)
			(xy 420.948012 -274.950904) (xy 420.959789 -274.90312) (xy 420.97908 -274.857844) (xy 421.005383 -274.816248)
			(xy 421.038018 -274.779411) (xy 421.076139 -274.748286) (xy 421.11876 -274.723679) (xy 421.164776 -274.706227)
			(xy 421.212995 -274.696383) (xy 421.26217 -274.694402) (xy 421.311025 -274.700334) (xy 421.358296 -274.714026)
			(xy 421.402758 -274.735124) (xy 421.443261 -274.76308) (xy 421.478754 -274.797172) (xy 421.508319 -274.836516)
			(xy 421.53119 -274.880093) (xy 421.546774 -274.926774) (xy 421.554669 -274.975351) (xy 421.555164 -274.999958)
			(xy 421.554669 -275.024565) (xy 421.55449 -275.025666) (xy 421.872914 -275.025666) (xy 421.872914 -274.97425)
			(xy 421.880957 -274.923468) (xy 421.896845 -274.874569) (xy 421.920188 -274.828757) (xy 421.950409 -274.787161)
			(xy 421.986765 -274.750805) (xy 422.028361 -274.720584) (xy 422.074173 -274.697241) (xy 422.123072 -274.681353)
			(xy 422.173854 -274.67331) (xy 422.22527 -274.67331) (xy 422.276052 -274.681353) (xy 422.324951 -274.697241)
			(xy 422.370763 -274.720584) (xy 422.412359 -274.750805) (xy 422.448715 -274.787161) (xy 422.478936 -274.828757)
			(xy 422.502279 -274.874569) (xy 422.518167 -274.923468) (xy 422.52621 -274.97425) (xy 422.526714 -274.999958)
			(xy 422.843972 -274.999958) (xy 422.847932 -274.950904) (xy 422.859709 -274.90312) (xy 422.879 -274.857844)
			(xy 422.905303 -274.816248) (xy 422.937938 -274.779411) (xy 422.976059 -274.748286) (xy 423.01868 -274.723679)
			(xy 423.064696 -274.706227) (xy 423.112915 -274.696383) (xy 423.16209 -274.694402) (xy 423.210945 -274.700334)
			(xy 423.258216 -274.714026) (xy 423.302678 -274.735124) (xy 423.343181 -274.76308) (xy 423.378674 -274.797172)
			(xy 423.408239 -274.836516) (xy 423.43111 -274.880093) (xy 423.446694 -274.926774) (xy 423.454589 -274.975351)
			(xy 423.455084 -274.999958) (xy 423.454589 -275.024565) (xy 423.454451 -275.025412) (xy 423.773088 -275.025412)
			(xy 423.773088 -274.973996) (xy 423.781131 -274.923214) (xy 423.797019 -274.874315) (xy 423.820362 -274.828503)
			(xy 423.850583 -274.786907) (xy 423.886939 -274.750551) (xy 423.928535 -274.72033) (xy 423.974347 -274.696987)
			(xy 424.023246 -274.681099) (xy 424.074028 -274.673056) (xy 424.125444 -274.673056) (xy 424.176226 -274.681099)
			(xy 424.225125 -274.696987) (xy 424.270937 -274.72033) (xy 424.312533 -274.750551) (xy 424.348889 -274.786907)
			(xy 424.37911 -274.828503) (xy 424.402453 -274.874315) (xy 424.418341 -274.923214) (xy 424.426384 -274.973996)
			(xy 424.426888 -274.999704) (xy 424.426883 -274.999958) (xy 424.743892 -274.999958) (xy 424.747852 -274.950904)
			(xy 424.759629 -274.90312) (xy 424.77892 -274.857844) (xy 424.805223 -274.816248) (xy 424.837858 -274.779411)
			(xy 424.875979 -274.748286) (xy 424.9186 -274.723679) (xy 424.964616 -274.706227) (xy 425.012835 -274.696383)
			(xy 425.06201 -274.694402) (xy 425.110865 -274.700334) (xy 425.158136 -274.714026) (xy 425.202598 -274.735124)
			(xy 425.243101 -274.76308) (xy 425.278594 -274.797172) (xy 425.308159 -274.836516) (xy 425.33103 -274.880093)
			(xy 425.346614 -274.926774) (xy 425.354509 -274.975351) (xy 425.355004 -274.999958) (xy 425.354509 -275.024565)
			(xy 425.35433 -275.025666) (xy 425.673008 -275.025666) (xy 425.673008 -274.97425) (xy 425.681051 -274.923468)
			(xy 425.696939 -274.874569) (xy 425.720282 -274.828757) (xy 425.750503 -274.787161) (xy 425.786859 -274.750805)
			(xy 425.828455 -274.720584) (xy 425.874267 -274.697241) (xy 425.923166 -274.681353) (xy 425.973948 -274.67331)
			(xy 426.025364 -274.67331) (xy 426.076146 -274.681353) (xy 426.125045 -274.697241) (xy 426.170857 -274.720584)
			(xy 426.212453 -274.750805) (xy 426.248809 -274.787161) (xy 426.27903 -274.828757) (xy 426.302373 -274.874569)
			(xy 426.318261 -274.923468) (xy 426.326304 -274.97425) (xy 426.326808 -274.999958) (xy 426.643812 -274.999958)
			(xy 426.647772 -274.950904) (xy 426.659549 -274.90312) (xy 426.67884 -274.857844) (xy 426.705143 -274.816248)
			(xy 426.737778 -274.779411) (xy 426.775899 -274.748286) (xy 426.81852 -274.723679) (xy 426.864536 -274.706227)
			(xy 426.912755 -274.696383) (xy 426.96193 -274.694402) (xy 427.010785 -274.700334) (xy 427.058056 -274.714026)
			(xy 427.102518 -274.735124) (xy 427.143021 -274.76308) (xy 427.178514 -274.797172) (xy 427.208079 -274.836516)
			(xy 427.23095 -274.880093) (xy 427.246534 -274.926774) (xy 427.254429 -274.975351) (xy 427.254924 -274.999958)
			(xy 427.254429 -275.024565) (xy 427.25425 -275.025666) (xy 427.572928 -275.025666) (xy 427.572928 -274.97425)
			(xy 427.580971 -274.923468) (xy 427.596859 -274.874569) (xy 427.620202 -274.828757) (xy 427.650423 -274.787161)
			(xy 427.686779 -274.750805) (xy 427.728375 -274.720584) (xy 427.774187 -274.697241) (xy 427.823086 -274.681353)
			(xy 427.873868 -274.67331) (xy 427.925284 -274.67331) (xy 427.976066 -274.681353) (xy 428.024965 -274.697241)
			(xy 428.070777 -274.720584) (xy 428.112373 -274.750805) (xy 428.148729 -274.787161) (xy 428.17895 -274.828757)
			(xy 428.202293 -274.874569) (xy 428.218181 -274.923468) (xy 428.226224 -274.97425) (xy 428.226728 -274.999958)
			(xy 428.543986 -274.999958) (xy 428.547946 -274.950904) (xy 428.559723 -274.90312) (xy 428.579014 -274.857844)
			(xy 428.605317 -274.816248) (xy 428.637952 -274.779411) (xy 428.676073 -274.748286) (xy 428.718694 -274.723679)
			(xy 428.76471 -274.706227) (xy 428.812929 -274.696383) (xy 428.862104 -274.694402) (xy 428.910959 -274.700334)
			(xy 428.95823 -274.714026) (xy 429.002692 -274.735124) (xy 429.043195 -274.76308) (xy 429.078688 -274.797172)
			(xy 429.108253 -274.836516) (xy 429.131124 -274.880093) (xy 429.146708 -274.926774) (xy 429.154603 -274.975351)
			(xy 429.155098 -274.999958) (xy 429.154603 -275.024565) (xy 429.154465 -275.025412) (xy 429.473356 -275.025412)
			(xy 429.473356 -274.973996) (xy 429.481399 -274.923214) (xy 429.497287 -274.874315) (xy 429.52063 -274.828503)
			(xy 429.550851 -274.786907) (xy 429.587207 -274.750551) (xy 429.628803 -274.72033) (xy 429.674615 -274.696987)
			(xy 429.723514 -274.681099) (xy 429.774296 -274.673056) (xy 429.825712 -274.673056) (xy 429.876494 -274.681099)
			(xy 429.925393 -274.696987) (xy 429.971205 -274.72033) (xy 430.012801 -274.750551) (xy 430.049157 -274.786907)
			(xy 430.079378 -274.828503) (xy 430.102721 -274.874315) (xy 430.118609 -274.923214) (xy 430.126652 -274.973996)
			(xy 430.127156 -274.999704) (xy 430.126652 -275.025412) (xy 430.423316 -275.025412) (xy 430.423316 -274.973996)
			(xy 430.431359 -274.923214) (xy 430.447247 -274.874315) (xy 430.47059 -274.828503) (xy 430.500811 -274.786907)
			(xy 430.537167 -274.750551) (xy 430.578763 -274.72033) (xy 430.624575 -274.696987) (xy 430.673474 -274.681099)
			(xy 430.724256 -274.673056) (xy 430.775672 -274.673056) (xy 430.826454 -274.681099) (xy 430.875353 -274.696987)
			(xy 430.921165 -274.72033) (xy 430.962761 -274.750551) (xy 430.999117 -274.786907) (xy 431.029338 -274.828503)
			(xy 431.052681 -274.874315) (xy 431.068569 -274.923214) (xy 431.076612 -274.973996) (xy 431.077116 -274.999704)
			(xy 431.077111 -274.999958) (xy 431.394374 -274.999958) (xy 431.398334 -274.950904) (xy 431.410111 -274.90312)
			(xy 431.429402 -274.857844) (xy 431.455705 -274.816248) (xy 431.48834 -274.779411) (xy 431.526461 -274.748286)
			(xy 431.569082 -274.723679) (xy 431.615098 -274.706227) (xy 431.663317 -274.696383) (xy 431.712492 -274.694402)
			(xy 431.761347 -274.700334) (xy 431.808618 -274.714026) (xy 431.85308 -274.735124) (xy 431.893583 -274.76308)
			(xy 431.929076 -274.797172) (xy 431.958641 -274.836516) (xy 431.981512 -274.880093) (xy 431.997096 -274.926774)
			(xy 432.004991 -274.975351) (xy 432.005486 -274.999958) (xy 432.004991 -275.024565) (xy 431.997096 -275.073142)
			(xy 431.981512 -275.119823) (xy 431.958641 -275.1634) (xy 431.929076 -275.202744) (xy 431.893583 -275.236836)
			(xy 431.85308 -275.264792) (xy 431.808618 -275.28589) (xy 431.761347 -275.299582) (xy 431.712492 -275.305514)
			(xy 431.663317 -275.303533) (xy 431.615098 -275.293689) (xy 431.569082 -275.276237) (xy 431.526461 -275.25163)
			(xy 431.48834 -275.220505) (xy 431.455705 -275.183668) (xy 431.429402 -275.142072) (xy 431.410111 -275.096796)
			(xy 431.398334 -275.049012) (xy 431.394374 -274.999958) (xy 431.077111 -274.999958) (xy 431.076612 -275.025412)
			(xy 431.068569 -275.076194) (xy 431.052681 -275.125093) (xy 431.029338 -275.170905) (xy 430.999117 -275.212501)
			(xy 430.962761 -275.248857) (xy 430.921165 -275.279078) (xy 430.875353 -275.302421) (xy 430.826454 -275.318309)
			(xy 430.775672 -275.326352) (xy 430.724256 -275.326352) (xy 430.673474 -275.318309) (xy 430.624575 -275.302421)
			(xy 430.578763 -275.279078) (xy 430.537167 -275.248857) (xy 430.500811 -275.212501) (xy 430.47059 -275.170905)
			(xy 430.447247 -275.125093) (xy 430.431359 -275.076194) (xy 430.423316 -275.025412) (xy 430.126652 -275.025412)
			(xy 430.118609 -275.076194) (xy 430.102721 -275.125093) (xy 430.079378 -275.170905) (xy 430.049157 -275.212501)
			(xy 430.012801 -275.248857) (xy 429.971205 -275.279078) (xy 429.925393 -275.302421) (xy 429.876494 -275.318309)
			(xy 429.825712 -275.326352) (xy 429.774296 -275.326352) (xy 429.723514 -275.318309) (xy 429.674615 -275.302421)
			(xy 429.628803 -275.279078) (xy 429.587207 -275.248857) (xy 429.550851 -275.212501) (xy 429.52063 -275.170905)
			(xy 429.497287 -275.125093) (xy 429.481399 -275.076194) (xy 429.473356 -275.025412) (xy 429.154465 -275.025412)
			(xy 429.146708 -275.073142) (xy 429.131124 -275.119823) (xy 429.108253 -275.1634) (xy 429.078688 -275.202744)
			(xy 429.043195 -275.236836) (xy 429.002692 -275.264792) (xy 428.95823 -275.28589) (xy 428.910959 -275.299582)
			(xy 428.862104 -275.305514) (xy 428.812929 -275.303533) (xy 428.76471 -275.293689) (xy 428.718694 -275.276237)
			(xy 428.676073 -275.25163) (xy 428.637952 -275.220505) (xy 428.605317 -275.183668) (xy 428.579014 -275.142072)
			(xy 428.559723 -275.096796) (xy 428.547946 -275.049012) (xy 428.543986 -274.999958) (xy 428.226728 -274.999958)
			(xy 428.226224 -275.025666) (xy 428.218181 -275.076448) (xy 428.202293 -275.125347) (xy 428.17895 -275.171159)
			(xy 428.148729 -275.212755) (xy 428.112373 -275.249111) (xy 428.070777 -275.279332) (xy 428.024965 -275.302675)
			(xy 427.976066 -275.318563) (xy 427.925284 -275.326606) (xy 427.873868 -275.326606) (xy 427.823086 -275.318563)
			(xy 427.774187 -275.302675) (xy 427.728375 -275.279332) (xy 427.686779 -275.249111) (xy 427.650423 -275.212755)
			(xy 427.620202 -275.171159) (xy 427.596859 -275.125347) (xy 427.580971 -275.076448) (xy 427.572928 -275.025666)
			(xy 427.25425 -275.025666) (xy 427.246534 -275.073142) (xy 427.23095 -275.119823) (xy 427.208079 -275.1634)
			(xy 427.178514 -275.202744) (xy 427.143021 -275.236836) (xy 427.102518 -275.264792) (xy 427.058056 -275.28589)
			(xy 427.010785 -275.299582) (xy 426.96193 -275.305514) (xy 426.912755 -275.303533) (xy 426.864536 -275.293689)
			(xy 426.81852 -275.276237) (xy 426.775899 -275.25163) (xy 426.737778 -275.220505) (xy 426.705143 -275.183668)
			(xy 426.67884 -275.142072) (xy 426.659549 -275.096796) (xy 426.647772 -275.049012) (xy 426.643812 -274.999958)
			(xy 426.326808 -274.999958) (xy 426.326304 -275.025666) (xy 426.318261 -275.076448) (xy 426.302373 -275.125347)
			(xy 426.27903 -275.171159) (xy 426.248809 -275.212755) (xy 426.212453 -275.249111) (xy 426.170857 -275.279332)
			(xy 426.125045 -275.302675) (xy 426.076146 -275.318563) (xy 426.025364 -275.326606) (xy 425.973948 -275.326606)
			(xy 425.923166 -275.318563) (xy 425.874267 -275.302675) (xy 425.828455 -275.279332) (xy 425.786859 -275.249111)
			(xy 425.750503 -275.212755) (xy 425.720282 -275.171159) (xy 425.696939 -275.125347) (xy 425.681051 -275.076448)
			(xy 425.673008 -275.025666) (xy 425.35433 -275.025666) (xy 425.346614 -275.073142) (xy 425.33103 -275.119823)
			(xy 425.308159 -275.1634) (xy 425.278594 -275.202744) (xy 425.243101 -275.236836) (xy 425.202598 -275.264792)
			(xy 425.158136 -275.28589) (xy 425.110865 -275.299582) (xy 425.06201 -275.305514) (xy 425.012835 -275.303533)
			(xy 424.964616 -275.293689) (xy 424.9186 -275.276237) (xy 424.875979 -275.25163) (xy 424.837858 -275.220505)
			(xy 424.805223 -275.183668) (xy 424.77892 -275.142072) (xy 424.759629 -275.096796) (xy 424.747852 -275.049012)
			(xy 424.743892 -274.999958) (xy 424.426883 -274.999958) (xy 424.426384 -275.025412) (xy 424.418341 -275.076194)
			(xy 424.402453 -275.125093) (xy 424.37911 -275.170905) (xy 424.348889 -275.212501) (xy 424.312533 -275.248857)
			(xy 424.270937 -275.279078) (xy 424.225125 -275.302421) (xy 424.176226 -275.318309) (xy 424.125444 -275.326352)
			(xy 424.074028 -275.326352) (xy 424.023246 -275.318309) (xy 423.974347 -275.302421) (xy 423.928535 -275.279078)
			(xy 423.886939 -275.248857) (xy 423.850583 -275.212501) (xy 423.820362 -275.170905) (xy 423.797019 -275.125093)
			(xy 423.781131 -275.076194) (xy 423.773088 -275.025412) (xy 423.454451 -275.025412) (xy 423.446694 -275.073142)
			(xy 423.43111 -275.119823) (xy 423.408239 -275.1634) (xy 423.378674 -275.202744) (xy 423.343181 -275.236836)
			(xy 423.302678 -275.264792) (xy 423.258216 -275.28589) (xy 423.210945 -275.299582) (xy 423.16209 -275.305514)
			(xy 423.112915 -275.303533) (xy 423.064696 -275.293689) (xy 423.01868 -275.276237) (xy 422.976059 -275.25163)
			(xy 422.937938 -275.220505) (xy 422.905303 -275.183668) (xy 422.879 -275.142072) (xy 422.859709 -275.096796)
			(xy 422.847932 -275.049012) (xy 422.843972 -274.999958) (xy 422.526714 -274.999958) (xy 422.52621 -275.025666)
			(xy 422.518167 -275.076448) (xy 422.502279 -275.125347) (xy 422.478936 -275.171159) (xy 422.448715 -275.212755)
			(xy 422.412359 -275.249111) (xy 422.370763 -275.279332) (xy 422.324951 -275.302675) (xy 422.276052 -275.318563)
			(xy 422.22527 -275.326606) (xy 422.173854 -275.326606) (xy 422.123072 -275.318563) (xy 422.074173 -275.302675)
			(xy 422.028361 -275.279332) (xy 421.986765 -275.249111) (xy 421.950409 -275.212755) (xy 421.920188 -275.171159)
			(xy 421.896845 -275.125347) (xy 421.880957 -275.076448) (xy 421.872914 -275.025666) (xy 421.55449 -275.025666)
			(xy 421.546774 -275.073142) (xy 421.53119 -275.119823) (xy 421.508319 -275.1634) (xy 421.478754 -275.202744)
			(xy 421.443261 -275.236836) (xy 421.402758 -275.264792) (xy 421.358296 -275.28589) (xy 421.311025 -275.299582)
			(xy 421.26217 -275.305514) (xy 421.212995 -275.303533) (xy 421.164776 -275.293689) (xy 421.11876 -275.276237)
			(xy 421.076139 -275.25163) (xy 421.038018 -275.220505) (xy 421.005383 -275.183668) (xy 420.97908 -275.142072)
			(xy 420.959789 -275.096796) (xy 420.948012 -275.049012) (xy 420.944052 -274.999958) (xy 420.626789 -274.999958)
			(xy 420.62629 -275.025412) (xy 420.618247 -275.076194) (xy 420.602359 -275.125093) (xy 420.579016 -275.170905)
			(xy 420.548795 -275.212501) (xy 420.512439 -275.248857) (xy 420.470843 -275.279078) (xy 420.425031 -275.302421)
			(xy 420.376132 -275.318309) (xy 420.32535 -275.326352) (xy 420.273934 -275.326352) (xy 420.223152 -275.318309)
			(xy 420.174253 -275.302421) (xy 420.128441 -275.279078) (xy 420.086845 -275.248857) (xy 420.050489 -275.212501)
			(xy 420.020268 -275.170905) (xy 419.996925 -275.125093) (xy 419.981037 -275.076194) (xy 419.972994 -275.025412)
			(xy 419.654611 -275.025412) (xy 419.646854 -275.073142) (xy 419.63127 -275.119823) (xy 419.608399 -275.1634)
			(xy 419.578834 -275.202744) (xy 419.543341 -275.236836) (xy 419.502838 -275.264792) (xy 419.458376 -275.28589)
			(xy 419.411105 -275.299582) (xy 419.36225 -275.305514) (xy 419.313075 -275.303533) (xy 419.264856 -275.293689)
			(xy 419.21884 -275.276237) (xy 419.176219 -275.25163) (xy 419.138098 -275.220505) (xy 419.105463 -275.183668)
			(xy 419.07916 -275.142072) (xy 419.059869 -275.096796) (xy 419.048092 -275.049012) (xy 419.044132 -274.999958)
			(xy 418.72662 -274.999958) (xy 418.726116 -275.025666) (xy 418.718073 -275.076448) (xy 418.702185 -275.125347)
			(xy 418.678842 -275.171159) (xy 418.648621 -275.212755) (xy 418.612265 -275.249111) (xy 418.570669 -275.279332)
			(xy 418.524857 -275.302675) (xy 418.475958 -275.318563) (xy 418.425176 -275.326606) (xy 418.37376 -275.326606)
			(xy 418.322978 -275.318563) (xy 418.274079 -275.302675) (xy 418.228267 -275.279332) (xy 418.186671 -275.249111)
			(xy 418.150315 -275.212755) (xy 418.120094 -275.171159) (xy 418.096751 -275.125347) (xy 418.080863 -275.076448)
			(xy 418.07282 -275.025666) (xy 417.75465 -275.025666) (xy 417.746934 -275.073142) (xy 417.73135 -275.119823)
			(xy 417.708479 -275.1634) (xy 417.678914 -275.202744) (xy 417.643421 -275.236836) (xy 417.602918 -275.264792)
			(xy 417.558456 -275.28589) (xy 417.511185 -275.299582) (xy 417.46233 -275.305514) (xy 417.413155 -275.303533)
			(xy 417.364936 -275.293689) (xy 417.31892 -275.276237) (xy 417.276299 -275.25163) (xy 417.238178 -275.220505)
			(xy 417.205543 -275.183668) (xy 417.17924 -275.142072) (xy 417.159949 -275.096796) (xy 417.148172 -275.049012)
			(xy 417.144212 -274.999958) (xy 416.826695 -274.999958) (xy 416.826196 -275.025412) (xy 416.818153 -275.076194)
			(xy 416.802265 -275.125093) (xy 416.778922 -275.170905) (xy 416.748701 -275.212501) (xy 416.712345 -275.248857)
			(xy 416.670749 -275.279078) (xy 416.624937 -275.302421) (xy 416.576038 -275.318309) (xy 416.525256 -275.326352)
			(xy 416.47384 -275.326352) (xy 416.423058 -275.318309) (xy 416.374159 -275.302421) (xy 416.328347 -275.279078)
			(xy 416.286751 -275.248857) (xy 416.250395 -275.212501) (xy 416.220174 -275.170905) (xy 416.196831 -275.125093)
			(xy 416.180943 -275.076194) (xy 416.1729 -275.025412) (xy 415.854517 -275.025412) (xy 415.84676 -275.073142)
			(xy 415.831176 -275.119823) (xy 415.808305 -275.1634) (xy 415.77874 -275.202744) (xy 415.743247 -275.236836)
			(xy 415.702744 -275.264792) (xy 415.658282 -275.28589) (xy 415.611011 -275.299582) (xy 415.562156 -275.305514)
			(xy 415.512981 -275.303533) (xy 415.464762 -275.293689) (xy 415.418746 -275.276237) (xy 415.376125 -275.25163)
			(xy 415.338004 -275.220505) (xy 415.305369 -275.183668) (xy 415.279066 -275.142072) (xy 415.259775 -275.096796)
			(xy 415.247998 -275.049012) (xy 415.244038 -274.999958) (xy 414.92678 -274.999958) (xy 414.926276 -275.025666)
			(xy 414.918233 -275.076448) (xy 414.902345 -275.125347) (xy 414.879002 -275.171159) (xy 414.848781 -275.212755)
			(xy 414.812425 -275.249111) (xy 414.770829 -275.279332) (xy 414.725017 -275.302675) (xy 414.676118 -275.318563)
			(xy 414.625336 -275.326606) (xy 414.57392 -275.326606) (xy 414.523138 -275.318563) (xy 414.474239 -275.302675)
			(xy 414.428427 -275.279332) (xy 414.386831 -275.249111) (xy 414.350475 -275.212755) (xy 414.320254 -275.171159)
			(xy 414.296911 -275.125347) (xy 414.281023 -275.076448) (xy 414.27298 -275.025666) (xy 413.954556 -275.025666)
			(xy 413.94684 -275.073142) (xy 413.931256 -275.119823) (xy 413.908385 -275.1634) (xy 413.87882 -275.202744)
			(xy 413.843327 -275.236836) (xy 413.802824 -275.264792) (xy 413.758362 -275.28589) (xy 413.711091 -275.299582)
			(xy 413.662236 -275.305514) (xy 413.613061 -275.303533) (xy 413.564842 -275.293689) (xy 413.518826 -275.276237)
			(xy 413.476205 -275.25163) (xy 413.438084 -275.220505) (xy 413.405449 -275.183668) (xy 413.379146 -275.142072)
			(xy 413.359855 -275.096796) (xy 413.348078 -275.049012) (xy 413.344118 -274.999958) (xy 413.026855 -274.999958)
			(xy 413.026356 -275.025412) (xy 413.018313 -275.076194) (xy 413.002425 -275.125093) (xy 412.979082 -275.170905)
			(xy 412.948861 -275.212501) (xy 412.912505 -275.248857) (xy 412.870909 -275.279078) (xy 412.825097 -275.302421)
			(xy 412.776198 -275.318309) (xy 412.725416 -275.326352) (xy 412.674 -275.326352) (xy 412.623218 -275.318309)
			(xy 412.574319 -275.302421) (xy 412.528507 -275.279078) (xy 412.486911 -275.248857) (xy 412.450555 -275.212501)
			(xy 412.420334 -275.170905) (xy 412.396991 -275.125093) (xy 412.381103 -275.076194) (xy 412.37306 -275.025412)
			(xy 412.054677 -275.025412) (xy 412.04692 -275.073142) (xy 412.031336 -275.119823) (xy 412.008465 -275.1634)
			(xy 411.9789 -275.202744) (xy 411.943407 -275.236836) (xy 411.902904 -275.264792) (xy 411.858442 -275.28589)
			(xy 411.811171 -275.299582) (xy 411.762316 -275.305514) (xy 411.713141 -275.303533) (xy 411.664922 -275.293689)
			(xy 411.618906 -275.276237) (xy 411.576285 -275.25163) (xy 411.538164 -275.220505) (xy 411.505529 -275.183668)
			(xy 411.479226 -275.142072) (xy 411.459935 -275.096796) (xy 411.448158 -275.049012) (xy 411.444198 -274.999958)
			(xy 411.126686 -274.999958) (xy 411.126182 -275.025666) (xy 411.118139 -275.076448) (xy 411.102251 -275.125347)
			(xy 411.078908 -275.171159) (xy 411.048687 -275.212755) (xy 411.012331 -275.249111) (xy 410.970735 -275.279332)
			(xy 410.924923 -275.302675) (xy 410.876024 -275.318563) (xy 410.825242 -275.326606) (xy 410.773826 -275.326606)
			(xy 410.723044 -275.318563) (xy 410.674145 -275.302675) (xy 410.628333 -275.279332) (xy 410.586737 -275.249111)
			(xy 410.550381 -275.212755) (xy 410.52016 -275.171159) (xy 410.496817 -275.125347) (xy 410.480929 -275.076448)
			(xy 410.472886 -275.025666) (xy 410.154462 -275.025666) (xy 410.146746 -275.073142) (xy 410.131162 -275.119823)
			(xy 410.108291 -275.1634) (xy 410.078726 -275.202744) (xy 410.043233 -275.236836) (xy 410.00273 -275.264792)
			(xy 409.958268 -275.28589) (xy 409.910997 -275.299582) (xy 409.862142 -275.305514) (xy 409.812967 -275.303533)
			(xy 409.764748 -275.293689) (xy 409.718732 -275.276237) (xy 409.676111 -275.25163) (xy 409.63799 -275.220505)
			(xy 409.605355 -275.183668) (xy 409.579052 -275.142072) (xy 409.559761 -275.096796) (xy 409.547984 -275.049012)
			(xy 409.544024 -274.999958) (xy 409.226761 -274.999958) (xy 409.226262 -275.025412) (xy 409.218219 -275.076194)
			(xy 409.202331 -275.125093) (xy 409.178988 -275.170905) (xy 409.148767 -275.212501) (xy 409.112411 -275.248857)
			(xy 409.070815 -275.279078) (xy 409.025003 -275.302421) (xy 408.976104 -275.318309) (xy 408.925322 -275.326352)
			(xy 408.873906 -275.326352) (xy 408.823124 -275.318309) (xy 408.774225 -275.302421) (xy 408.728413 -275.279078)
			(xy 408.686817 -275.248857) (xy 408.650461 -275.212501) (xy 408.62024 -275.170905) (xy 408.596897 -275.125093)
			(xy 408.581009 -275.076194) (xy 408.572966 -275.025412) (xy 408.254583 -275.025412) (xy 408.246826 -275.073142)
			(xy 408.231242 -275.119823) (xy 408.208371 -275.1634) (xy 408.178806 -275.202744) (xy 408.143313 -275.236836)
			(xy 408.10281 -275.264792) (xy 408.058348 -275.28589) (xy 408.011077 -275.299582) (xy 407.962222 -275.305514)
			(xy 407.913047 -275.303533) (xy 407.864828 -275.293689) (xy 407.818812 -275.276237) (xy 407.776191 -275.25163)
			(xy 407.73807 -275.220505) (xy 407.705435 -275.183668) (xy 407.679132 -275.142072) (xy 407.659841 -275.096796)
			(xy 407.648064 -275.049012) (xy 407.644104 -274.999958) (xy 407.3271 -274.999958) (xy 407.326596 -275.025666)
			(xy 407.318553 -275.076448) (xy 407.302665 -275.125347) (xy 407.279322 -275.171159) (xy 407.249101 -275.212755)
			(xy 407.212745 -275.249111) (xy 407.171149 -275.279332) (xy 407.125337 -275.302675) (xy 407.076438 -275.318563)
			(xy 407.025656 -275.326606) (xy 406.97424 -275.326606) (xy 406.923458 -275.318563) (xy 406.874559 -275.302675)
			(xy 406.828747 -275.279332) (xy 406.787151 -275.249111) (xy 406.750795 -275.212755) (xy 406.720574 -275.171159)
			(xy 406.697231 -275.125347) (xy 406.681343 -275.076448) (xy 406.6733 -275.025666) (xy 406.354622 -275.025666)
			(xy 406.346906 -275.073142) (xy 406.331322 -275.119823) (xy 406.308451 -275.1634) (xy 406.278886 -275.202744)
			(xy 406.243393 -275.236836) (xy 406.20289 -275.264792) (xy 406.158428 -275.28589) (xy 406.111157 -275.299582)
			(xy 406.062302 -275.305514) (xy 406.013127 -275.303533) (xy 405.964908 -275.293689) (xy 405.918892 -275.276237)
			(xy 405.876271 -275.25163) (xy 405.83815 -275.220505) (xy 405.805515 -275.183668) (xy 405.779212 -275.142072)
			(xy 405.759921 -275.096796) (xy 405.748144 -275.049012) (xy 405.744184 -274.999958) (xy 405.42718 -274.999958)
			(xy 405.426676 -275.025666) (xy 405.418633 -275.076448) (xy 405.402745 -275.125347) (xy 405.379402 -275.171159)
			(xy 405.349181 -275.212755) (xy 405.312825 -275.249111) (xy 405.271229 -275.279332) (xy 405.225417 -275.302675)
			(xy 405.176518 -275.318563) (xy 405.125736 -275.326606) (xy 405.07432 -275.326606) (xy 405.023538 -275.318563)
			(xy 404.974639 -275.302675) (xy 404.928827 -275.279332) (xy 404.887231 -275.249111) (xy 404.850875 -275.212755)
			(xy 404.820654 -275.171159) (xy 404.797311 -275.125347) (xy 404.781423 -275.076448) (xy 404.77338 -275.025666)
			(xy 404.454448 -275.025666) (xy 404.446732 -275.073142) (xy 404.431148 -275.119823) (xy 404.408277 -275.1634)
			(xy 404.378712 -275.202744) (xy 404.343219 -275.236836) (xy 404.302716 -275.264792) (xy 404.258254 -275.28589)
			(xy 404.210983 -275.299582) (xy 404.162128 -275.305514) (xy 404.112953 -275.303533) (xy 404.064734 -275.293689)
			(xy 404.018718 -275.276237) (xy 403.976097 -275.25163) (xy 403.937976 -275.220505) (xy 403.905341 -275.183668)
			(xy 403.879038 -275.142072) (xy 403.859747 -275.096796) (xy 403.84797 -275.049012) (xy 403.84401 -274.999958)
			(xy 403.527006 -274.999958) (xy 403.526502 -275.025666) (xy 403.518459 -275.076448) (xy 403.502571 -275.125347)
			(xy 403.479228 -275.171159) (xy 403.449007 -275.212755) (xy 403.412651 -275.249111) (xy 403.371055 -275.279332)
			(xy 403.325243 -275.302675) (xy 403.276344 -275.318563) (xy 403.225562 -275.326606) (xy 403.174146 -275.326606)
			(xy 403.123364 -275.318563) (xy 403.074465 -275.302675) (xy 403.028653 -275.279332) (xy 402.987057 -275.249111)
			(xy 402.950701 -275.212755) (xy 402.92048 -275.171159) (xy 402.897137 -275.125347) (xy 402.881249 -275.076448)
			(xy 402.873206 -275.025666) (xy 402.554528 -275.025666) (xy 402.546812 -275.073142) (xy 402.531228 -275.119823)
			(xy 402.508357 -275.1634) (xy 402.478792 -275.202744) (xy 402.443299 -275.236836) (xy 402.402796 -275.264792)
			(xy 402.358334 -275.28589) (xy 402.311063 -275.299582) (xy 402.262208 -275.305514) (xy 402.213033 -275.303533)
			(xy 402.164814 -275.293689) (xy 402.118798 -275.276237) (xy 402.076177 -275.25163) (xy 402.038056 -275.220505)
			(xy 402.005421 -275.183668) (xy 401.979118 -275.142072) (xy 401.959827 -275.096796) (xy 401.94805 -275.049012)
			(xy 401.94409 -274.999958) (xy 401.627086 -274.999958) (xy 401.626582 -275.025666) (xy 401.618539 -275.076448)
			(xy 401.602651 -275.125347) (xy 401.579308 -275.171159) (xy 401.549087 -275.212755) (xy 401.512731 -275.249111)
			(xy 401.471135 -275.279332) (xy 401.425323 -275.302675) (xy 401.376424 -275.318563) (xy 401.325642 -275.326606)
			(xy 401.274226 -275.326606) (xy 401.223444 -275.318563) (xy 401.174545 -275.302675) (xy 401.128733 -275.279332)
			(xy 401.087137 -275.249111) (xy 401.050781 -275.212755) (xy 401.02056 -275.171159) (xy 400.997217 -275.125347)
			(xy 400.981329 -275.076448) (xy 400.973286 -275.025666) (xy 400.654608 -275.025666) (xy 400.646892 -275.073142)
			(xy 400.631308 -275.119823) (xy 400.608437 -275.1634) (xy 400.578872 -275.202744) (xy 400.543379 -275.236836)
			(xy 400.502876 -275.264792) (xy 400.458414 -275.28589) (xy 400.411143 -275.299582) (xy 400.362288 -275.305514)
			(xy 400.313113 -275.303533) (xy 400.264894 -275.293689) (xy 400.218878 -275.276237) (xy 400.176257 -275.25163)
			(xy 400.138136 -275.220505) (xy 400.105501 -275.183668) (xy 400.079198 -275.142072) (xy 400.059907 -275.096796)
			(xy 400.04813 -275.049012) (xy 400.04417 -274.999958) (xy 399.727166 -274.999958) (xy 399.726662 -275.025666)
			(xy 399.718619 -275.076448) (xy 399.702731 -275.125347) (xy 399.679388 -275.171159) (xy 399.649167 -275.212755)
			(xy 399.612811 -275.249111) (xy 399.571215 -275.279332) (xy 399.525403 -275.302675) (xy 399.476504 -275.318563)
			(xy 399.425722 -275.326606) (xy 399.374306 -275.326606) (xy 399.323524 -275.318563) (xy 399.274625 -275.302675)
			(xy 399.228813 -275.279332) (xy 399.187217 -275.249111) (xy 399.150861 -275.212755) (xy 399.12064 -275.171159)
			(xy 399.097297 -275.125347) (xy 399.081409 -275.076448) (xy 399.073366 -275.025666) (xy 398.753546 -275.025666)
			(xy 398.751501 -275.050345) (xy 398.7391 -275.099317) (xy 398.718807 -275.145579) (xy 398.691177 -275.187871)
			(xy 398.656962 -275.225038) (xy 398.617097 -275.256067) (xy 398.572668 -275.28011) (xy 398.524887 -275.296513)
			(xy 398.475059 -275.304828) (xy 398.4498 -275.305266) (xy 398.435618 -275.30508) (xy 398.407378 -275.302407)
			(xy 398.393412 -275.299932) (xy 398.380966 -275.297646) (xy 398.357344 -275.305012) (xy 398.279874 -275.382482)
			(xy 398.272508 -275.406104) (xy 398.274794 -275.41855) (xy 398.277277 -275.432515) (xy 398.279946 -275.460755)
			(xy 398.280128 -275.474938) (xy 398.279944 -275.489121) (xy 398.277277 -275.517361) (xy 398.274794 -275.531326)
			(xy 398.272508 -275.543772) (xy 398.279874 -275.567394) (xy 398.357344 -275.644864) (xy 398.380966 -275.65223)
			(xy 398.393412 -275.649944) (xy 398.407377 -275.647459) (xy 398.435617 -275.644786) (xy 398.4498 -275.64461)
			(xy 398.475054 -275.645132) (xy 398.524873 -275.653445) (xy 398.572644 -275.669845) (xy 398.617064 -275.693884)
			(xy 398.656922 -275.724906) (xy 398.691129 -275.762066) (xy 398.718755 -275.804349) (xy 398.739043 -275.850603)
			(xy 398.751442 -275.899565) (xy 398.755613 -275.9499) (xy 398.753481 -275.975626) (xy 399.073366 -275.975626)
			(xy 399.073366 -275.92421) (xy 399.081409 -275.873428) (xy 399.097297 -275.824529) (xy 399.12064 -275.778717)
			(xy 399.150861 -275.737121) (xy 399.187217 -275.700765) (xy 399.228813 -275.670544) (xy 399.274625 -275.647201)
			(xy 399.323524 -275.631313) (xy 399.374306 -275.62327) (xy 399.425722 -275.62327) (xy 399.476504 -275.631313)
			(xy 399.525403 -275.647201) (xy 399.571215 -275.670544) (xy 399.612811 -275.700765) (xy 399.649167 -275.737121)
			(xy 399.679388 -275.778717) (xy 399.702731 -275.824529) (xy 399.718619 -275.873428) (xy 399.726662 -275.92421)
			(xy 399.727166 -275.949918) (xy 400.04417 -275.949918) (xy 400.04813 -275.900864) (xy 400.059907 -275.85308)
			(xy 400.079198 -275.807804) (xy 400.105501 -275.766208) (xy 400.138136 -275.729371) (xy 400.176257 -275.698246)
			(xy 400.218878 -275.673639) (xy 400.264894 -275.656187) (xy 400.313113 -275.646343) (xy 400.362288 -275.644362)
			(xy 400.411143 -275.650294) (xy 400.458414 -275.663986) (xy 400.502876 -275.685084) (xy 400.543379 -275.71304)
			(xy 400.578872 -275.747132) (xy 400.608437 -275.786476) (xy 400.631308 -275.830053) (xy 400.646892 -275.876734)
			(xy 400.654787 -275.925311) (xy 400.655282 -275.949918) (xy 400.654787 -275.974525) (xy 400.654608 -275.975626)
			(xy 400.973286 -275.975626) (xy 400.973286 -275.92421) (xy 400.981329 -275.873428) (xy 400.997217 -275.824529)
			(xy 401.02056 -275.778717) (xy 401.050781 -275.737121) (xy 401.087137 -275.700765) (xy 401.128733 -275.670544)
			(xy 401.174545 -275.647201) (xy 401.223444 -275.631313) (xy 401.274226 -275.62327) (xy 401.325642 -275.62327)
			(xy 401.376424 -275.631313) (xy 401.425323 -275.647201) (xy 401.471135 -275.670544) (xy 401.512731 -275.700765)
			(xy 401.549087 -275.737121) (xy 401.579308 -275.778717) (xy 401.602651 -275.824529) (xy 401.618539 -275.873428)
			(xy 401.626582 -275.92421) (xy 401.627086 -275.949918) (xy 401.94409 -275.949918) (xy 401.94805 -275.900864)
			(xy 401.959827 -275.85308) (xy 401.979118 -275.807804) (xy 402.005421 -275.766208) (xy 402.038056 -275.729371)
			(xy 402.076177 -275.698246) (xy 402.118798 -275.673639) (xy 402.164814 -275.656187) (xy 402.213033 -275.646343)
			(xy 402.262208 -275.644362) (xy 402.311063 -275.650294) (xy 402.358334 -275.663986) (xy 402.402796 -275.685084)
			(xy 402.443299 -275.71304) (xy 402.478792 -275.747132) (xy 402.508357 -275.786476) (xy 402.531228 -275.830053)
			(xy 402.546812 -275.876734) (xy 402.554707 -275.925311) (xy 402.555202 -275.949918) (xy 402.554707 -275.974525)
			(xy 402.554528 -275.975626) (xy 402.873206 -275.975626) (xy 402.873206 -275.92421) (xy 402.881249 -275.873428)
			(xy 402.897137 -275.824529) (xy 402.92048 -275.778717) (xy 402.950701 -275.737121) (xy 402.987057 -275.700765)
			(xy 403.028653 -275.670544) (xy 403.074465 -275.647201) (xy 403.123364 -275.631313) (xy 403.174146 -275.62327)
			(xy 403.225562 -275.62327) (xy 403.276344 -275.631313) (xy 403.325243 -275.647201) (xy 403.371055 -275.670544)
			(xy 403.412651 -275.700765) (xy 403.449007 -275.737121) (xy 403.479228 -275.778717) (xy 403.502571 -275.824529)
			(xy 403.518459 -275.873428) (xy 403.526502 -275.92421) (xy 403.527006 -275.949918) (xy 403.84401 -275.949918)
			(xy 403.84797 -275.900864) (xy 403.859747 -275.85308) (xy 403.879038 -275.807804) (xy 403.905341 -275.766208)
			(xy 403.937976 -275.729371) (xy 403.976097 -275.698246) (xy 404.018718 -275.673639) (xy 404.064734 -275.656187)
			(xy 404.112953 -275.646343) (xy 404.162128 -275.644362) (xy 404.210983 -275.650294) (xy 404.258254 -275.663986)
			(xy 404.302716 -275.685084) (xy 404.343219 -275.71304) (xy 404.378712 -275.747132) (xy 404.408277 -275.786476)
			(xy 404.431148 -275.830053) (xy 404.446732 -275.876734) (xy 404.454627 -275.925311) (xy 404.455122 -275.949918)
			(xy 404.454627 -275.974525) (xy 404.454448 -275.975626) (xy 404.77338 -275.975626) (xy 404.77338 -275.92421)
			(xy 404.781423 -275.873428) (xy 404.797311 -275.824529) (xy 404.820654 -275.778717) (xy 404.850875 -275.737121)
			(xy 404.887231 -275.700765) (xy 404.928827 -275.670544) (xy 404.974639 -275.647201) (xy 405.023538 -275.631313)
			(xy 405.07432 -275.62327) (xy 405.125736 -275.62327) (xy 405.176518 -275.631313) (xy 405.225417 -275.647201)
			(xy 405.271229 -275.670544) (xy 405.312825 -275.700765) (xy 405.349181 -275.737121) (xy 405.379402 -275.778717)
			(xy 405.402745 -275.824529) (xy 405.418633 -275.873428) (xy 405.426676 -275.92421) (xy 405.42718 -275.949918)
			(xy 405.744184 -275.949918) (xy 405.748144 -275.900864) (xy 405.759921 -275.85308) (xy 405.779212 -275.807804)
			(xy 405.805515 -275.766208) (xy 405.83815 -275.729371) (xy 405.876271 -275.698246) (xy 405.918892 -275.673639)
			(xy 405.964908 -275.656187) (xy 406.013127 -275.646343) (xy 406.062302 -275.644362) (xy 406.111157 -275.650294)
			(xy 406.158428 -275.663986) (xy 406.20289 -275.685084) (xy 406.243393 -275.71304) (xy 406.278886 -275.747132)
			(xy 406.308451 -275.786476) (xy 406.331322 -275.830053) (xy 406.346906 -275.876734) (xy 406.354801 -275.925311)
			(xy 406.355296 -275.949918) (xy 406.354801 -275.974525) (xy 406.354622 -275.975626) (xy 406.6733 -275.975626)
			(xy 406.6733 -275.92421) (xy 406.681343 -275.873428) (xy 406.697231 -275.824529) (xy 406.720574 -275.778717)
			(xy 406.750795 -275.737121) (xy 406.787151 -275.700765) (xy 406.828747 -275.670544) (xy 406.874559 -275.647201)
			(xy 406.923458 -275.631313) (xy 406.97424 -275.62327) (xy 407.025656 -275.62327) (xy 407.076438 -275.631313)
			(xy 407.125337 -275.647201) (xy 407.171149 -275.670544) (xy 407.212745 -275.700765) (xy 407.249101 -275.737121)
			(xy 407.279322 -275.778717) (xy 407.302665 -275.824529) (xy 407.318553 -275.873428) (xy 407.326596 -275.92421)
			(xy 407.3271 -275.949918) (xy 407.644104 -275.949918) (xy 407.648064 -275.900864) (xy 407.659841 -275.85308)
			(xy 407.679132 -275.807804) (xy 407.705435 -275.766208) (xy 407.73807 -275.729371) (xy 407.776191 -275.698246)
			(xy 407.818812 -275.673639) (xy 407.864828 -275.656187) (xy 407.913047 -275.646343) (xy 407.962222 -275.644362)
			(xy 408.011077 -275.650294) (xy 408.058348 -275.663986) (xy 408.10281 -275.685084) (xy 408.143313 -275.71304)
			(xy 408.178806 -275.747132) (xy 408.208371 -275.786476) (xy 408.231242 -275.830053) (xy 408.246826 -275.876734)
			(xy 408.254721 -275.925311) (xy 408.255216 -275.949918) (xy 408.254721 -275.974525) (xy 408.254583 -275.975372)
			(xy 408.572966 -275.975372) (xy 408.572966 -275.923956) (xy 408.581009 -275.873174) (xy 408.596897 -275.824275)
			(xy 408.62024 -275.778463) (xy 408.650461 -275.736867) (xy 408.686817 -275.700511) (xy 408.728413 -275.67029)
			(xy 408.774225 -275.646947) (xy 408.823124 -275.631059) (xy 408.873906 -275.623016) (xy 408.925322 -275.623016)
			(xy 408.976104 -275.631059) (xy 409.025003 -275.646947) (xy 409.070815 -275.67029) (xy 409.112411 -275.700511)
			(xy 409.148767 -275.736867) (xy 409.178988 -275.778463) (xy 409.202331 -275.824275) (xy 409.218219 -275.873174)
			(xy 409.226262 -275.923956) (xy 409.226766 -275.949664) (xy 409.226761 -275.949918) (xy 409.544024 -275.949918)
			(xy 409.547984 -275.900864) (xy 409.559761 -275.85308) (xy 409.579052 -275.807804) (xy 409.605355 -275.766208)
			(xy 409.63799 -275.729371) (xy 409.676111 -275.698246) (xy 409.718732 -275.673639) (xy 409.764748 -275.656187)
			(xy 409.812967 -275.646343) (xy 409.862142 -275.644362) (xy 409.910997 -275.650294) (xy 409.958268 -275.663986)
			(xy 410.00273 -275.685084) (xy 410.043233 -275.71304) (xy 410.078726 -275.747132) (xy 410.108291 -275.786476)
			(xy 410.131162 -275.830053) (xy 410.146746 -275.876734) (xy 410.154641 -275.925311) (xy 410.155136 -275.949918)
			(xy 410.154641 -275.974525) (xy 410.154462 -275.975626) (xy 410.472886 -275.975626) (xy 410.472886 -275.92421)
			(xy 410.480929 -275.873428) (xy 410.496817 -275.824529) (xy 410.52016 -275.778717) (xy 410.550381 -275.737121)
			(xy 410.586737 -275.700765) (xy 410.628333 -275.670544) (xy 410.674145 -275.647201) (xy 410.723044 -275.631313)
			(xy 410.773826 -275.62327) (xy 410.825242 -275.62327) (xy 410.876024 -275.631313) (xy 410.924923 -275.647201)
			(xy 410.970735 -275.670544) (xy 411.012331 -275.700765) (xy 411.048687 -275.737121) (xy 411.078908 -275.778717)
			(xy 411.102251 -275.824529) (xy 411.118139 -275.873428) (xy 411.126182 -275.92421) (xy 411.126686 -275.949918)
			(xy 411.444198 -275.949918) (xy 411.448158 -275.900864) (xy 411.459935 -275.85308) (xy 411.479226 -275.807804)
			(xy 411.505529 -275.766208) (xy 411.538164 -275.729371) (xy 411.576285 -275.698246) (xy 411.618906 -275.673639)
			(xy 411.664922 -275.656187) (xy 411.713141 -275.646343) (xy 411.762316 -275.644362) (xy 411.811171 -275.650294)
			(xy 411.858442 -275.663986) (xy 411.902904 -275.685084) (xy 411.943407 -275.71304) (xy 411.9789 -275.747132)
			(xy 412.008465 -275.786476) (xy 412.031336 -275.830053) (xy 412.04692 -275.876734) (xy 412.054815 -275.925311)
			(xy 412.05531 -275.949918) (xy 412.054815 -275.974525) (xy 412.054677 -275.975372) (xy 412.37306 -275.975372)
			(xy 412.37306 -275.923956) (xy 412.381103 -275.873174) (xy 412.396991 -275.824275) (xy 412.420334 -275.778463)
			(xy 412.450555 -275.736867) (xy 412.486911 -275.700511) (xy 412.528507 -275.67029) (xy 412.574319 -275.646947)
			(xy 412.623218 -275.631059) (xy 412.674 -275.623016) (xy 412.725416 -275.623016) (xy 412.776198 -275.631059)
			(xy 412.825097 -275.646947) (xy 412.870909 -275.67029) (xy 412.912505 -275.700511) (xy 412.948861 -275.736867)
			(xy 412.979082 -275.778463) (xy 413.002425 -275.824275) (xy 413.018313 -275.873174) (xy 413.026356 -275.923956)
			(xy 413.02686 -275.949664) (xy 413.026855 -275.949918) (xy 413.344118 -275.949918) (xy 413.348078 -275.900864)
			(xy 413.359855 -275.85308) (xy 413.379146 -275.807804) (xy 413.405449 -275.766208) (xy 413.438084 -275.729371)
			(xy 413.476205 -275.698246) (xy 413.518826 -275.673639) (xy 413.564842 -275.656187) (xy 413.613061 -275.646343)
			(xy 413.662236 -275.644362) (xy 413.711091 -275.650294) (xy 413.758362 -275.663986) (xy 413.802824 -275.685084)
			(xy 413.843327 -275.71304) (xy 413.87882 -275.747132) (xy 413.908385 -275.786476) (xy 413.931256 -275.830053)
			(xy 413.94684 -275.876734) (xy 413.954735 -275.925311) (xy 413.95523 -275.949918) (xy 413.954735 -275.974525)
			(xy 413.954556 -275.975626) (xy 414.27298 -275.975626) (xy 414.27298 -275.92421) (xy 414.281023 -275.873428)
			(xy 414.296911 -275.824529) (xy 414.320254 -275.778717) (xy 414.350475 -275.737121) (xy 414.386831 -275.700765)
			(xy 414.428427 -275.670544) (xy 414.474239 -275.647201) (xy 414.523138 -275.631313) (xy 414.57392 -275.62327)
			(xy 414.625336 -275.62327) (xy 414.676118 -275.631313) (xy 414.725017 -275.647201) (xy 414.770829 -275.670544)
			(xy 414.812425 -275.700765) (xy 414.848781 -275.737121) (xy 414.879002 -275.778717) (xy 414.902345 -275.824529)
			(xy 414.918233 -275.873428) (xy 414.926276 -275.92421) (xy 414.92678 -275.949918) (xy 415.244038 -275.949918)
			(xy 415.247998 -275.900864) (xy 415.259775 -275.85308) (xy 415.279066 -275.807804) (xy 415.305369 -275.766208)
			(xy 415.338004 -275.729371) (xy 415.376125 -275.698246) (xy 415.418746 -275.673639) (xy 415.464762 -275.656187)
			(xy 415.512981 -275.646343) (xy 415.562156 -275.644362) (xy 415.611011 -275.650294) (xy 415.658282 -275.663986)
			(xy 415.702744 -275.685084) (xy 415.743247 -275.71304) (xy 415.77874 -275.747132) (xy 415.808305 -275.786476)
			(xy 415.831176 -275.830053) (xy 415.84676 -275.876734) (xy 415.854655 -275.925311) (xy 415.85515 -275.949918)
			(xy 415.854655 -275.974525) (xy 415.854517 -275.975372) (xy 416.1729 -275.975372) (xy 416.1729 -275.923956)
			(xy 416.180943 -275.873174) (xy 416.196831 -275.824275) (xy 416.220174 -275.778463) (xy 416.250395 -275.736867)
			(xy 416.286751 -275.700511) (xy 416.328347 -275.67029) (xy 416.374159 -275.646947) (xy 416.423058 -275.631059)
			(xy 416.47384 -275.623016) (xy 416.525256 -275.623016) (xy 416.576038 -275.631059) (xy 416.624937 -275.646947)
			(xy 416.670749 -275.67029) (xy 416.712345 -275.700511) (xy 416.748701 -275.736867) (xy 416.778922 -275.778463)
			(xy 416.802265 -275.824275) (xy 416.818153 -275.873174) (xy 416.826196 -275.923956) (xy 416.8267 -275.949664)
			(xy 416.826695 -275.949918) (xy 417.144212 -275.949918) (xy 417.148172 -275.900864) (xy 417.159949 -275.85308)
			(xy 417.17924 -275.807804) (xy 417.205543 -275.766208) (xy 417.238178 -275.729371) (xy 417.276299 -275.698246)
			(xy 417.31892 -275.673639) (xy 417.364936 -275.656187) (xy 417.413155 -275.646343) (xy 417.46233 -275.644362)
			(xy 417.511185 -275.650294) (xy 417.558456 -275.663986) (xy 417.602918 -275.685084) (xy 417.643421 -275.71304)
			(xy 417.678914 -275.747132) (xy 417.708479 -275.786476) (xy 417.73135 -275.830053) (xy 417.746934 -275.876734)
			(xy 417.754829 -275.925311) (xy 417.755324 -275.949918) (xy 417.754829 -275.974525) (xy 417.75465 -275.975626)
			(xy 418.07282 -275.975626) (xy 418.07282 -275.92421) (xy 418.080863 -275.873428) (xy 418.096751 -275.824529)
			(xy 418.120094 -275.778717) (xy 418.150315 -275.737121) (xy 418.186671 -275.700765) (xy 418.228267 -275.670544)
			(xy 418.274079 -275.647201) (xy 418.322978 -275.631313) (xy 418.37376 -275.62327) (xy 418.425176 -275.62327)
			(xy 418.475958 -275.631313) (xy 418.524857 -275.647201) (xy 418.570669 -275.670544) (xy 418.612265 -275.700765)
			(xy 418.648621 -275.737121) (xy 418.678842 -275.778717) (xy 418.702185 -275.824529) (xy 418.718073 -275.873428)
			(xy 418.726116 -275.92421) (xy 418.72662 -275.949918) (xy 419.044132 -275.949918) (xy 419.048092 -275.900864)
			(xy 419.059869 -275.85308) (xy 419.07916 -275.807804) (xy 419.105463 -275.766208) (xy 419.138098 -275.729371)
			(xy 419.176219 -275.698246) (xy 419.21884 -275.673639) (xy 419.264856 -275.656187) (xy 419.313075 -275.646343)
			(xy 419.36225 -275.644362) (xy 419.411105 -275.650294) (xy 419.458376 -275.663986) (xy 419.502838 -275.685084)
			(xy 419.543341 -275.71304) (xy 419.578834 -275.747132) (xy 419.608399 -275.786476) (xy 419.63127 -275.830053)
			(xy 419.646854 -275.876734) (xy 419.654749 -275.925311) (xy 419.655244 -275.949918) (xy 419.654749 -275.974525)
			(xy 419.654611 -275.975372) (xy 419.972994 -275.975372) (xy 419.972994 -275.923956) (xy 419.981037 -275.873174)
			(xy 419.996925 -275.824275) (xy 420.020268 -275.778463) (xy 420.050489 -275.736867) (xy 420.086845 -275.700511)
			(xy 420.128441 -275.67029) (xy 420.174253 -275.646947) (xy 420.223152 -275.631059) (xy 420.273934 -275.623016)
			(xy 420.32535 -275.623016) (xy 420.376132 -275.631059) (xy 420.425031 -275.646947) (xy 420.470843 -275.67029)
			(xy 420.512439 -275.700511) (xy 420.548795 -275.736867) (xy 420.579016 -275.778463) (xy 420.602359 -275.824275)
			(xy 420.618247 -275.873174) (xy 420.62629 -275.923956) (xy 420.626794 -275.949664) (xy 420.626789 -275.949918)
			(xy 420.944052 -275.949918) (xy 420.948012 -275.900864) (xy 420.959789 -275.85308) (xy 420.97908 -275.807804)
			(xy 421.005383 -275.766208) (xy 421.038018 -275.729371) (xy 421.076139 -275.698246) (xy 421.11876 -275.673639)
			(xy 421.164776 -275.656187) (xy 421.212995 -275.646343) (xy 421.26217 -275.644362) (xy 421.311025 -275.650294)
			(xy 421.358296 -275.663986) (xy 421.402758 -275.685084) (xy 421.443261 -275.71304) (xy 421.478754 -275.747132)
			(xy 421.508319 -275.786476) (xy 421.53119 -275.830053) (xy 421.546774 -275.876734) (xy 421.554669 -275.925311)
			(xy 421.555164 -275.949918) (xy 421.554669 -275.974525) (xy 421.55449 -275.975626) (xy 421.872914 -275.975626)
			(xy 421.872914 -275.92421) (xy 421.880957 -275.873428) (xy 421.896845 -275.824529) (xy 421.920188 -275.778717)
			(xy 421.950409 -275.737121) (xy 421.986765 -275.700765) (xy 422.028361 -275.670544) (xy 422.074173 -275.647201)
			(xy 422.123072 -275.631313) (xy 422.173854 -275.62327) (xy 422.22527 -275.62327) (xy 422.276052 -275.631313)
			(xy 422.324951 -275.647201) (xy 422.370763 -275.670544) (xy 422.412359 -275.700765) (xy 422.448715 -275.737121)
			(xy 422.478936 -275.778717) (xy 422.502279 -275.824529) (xy 422.518167 -275.873428) (xy 422.52621 -275.92421)
			(xy 422.526714 -275.949918) (xy 422.844226 -275.949918) (xy 422.848186 -275.900864) (xy 422.859963 -275.85308)
			(xy 422.879254 -275.807804) (xy 422.905557 -275.766208) (xy 422.938192 -275.729371) (xy 422.976313 -275.698246)
			(xy 423.018934 -275.673639) (xy 423.06495 -275.656187) (xy 423.113169 -275.646343) (xy 423.162344 -275.644362)
			(xy 423.211199 -275.650294) (xy 423.25847 -275.663986) (xy 423.302932 -275.685084) (xy 423.343435 -275.71304)
			(xy 423.378928 -275.747132) (xy 423.408493 -275.786476) (xy 423.431364 -275.830053) (xy 423.446948 -275.876734)
			(xy 423.454843 -275.925311) (xy 423.455338 -275.949918) (xy 423.454843 -275.974525) (xy 423.454705 -275.975372)
			(xy 423.773088 -275.975372) (xy 423.773088 -275.923956) (xy 423.781131 -275.873174) (xy 423.797019 -275.824275)
			(xy 423.820362 -275.778463) (xy 423.850583 -275.736867) (xy 423.886939 -275.700511) (xy 423.928535 -275.67029)
			(xy 423.974347 -275.646947) (xy 424.023246 -275.631059) (xy 424.074028 -275.623016) (xy 424.125444 -275.623016)
			(xy 424.176226 -275.631059) (xy 424.225125 -275.646947) (xy 424.270937 -275.67029) (xy 424.312533 -275.700511)
			(xy 424.348889 -275.736867) (xy 424.37911 -275.778463) (xy 424.402453 -275.824275) (xy 424.418341 -275.873174)
			(xy 424.426384 -275.923956) (xy 424.426888 -275.949664) (xy 424.426883 -275.949918) (xy 424.744146 -275.949918)
			(xy 424.748106 -275.900864) (xy 424.759883 -275.85308) (xy 424.779174 -275.807804) (xy 424.805477 -275.766208)
			(xy 424.838112 -275.729371) (xy 424.876233 -275.698246) (xy 424.918854 -275.673639) (xy 424.96487 -275.656187)
			(xy 425.013089 -275.646343) (xy 425.062264 -275.644362) (xy 425.111119 -275.650294) (xy 425.15839 -275.663986)
			(xy 425.202852 -275.685084) (xy 425.243355 -275.71304) (xy 425.278848 -275.747132) (xy 425.308413 -275.786476)
			(xy 425.331284 -275.830053) (xy 425.346868 -275.876734) (xy 425.354763 -275.925311) (xy 425.355258 -275.949918)
			(xy 425.354763 -275.974525) (xy 425.354584 -275.975626) (xy 425.673008 -275.975626) (xy 425.673008 -275.92421)
			(xy 425.681051 -275.873428) (xy 425.696939 -275.824529) (xy 425.720282 -275.778717) (xy 425.750503 -275.737121)
			(xy 425.786859 -275.700765) (xy 425.828455 -275.670544) (xy 425.874267 -275.647201) (xy 425.923166 -275.631313)
			(xy 425.973948 -275.62327) (xy 426.025364 -275.62327) (xy 426.076146 -275.631313) (xy 426.125045 -275.647201)
			(xy 426.170857 -275.670544) (xy 426.212453 -275.700765) (xy 426.248809 -275.737121) (xy 426.27903 -275.778717)
			(xy 426.302373 -275.824529) (xy 426.318261 -275.873428) (xy 426.326304 -275.92421) (xy 426.326808 -275.949918)
			(xy 426.644066 -275.949918) (xy 426.648026 -275.900864) (xy 426.659803 -275.85308) (xy 426.679094 -275.807804)
			(xy 426.705397 -275.766208) (xy 426.738032 -275.729371) (xy 426.776153 -275.698246) (xy 426.818774 -275.673639)
			(xy 426.86479 -275.656187) (xy 426.913009 -275.646343) (xy 426.962184 -275.644362) (xy 427.011039 -275.650294)
			(xy 427.05831 -275.663986) (xy 427.102772 -275.685084) (xy 427.143275 -275.71304) (xy 427.178768 -275.747132)
			(xy 427.208333 -275.786476) (xy 427.231204 -275.830053) (xy 427.246788 -275.876734) (xy 427.254683 -275.925311)
			(xy 427.255178 -275.949918) (xy 427.254683 -275.974525) (xy 427.254504 -275.975626) (xy 427.572928 -275.975626)
			(xy 427.572928 -275.92421) (xy 427.580971 -275.873428) (xy 427.596859 -275.824529) (xy 427.620202 -275.778717)
			(xy 427.650423 -275.737121) (xy 427.686779 -275.700765) (xy 427.728375 -275.670544) (xy 427.774187 -275.647201)
			(xy 427.823086 -275.631313) (xy 427.873868 -275.62327) (xy 427.925284 -275.62327) (xy 427.976066 -275.631313)
			(xy 428.024965 -275.647201) (xy 428.070777 -275.670544) (xy 428.112373 -275.700765) (xy 428.148729 -275.737121)
			(xy 428.17895 -275.778717) (xy 428.202293 -275.824529) (xy 428.218181 -275.873428) (xy 428.226224 -275.92421)
			(xy 428.226728 -275.949918) (xy 428.54424 -275.949918) (xy 428.5482 -275.900864) (xy 428.559977 -275.85308)
			(xy 428.579268 -275.807804) (xy 428.605571 -275.766208) (xy 428.638206 -275.729371) (xy 428.676327 -275.698246)
			(xy 428.718948 -275.673639) (xy 428.764964 -275.656187) (xy 428.813183 -275.646343) (xy 428.862358 -275.644362)
			(xy 428.911213 -275.650294) (xy 428.958484 -275.663986) (xy 429.002946 -275.685084) (xy 429.043449 -275.71304)
			(xy 429.078942 -275.747132) (xy 429.108507 -275.786476) (xy 429.131378 -275.830053) (xy 429.146962 -275.876734)
			(xy 429.154857 -275.925311) (xy 429.155352 -275.949918) (xy 429.4942 -275.949918) (xy 429.49816 -275.900864)
			(xy 429.509937 -275.85308) (xy 429.529228 -275.807804) (xy 429.555531 -275.766208) (xy 429.588166 -275.729371)
			(xy 429.626287 -275.698246) (xy 429.668908 -275.673639) (xy 429.714924 -275.656187) (xy 429.763143 -275.646343)
			(xy 429.812318 -275.644362) (xy 429.861173 -275.650294) (xy 429.908444 -275.663986) (xy 429.952906 -275.685084)
			(xy 429.993409 -275.71304) (xy 430.028902 -275.747132) (xy 430.058467 -275.786476) (xy 430.081338 -275.830053)
			(xy 430.096922 -275.876734) (xy 430.104817 -275.925311) (xy 430.105312 -275.949918) (xy 430.44416 -275.949918)
			(xy 430.44812 -275.900864) (xy 430.459897 -275.85308) (xy 430.479188 -275.807804) (xy 430.505491 -275.766208)
			(xy 430.538126 -275.729371) (xy 430.576247 -275.698246) (xy 430.618868 -275.673639) (xy 430.664884 -275.656187)
			(xy 430.713103 -275.646343) (xy 430.762278 -275.644362) (xy 430.811133 -275.650294) (xy 430.858404 -275.663986)
			(xy 430.902866 -275.685084) (xy 430.943369 -275.71304) (xy 430.978862 -275.747132) (xy 431.008427 -275.786476)
			(xy 431.031298 -275.830053) (xy 431.046882 -275.876734) (xy 431.054777 -275.925311) (xy 431.055272 -275.949918)
			(xy 431.054777 -275.974525) (xy 431.046882 -276.023102) (xy 431.031298 -276.069783) (xy 431.008427 -276.11336)
			(xy 430.978862 -276.152704) (xy 430.943369 -276.186796) (xy 430.902866 -276.214752) (xy 430.858404 -276.23585)
			(xy 430.811133 -276.249542) (xy 430.762278 -276.255474) (xy 430.713103 -276.253493) (xy 430.664884 -276.243649)
			(xy 430.618868 -276.226197) (xy 430.576247 -276.20159) (xy 430.538126 -276.170465) (xy 430.505491 -276.133628)
			(xy 430.479188 -276.092032) (xy 430.459897 -276.046756) (xy 430.44812 -275.998972) (xy 430.44416 -275.949918)
			(xy 430.105312 -275.949918) (xy 430.104817 -275.974525) (xy 430.096922 -276.023102) (xy 430.081338 -276.069783)
			(xy 430.058467 -276.11336) (xy 430.028902 -276.152704) (xy 429.993409 -276.186796) (xy 429.952906 -276.214752)
			(xy 429.908444 -276.23585) (xy 429.861173 -276.249542) (xy 429.812318 -276.255474) (xy 429.763143 -276.253493)
			(xy 429.714924 -276.243649) (xy 429.668908 -276.226197) (xy 429.626287 -276.20159) (xy 429.588166 -276.170465)
			(xy 429.555531 -276.133628) (xy 429.529228 -276.092032) (xy 429.509937 -276.046756) (xy 429.49816 -275.998972)
			(xy 429.4942 -275.949918) (xy 429.155352 -275.949918) (xy 429.154857 -275.974525) (xy 429.146962 -276.023102)
			(xy 429.131378 -276.069783) (xy 429.108507 -276.11336) (xy 429.078942 -276.152704) (xy 429.043449 -276.186796)
			(xy 429.002946 -276.214752) (xy 428.958484 -276.23585) (xy 428.911213 -276.249542) (xy 428.862358 -276.255474)
			(xy 428.813183 -276.253493) (xy 428.764964 -276.243649) (xy 428.718948 -276.226197) (xy 428.676327 -276.20159)
			(xy 428.638206 -276.170465) (xy 428.605571 -276.133628) (xy 428.579268 -276.092032) (xy 428.559977 -276.046756)
			(xy 428.5482 -275.998972) (xy 428.54424 -275.949918) (xy 428.226728 -275.949918) (xy 428.226224 -275.975626)
			(xy 428.218181 -276.026408) (xy 428.202293 -276.075307) (xy 428.17895 -276.121119) (xy 428.148729 -276.162715)
			(xy 428.112373 -276.199071) (xy 428.070777 -276.229292) (xy 428.024965 -276.252635) (xy 427.976066 -276.268523)
			(xy 427.925284 -276.276566) (xy 427.873868 -276.276566) (xy 427.823086 -276.268523) (xy 427.774187 -276.252635)
			(xy 427.728375 -276.229292) (xy 427.686779 -276.199071) (xy 427.650423 -276.162715) (xy 427.620202 -276.121119)
			(xy 427.596859 -276.075307) (xy 427.580971 -276.026408) (xy 427.572928 -275.975626) (xy 427.254504 -275.975626)
			(xy 427.246788 -276.023102) (xy 427.231204 -276.069783) (xy 427.208333 -276.11336) (xy 427.178768 -276.152704)
			(xy 427.143275 -276.186796) (xy 427.102772 -276.214752) (xy 427.05831 -276.23585) (xy 427.011039 -276.249542)
			(xy 426.962184 -276.255474) (xy 426.913009 -276.253493) (xy 426.86479 -276.243649) (xy 426.818774 -276.226197)
			(xy 426.776153 -276.20159) (xy 426.738032 -276.170465) (xy 426.705397 -276.133628) (xy 426.679094 -276.092032)
			(xy 426.659803 -276.046756) (xy 426.648026 -275.998972) (xy 426.644066 -275.949918) (xy 426.326808 -275.949918)
			(xy 426.326304 -275.975626) (xy 426.318261 -276.026408) (xy 426.302373 -276.075307) (xy 426.27903 -276.121119)
			(xy 426.248809 -276.162715) (xy 426.212453 -276.199071) (xy 426.170857 -276.229292) (xy 426.125045 -276.252635)
			(xy 426.076146 -276.268523) (xy 426.025364 -276.276566) (xy 425.973948 -276.276566) (xy 425.923166 -276.268523)
			(xy 425.874267 -276.252635) (xy 425.828455 -276.229292) (xy 425.786859 -276.199071) (xy 425.750503 -276.162715)
			(xy 425.720282 -276.121119) (xy 425.696939 -276.075307) (xy 425.681051 -276.026408) (xy 425.673008 -275.975626)
			(xy 425.354584 -275.975626) (xy 425.346868 -276.023102) (xy 425.331284 -276.069783) (xy 425.308413 -276.11336)
			(xy 425.278848 -276.152704) (xy 425.243355 -276.186796) (xy 425.202852 -276.214752) (xy 425.15839 -276.23585)
			(xy 425.111119 -276.249542) (xy 425.062264 -276.255474) (xy 425.013089 -276.253493) (xy 424.96487 -276.243649)
			(xy 424.918854 -276.226197) (xy 424.876233 -276.20159) (xy 424.838112 -276.170465) (xy 424.805477 -276.133628)
			(xy 424.779174 -276.092032) (xy 424.759883 -276.046756) (xy 424.748106 -275.998972) (xy 424.744146 -275.949918)
			(xy 424.426883 -275.949918) (xy 424.426384 -275.975372) (xy 424.418341 -276.026154) (xy 424.402453 -276.075053)
			(xy 424.37911 -276.120865) (xy 424.348889 -276.162461) (xy 424.312533 -276.198817) (xy 424.270937 -276.229038)
			(xy 424.225125 -276.252381) (xy 424.176226 -276.268269) (xy 424.125444 -276.276312) (xy 424.074028 -276.276312)
			(xy 424.023246 -276.268269) (xy 423.974347 -276.252381) (xy 423.928535 -276.229038) (xy 423.886939 -276.198817)
			(xy 423.850583 -276.162461) (xy 423.820362 -276.120865) (xy 423.797019 -276.075053) (xy 423.781131 -276.026154)
			(xy 423.773088 -275.975372) (xy 423.454705 -275.975372) (xy 423.446948 -276.023102) (xy 423.431364 -276.069783)
			(xy 423.408493 -276.11336) (xy 423.378928 -276.152704) (xy 423.343435 -276.186796) (xy 423.302932 -276.214752)
			(xy 423.25847 -276.23585) (xy 423.211199 -276.249542) (xy 423.162344 -276.255474) (xy 423.113169 -276.253493)
			(xy 423.06495 -276.243649) (xy 423.018934 -276.226197) (xy 422.976313 -276.20159) (xy 422.938192 -276.170465)
			(xy 422.905557 -276.133628) (xy 422.879254 -276.092032) (xy 422.859963 -276.046756) (xy 422.848186 -275.998972)
			(xy 422.844226 -275.949918) (xy 422.526714 -275.949918) (xy 422.52621 -275.975626) (xy 422.518167 -276.026408)
			(xy 422.502279 -276.075307) (xy 422.478936 -276.121119) (xy 422.448715 -276.162715) (xy 422.412359 -276.199071)
			(xy 422.370763 -276.229292) (xy 422.324951 -276.252635) (xy 422.276052 -276.268523) (xy 422.22527 -276.276566)
			(xy 422.173854 -276.276566) (xy 422.123072 -276.268523) (xy 422.074173 -276.252635) (xy 422.028361 -276.229292)
			(xy 421.986765 -276.199071) (xy 421.950409 -276.162715) (xy 421.920188 -276.121119) (xy 421.896845 -276.075307)
			(xy 421.880957 -276.026408) (xy 421.872914 -275.975626) (xy 421.55449 -275.975626) (xy 421.546774 -276.023102)
			(xy 421.53119 -276.069783) (xy 421.508319 -276.11336) (xy 421.478754 -276.152704) (xy 421.443261 -276.186796)
			(xy 421.402758 -276.214752) (xy 421.358296 -276.23585) (xy 421.311025 -276.249542) (xy 421.26217 -276.255474)
			(xy 421.212995 -276.253493) (xy 421.164776 -276.243649) (xy 421.11876 -276.226197) (xy 421.076139 -276.20159)
			(xy 421.038018 -276.170465) (xy 421.005383 -276.133628) (xy 420.97908 -276.092032) (xy 420.959789 -276.046756)
			(xy 420.948012 -275.998972) (xy 420.944052 -275.949918) (xy 420.626789 -275.949918) (xy 420.62629 -275.975372)
			(xy 420.618247 -276.026154) (xy 420.602359 -276.075053) (xy 420.579016 -276.120865) (xy 420.548795 -276.162461)
			(xy 420.512439 -276.198817) (xy 420.470843 -276.229038) (xy 420.425031 -276.252381) (xy 420.376132 -276.268269)
			(xy 420.32535 -276.276312) (xy 420.273934 -276.276312) (xy 420.223152 -276.268269) (xy 420.174253 -276.252381)
			(xy 420.128441 -276.229038) (xy 420.086845 -276.198817) (xy 420.050489 -276.162461) (xy 420.020268 -276.120865)
			(xy 419.996925 -276.075053) (xy 419.981037 -276.026154) (xy 419.972994 -275.975372) (xy 419.654611 -275.975372)
			(xy 419.646854 -276.023102) (xy 419.63127 -276.069783) (xy 419.608399 -276.11336) (xy 419.578834 -276.152704)
			(xy 419.543341 -276.186796) (xy 419.502838 -276.214752) (xy 419.458376 -276.23585) (xy 419.411105 -276.249542)
			(xy 419.36225 -276.255474) (xy 419.313075 -276.253493) (xy 419.264856 -276.243649) (xy 419.21884 -276.226197)
			(xy 419.176219 -276.20159) (xy 419.138098 -276.170465) (xy 419.105463 -276.133628) (xy 419.07916 -276.092032)
			(xy 419.059869 -276.046756) (xy 419.048092 -275.998972) (xy 419.044132 -275.949918) (xy 418.72662 -275.949918)
			(xy 418.726116 -275.975626) (xy 418.718073 -276.026408) (xy 418.702185 -276.075307) (xy 418.678842 -276.121119)
			(xy 418.648621 -276.162715) (xy 418.612265 -276.199071) (xy 418.570669 -276.229292) (xy 418.524857 -276.252635)
			(xy 418.475958 -276.268523) (xy 418.425176 -276.276566) (xy 418.37376 -276.276566) (xy 418.322978 -276.268523)
			(xy 418.274079 -276.252635) (xy 418.228267 -276.229292) (xy 418.186671 -276.199071) (xy 418.150315 -276.162715)
			(xy 418.120094 -276.121119) (xy 418.096751 -276.075307) (xy 418.080863 -276.026408) (xy 418.07282 -275.975626)
			(xy 417.75465 -275.975626) (xy 417.746934 -276.023102) (xy 417.73135 -276.069783) (xy 417.708479 -276.11336)
			(xy 417.678914 -276.152704) (xy 417.643421 -276.186796) (xy 417.602918 -276.214752) (xy 417.558456 -276.23585)
			(xy 417.511185 -276.249542) (xy 417.46233 -276.255474) (xy 417.413155 -276.253493) (xy 417.364936 -276.243649)
			(xy 417.31892 -276.226197) (xy 417.276299 -276.20159) (xy 417.238178 -276.170465) (xy 417.205543 -276.133628)
			(xy 417.17924 -276.092032) (xy 417.159949 -276.046756) (xy 417.148172 -275.998972) (xy 417.144212 -275.949918)
			(xy 416.826695 -275.949918) (xy 416.826196 -275.975372) (xy 416.818153 -276.026154) (xy 416.802265 -276.075053)
			(xy 416.778922 -276.120865) (xy 416.748701 -276.162461) (xy 416.712345 -276.198817) (xy 416.670749 -276.229038)
			(xy 416.624937 -276.252381) (xy 416.576038 -276.268269) (xy 416.525256 -276.276312) (xy 416.47384 -276.276312)
			(xy 416.423058 -276.268269) (xy 416.374159 -276.252381) (xy 416.328347 -276.229038) (xy 416.286751 -276.198817)
			(xy 416.250395 -276.162461) (xy 416.220174 -276.120865) (xy 416.196831 -276.075053) (xy 416.180943 -276.026154)
			(xy 416.1729 -275.975372) (xy 415.854517 -275.975372) (xy 415.84676 -276.023102) (xy 415.831176 -276.069783)
			(xy 415.808305 -276.11336) (xy 415.77874 -276.152704) (xy 415.743247 -276.186796) (xy 415.702744 -276.214752)
			(xy 415.658282 -276.23585) (xy 415.611011 -276.249542) (xy 415.562156 -276.255474) (xy 415.512981 -276.253493)
			(xy 415.464762 -276.243649) (xy 415.418746 -276.226197) (xy 415.376125 -276.20159) (xy 415.338004 -276.170465)
			(xy 415.305369 -276.133628) (xy 415.279066 -276.092032) (xy 415.259775 -276.046756) (xy 415.247998 -275.998972)
			(xy 415.244038 -275.949918) (xy 414.92678 -275.949918) (xy 414.926276 -275.975626) (xy 414.918233 -276.026408)
			(xy 414.902345 -276.075307) (xy 414.879002 -276.121119) (xy 414.848781 -276.162715) (xy 414.812425 -276.199071)
			(xy 414.770829 -276.229292) (xy 414.725017 -276.252635) (xy 414.676118 -276.268523) (xy 414.625336 -276.276566)
			(xy 414.57392 -276.276566) (xy 414.523138 -276.268523) (xy 414.474239 -276.252635) (xy 414.428427 -276.229292)
			(xy 414.386831 -276.199071) (xy 414.350475 -276.162715) (xy 414.320254 -276.121119) (xy 414.296911 -276.075307)
			(xy 414.281023 -276.026408) (xy 414.27298 -275.975626) (xy 413.954556 -275.975626) (xy 413.94684 -276.023102)
			(xy 413.931256 -276.069783) (xy 413.908385 -276.11336) (xy 413.87882 -276.152704) (xy 413.843327 -276.186796)
			(xy 413.802824 -276.214752) (xy 413.758362 -276.23585) (xy 413.711091 -276.249542) (xy 413.662236 -276.255474)
			(xy 413.613061 -276.253493) (xy 413.564842 -276.243649) (xy 413.518826 -276.226197) (xy 413.476205 -276.20159)
			(xy 413.438084 -276.170465) (xy 413.405449 -276.133628) (xy 413.379146 -276.092032) (xy 413.359855 -276.046756)
			(xy 413.348078 -275.998972) (xy 413.344118 -275.949918) (xy 413.026855 -275.949918) (xy 413.026356 -275.975372)
			(xy 413.018313 -276.026154) (xy 413.002425 -276.075053) (xy 412.979082 -276.120865) (xy 412.948861 -276.162461)
			(xy 412.912505 -276.198817) (xy 412.870909 -276.229038) (xy 412.825097 -276.252381) (xy 412.776198 -276.268269)
			(xy 412.725416 -276.276312) (xy 412.674 -276.276312) (xy 412.623218 -276.268269) (xy 412.574319 -276.252381)
			(xy 412.528507 -276.229038) (xy 412.486911 -276.198817) (xy 412.450555 -276.162461) (xy 412.420334 -276.120865)
			(xy 412.396991 -276.075053) (xy 412.381103 -276.026154) (xy 412.37306 -275.975372) (xy 412.054677 -275.975372)
			(xy 412.04692 -276.023102) (xy 412.031336 -276.069783) (xy 412.008465 -276.11336) (xy 411.9789 -276.152704)
			(xy 411.943407 -276.186796) (xy 411.902904 -276.214752) (xy 411.858442 -276.23585) (xy 411.811171 -276.249542)
			(xy 411.762316 -276.255474) (xy 411.713141 -276.253493) (xy 411.664922 -276.243649) (xy 411.618906 -276.226197)
			(xy 411.576285 -276.20159) (xy 411.538164 -276.170465) (xy 411.505529 -276.133628) (xy 411.479226 -276.092032)
			(xy 411.459935 -276.046756) (xy 411.448158 -275.998972) (xy 411.444198 -275.949918) (xy 411.126686 -275.949918)
			(xy 411.126182 -275.975626) (xy 411.118139 -276.026408) (xy 411.102251 -276.075307) (xy 411.078908 -276.121119)
			(xy 411.048687 -276.162715) (xy 411.012331 -276.199071) (xy 410.970735 -276.229292) (xy 410.924923 -276.252635)
			(xy 410.876024 -276.268523) (xy 410.825242 -276.276566) (xy 410.773826 -276.276566) (xy 410.723044 -276.268523)
			(xy 410.674145 -276.252635) (xy 410.628333 -276.229292) (xy 410.586737 -276.199071) (xy 410.550381 -276.162715)
			(xy 410.52016 -276.121119) (xy 410.496817 -276.075307) (xy 410.480929 -276.026408) (xy 410.472886 -275.975626)
			(xy 410.154462 -275.975626) (xy 410.146746 -276.023102) (xy 410.131162 -276.069783) (xy 410.108291 -276.11336)
			(xy 410.078726 -276.152704) (xy 410.043233 -276.186796) (xy 410.00273 -276.214752) (xy 409.958268 -276.23585)
			(xy 409.910997 -276.249542) (xy 409.862142 -276.255474) (xy 409.812967 -276.253493) (xy 409.764748 -276.243649)
			(xy 409.718732 -276.226197) (xy 409.676111 -276.20159) (xy 409.63799 -276.170465) (xy 409.605355 -276.133628)
			(xy 409.579052 -276.092032) (xy 409.559761 -276.046756) (xy 409.547984 -275.998972) (xy 409.544024 -275.949918)
			(xy 409.226761 -275.949918) (xy 409.226262 -275.975372) (xy 409.218219 -276.026154) (xy 409.202331 -276.075053)
			(xy 409.178988 -276.120865) (xy 409.148767 -276.162461) (xy 409.112411 -276.198817) (xy 409.070815 -276.229038)
			(xy 409.025003 -276.252381) (xy 408.976104 -276.268269) (xy 408.925322 -276.276312) (xy 408.873906 -276.276312)
			(xy 408.823124 -276.268269) (xy 408.774225 -276.252381) (xy 408.728413 -276.229038) (xy 408.686817 -276.198817)
			(xy 408.650461 -276.162461) (xy 408.62024 -276.120865) (xy 408.596897 -276.075053) (xy 408.581009 -276.026154)
			(xy 408.572966 -275.975372) (xy 408.254583 -275.975372) (xy 408.246826 -276.023102) (xy 408.231242 -276.069783)
			(xy 408.208371 -276.11336) (xy 408.178806 -276.152704) (xy 408.143313 -276.186796) (xy 408.10281 -276.214752)
			(xy 408.058348 -276.23585) (xy 408.011077 -276.249542) (xy 407.962222 -276.255474) (xy 407.913047 -276.253493)
			(xy 407.864828 -276.243649) (xy 407.818812 -276.226197) (xy 407.776191 -276.20159) (xy 407.73807 -276.170465)
			(xy 407.705435 -276.133628) (xy 407.679132 -276.092032) (xy 407.659841 -276.046756) (xy 407.648064 -275.998972)
			(xy 407.644104 -275.949918) (xy 407.3271 -275.949918) (xy 407.326596 -275.975626) (xy 407.318553 -276.026408)
			(xy 407.302665 -276.075307) (xy 407.279322 -276.121119) (xy 407.249101 -276.162715) (xy 407.212745 -276.199071)
			(xy 407.171149 -276.229292) (xy 407.125337 -276.252635) (xy 407.076438 -276.268523) (xy 407.025656 -276.276566)
			(xy 406.97424 -276.276566) (xy 406.923458 -276.268523) (xy 406.874559 -276.252635) (xy 406.828747 -276.229292)
			(xy 406.787151 -276.199071) (xy 406.750795 -276.162715) (xy 406.720574 -276.121119) (xy 406.697231 -276.075307)
			(xy 406.681343 -276.026408) (xy 406.6733 -275.975626) (xy 406.354622 -275.975626) (xy 406.346906 -276.023102)
			(xy 406.331322 -276.069783) (xy 406.308451 -276.11336) (xy 406.278886 -276.152704) (xy 406.243393 -276.186796)
			(xy 406.20289 -276.214752) (xy 406.158428 -276.23585) (xy 406.111157 -276.249542) (xy 406.062302 -276.255474)
			(xy 406.013127 -276.253493) (xy 405.964908 -276.243649) (xy 405.918892 -276.226197) (xy 405.876271 -276.20159)
			(xy 405.83815 -276.170465) (xy 405.805515 -276.133628) (xy 405.779212 -276.092032) (xy 405.759921 -276.046756)
			(xy 405.748144 -275.998972) (xy 405.744184 -275.949918) (xy 405.42718 -275.949918) (xy 405.426676 -275.975626)
			(xy 405.418633 -276.026408) (xy 405.402745 -276.075307) (xy 405.379402 -276.121119) (xy 405.349181 -276.162715)
			(xy 405.312825 -276.199071) (xy 405.271229 -276.229292) (xy 405.225417 -276.252635) (xy 405.176518 -276.268523)
			(xy 405.125736 -276.276566) (xy 405.07432 -276.276566) (xy 405.023538 -276.268523) (xy 404.974639 -276.252635)
			(xy 404.928827 -276.229292) (xy 404.887231 -276.199071) (xy 404.850875 -276.162715) (xy 404.820654 -276.121119)
			(xy 404.797311 -276.075307) (xy 404.781423 -276.026408) (xy 404.77338 -275.975626) (xy 404.454448 -275.975626)
			(xy 404.446732 -276.023102) (xy 404.431148 -276.069783) (xy 404.408277 -276.11336) (xy 404.378712 -276.152704)
			(xy 404.343219 -276.186796) (xy 404.302716 -276.214752) (xy 404.258254 -276.23585) (xy 404.210983 -276.249542)
			(xy 404.162128 -276.255474) (xy 404.112953 -276.253493) (xy 404.064734 -276.243649) (xy 404.018718 -276.226197)
			(xy 403.976097 -276.20159) (xy 403.937976 -276.170465) (xy 403.905341 -276.133628) (xy 403.879038 -276.092032)
			(xy 403.859747 -276.046756) (xy 403.84797 -275.998972) (xy 403.84401 -275.949918) (xy 403.527006 -275.949918)
			(xy 403.526502 -275.975626) (xy 403.518459 -276.026408) (xy 403.502571 -276.075307) (xy 403.479228 -276.121119)
			(xy 403.449007 -276.162715) (xy 403.412651 -276.199071) (xy 403.371055 -276.229292) (xy 403.325243 -276.252635)
			(xy 403.276344 -276.268523) (xy 403.225562 -276.276566) (xy 403.174146 -276.276566) (xy 403.123364 -276.268523)
			(xy 403.074465 -276.252635) (xy 403.028653 -276.229292) (xy 402.987057 -276.199071) (xy 402.950701 -276.162715)
			(xy 402.92048 -276.121119) (xy 402.897137 -276.075307) (xy 402.881249 -276.026408) (xy 402.873206 -275.975626)
			(xy 402.554528 -275.975626) (xy 402.546812 -276.023102) (xy 402.531228 -276.069783) (xy 402.508357 -276.11336)
			(xy 402.478792 -276.152704) (xy 402.443299 -276.186796) (xy 402.402796 -276.214752) (xy 402.358334 -276.23585)
			(xy 402.311063 -276.249542) (xy 402.262208 -276.255474) (xy 402.213033 -276.253493) (xy 402.164814 -276.243649)
			(xy 402.118798 -276.226197) (xy 402.076177 -276.20159) (xy 402.038056 -276.170465) (xy 402.005421 -276.133628)
			(xy 401.979118 -276.092032) (xy 401.959827 -276.046756) (xy 401.94805 -275.998972) (xy 401.94409 -275.949918)
			(xy 401.627086 -275.949918) (xy 401.626582 -275.975626) (xy 401.618539 -276.026408) (xy 401.602651 -276.075307)
			(xy 401.579308 -276.121119) (xy 401.549087 -276.162715) (xy 401.512731 -276.199071) (xy 401.471135 -276.229292)
			(xy 401.425323 -276.252635) (xy 401.376424 -276.268523) (xy 401.325642 -276.276566) (xy 401.274226 -276.276566)
			(xy 401.223444 -276.268523) (xy 401.174545 -276.252635) (xy 401.128733 -276.229292) (xy 401.087137 -276.199071)
			(xy 401.050781 -276.162715) (xy 401.02056 -276.121119) (xy 400.997217 -276.075307) (xy 400.981329 -276.026408)
			(xy 400.973286 -275.975626) (xy 400.654608 -275.975626) (xy 400.646892 -276.023102) (xy 400.631308 -276.069783)
			(xy 400.608437 -276.11336) (xy 400.578872 -276.152704) (xy 400.543379 -276.186796) (xy 400.502876 -276.214752)
			(xy 400.458414 -276.23585) (xy 400.411143 -276.249542) (xy 400.362288 -276.255474) (xy 400.313113 -276.253493)
			(xy 400.264894 -276.243649) (xy 400.218878 -276.226197) (xy 400.176257 -276.20159) (xy 400.138136 -276.170465)
			(xy 400.105501 -276.133628) (xy 400.079198 -276.092032) (xy 400.059907 -276.046756) (xy 400.04813 -275.998972)
			(xy 400.04417 -275.949918) (xy 399.727166 -275.949918) (xy 399.726662 -275.975626) (xy 399.718619 -276.026408)
			(xy 399.702731 -276.075307) (xy 399.679388 -276.121119) (xy 399.649167 -276.162715) (xy 399.612811 -276.199071)
			(xy 399.571215 -276.229292) (xy 399.525403 -276.252635) (xy 399.476504 -276.268523) (xy 399.425722 -276.276566)
			(xy 399.374306 -276.276566) (xy 399.323524 -276.268523) (xy 399.274625 -276.252635) (xy 399.228813 -276.229292)
			(xy 399.187217 -276.199071) (xy 399.150861 -276.162715) (xy 399.12064 -276.121119) (xy 399.097297 -276.075307)
			(xy 399.081409 -276.026408) (xy 399.073366 -275.975626) (xy 398.753481 -275.975626) (xy 398.751442 -276.000235)
			(xy 398.739043 -276.049197) (xy 398.718755 -276.095451) (xy 398.691129 -276.137734) (xy 398.656922 -276.174894)
			(xy 398.617064 -276.205916) (xy 398.572644 -276.229955) (xy 398.524873 -276.246355) (xy 398.475054 -276.254668)
			(xy 398.4498 -276.255226) (xy 398.435618 -276.255039) (xy 398.407378 -276.252366) (xy 398.393412 -276.249892)
			(xy 398.380966 -276.247606) (xy 398.357344 -276.254972) (xy 398.279874 -276.332442) (xy 398.272508 -276.356064)
			(xy 398.274794 -276.36851) (xy 398.277279 -276.382475) (xy 398.279951 -276.410715) (xy 398.280128 -276.424898)
			(xy 398.279942 -276.43908) (xy 398.277268 -276.46732) (xy 398.274794 -276.481286) (xy 398.272508 -276.493732)
			(xy 398.279874 -276.517354) (xy 398.357344 -276.594824) (xy 398.380966 -276.60219) (xy 398.393412 -276.599904)
			(xy 398.407377 -276.597419) (xy 398.435617 -276.594747) (xy 398.4498 -276.59457) (xy 398.475057 -276.595092)
			(xy 398.524882 -276.603406) (xy 398.57266 -276.619808) (xy 398.617086 -276.64385) (xy 398.656949 -276.674877)
			(xy 398.691161 -276.712041) (xy 398.71879 -276.75433) (xy 398.739081 -276.80059) (xy 398.751482 -276.849558)
			(xy 398.755651 -276.899878) (xy 399.09421 -276.899878) (xy 399.09817 -276.850824) (xy 399.109947 -276.80304)
			(xy 399.129238 -276.757764) (xy 399.155541 -276.716168) (xy 399.188176 -276.679331) (xy 399.226297 -276.648206)
			(xy 399.268918 -276.623599) (xy 399.314934 -276.606147) (xy 399.363153 -276.596303) (xy 399.412328 -276.594322)
			(xy 399.461183 -276.600254) (xy 399.508454 -276.613946) (xy 399.552916 -276.635044) (xy 399.593419 -276.663)
			(xy 399.628912 -276.697092) (xy 399.658477 -276.736436) (xy 399.681348 -276.780013) (xy 399.696932 -276.826694)
			(xy 399.704827 -276.875271) (xy 399.705322 -276.899878) (xy 400.04417 -276.899878) (xy 400.04813 -276.850824)
			(xy 400.059907 -276.80304) (xy 400.079198 -276.757764) (xy 400.105501 -276.716168) (xy 400.138136 -276.679331)
			(xy 400.176257 -276.648206) (xy 400.218878 -276.623599) (xy 400.264894 -276.606147) (xy 400.313113 -276.596303)
			(xy 400.362288 -276.594322) (xy 400.411143 -276.600254) (xy 400.458414 -276.613946) (xy 400.502876 -276.635044)
			(xy 400.543379 -276.663) (xy 400.578872 -276.697092) (xy 400.608437 -276.736436) (xy 400.631308 -276.780013)
			(xy 400.646892 -276.826694) (xy 400.654787 -276.875271) (xy 400.655282 -276.899878) (xy 400.99413 -276.899878)
			(xy 400.99809 -276.850824) (xy 401.009867 -276.80304) (xy 401.029158 -276.757764) (xy 401.055461 -276.716168)
			(xy 401.088096 -276.679331) (xy 401.126217 -276.648206) (xy 401.168838 -276.623599) (xy 401.214854 -276.606147)
			(xy 401.263073 -276.596303) (xy 401.312248 -276.594322) (xy 401.361103 -276.600254) (xy 401.408374 -276.613946)
			(xy 401.452836 -276.635044) (xy 401.493339 -276.663) (xy 401.528832 -276.697092) (xy 401.558397 -276.736436)
			(xy 401.581268 -276.780013) (xy 401.596852 -276.826694) (xy 401.604747 -276.875271) (xy 401.605242 -276.899878)
			(xy 401.94409 -276.899878) (xy 401.94805 -276.850824) (xy 401.959827 -276.80304) (xy 401.979118 -276.757764)
			(xy 402.005421 -276.716168) (xy 402.038056 -276.679331) (xy 402.076177 -276.648206) (xy 402.118798 -276.623599)
			(xy 402.164814 -276.606147) (xy 402.213033 -276.596303) (xy 402.262208 -276.594322) (xy 402.311063 -276.600254)
			(xy 402.358334 -276.613946) (xy 402.402796 -276.635044) (xy 402.443299 -276.663) (xy 402.478792 -276.697092)
			(xy 402.508357 -276.736436) (xy 402.531228 -276.780013) (xy 402.546812 -276.826694) (xy 402.554707 -276.875271)
			(xy 402.555202 -276.899878) (xy 402.89405 -276.899878) (xy 402.89801 -276.850824) (xy 402.909787 -276.80304)
			(xy 402.929078 -276.757764) (xy 402.955381 -276.716168) (xy 402.988016 -276.679331) (xy 403.026137 -276.648206)
			(xy 403.068758 -276.623599) (xy 403.114774 -276.606147) (xy 403.162993 -276.596303) (xy 403.212168 -276.594322)
			(xy 403.261023 -276.600254) (xy 403.308294 -276.613946) (xy 403.352756 -276.635044) (xy 403.393259 -276.663)
			(xy 403.428752 -276.697092) (xy 403.458317 -276.736436) (xy 403.481188 -276.780013) (xy 403.496772 -276.826694)
			(xy 403.504667 -276.875271) (xy 403.505162 -276.899878) (xy 403.84401 -276.899878) (xy 403.84797 -276.850824)
			(xy 403.859747 -276.80304) (xy 403.879038 -276.757764) (xy 403.905341 -276.716168) (xy 403.937976 -276.679331)
			(xy 403.976097 -276.648206) (xy 404.018718 -276.623599) (xy 404.064734 -276.606147) (xy 404.112953 -276.596303)
			(xy 404.162128 -276.594322) (xy 404.210983 -276.600254) (xy 404.258254 -276.613946) (xy 404.302716 -276.635044)
			(xy 404.343219 -276.663) (xy 404.378712 -276.697092) (xy 404.408277 -276.736436) (xy 404.431148 -276.780013)
			(xy 404.446732 -276.826694) (xy 404.454627 -276.875271) (xy 404.455122 -276.899878) (xy 404.794224 -276.899878)
			(xy 404.798184 -276.850824) (xy 404.809961 -276.80304) (xy 404.829252 -276.757764) (xy 404.855555 -276.716168)
			(xy 404.88819 -276.679331) (xy 404.926311 -276.648206) (xy 404.968932 -276.623599) (xy 405.014948 -276.606147)
			(xy 405.063167 -276.596303) (xy 405.112342 -276.594322) (xy 405.161197 -276.600254) (xy 405.208468 -276.613946)
			(xy 405.25293 -276.635044) (xy 405.293433 -276.663) (xy 405.328926 -276.697092) (xy 405.358491 -276.736436)
			(xy 405.381362 -276.780013) (xy 405.396946 -276.826694) (xy 405.404841 -276.875271) (xy 405.405336 -276.899878)
			(xy 405.744184 -276.899878) (xy 405.748144 -276.850824) (xy 405.759921 -276.80304) (xy 405.779212 -276.757764)
			(xy 405.805515 -276.716168) (xy 405.83815 -276.679331) (xy 405.876271 -276.648206) (xy 405.918892 -276.623599)
			(xy 405.964908 -276.606147) (xy 406.013127 -276.596303) (xy 406.062302 -276.594322) (xy 406.111157 -276.600254)
			(xy 406.158428 -276.613946) (xy 406.20289 -276.635044) (xy 406.243393 -276.663) (xy 406.278886 -276.697092)
			(xy 406.308451 -276.736436) (xy 406.331322 -276.780013) (xy 406.346906 -276.826694) (xy 406.354801 -276.875271)
			(xy 406.355296 -276.899878) (xy 406.694144 -276.899878) (xy 406.698104 -276.850824) (xy 406.709881 -276.80304)
			(xy 406.729172 -276.757764) (xy 406.755475 -276.716168) (xy 406.78811 -276.679331) (xy 406.826231 -276.648206)
			(xy 406.868852 -276.623599) (xy 406.914868 -276.606147) (xy 406.963087 -276.596303) (xy 407.012262 -276.594322)
			(xy 407.061117 -276.600254) (xy 407.108388 -276.613946) (xy 407.15285 -276.635044) (xy 407.193353 -276.663)
			(xy 407.228846 -276.697092) (xy 407.258411 -276.736436) (xy 407.281282 -276.780013) (xy 407.296866 -276.826694)
			(xy 407.304761 -276.875271) (xy 407.305256 -276.899878) (xy 407.644104 -276.899878) (xy 407.648064 -276.850824)
			(xy 407.659841 -276.80304) (xy 407.679132 -276.757764) (xy 407.705435 -276.716168) (xy 407.73807 -276.679331)
			(xy 407.776191 -276.648206) (xy 407.818812 -276.623599) (xy 407.864828 -276.606147) (xy 407.913047 -276.596303)
			(xy 407.962222 -276.594322) (xy 408.011077 -276.600254) (xy 408.058348 -276.613946) (xy 408.10281 -276.635044)
			(xy 408.143313 -276.663) (xy 408.178806 -276.697092) (xy 408.208371 -276.736436) (xy 408.231242 -276.780013)
			(xy 408.246826 -276.826694) (xy 408.254721 -276.875271) (xy 408.255216 -276.899878) (xy 408.594064 -276.899878)
			(xy 408.598024 -276.850824) (xy 408.609801 -276.80304) (xy 408.629092 -276.757764) (xy 408.655395 -276.716168)
			(xy 408.68803 -276.679331) (xy 408.726151 -276.648206) (xy 408.768772 -276.623599) (xy 408.814788 -276.606147)
			(xy 408.863007 -276.596303) (xy 408.912182 -276.594322) (xy 408.961037 -276.600254) (xy 409.008308 -276.613946)
			(xy 409.05277 -276.635044) (xy 409.093273 -276.663) (xy 409.128766 -276.697092) (xy 409.158331 -276.736436)
			(xy 409.181202 -276.780013) (xy 409.196786 -276.826694) (xy 409.204681 -276.875271) (xy 409.205176 -276.899878)
			(xy 409.544024 -276.899878) (xy 409.547984 -276.850824) (xy 409.559761 -276.80304) (xy 409.579052 -276.757764)
			(xy 409.605355 -276.716168) (xy 409.63799 -276.679331) (xy 409.676111 -276.648206) (xy 409.718732 -276.623599)
			(xy 409.764748 -276.606147) (xy 409.812967 -276.596303) (xy 409.862142 -276.594322) (xy 409.910997 -276.600254)
			(xy 409.958268 -276.613946) (xy 410.00273 -276.635044) (xy 410.043233 -276.663) (xy 410.078726 -276.697092)
			(xy 410.108291 -276.736436) (xy 410.131162 -276.780013) (xy 410.146746 -276.826694) (xy 410.154641 -276.875271)
			(xy 410.155136 -276.899878) (xy 410.493984 -276.899878) (xy 410.497944 -276.850824) (xy 410.509721 -276.80304)
			(xy 410.529012 -276.757764) (xy 410.555315 -276.716168) (xy 410.58795 -276.679331) (xy 410.626071 -276.648206)
			(xy 410.668692 -276.623599) (xy 410.714708 -276.606147) (xy 410.762927 -276.596303) (xy 410.812102 -276.594322)
			(xy 410.860957 -276.600254) (xy 410.908228 -276.613946) (xy 410.95269 -276.635044) (xy 410.993193 -276.663)
			(xy 411.028686 -276.697092) (xy 411.058251 -276.736436) (xy 411.081122 -276.780013) (xy 411.096706 -276.826694)
			(xy 411.104601 -276.875271) (xy 411.105096 -276.899878) (xy 411.444198 -276.899878) (xy 411.448158 -276.850824)
			(xy 411.459935 -276.80304) (xy 411.479226 -276.757764) (xy 411.505529 -276.716168) (xy 411.538164 -276.679331)
			(xy 411.576285 -276.648206) (xy 411.618906 -276.623599) (xy 411.664922 -276.606147) (xy 411.713141 -276.596303)
			(xy 411.762316 -276.594322) (xy 411.811171 -276.600254) (xy 411.858442 -276.613946) (xy 411.902904 -276.635044)
			(xy 411.943407 -276.663) (xy 411.9789 -276.697092) (xy 412.008465 -276.736436) (xy 412.031336 -276.780013)
			(xy 412.04692 -276.826694) (xy 412.054815 -276.875271) (xy 412.05531 -276.899878) (xy 412.394158 -276.899878)
			(xy 412.398118 -276.850824) (xy 412.409895 -276.80304) (xy 412.429186 -276.757764) (xy 412.455489 -276.716168)
			(xy 412.488124 -276.679331) (xy 412.526245 -276.648206) (xy 412.568866 -276.623599) (xy 412.614882 -276.606147)
			(xy 412.663101 -276.596303) (xy 412.712276 -276.594322) (xy 412.761131 -276.600254) (xy 412.808402 -276.613946)
			(xy 412.852864 -276.635044) (xy 412.893367 -276.663) (xy 412.92886 -276.697092) (xy 412.958425 -276.736436)
			(xy 412.981296 -276.780013) (xy 412.99688 -276.826694) (xy 413.004775 -276.875271) (xy 413.00527 -276.899878)
			(xy 413.344118 -276.899878) (xy 413.348078 -276.850824) (xy 413.359855 -276.80304) (xy 413.379146 -276.757764)
			(xy 413.405449 -276.716168) (xy 413.438084 -276.679331) (xy 413.476205 -276.648206) (xy 413.518826 -276.623599)
			(xy 413.564842 -276.606147) (xy 413.613061 -276.596303) (xy 413.662236 -276.594322) (xy 413.711091 -276.600254)
			(xy 413.758362 -276.613946) (xy 413.802824 -276.635044) (xy 413.843327 -276.663) (xy 413.87882 -276.697092)
			(xy 413.908385 -276.736436) (xy 413.931256 -276.780013) (xy 413.94684 -276.826694) (xy 413.954735 -276.875271)
			(xy 413.95523 -276.899878) (xy 414.294078 -276.899878) (xy 414.298038 -276.850824) (xy 414.309815 -276.80304)
			(xy 414.329106 -276.757764) (xy 414.355409 -276.716168) (xy 414.388044 -276.679331) (xy 414.426165 -276.648206)
			(xy 414.468786 -276.623599) (xy 414.514802 -276.606147) (xy 414.563021 -276.596303) (xy 414.612196 -276.594322)
			(xy 414.661051 -276.600254) (xy 414.708322 -276.613946) (xy 414.752784 -276.635044) (xy 414.793287 -276.663)
			(xy 414.82878 -276.697092) (xy 414.858345 -276.736436) (xy 414.881216 -276.780013) (xy 414.8968 -276.826694)
			(xy 414.904695 -276.875271) (xy 414.90519 -276.899878) (xy 415.244038 -276.899878) (xy 415.247998 -276.850824)
			(xy 415.259775 -276.80304) (xy 415.279066 -276.757764) (xy 415.305369 -276.716168) (xy 415.338004 -276.679331)
			(xy 415.376125 -276.648206) (xy 415.418746 -276.623599) (xy 415.464762 -276.606147) (xy 415.512981 -276.596303)
			(xy 415.562156 -276.594322) (xy 415.611011 -276.600254) (xy 415.658282 -276.613946) (xy 415.702744 -276.635044)
			(xy 415.743247 -276.663) (xy 415.77874 -276.697092) (xy 415.808305 -276.736436) (xy 415.831176 -276.780013)
			(xy 415.84676 -276.826694) (xy 415.854655 -276.875271) (xy 415.85515 -276.899878) (xy 416.193998 -276.899878)
			(xy 416.197958 -276.850824) (xy 416.209735 -276.80304) (xy 416.229026 -276.757764) (xy 416.255329 -276.716168)
			(xy 416.287964 -276.679331) (xy 416.326085 -276.648206) (xy 416.368706 -276.623599) (xy 416.414722 -276.606147)
			(xy 416.462941 -276.596303) (xy 416.512116 -276.594322) (xy 416.560971 -276.600254) (xy 416.608242 -276.613946)
			(xy 416.652704 -276.635044) (xy 416.693207 -276.663) (xy 416.7287 -276.697092) (xy 416.758265 -276.736436)
			(xy 416.781136 -276.780013) (xy 416.79672 -276.826694) (xy 416.804615 -276.875271) (xy 416.80511 -276.899878)
			(xy 417.144212 -276.899878) (xy 417.148172 -276.850824) (xy 417.159949 -276.80304) (xy 417.17924 -276.757764)
			(xy 417.205543 -276.716168) (xy 417.238178 -276.679331) (xy 417.276299 -276.648206) (xy 417.31892 -276.623599)
			(xy 417.364936 -276.606147) (xy 417.413155 -276.596303) (xy 417.46233 -276.594322) (xy 417.511185 -276.600254)
			(xy 417.558456 -276.613946) (xy 417.602918 -276.635044) (xy 417.643421 -276.663) (xy 417.678914 -276.697092)
			(xy 417.708479 -276.736436) (xy 417.73135 -276.780013) (xy 417.746934 -276.826694) (xy 417.754829 -276.875271)
			(xy 417.755324 -276.899878) (xy 418.094172 -276.899878) (xy 418.098132 -276.850824) (xy 418.109909 -276.80304)
			(xy 418.1292 -276.757764) (xy 418.155503 -276.716168) (xy 418.188138 -276.679331) (xy 418.226259 -276.648206)
			(xy 418.26888 -276.623599) (xy 418.314896 -276.606147) (xy 418.363115 -276.596303) (xy 418.41229 -276.594322)
			(xy 418.461145 -276.600254) (xy 418.508416 -276.613946) (xy 418.552878 -276.635044) (xy 418.593381 -276.663)
			(xy 418.628874 -276.697092) (xy 418.658439 -276.736436) (xy 418.68131 -276.780013) (xy 418.696894 -276.826694)
			(xy 418.704789 -276.875271) (xy 418.705284 -276.899878) (xy 419.044132 -276.899878) (xy 419.048092 -276.850824)
			(xy 419.059869 -276.80304) (xy 419.07916 -276.757764) (xy 419.105463 -276.716168) (xy 419.138098 -276.679331)
			(xy 419.176219 -276.648206) (xy 419.21884 -276.623599) (xy 419.264856 -276.606147) (xy 419.313075 -276.596303)
			(xy 419.36225 -276.594322) (xy 419.411105 -276.600254) (xy 419.458376 -276.613946) (xy 419.502838 -276.635044)
			(xy 419.543341 -276.663) (xy 419.578834 -276.697092) (xy 419.608399 -276.736436) (xy 419.63127 -276.780013)
			(xy 419.646854 -276.826694) (xy 419.654749 -276.875271) (xy 419.655244 -276.899878) (xy 419.994092 -276.899878)
			(xy 419.998052 -276.850824) (xy 420.009829 -276.80304) (xy 420.02912 -276.757764) (xy 420.055423 -276.716168)
			(xy 420.088058 -276.679331) (xy 420.126179 -276.648206) (xy 420.1688 -276.623599) (xy 420.214816 -276.606147)
			(xy 420.263035 -276.596303) (xy 420.31221 -276.594322) (xy 420.361065 -276.600254) (xy 420.408336 -276.613946)
			(xy 420.452798 -276.635044) (xy 420.493301 -276.663) (xy 420.528794 -276.697092) (xy 420.558359 -276.736436)
			(xy 420.58123 -276.780013) (xy 420.596814 -276.826694) (xy 420.604709 -276.875271) (xy 420.605204 -276.899878)
			(xy 420.944052 -276.899878) (xy 420.948012 -276.850824) (xy 420.959789 -276.80304) (xy 420.97908 -276.757764)
			(xy 421.005383 -276.716168) (xy 421.038018 -276.679331) (xy 421.076139 -276.648206) (xy 421.11876 -276.623599)
			(xy 421.164776 -276.606147) (xy 421.212995 -276.596303) (xy 421.26217 -276.594322) (xy 421.311025 -276.600254)
			(xy 421.358296 -276.613946) (xy 421.402758 -276.635044) (xy 421.443261 -276.663) (xy 421.478754 -276.697092)
			(xy 421.508319 -276.736436) (xy 421.53119 -276.780013) (xy 421.546774 -276.826694) (xy 421.554669 -276.875271)
			(xy 421.555164 -276.899878) (xy 421.893758 -276.899878) (xy 421.897718 -276.850824) (xy 421.909495 -276.80304)
			(xy 421.928786 -276.757764) (xy 421.955089 -276.716168) (xy 421.987724 -276.679331) (xy 422.025845 -276.648206)
			(xy 422.068466 -276.623599) (xy 422.114482 -276.606147) (xy 422.162701 -276.596303) (xy 422.211876 -276.594322)
			(xy 422.260731 -276.600254) (xy 422.308002 -276.613946) (xy 422.352464 -276.635044) (xy 422.392967 -276.663)
			(xy 422.42846 -276.697092) (xy 422.458025 -276.736436) (xy 422.480896 -276.780013) (xy 422.49648 -276.826694)
			(xy 422.504375 -276.875271) (xy 422.50487 -276.899878) (xy 422.843972 -276.899878) (xy 422.847932 -276.850824)
			(xy 422.859709 -276.80304) (xy 422.879 -276.757764) (xy 422.905303 -276.716168) (xy 422.937938 -276.679331)
			(xy 422.976059 -276.648206) (xy 423.01868 -276.623599) (xy 423.064696 -276.606147) (xy 423.112915 -276.596303)
			(xy 423.16209 -276.594322) (xy 423.210945 -276.600254) (xy 423.258216 -276.613946) (xy 423.302678 -276.635044)
			(xy 423.343181 -276.663) (xy 423.378674 -276.697092) (xy 423.408239 -276.736436) (xy 423.43111 -276.780013)
			(xy 423.446694 -276.826694) (xy 423.454589 -276.875271) (xy 423.455084 -276.899878) (xy 423.793932 -276.899878)
			(xy 423.797892 -276.850824) (xy 423.809669 -276.80304) (xy 423.82896 -276.757764) (xy 423.855263 -276.716168)
			(xy 423.887898 -276.679331) (xy 423.926019 -276.648206) (xy 423.96864 -276.623599) (xy 424.014656 -276.606147)
			(xy 424.062875 -276.596303) (xy 424.11205 -276.594322) (xy 424.160905 -276.600254) (xy 424.208176 -276.613946)
			(xy 424.252638 -276.635044) (xy 424.293141 -276.663) (xy 424.328634 -276.697092) (xy 424.358199 -276.736436)
			(xy 424.38107 -276.780013) (xy 424.396654 -276.826694) (xy 424.404549 -276.875271) (xy 424.405044 -276.899878)
			(xy 424.743892 -276.899878) (xy 424.747852 -276.850824) (xy 424.759629 -276.80304) (xy 424.77892 -276.757764)
			(xy 424.805223 -276.716168) (xy 424.837858 -276.679331) (xy 424.875979 -276.648206) (xy 424.9186 -276.623599)
			(xy 424.964616 -276.606147) (xy 425.012835 -276.596303) (xy 425.06201 -276.594322) (xy 425.110865 -276.600254)
			(xy 425.158136 -276.613946) (xy 425.202598 -276.635044) (xy 425.243101 -276.663) (xy 425.278594 -276.697092)
			(xy 425.308159 -276.736436) (xy 425.33103 -276.780013) (xy 425.346614 -276.826694) (xy 425.354509 -276.875271)
			(xy 425.355004 -276.899878) (xy 425.693852 -276.899878) (xy 425.697812 -276.850824) (xy 425.709589 -276.80304)
			(xy 425.72888 -276.757764) (xy 425.755183 -276.716168) (xy 425.787818 -276.679331) (xy 425.825939 -276.648206)
			(xy 425.86856 -276.623599) (xy 425.914576 -276.606147) (xy 425.962795 -276.596303) (xy 426.01197 -276.594322)
			(xy 426.060825 -276.600254) (xy 426.108096 -276.613946) (xy 426.152558 -276.635044) (xy 426.193061 -276.663)
			(xy 426.228554 -276.697092) (xy 426.258119 -276.736436) (xy 426.28099 -276.780013) (xy 426.296574 -276.826694)
			(xy 426.304469 -276.875271) (xy 426.304964 -276.899878) (xy 426.643812 -276.899878) (xy 426.647772 -276.850824)
			(xy 426.659549 -276.80304) (xy 426.67884 -276.757764) (xy 426.705143 -276.716168) (xy 426.737778 -276.679331)
			(xy 426.775899 -276.648206) (xy 426.81852 -276.623599) (xy 426.864536 -276.606147) (xy 426.912755 -276.596303)
			(xy 426.96193 -276.594322) (xy 427.010785 -276.600254) (xy 427.058056 -276.613946) (xy 427.102518 -276.635044)
			(xy 427.143021 -276.663) (xy 427.178514 -276.697092) (xy 427.208079 -276.736436) (xy 427.23095 -276.780013)
			(xy 427.246534 -276.826694) (xy 427.254429 -276.875271) (xy 427.254924 -276.899878) (xy 427.593772 -276.899878)
			(xy 427.597732 -276.850824) (xy 427.609509 -276.80304) (xy 427.6288 -276.757764) (xy 427.655103 -276.716168)
			(xy 427.687738 -276.679331) (xy 427.725859 -276.648206) (xy 427.76848 -276.623599) (xy 427.814496 -276.606147)
			(xy 427.862715 -276.596303) (xy 427.91189 -276.594322) (xy 427.960745 -276.600254) (xy 428.008016 -276.613946)
			(xy 428.052478 -276.635044) (xy 428.092981 -276.663) (xy 428.128474 -276.697092) (xy 428.158039 -276.736436)
			(xy 428.18091 -276.780013) (xy 428.196494 -276.826694) (xy 428.204389 -276.875271) (xy 428.204884 -276.899878)
			(xy 428.543986 -276.899878) (xy 428.547946 -276.850824) (xy 428.559723 -276.80304) (xy 428.579014 -276.757764)
			(xy 428.605317 -276.716168) (xy 428.637952 -276.679331) (xy 428.676073 -276.648206) (xy 428.718694 -276.623599)
			(xy 428.76471 -276.606147) (xy 428.812929 -276.596303) (xy 428.862104 -276.594322) (xy 428.910959 -276.600254)
			(xy 428.95823 -276.613946) (xy 429.002692 -276.635044) (xy 429.043195 -276.663) (xy 429.078688 -276.697092)
			(xy 429.108253 -276.736436) (xy 429.131124 -276.780013) (xy 429.146708 -276.826694) (xy 429.154603 -276.875271)
			(xy 429.155098 -276.899878) (xy 429.154603 -276.924485) (xy 429.154424 -276.925586) (xy 429.473356 -276.925586)
			(xy 429.473356 -276.87417) (xy 429.481399 -276.823388) (xy 429.497287 -276.774489) (xy 429.52063 -276.728677)
			(xy 429.550851 -276.687081) (xy 429.587207 -276.650725) (xy 429.628803 -276.620504) (xy 429.674615 -276.597161)
			(xy 429.723514 -276.581273) (xy 429.774296 -276.57323) (xy 429.825712 -276.57323) (xy 429.876494 -276.581273)
			(xy 429.925393 -276.597161) (xy 429.971205 -276.620504) (xy 430.012801 -276.650725) (xy 430.049157 -276.687081)
			(xy 430.079378 -276.728677) (xy 430.102721 -276.774489) (xy 430.118609 -276.823388) (xy 430.126652 -276.87417)
			(xy 430.127156 -276.899878) (xy 430.126652 -276.925586) (xy 430.423316 -276.925586) (xy 430.423316 -276.87417)
			(xy 430.431359 -276.823388) (xy 430.447247 -276.774489) (xy 430.47059 -276.728677) (xy 430.500811 -276.687081)
			(xy 430.537167 -276.650725) (xy 430.578763 -276.620504) (xy 430.624575 -276.597161) (xy 430.673474 -276.581273)
			(xy 430.724256 -276.57323) (xy 430.775672 -276.57323) (xy 430.826454 -276.581273) (xy 430.875353 -276.597161)
			(xy 430.921165 -276.620504) (xy 430.962761 -276.650725) (xy 430.999117 -276.687081) (xy 431.029338 -276.728677)
			(xy 431.052681 -276.774489) (xy 431.068569 -276.823388) (xy 431.076612 -276.87417) (xy 431.077116 -276.899878)
			(xy 431.077111 -276.900132) (xy 431.394374 -276.900132) (xy 431.398334 -276.851078) (xy 431.410111 -276.803294)
			(xy 431.429402 -276.758018) (xy 431.455705 -276.716422) (xy 431.48834 -276.679585) (xy 431.526461 -276.64846)
			(xy 431.569082 -276.623853) (xy 431.615098 -276.606401) (xy 431.663317 -276.596557) (xy 431.712492 -276.594576)
			(xy 431.761347 -276.600508) (xy 431.808618 -276.6142) (xy 431.85308 -276.635298) (xy 431.893583 -276.663254)
			(xy 431.929076 -276.697346) (xy 431.958641 -276.73669) (xy 431.981512 -276.780267) (xy 431.997096 -276.826948)
			(xy 432.004991 -276.875525) (xy 432.005486 -276.900132) (xy 432.004991 -276.924739) (xy 431.997096 -276.973316)
			(xy 431.981512 -277.019997) (xy 431.958641 -277.063574) (xy 431.929076 -277.102918) (xy 431.893583 -277.13701)
			(xy 431.85308 -277.164966) (xy 431.808618 -277.186064) (xy 431.761347 -277.199756) (xy 431.712492 -277.205688)
			(xy 431.663317 -277.203707) (xy 431.615098 -277.193863) (xy 431.569082 -277.176411) (xy 431.526461 -277.151804)
			(xy 431.48834 -277.120679) (xy 431.455705 -277.083842) (xy 431.429402 -277.042246) (xy 431.410111 -276.99697)
			(xy 431.398334 -276.949186) (xy 431.394374 -276.900132) (xy 431.077111 -276.900132) (xy 431.076612 -276.925586)
			(xy 431.068569 -276.976368) (xy 431.052681 -277.025267) (xy 431.029338 -277.071079) (xy 430.999117 -277.112675)
			(xy 430.962761 -277.149031) (xy 430.921165 -277.179252) (xy 430.875353 -277.202595) (xy 430.826454 -277.218483)
			(xy 430.775672 -277.226526) (xy 430.724256 -277.226526) (xy 430.673474 -277.218483) (xy 430.624575 -277.202595)
			(xy 430.578763 -277.179252) (xy 430.537167 -277.149031) (xy 430.500811 -277.112675) (xy 430.47059 -277.071079)
			(xy 430.447247 -277.025267) (xy 430.431359 -276.976368) (xy 430.423316 -276.925586) (xy 430.126652 -276.925586)
			(xy 430.118609 -276.976368) (xy 430.102721 -277.025267) (xy 430.079378 -277.071079) (xy 430.049157 -277.112675)
			(xy 430.012801 -277.149031) (xy 429.971205 -277.179252) (xy 429.925393 -277.202595) (xy 429.876494 -277.218483)
			(xy 429.825712 -277.226526) (xy 429.774296 -277.226526) (xy 429.723514 -277.218483) (xy 429.674615 -277.202595)
			(xy 429.628803 -277.179252) (xy 429.587207 -277.149031) (xy 429.550851 -277.112675) (xy 429.52063 -277.071079)
			(xy 429.497287 -277.025267) (xy 429.481399 -276.976368) (xy 429.473356 -276.925586) (xy 429.154424 -276.925586)
			(xy 429.146708 -276.973062) (xy 429.131124 -277.019743) (xy 429.108253 -277.06332) (xy 429.078688 -277.102664)
			(xy 429.043195 -277.136756) (xy 429.002692 -277.164712) (xy 428.95823 -277.18581) (xy 428.910959 -277.199502)
			(xy 428.862104 -277.205434) (xy 428.812929 -277.203453) (xy 428.76471 -277.193609) (xy 428.718694 -277.176157)
			(xy 428.676073 -277.15155) (xy 428.637952 -277.120425) (xy 428.605317 -277.083588) (xy 428.579014 -277.041992)
			(xy 428.559723 -276.996716) (xy 428.547946 -276.948932) (xy 428.543986 -276.899878) (xy 428.204884 -276.899878)
			(xy 428.204389 -276.924485) (xy 428.196494 -276.973062) (xy 428.18091 -277.019743) (xy 428.158039 -277.06332)
			(xy 428.128474 -277.102664) (xy 428.092981 -277.136756) (xy 428.052478 -277.164712) (xy 428.008016 -277.18581)
			(xy 427.960745 -277.199502) (xy 427.91189 -277.205434) (xy 427.862715 -277.203453) (xy 427.814496 -277.193609)
			(xy 427.76848 -277.176157) (xy 427.725859 -277.15155) (xy 427.687738 -277.120425) (xy 427.655103 -277.083588)
			(xy 427.6288 -277.041992) (xy 427.609509 -276.996716) (xy 427.597732 -276.948932) (xy 427.593772 -276.899878)
			(xy 427.254924 -276.899878) (xy 427.254429 -276.924485) (xy 427.246534 -276.973062) (xy 427.23095 -277.019743)
			(xy 427.208079 -277.06332) (xy 427.178514 -277.102664) (xy 427.143021 -277.136756) (xy 427.102518 -277.164712)
			(xy 427.058056 -277.18581) (xy 427.010785 -277.199502) (xy 426.96193 -277.205434) (xy 426.912755 -277.203453)
			(xy 426.864536 -277.193609) (xy 426.81852 -277.176157) (xy 426.775899 -277.15155) (xy 426.737778 -277.120425)
			(xy 426.705143 -277.083588) (xy 426.67884 -277.041992) (xy 426.659549 -276.996716) (xy 426.647772 -276.948932)
			(xy 426.643812 -276.899878) (xy 426.304964 -276.899878) (xy 426.304469 -276.924485) (xy 426.296574 -276.973062)
			(xy 426.28099 -277.019743) (xy 426.258119 -277.06332) (xy 426.228554 -277.102664) (xy 426.193061 -277.136756)
			(xy 426.152558 -277.164712) (xy 426.108096 -277.18581) (xy 426.060825 -277.199502) (xy 426.01197 -277.205434)
			(xy 425.962795 -277.203453) (xy 425.914576 -277.193609) (xy 425.86856 -277.176157) (xy 425.825939 -277.15155)
			(xy 425.787818 -277.120425) (xy 425.755183 -277.083588) (xy 425.72888 -277.041992) (xy 425.709589 -276.996716)
			(xy 425.697812 -276.948932) (xy 425.693852 -276.899878) (xy 425.355004 -276.899878) (xy 425.354509 -276.924485)
			(xy 425.346614 -276.973062) (xy 425.33103 -277.019743) (xy 425.308159 -277.06332) (xy 425.278594 -277.102664)
			(xy 425.243101 -277.136756) (xy 425.202598 -277.164712) (xy 425.158136 -277.18581) (xy 425.110865 -277.199502)
			(xy 425.06201 -277.205434) (xy 425.012835 -277.203453) (xy 424.964616 -277.193609) (xy 424.9186 -277.176157)
			(xy 424.875979 -277.15155) (xy 424.837858 -277.120425) (xy 424.805223 -277.083588) (xy 424.77892 -277.041992)
			(xy 424.759629 -276.996716) (xy 424.747852 -276.948932) (xy 424.743892 -276.899878) (xy 424.405044 -276.899878)
			(xy 424.404549 -276.924485) (xy 424.396654 -276.973062) (xy 424.38107 -277.019743) (xy 424.358199 -277.06332)
			(xy 424.328634 -277.102664) (xy 424.293141 -277.136756) (xy 424.252638 -277.164712) (xy 424.208176 -277.18581)
			(xy 424.160905 -277.199502) (xy 424.11205 -277.205434) (xy 424.062875 -277.203453) (xy 424.014656 -277.193609)
			(xy 423.96864 -277.176157) (xy 423.926019 -277.15155) (xy 423.887898 -277.120425) (xy 423.855263 -277.083588)
			(xy 423.82896 -277.041992) (xy 423.809669 -276.996716) (xy 423.797892 -276.948932) (xy 423.793932 -276.899878)
			(xy 423.455084 -276.899878) (xy 423.454589 -276.924485) (xy 423.446694 -276.973062) (xy 423.43111 -277.019743)
			(xy 423.408239 -277.06332) (xy 423.378674 -277.102664) (xy 423.343181 -277.136756) (xy 423.302678 -277.164712)
			(xy 423.258216 -277.18581) (xy 423.210945 -277.199502) (xy 423.16209 -277.205434) (xy 423.112915 -277.203453)
			(xy 423.064696 -277.193609) (xy 423.01868 -277.176157) (xy 422.976059 -277.15155) (xy 422.937938 -277.120425)
			(xy 422.905303 -277.083588) (xy 422.879 -277.041992) (xy 422.859709 -276.996716) (xy 422.847932 -276.948932)
			(xy 422.843972 -276.899878) (xy 422.50487 -276.899878) (xy 422.504375 -276.924485) (xy 422.49648 -276.973062)
			(xy 422.480896 -277.019743) (xy 422.458025 -277.06332) (xy 422.42846 -277.102664) (xy 422.392967 -277.136756)
			(xy 422.352464 -277.164712) (xy 422.308002 -277.18581) (xy 422.260731 -277.199502) (xy 422.211876 -277.205434)
			(xy 422.162701 -277.203453) (xy 422.114482 -277.193609) (xy 422.068466 -277.176157) (xy 422.025845 -277.15155)
			(xy 421.987724 -277.120425) (xy 421.955089 -277.083588) (xy 421.928786 -277.041992) (xy 421.909495 -276.996716)
			(xy 421.897718 -276.948932) (xy 421.893758 -276.899878) (xy 421.555164 -276.899878) (xy 421.554669 -276.924485)
			(xy 421.546774 -276.973062) (xy 421.53119 -277.019743) (xy 421.508319 -277.06332) (xy 421.478754 -277.102664)
			(xy 421.443261 -277.136756) (xy 421.402758 -277.164712) (xy 421.358296 -277.18581) (xy 421.311025 -277.199502)
			(xy 421.26217 -277.205434) (xy 421.212995 -277.203453) (xy 421.164776 -277.193609) (xy 421.11876 -277.176157)
			(xy 421.076139 -277.15155) (xy 421.038018 -277.120425) (xy 421.005383 -277.083588) (xy 420.97908 -277.041992)
			(xy 420.959789 -276.996716) (xy 420.948012 -276.948932) (xy 420.944052 -276.899878) (xy 420.605204 -276.899878)
			(xy 420.604709 -276.924485) (xy 420.596814 -276.973062) (xy 420.58123 -277.019743) (xy 420.558359 -277.06332)
			(xy 420.528794 -277.102664) (xy 420.493301 -277.136756) (xy 420.452798 -277.164712) (xy 420.408336 -277.18581)
			(xy 420.361065 -277.199502) (xy 420.31221 -277.205434) (xy 420.263035 -277.203453) (xy 420.214816 -277.193609)
			(xy 420.1688 -277.176157) (xy 420.126179 -277.15155) (xy 420.088058 -277.120425) (xy 420.055423 -277.083588)
			(xy 420.02912 -277.041992) (xy 420.009829 -276.996716) (xy 419.998052 -276.948932) (xy 419.994092 -276.899878)
			(xy 419.655244 -276.899878) (xy 419.654749 -276.924485) (xy 419.646854 -276.973062) (xy 419.63127 -277.019743)
			(xy 419.608399 -277.06332) (xy 419.578834 -277.102664) (xy 419.543341 -277.136756) (xy 419.502838 -277.164712)
			(xy 419.458376 -277.18581) (xy 419.411105 -277.199502) (xy 419.36225 -277.205434) (xy 419.313075 -277.203453)
			(xy 419.264856 -277.193609) (xy 419.21884 -277.176157) (xy 419.176219 -277.15155) (xy 419.138098 -277.120425)
			(xy 419.105463 -277.083588) (xy 419.07916 -277.041992) (xy 419.059869 -276.996716) (xy 419.048092 -276.948932)
			(xy 419.044132 -276.899878) (xy 418.705284 -276.899878) (xy 418.704789 -276.924485) (xy 418.696894 -276.973062)
			(xy 418.68131 -277.019743) (xy 418.658439 -277.06332) (xy 418.628874 -277.102664) (xy 418.593381 -277.136756)
			(xy 418.552878 -277.164712) (xy 418.508416 -277.18581) (xy 418.461145 -277.199502) (xy 418.41229 -277.205434)
			(xy 418.363115 -277.203453) (xy 418.314896 -277.193609) (xy 418.26888 -277.176157) (xy 418.226259 -277.15155)
			(xy 418.188138 -277.120425) (xy 418.155503 -277.083588) (xy 418.1292 -277.041992) (xy 418.109909 -276.996716)
			(xy 418.098132 -276.948932) (xy 418.094172 -276.899878) (xy 417.755324 -276.899878) (xy 417.754829 -276.924485)
			(xy 417.746934 -276.973062) (xy 417.73135 -277.019743) (xy 417.708479 -277.06332) (xy 417.678914 -277.102664)
			(xy 417.643421 -277.136756) (xy 417.602918 -277.164712) (xy 417.558456 -277.18581) (xy 417.511185 -277.199502)
			(xy 417.46233 -277.205434) (xy 417.413155 -277.203453) (xy 417.364936 -277.193609) (xy 417.31892 -277.176157)
			(xy 417.276299 -277.15155) (xy 417.238178 -277.120425) (xy 417.205543 -277.083588) (xy 417.17924 -277.041992)
			(xy 417.159949 -276.996716) (xy 417.148172 -276.948932) (xy 417.144212 -276.899878) (xy 416.80511 -276.899878)
			(xy 416.804615 -276.924485) (xy 416.79672 -276.973062) (xy 416.781136 -277.019743) (xy 416.758265 -277.06332)
			(xy 416.7287 -277.102664) (xy 416.693207 -277.136756) (xy 416.652704 -277.164712) (xy 416.608242 -277.18581)
			(xy 416.560971 -277.199502) (xy 416.512116 -277.205434) (xy 416.462941 -277.203453) (xy 416.414722 -277.193609)
			(xy 416.368706 -277.176157) (xy 416.326085 -277.15155) (xy 416.287964 -277.120425) (xy 416.255329 -277.083588)
			(xy 416.229026 -277.041992) (xy 416.209735 -276.996716) (xy 416.197958 -276.948932) (xy 416.193998 -276.899878)
			(xy 415.85515 -276.899878) (xy 415.854655 -276.924485) (xy 415.84676 -276.973062) (xy 415.831176 -277.019743)
			(xy 415.808305 -277.06332) (xy 415.77874 -277.102664) (xy 415.743247 -277.136756) (xy 415.702744 -277.164712)
			(xy 415.658282 -277.18581) (xy 415.611011 -277.199502) (xy 415.562156 -277.205434) (xy 415.512981 -277.203453)
			(xy 415.464762 -277.193609) (xy 415.418746 -277.176157) (xy 415.376125 -277.15155) (xy 415.338004 -277.120425)
			(xy 415.305369 -277.083588) (xy 415.279066 -277.041992) (xy 415.259775 -276.996716) (xy 415.247998 -276.948932)
			(xy 415.244038 -276.899878) (xy 414.90519 -276.899878) (xy 414.904695 -276.924485) (xy 414.8968 -276.973062)
			(xy 414.881216 -277.019743) (xy 414.858345 -277.06332) (xy 414.82878 -277.102664) (xy 414.793287 -277.136756)
			(xy 414.752784 -277.164712) (xy 414.708322 -277.18581) (xy 414.661051 -277.199502) (xy 414.612196 -277.205434)
			(xy 414.563021 -277.203453) (xy 414.514802 -277.193609) (xy 414.468786 -277.176157) (xy 414.426165 -277.15155)
			(xy 414.388044 -277.120425) (xy 414.355409 -277.083588) (xy 414.329106 -277.041992) (xy 414.309815 -276.996716)
			(xy 414.298038 -276.948932) (xy 414.294078 -276.899878) (xy 413.95523 -276.899878) (xy 413.954735 -276.924485)
			(xy 413.94684 -276.973062) (xy 413.931256 -277.019743) (xy 413.908385 -277.06332) (xy 413.87882 -277.102664)
			(xy 413.843327 -277.136756) (xy 413.802824 -277.164712) (xy 413.758362 -277.18581) (xy 413.711091 -277.199502)
			(xy 413.662236 -277.205434) (xy 413.613061 -277.203453) (xy 413.564842 -277.193609) (xy 413.518826 -277.176157)
			(xy 413.476205 -277.15155) (xy 413.438084 -277.120425) (xy 413.405449 -277.083588) (xy 413.379146 -277.041992)
			(xy 413.359855 -276.996716) (xy 413.348078 -276.948932) (xy 413.344118 -276.899878) (xy 413.00527 -276.899878)
			(xy 413.004775 -276.924485) (xy 412.99688 -276.973062) (xy 412.981296 -277.019743) (xy 412.958425 -277.06332)
			(xy 412.92886 -277.102664) (xy 412.893367 -277.136756) (xy 412.852864 -277.164712) (xy 412.808402 -277.18581)
			(xy 412.761131 -277.199502) (xy 412.712276 -277.205434) (xy 412.663101 -277.203453) (xy 412.614882 -277.193609)
			(xy 412.568866 -277.176157) (xy 412.526245 -277.15155) (xy 412.488124 -277.120425) (xy 412.455489 -277.083588)
			(xy 412.429186 -277.041992) (xy 412.409895 -276.996716) (xy 412.398118 -276.948932) (xy 412.394158 -276.899878)
			(xy 412.05531 -276.899878) (xy 412.054815 -276.924485) (xy 412.04692 -276.973062) (xy 412.031336 -277.019743)
			(xy 412.008465 -277.06332) (xy 411.9789 -277.102664) (xy 411.943407 -277.136756) (xy 411.902904 -277.164712)
			(xy 411.858442 -277.18581) (xy 411.811171 -277.199502) (xy 411.762316 -277.205434) (xy 411.713141 -277.203453)
			(xy 411.664922 -277.193609) (xy 411.618906 -277.176157) (xy 411.576285 -277.15155) (xy 411.538164 -277.120425)
			(xy 411.505529 -277.083588) (xy 411.479226 -277.041992) (xy 411.459935 -276.996716) (xy 411.448158 -276.948932)
			(xy 411.444198 -276.899878) (xy 411.105096 -276.899878) (xy 411.104601 -276.924485) (xy 411.096706 -276.973062)
			(xy 411.081122 -277.019743) (xy 411.058251 -277.06332) (xy 411.028686 -277.102664) (xy 410.993193 -277.136756)
			(xy 410.95269 -277.164712) (xy 410.908228 -277.18581) (xy 410.860957 -277.199502) (xy 410.812102 -277.205434)
			(xy 410.762927 -277.203453) (xy 410.714708 -277.193609) (xy 410.668692 -277.176157) (xy 410.626071 -277.15155)
			(xy 410.58795 -277.120425) (xy 410.555315 -277.083588) (xy 410.529012 -277.041992) (xy 410.509721 -276.996716)
			(xy 410.497944 -276.948932) (xy 410.493984 -276.899878) (xy 410.155136 -276.899878) (xy 410.154641 -276.924485)
			(xy 410.146746 -276.973062) (xy 410.131162 -277.019743) (xy 410.108291 -277.06332) (xy 410.078726 -277.102664)
			(xy 410.043233 -277.136756) (xy 410.00273 -277.164712) (xy 409.958268 -277.18581) (xy 409.910997 -277.199502)
			(xy 409.862142 -277.205434) (xy 409.812967 -277.203453) (xy 409.764748 -277.193609) (xy 409.718732 -277.176157)
			(xy 409.676111 -277.15155) (xy 409.63799 -277.120425) (xy 409.605355 -277.083588) (xy 409.579052 -277.041992)
			(xy 409.559761 -276.996716) (xy 409.547984 -276.948932) (xy 409.544024 -276.899878) (xy 409.205176 -276.899878)
			(xy 409.204681 -276.924485) (xy 409.196786 -276.973062) (xy 409.181202 -277.019743) (xy 409.158331 -277.06332)
			(xy 409.128766 -277.102664) (xy 409.093273 -277.136756) (xy 409.05277 -277.164712) (xy 409.008308 -277.18581)
			(xy 408.961037 -277.199502) (xy 408.912182 -277.205434) (xy 408.863007 -277.203453) (xy 408.814788 -277.193609)
			(xy 408.768772 -277.176157) (xy 408.726151 -277.15155) (xy 408.68803 -277.120425) (xy 408.655395 -277.083588)
			(xy 408.629092 -277.041992) (xy 408.609801 -276.996716) (xy 408.598024 -276.948932) (xy 408.594064 -276.899878)
			(xy 408.255216 -276.899878) (xy 408.254721 -276.924485) (xy 408.246826 -276.973062) (xy 408.231242 -277.019743)
			(xy 408.208371 -277.06332) (xy 408.178806 -277.102664) (xy 408.143313 -277.136756) (xy 408.10281 -277.164712)
			(xy 408.058348 -277.18581) (xy 408.011077 -277.199502) (xy 407.962222 -277.205434) (xy 407.913047 -277.203453)
			(xy 407.864828 -277.193609) (xy 407.818812 -277.176157) (xy 407.776191 -277.15155) (xy 407.73807 -277.120425)
			(xy 407.705435 -277.083588) (xy 407.679132 -277.041992) (xy 407.659841 -276.996716) (xy 407.648064 -276.948932)
			(xy 407.644104 -276.899878) (xy 407.305256 -276.899878) (xy 407.304761 -276.924485) (xy 407.296866 -276.973062)
			(xy 407.281282 -277.019743) (xy 407.258411 -277.06332) (xy 407.228846 -277.102664) (xy 407.193353 -277.136756)
			(xy 407.15285 -277.164712) (xy 407.108388 -277.18581) (xy 407.061117 -277.199502) (xy 407.012262 -277.205434)
			(xy 406.963087 -277.203453) (xy 406.914868 -277.193609) (xy 406.868852 -277.176157) (xy 406.826231 -277.15155)
			(xy 406.78811 -277.120425) (xy 406.755475 -277.083588) (xy 406.729172 -277.041992) (xy 406.709881 -276.996716)
			(xy 406.698104 -276.948932) (xy 406.694144 -276.899878) (xy 406.355296 -276.899878) (xy 406.354801 -276.924485)
			(xy 406.346906 -276.973062) (xy 406.331322 -277.019743) (xy 406.308451 -277.06332) (xy 406.278886 -277.102664)
			(xy 406.243393 -277.136756) (xy 406.20289 -277.164712) (xy 406.158428 -277.18581) (xy 406.111157 -277.199502)
			(xy 406.062302 -277.205434) (xy 406.013127 -277.203453) (xy 405.964908 -277.193609) (xy 405.918892 -277.176157)
			(xy 405.876271 -277.15155) (xy 405.83815 -277.120425) (xy 405.805515 -277.083588) (xy 405.779212 -277.041992)
			(xy 405.759921 -276.996716) (xy 405.748144 -276.948932) (xy 405.744184 -276.899878) (xy 405.405336 -276.899878)
			(xy 405.404841 -276.924485) (xy 405.396946 -276.973062) (xy 405.381362 -277.019743) (xy 405.358491 -277.06332)
			(xy 405.328926 -277.102664) (xy 405.293433 -277.136756) (xy 405.25293 -277.164712) (xy 405.208468 -277.18581)
			(xy 405.161197 -277.199502) (xy 405.112342 -277.205434) (xy 405.063167 -277.203453) (xy 405.014948 -277.193609)
			(xy 404.968932 -277.176157) (xy 404.926311 -277.15155) (xy 404.88819 -277.120425) (xy 404.855555 -277.083588)
			(xy 404.829252 -277.041992) (xy 404.809961 -276.996716) (xy 404.798184 -276.948932) (xy 404.794224 -276.899878)
			(xy 404.455122 -276.899878) (xy 404.454627 -276.924485) (xy 404.446732 -276.973062) (xy 404.431148 -277.019743)
			(xy 404.408277 -277.06332) (xy 404.378712 -277.102664) (xy 404.343219 -277.136756) (xy 404.302716 -277.164712)
			(xy 404.258254 -277.18581) (xy 404.210983 -277.199502) (xy 404.162128 -277.205434) (xy 404.112953 -277.203453)
			(xy 404.064734 -277.193609) (xy 404.018718 -277.176157) (xy 403.976097 -277.15155) (xy 403.937976 -277.120425)
			(xy 403.905341 -277.083588) (xy 403.879038 -277.041992) (xy 403.859747 -276.996716) (xy 403.84797 -276.948932)
			(xy 403.84401 -276.899878) (xy 403.505162 -276.899878) (xy 403.504667 -276.924485) (xy 403.496772 -276.973062)
			(xy 403.481188 -277.019743) (xy 403.458317 -277.06332) (xy 403.428752 -277.102664) (xy 403.393259 -277.136756)
			(xy 403.352756 -277.164712) (xy 403.308294 -277.18581) (xy 403.261023 -277.199502) (xy 403.212168 -277.205434)
			(xy 403.162993 -277.203453) (xy 403.114774 -277.193609) (xy 403.068758 -277.176157) (xy 403.026137 -277.15155)
			(xy 402.988016 -277.120425) (xy 402.955381 -277.083588) (xy 402.929078 -277.041992) (xy 402.909787 -276.996716)
			(xy 402.89801 -276.948932) (xy 402.89405 -276.899878) (xy 402.555202 -276.899878) (xy 402.554707 -276.924485)
			(xy 402.546812 -276.973062) (xy 402.531228 -277.019743) (xy 402.508357 -277.06332) (xy 402.478792 -277.102664)
			(xy 402.443299 -277.136756) (xy 402.402796 -277.164712) (xy 402.358334 -277.18581) (xy 402.311063 -277.199502)
			(xy 402.262208 -277.205434) (xy 402.213033 -277.203453) (xy 402.164814 -277.193609) (xy 402.118798 -277.176157)
			(xy 402.076177 -277.15155) (xy 402.038056 -277.120425) (xy 402.005421 -277.083588) (xy 401.979118 -277.041992)
			(xy 401.959827 -276.996716) (xy 401.94805 -276.948932) (xy 401.94409 -276.899878) (xy 401.605242 -276.899878)
			(xy 401.604747 -276.924485) (xy 401.596852 -276.973062) (xy 401.581268 -277.019743) (xy 401.558397 -277.06332)
			(xy 401.528832 -277.102664) (xy 401.493339 -277.136756) (xy 401.452836 -277.164712) (xy 401.408374 -277.18581)
			(xy 401.361103 -277.199502) (xy 401.312248 -277.205434) (xy 401.263073 -277.203453) (xy 401.214854 -277.193609)
			(xy 401.168838 -277.176157) (xy 401.126217 -277.15155) (xy 401.088096 -277.120425) (xy 401.055461 -277.083588)
			(xy 401.029158 -277.041992) (xy 401.009867 -276.996716) (xy 400.99809 -276.948932) (xy 400.99413 -276.899878)
			(xy 400.655282 -276.899878) (xy 400.654787 -276.924485) (xy 400.646892 -276.973062) (xy 400.631308 -277.019743)
			(xy 400.608437 -277.06332) (xy 400.578872 -277.102664) (xy 400.543379 -277.136756) (xy 400.502876 -277.164712)
			(xy 400.458414 -277.18581) (xy 400.411143 -277.199502) (xy 400.362288 -277.205434) (xy 400.313113 -277.203453)
			(xy 400.264894 -277.193609) (xy 400.218878 -277.176157) (xy 400.176257 -277.15155) (xy 400.138136 -277.120425)
			(xy 400.105501 -277.083588) (xy 400.079198 -277.041992) (xy 400.059907 -276.996716) (xy 400.04813 -276.948932)
			(xy 400.04417 -276.899878) (xy 399.705322 -276.899878) (xy 399.704827 -276.924485) (xy 399.696932 -276.973062)
			(xy 399.681348 -277.019743) (xy 399.658477 -277.06332) (xy 399.628912 -277.102664) (xy 399.593419 -277.136756)
			(xy 399.552916 -277.164712) (xy 399.508454 -277.18581) (xy 399.461183 -277.199502) (xy 399.412328 -277.205434)
			(xy 399.363153 -277.203453) (xy 399.314934 -277.193609) (xy 399.268918 -277.176157) (xy 399.226297 -277.15155)
			(xy 399.188176 -277.120425) (xy 399.155541 -277.083588) (xy 399.129238 -277.041992) (xy 399.109947 -276.996716)
			(xy 399.09817 -276.948932) (xy 399.09421 -276.899878) (xy 398.755651 -276.899878) (xy 398.755653 -276.8999)
			(xy 398.751482 -276.950242) (xy 398.739081 -276.99921) (xy 398.71879 -277.04547) (xy 398.691161 -277.087759)
			(xy 398.656949 -277.124923) (xy 398.617086 -277.15595) (xy 398.57266 -277.179992) (xy 398.524882 -277.196394)
			(xy 398.475057 -277.204708) (xy 398.4498 -277.205186) (xy 398.440569 -277.205099) (xy 398.422141 -277.203953)
			(xy 398.41297 -277.2029) (xy 398.400778 -277.201376) (xy 398.37868 -277.209504) (xy 398.305528 -277.285704)
			(xy 398.29867 -277.30831) (xy 398.300448 -277.320502) (xy 398.302559 -277.333865) (xy 398.304848 -277.360823)
			(xy 398.30502 -277.37435) (xy 398.30502 -277.423372) (xy 398.305475 -277.434033) (xy 398.314152 -277.453507)
			(xy 398.317885 -277.457154) (xy 450.500496 -277.457154) (xy 450.500995 -277.429785) (xy 450.508805 -277.375607)
			(xy 450.524286 -277.323105) (xy 450.547121 -277.273357) (xy 450.576838 -277.227389) (xy 450.594476 -277.206456)
			(xy 450.600572 -277.199344) (xy 450.606922 -277.182326) (xy 450.606922 -277.096982) (xy 450.600572 -277.079964)
			(xy 450.594476 -277.072852) (xy 450.576844 -277.051914) (xy 450.547132 -277.005943) (xy 450.524295 -276.956197)
			(xy 450.508802 -276.903697) (xy 450.500972 -276.849523) (xy 450.500496 -276.822154) (xy 450.500935 -276.794901)
			(xy 450.508698 -276.740952) (xy 450.524059 -276.688656) (xy 450.546706 -276.639078) (xy 450.576177 -276.593228)
			(xy 450.611874 -276.552038) (xy 450.653068 -276.516347) (xy 450.698922 -276.486882) (xy 450.748503 -276.464242)
			(xy 450.800801 -276.448887) (xy 450.854751 -276.441131) (xy 450.882004 -276.440646) (xy 450.910742 -276.441182)
			(xy 450.967568 -276.449804) (xy 451.022458 -276.466852) (xy 451.07417 -276.49194) (xy 451.121534 -276.524501)
			(xy 451.142862 -276.54377) (xy 451.149974 -276.550374) (xy 451.1675 -276.557486) (xy 451.256908 -276.557486)
			(xy 451.274434 -276.550374) (xy 451.281546 -276.54377) (xy 451.302873 -276.5245) (xy 451.350236 -276.491935)
			(xy 451.401947 -276.466844) (xy 451.456838 -276.449794) (xy 451.513665 -276.441172) (xy 451.571143 -276.441172)
			(xy 451.62797 -276.449794) (xy 451.682861 -276.466844) (xy 451.734572 -276.491935) (xy 451.781935 -276.5245)
			(xy 451.803262 -276.54377) (xy 451.810374 -276.550374) (xy 451.8279 -276.557486) (xy 451.917308 -276.557486)
			(xy 451.934834 -276.550374) (xy 451.941946 -276.54377) (xy 451.963273 -276.5245) (xy 452.010636 -276.491935)
			(xy 452.062347 -276.466844) (xy 452.117238 -276.449794) (xy 452.174065 -276.441172) (xy 452.231543 -276.441172)
			(xy 452.28837 -276.449794) (xy 452.343261 -276.466844) (xy 452.394972 -276.491935) (xy 452.442335 -276.5245)
			(xy 452.463662 -276.54377) (xy 452.470774 -276.550374) (xy 452.4883 -276.557486) (xy 452.577708 -276.557486)
			(xy 452.595234 -276.550374) (xy 452.602346 -276.54377) (xy 452.623676 -276.524503) (xy 452.671037 -276.491935)
			(xy 452.722747 -276.466841) (xy 452.777638 -276.44979) (xy 452.834465 -276.441167) (xy 452.863204 -276.440646)
			(xy 452.890453 -276.441174) (xy 452.944397 -276.44893) (xy 452.996688 -276.464283) (xy 453.046262 -276.486921)
			(xy 453.054885 -276.492462) (xy 455.756008 -276.492462) (xy 455.760079 -276.43684) (xy 455.772205 -276.382403)
			(xy 455.792128 -276.330312) (xy 455.819424 -276.281677) (xy 455.85351 -276.237534) (xy 455.893659 -276.198825)
			(xy 455.939017 -276.166374) (xy 455.988617 -276.140873) (xy 456.041401 -276.122866) (xy 456.096244 -276.112736)
			(xy 456.151978 -276.110699) (xy 456.207415 -276.116799) (xy 456.261372 -276.130905) (xy 456.312701 -276.152717)
			(xy 456.360307 -276.181771) (xy 456.403175 -276.217446) (xy 456.440392 -276.258983) (xy 456.471165 -276.305496)
			(xy 456.494837 -276.355993) (xy 456.510905 -276.4094) (xy 456.519025 -276.464576) (xy 456.519534 -276.492462)
			(xy 456.519025 -276.520348) (xy 456.510905 -276.575524) (xy 456.494837 -276.628931) (xy 456.488321 -276.64283)
			(xy 461.074006 -276.64283) (xy 461.078077 -276.587208) (xy 461.090203 -276.532771) (xy 461.110126 -276.48068)
			(xy 461.137422 -276.432045) (xy 461.171508 -276.387902) (xy 461.211657 -276.349193) (xy 461.257015 -276.316742)
			(xy 461.306615 -276.291241) (xy 461.359399 -276.273234) (xy 461.414242 -276.263104) (xy 461.469976 -276.261067)
			(xy 461.525413 -276.267167) (xy 461.57937 -276.281273) (xy 461.630699 -276.303085) (xy 461.678305 -276.332139)
			(xy 461.721173 -276.367814) (xy 461.75839 -276.409351) (xy 461.789163 -276.455864) (xy 461.812835 -276.506361)
			(xy 461.828903 -276.559768) (xy 461.837023 -276.614944) (xy 461.837532 -276.64283) (xy 461.837023 -276.670716)
			(xy 461.828903 -276.725892) (xy 461.812835 -276.779299) (xy 461.789163 -276.829796) (xy 461.75839 -276.876309)
			(xy 461.721173 -276.917846) (xy 461.678305 -276.953521) (xy 461.630699 -276.982575) (xy 461.57937 -277.004387)
			(xy 461.525413 -277.018493) (xy 461.469976 -277.024593) (xy 461.414242 -277.022556) (xy 461.359399 -277.012426)
			(xy 461.306615 -276.994419) (xy 461.257015 -276.968918) (xy 461.211657 -276.936467) (xy 461.171508 -276.897758)
			(xy 461.137422 -276.853615) (xy 461.110126 -276.80498) (xy 461.090203 -276.752889) (xy 461.078077 -276.698452)
			(xy 461.074006 -276.64283) (xy 456.488321 -276.64283) (xy 456.471165 -276.679428) (xy 456.440392 -276.725941)
			(xy 456.403175 -276.767478) (xy 456.360307 -276.803153) (xy 456.312701 -276.832207) (xy 456.261372 -276.854019)
			(xy 456.207415 -276.868125) (xy 456.151978 -276.874225) (xy 456.096244 -276.872188) (xy 456.041401 -276.862058)
			(xy 455.988617 -276.844051) (xy 455.939017 -276.81855) (xy 455.893659 -276.786099) (xy 455.85351 -276.74739)
			(xy 455.819424 -276.703247) (xy 455.792128 -276.654612) (xy 455.772205 -276.602521) (xy 455.760079 -276.548084)
			(xy 455.756008 -276.492462) (xy 453.054885 -276.492462) (xy 453.092111 -276.516384) (xy 453.1333 -276.552071)
			(xy 453.168991 -276.593256) (xy 453.198458 -276.639101) (xy 453.221102 -276.688672) (xy 453.236461 -276.740962)
			(xy 453.244223 -276.794905) (xy 453.244712 -276.822154) (xy 453.244216 -276.849523) (xy 453.236405 -276.903701)
			(xy 453.220923 -276.956203) (xy 453.198088 -277.005951) (xy 453.16837 -277.051919) (xy 453.150732 -277.072852)
			(xy 453.144636 -277.079964) (xy 453.138286 -277.096982) (xy 453.138286 -277.182326) (xy 453.144636 -277.199344)
			(xy 453.150732 -277.206456) (xy 453.168369 -277.22739) (xy 453.19808 -277.273363) (xy 453.220916 -277.32311)
			(xy 453.224943 -277.336758) (xy 458.091284 -277.336758) (xy 458.095355 -277.281136) (xy 458.107481 -277.226699)
			(xy 458.127404 -277.174608) (xy 458.1547 -277.125973) (xy 458.188786 -277.08183) (xy 458.228935 -277.043121)
			(xy 458.274293 -277.01067) (xy 458.323893 -276.985169) (xy 458.376677 -276.967162) (xy 458.43152 -276.957032)
			(xy 458.487254 -276.954995) (xy 458.542691 -276.961095) (xy 458.596648 -276.975201) (xy 458.647977 -276.997013)
			(xy 458.695583 -277.026067) (xy 458.738451 -277.061742) (xy 458.775668 -277.103279) (xy 458.806441 -277.149792)
			(xy 458.830113 -277.200289) (xy 458.846181 -277.253696) (xy 458.854301 -277.308872) (xy 458.854601 -277.325328)
			(xy 459.280766 -277.325328) (xy 459.284837 -277.269706) (xy 459.296963 -277.215269) (xy 459.316886 -277.163178)
			(xy 459.344182 -277.114543) (xy 459.378268 -277.0704) (xy 459.418417 -277.031691) (xy 459.463775 -276.99924)
			(xy 459.513375 -276.973739) (xy 459.566159 -276.955732) (xy 459.621002 -276.945602) (xy 459.676736 -276.943565)
			(xy 459.732173 -276.949665) (xy 459.78613 -276.963771) (xy 459.837459 -276.985583) (xy 459.885065 -277.014637)
			(xy 459.927933 -277.050312) (xy 459.96515 -277.091849) (xy 459.995923 -277.138362) (xy 460.019595 -277.188859)
			(xy 460.035663 -277.242266) (xy 460.043783 -277.297442) (xy 460.044292 -277.325328) (xy 460.043783 -277.353214)
			(xy 460.035663 -277.40839) (xy 460.019595 -277.461797) (xy 459.995923 -277.512294) (xy 459.96515 -277.558807)
			(xy 459.927933 -277.600344) (xy 459.885065 -277.636019) (xy 459.837459 -277.665073) (xy 459.78613 -277.686885)
			(xy 459.732173 -277.700991) (xy 459.676736 -277.707091) (xy 459.621002 -277.705054) (xy 459.566159 -277.694924)
			(xy 459.513375 -277.676917) (xy 459.463775 -277.651416) (xy 459.418417 -277.618965) (xy 459.378268 -277.580256)
			(xy 459.344182 -277.536113) (xy 459.316886 -277.487478) (xy 459.296963 -277.435387) (xy 459.284837 -277.38095)
			(xy 459.280766 -277.325328) (xy 458.854601 -277.325328) (xy 458.85481 -277.336758) (xy 458.854301 -277.364644)
			(xy 458.846181 -277.41982) (xy 458.830113 -277.473227) (xy 458.806441 -277.523724) (xy 458.775668 -277.570237)
			(xy 458.738451 -277.611774) (xy 458.695583 -277.647449) (xy 458.647977 -277.676503) (xy 458.596648 -277.698315)
			(xy 458.542691 -277.712421) (xy 458.487254 -277.718521) (xy 458.43152 -277.716484) (xy 458.376677 -277.706354)
			(xy 458.323893 -277.688347) (xy 458.274293 -277.662846) (xy 458.228935 -277.630395) (xy 458.188786 -277.591686)
			(xy 458.1547 -277.547543) (xy 458.127404 -277.498908) (xy 458.107481 -277.446817) (xy 458.095355 -277.39238)
			(xy 458.091284 -277.336758) (xy 453.224943 -277.336758) (xy 453.236408 -277.37561) (xy 453.244237 -277.429785)
			(xy 453.244712 -277.457154) (xy 453.244202 -277.484406) (xy 453.236451 -277.538355) (xy 453.221101 -277.590651)
			(xy 453.198464 -277.640231) (xy 453.169002 -277.686084) (xy 453.133313 -277.727277) (xy 453.092124 -277.762972)
			(xy 453.046275 -277.79244) (xy 452.996698 -277.815084) (xy 452.944404 -277.830441) (xy 452.890455 -277.838198)
			(xy 452.863204 -277.838662) (xy 452.834466 -277.838119) (xy 452.77764 -277.829499) (xy 452.72275 -277.812452)
			(xy 452.671038 -277.787365) (xy 452.623674 -277.754806) (xy 452.602346 -277.735538) (xy 452.595234 -277.728934)
			(xy 452.577708 -277.721822) (xy 452.4883 -277.721822) (xy 452.470774 -277.728934) (xy 452.463662 -277.735538)
			(xy 452.442335 -277.754808) (xy 452.394972 -277.787373) (xy 452.343261 -277.812464) (xy 452.28837 -277.829514)
			(xy 452.231543 -277.838136) (xy 452.174065 -277.838136) (xy 452.117238 -277.829514) (xy 452.062347 -277.812464)
			(xy 452.010636 -277.787373) (xy 451.963273 -277.754808) (xy 451.941946 -277.735538) (xy 451.934834 -277.728934)
			(xy 451.917308 -277.721822) (xy 451.8279 -277.721822) (xy 451.810374 -277.728934) (xy 451.803262 -277.735538)
			(xy 451.781935 -277.754808) (xy 451.734572 -277.787373) (xy 451.682861 -277.812464) (xy 451.62797 -277.829514)
			(xy 451.571143 -277.838136) (xy 451.513665 -277.838136) (xy 451.456838 -277.829514) (xy 451.401947 -277.812464)
			(xy 451.350236 -277.787373) (xy 451.302873 -277.754808) (xy 451.281546 -277.735538) (xy 451.274434 -277.728934)
			(xy 451.256908 -277.721822) (xy 451.1675 -277.721822) (xy 451.149974 -277.728934) (xy 451.142862 -277.735538)
			(xy 451.12153 -277.754803) (xy 451.07417 -277.787371) (xy 451.022459 -277.812465) (xy 450.96757 -277.829517)
			(xy 450.910743 -277.838141) (xy 450.882004 -277.838662) (xy 450.854749 -277.838241) (xy 450.800794 -277.830483)
			(xy 450.748493 -277.815125) (xy 450.69891 -277.79248) (xy 450.653054 -277.763008) (xy 450.61186 -277.72731)
			(xy 450.576167 -277.686112) (xy 450.5467 -277.640253) (xy 450.52406 -277.590668) (xy 450.508708 -277.538365)
			(xy 450.500956 -277.484409) (xy 450.500496 -277.457154) (xy 398.317885 -277.457154) (xy 398.321784 -277.460964)
			(xy 398.385792 -277.518876) (xy 398.406112 -277.52548) (xy 398.41678 -277.524464) (xy 398.4498 -277.52294)
			(xy 398.475485 -277.523444) (xy 398.526222 -277.53148) (xy 398.575077 -277.547354) (xy 398.620848 -277.570675)
			(xy 398.662407 -277.600869) (xy 398.698731 -277.637193) (xy 398.728925 -277.678752) (xy 398.752246 -277.724523)
			(xy 398.76812 -277.773378) (xy 398.776156 -277.824115) (xy 398.776156 -277.849838) (xy 399.09421 -277.849838)
			(xy 399.09817 -277.800784) (xy 399.109947 -277.753) (xy 399.129238 -277.707724) (xy 399.155541 -277.666128)
			(xy 399.188176 -277.629291) (xy 399.226297 -277.598166) (xy 399.268918 -277.573559) (xy 399.314934 -277.556107)
			(xy 399.363153 -277.546263) (xy 399.412328 -277.544282) (xy 399.461183 -277.550214) (xy 399.508454 -277.563906)
			(xy 399.552916 -277.585004) (xy 399.593419 -277.61296) (xy 399.628912 -277.647052) (xy 399.658477 -277.686396)
			(xy 399.681348 -277.729973) (xy 399.696932 -277.776654) (xy 399.704827 -277.825231) (xy 399.705322 -277.849838)
			(xy 399.704827 -277.874445) (xy 399.704648 -277.875546) (xy 400.023326 -277.875546) (xy 400.023326 -277.82413)
			(xy 400.031369 -277.773348) (xy 400.047257 -277.724449) (xy 400.0706 -277.678637) (xy 400.100821 -277.637041)
			(xy 400.137177 -277.600685) (xy 400.178773 -277.570464) (xy 400.224585 -277.547121) (xy 400.273484 -277.531233)
			(xy 400.324266 -277.52319) (xy 400.375682 -277.52319) (xy 400.426464 -277.531233) (xy 400.475363 -277.547121)
			(xy 400.521175 -277.570464) (xy 400.562771 -277.600685) (xy 400.599127 -277.637041) (xy 400.629348 -277.678637)
			(xy 400.652691 -277.724449) (xy 400.668579 -277.773348) (xy 400.676622 -277.82413) (xy 400.677126 -277.849838)
			(xy 400.99413 -277.849838) (xy 400.99809 -277.800784) (xy 401.009867 -277.753) (xy 401.029158 -277.707724)
			(xy 401.055461 -277.666128) (xy 401.088096 -277.629291) (xy 401.126217 -277.598166) (xy 401.168838 -277.573559)
			(xy 401.214854 -277.556107) (xy 401.263073 -277.546263) (xy 401.312248 -277.544282) (xy 401.361103 -277.550214)
			(xy 401.408374 -277.563906) (xy 401.452836 -277.585004) (xy 401.493339 -277.61296) (xy 401.528832 -277.647052)
			(xy 401.558397 -277.686396) (xy 401.581268 -277.729973) (xy 401.596852 -277.776654) (xy 401.604747 -277.825231)
			(xy 401.605242 -277.849838) (xy 401.604747 -277.874445) (xy 401.604568 -277.875546) (xy 401.923246 -277.875546)
			(xy 401.923246 -277.82413) (xy 401.931289 -277.773348) (xy 401.947177 -277.724449) (xy 401.97052 -277.678637)
			(xy 402.000741 -277.637041) (xy 402.037097 -277.600685) (xy 402.078693 -277.570464) (xy 402.124505 -277.547121)
			(xy 402.173404 -277.531233) (xy 402.224186 -277.52319) (xy 402.275602 -277.52319) (xy 402.326384 -277.531233)
			(xy 402.375283 -277.547121) (xy 402.421095 -277.570464) (xy 402.462691 -277.600685) (xy 402.499047 -277.637041)
			(xy 402.529268 -277.678637) (xy 402.552611 -277.724449) (xy 402.568499 -277.773348) (xy 402.576542 -277.82413)
			(xy 402.577046 -277.849838) (xy 402.89405 -277.849838) (xy 402.89801 -277.800784) (xy 402.909787 -277.753)
			(xy 402.929078 -277.707724) (xy 402.955381 -277.666128) (xy 402.988016 -277.629291) (xy 403.026137 -277.598166)
			(xy 403.068758 -277.573559) (xy 403.114774 -277.556107) (xy 403.162993 -277.546263) (xy 403.212168 -277.544282)
			(xy 403.261023 -277.550214) (xy 403.308294 -277.563906) (xy 403.352756 -277.585004) (xy 403.393259 -277.61296)
			(xy 403.428752 -277.647052) (xy 403.458317 -277.686396) (xy 403.481188 -277.729973) (xy 403.496772 -277.776654)
			(xy 403.504667 -277.825231) (xy 403.505162 -277.849838) (xy 403.504667 -277.874445) (xy 403.504488 -277.875546)
			(xy 403.823166 -277.875546) (xy 403.823166 -277.82413) (xy 403.831209 -277.773348) (xy 403.847097 -277.724449)
			(xy 403.87044 -277.678637) (xy 403.900661 -277.637041) (xy 403.937017 -277.600685) (xy 403.978613 -277.570464)
			(xy 404.024425 -277.547121) (xy 404.073324 -277.531233) (xy 404.124106 -277.52319) (xy 404.175522 -277.52319)
			(xy 404.226304 -277.531233) (xy 404.275203 -277.547121) (xy 404.321015 -277.570464) (xy 404.362611 -277.600685)
			(xy 404.398967 -277.637041) (xy 404.429188 -277.678637) (xy 404.452531 -277.724449) (xy 404.468419 -277.773348)
			(xy 404.476462 -277.82413) (xy 404.476966 -277.849838) (xy 404.794224 -277.849838) (xy 404.798184 -277.800784)
			(xy 404.809961 -277.753) (xy 404.829252 -277.707724) (xy 404.855555 -277.666128) (xy 404.88819 -277.629291)
			(xy 404.926311 -277.598166) (xy 404.968932 -277.573559) (xy 405.014948 -277.556107) (xy 405.063167 -277.546263)
			(xy 405.112342 -277.544282) (xy 405.161197 -277.550214) (xy 405.208468 -277.563906) (xy 405.25293 -277.585004)
			(xy 405.293433 -277.61296) (xy 405.328926 -277.647052) (xy 405.358491 -277.686396) (xy 405.381362 -277.729973)
			(xy 405.396946 -277.776654) (xy 405.404841 -277.825231) (xy 405.405336 -277.849838) (xy 405.404841 -277.874445)
			(xy 405.404662 -277.875546) (xy 405.72334 -277.875546) (xy 405.72334 -277.82413) (xy 405.731383 -277.773348)
			(xy 405.747271 -277.724449) (xy 405.770614 -277.678637) (xy 405.800835 -277.637041) (xy 405.837191 -277.600685)
			(xy 405.878787 -277.570464) (xy 405.924599 -277.547121) (xy 405.973498 -277.531233) (xy 406.02428 -277.52319)
			(xy 406.075696 -277.52319) (xy 406.126478 -277.531233) (xy 406.175377 -277.547121) (xy 406.221189 -277.570464)
			(xy 406.262785 -277.600685) (xy 406.299141 -277.637041) (xy 406.329362 -277.678637) (xy 406.352705 -277.724449)
			(xy 406.368593 -277.773348) (xy 406.376636 -277.82413) (xy 406.37714 -277.849838) (xy 406.694144 -277.849838)
			(xy 406.698104 -277.800784) (xy 406.709881 -277.753) (xy 406.729172 -277.707724) (xy 406.755475 -277.666128)
			(xy 406.78811 -277.629291) (xy 406.826231 -277.598166) (xy 406.868852 -277.573559) (xy 406.914868 -277.556107)
			(xy 406.963087 -277.546263) (xy 407.012262 -277.544282) (xy 407.061117 -277.550214) (xy 407.108388 -277.563906)
			(xy 407.15285 -277.585004) (xy 407.193353 -277.61296) (xy 407.228846 -277.647052) (xy 407.258411 -277.686396)
			(xy 407.281282 -277.729973) (xy 407.296866 -277.776654) (xy 407.304761 -277.825231) (xy 407.305256 -277.849838)
			(xy 407.304761 -277.874445) (xy 407.304582 -277.875546) (xy 407.623006 -277.875546) (xy 407.623006 -277.82413)
			(xy 407.631049 -277.773348) (xy 407.646937 -277.724449) (xy 407.67028 -277.678637) (xy 407.700501 -277.637041)
			(xy 407.736857 -277.600685) (xy 407.778453 -277.570464) (xy 407.824265 -277.547121) (xy 407.873164 -277.531233)
			(xy 407.923946 -277.52319) (xy 407.975362 -277.52319) (xy 408.026144 -277.531233) (xy 408.075043 -277.547121)
			(xy 408.120855 -277.570464) (xy 408.162451 -277.600685) (xy 408.198807 -277.637041) (xy 408.229028 -277.678637)
			(xy 408.252371 -277.724449) (xy 408.268259 -277.773348) (xy 408.276302 -277.82413) (xy 408.276806 -277.849838)
			(xy 408.594064 -277.849838) (xy 408.598024 -277.800784) (xy 408.609801 -277.753) (xy 408.629092 -277.707724)
			(xy 408.655395 -277.666128) (xy 408.68803 -277.629291) (xy 408.726151 -277.598166) (xy 408.768772 -277.573559)
			(xy 408.814788 -277.556107) (xy 408.863007 -277.546263) (xy 408.912182 -277.544282) (xy 408.961037 -277.550214)
			(xy 409.008308 -277.563906) (xy 409.05277 -277.585004) (xy 409.093273 -277.61296) (xy 409.128766 -277.647052)
			(xy 409.158331 -277.686396) (xy 409.181202 -277.729973) (xy 409.196786 -277.776654) (xy 409.204681 -277.825231)
			(xy 409.205176 -277.849838) (xy 409.204681 -277.874445) (xy 409.204502 -277.875546) (xy 409.522926 -277.875546)
			(xy 409.522926 -277.82413) (xy 409.530969 -277.773348) (xy 409.546857 -277.724449) (xy 409.5702 -277.678637)
			(xy 409.600421 -277.637041) (xy 409.636777 -277.600685) (xy 409.678373 -277.570464) (xy 409.724185 -277.547121)
			(xy 409.773084 -277.531233) (xy 409.823866 -277.52319) (xy 409.875282 -277.52319) (xy 409.926064 -277.531233)
			(xy 409.974963 -277.547121) (xy 410.020775 -277.570464) (xy 410.062371 -277.600685) (xy 410.098727 -277.637041)
			(xy 410.128948 -277.678637) (xy 410.152291 -277.724449) (xy 410.168179 -277.773348) (xy 410.176222 -277.82413)
			(xy 410.176726 -277.849838) (xy 410.493984 -277.849838) (xy 410.497944 -277.800784) (xy 410.509721 -277.753)
			(xy 410.529012 -277.707724) (xy 410.555315 -277.666128) (xy 410.58795 -277.629291) (xy 410.626071 -277.598166)
			(xy 410.668692 -277.573559) (xy 410.714708 -277.556107) (xy 410.762927 -277.546263) (xy 410.812102 -277.544282)
			(xy 410.860957 -277.550214) (xy 410.908228 -277.563906) (xy 410.95269 -277.585004) (xy 410.993193 -277.61296)
			(xy 411.028686 -277.647052) (xy 411.058251 -277.686396) (xy 411.081122 -277.729973) (xy 411.096706 -277.776654)
			(xy 411.104601 -277.825231) (xy 411.105096 -277.849838) (xy 411.104601 -277.874445) (xy 411.104422 -277.875546)
			(xy 411.4231 -277.875546) (xy 411.4231 -277.82413) (xy 411.431143 -277.773348) (xy 411.447031 -277.724449)
			(xy 411.470374 -277.678637) (xy 411.500595 -277.637041) (xy 411.536951 -277.600685) (xy 411.578547 -277.570464)
			(xy 411.624359 -277.547121) (xy 411.673258 -277.531233) (xy 411.72404 -277.52319) (xy 411.775456 -277.52319)
			(xy 411.826238 -277.531233) (xy 411.875137 -277.547121) (xy 411.920949 -277.570464) (xy 411.962545 -277.600685)
			(xy 411.998901 -277.637041) (xy 412.029122 -277.678637) (xy 412.052465 -277.724449) (xy 412.068353 -277.773348)
			(xy 412.076396 -277.82413) (xy 412.0769 -277.849838) (xy 412.394158 -277.849838) (xy 412.398118 -277.800784)
			(xy 412.409895 -277.753) (xy 412.429186 -277.707724) (xy 412.455489 -277.666128) (xy 412.488124 -277.629291)
			(xy 412.526245 -277.598166) (xy 412.568866 -277.573559) (xy 412.614882 -277.556107) (xy 412.663101 -277.546263)
			(xy 412.712276 -277.544282) (xy 412.761131 -277.550214) (xy 412.808402 -277.563906) (xy 412.852864 -277.585004)
			(xy 412.893367 -277.61296) (xy 412.92886 -277.647052) (xy 412.958425 -277.686396) (xy 412.981296 -277.729973)
			(xy 412.99688 -277.776654) (xy 413.004775 -277.825231) (xy 413.00527 -277.849838) (xy 413.004775 -277.874445)
			(xy 413.004596 -277.875546) (xy 413.32302 -277.875546) (xy 413.32302 -277.82413) (xy 413.331063 -277.773348)
			(xy 413.346951 -277.724449) (xy 413.370294 -277.678637) (xy 413.400515 -277.637041) (xy 413.436871 -277.600685)
			(xy 413.478467 -277.570464) (xy 413.524279 -277.547121) (xy 413.573178 -277.531233) (xy 413.62396 -277.52319)
			(xy 413.675376 -277.52319) (xy 413.726158 -277.531233) (xy 413.775057 -277.547121) (xy 413.820869 -277.570464)
			(xy 413.862465 -277.600685) (xy 413.898821 -277.637041) (xy 413.929042 -277.678637) (xy 413.952385 -277.724449)
			(xy 413.968273 -277.773348) (xy 413.976316 -277.82413) (xy 413.97682 -277.849838) (xy 414.294078 -277.849838)
			(xy 414.298038 -277.800784) (xy 414.309815 -277.753) (xy 414.329106 -277.707724) (xy 414.355409 -277.666128)
			(xy 414.388044 -277.629291) (xy 414.426165 -277.598166) (xy 414.468786 -277.573559) (xy 414.514802 -277.556107)
			(xy 414.563021 -277.546263) (xy 414.612196 -277.544282) (xy 414.661051 -277.550214) (xy 414.708322 -277.563906)
			(xy 414.752784 -277.585004) (xy 414.793287 -277.61296) (xy 414.82878 -277.647052) (xy 414.858345 -277.686396)
			(xy 414.881216 -277.729973) (xy 414.8968 -277.776654) (xy 414.904695 -277.825231) (xy 414.90519 -277.849838)
			(xy 414.904695 -277.874445) (xy 414.904516 -277.875546) (xy 415.22294 -277.875546) (xy 415.22294 -277.82413)
			(xy 415.230983 -277.773348) (xy 415.246871 -277.724449) (xy 415.270214 -277.678637) (xy 415.300435 -277.637041)
			(xy 415.336791 -277.600685) (xy 415.378387 -277.570464) (xy 415.424199 -277.547121) (xy 415.473098 -277.531233)
			(xy 415.52388 -277.52319) (xy 415.575296 -277.52319) (xy 415.626078 -277.531233) (xy 415.674977 -277.547121)
			(xy 415.720789 -277.570464) (xy 415.762385 -277.600685) (xy 415.798741 -277.637041) (xy 415.828962 -277.678637)
			(xy 415.852305 -277.724449) (xy 415.868193 -277.773348) (xy 415.876236 -277.82413) (xy 415.87674 -277.849838)
			(xy 416.193998 -277.849838) (xy 416.197958 -277.800784) (xy 416.209735 -277.753) (xy 416.229026 -277.707724)
			(xy 416.255329 -277.666128) (xy 416.287964 -277.629291) (xy 416.326085 -277.598166) (xy 416.368706 -277.573559)
			(xy 416.414722 -277.556107) (xy 416.462941 -277.546263) (xy 416.512116 -277.544282) (xy 416.560971 -277.550214)
			(xy 416.608242 -277.563906) (xy 416.652704 -277.585004) (xy 416.693207 -277.61296) (xy 416.7287 -277.647052)
			(xy 416.758265 -277.686396) (xy 416.781136 -277.729973) (xy 416.79672 -277.776654) (xy 416.804615 -277.825231)
			(xy 416.80511 -277.849838) (xy 416.804615 -277.874445) (xy 416.804436 -277.875546) (xy 417.123114 -277.875546)
			(xy 417.123114 -277.82413) (xy 417.131157 -277.773348) (xy 417.147045 -277.724449) (xy 417.170388 -277.678637)
			(xy 417.200609 -277.637041) (xy 417.236965 -277.600685) (xy 417.278561 -277.570464) (xy 417.324373 -277.547121)
			(xy 417.373272 -277.531233) (xy 417.424054 -277.52319) (xy 417.47547 -277.52319) (xy 417.526252 -277.531233)
			(xy 417.575151 -277.547121) (xy 417.620963 -277.570464) (xy 417.662559 -277.600685) (xy 417.698915 -277.637041)
			(xy 417.729136 -277.678637) (xy 417.752479 -277.724449) (xy 417.768367 -277.773348) (xy 417.77641 -277.82413)
			(xy 417.776914 -277.849838) (xy 418.094172 -277.849838) (xy 418.098132 -277.800784) (xy 418.109909 -277.753)
			(xy 418.1292 -277.707724) (xy 418.155503 -277.666128) (xy 418.188138 -277.629291) (xy 418.226259 -277.598166)
			(xy 418.26888 -277.573559) (xy 418.314896 -277.556107) (xy 418.363115 -277.546263) (xy 418.41229 -277.544282)
			(xy 418.461145 -277.550214) (xy 418.508416 -277.563906) (xy 418.552878 -277.585004) (xy 418.593381 -277.61296)
			(xy 418.628874 -277.647052) (xy 418.658439 -277.686396) (xy 418.68131 -277.729973) (xy 418.696894 -277.776654)
			(xy 418.704789 -277.825231) (xy 418.705284 -277.849838) (xy 418.704789 -277.874445) (xy 418.70461 -277.875546)
			(xy 419.023034 -277.875546) (xy 419.023034 -277.82413) (xy 419.031077 -277.773348) (xy 419.046965 -277.724449)
			(xy 419.070308 -277.678637) (xy 419.100529 -277.637041) (xy 419.136885 -277.600685) (xy 419.178481 -277.570464)
			(xy 419.224293 -277.547121) (xy 419.273192 -277.531233) (xy 419.323974 -277.52319) (xy 419.37539 -277.52319)
			(xy 419.426172 -277.531233) (xy 419.475071 -277.547121) (xy 419.520883 -277.570464) (xy 419.562479 -277.600685)
			(xy 419.598835 -277.637041) (xy 419.629056 -277.678637) (xy 419.652399 -277.724449) (xy 419.668287 -277.773348)
			(xy 419.67633 -277.82413) (xy 419.676834 -277.849838) (xy 419.994092 -277.849838) (xy 419.998052 -277.800784)
			(xy 420.009829 -277.753) (xy 420.02912 -277.707724) (xy 420.055423 -277.666128) (xy 420.088058 -277.629291)
			(xy 420.126179 -277.598166) (xy 420.1688 -277.573559) (xy 420.214816 -277.556107) (xy 420.263035 -277.546263)
			(xy 420.31221 -277.544282) (xy 420.361065 -277.550214) (xy 420.408336 -277.563906) (xy 420.452798 -277.585004)
			(xy 420.493301 -277.61296) (xy 420.528794 -277.647052) (xy 420.558359 -277.686396) (xy 420.58123 -277.729973)
			(xy 420.596814 -277.776654) (xy 420.604709 -277.825231) (xy 420.605204 -277.849838) (xy 420.604709 -277.874445)
			(xy 420.60453 -277.875546) (xy 420.922954 -277.875546) (xy 420.922954 -277.82413) (xy 420.930997 -277.773348)
			(xy 420.946885 -277.724449) (xy 420.970228 -277.678637) (xy 421.000449 -277.637041) (xy 421.036805 -277.600685)
			(xy 421.078401 -277.570464) (xy 421.124213 -277.547121) (xy 421.173112 -277.531233) (xy 421.223894 -277.52319)
			(xy 421.27531 -277.52319) (xy 421.326092 -277.531233) (xy 421.374991 -277.547121) (xy 421.420803 -277.570464)
			(xy 421.462399 -277.600685) (xy 421.498755 -277.637041) (xy 421.528976 -277.678637) (xy 421.552319 -277.724449)
			(xy 421.568207 -277.773348) (xy 421.57625 -277.82413) (xy 421.576754 -277.849838) (xy 421.894012 -277.849838)
			(xy 421.897972 -277.800784) (xy 421.909749 -277.753) (xy 421.92904 -277.707724) (xy 421.955343 -277.666128)
			(xy 421.987978 -277.629291) (xy 422.026099 -277.598166) (xy 422.06872 -277.573559) (xy 422.114736 -277.556107)
			(xy 422.162955 -277.546263) (xy 422.21213 -277.544282) (xy 422.260985 -277.550214) (xy 422.308256 -277.563906)
			(xy 422.352718 -277.585004) (xy 422.393221 -277.61296) (xy 422.428714 -277.647052) (xy 422.458279 -277.686396)
			(xy 422.48115 -277.729973) (xy 422.496734 -277.776654) (xy 422.504629 -277.825231) (xy 422.505124 -277.849838)
			(xy 422.504629 -277.874445) (xy 422.50445 -277.875546) (xy 422.823128 -277.875546) (xy 422.823128 -277.82413)
			(xy 422.831171 -277.773348) (xy 422.847059 -277.724449) (xy 422.870402 -277.678637) (xy 422.900623 -277.637041)
			(xy 422.936979 -277.600685) (xy 422.978575 -277.570464) (xy 423.024387 -277.547121) (xy 423.073286 -277.531233)
			(xy 423.124068 -277.52319) (xy 423.175484 -277.52319) (xy 423.226266 -277.531233) (xy 423.275165 -277.547121)
			(xy 423.320977 -277.570464) (xy 423.362573 -277.600685) (xy 423.398929 -277.637041) (xy 423.42915 -277.678637)
			(xy 423.452493 -277.724449) (xy 423.468381 -277.773348) (xy 423.476424 -277.82413) (xy 423.476928 -277.849838)
			(xy 423.794186 -277.849838) (xy 423.798146 -277.800784) (xy 423.809923 -277.753) (xy 423.829214 -277.707724)
			(xy 423.855517 -277.666128) (xy 423.888152 -277.629291) (xy 423.926273 -277.598166) (xy 423.968894 -277.573559)
			(xy 424.01491 -277.556107) (xy 424.063129 -277.546263) (xy 424.112304 -277.544282) (xy 424.161159 -277.550214)
			(xy 424.20843 -277.563906) (xy 424.252892 -277.585004) (xy 424.293395 -277.61296) (xy 424.328888 -277.647052)
			(xy 424.358453 -277.686396) (xy 424.381324 -277.729973) (xy 424.396908 -277.776654) (xy 424.404803 -277.825231)
			(xy 424.405298 -277.849838) (xy 424.404803 -277.874445) (xy 424.404624 -277.875546) (xy 424.723048 -277.875546)
			(xy 424.723048 -277.82413) (xy 424.731091 -277.773348) (xy 424.746979 -277.724449) (xy 424.770322 -277.678637)
			(xy 424.800543 -277.637041) (xy 424.836899 -277.600685) (xy 424.878495 -277.570464) (xy 424.924307 -277.547121)
			(xy 424.973206 -277.531233) (xy 425.023988 -277.52319) (xy 425.075404 -277.52319) (xy 425.126186 -277.531233)
			(xy 425.175085 -277.547121) (xy 425.220897 -277.570464) (xy 425.262493 -277.600685) (xy 425.298849 -277.637041)
			(xy 425.32907 -277.678637) (xy 425.352413 -277.724449) (xy 425.368301 -277.773348) (xy 425.376344 -277.82413)
			(xy 425.376848 -277.849838) (xy 425.694106 -277.849838) (xy 425.698066 -277.800784) (xy 425.709843 -277.753)
			(xy 425.729134 -277.707724) (xy 425.755437 -277.666128) (xy 425.788072 -277.629291) (xy 425.826193 -277.598166)
			(xy 425.868814 -277.573559) (xy 425.91483 -277.556107) (xy 425.963049 -277.546263) (xy 426.012224 -277.544282)
			(xy 426.061079 -277.550214) (xy 426.10835 -277.563906) (xy 426.152812 -277.585004) (xy 426.193315 -277.61296)
			(xy 426.228808 -277.647052) (xy 426.258373 -277.686396) (xy 426.281244 -277.729973) (xy 426.296828 -277.776654)
			(xy 426.304723 -277.825231) (xy 426.305218 -277.849838) (xy 426.304723 -277.874445) (xy 426.304544 -277.875546)
			(xy 426.622968 -277.875546) (xy 426.622968 -277.82413) (xy 426.631011 -277.773348) (xy 426.646899 -277.724449)
			(xy 426.670242 -277.678637) (xy 426.700463 -277.637041) (xy 426.736819 -277.600685) (xy 426.778415 -277.570464)
			(xy 426.824227 -277.547121) (xy 426.873126 -277.531233) (xy 426.923908 -277.52319) (xy 426.975324 -277.52319)
			(xy 427.026106 -277.531233) (xy 427.075005 -277.547121) (xy 427.120817 -277.570464) (xy 427.162413 -277.600685)
			(xy 427.198769 -277.637041) (xy 427.22899 -277.678637) (xy 427.252333 -277.724449) (xy 427.268221 -277.773348)
			(xy 427.276264 -277.82413) (xy 427.276768 -277.849838) (xy 427.594026 -277.849838) (xy 427.597986 -277.800784)
			(xy 427.609763 -277.753) (xy 427.629054 -277.707724) (xy 427.655357 -277.666128) (xy 427.687992 -277.629291)
			(xy 427.726113 -277.598166) (xy 427.768734 -277.573559) (xy 427.81475 -277.556107) (xy 427.862969 -277.546263)
			(xy 427.912144 -277.544282) (xy 427.960999 -277.550214) (xy 428.00827 -277.563906) (xy 428.052732 -277.585004)
			(xy 428.093235 -277.61296) (xy 428.128728 -277.647052) (xy 428.158293 -277.686396) (xy 428.181164 -277.729973)
			(xy 428.196748 -277.776654) (xy 428.204643 -277.825231) (xy 428.205138 -277.849838) (xy 428.204643 -277.874445)
			(xy 428.204464 -277.875546) (xy 428.523142 -277.875546) (xy 428.523142 -277.82413) (xy 428.531185 -277.773348)
			(xy 428.547073 -277.724449) (xy 428.570416 -277.678637) (xy 428.600637 -277.637041) (xy 428.636993 -277.600685)
			(xy 428.678589 -277.570464) (xy 428.724401 -277.547121) (xy 428.7733 -277.531233) (xy 428.824082 -277.52319)
			(xy 428.875498 -277.52319) (xy 428.92628 -277.531233) (xy 428.975179 -277.547121) (xy 429.020991 -277.570464)
			(xy 429.062587 -277.600685) (xy 429.098943 -277.637041) (xy 429.129164 -277.678637) (xy 429.152507 -277.724449)
			(xy 429.168395 -277.773348) (xy 429.176438 -277.82413) (xy 429.176942 -277.849838) (xy 429.4942 -277.849838)
			(xy 429.49816 -277.800784) (xy 429.509937 -277.753) (xy 429.529228 -277.707724) (xy 429.555531 -277.666128)
			(xy 429.588166 -277.629291) (xy 429.626287 -277.598166) (xy 429.668908 -277.573559) (xy 429.714924 -277.556107)
			(xy 429.763143 -277.546263) (xy 429.812318 -277.544282) (xy 429.861173 -277.550214) (xy 429.908444 -277.563906)
			(xy 429.952906 -277.585004) (xy 429.993409 -277.61296) (xy 430.028902 -277.647052) (xy 430.058467 -277.686396)
			(xy 430.081338 -277.729973) (xy 430.096922 -277.776654) (xy 430.104817 -277.825231) (xy 430.105312 -277.849838)
			(xy 430.44416 -277.849838) (xy 430.44812 -277.800784) (xy 430.459897 -277.753) (xy 430.479188 -277.707724)
			(xy 430.505491 -277.666128) (xy 430.538126 -277.629291) (xy 430.576247 -277.598166) (xy 430.618868 -277.573559)
			(xy 430.664884 -277.556107) (xy 430.713103 -277.546263) (xy 430.762278 -277.544282) (xy 430.811133 -277.550214)
			(xy 430.858404 -277.563906) (xy 430.902866 -277.585004) (xy 430.943369 -277.61296) (xy 430.978862 -277.647052)
			(xy 431.008427 -277.686396) (xy 431.031298 -277.729973) (xy 431.046882 -277.776654) (xy 431.054777 -277.825231)
			(xy 431.055272 -277.849838) (xy 431.054777 -277.874445) (xy 431.046882 -277.923022) (xy 431.031298 -277.969703)
			(xy 431.008427 -278.01328) (xy 430.978862 -278.052624) (xy 430.943369 -278.086716) (xy 430.902866 -278.114672)
			(xy 430.858404 -278.13577) (xy 430.811133 -278.149462) (xy 430.762278 -278.155394) (xy 430.713103 -278.153413)
			(xy 430.664884 -278.143569) (xy 430.618868 -278.126117) (xy 430.576247 -278.10151) (xy 430.538126 -278.070385)
			(xy 430.505491 -278.033548) (xy 430.479188 -277.991952) (xy 430.459897 -277.946676) (xy 430.44812 -277.898892)
			(xy 430.44416 -277.849838) (xy 430.105312 -277.849838) (xy 430.104817 -277.874445) (xy 430.096922 -277.923022)
			(xy 430.081338 -277.969703) (xy 430.058467 -278.01328) (xy 430.028902 -278.052624) (xy 429.993409 -278.086716)
			(xy 429.952906 -278.114672) (xy 429.908444 -278.13577) (xy 429.861173 -278.149462) (xy 429.812318 -278.155394)
			(xy 429.763143 -278.153413) (xy 429.714924 -278.143569) (xy 429.668908 -278.126117) (xy 429.626287 -278.10151)
			(xy 429.588166 -278.070385) (xy 429.555531 -278.033548) (xy 429.529228 -277.991952) (xy 429.509937 -277.946676)
			(xy 429.49816 -277.898892) (xy 429.4942 -277.849838) (xy 429.176942 -277.849838) (xy 429.176438 -277.875546)
			(xy 429.168395 -277.926328) (xy 429.152507 -277.975227) (xy 429.129164 -278.021039) (xy 429.098943 -278.062635)
			(xy 429.062587 -278.098991) (xy 429.020991 -278.129212) (xy 428.975179 -278.152555) (xy 428.92628 -278.168443)
			(xy 428.875498 -278.176486) (xy 428.824082 -278.176486) (xy 428.7733 -278.168443) (xy 428.724401 -278.152555)
			(xy 428.678589 -278.129212) (xy 428.636993 -278.098991) (xy 428.600637 -278.062635) (xy 428.570416 -278.021039)
			(xy 428.547073 -277.975227) (xy 428.531185 -277.926328) (xy 428.523142 -277.875546) (xy 428.204464 -277.875546)
			(xy 428.196748 -277.923022) (xy 428.181164 -277.969703) (xy 428.158293 -278.01328) (xy 428.128728 -278.052624)
			(xy 428.093235 -278.086716) (xy 428.052732 -278.114672) (xy 428.00827 -278.13577) (xy 427.960999 -278.149462)
			(xy 427.912144 -278.155394) (xy 427.862969 -278.153413) (xy 427.81475 -278.143569) (xy 427.768734 -278.126117)
			(xy 427.726113 -278.10151) (xy 427.687992 -278.070385) (xy 427.655357 -278.033548) (xy 427.629054 -277.991952)
			(xy 427.609763 -277.946676) (xy 427.597986 -277.898892) (xy 427.594026 -277.849838) (xy 427.276768 -277.849838)
			(xy 427.276264 -277.875546) (xy 427.268221 -277.926328) (xy 427.252333 -277.975227) (xy 427.22899 -278.021039)
			(xy 427.198769 -278.062635) (xy 427.162413 -278.098991) (xy 427.120817 -278.129212) (xy 427.075005 -278.152555)
			(xy 427.026106 -278.168443) (xy 426.975324 -278.176486) (xy 426.923908 -278.176486) (xy 426.873126 -278.168443)
			(xy 426.824227 -278.152555) (xy 426.778415 -278.129212) (xy 426.736819 -278.098991) (xy 426.700463 -278.062635)
			(xy 426.670242 -278.021039) (xy 426.646899 -277.975227) (xy 426.631011 -277.926328) (xy 426.622968 -277.875546)
			(xy 426.304544 -277.875546) (xy 426.296828 -277.923022) (xy 426.281244 -277.969703) (xy 426.258373 -278.01328)
			(xy 426.228808 -278.052624) (xy 426.193315 -278.086716) (xy 426.152812 -278.114672) (xy 426.10835 -278.13577)
			(xy 426.061079 -278.149462) (xy 426.012224 -278.155394) (xy 425.963049 -278.153413) (xy 425.91483 -278.143569)
			(xy 425.868814 -278.126117) (xy 425.826193 -278.10151) (xy 425.788072 -278.070385) (xy 425.755437 -278.033548)
			(xy 425.729134 -277.991952) (xy 425.709843 -277.946676) (xy 425.698066 -277.898892) (xy 425.694106 -277.849838)
			(xy 425.376848 -277.849838) (xy 425.376344 -277.875546) (xy 425.368301 -277.926328) (xy 425.352413 -277.975227)
			(xy 425.32907 -278.021039) (xy 425.298849 -278.062635) (xy 425.262493 -278.098991) (xy 425.220897 -278.129212)
			(xy 425.175085 -278.152555) (xy 425.126186 -278.168443) (xy 425.075404 -278.176486) (xy 425.023988 -278.176486)
			(xy 424.973206 -278.168443) (xy 424.924307 -278.152555) (xy 424.878495 -278.129212) (xy 424.836899 -278.098991)
			(xy 424.800543 -278.062635) (xy 424.770322 -278.021039) (xy 424.746979 -277.975227) (xy 424.731091 -277.926328)
			(xy 424.723048 -277.875546) (xy 424.404624 -277.875546) (xy 424.396908 -277.923022) (xy 424.381324 -277.969703)
			(xy 424.358453 -278.01328) (xy 424.328888 -278.052624) (xy 424.293395 -278.086716) (xy 424.252892 -278.114672)
			(xy 424.20843 -278.13577) (xy 424.161159 -278.149462) (xy 424.112304 -278.155394) (xy 424.063129 -278.153413)
			(xy 424.01491 -278.143569) (xy 423.968894 -278.126117) (xy 423.926273 -278.10151) (xy 423.888152 -278.070385)
			(xy 423.855517 -278.033548) (xy 423.829214 -277.991952) (xy 423.809923 -277.946676) (xy 423.798146 -277.898892)
			(xy 423.794186 -277.849838) (xy 423.476928 -277.849838) (xy 423.476424 -277.875546) (xy 423.468381 -277.926328)
			(xy 423.452493 -277.975227) (xy 423.42915 -278.021039) (xy 423.398929 -278.062635) (xy 423.362573 -278.098991)
			(xy 423.320977 -278.129212) (xy 423.275165 -278.152555) (xy 423.226266 -278.168443) (xy 423.175484 -278.176486)
			(xy 423.124068 -278.176486) (xy 423.073286 -278.168443) (xy 423.024387 -278.152555) (xy 422.978575 -278.129212)
			(xy 422.936979 -278.098991) (xy 422.900623 -278.062635) (xy 422.870402 -278.021039) (xy 422.847059 -277.975227)
			(xy 422.831171 -277.926328) (xy 422.823128 -277.875546) (xy 422.50445 -277.875546) (xy 422.496734 -277.923022)
			(xy 422.48115 -277.969703) (xy 422.458279 -278.01328) (xy 422.428714 -278.052624) (xy 422.393221 -278.086716)
			(xy 422.352718 -278.114672) (xy 422.308256 -278.13577) (xy 422.260985 -278.149462) (xy 422.21213 -278.155394)
			(xy 422.162955 -278.153413) (xy 422.114736 -278.143569) (xy 422.06872 -278.126117) (xy 422.026099 -278.10151)
			(xy 421.987978 -278.070385) (xy 421.955343 -278.033548) (xy 421.92904 -277.991952) (xy 421.909749 -277.946676)
			(xy 421.897972 -277.898892) (xy 421.894012 -277.849838) (xy 421.576754 -277.849838) (xy 421.57625 -277.875546)
			(xy 421.568207 -277.926328) (xy 421.552319 -277.975227) (xy 421.528976 -278.021039) (xy 421.498755 -278.062635)
			(xy 421.462399 -278.098991) (xy 421.420803 -278.129212) (xy 421.374991 -278.152555) (xy 421.326092 -278.168443)
			(xy 421.27531 -278.176486) (xy 421.223894 -278.176486) (xy 421.173112 -278.168443) (xy 421.124213 -278.152555)
			(xy 421.078401 -278.129212) (xy 421.036805 -278.098991) (xy 421.000449 -278.062635) (xy 420.970228 -278.021039)
			(xy 420.946885 -277.975227) (xy 420.930997 -277.926328) (xy 420.922954 -277.875546) (xy 420.60453 -277.875546)
			(xy 420.596814 -277.923022) (xy 420.58123 -277.969703) (xy 420.558359 -278.01328) (xy 420.528794 -278.052624)
			(xy 420.493301 -278.086716) (xy 420.452798 -278.114672) (xy 420.408336 -278.13577) (xy 420.361065 -278.149462)
			(xy 420.31221 -278.155394) (xy 420.263035 -278.153413) (xy 420.214816 -278.143569) (xy 420.1688 -278.126117)
			(xy 420.126179 -278.10151) (xy 420.088058 -278.070385) (xy 420.055423 -278.033548) (xy 420.02912 -277.991952)
			(xy 420.009829 -277.946676) (xy 419.998052 -277.898892) (xy 419.994092 -277.849838) (xy 419.676834 -277.849838)
			(xy 419.67633 -277.875546) (xy 419.668287 -277.926328) (xy 419.652399 -277.975227) (xy 419.629056 -278.021039)
			(xy 419.598835 -278.062635) (xy 419.562479 -278.098991) (xy 419.520883 -278.129212) (xy 419.475071 -278.152555)
			(xy 419.426172 -278.168443) (xy 419.37539 -278.176486) (xy 419.323974 -278.176486) (xy 419.273192 -278.168443)
			(xy 419.224293 -278.152555) (xy 419.178481 -278.129212) (xy 419.136885 -278.098991) (xy 419.100529 -278.062635)
			(xy 419.070308 -278.021039) (xy 419.046965 -277.975227) (xy 419.031077 -277.926328) (xy 419.023034 -277.875546)
			(xy 418.70461 -277.875546) (xy 418.696894 -277.923022) (xy 418.68131 -277.969703) (xy 418.658439 -278.01328)
			(xy 418.628874 -278.052624) (xy 418.593381 -278.086716) (xy 418.552878 -278.114672) (xy 418.508416 -278.13577)
			(xy 418.461145 -278.149462) (xy 418.41229 -278.155394) (xy 418.363115 -278.153413) (xy 418.314896 -278.143569)
			(xy 418.26888 -278.126117) (xy 418.226259 -278.10151) (xy 418.188138 -278.070385) (xy 418.155503 -278.033548)
			(xy 418.1292 -277.991952) (xy 418.109909 -277.946676) (xy 418.098132 -277.898892) (xy 418.094172 -277.849838)
			(xy 417.776914 -277.849838) (xy 417.77641 -277.875546) (xy 417.768367 -277.926328) (xy 417.752479 -277.975227)
			(xy 417.729136 -278.021039) (xy 417.698915 -278.062635) (xy 417.662559 -278.098991) (xy 417.620963 -278.129212)
			(xy 417.575151 -278.152555) (xy 417.526252 -278.168443) (xy 417.47547 -278.176486) (xy 417.424054 -278.176486)
			(xy 417.373272 -278.168443) (xy 417.324373 -278.152555) (xy 417.278561 -278.129212) (xy 417.236965 -278.098991)
			(xy 417.200609 -278.062635) (xy 417.170388 -278.021039) (xy 417.147045 -277.975227) (xy 417.131157 -277.926328)
			(xy 417.123114 -277.875546) (xy 416.804436 -277.875546) (xy 416.79672 -277.923022) (xy 416.781136 -277.969703)
			(xy 416.758265 -278.01328) (xy 416.7287 -278.052624) (xy 416.693207 -278.086716) (xy 416.652704 -278.114672)
			(xy 416.608242 -278.13577) (xy 416.560971 -278.149462) (xy 416.512116 -278.155394) (xy 416.462941 -278.153413)
			(xy 416.414722 -278.143569) (xy 416.368706 -278.126117) (xy 416.326085 -278.10151) (xy 416.287964 -278.070385)
			(xy 416.255329 -278.033548) (xy 416.229026 -277.991952) (xy 416.209735 -277.946676) (xy 416.197958 -277.898892)
			(xy 416.193998 -277.849838) (xy 415.87674 -277.849838) (xy 415.876236 -277.875546) (xy 415.868193 -277.926328)
			(xy 415.852305 -277.975227) (xy 415.828962 -278.021039) (xy 415.798741 -278.062635) (xy 415.762385 -278.098991)
			(xy 415.720789 -278.129212) (xy 415.674977 -278.152555) (xy 415.626078 -278.168443) (xy 415.575296 -278.176486)
			(xy 415.52388 -278.176486) (xy 415.473098 -278.168443) (xy 415.424199 -278.152555) (xy 415.378387 -278.129212)
			(xy 415.336791 -278.098991) (xy 415.300435 -278.062635) (xy 415.270214 -278.021039) (xy 415.246871 -277.975227)
			(xy 415.230983 -277.926328) (xy 415.22294 -277.875546) (xy 414.904516 -277.875546) (xy 414.8968 -277.923022)
			(xy 414.881216 -277.969703) (xy 414.858345 -278.01328) (xy 414.82878 -278.052624) (xy 414.793287 -278.086716)
			(xy 414.752784 -278.114672) (xy 414.708322 -278.13577) (xy 414.661051 -278.149462) (xy 414.612196 -278.155394)
			(xy 414.563021 -278.153413) (xy 414.514802 -278.143569) (xy 414.468786 -278.126117) (xy 414.426165 -278.10151)
			(xy 414.388044 -278.070385) (xy 414.355409 -278.033548) (xy 414.329106 -277.991952) (xy 414.309815 -277.946676)
			(xy 414.298038 -277.898892) (xy 414.294078 -277.849838) (xy 413.97682 -277.849838) (xy 413.976316 -277.875546)
			(xy 413.968273 -277.926328) (xy 413.952385 -277.975227) (xy 413.929042 -278.021039) (xy 413.898821 -278.062635)
			(xy 413.862465 -278.098991) (xy 413.820869 -278.129212) (xy 413.775057 -278.152555) (xy 413.726158 -278.168443)
			(xy 413.675376 -278.176486) (xy 413.62396 -278.176486) (xy 413.573178 -278.168443) (xy 413.524279 -278.152555)
			(xy 413.478467 -278.129212) (xy 413.436871 -278.098991) (xy 413.400515 -278.062635) (xy 413.370294 -278.021039)
			(xy 413.346951 -277.975227) (xy 413.331063 -277.926328) (xy 413.32302 -277.875546) (xy 413.004596 -277.875546)
			(xy 412.99688 -277.923022) (xy 412.981296 -277.969703) (xy 412.958425 -278.01328) (xy 412.92886 -278.052624)
			(xy 412.893367 -278.086716) (xy 412.852864 -278.114672) (xy 412.808402 -278.13577) (xy 412.761131 -278.149462)
			(xy 412.712276 -278.155394) (xy 412.663101 -278.153413) (xy 412.614882 -278.143569) (xy 412.568866 -278.126117)
			(xy 412.526245 -278.10151) (xy 412.488124 -278.070385) (xy 412.455489 -278.033548) (xy 412.429186 -277.991952)
			(xy 412.409895 -277.946676) (xy 412.398118 -277.898892) (xy 412.394158 -277.849838) (xy 412.0769 -277.849838)
			(xy 412.076396 -277.875546) (xy 412.068353 -277.926328) (xy 412.052465 -277.975227) (xy 412.029122 -278.021039)
			(xy 411.998901 -278.062635) (xy 411.962545 -278.098991) (xy 411.920949 -278.129212) (xy 411.875137 -278.152555)
			(xy 411.826238 -278.168443) (xy 411.775456 -278.176486) (xy 411.72404 -278.176486) (xy 411.673258 -278.168443)
			(xy 411.624359 -278.152555) (xy 411.578547 -278.129212) (xy 411.536951 -278.098991) (xy 411.500595 -278.062635)
			(xy 411.470374 -278.021039) (xy 411.447031 -277.975227) (xy 411.431143 -277.926328) (xy 411.4231 -277.875546)
			(xy 411.104422 -277.875546) (xy 411.096706 -277.923022) (xy 411.081122 -277.969703) (xy 411.058251 -278.01328)
			(xy 411.028686 -278.052624) (xy 410.993193 -278.086716) (xy 410.95269 -278.114672) (xy 410.908228 -278.13577)
			(xy 410.860957 -278.149462) (xy 410.812102 -278.155394) (xy 410.762927 -278.153413) (xy 410.714708 -278.143569)
			(xy 410.668692 -278.126117) (xy 410.626071 -278.10151) (xy 410.58795 -278.070385) (xy 410.555315 -278.033548)
			(xy 410.529012 -277.991952) (xy 410.509721 -277.946676) (xy 410.497944 -277.898892) (xy 410.493984 -277.849838)
			(xy 410.176726 -277.849838) (xy 410.176222 -277.875546) (xy 410.168179 -277.926328) (xy 410.152291 -277.975227)
			(xy 410.128948 -278.021039) (xy 410.098727 -278.062635) (xy 410.062371 -278.098991) (xy 410.020775 -278.129212)
			(xy 409.974963 -278.152555) (xy 409.926064 -278.168443) (xy 409.875282 -278.176486) (xy 409.823866 -278.176486)
			(xy 409.773084 -278.168443) (xy 409.724185 -278.152555) (xy 409.678373 -278.129212) (xy 409.636777 -278.098991)
			(xy 409.600421 -278.062635) (xy 409.5702 -278.021039) (xy 409.546857 -277.975227) (xy 409.530969 -277.926328)
			(xy 409.522926 -277.875546) (xy 409.204502 -277.875546) (xy 409.196786 -277.923022) (xy 409.181202 -277.969703)
			(xy 409.158331 -278.01328) (xy 409.128766 -278.052624) (xy 409.093273 -278.086716) (xy 409.05277 -278.114672)
			(xy 409.008308 -278.13577) (xy 408.961037 -278.149462) (xy 408.912182 -278.155394) (xy 408.863007 -278.153413)
			(xy 408.814788 -278.143569) (xy 408.768772 -278.126117) (xy 408.726151 -278.10151) (xy 408.68803 -278.070385)
			(xy 408.655395 -278.033548) (xy 408.629092 -277.991952) (xy 408.609801 -277.946676) (xy 408.598024 -277.898892)
			(xy 408.594064 -277.849838) (xy 408.276806 -277.849838) (xy 408.276302 -277.875546) (xy 408.268259 -277.926328)
			(xy 408.252371 -277.975227) (xy 408.229028 -278.021039) (xy 408.198807 -278.062635) (xy 408.162451 -278.098991)
			(xy 408.120855 -278.129212) (xy 408.075043 -278.152555) (xy 408.026144 -278.168443) (xy 407.975362 -278.176486)
			(xy 407.923946 -278.176486) (xy 407.873164 -278.168443) (xy 407.824265 -278.152555) (xy 407.778453 -278.129212)
			(xy 407.736857 -278.098991) (xy 407.700501 -278.062635) (xy 407.67028 -278.021039) (xy 407.646937 -277.975227)
			(xy 407.631049 -277.926328) (xy 407.623006 -277.875546) (xy 407.304582 -277.875546) (xy 407.296866 -277.923022)
			(xy 407.281282 -277.969703) (xy 407.258411 -278.01328) (xy 407.228846 -278.052624) (xy 407.193353 -278.086716)
			(xy 407.15285 -278.114672) (xy 407.108388 -278.13577) (xy 407.061117 -278.149462) (xy 407.012262 -278.155394)
			(xy 406.963087 -278.153413) (xy 406.914868 -278.143569) (xy 406.868852 -278.126117) (xy 406.826231 -278.10151)
			(xy 406.78811 -278.070385) (xy 406.755475 -278.033548) (xy 406.729172 -277.991952) (xy 406.709881 -277.946676)
			(xy 406.698104 -277.898892) (xy 406.694144 -277.849838) (xy 406.37714 -277.849838) (xy 406.376636 -277.875546)
			(xy 406.368593 -277.926328) (xy 406.352705 -277.975227) (xy 406.329362 -278.021039) (xy 406.299141 -278.062635)
			(xy 406.262785 -278.098991) (xy 406.221189 -278.129212) (xy 406.175377 -278.152555) (xy 406.126478 -278.168443)
			(xy 406.075696 -278.176486) (xy 406.02428 -278.176486) (xy 405.973498 -278.168443) (xy 405.924599 -278.152555)
			(xy 405.878787 -278.129212) (xy 405.837191 -278.098991) (xy 405.800835 -278.062635) (xy 405.770614 -278.021039)
			(xy 405.747271 -277.975227) (xy 405.731383 -277.926328) (xy 405.72334 -277.875546) (xy 405.404662 -277.875546)
			(xy 405.396946 -277.923022) (xy 405.381362 -277.969703) (xy 405.358491 -278.01328) (xy 405.328926 -278.052624)
			(xy 405.293433 -278.086716) (xy 405.25293 -278.114672) (xy 405.208468 -278.13577) (xy 405.161197 -278.149462)
			(xy 405.112342 -278.155394) (xy 405.063167 -278.153413) (xy 405.014948 -278.143569) (xy 404.968932 -278.126117)
			(xy 404.926311 -278.10151) (xy 404.88819 -278.070385) (xy 404.855555 -278.033548) (xy 404.829252 -277.991952)
			(xy 404.809961 -277.946676) (xy 404.798184 -277.898892) (xy 404.794224 -277.849838) (xy 404.476966 -277.849838)
			(xy 404.476462 -277.875546) (xy 404.468419 -277.926328) (xy 404.452531 -277.975227) (xy 404.429188 -278.021039)
			(xy 404.398967 -278.062635) (xy 404.362611 -278.098991) (xy 404.321015 -278.129212) (xy 404.275203 -278.152555)
			(xy 404.226304 -278.168443) (xy 404.175522 -278.176486) (xy 404.124106 -278.176486) (xy 404.073324 -278.168443)
			(xy 404.024425 -278.152555) (xy 403.978613 -278.129212) (xy 403.937017 -278.098991) (xy 403.900661 -278.062635)
			(xy 403.87044 -278.021039) (xy 403.847097 -277.975227) (xy 403.831209 -277.926328) (xy 403.823166 -277.875546)
			(xy 403.504488 -277.875546) (xy 403.496772 -277.923022) (xy 403.481188 -277.969703) (xy 403.458317 -278.01328)
			(xy 403.428752 -278.052624) (xy 403.393259 -278.086716) (xy 403.352756 -278.114672) (xy 403.308294 -278.13577)
			(xy 403.261023 -278.149462) (xy 403.212168 -278.155394) (xy 403.162993 -278.153413) (xy 403.114774 -278.143569)
			(xy 403.068758 -278.126117) (xy 403.026137 -278.10151) (xy 402.988016 -278.070385) (xy 402.955381 -278.033548)
			(xy 402.929078 -277.991952) (xy 402.909787 -277.946676) (xy 402.89801 -277.898892) (xy 402.89405 -277.849838)
			(xy 402.577046 -277.849838) (xy 402.576542 -277.875546) (xy 402.568499 -277.926328) (xy 402.552611 -277.975227)
			(xy 402.529268 -278.021039) (xy 402.499047 -278.062635) (xy 402.462691 -278.098991) (xy 402.421095 -278.129212)
			(xy 402.375283 -278.152555) (xy 402.326384 -278.168443) (xy 402.275602 -278.176486) (xy 402.224186 -278.176486)
			(xy 402.173404 -278.168443) (xy 402.124505 -278.152555) (xy 402.078693 -278.129212) (xy 402.037097 -278.098991)
			(xy 402.000741 -278.062635) (xy 401.97052 -278.021039) (xy 401.947177 -277.975227) (xy 401.931289 -277.926328)
			(xy 401.923246 -277.875546) (xy 401.604568 -277.875546) (xy 401.596852 -277.923022) (xy 401.581268 -277.969703)
			(xy 401.558397 -278.01328) (xy 401.528832 -278.052624) (xy 401.493339 -278.086716) (xy 401.452836 -278.114672)
			(xy 401.408374 -278.13577) (xy 401.361103 -278.149462) (xy 401.312248 -278.155394) (xy 401.263073 -278.153413)
			(xy 401.214854 -278.143569) (xy 401.168838 -278.126117) (xy 401.126217 -278.10151) (xy 401.088096 -278.070385)
			(xy 401.055461 -278.033548) (xy 401.029158 -277.991952) (xy 401.009867 -277.946676) (xy 400.99809 -277.898892)
			(xy 400.99413 -277.849838) (xy 400.677126 -277.849838) (xy 400.676622 -277.875546) (xy 400.668579 -277.926328)
			(xy 400.652691 -277.975227) (xy 400.629348 -278.021039) (xy 400.599127 -278.062635) (xy 400.562771 -278.098991)
			(xy 400.521175 -278.129212) (xy 400.475363 -278.152555) (xy 400.426464 -278.168443) (xy 400.375682 -278.176486)
			(xy 400.324266 -278.176486) (xy 400.273484 -278.168443) (xy 400.224585 -278.152555) (xy 400.178773 -278.129212)
			(xy 400.137177 -278.098991) (xy 400.100821 -278.062635) (xy 400.0706 -278.021039) (xy 400.047257 -277.975227)
			(xy 400.031369 -277.926328) (xy 400.023326 -277.875546) (xy 399.704648 -277.875546) (xy 399.696932 -277.923022)
			(xy 399.681348 -277.969703) (xy 399.658477 -278.01328) (xy 399.628912 -278.052624) (xy 399.593419 -278.086716)
			(xy 399.552916 -278.114672) (xy 399.508454 -278.13577) (xy 399.461183 -278.149462) (xy 399.412328 -278.155394)
			(xy 399.363153 -278.153413) (xy 399.314934 -278.143569) (xy 399.268918 -278.126117) (xy 399.226297 -278.10151)
			(xy 399.188176 -278.070385) (xy 399.155541 -278.033548) (xy 399.129238 -277.991952) (xy 399.109947 -277.946676)
			(xy 399.09817 -277.898892) (xy 399.09421 -277.849838) (xy 398.776156 -277.849838) (xy 398.776156 -277.875485)
			(xy 398.76812 -277.926222) (xy 398.752246 -277.975077) (xy 398.728925 -278.020848) (xy 398.698731 -278.062407)
			(xy 398.662407 -278.098731) (xy 398.620848 -278.128925) (xy 398.575077 -278.152246) (xy 398.526222 -278.16812)
			(xy 398.475485 -278.176156) (xy 398.4498 -278.176736) (xy 398.417034 -278.175212) (xy 398.406112 -278.174196)
			(xy 398.385792 -278.1808) (xy 398.322038 -278.238712) (xy 398.314531 -278.246257) (xy 398.305877 -278.265677)
			(xy 398.305274 -278.276304) (xy 398.305274 -278.324818) (xy 398.30523 -278.334172) (xy 398.304211 -278.352852)
			(xy 398.303798 -278.356822) (xy 456.56703 -278.356822) (xy 456.571101 -278.3012) (xy 456.583227 -278.246763)
			(xy 456.60315 -278.194672) (xy 456.630446 -278.146037) (xy 456.664532 -278.101894) (xy 456.704681 -278.063185)
			(xy 456.750039 -278.030734) (xy 456.799639 -278.005233) (xy 456.852423 -277.987226) (xy 456.907266 -277.977096)
			(xy 456.963 -277.975059) (xy 457.018437 -277.981159) (xy 457.072394 -277.995265) (xy 457.123723 -278.017077)
			(xy 457.171329 -278.046131) (xy 457.214197 -278.081806) (xy 457.251414 -278.123343) (xy 457.282187 -278.169856)
			(xy 457.305859 -278.220353) (xy 457.321927 -278.27376) (xy 457.330047 -278.328936) (xy 457.330556 -278.356822)
			(xy 457.330047 -278.384708) (xy 457.321927 -278.439884) (xy 457.305859 -278.493291) (xy 457.301129 -278.50338)
			(xy 458.091284 -278.50338) (xy 458.095355 -278.447758) (xy 458.107481 -278.393321) (xy 458.127404 -278.34123)
			(xy 458.1547 -278.292595) (xy 458.188786 -278.248452) (xy 458.228935 -278.209743) (xy 458.274293 -278.177292)
			(xy 458.323893 -278.151791) (xy 458.376677 -278.133784) (xy 458.43152 -278.123654) (xy 458.487254 -278.121617)
			(xy 458.542691 -278.127717) (xy 458.596648 -278.141823) (xy 458.647977 -278.163635) (xy 458.695583 -278.192689)
			(xy 458.738451 -278.228364) (xy 458.775668 -278.269901) (xy 458.806441 -278.316414) (xy 458.830113 -278.366911)
			(xy 458.846181 -278.420318) (xy 458.854301 -278.475494) (xy 458.854606 -278.492204) (xy 459.269336 -278.492204)
			(xy 459.273407 -278.436582) (xy 459.285533 -278.382145) (xy 459.305456 -278.330054) (xy 459.332752 -278.281419)
			(xy 459.366838 -278.237276) (xy 459.406987 -278.198567) (xy 459.452345 -278.166116) (xy 459.501945 -278.140615)
			(xy 459.554729 -278.122608) (xy 459.609572 -278.112478) (xy 459.665306 -278.110441) (xy 459.720743 -278.116541)
			(xy 459.7747 -278.130647) (xy 459.826029 -278.152459) (xy 459.873635 -278.181513) (xy 459.916503 -278.217188)
			(xy 459.95372 -278.258725) (xy 459.984493 -278.305238) (xy 460.008165 -278.355735) (xy 460.024233 -278.409142)
			(xy 460.032353 -278.464318) (xy 460.032862 -278.492204) (xy 460.032353 -278.52009) (xy 460.024233 -278.575266)
			(xy 460.008165 -278.628673) (xy 459.986528 -278.67483) (xy 461.074516 -278.67483) (xy 461.07505 -278.645914)
			(xy 461.083775 -278.588743) (xy 461.101029 -278.533544) (xy 461.126418 -278.481582) (xy 461.159359 -278.434048)
			(xy 461.199098 -278.39203) (xy 461.221582 -278.37384) (xy 461.230335 -278.366271) (xy 461.24052 -278.345517)
			(xy 461.24114 -278.333962) (xy 461.24114 -278.253698) (xy 461.240592 -278.242127) (xy 461.230384 -278.221355)
			(xy 461.221582 -278.21382) (xy 461.199104 -278.195622) (xy 461.15937 -278.153603) (xy 461.12643 -278.10607)
			(xy 461.101041 -278.05411) (xy 461.083783 -277.998914) (xy 461.075052 -277.941746) (xy 461.074516 -277.91283)
			(xy 461.075002 -277.885579) (xy 461.082758 -277.831631) (xy 461.098113 -277.779336) (xy 461.120755 -277.729759)
			(xy 461.150221 -277.683909) (xy 461.185912 -277.642718) (xy 461.227103 -277.607027) (xy 461.272953 -277.577561)
			(xy 461.32253 -277.554919) (xy 461.374825 -277.539564) (xy 461.428773 -277.531808) (xy 461.483275 -277.531808)
			(xy 461.537223 -277.539564) (xy 461.589518 -277.554919) (xy 461.639095 -277.577561) (xy 461.684945 -277.607027)
			(xy 461.726136 -277.642718) (xy 461.761827 -277.683909) (xy 461.791293 -277.729759) (xy 461.813935 -277.779336)
			(xy 461.82929 -277.831631) (xy 461.837046 -277.885579) (xy 461.837532 -277.91283) (xy 461.836989 -277.941746)
			(xy 461.828269 -277.998917) (xy 461.811017 -278.054117) (xy 461.78563 -278.106079) (xy 461.75269 -278.153614)
			(xy 461.712951 -278.19563) (xy 461.690466 -278.21382) (xy 461.681694 -278.221372) (xy 461.671517 -278.242138)
			(xy 461.670908 -278.253698) (xy 461.670908 -278.333962) (xy 461.671497 -278.345527) (xy 461.681678 -278.366299)
			(xy 461.690466 -278.37384) (xy 461.712962 -278.392017) (xy 461.752698 -278.434039) (xy 461.785636 -278.481576)
			(xy 461.811023 -278.53354) (xy 461.828276 -278.588741) (xy 461.837 -278.645913) (xy 461.837532 -278.67483)
			(xy 461.837046 -278.702081) (xy 461.82929 -278.756029) (xy 461.813935 -278.808324) (xy 461.791293 -278.857901)
			(xy 461.761827 -278.903751) (xy 461.726136 -278.944942) (xy 461.684945 -278.980633) (xy 461.639095 -279.010099)
			(xy 461.589518 -279.032741) (xy 461.537223 -279.048096) (xy 461.483275 -279.055852) (xy 461.428773 -279.055852)
			(xy 461.374825 -279.048096) (xy 461.32253 -279.032741) (xy 461.272953 -279.010099) (xy 461.227103 -278.980633)
			(xy 461.185912 -278.944942) (xy 461.150221 -278.903751) (xy 461.120755 -278.857901) (xy 461.098113 -278.808324)
			(xy 461.082758 -278.756029) (xy 461.075002 -278.702081) (xy 461.074516 -278.67483) (xy 459.986528 -278.67483)
			(xy 459.984493 -278.67917) (xy 459.95372 -278.725683) (xy 459.916503 -278.76722) (xy 459.873635 -278.802895)
			(xy 459.826029 -278.831949) (xy 459.7747 -278.853761) (xy 459.720743 -278.867867) (xy 459.665306 -278.873967)
			(xy 459.609572 -278.87193) (xy 459.554729 -278.8618) (xy 459.501945 -278.843793) (xy 459.452345 -278.818292)
			(xy 459.406987 -278.785841) (xy 459.366838 -278.747132) (xy 459.332752 -278.702989) (xy 459.305456 -278.654354)
			(xy 459.285533 -278.602263) (xy 459.273407 -278.547826) (xy 459.269336 -278.492204) (xy 458.854606 -278.492204)
			(xy 458.85481 -278.50338) (xy 458.854301 -278.531266) (xy 458.846181 -278.586442) (xy 458.830113 -278.639849)
			(xy 458.806441 -278.690346) (xy 458.775668 -278.736859) (xy 458.738451 -278.778396) (xy 458.695583 -278.814071)
			(xy 458.647977 -278.843125) (xy 458.596648 -278.864937) (xy 458.542691 -278.879043) (xy 458.487254 -278.885143)
			(xy 458.43152 -278.883106) (xy 458.376677 -278.872976) (xy 458.323893 -278.854969) (xy 458.274293 -278.829468)
			(xy 458.228935 -278.797017) (xy 458.188786 -278.758308) (xy 458.1547 -278.714165) (xy 458.127404 -278.66553)
			(xy 458.107481 -278.613439) (xy 458.095355 -278.559002) (xy 458.091284 -278.50338) (xy 457.301129 -278.50338)
			(xy 457.282187 -278.543788) (xy 457.251414 -278.590301) (xy 457.214197 -278.631838) (xy 457.171329 -278.667513)
			(xy 457.123723 -278.696567) (xy 457.072394 -278.718379) (xy 457.018437 -278.732485) (xy 456.963 -278.738585)
			(xy 456.907266 -278.736548) (xy 456.852423 -278.726418) (xy 456.799639 -278.708411) (xy 456.750039 -278.68291)
			(xy 456.704681 -278.650459) (xy 456.664532 -278.61175) (xy 456.630446 -278.567607) (xy 456.60315 -278.518972)
			(xy 456.583227 -278.466881) (xy 456.571101 -278.412444) (xy 456.56703 -278.356822) (xy 398.303798 -278.356822)
			(xy 398.303242 -278.362156) (xy 398.301718 -278.37384) (xy 398.309338 -278.39543) (xy 398.381728 -278.468328)
			(xy 398.403318 -278.475948) (xy 398.415002 -278.474678) (xy 398.4498 -278.4729) (xy 398.475488 -278.473404)
			(xy 398.526231 -278.481441) (xy 398.575093 -278.497317) (xy 398.620869 -278.520641) (xy 398.662433 -278.550839)
			(xy 398.698761 -278.587167) (xy 398.728959 -278.628731) (xy 398.752283 -278.674507) (xy 398.768159 -278.723369)
			(xy 398.776196 -278.774112) (xy 398.776196 -278.799798) (xy 399.09421 -278.799798) (xy 399.09817 -278.750744)
			(xy 399.109947 -278.70296) (xy 399.129238 -278.657684) (xy 399.155541 -278.616088) (xy 399.188176 -278.579251)
			(xy 399.226297 -278.548126) (xy 399.268918 -278.523519) (xy 399.314934 -278.506067) (xy 399.363153 -278.496223)
			(xy 399.412328 -278.494242) (xy 399.461183 -278.500174) (xy 399.508454 -278.513866) (xy 399.552916 -278.534964)
			(xy 399.593419 -278.56292) (xy 399.628912 -278.597012) (xy 399.658477 -278.636356) (xy 399.681348 -278.679933)
			(xy 399.696932 -278.726614) (xy 399.704827 -278.775191) (xy 399.705322 -278.799798) (xy 399.704827 -278.824405)
			(xy 399.704648 -278.825506) (xy 400.023326 -278.825506) (xy 400.023326 -278.77409) (xy 400.031369 -278.723308)
			(xy 400.047257 -278.674409) (xy 400.0706 -278.628597) (xy 400.100821 -278.587001) (xy 400.137177 -278.550645)
			(xy 400.178773 -278.520424) (xy 400.224585 -278.497081) (xy 400.273484 -278.481193) (xy 400.324266 -278.47315)
			(xy 400.375682 -278.47315) (xy 400.426464 -278.481193) (xy 400.475363 -278.497081) (xy 400.521175 -278.520424)
			(xy 400.562771 -278.550645) (xy 400.599127 -278.587001) (xy 400.629348 -278.628597) (xy 400.652691 -278.674409)
			(xy 400.668579 -278.723308) (xy 400.676622 -278.77409) (xy 400.677126 -278.799798) (xy 400.99413 -278.799798)
			(xy 400.99809 -278.750744) (xy 401.009867 -278.70296) (xy 401.029158 -278.657684) (xy 401.055461 -278.616088)
			(xy 401.088096 -278.579251) (xy 401.126217 -278.548126) (xy 401.168838 -278.523519) (xy 401.214854 -278.506067)
			(xy 401.263073 -278.496223) (xy 401.312248 -278.494242) (xy 401.361103 -278.500174) (xy 401.408374 -278.513866)
			(xy 401.452836 -278.534964) (xy 401.493339 -278.56292) (xy 401.528832 -278.597012) (xy 401.558397 -278.636356)
			(xy 401.581268 -278.679933) (xy 401.596852 -278.726614) (xy 401.604747 -278.775191) (xy 401.605242 -278.799798)
			(xy 401.604747 -278.824405) (xy 401.604568 -278.825506) (xy 401.923246 -278.825506) (xy 401.923246 -278.77409)
			(xy 401.931289 -278.723308) (xy 401.947177 -278.674409) (xy 401.97052 -278.628597) (xy 402.000741 -278.587001)
			(xy 402.037097 -278.550645) (xy 402.078693 -278.520424) (xy 402.124505 -278.497081) (xy 402.173404 -278.481193)
			(xy 402.224186 -278.47315) (xy 402.275602 -278.47315) (xy 402.326384 -278.481193) (xy 402.375283 -278.497081)
			(xy 402.421095 -278.520424) (xy 402.462691 -278.550645) (xy 402.499047 -278.587001) (xy 402.529268 -278.628597)
			(xy 402.552611 -278.674409) (xy 402.568499 -278.723308) (xy 402.576542 -278.77409) (xy 402.577046 -278.799798)
			(xy 402.89405 -278.799798) (xy 402.89801 -278.750744) (xy 402.909787 -278.70296) (xy 402.929078 -278.657684)
			(xy 402.955381 -278.616088) (xy 402.988016 -278.579251) (xy 403.026137 -278.548126) (xy 403.068758 -278.523519)
			(xy 403.114774 -278.506067) (xy 403.162993 -278.496223) (xy 403.212168 -278.494242) (xy 403.261023 -278.500174)
			(xy 403.308294 -278.513866) (xy 403.352756 -278.534964) (xy 403.393259 -278.56292) (xy 403.428752 -278.597012)
			(xy 403.458317 -278.636356) (xy 403.481188 -278.679933) (xy 403.496772 -278.726614) (xy 403.504667 -278.775191)
			(xy 403.505162 -278.799798) (xy 403.504667 -278.824405) (xy 403.504488 -278.825506) (xy 403.823166 -278.825506)
			(xy 403.823166 -278.77409) (xy 403.831209 -278.723308) (xy 403.847097 -278.674409) (xy 403.87044 -278.628597)
			(xy 403.900661 -278.587001) (xy 403.937017 -278.550645) (xy 403.978613 -278.520424) (xy 404.024425 -278.497081)
			(xy 404.073324 -278.481193) (xy 404.124106 -278.47315) (xy 404.175522 -278.47315) (xy 404.226304 -278.481193)
			(xy 404.275203 -278.497081) (xy 404.321015 -278.520424) (xy 404.362611 -278.550645) (xy 404.398967 -278.587001)
			(xy 404.429188 -278.628597) (xy 404.452531 -278.674409) (xy 404.468419 -278.723308) (xy 404.476462 -278.77409)
			(xy 404.476966 -278.799798) (xy 404.794224 -278.799798) (xy 404.798184 -278.750744) (xy 404.809961 -278.70296)
			(xy 404.829252 -278.657684) (xy 404.855555 -278.616088) (xy 404.88819 -278.579251) (xy 404.926311 -278.548126)
			(xy 404.968932 -278.523519) (xy 405.014948 -278.506067) (xy 405.063167 -278.496223) (xy 405.112342 -278.494242)
			(xy 405.161197 -278.500174) (xy 405.208468 -278.513866) (xy 405.25293 -278.534964) (xy 405.293433 -278.56292)
			(xy 405.328926 -278.597012) (xy 405.358491 -278.636356) (xy 405.381362 -278.679933) (xy 405.396946 -278.726614)
			(xy 405.404841 -278.775191) (xy 405.405336 -278.799798) (xy 405.404841 -278.824405) (xy 405.404662 -278.825506)
			(xy 405.72334 -278.825506) (xy 405.72334 -278.77409) (xy 405.731383 -278.723308) (xy 405.747271 -278.674409)
			(xy 405.770614 -278.628597) (xy 405.800835 -278.587001) (xy 405.837191 -278.550645) (xy 405.878787 -278.520424)
			(xy 405.924599 -278.497081) (xy 405.973498 -278.481193) (xy 406.02428 -278.47315) (xy 406.075696 -278.47315)
			(xy 406.126478 -278.481193) (xy 406.175377 -278.497081) (xy 406.221189 -278.520424) (xy 406.262785 -278.550645)
			(xy 406.299141 -278.587001) (xy 406.329362 -278.628597) (xy 406.352705 -278.674409) (xy 406.368593 -278.723308)
			(xy 406.376636 -278.77409) (xy 406.37714 -278.799798) (xy 406.694144 -278.799798) (xy 406.698104 -278.750744)
			(xy 406.709881 -278.70296) (xy 406.729172 -278.657684) (xy 406.755475 -278.616088) (xy 406.78811 -278.579251)
			(xy 406.826231 -278.548126) (xy 406.868852 -278.523519) (xy 406.914868 -278.506067) (xy 406.963087 -278.496223)
			(xy 407.012262 -278.494242) (xy 407.061117 -278.500174) (xy 407.108388 -278.513866) (xy 407.15285 -278.534964)
			(xy 407.193353 -278.56292) (xy 407.228846 -278.597012) (xy 407.258411 -278.636356) (xy 407.281282 -278.679933)
			(xy 407.296866 -278.726614) (xy 407.304761 -278.775191) (xy 407.305256 -278.799798) (xy 407.304761 -278.824405)
			(xy 407.304582 -278.825506) (xy 407.623006 -278.825506) (xy 407.623006 -278.77409) (xy 407.631049 -278.723308)
			(xy 407.646937 -278.674409) (xy 407.67028 -278.628597) (xy 407.700501 -278.587001) (xy 407.736857 -278.550645)
			(xy 407.778453 -278.520424) (xy 407.824265 -278.497081) (xy 407.873164 -278.481193) (xy 407.923946 -278.47315)
			(xy 407.975362 -278.47315) (xy 408.026144 -278.481193) (xy 408.075043 -278.497081) (xy 408.120855 -278.520424)
			(xy 408.162451 -278.550645) (xy 408.198807 -278.587001) (xy 408.229028 -278.628597) (xy 408.252371 -278.674409)
			(xy 408.268259 -278.723308) (xy 408.276302 -278.77409) (xy 408.276806 -278.799798) (xy 408.594064 -278.799798)
			(xy 408.598024 -278.750744) (xy 408.609801 -278.70296) (xy 408.629092 -278.657684) (xy 408.655395 -278.616088)
			(xy 408.68803 -278.579251) (xy 408.726151 -278.548126) (xy 408.768772 -278.523519) (xy 408.814788 -278.506067)
			(xy 408.863007 -278.496223) (xy 408.912182 -278.494242) (xy 408.961037 -278.500174) (xy 409.008308 -278.513866)
			(xy 409.05277 -278.534964) (xy 409.093273 -278.56292) (xy 409.128766 -278.597012) (xy 409.158331 -278.636356)
			(xy 409.181202 -278.679933) (xy 409.196786 -278.726614) (xy 409.204681 -278.775191) (xy 409.205176 -278.799798)
			(xy 409.204681 -278.824405) (xy 409.204502 -278.825506) (xy 409.522926 -278.825506) (xy 409.522926 -278.77409)
			(xy 409.530969 -278.723308) (xy 409.546857 -278.674409) (xy 409.5702 -278.628597) (xy 409.600421 -278.587001)
			(xy 409.636777 -278.550645) (xy 409.678373 -278.520424) (xy 409.724185 -278.497081) (xy 409.773084 -278.481193)
			(xy 409.823866 -278.47315) (xy 409.875282 -278.47315) (xy 409.926064 -278.481193) (xy 409.974963 -278.497081)
			(xy 410.020775 -278.520424) (xy 410.062371 -278.550645) (xy 410.098727 -278.587001) (xy 410.128948 -278.628597)
			(xy 410.152291 -278.674409) (xy 410.168179 -278.723308) (xy 410.176222 -278.77409) (xy 410.176726 -278.799798)
			(xy 410.493984 -278.799798) (xy 410.497944 -278.750744) (xy 410.509721 -278.70296) (xy 410.529012 -278.657684)
			(xy 410.555315 -278.616088) (xy 410.58795 -278.579251) (xy 410.626071 -278.548126) (xy 410.668692 -278.523519)
			(xy 410.714708 -278.506067) (xy 410.762927 -278.496223) (xy 410.812102 -278.494242) (xy 410.860957 -278.500174)
			(xy 410.908228 -278.513866) (xy 410.95269 -278.534964) (xy 410.993193 -278.56292) (xy 411.028686 -278.597012)
			(xy 411.058251 -278.636356) (xy 411.081122 -278.679933) (xy 411.096706 -278.726614) (xy 411.104601 -278.775191)
			(xy 411.105096 -278.799798) (xy 411.104601 -278.824405) (xy 411.104422 -278.825506) (xy 411.4231 -278.825506)
			(xy 411.4231 -278.77409) (xy 411.431143 -278.723308) (xy 411.447031 -278.674409) (xy 411.470374 -278.628597)
			(xy 411.500595 -278.587001) (xy 411.536951 -278.550645) (xy 411.578547 -278.520424) (xy 411.624359 -278.497081)
			(xy 411.673258 -278.481193) (xy 411.72404 -278.47315) (xy 411.775456 -278.47315) (xy 411.826238 -278.481193)
			(xy 411.875137 -278.497081) (xy 411.920949 -278.520424) (xy 411.962545 -278.550645) (xy 411.998901 -278.587001)
			(xy 412.029122 -278.628597) (xy 412.052465 -278.674409) (xy 412.068353 -278.723308) (xy 412.076396 -278.77409)
			(xy 412.0769 -278.799798) (xy 412.394158 -278.799798) (xy 412.398118 -278.750744) (xy 412.409895 -278.70296)
			(xy 412.429186 -278.657684) (xy 412.455489 -278.616088) (xy 412.488124 -278.579251) (xy 412.526245 -278.548126)
			(xy 412.568866 -278.523519) (xy 412.614882 -278.506067) (xy 412.663101 -278.496223) (xy 412.712276 -278.494242)
			(xy 412.761131 -278.500174) (xy 412.808402 -278.513866) (xy 412.852864 -278.534964) (xy 412.893367 -278.56292)
			(xy 412.92886 -278.597012) (xy 412.958425 -278.636356) (xy 412.981296 -278.679933) (xy 412.99688 -278.726614)
			(xy 413.004775 -278.775191) (xy 413.00527 -278.799798) (xy 413.004775 -278.824405) (xy 413.004596 -278.825506)
			(xy 413.32302 -278.825506) (xy 413.32302 -278.77409) (xy 413.331063 -278.723308) (xy 413.346951 -278.674409)
			(xy 413.370294 -278.628597) (xy 413.400515 -278.587001) (xy 413.436871 -278.550645) (xy 413.478467 -278.520424)
			(xy 413.524279 -278.497081) (xy 413.573178 -278.481193) (xy 413.62396 -278.47315) (xy 413.675376 -278.47315)
			(xy 413.726158 -278.481193) (xy 413.775057 -278.497081) (xy 413.820869 -278.520424) (xy 413.862465 -278.550645)
			(xy 413.898821 -278.587001) (xy 413.929042 -278.628597) (xy 413.952385 -278.674409) (xy 413.968273 -278.723308)
			(xy 413.976316 -278.77409) (xy 413.97682 -278.799798) (xy 414.294078 -278.799798) (xy 414.298038 -278.750744)
			(xy 414.309815 -278.70296) (xy 414.329106 -278.657684) (xy 414.355409 -278.616088) (xy 414.388044 -278.579251)
			(xy 414.426165 -278.548126) (xy 414.468786 -278.523519) (xy 414.514802 -278.506067) (xy 414.563021 -278.496223)
			(xy 414.612196 -278.494242) (xy 414.661051 -278.500174) (xy 414.708322 -278.513866) (xy 414.752784 -278.534964)
			(xy 414.793287 -278.56292) (xy 414.82878 -278.597012) (xy 414.858345 -278.636356) (xy 414.881216 -278.679933)
			(xy 414.8968 -278.726614) (xy 414.904695 -278.775191) (xy 414.90519 -278.799798) (xy 414.904695 -278.824405)
			(xy 414.904516 -278.825506) (xy 415.22294 -278.825506) (xy 415.22294 -278.77409) (xy 415.230983 -278.723308)
			(xy 415.246871 -278.674409) (xy 415.270214 -278.628597) (xy 415.300435 -278.587001) (xy 415.336791 -278.550645)
			(xy 415.378387 -278.520424) (xy 415.424199 -278.497081) (xy 415.473098 -278.481193) (xy 415.52388 -278.47315)
			(xy 415.575296 -278.47315) (xy 415.626078 -278.481193) (xy 415.674977 -278.497081) (xy 415.720789 -278.520424)
			(xy 415.762385 -278.550645) (xy 415.798741 -278.587001) (xy 415.828962 -278.628597) (xy 415.852305 -278.674409)
			(xy 415.868193 -278.723308) (xy 415.876236 -278.77409) (xy 415.87674 -278.799798) (xy 416.193998 -278.799798)
			(xy 416.197958 -278.750744) (xy 416.209735 -278.70296) (xy 416.229026 -278.657684) (xy 416.255329 -278.616088)
			(xy 416.287964 -278.579251) (xy 416.326085 -278.548126) (xy 416.368706 -278.523519) (xy 416.414722 -278.506067)
			(xy 416.462941 -278.496223) (xy 416.512116 -278.494242) (xy 416.560971 -278.500174) (xy 416.608242 -278.513866)
			(xy 416.652704 -278.534964) (xy 416.693207 -278.56292) (xy 416.7287 -278.597012) (xy 416.758265 -278.636356)
			(xy 416.781136 -278.679933) (xy 416.79672 -278.726614) (xy 416.804615 -278.775191) (xy 416.80511 -278.799798)
			(xy 416.804615 -278.824405) (xy 416.804436 -278.825506) (xy 417.123114 -278.825506) (xy 417.123114 -278.77409)
			(xy 417.131157 -278.723308) (xy 417.147045 -278.674409) (xy 417.170388 -278.628597) (xy 417.200609 -278.587001)
			(xy 417.236965 -278.550645) (xy 417.278561 -278.520424) (xy 417.324373 -278.497081) (xy 417.373272 -278.481193)
			(xy 417.424054 -278.47315) (xy 417.47547 -278.47315) (xy 417.526252 -278.481193) (xy 417.575151 -278.497081)
			(xy 417.620963 -278.520424) (xy 417.662559 -278.550645) (xy 417.698915 -278.587001) (xy 417.729136 -278.628597)
			(xy 417.752479 -278.674409) (xy 417.768367 -278.723308) (xy 417.77641 -278.77409) (xy 417.776914 -278.799798)
			(xy 418.094172 -278.799798) (xy 418.098132 -278.750744) (xy 418.109909 -278.70296) (xy 418.1292 -278.657684)
			(xy 418.155503 -278.616088) (xy 418.188138 -278.579251) (xy 418.226259 -278.548126) (xy 418.26888 -278.523519)
			(xy 418.314896 -278.506067) (xy 418.363115 -278.496223) (xy 418.41229 -278.494242) (xy 418.461145 -278.500174)
			(xy 418.508416 -278.513866) (xy 418.552878 -278.534964) (xy 418.593381 -278.56292) (xy 418.628874 -278.597012)
			(xy 418.658439 -278.636356) (xy 418.68131 -278.679933) (xy 418.696894 -278.726614) (xy 418.704789 -278.775191)
			(xy 418.705284 -278.799798) (xy 418.704789 -278.824405) (xy 418.70461 -278.825506) (xy 419.023034 -278.825506)
			(xy 419.023034 -278.77409) (xy 419.031077 -278.723308) (xy 419.046965 -278.674409) (xy 419.070308 -278.628597)
			(xy 419.100529 -278.587001) (xy 419.136885 -278.550645) (xy 419.178481 -278.520424) (xy 419.224293 -278.497081)
			(xy 419.273192 -278.481193) (xy 419.323974 -278.47315) (xy 419.37539 -278.47315) (xy 419.426172 -278.481193)
			(xy 419.475071 -278.497081) (xy 419.520883 -278.520424) (xy 419.562479 -278.550645) (xy 419.598835 -278.587001)
			(xy 419.629056 -278.628597) (xy 419.652399 -278.674409) (xy 419.668287 -278.723308) (xy 419.67633 -278.77409)
			(xy 419.676834 -278.799798) (xy 419.994092 -278.799798) (xy 419.998052 -278.750744) (xy 420.009829 -278.70296)
			(xy 420.02912 -278.657684) (xy 420.055423 -278.616088) (xy 420.088058 -278.579251) (xy 420.126179 -278.548126)
			(xy 420.1688 -278.523519) (xy 420.214816 -278.506067) (xy 420.263035 -278.496223) (xy 420.31221 -278.494242)
			(xy 420.361065 -278.500174) (xy 420.408336 -278.513866) (xy 420.452798 -278.534964) (xy 420.493301 -278.56292)
			(xy 420.528794 -278.597012) (xy 420.558359 -278.636356) (xy 420.58123 -278.679933) (xy 420.596814 -278.726614)
			(xy 420.604709 -278.775191) (xy 420.605204 -278.799798) (xy 420.604709 -278.824405) (xy 420.60453 -278.825506)
			(xy 420.922954 -278.825506) (xy 420.922954 -278.77409) (xy 420.930997 -278.723308) (xy 420.946885 -278.674409)
			(xy 420.970228 -278.628597) (xy 421.000449 -278.587001) (xy 421.036805 -278.550645) (xy 421.078401 -278.520424)
			(xy 421.124213 -278.497081) (xy 421.173112 -278.481193) (xy 421.223894 -278.47315) (xy 421.27531 -278.47315)
			(xy 421.326092 -278.481193) (xy 421.374991 -278.497081) (xy 421.420803 -278.520424) (xy 421.462399 -278.550645)
			(xy 421.498755 -278.587001) (xy 421.528976 -278.628597) (xy 421.552319 -278.674409) (xy 421.568207 -278.723308)
			(xy 421.57625 -278.77409) (xy 421.576754 -278.799798) (xy 421.894012 -278.799798) (xy 421.897972 -278.750744)
			(xy 421.909749 -278.70296) (xy 421.92904 -278.657684) (xy 421.955343 -278.616088) (xy 421.987978 -278.579251)
			(xy 422.026099 -278.548126) (xy 422.06872 -278.523519) (xy 422.114736 -278.506067) (xy 422.162955 -278.496223)
			(xy 422.21213 -278.494242) (xy 422.260985 -278.500174) (xy 422.308256 -278.513866) (xy 422.352718 -278.534964)
			(xy 422.393221 -278.56292) (xy 422.428714 -278.597012) (xy 422.458279 -278.636356) (xy 422.48115 -278.679933)
			(xy 422.496734 -278.726614) (xy 422.504629 -278.775191) (xy 422.505124 -278.799798) (xy 422.504629 -278.824405)
			(xy 422.50445 -278.825506) (xy 422.823128 -278.825506) (xy 422.823128 -278.77409) (xy 422.831171 -278.723308)
			(xy 422.847059 -278.674409) (xy 422.870402 -278.628597) (xy 422.900623 -278.587001) (xy 422.936979 -278.550645)
			(xy 422.978575 -278.520424) (xy 423.024387 -278.497081) (xy 423.073286 -278.481193) (xy 423.124068 -278.47315)
			(xy 423.175484 -278.47315) (xy 423.226266 -278.481193) (xy 423.275165 -278.497081) (xy 423.320977 -278.520424)
			(xy 423.362573 -278.550645) (xy 423.398929 -278.587001) (xy 423.42915 -278.628597) (xy 423.452493 -278.674409)
			(xy 423.468381 -278.723308) (xy 423.476424 -278.77409) (xy 423.476928 -278.799798) (xy 423.794186 -278.799798)
			(xy 423.798146 -278.750744) (xy 423.809923 -278.70296) (xy 423.829214 -278.657684) (xy 423.855517 -278.616088)
			(xy 423.888152 -278.579251) (xy 423.926273 -278.548126) (xy 423.968894 -278.523519) (xy 424.01491 -278.506067)
			(xy 424.063129 -278.496223) (xy 424.112304 -278.494242) (xy 424.161159 -278.500174) (xy 424.20843 -278.513866)
			(xy 424.252892 -278.534964) (xy 424.293395 -278.56292) (xy 424.328888 -278.597012) (xy 424.358453 -278.636356)
			(xy 424.381324 -278.679933) (xy 424.396908 -278.726614) (xy 424.404803 -278.775191) (xy 424.405298 -278.799798)
			(xy 424.404803 -278.824405) (xy 424.404624 -278.825506) (xy 424.723048 -278.825506) (xy 424.723048 -278.77409)
			(xy 424.731091 -278.723308) (xy 424.746979 -278.674409) (xy 424.770322 -278.628597) (xy 424.800543 -278.587001)
			(xy 424.836899 -278.550645) (xy 424.878495 -278.520424) (xy 424.924307 -278.497081) (xy 424.973206 -278.481193)
			(xy 425.023988 -278.47315) (xy 425.075404 -278.47315) (xy 425.126186 -278.481193) (xy 425.175085 -278.497081)
			(xy 425.220897 -278.520424) (xy 425.262493 -278.550645) (xy 425.298849 -278.587001) (xy 425.32907 -278.628597)
			(xy 425.352413 -278.674409) (xy 425.368301 -278.723308) (xy 425.376344 -278.77409) (xy 425.376848 -278.799798)
			(xy 425.694106 -278.799798) (xy 425.698066 -278.750744) (xy 425.709843 -278.70296) (xy 425.729134 -278.657684)
			(xy 425.755437 -278.616088) (xy 425.788072 -278.579251) (xy 425.826193 -278.548126) (xy 425.868814 -278.523519)
			(xy 425.91483 -278.506067) (xy 425.963049 -278.496223) (xy 426.012224 -278.494242) (xy 426.061079 -278.500174)
			(xy 426.10835 -278.513866) (xy 426.152812 -278.534964) (xy 426.193315 -278.56292) (xy 426.228808 -278.597012)
			(xy 426.258373 -278.636356) (xy 426.281244 -278.679933) (xy 426.296828 -278.726614) (xy 426.304723 -278.775191)
			(xy 426.305218 -278.799798) (xy 426.304723 -278.824405) (xy 426.304544 -278.825506) (xy 426.622968 -278.825506)
			(xy 426.622968 -278.77409) (xy 426.631011 -278.723308) (xy 426.646899 -278.674409) (xy 426.670242 -278.628597)
			(xy 426.700463 -278.587001) (xy 426.736819 -278.550645) (xy 426.778415 -278.520424) (xy 426.824227 -278.497081)
			(xy 426.873126 -278.481193) (xy 426.923908 -278.47315) (xy 426.975324 -278.47315) (xy 427.026106 -278.481193)
			(xy 427.075005 -278.497081) (xy 427.120817 -278.520424) (xy 427.162413 -278.550645) (xy 427.198769 -278.587001)
			(xy 427.22899 -278.628597) (xy 427.252333 -278.674409) (xy 427.268221 -278.723308) (xy 427.276264 -278.77409)
			(xy 427.276768 -278.799798) (xy 427.594026 -278.799798) (xy 427.597986 -278.750744) (xy 427.609763 -278.70296)
			(xy 427.629054 -278.657684) (xy 427.655357 -278.616088) (xy 427.687992 -278.579251) (xy 427.726113 -278.548126)
			(xy 427.768734 -278.523519) (xy 427.81475 -278.506067) (xy 427.862969 -278.496223) (xy 427.912144 -278.494242)
			(xy 427.960999 -278.500174) (xy 428.00827 -278.513866) (xy 428.052732 -278.534964) (xy 428.093235 -278.56292)
			(xy 428.128728 -278.597012) (xy 428.158293 -278.636356) (xy 428.181164 -278.679933) (xy 428.196748 -278.726614)
			(xy 428.204643 -278.775191) (xy 428.205138 -278.799798) (xy 428.204643 -278.824405) (xy 428.204464 -278.825506)
			(xy 428.523142 -278.825506) (xy 428.523142 -278.77409) (xy 428.531185 -278.723308) (xy 428.547073 -278.674409)
			(xy 428.570416 -278.628597) (xy 428.600637 -278.587001) (xy 428.636993 -278.550645) (xy 428.678589 -278.520424)
			(xy 428.724401 -278.497081) (xy 428.7733 -278.481193) (xy 428.824082 -278.47315) (xy 428.875498 -278.47315)
			(xy 428.92628 -278.481193) (xy 428.975179 -278.497081) (xy 429.020991 -278.520424) (xy 429.062587 -278.550645)
			(xy 429.098943 -278.587001) (xy 429.129164 -278.628597) (xy 429.152507 -278.674409) (xy 429.168395 -278.723308)
			(xy 429.176438 -278.77409) (xy 429.176942 -278.799798) (xy 429.4942 -278.799798) (xy 429.49816 -278.750744)
			(xy 429.509937 -278.70296) (xy 429.529228 -278.657684) (xy 429.555531 -278.616088) (xy 429.588166 -278.579251)
			(xy 429.626287 -278.548126) (xy 429.668908 -278.523519) (xy 429.714924 -278.506067) (xy 429.763143 -278.496223)
			(xy 429.812318 -278.494242) (xy 429.861173 -278.500174) (xy 429.908444 -278.513866) (xy 429.952906 -278.534964)
			(xy 429.993409 -278.56292) (xy 430.028902 -278.597012) (xy 430.058467 -278.636356) (xy 430.081338 -278.679933)
			(xy 430.096922 -278.726614) (xy 430.104817 -278.775191) (xy 430.105312 -278.799798) (xy 430.44416 -278.799798)
			(xy 430.44812 -278.750744) (xy 430.459897 -278.70296) (xy 430.479188 -278.657684) (xy 430.505491 -278.616088)
			(xy 430.538126 -278.579251) (xy 430.576247 -278.548126) (xy 430.618868 -278.523519) (xy 430.664884 -278.506067)
			(xy 430.713103 -278.496223) (xy 430.762278 -278.494242) (xy 430.811133 -278.500174) (xy 430.858404 -278.513866)
			(xy 430.902866 -278.534964) (xy 430.943369 -278.56292) (xy 430.978862 -278.597012) (xy 431.008427 -278.636356)
			(xy 431.031298 -278.679933) (xy 431.046882 -278.726614) (xy 431.054777 -278.775191) (xy 431.055272 -278.799798)
			(xy 431.054777 -278.824405) (xy 431.048786 -278.861266) (xy 447.862958 -278.861266) (xy 447.867029 -278.805644)
			(xy 447.879155 -278.751207) (xy 447.899078 -278.699116) (xy 447.926374 -278.650481) (xy 447.96046 -278.606338)
			(xy 448.000609 -278.567629) (xy 448.045967 -278.535178) (xy 448.095567 -278.509677) (xy 448.148351 -278.49167)
			(xy 448.203194 -278.48154) (xy 448.258928 -278.479503) (xy 448.314365 -278.485603) (xy 448.368322 -278.499709)
			(xy 448.419651 -278.521521) (xy 448.467257 -278.550575) (xy 448.510125 -278.58625) (xy 448.547342 -278.627787)
			(xy 448.578115 -278.6743) (xy 448.601787 -278.724797) (xy 448.617855 -278.778204) (xy 448.625975 -278.83338)
			(xy 448.626484 -278.861266) (xy 448.625975 -278.889152) (xy 448.617855 -278.944328) (xy 448.601787 -278.997735)
			(xy 448.578115 -279.048232) (xy 448.547342 -279.094745) (xy 448.510125 -279.136282) (xy 448.467257 -279.171957)
			(xy 448.422389 -279.19934) (xy 455.00112 -279.19934) (xy 455.005191 -279.143718) (xy 455.017317 -279.089281)
			(xy 455.03724 -279.03719) (xy 455.064536 -278.988555) (xy 455.098622 -278.944412) (xy 455.138771 -278.905703)
			(xy 455.184129 -278.873252) (xy 455.233729 -278.847751) (xy 455.286513 -278.829744) (xy 455.341356 -278.819614)
			(xy 455.39709 -278.817577) (xy 455.452527 -278.823677) (xy 455.506484 -278.837783) (xy 455.557813 -278.859595)
			(xy 455.605419 -278.888649) (xy 455.648287 -278.924324) (xy 455.685504 -278.965861) (xy 455.716277 -279.012374)
			(xy 455.739949 -279.062871) (xy 455.756017 -279.116278) (xy 455.764137 -279.171454) (xy 455.764646 -279.19934)
			(xy 455.764137 -279.227226) (xy 455.756017 -279.282402) (xy 455.739949 -279.335809) (xy 455.716277 -279.386306)
			(xy 455.685504 -279.432819) (xy 455.648287 -279.474356) (xy 455.605419 -279.510031) (xy 455.557813 -279.539085)
			(xy 455.506484 -279.560897) (xy 455.452527 -279.575003) (xy 455.39709 -279.581103) (xy 455.341356 -279.579066)
			(xy 455.286513 -279.568936) (xy 455.233729 -279.550929) (xy 455.184129 -279.525428) (xy 455.138771 -279.492977)
			(xy 455.098622 -279.454268) (xy 455.064536 -279.410125) (xy 455.03724 -279.36149) (xy 455.017317 -279.309399)
			(xy 455.005191 -279.254962) (xy 455.00112 -279.19934) (xy 448.422389 -279.19934) (xy 448.419651 -279.201011)
			(xy 448.368322 -279.222823) (xy 448.314365 -279.236929) (xy 448.258928 -279.243029) (xy 448.203194 -279.240992)
			(xy 448.148351 -279.230862) (xy 448.095567 -279.212855) (xy 448.045967 -279.187354) (xy 448.000609 -279.154903)
			(xy 447.96046 -279.116194) (xy 447.926374 -279.072051) (xy 447.899078 -279.023416) (xy 447.879155 -278.971325)
			(xy 447.867029 -278.916888) (xy 447.862958 -278.861266) (xy 431.048786 -278.861266) (xy 431.046882 -278.872982)
			(xy 431.031298 -278.919663) (xy 431.008427 -278.96324) (xy 430.978862 -279.002584) (xy 430.943369 -279.036676)
			(xy 430.902866 -279.064632) (xy 430.858404 -279.08573) (xy 430.811133 -279.099422) (xy 430.762278 -279.105354)
			(xy 430.713103 -279.103373) (xy 430.664884 -279.093529) (xy 430.618868 -279.076077) (xy 430.576247 -279.05147)
			(xy 430.538126 -279.020345) (xy 430.505491 -278.983508) (xy 430.479188 -278.941912) (xy 430.459897 -278.896636)
			(xy 430.44812 -278.848852) (xy 430.44416 -278.799798) (xy 430.105312 -278.799798) (xy 430.104817 -278.824405)
			(xy 430.096922 -278.872982) (xy 430.081338 -278.919663) (xy 430.058467 -278.96324) (xy 430.028902 -279.002584)
			(xy 429.993409 -279.036676) (xy 429.952906 -279.064632) (xy 429.908444 -279.08573) (xy 429.861173 -279.099422)
			(xy 429.812318 -279.105354) (xy 429.763143 -279.103373) (xy 429.714924 -279.093529) (xy 429.668908 -279.076077)
			(xy 429.626287 -279.05147) (xy 429.588166 -279.020345) (xy 429.555531 -278.983508) (xy 429.529228 -278.941912)
			(xy 429.509937 -278.896636) (xy 429.49816 -278.848852) (xy 429.4942 -278.799798) (xy 429.176942 -278.799798)
			(xy 429.176438 -278.825506) (xy 429.168395 -278.876288) (xy 429.152507 -278.925187) (xy 429.129164 -278.970999)
			(xy 429.098943 -279.012595) (xy 429.062587 -279.048951) (xy 429.020991 -279.079172) (xy 428.975179 -279.102515)
			(xy 428.92628 -279.118403) (xy 428.875498 -279.126446) (xy 428.824082 -279.126446) (xy 428.7733 -279.118403)
			(xy 428.724401 -279.102515) (xy 428.678589 -279.079172) (xy 428.636993 -279.048951) (xy 428.600637 -279.012595)
			(xy 428.570416 -278.970999) (xy 428.547073 -278.925187) (xy 428.531185 -278.876288) (xy 428.523142 -278.825506)
			(xy 428.204464 -278.825506) (xy 428.196748 -278.872982) (xy 428.181164 -278.919663) (xy 428.158293 -278.96324)
			(xy 428.128728 -279.002584) (xy 428.093235 -279.036676) (xy 428.052732 -279.064632) (xy 428.00827 -279.08573)
			(xy 427.960999 -279.099422) (xy 427.912144 -279.105354) (xy 427.862969 -279.103373) (xy 427.81475 -279.093529)
			(xy 427.768734 -279.076077) (xy 427.726113 -279.05147) (xy 427.687992 -279.020345) (xy 427.655357 -278.983508)
			(xy 427.629054 -278.941912) (xy 427.609763 -278.896636) (xy 427.597986 -278.848852) (xy 427.594026 -278.799798)
			(xy 427.276768 -278.799798) (xy 427.276264 -278.825506) (xy 427.268221 -278.876288) (xy 427.252333 -278.925187)
			(xy 427.22899 -278.970999) (xy 427.198769 -279.012595) (xy 427.162413 -279.048951) (xy 427.120817 -279.079172)
			(xy 427.075005 -279.102515) (xy 427.026106 -279.118403) (xy 426.975324 -279.126446) (xy 426.923908 -279.126446)
			(xy 426.873126 -279.118403) (xy 426.824227 -279.102515) (xy 426.778415 -279.079172) (xy 426.736819 -279.048951)
			(xy 426.700463 -279.012595) (xy 426.670242 -278.970999) (xy 426.646899 -278.925187) (xy 426.631011 -278.876288)
			(xy 426.622968 -278.825506) (xy 426.304544 -278.825506) (xy 426.296828 -278.872982) (xy 426.281244 -278.919663)
			(xy 426.258373 -278.96324) (xy 426.228808 -279.002584) (xy 426.193315 -279.036676) (xy 426.152812 -279.064632)
			(xy 426.10835 -279.08573) (xy 426.061079 -279.099422) (xy 426.012224 -279.105354) (xy 425.963049 -279.103373)
			(xy 425.91483 -279.093529) (xy 425.868814 -279.076077) (xy 425.826193 -279.05147) (xy 425.788072 -279.020345)
			(xy 425.755437 -278.983508) (xy 425.729134 -278.941912) (xy 425.709843 -278.896636) (xy 425.698066 -278.848852)
			(xy 425.694106 -278.799798) (xy 425.376848 -278.799798) (xy 425.376344 -278.825506) (xy 425.368301 -278.876288)
			(xy 425.352413 -278.925187) (xy 425.32907 -278.970999) (xy 425.298849 -279.012595) (xy 425.262493 -279.048951)
			(xy 425.220897 -279.079172) (xy 425.175085 -279.102515) (xy 425.126186 -279.118403) (xy 425.075404 -279.126446)
			(xy 425.023988 -279.126446) (xy 424.973206 -279.118403) (xy 424.924307 -279.102515) (xy 424.878495 -279.079172)
			(xy 424.836899 -279.048951) (xy 424.800543 -279.012595) (xy 424.770322 -278.970999) (xy 424.746979 -278.925187)
			(xy 424.731091 -278.876288) (xy 424.723048 -278.825506) (xy 424.404624 -278.825506) (xy 424.396908 -278.872982)
			(xy 424.381324 -278.919663) (xy 424.358453 -278.96324) (xy 424.328888 -279.002584) (xy 424.293395 -279.036676)
			(xy 424.252892 -279.064632) (xy 424.20843 -279.08573) (xy 424.161159 -279.099422) (xy 424.112304 -279.105354)
			(xy 424.063129 -279.103373) (xy 424.01491 -279.093529) (xy 423.968894 -279.076077) (xy 423.926273 -279.05147)
			(xy 423.888152 -279.020345) (xy 423.855517 -278.983508) (xy 423.829214 -278.941912) (xy 423.809923 -278.896636)
			(xy 423.798146 -278.848852) (xy 423.794186 -278.799798) (xy 423.476928 -278.799798) (xy 423.476424 -278.825506)
			(xy 423.468381 -278.876288) (xy 423.452493 -278.925187) (xy 423.42915 -278.970999) (xy 423.398929 -279.012595)
			(xy 423.362573 -279.048951) (xy 423.320977 -279.079172) (xy 423.275165 -279.102515) (xy 423.226266 -279.118403)
			(xy 423.175484 -279.126446) (xy 423.124068 -279.126446) (xy 423.073286 -279.118403) (xy 423.024387 -279.102515)
			(xy 422.978575 -279.079172) (xy 422.936979 -279.048951) (xy 422.900623 -279.012595) (xy 422.870402 -278.970999)
			(xy 422.847059 -278.925187) (xy 422.831171 -278.876288) (xy 422.823128 -278.825506) (xy 422.50445 -278.825506)
			(xy 422.496734 -278.872982) (xy 422.48115 -278.919663) (xy 422.458279 -278.96324) (xy 422.428714 -279.002584)
			(xy 422.393221 -279.036676) (xy 422.352718 -279.064632) (xy 422.308256 -279.08573) (xy 422.260985 -279.099422)
			(xy 422.21213 -279.105354) (xy 422.162955 -279.103373) (xy 422.114736 -279.093529) (xy 422.06872 -279.076077)
			(xy 422.026099 -279.05147) (xy 421.987978 -279.020345) (xy 421.955343 -278.983508) (xy 421.92904 -278.941912)
			(xy 421.909749 -278.896636) (xy 421.897972 -278.848852) (xy 421.894012 -278.799798) (xy 421.576754 -278.799798)
			(xy 421.57625 -278.825506) (xy 421.568207 -278.876288) (xy 421.552319 -278.925187) (xy 421.528976 -278.970999)
			(xy 421.498755 -279.012595) (xy 421.462399 -279.048951) (xy 421.420803 -279.079172) (xy 421.374991 -279.102515)
			(xy 421.326092 -279.118403) (xy 421.27531 -279.126446) (xy 421.223894 -279.126446) (xy 421.173112 -279.118403)
			(xy 421.124213 -279.102515) (xy 421.078401 -279.079172) (xy 421.036805 -279.048951) (xy 421.000449 -279.012595)
			(xy 420.970228 -278.970999) (xy 420.946885 -278.925187) (xy 420.930997 -278.876288) (xy 420.922954 -278.825506)
			(xy 420.60453 -278.825506) (xy 420.596814 -278.872982) (xy 420.58123 -278.919663) (xy 420.558359 -278.96324)
			(xy 420.528794 -279.002584) (xy 420.493301 -279.036676) (xy 420.452798 -279.064632) (xy 420.408336 -279.08573)
			(xy 420.361065 -279.099422) (xy 420.31221 -279.105354) (xy 420.263035 -279.103373) (xy 420.214816 -279.093529)
			(xy 420.1688 -279.076077) (xy 420.126179 -279.05147) (xy 420.088058 -279.020345) (xy 420.055423 -278.983508)
			(xy 420.02912 -278.941912) (xy 420.009829 -278.896636) (xy 419.998052 -278.848852) (xy 419.994092 -278.799798)
			(xy 419.676834 -278.799798) (xy 419.67633 -278.825506) (xy 419.668287 -278.876288) (xy 419.652399 -278.925187)
			(xy 419.629056 -278.970999) (xy 419.598835 -279.012595) (xy 419.562479 -279.048951) (xy 419.520883 -279.079172)
			(xy 419.475071 -279.102515) (xy 419.426172 -279.118403) (xy 419.37539 -279.126446) (xy 419.323974 -279.126446)
			(xy 419.273192 -279.118403) (xy 419.224293 -279.102515) (xy 419.178481 -279.079172) (xy 419.136885 -279.048951)
			(xy 419.100529 -279.012595) (xy 419.070308 -278.970999) (xy 419.046965 -278.925187) (xy 419.031077 -278.876288)
			(xy 419.023034 -278.825506) (xy 418.70461 -278.825506) (xy 418.696894 -278.872982) (xy 418.68131 -278.919663)
			(xy 418.658439 -278.96324) (xy 418.628874 -279.002584) (xy 418.593381 -279.036676) (xy 418.552878 -279.064632)
			(xy 418.508416 -279.08573) (xy 418.461145 -279.099422) (xy 418.41229 -279.105354) (xy 418.363115 -279.103373)
			(xy 418.314896 -279.093529) (xy 418.26888 -279.076077) (xy 418.226259 -279.05147) (xy 418.188138 -279.020345)
			(xy 418.155503 -278.983508) (xy 418.1292 -278.941912) (xy 418.109909 -278.896636) (xy 418.098132 -278.848852)
			(xy 418.094172 -278.799798) (xy 417.776914 -278.799798) (xy 417.77641 -278.825506) (xy 417.768367 -278.876288)
			(xy 417.752479 -278.925187) (xy 417.729136 -278.970999) (xy 417.698915 -279.012595) (xy 417.662559 -279.048951)
			(xy 417.620963 -279.079172) (xy 417.575151 -279.102515) (xy 417.526252 -279.118403) (xy 417.47547 -279.126446)
			(xy 417.424054 -279.126446) (xy 417.373272 -279.118403) (xy 417.324373 -279.102515) (xy 417.278561 -279.079172)
			(xy 417.236965 -279.048951) (xy 417.200609 -279.012595) (xy 417.170388 -278.970999) (xy 417.147045 -278.925187)
			(xy 417.131157 -278.876288) (xy 417.123114 -278.825506) (xy 416.804436 -278.825506) (xy 416.79672 -278.872982)
			(xy 416.781136 -278.919663) (xy 416.758265 -278.96324) (xy 416.7287 -279.002584) (xy 416.693207 -279.036676)
			(xy 416.652704 -279.064632) (xy 416.608242 -279.08573) (xy 416.560971 -279.099422) (xy 416.512116 -279.105354)
			(xy 416.462941 -279.103373) (xy 416.414722 -279.093529) (xy 416.368706 -279.076077) (xy 416.326085 -279.05147)
			(xy 416.287964 -279.020345) (xy 416.255329 -278.983508) (xy 416.229026 -278.941912) (xy 416.209735 -278.896636)
			(xy 416.197958 -278.848852) (xy 416.193998 -278.799798) (xy 415.87674 -278.799798) (xy 415.876236 -278.825506)
			(xy 415.868193 -278.876288) (xy 415.852305 -278.925187) (xy 415.828962 -278.970999) (xy 415.798741 -279.012595)
			(xy 415.762385 -279.048951) (xy 415.720789 -279.079172) (xy 415.674977 -279.102515) (xy 415.626078 -279.118403)
			(xy 415.575296 -279.126446) (xy 415.52388 -279.126446) (xy 415.473098 -279.118403) (xy 415.424199 -279.102515)
			(xy 415.378387 -279.079172) (xy 415.336791 -279.048951) (xy 415.300435 -279.012595) (xy 415.270214 -278.970999)
			(xy 415.246871 -278.925187) (xy 415.230983 -278.876288) (xy 415.22294 -278.825506) (xy 414.904516 -278.825506)
			(xy 414.8968 -278.872982) (xy 414.881216 -278.919663) (xy 414.858345 -278.96324) (xy 414.82878 -279.002584)
			(xy 414.793287 -279.036676) (xy 414.752784 -279.064632) (xy 414.708322 -279.08573) (xy 414.661051 -279.099422)
			(xy 414.612196 -279.105354) (xy 414.563021 -279.103373) (xy 414.514802 -279.093529) (xy 414.468786 -279.076077)
			(xy 414.426165 -279.05147) (xy 414.388044 -279.020345) (xy 414.355409 -278.983508) (xy 414.329106 -278.941912)
			(xy 414.309815 -278.896636) (xy 414.298038 -278.848852) (xy 414.294078 -278.799798) (xy 413.97682 -278.799798)
			(xy 413.976316 -278.825506) (xy 413.968273 -278.876288) (xy 413.952385 -278.925187) (xy 413.929042 -278.970999)
			(xy 413.898821 -279.012595) (xy 413.862465 -279.048951) (xy 413.820869 -279.079172) (xy 413.775057 -279.102515)
			(xy 413.726158 -279.118403) (xy 413.675376 -279.126446) (xy 413.62396 -279.126446) (xy 413.573178 -279.118403)
			(xy 413.524279 -279.102515) (xy 413.478467 -279.079172) (xy 413.436871 -279.048951) (xy 413.400515 -279.012595)
			(xy 413.370294 -278.970999) (xy 413.346951 -278.925187) (xy 413.331063 -278.876288) (xy 413.32302 -278.825506)
			(xy 413.004596 -278.825506) (xy 412.99688 -278.872982) (xy 412.981296 -278.919663) (xy 412.958425 -278.96324)
			(xy 412.92886 -279.002584) (xy 412.893367 -279.036676) (xy 412.852864 -279.064632) (xy 412.808402 -279.08573)
			(xy 412.761131 -279.099422) (xy 412.712276 -279.105354) (xy 412.663101 -279.103373) (xy 412.614882 -279.093529)
			(xy 412.568866 -279.076077) (xy 412.526245 -279.05147) (xy 412.488124 -279.020345) (xy 412.455489 -278.983508)
			(xy 412.429186 -278.941912) (xy 412.409895 -278.896636) (xy 412.398118 -278.848852) (xy 412.394158 -278.799798)
			(xy 412.0769 -278.799798) (xy 412.076396 -278.825506) (xy 412.068353 -278.876288) (xy 412.052465 -278.925187)
			(xy 412.029122 -278.970999) (xy 411.998901 -279.012595) (xy 411.962545 -279.048951) (xy 411.920949 -279.079172)
			(xy 411.875137 -279.102515) (xy 411.826238 -279.118403) (xy 411.775456 -279.126446) (xy 411.72404 -279.126446)
			(xy 411.673258 -279.118403) (xy 411.624359 -279.102515) (xy 411.578547 -279.079172) (xy 411.536951 -279.048951)
			(xy 411.500595 -279.012595) (xy 411.470374 -278.970999) (xy 411.447031 -278.925187) (xy 411.431143 -278.876288)
			(xy 411.4231 -278.825506) (xy 411.104422 -278.825506) (xy 411.096706 -278.872982) (xy 411.081122 -278.919663)
			(xy 411.058251 -278.96324) (xy 411.028686 -279.002584) (xy 410.993193 -279.036676) (xy 410.95269 -279.064632)
			(xy 410.908228 -279.08573) (xy 410.860957 -279.099422) (xy 410.812102 -279.105354) (xy 410.762927 -279.103373)
			(xy 410.714708 -279.093529) (xy 410.668692 -279.076077) (xy 410.626071 -279.05147) (xy 410.58795 -279.020345)
			(xy 410.555315 -278.983508) (xy 410.529012 -278.941912) (xy 410.509721 -278.896636) (xy 410.497944 -278.848852)
			(xy 410.493984 -278.799798) (xy 410.176726 -278.799798) (xy 410.176222 -278.825506) (xy 410.168179 -278.876288)
			(xy 410.152291 -278.925187) (xy 410.128948 -278.970999) (xy 410.098727 -279.012595) (xy 410.062371 -279.048951)
			(xy 410.020775 -279.079172) (xy 409.974963 -279.102515) (xy 409.926064 -279.118403) (xy 409.875282 -279.126446)
			(xy 409.823866 -279.126446) (xy 409.773084 -279.118403) (xy 409.724185 -279.102515) (xy 409.678373 -279.079172)
			(xy 409.636777 -279.048951) (xy 409.600421 -279.012595) (xy 409.5702 -278.970999) (xy 409.546857 -278.925187)
			(xy 409.530969 -278.876288) (xy 409.522926 -278.825506) (xy 409.204502 -278.825506) (xy 409.196786 -278.872982)
			(xy 409.181202 -278.919663) (xy 409.158331 -278.96324) (xy 409.128766 -279.002584) (xy 409.093273 -279.036676)
			(xy 409.05277 -279.064632) (xy 409.008308 -279.08573) (xy 408.961037 -279.099422) (xy 408.912182 -279.105354)
			(xy 408.863007 -279.103373) (xy 408.814788 -279.093529) (xy 408.768772 -279.076077) (xy 408.726151 -279.05147)
			(xy 408.68803 -279.020345) (xy 408.655395 -278.983508) (xy 408.629092 -278.941912) (xy 408.609801 -278.896636)
			(xy 408.598024 -278.848852) (xy 408.594064 -278.799798) (xy 408.276806 -278.799798) (xy 408.276302 -278.825506)
			(xy 408.268259 -278.876288) (xy 408.252371 -278.925187) (xy 408.229028 -278.970999) (xy 408.198807 -279.012595)
			(xy 408.162451 -279.048951) (xy 408.120855 -279.079172) (xy 408.075043 -279.102515) (xy 408.026144 -279.118403)
			(xy 407.975362 -279.126446) (xy 407.923946 -279.126446) (xy 407.873164 -279.118403) (xy 407.824265 -279.102515)
			(xy 407.778453 -279.079172) (xy 407.736857 -279.048951) (xy 407.700501 -279.012595) (xy 407.67028 -278.970999)
			(xy 407.646937 -278.925187) (xy 407.631049 -278.876288) (xy 407.623006 -278.825506) (xy 407.304582 -278.825506)
			(xy 407.296866 -278.872982) (xy 407.281282 -278.919663) (xy 407.258411 -278.96324) (xy 407.228846 -279.002584)
			(xy 407.193353 -279.036676) (xy 407.15285 -279.064632) (xy 407.108388 -279.08573) (xy 407.061117 -279.099422)
			(xy 407.012262 -279.105354) (xy 406.963087 -279.103373) (xy 406.914868 -279.093529) (xy 406.868852 -279.076077)
			(xy 406.826231 -279.05147) (xy 406.78811 -279.020345) (xy 406.755475 -278.983508) (xy 406.729172 -278.941912)
			(xy 406.709881 -278.896636) (xy 406.698104 -278.848852) (xy 406.694144 -278.799798) (xy 406.37714 -278.799798)
			(xy 406.376636 -278.825506) (xy 406.368593 -278.876288) (xy 406.352705 -278.925187) (xy 406.329362 -278.970999)
			(xy 406.299141 -279.012595) (xy 406.262785 -279.048951) (xy 406.221189 -279.079172) (xy 406.175377 -279.102515)
			(xy 406.126478 -279.118403) (xy 406.075696 -279.126446) (xy 406.02428 -279.126446) (xy 405.973498 -279.118403)
			(xy 405.924599 -279.102515) (xy 405.878787 -279.079172) (xy 405.837191 -279.048951) (xy 405.800835 -279.012595)
			(xy 405.770614 -278.970999) (xy 405.747271 -278.925187) (xy 405.731383 -278.876288) (xy 405.72334 -278.825506)
			(xy 405.404662 -278.825506) (xy 405.396946 -278.872982) (xy 405.381362 -278.919663) (xy 405.358491 -278.96324)
			(xy 405.328926 -279.002584) (xy 405.293433 -279.036676) (xy 405.25293 -279.064632) (xy 405.208468 -279.08573)
			(xy 405.161197 -279.099422) (xy 405.112342 -279.105354) (xy 405.063167 -279.103373) (xy 405.014948 -279.093529)
			(xy 404.968932 -279.076077) (xy 404.926311 -279.05147) (xy 404.88819 -279.020345) (xy 404.855555 -278.983508)
			(xy 404.829252 -278.941912) (xy 404.809961 -278.896636) (xy 404.798184 -278.848852) (xy 404.794224 -278.799798)
			(xy 404.476966 -278.799798) (xy 404.476462 -278.825506) (xy 404.468419 -278.876288) (xy 404.452531 -278.925187)
			(xy 404.429188 -278.970999) (xy 404.398967 -279.012595) (xy 404.362611 -279.048951) (xy 404.321015 -279.079172)
			(xy 404.275203 -279.102515) (xy 404.226304 -279.118403) (xy 404.175522 -279.126446) (xy 404.124106 -279.126446)
			(xy 404.073324 -279.118403) (xy 404.024425 -279.102515) (xy 403.978613 -279.079172) (xy 403.937017 -279.048951)
			(xy 403.900661 -279.012595) (xy 403.87044 -278.970999) (xy 403.847097 -278.925187) (xy 403.831209 -278.876288)
			(xy 403.823166 -278.825506) (xy 403.504488 -278.825506) (xy 403.496772 -278.872982) (xy 403.481188 -278.919663)
			(xy 403.458317 -278.96324) (xy 403.428752 -279.002584) (xy 403.393259 -279.036676) (xy 403.352756 -279.064632)
			(xy 403.308294 -279.08573) (xy 403.261023 -279.099422) (xy 403.212168 -279.105354) (xy 403.162993 -279.103373)
			(xy 403.114774 -279.093529) (xy 403.068758 -279.076077) (xy 403.026137 -279.05147) (xy 402.988016 -279.020345)
			(xy 402.955381 -278.983508) (xy 402.929078 -278.941912) (xy 402.909787 -278.896636) (xy 402.89801 -278.848852)
			(xy 402.89405 -278.799798) (xy 402.577046 -278.799798) (xy 402.576542 -278.825506) (xy 402.568499 -278.876288)
			(xy 402.552611 -278.925187) (xy 402.529268 -278.970999) (xy 402.499047 -279.012595) (xy 402.462691 -279.048951)
			(xy 402.421095 -279.079172) (xy 402.375283 -279.102515) (xy 402.326384 -279.118403) (xy 402.275602 -279.126446)
			(xy 402.224186 -279.126446) (xy 402.173404 -279.118403) (xy 402.124505 -279.102515) (xy 402.078693 -279.079172)
			(xy 402.037097 -279.048951) (xy 402.000741 -279.012595) (xy 401.97052 -278.970999) (xy 401.947177 -278.925187)
			(xy 401.931289 -278.876288) (xy 401.923246 -278.825506) (xy 401.604568 -278.825506) (xy 401.596852 -278.872982)
			(xy 401.581268 -278.919663) (xy 401.558397 -278.96324) (xy 401.528832 -279.002584) (xy 401.493339 -279.036676)
			(xy 401.452836 -279.064632) (xy 401.408374 -279.08573) (xy 401.361103 -279.099422) (xy 401.312248 -279.105354)
			(xy 401.263073 -279.103373) (xy 401.214854 -279.093529) (xy 401.168838 -279.076077) (xy 401.126217 -279.05147)
			(xy 401.088096 -279.020345) (xy 401.055461 -278.983508) (xy 401.029158 -278.941912) (xy 401.009867 -278.896636)
			(xy 400.99809 -278.848852) (xy 400.99413 -278.799798) (xy 400.677126 -278.799798) (xy 400.676622 -278.825506)
			(xy 400.668579 -278.876288) (xy 400.652691 -278.925187) (xy 400.629348 -278.970999) (xy 400.599127 -279.012595)
			(xy 400.562771 -279.048951) (xy 400.521175 -279.079172) (xy 400.475363 -279.102515) (xy 400.426464 -279.118403)
			(xy 400.375682 -279.126446) (xy 400.324266 -279.126446) (xy 400.273484 -279.118403) (xy 400.224585 -279.102515)
			(xy 400.178773 -279.079172) (xy 400.137177 -279.048951) (xy 400.100821 -279.012595) (xy 400.0706 -278.970999)
			(xy 400.047257 -278.925187) (xy 400.031369 -278.876288) (xy 400.023326 -278.825506) (xy 399.704648 -278.825506)
			(xy 399.696932 -278.872982) (xy 399.681348 -278.919663) (xy 399.658477 -278.96324) (xy 399.628912 -279.002584)
			(xy 399.593419 -279.036676) (xy 399.552916 -279.064632) (xy 399.508454 -279.08573) (xy 399.461183 -279.099422)
			(xy 399.412328 -279.105354) (xy 399.363153 -279.103373) (xy 399.314934 -279.093529) (xy 399.268918 -279.076077)
			(xy 399.226297 -279.05147) (xy 399.188176 -279.020345) (xy 399.155541 -278.983508) (xy 399.129238 -278.941912)
			(xy 399.109947 -278.896636) (xy 399.09817 -278.848852) (xy 399.09421 -278.799798) (xy 398.776196 -278.799798)
			(xy 398.776196 -278.825488) (xy 398.768159 -278.876231) (xy 398.752283 -278.925093) (xy 398.728959 -278.970869)
			(xy 398.698761 -279.012433) (xy 398.662433 -279.048761) (xy 398.620869 -279.078959) (xy 398.575093 -279.102283)
			(xy 398.526231 -279.118159) (xy 398.475488 -279.126196) (xy 398.4498 -279.126696) (xy 398.436081 -279.126568)
			(xy 398.408739 -279.124281) (xy 398.39519 -279.122124) (xy 398.383252 -279.120346) (xy 398.360392 -279.127204)
			(xy 398.283938 -279.200864) (xy 398.276064 -279.22347) (xy 398.277588 -279.235408) (xy 398.278785 -279.245206)
			(xy 398.280057 -279.264907) (xy 398.280128 -279.274778) (xy 398.279942 -279.288961) (xy 398.277271 -279.3172)
			(xy 398.274794 -279.331166) (xy 398.272508 -279.343612) (xy 398.279874 -279.367234) (xy 398.357344 -279.444704)
			(xy 398.380966 -279.45207) (xy 398.393412 -279.449784) (xy 398.407377 -279.447299) (xy 398.435617 -279.444627)
			(xy 398.4498 -279.44445) (xy 398.475059 -279.444972) (xy 398.524887 -279.453287) (xy 398.572668 -279.46969)
			(xy 398.617097 -279.493733) (xy 398.656962 -279.524762) (xy 398.691177 -279.561929) (xy 398.718807 -279.604221)
			(xy 398.7391 -279.650483) (xy 398.751501 -279.699455) (xy 398.755673 -279.7498) (xy 398.753567 -279.775212)
			(xy 399.073366 -279.775212) (xy 399.073366 -279.723796) (xy 399.081409 -279.673014) (xy 399.097297 -279.624115)
			(xy 399.12064 -279.578303) (xy 399.150861 -279.536707) (xy 399.187217 -279.500351) (xy 399.228813 -279.47013)
			(xy 399.274625 -279.446787) (xy 399.323524 -279.430899) (xy 399.374306 -279.422856) (xy 399.425722 -279.422856)
			(xy 399.476504 -279.430899) (xy 399.525403 -279.446787) (xy 399.571215 -279.47013) (xy 399.612811 -279.500351)
			(xy 399.649167 -279.536707) (xy 399.679388 -279.578303) (xy 399.702731 -279.624115) (xy 399.718619 -279.673014)
			(xy 399.726662 -279.723796) (xy 399.727166 -279.749504) (xy 399.727161 -279.749758) (xy 400.04417 -279.749758)
			(xy 400.04813 -279.700704) (xy 400.059907 -279.65292) (xy 400.079198 -279.607644) (xy 400.105501 -279.566048)
			(xy 400.138136 -279.529211) (xy 400.176257 -279.498086) (xy 400.218878 -279.473479) (xy 400.264894 -279.456027)
			(xy 400.313113 -279.446183) (xy 400.362288 -279.444202) (xy 400.411143 -279.450134) (xy 400.458414 -279.463826)
			(xy 400.502876 -279.484924) (xy 400.543379 -279.51288) (xy 400.578872 -279.546972) (xy 400.608437 -279.586316)
			(xy 400.631308 -279.629893) (xy 400.646892 -279.676574) (xy 400.654787 -279.725151) (xy 400.655282 -279.749758)
			(xy 400.654787 -279.774365) (xy 400.654649 -279.775212) (xy 400.973286 -279.775212) (xy 400.973286 -279.723796)
			(xy 400.981329 -279.673014) (xy 400.997217 -279.624115) (xy 401.02056 -279.578303) (xy 401.050781 -279.536707)
			(xy 401.087137 -279.500351) (xy 401.128733 -279.47013) (xy 401.174545 -279.446787) (xy 401.223444 -279.430899)
			(xy 401.274226 -279.422856) (xy 401.325642 -279.422856) (xy 401.376424 -279.430899) (xy 401.425323 -279.446787)
			(xy 401.471135 -279.47013) (xy 401.512731 -279.500351) (xy 401.549087 -279.536707) (xy 401.579308 -279.578303)
			(xy 401.602651 -279.624115) (xy 401.618539 -279.673014) (xy 401.626582 -279.723796) (xy 401.627086 -279.749504)
			(xy 401.627081 -279.749758) (xy 401.94409 -279.749758) (xy 401.94805 -279.700704) (xy 401.959827 -279.65292)
			(xy 401.979118 -279.607644) (xy 402.005421 -279.566048) (xy 402.038056 -279.529211) (xy 402.076177 -279.498086)
			(xy 402.118798 -279.473479) (xy 402.164814 -279.456027) (xy 402.213033 -279.446183) (xy 402.262208 -279.444202)
			(xy 402.311063 -279.450134) (xy 402.358334 -279.463826) (xy 402.402796 -279.484924) (xy 402.443299 -279.51288)
			(xy 402.478792 -279.546972) (xy 402.508357 -279.586316) (xy 402.531228 -279.629893) (xy 402.546812 -279.676574)
			(xy 402.554707 -279.725151) (xy 402.555202 -279.749758) (xy 402.554707 -279.774365) (xy 402.554569 -279.775212)
			(xy 402.873206 -279.775212) (xy 402.873206 -279.723796) (xy 402.881249 -279.673014) (xy 402.897137 -279.624115)
			(xy 402.92048 -279.578303) (xy 402.950701 -279.536707) (xy 402.987057 -279.500351) (xy 403.028653 -279.47013)
			(xy 403.074465 -279.446787) (xy 403.123364 -279.430899) (xy 403.174146 -279.422856) (xy 403.225562 -279.422856)
			(xy 403.276344 -279.430899) (xy 403.325243 -279.446787) (xy 403.371055 -279.47013) (xy 403.412651 -279.500351)
			(xy 403.449007 -279.536707) (xy 403.479228 -279.578303) (xy 403.502571 -279.624115) (xy 403.518459 -279.673014)
			(xy 403.526502 -279.723796) (xy 403.527006 -279.749504) (xy 403.527001 -279.749758) (xy 403.84401 -279.749758)
			(xy 403.84797 -279.700704) (xy 403.859747 -279.65292) (xy 403.879038 -279.607644) (xy 403.905341 -279.566048)
			(xy 403.937976 -279.529211) (xy 403.976097 -279.498086) (xy 404.018718 -279.473479) (xy 404.064734 -279.456027)
			(xy 404.112953 -279.446183) (xy 404.162128 -279.444202) (xy 404.210983 -279.450134) (xy 404.258254 -279.463826)
			(xy 404.302716 -279.484924) (xy 404.343219 -279.51288) (xy 404.378712 -279.546972) (xy 404.408277 -279.586316)
			(xy 404.431148 -279.629893) (xy 404.446732 -279.676574) (xy 404.454627 -279.725151) (xy 404.455122 -279.749758)
			(xy 404.454627 -279.774365) (xy 404.454489 -279.775212) (xy 404.773126 -279.775212) (xy 404.773126 -279.723796)
			(xy 404.781169 -279.673014) (xy 404.797057 -279.624115) (xy 404.8204 -279.578303) (xy 404.850621 -279.536707)
			(xy 404.886977 -279.500351) (xy 404.928573 -279.47013) (xy 404.974385 -279.446787) (xy 405.023284 -279.430899)
			(xy 405.074066 -279.422856) (xy 405.125482 -279.422856) (xy 405.176264 -279.430899) (xy 405.225163 -279.446787)
			(xy 405.270975 -279.47013) (xy 405.312571 -279.500351) (xy 405.348927 -279.536707) (xy 405.379148 -279.578303)
			(xy 405.402491 -279.624115) (xy 405.418379 -279.673014) (xy 405.426422 -279.723796) (xy 405.426926 -279.749504)
			(xy 405.426921 -279.749758) (xy 405.744184 -279.749758) (xy 405.748144 -279.700704) (xy 405.759921 -279.65292)
			(xy 405.779212 -279.607644) (xy 405.805515 -279.566048) (xy 405.83815 -279.529211) (xy 405.876271 -279.498086)
			(xy 405.918892 -279.473479) (xy 405.964908 -279.456027) (xy 406.013127 -279.446183) (xy 406.062302 -279.444202)
			(xy 406.111157 -279.450134) (xy 406.158428 -279.463826) (xy 406.20289 -279.484924) (xy 406.243393 -279.51288)
			(xy 406.278886 -279.546972) (xy 406.308451 -279.586316) (xy 406.331322 -279.629893) (xy 406.346906 -279.676574)
			(xy 406.354801 -279.725151) (xy 406.355296 -279.749758) (xy 406.354801 -279.774365) (xy 406.354663 -279.775212)
			(xy 406.6733 -279.775212) (xy 406.6733 -279.723796) (xy 406.681343 -279.673014) (xy 406.697231 -279.624115)
			(xy 406.720574 -279.578303) (xy 406.750795 -279.536707) (xy 406.787151 -279.500351) (xy 406.828747 -279.47013)
			(xy 406.874559 -279.446787) (xy 406.923458 -279.430899) (xy 406.97424 -279.422856) (xy 407.025656 -279.422856)
			(xy 407.076438 -279.430899) (xy 407.125337 -279.446787) (xy 407.171149 -279.47013) (xy 407.212745 -279.500351)
			(xy 407.249101 -279.536707) (xy 407.279322 -279.578303) (xy 407.302665 -279.624115) (xy 407.318553 -279.673014)
			(xy 407.326596 -279.723796) (xy 407.3271 -279.749504) (xy 407.327095 -279.749758) (xy 407.644104 -279.749758)
			(xy 407.648064 -279.700704) (xy 407.659841 -279.65292) (xy 407.679132 -279.607644) (xy 407.705435 -279.566048)
			(xy 407.73807 -279.529211) (xy 407.776191 -279.498086) (xy 407.818812 -279.473479) (xy 407.864828 -279.456027)
			(xy 407.913047 -279.446183) (xy 407.962222 -279.444202) (xy 408.011077 -279.450134) (xy 408.058348 -279.463826)
			(xy 408.10281 -279.484924) (xy 408.143313 -279.51288) (xy 408.178806 -279.546972) (xy 408.208371 -279.586316)
			(xy 408.231242 -279.629893) (xy 408.246826 -279.676574) (xy 408.254721 -279.725151) (xy 408.255216 -279.749758)
			(xy 408.254721 -279.774365) (xy 408.254583 -279.775212) (xy 408.57322 -279.775212) (xy 408.57322 -279.723796)
			(xy 408.581263 -279.673014) (xy 408.597151 -279.624115) (xy 408.620494 -279.578303) (xy 408.650715 -279.536707)
			(xy 408.687071 -279.500351) (xy 408.728667 -279.47013) (xy 408.774479 -279.446787) (xy 408.823378 -279.430899)
			(xy 408.87416 -279.422856) (xy 408.925576 -279.422856) (xy 408.976358 -279.430899) (xy 409.025257 -279.446787)
			(xy 409.071069 -279.47013) (xy 409.112665 -279.500351) (xy 409.149021 -279.536707) (xy 409.179242 -279.578303)
			(xy 409.202585 -279.624115) (xy 409.218473 -279.673014) (xy 409.226516 -279.723796) (xy 409.22702 -279.749504)
			(xy 409.227015 -279.749758) (xy 409.544024 -279.749758) (xy 409.547984 -279.700704) (xy 409.559761 -279.65292)
			(xy 409.579052 -279.607644) (xy 409.605355 -279.566048) (xy 409.63799 -279.529211) (xy 409.676111 -279.498086)
			(xy 409.718732 -279.473479) (xy 409.764748 -279.456027) (xy 409.812967 -279.446183) (xy 409.862142 -279.444202)
			(xy 409.910997 -279.450134) (xy 409.958268 -279.463826) (xy 410.00273 -279.484924) (xy 410.043233 -279.51288)
			(xy 410.078726 -279.546972) (xy 410.108291 -279.586316) (xy 410.131162 -279.629893) (xy 410.146746 -279.676574)
			(xy 410.154641 -279.725151) (xy 410.155136 -279.749758) (xy 410.154641 -279.774365) (xy 410.154503 -279.775212)
			(xy 410.47314 -279.775212) (xy 410.47314 -279.723796) (xy 410.481183 -279.673014) (xy 410.497071 -279.624115)
			(xy 410.520414 -279.578303) (xy 410.550635 -279.536707) (xy 410.586991 -279.500351) (xy 410.628587 -279.47013)
			(xy 410.674399 -279.446787) (xy 410.723298 -279.430899) (xy 410.77408 -279.422856) (xy 410.825496 -279.422856)
			(xy 410.876278 -279.430899) (xy 410.925177 -279.446787) (xy 410.970989 -279.47013) (xy 411.012585 -279.500351)
			(xy 411.048941 -279.536707) (xy 411.079162 -279.578303) (xy 411.102505 -279.624115) (xy 411.118393 -279.673014)
			(xy 411.126436 -279.723796) (xy 411.12694 -279.749504) (xy 411.126935 -279.749758) (xy 411.444198 -279.749758)
			(xy 411.448158 -279.700704) (xy 411.459935 -279.65292) (xy 411.479226 -279.607644) (xy 411.505529 -279.566048)
			(xy 411.538164 -279.529211) (xy 411.576285 -279.498086) (xy 411.618906 -279.473479) (xy 411.664922 -279.456027)
			(xy 411.713141 -279.446183) (xy 411.762316 -279.444202) (xy 411.811171 -279.450134) (xy 411.858442 -279.463826)
			(xy 411.902904 -279.484924) (xy 411.943407 -279.51288) (xy 411.9789 -279.546972) (xy 412.008465 -279.586316)
			(xy 412.031336 -279.629893) (xy 412.04692 -279.676574) (xy 412.054815 -279.725151) (xy 412.05531 -279.749758)
			(xy 412.054815 -279.774365) (xy 412.054677 -279.775212) (xy 412.373314 -279.775212) (xy 412.373314 -279.723796)
			(xy 412.381357 -279.673014) (xy 412.397245 -279.624115) (xy 412.420588 -279.578303) (xy 412.450809 -279.536707)
			(xy 412.487165 -279.500351) (xy 412.528761 -279.47013) (xy 412.574573 -279.446787) (xy 412.623472 -279.430899)
			(xy 412.674254 -279.422856) (xy 412.72567 -279.422856) (xy 412.776452 -279.430899) (xy 412.825351 -279.446787)
			(xy 412.871163 -279.47013) (xy 412.912759 -279.500351) (xy 412.949115 -279.536707) (xy 412.979336 -279.578303)
			(xy 413.002679 -279.624115) (xy 413.018567 -279.673014) (xy 413.02661 -279.723796) (xy 413.027114 -279.749504)
			(xy 413.027109 -279.749758) (xy 413.344118 -279.749758) (xy 413.348078 -279.700704) (xy 413.359855 -279.65292)
			(xy 413.379146 -279.607644) (xy 413.405449 -279.566048) (xy 413.438084 -279.529211) (xy 413.476205 -279.498086)
			(xy 413.518826 -279.473479) (xy 413.564842 -279.456027) (xy 413.613061 -279.446183) (xy 413.662236 -279.444202)
			(xy 413.711091 -279.450134) (xy 413.758362 -279.463826) (xy 413.802824 -279.484924) (xy 413.843327 -279.51288)
			(xy 413.87882 -279.546972) (xy 413.908385 -279.586316) (xy 413.931256 -279.629893) (xy 413.94684 -279.676574)
			(xy 413.954735 -279.725151) (xy 413.95523 -279.749758) (xy 413.954735 -279.774365) (xy 413.954597 -279.775212)
			(xy 414.273234 -279.775212) (xy 414.273234 -279.723796) (xy 414.281277 -279.673014) (xy 414.297165 -279.624115)
			(xy 414.320508 -279.578303) (xy 414.350729 -279.536707) (xy 414.387085 -279.500351) (xy 414.428681 -279.47013)
			(xy 414.474493 -279.446787) (xy 414.523392 -279.430899) (xy 414.574174 -279.422856) (xy 414.62559 -279.422856)
			(xy 414.676372 -279.430899) (xy 414.725271 -279.446787) (xy 414.771083 -279.47013) (xy 414.812679 -279.500351)
			(xy 414.849035 -279.536707) (xy 414.879256 -279.578303) (xy 414.902599 -279.624115) (xy 414.918487 -279.673014)
			(xy 414.92653 -279.723796) (xy 414.927034 -279.749504) (xy 414.927029 -279.749758) (xy 415.244038 -279.749758)
			(xy 415.247998 -279.700704) (xy 415.259775 -279.65292) (xy 415.279066 -279.607644) (xy 415.305369 -279.566048)
			(xy 415.338004 -279.529211) (xy 415.376125 -279.498086) (xy 415.418746 -279.473479) (xy 415.464762 -279.456027)
			(xy 415.512981 -279.446183) (xy 415.562156 -279.444202) (xy 415.611011 -279.450134) (xy 415.658282 -279.463826)
			(xy 415.702744 -279.484924) (xy 415.743247 -279.51288) (xy 415.77874 -279.546972) (xy 415.808305 -279.586316)
			(xy 415.831176 -279.629893) (xy 415.84676 -279.676574) (xy 415.854655 -279.725151) (xy 415.85515 -279.749758)
			(xy 415.854655 -279.774365) (xy 415.854517 -279.775212) (xy 416.173154 -279.775212) (xy 416.173154 -279.723796)
			(xy 416.181197 -279.673014) (xy 416.197085 -279.624115) (xy 416.220428 -279.578303) (xy 416.250649 -279.536707)
			(xy 416.287005 -279.500351) (xy 416.328601 -279.47013) (xy 416.374413 -279.446787) (xy 416.423312 -279.430899)
			(xy 416.474094 -279.422856) (xy 416.52551 -279.422856) (xy 416.576292 -279.430899) (xy 416.625191 -279.446787)
			(xy 416.671003 -279.47013) (xy 416.712599 -279.500351) (xy 416.748955 -279.536707) (xy 416.779176 -279.578303)
			(xy 416.802519 -279.624115) (xy 416.818407 -279.673014) (xy 416.82645 -279.723796) (xy 416.826954 -279.749504)
			(xy 416.826949 -279.749758) (xy 417.144212 -279.749758) (xy 417.148172 -279.700704) (xy 417.159949 -279.65292)
			(xy 417.17924 -279.607644) (xy 417.205543 -279.566048) (xy 417.238178 -279.529211) (xy 417.276299 -279.498086)
			(xy 417.31892 -279.473479) (xy 417.364936 -279.456027) (xy 417.413155 -279.446183) (xy 417.46233 -279.444202)
			(xy 417.511185 -279.450134) (xy 417.558456 -279.463826) (xy 417.602918 -279.484924) (xy 417.643421 -279.51288)
			(xy 417.678914 -279.546972) (xy 417.708479 -279.586316) (xy 417.73135 -279.629893) (xy 417.746934 -279.676574)
			(xy 417.754829 -279.725151) (xy 417.755324 -279.749758) (xy 417.754829 -279.774365) (xy 417.754691 -279.775212)
			(xy 418.073328 -279.775212) (xy 418.073328 -279.723796) (xy 418.081371 -279.673014) (xy 418.097259 -279.624115)
			(xy 418.120602 -279.578303) (xy 418.150823 -279.536707) (xy 418.187179 -279.500351) (xy 418.228775 -279.47013)
			(xy 418.274587 -279.446787) (xy 418.323486 -279.430899) (xy 418.374268 -279.422856) (xy 418.425684 -279.422856)
			(xy 418.476466 -279.430899) (xy 418.525365 -279.446787) (xy 418.571177 -279.47013) (xy 418.612773 -279.500351)
			(xy 418.649129 -279.536707) (xy 418.67935 -279.578303) (xy 418.702693 -279.624115) (xy 418.718581 -279.673014)
			(xy 418.726624 -279.723796) (xy 418.727128 -279.749504) (xy 418.727123 -279.749758) (xy 419.044132 -279.749758)
			(xy 419.048092 -279.700704) (xy 419.059869 -279.65292) (xy 419.07916 -279.607644) (xy 419.105463 -279.566048)
			(xy 419.138098 -279.529211) (xy 419.176219 -279.498086) (xy 419.21884 -279.473479) (xy 419.264856 -279.456027)
			(xy 419.313075 -279.446183) (xy 419.36225 -279.444202) (xy 419.411105 -279.450134) (xy 419.458376 -279.463826)
			(xy 419.502838 -279.484924) (xy 419.543341 -279.51288) (xy 419.578834 -279.546972) (xy 419.608399 -279.586316)
			(xy 419.63127 -279.629893) (xy 419.646854 -279.676574) (xy 419.654749 -279.725151) (xy 419.655244 -279.749758)
			(xy 419.654749 -279.774365) (xy 419.654611 -279.775212) (xy 419.973248 -279.775212) (xy 419.973248 -279.723796)
			(xy 419.981291 -279.673014) (xy 419.997179 -279.624115) (xy 420.020522 -279.578303) (xy 420.050743 -279.536707)
			(xy 420.087099 -279.500351) (xy 420.128695 -279.47013) (xy 420.174507 -279.446787) (xy 420.223406 -279.430899)
			(xy 420.274188 -279.422856) (xy 420.325604 -279.422856) (xy 420.376386 -279.430899) (xy 420.425285 -279.446787)
			(xy 420.471097 -279.47013) (xy 420.512693 -279.500351) (xy 420.549049 -279.536707) (xy 420.57927 -279.578303)
			(xy 420.602613 -279.624115) (xy 420.618501 -279.673014) (xy 420.626544 -279.723796) (xy 420.627048 -279.749504)
			(xy 420.627043 -279.749758) (xy 420.944052 -279.749758) (xy 420.948012 -279.700704) (xy 420.959789 -279.65292)
			(xy 420.97908 -279.607644) (xy 421.005383 -279.566048) (xy 421.038018 -279.529211) (xy 421.076139 -279.498086)
			(xy 421.11876 -279.473479) (xy 421.164776 -279.456027) (xy 421.212995 -279.446183) (xy 421.26217 -279.444202)
			(xy 421.311025 -279.450134) (xy 421.358296 -279.463826) (xy 421.402758 -279.484924) (xy 421.443261 -279.51288)
			(xy 421.478754 -279.546972) (xy 421.508319 -279.586316) (xy 421.53119 -279.629893) (xy 421.546774 -279.676574)
			(xy 421.554669 -279.725151) (xy 421.555164 -279.749758) (xy 421.554669 -279.774365) (xy 421.554531 -279.775212)
			(xy 421.873168 -279.775212) (xy 421.873168 -279.723796) (xy 421.881211 -279.673014) (xy 421.897099 -279.624115)
			(xy 421.920442 -279.578303) (xy 421.950663 -279.536707) (xy 421.987019 -279.500351) (xy 422.028615 -279.47013)
			(xy 422.074427 -279.446787) (xy 422.123326 -279.430899) (xy 422.174108 -279.422856) (xy 422.225524 -279.422856)
			(xy 422.276306 -279.430899) (xy 422.325205 -279.446787) (xy 422.371017 -279.47013) (xy 422.412613 -279.500351)
			(xy 422.448969 -279.536707) (xy 422.47919 -279.578303) (xy 422.502533 -279.624115) (xy 422.518421 -279.673014)
			(xy 422.526464 -279.723796) (xy 422.526968 -279.749504) (xy 422.526963 -279.749758) (xy 422.843972 -279.749758)
			(xy 422.847932 -279.700704) (xy 422.859709 -279.65292) (xy 422.879 -279.607644) (xy 422.905303 -279.566048)
			(xy 422.937938 -279.529211) (xy 422.976059 -279.498086) (xy 423.01868 -279.473479) (xy 423.064696 -279.456027)
			(xy 423.112915 -279.446183) (xy 423.16209 -279.444202) (xy 423.210945 -279.450134) (xy 423.258216 -279.463826)
			(xy 423.302678 -279.484924) (xy 423.343181 -279.51288) (xy 423.378674 -279.546972) (xy 423.408239 -279.586316)
			(xy 423.43111 -279.629893) (xy 423.446694 -279.676574) (xy 423.454589 -279.725151) (xy 423.455084 -279.749758)
			(xy 423.454589 -279.774365) (xy 423.454451 -279.775212) (xy 423.773342 -279.775212) (xy 423.773342 -279.723796)
			(xy 423.781385 -279.673014) (xy 423.797273 -279.624115) (xy 423.820616 -279.578303) (xy 423.850837 -279.536707)
			(xy 423.887193 -279.500351) (xy 423.928789 -279.47013) (xy 423.974601 -279.446787) (xy 424.0235 -279.430899)
			(xy 424.074282 -279.422856) (xy 424.125698 -279.422856) (xy 424.17648 -279.430899) (xy 424.225379 -279.446787)
			(xy 424.271191 -279.47013) (xy 424.312787 -279.500351) (xy 424.349143 -279.536707) (xy 424.379364 -279.578303)
			(xy 424.402707 -279.624115) (xy 424.418595 -279.673014) (xy 424.426638 -279.723796) (xy 424.427142 -279.749504)
			(xy 424.427137 -279.749758) (xy 424.744146 -279.749758) (xy 424.748106 -279.700704) (xy 424.759883 -279.65292)
			(xy 424.779174 -279.607644) (xy 424.805477 -279.566048) (xy 424.838112 -279.529211) (xy 424.876233 -279.498086)
			(xy 424.918854 -279.473479) (xy 424.96487 -279.456027) (xy 425.013089 -279.446183) (xy 425.062264 -279.444202)
			(xy 425.111119 -279.450134) (xy 425.15839 -279.463826) (xy 425.202852 -279.484924) (xy 425.243355 -279.51288)
			(xy 425.278848 -279.546972) (xy 425.308413 -279.586316) (xy 425.331284 -279.629893) (xy 425.346868 -279.676574)
			(xy 425.354763 -279.725151) (xy 425.355258 -279.749758) (xy 425.354763 -279.774365) (xy 425.354625 -279.775212)
			(xy 425.673262 -279.775212) (xy 425.673262 -279.723796) (xy 425.681305 -279.673014) (xy 425.697193 -279.624115)
			(xy 425.720536 -279.578303) (xy 425.750757 -279.536707) (xy 425.787113 -279.500351) (xy 425.828709 -279.47013)
			(xy 425.874521 -279.446787) (xy 425.92342 -279.430899) (xy 425.974202 -279.422856) (xy 426.025618 -279.422856)
			(xy 426.0764 -279.430899) (xy 426.125299 -279.446787) (xy 426.171111 -279.47013) (xy 426.212707 -279.500351)
			(xy 426.249063 -279.536707) (xy 426.279284 -279.578303) (xy 426.302627 -279.624115) (xy 426.318515 -279.673014)
			(xy 426.326558 -279.723796) (xy 426.327062 -279.749504) (xy 426.327057 -279.749758) (xy 426.644066 -279.749758)
			(xy 426.648026 -279.700704) (xy 426.659803 -279.65292) (xy 426.679094 -279.607644) (xy 426.705397 -279.566048)
			(xy 426.738032 -279.529211) (xy 426.776153 -279.498086) (xy 426.818774 -279.473479) (xy 426.86479 -279.456027)
			(xy 426.913009 -279.446183) (xy 426.962184 -279.444202) (xy 427.011039 -279.450134) (xy 427.05831 -279.463826)
			(xy 427.102772 -279.484924) (xy 427.143275 -279.51288) (xy 427.178768 -279.546972) (xy 427.208333 -279.586316)
			(xy 427.231204 -279.629893) (xy 427.246788 -279.676574) (xy 427.254683 -279.725151) (xy 427.255178 -279.749758)
			(xy 427.254683 -279.774365) (xy 427.254504 -279.775466) (xy 427.573182 -279.775466) (xy 427.573182 -279.72405)
			(xy 427.581225 -279.673268) (xy 427.597113 -279.624369) (xy 427.620456 -279.578557) (xy 427.650677 -279.536961)
			(xy 427.687033 -279.500605) (xy 427.728629 -279.470384) (xy 427.774441 -279.447041) (xy 427.82334 -279.431153)
			(xy 427.874122 -279.42311) (xy 427.925538 -279.42311) (xy 427.97632 -279.431153) (xy 428.025219 -279.447041)
			(xy 428.071031 -279.470384) (xy 428.112627 -279.500605) (xy 428.148983 -279.536961) (xy 428.179204 -279.578557)
			(xy 428.202547 -279.624369) (xy 428.218435 -279.673268) (xy 428.226478 -279.72405) (xy 428.226982 -279.749758)
			(xy 428.543986 -279.749758) (xy 428.547946 -279.700704) (xy 428.559723 -279.65292) (xy 428.579014 -279.607644)
			(xy 428.605317 -279.566048) (xy 428.637952 -279.529211) (xy 428.676073 -279.498086) (xy 428.718694 -279.473479)
			(xy 428.76471 -279.456027) (xy 428.812929 -279.446183) (xy 428.862104 -279.444202) (xy 428.910959 -279.450134)
			(xy 428.95823 -279.463826) (xy 429.002692 -279.484924) (xy 429.043195 -279.51288) (xy 429.078688 -279.546972)
			(xy 429.108253 -279.586316) (xy 429.131124 -279.629893) (xy 429.146708 -279.676574) (xy 429.154603 -279.725151)
			(xy 429.155098 -279.749758) (xy 429.154603 -279.774365) (xy 429.154424 -279.775466) (xy 429.473356 -279.775466)
			(xy 429.473356 -279.72405) (xy 429.481399 -279.673268) (xy 429.497287 -279.624369) (xy 429.52063 -279.578557)
			(xy 429.550851 -279.536961) (xy 429.587207 -279.500605) (xy 429.628803 -279.470384) (xy 429.674615 -279.447041)
			(xy 429.723514 -279.431153) (xy 429.774296 -279.42311) (xy 429.825712 -279.42311) (xy 429.876494 -279.431153)
			(xy 429.925393 -279.447041) (xy 429.971205 -279.470384) (xy 430.012801 -279.500605) (xy 430.049157 -279.536961)
			(xy 430.079378 -279.578557) (xy 430.102721 -279.624369) (xy 430.118609 -279.673268) (xy 430.126652 -279.72405)
			(xy 430.127156 -279.749758) (xy 430.126652 -279.775466) (xy 430.423316 -279.775466) (xy 430.423316 -279.72405)
			(xy 430.431359 -279.673268) (xy 430.447247 -279.624369) (xy 430.47059 -279.578557) (xy 430.500811 -279.536961)
			(xy 430.537167 -279.500605) (xy 430.578763 -279.470384) (xy 430.624575 -279.447041) (xy 430.673474 -279.431153)
			(xy 430.724256 -279.42311) (xy 430.775672 -279.42311) (xy 430.826454 -279.431153) (xy 430.875353 -279.447041)
			(xy 430.921165 -279.470384) (xy 430.962761 -279.500605) (xy 430.999117 -279.536961) (xy 431.029338 -279.578557)
			(xy 431.052681 -279.624369) (xy 431.068569 -279.673268) (xy 431.076612 -279.72405) (xy 431.077116 -279.749758)
			(xy 431.077111 -279.750012) (xy 431.394374 -279.750012) (xy 431.398334 -279.700958) (xy 431.410111 -279.653174)
			(xy 431.429402 -279.607898) (xy 431.455705 -279.566302) (xy 431.48834 -279.529465) (xy 431.526461 -279.49834)
			(xy 431.569082 -279.473733) (xy 431.615098 -279.456281) (xy 431.663317 -279.446437) (xy 431.712492 -279.444456)
			(xy 431.761347 -279.450388) (xy 431.808618 -279.46408) (xy 431.85308 -279.485178) (xy 431.893583 -279.513134)
			(xy 431.929076 -279.547226) (xy 431.958641 -279.58657) (xy 431.981512 -279.630147) (xy 431.997096 -279.676828)
			(xy 432.004991 -279.725405) (xy 432.005486 -279.750012) (xy 432.004991 -279.774619) (xy 431.997096 -279.823196)
			(xy 431.981512 -279.869877) (xy 431.970835 -279.89022) (xy 447.862958 -279.89022) (xy 447.867029 -279.834598)
			(xy 447.879155 -279.780161) (xy 447.899078 -279.72807) (xy 447.926374 -279.679435) (xy 447.96046 -279.635292)
			(xy 448.000609 -279.596583) (xy 448.045967 -279.564132) (xy 448.095567 -279.538631) (xy 448.148351 -279.520624)
			(xy 448.203194 -279.510494) (xy 448.258928 -279.508457) (xy 448.314365 -279.514557) (xy 448.368322 -279.528663)
			(xy 448.419651 -279.550475) (xy 448.467257 -279.579529) (xy 448.510125 -279.615204) (xy 448.547342 -279.656741)
			(xy 448.569895 -279.69083) (xy 461.074006 -279.69083) (xy 461.078077 -279.635208) (xy 461.090203 -279.580771)
			(xy 461.110126 -279.52868) (xy 461.137422 -279.480045) (xy 461.171508 -279.435902) (xy 461.211657 -279.397193)
			(xy 461.257015 -279.364742) (xy 461.306615 -279.339241) (xy 461.359399 -279.321234) (xy 461.414242 -279.311104)
			(xy 461.469976 -279.309067) (xy 461.525413 -279.315167) (xy 461.57937 -279.329273) (xy 461.630699 -279.351085)
			(xy 461.678305 -279.380139) (xy 461.721173 -279.415814) (xy 461.75839 -279.457351) (xy 461.789163 -279.503864)
			(xy 461.812835 -279.554361) (xy 461.828903 -279.607768) (xy 461.837023 -279.662944) (xy 461.837532 -279.69083)
			(xy 461.837023 -279.718716) (xy 461.828903 -279.773892) (xy 461.812835 -279.827299) (xy 461.789163 -279.877796)
			(xy 461.75839 -279.924309) (xy 461.721173 -279.965846) (xy 461.678305 -280.001521) (xy 461.630699 -280.030575)
			(xy 461.57937 -280.052387) (xy 461.525413 -280.066493) (xy 461.469976 -280.072593) (xy 461.414242 -280.070556)
			(xy 461.359399 -280.060426) (xy 461.306615 -280.042419) (xy 461.257015 -280.016918) (xy 461.211657 -279.984467)
			(xy 461.171508 -279.945758) (xy 461.137422 -279.901615) (xy 461.110126 -279.85298) (xy 461.090203 -279.800889)
			(xy 461.078077 -279.746452) (xy 461.074006 -279.69083) (xy 448.569895 -279.69083) (xy 448.578115 -279.703254)
			(xy 448.601787 -279.753751) (xy 448.617855 -279.807158) (xy 448.625975 -279.862334) (xy 448.626484 -279.89022)
			(xy 448.625975 -279.918106) (xy 448.617855 -279.973282) (xy 448.601787 -280.026689) (xy 448.578115 -280.077186)
			(xy 448.547342 -280.123699) (xy 448.510125 -280.165236) (xy 448.467257 -280.200911) (xy 448.428632 -280.224484)
			(xy 455.005184 -280.224484) (xy 455.009255 -280.168862) (xy 455.021381 -280.114425) (xy 455.041304 -280.062334)
			(xy 455.0686 -280.013699) (xy 455.102686 -279.969556) (xy 455.142835 -279.930847) (xy 455.188193 -279.898396)
			(xy 455.237793 -279.872895) (xy 455.290577 -279.854888) (xy 455.34542 -279.844758) (xy 455.401154 -279.842721)
			(xy 455.456591 -279.848821) (xy 455.510548 -279.862927) (xy 455.561877 -279.884739) (xy 455.609483 -279.913793)
			(xy 455.652351 -279.949468) (xy 455.689568 -279.991005) (xy 455.720341 -280.037518) (xy 455.744013 -280.088015)
			(xy 455.760081 -280.141422) (xy 455.768201 -280.196598) (xy 455.76871 -280.224484) (xy 457.024484 -280.224484)
			(xy 457.028555 -280.168862) (xy 457.040681 -280.114425) (xy 457.060604 -280.062334) (xy 457.0879 -280.013699)
			(xy 457.121986 -279.969556) (xy 457.162135 -279.930847) (xy 457.207493 -279.898396) (xy 457.257093 -279.872895)
			(xy 457.309877 -279.854888) (xy 457.36472 -279.844758) (xy 457.420454 -279.842721) (xy 457.475891 -279.848821)
			(xy 457.529848 -279.862927) (xy 457.581177 -279.884739) (xy 457.628783 -279.913793) (xy 457.671651 -279.949468)
			(xy 457.708868 -279.991005) (xy 457.739641 -280.037518) (xy 457.763313 -280.088015) (xy 457.779381 -280.141422)
			(xy 457.787501 -280.196598) (xy 457.78801 -280.224484) (xy 457.787501 -280.25237) (xy 457.779381 -280.307546)
			(xy 457.763313 -280.360953) (xy 457.739641 -280.41145) (xy 457.708868 -280.457963) (xy 457.671651 -280.4995)
			(xy 457.628783 -280.535175) (xy 457.581177 -280.564229) (xy 457.529848 -280.586041) (xy 457.475891 -280.600147)
			(xy 457.420454 -280.606247) (xy 457.36472 -280.60421) (xy 457.309877 -280.59408) (xy 457.257093 -280.576073)
			(xy 457.207493 -280.550572) (xy 457.162135 -280.518121) (xy 457.121986 -280.479412) (xy 457.0879 -280.435269)
			(xy 457.060604 -280.386634) (xy 457.040681 -280.334543) (xy 457.028555 -280.280106) (xy 457.024484 -280.224484)
			(xy 455.76871 -280.224484) (xy 455.768201 -280.25237) (xy 455.760081 -280.307546) (xy 455.744013 -280.360953)
			(xy 455.720341 -280.41145) (xy 455.689568 -280.457963) (xy 455.652351 -280.4995) (xy 455.609483 -280.535175)
			(xy 455.561877 -280.564229) (xy 455.510548 -280.586041) (xy 455.456591 -280.600147) (xy 455.401154 -280.606247)
			(xy 455.34542 -280.60421) (xy 455.290577 -280.59408) (xy 455.237793 -280.576073) (xy 455.188193 -280.550572)
			(xy 455.142835 -280.518121) (xy 455.102686 -280.479412) (xy 455.0686 -280.435269) (xy 455.041304 -280.386634)
			(xy 455.021381 -280.334543) (xy 455.009255 -280.280106) (xy 455.005184 -280.224484) (xy 448.428632 -280.224484)
			(xy 448.419651 -280.229965) (xy 448.368322 -280.251777) (xy 448.314365 -280.265883) (xy 448.258928 -280.271983)
			(xy 448.203194 -280.269946) (xy 448.148351 -280.259816) (xy 448.095567 -280.241809) (xy 448.045967 -280.216308)
			(xy 448.000609 -280.183857) (xy 447.96046 -280.145148) (xy 447.926374 -280.101005) (xy 447.899078 -280.05237)
			(xy 447.879155 -280.000279) (xy 447.867029 -279.945842) (xy 447.862958 -279.89022) (xy 431.970835 -279.89022)
			(xy 431.958641 -279.913454) (xy 431.929076 -279.952798) (xy 431.893583 -279.98689) (xy 431.85308 -280.014846)
			(xy 431.808618 -280.035944) (xy 431.761347 -280.049636) (xy 431.712492 -280.055568) (xy 431.663317 -280.053587)
			(xy 431.615098 -280.043743) (xy 431.569082 -280.026291) (xy 431.526461 -280.001684) (xy 431.48834 -279.970559)
			(xy 431.455705 -279.933722) (xy 431.429402 -279.892126) (xy 431.410111 -279.84685) (xy 431.398334 -279.799066)
			(xy 431.394374 -279.750012) (xy 431.077111 -279.750012) (xy 431.076612 -279.775466) (xy 431.068569 -279.826248)
			(xy 431.052681 -279.875147) (xy 431.029338 -279.920959) (xy 430.999117 -279.962555) (xy 430.962761 -279.998911)
			(xy 430.921165 -280.029132) (xy 430.875353 -280.052475) (xy 430.826454 -280.068363) (xy 430.775672 -280.076406)
			(xy 430.724256 -280.076406) (xy 430.673474 -280.068363) (xy 430.624575 -280.052475) (xy 430.578763 -280.029132)
			(xy 430.537167 -279.998911) (xy 430.500811 -279.962555) (xy 430.47059 -279.920959) (xy 430.447247 -279.875147)
			(xy 430.431359 -279.826248) (xy 430.423316 -279.775466) (xy 430.126652 -279.775466) (xy 430.118609 -279.826248)
			(xy 430.102721 -279.875147) (xy 430.079378 -279.920959) (xy 430.049157 -279.962555) (xy 430.012801 -279.998911)
			(xy 429.971205 -280.029132) (xy 429.925393 -280.052475) (xy 429.876494 -280.068363) (xy 429.825712 -280.076406)
			(xy 429.774296 -280.076406) (xy 429.723514 -280.068363) (xy 429.674615 -280.052475) (xy 429.628803 -280.029132)
			(xy 429.587207 -279.998911) (xy 429.550851 -279.962555) (xy 429.52063 -279.920959) (xy 429.497287 -279.875147)
			(xy 429.481399 -279.826248) (xy 429.473356 -279.775466) (xy 429.154424 -279.775466) (xy 429.146708 -279.822942)
			(xy 429.131124 -279.869623) (xy 429.108253 -279.9132) (xy 429.078688 -279.952544) (xy 429.043195 -279.986636)
			(xy 429.002692 -280.014592) (xy 428.95823 -280.03569) (xy 428.910959 -280.049382) (xy 428.862104 -280.055314)
			(xy 428.812929 -280.053333) (xy 428.76471 -280.043489) (xy 428.718694 -280.026037) (xy 428.676073 -280.00143)
			(xy 428.637952 -279.970305) (xy 428.605317 -279.933468) (xy 428.579014 -279.891872) (xy 428.559723 -279.846596)
			(xy 428.547946 -279.798812) (xy 428.543986 -279.749758) (xy 428.226982 -279.749758) (xy 428.226478 -279.775466)
			(xy 428.218435 -279.826248) (xy 428.202547 -279.875147) (xy 428.179204 -279.920959) (xy 428.148983 -279.962555)
			(xy 428.112627 -279.998911) (xy 428.071031 -280.029132) (xy 428.025219 -280.052475) (xy 427.97632 -280.068363)
			(xy 427.925538 -280.076406) (xy 427.874122 -280.076406) (xy 427.82334 -280.068363) (xy 427.774441 -280.052475)
			(xy 427.728629 -280.029132) (xy 427.687033 -279.998911) (xy 427.650677 -279.962555) (xy 427.620456 -279.920959)
			(xy 427.597113 -279.875147) (xy 427.581225 -279.826248) (xy 427.573182 -279.775466) (xy 427.254504 -279.775466)
			(xy 427.246788 -279.822942) (xy 427.231204 -279.869623) (xy 427.208333 -279.9132) (xy 427.178768 -279.952544)
			(xy 427.143275 -279.986636) (xy 427.102772 -280.014592) (xy 427.05831 -280.03569) (xy 427.011039 -280.049382)
			(xy 426.962184 -280.055314) (xy 426.913009 -280.053333) (xy 426.86479 -280.043489) (xy 426.818774 -280.026037)
			(xy 426.776153 -280.00143) (xy 426.738032 -279.970305) (xy 426.705397 -279.933468) (xy 426.679094 -279.891872)
			(xy 426.659803 -279.846596) (xy 426.648026 -279.798812) (xy 426.644066 -279.749758) (xy 426.327057 -279.749758)
			(xy 426.326558 -279.775212) (xy 426.318515 -279.825994) (xy 426.302627 -279.874893) (xy 426.279284 -279.920705)
			(xy 426.249063 -279.962301) (xy 426.212707 -279.998657) (xy 426.171111 -280.028878) (xy 426.125299 -280.052221)
			(xy 426.0764 -280.068109) (xy 426.025618 -280.076152) (xy 425.974202 -280.076152) (xy 425.92342 -280.068109)
			(xy 425.874521 -280.052221) (xy 425.828709 -280.028878) (xy 425.787113 -279.998657) (xy 425.750757 -279.962301)
			(xy 425.720536 -279.920705) (xy 425.697193 -279.874893) (xy 425.681305 -279.825994) (xy 425.673262 -279.775212)
			(xy 425.354625 -279.775212) (xy 425.346868 -279.822942) (xy 425.331284 -279.869623) (xy 425.308413 -279.9132)
			(xy 425.278848 -279.952544) (xy 425.243355 -279.986636) (xy 425.202852 -280.014592) (xy 425.15839 -280.03569)
			(xy 425.111119 -280.049382) (xy 425.062264 -280.055314) (xy 425.013089 -280.053333) (xy 424.96487 -280.043489)
			(xy 424.918854 -280.026037) (xy 424.876233 -280.00143) (xy 424.838112 -279.970305) (xy 424.805477 -279.933468)
			(xy 424.779174 -279.891872) (xy 424.759883 -279.846596) (xy 424.748106 -279.798812) (xy 424.744146 -279.749758)
			(xy 424.427137 -279.749758) (xy 424.426638 -279.775212) (xy 424.418595 -279.825994) (xy 424.402707 -279.874893)
			(xy 424.379364 -279.920705) (xy 424.349143 -279.962301) (xy 424.312787 -279.998657) (xy 424.271191 -280.028878)
			(xy 424.225379 -280.052221) (xy 424.17648 -280.068109) (xy 424.125698 -280.076152) (xy 424.074282 -280.076152)
			(xy 424.0235 -280.068109) (xy 423.974601 -280.052221) (xy 423.928789 -280.028878) (xy 423.887193 -279.998657)
			(xy 423.850837 -279.962301) (xy 423.820616 -279.920705) (xy 423.797273 -279.874893) (xy 423.781385 -279.825994)
			(xy 423.773342 -279.775212) (xy 423.454451 -279.775212) (xy 423.446694 -279.822942) (xy 423.43111 -279.869623)
			(xy 423.408239 -279.9132) (xy 423.378674 -279.952544) (xy 423.343181 -279.986636) (xy 423.302678 -280.014592)
			(xy 423.258216 -280.03569) (xy 423.210945 -280.049382) (xy 423.16209 -280.055314) (xy 423.112915 -280.053333)
			(xy 423.064696 -280.043489) (xy 423.01868 -280.026037) (xy 422.976059 -280.00143) (xy 422.937938 -279.970305)
			(xy 422.905303 -279.933468) (xy 422.879 -279.891872) (xy 422.859709 -279.846596) (xy 422.847932 -279.798812)
			(xy 422.843972 -279.749758) (xy 422.526963 -279.749758) (xy 422.526464 -279.775212) (xy 422.518421 -279.825994)
			(xy 422.502533 -279.874893) (xy 422.47919 -279.920705) (xy 422.448969 -279.962301) (xy 422.412613 -279.998657)
			(xy 422.371017 -280.028878) (xy 422.325205 -280.052221) (xy 422.276306 -280.068109) (xy 422.225524 -280.076152)
			(xy 422.174108 -280.076152) (xy 422.123326 -280.068109) (xy 422.074427 -280.052221) (xy 422.028615 -280.028878)
			(xy 421.987019 -279.998657) (xy 421.950663 -279.962301) (xy 421.920442 -279.920705) (xy 421.897099 -279.874893)
			(xy 421.881211 -279.825994) (xy 421.873168 -279.775212) (xy 421.554531 -279.775212) (xy 421.546774 -279.822942)
			(xy 421.53119 -279.869623) (xy 421.508319 -279.9132) (xy 421.478754 -279.952544) (xy 421.443261 -279.986636)
			(xy 421.402758 -280.014592) (xy 421.358296 -280.03569) (xy 421.311025 -280.049382) (xy 421.26217 -280.055314)
			(xy 421.212995 -280.053333) (xy 421.164776 -280.043489) (xy 421.11876 -280.026037) (xy 421.076139 -280.00143)
			(xy 421.038018 -279.970305) (xy 421.005383 -279.933468) (xy 420.97908 -279.891872) (xy 420.959789 -279.846596)
			(xy 420.948012 -279.798812) (xy 420.944052 -279.749758) (xy 420.627043 -279.749758) (xy 420.626544 -279.775212)
			(xy 420.618501 -279.825994) (xy 420.602613 -279.874893) (xy 420.57927 -279.920705) (xy 420.549049 -279.962301)
			(xy 420.512693 -279.998657) (xy 420.471097 -280.028878) (xy 420.425285 -280.052221) (xy 420.376386 -280.068109)
			(xy 420.325604 -280.076152) (xy 420.274188 -280.076152) (xy 420.223406 -280.068109) (xy 420.174507 -280.052221)
			(xy 420.128695 -280.028878) (xy 420.087099 -279.998657) (xy 420.050743 -279.962301) (xy 420.020522 -279.920705)
			(xy 419.997179 -279.874893) (xy 419.981291 -279.825994) (xy 419.973248 -279.775212) (xy 419.654611 -279.775212)
			(xy 419.646854 -279.822942) (xy 419.63127 -279.869623) (xy 419.608399 -279.9132) (xy 419.578834 -279.952544)
			(xy 419.543341 -279.986636) (xy 419.502838 -280.014592) (xy 419.458376 -280.03569) (xy 419.411105 -280.049382)
			(xy 419.36225 -280.055314) (xy 419.313075 -280.053333) (xy 419.264856 -280.043489) (xy 419.21884 -280.026037)
			(xy 419.176219 -280.00143) (xy 419.138098 -279.970305) (xy 419.105463 -279.933468) (xy 419.07916 -279.891872)
			(xy 419.059869 -279.846596) (xy 419.048092 -279.798812) (xy 419.044132 -279.749758) (xy 418.727123 -279.749758)
			(xy 418.726624 -279.775212) (xy 418.718581 -279.825994) (xy 418.702693 -279.874893) (xy 418.67935 -279.920705)
			(xy 418.649129 -279.962301) (xy 418.612773 -279.998657) (xy 418.571177 -280.028878) (xy 418.525365 -280.052221)
			(xy 418.476466 -280.068109) (xy 418.425684 -280.076152) (xy 418.374268 -280.076152) (xy 418.323486 -280.068109)
			(xy 418.274587 -280.052221) (xy 418.228775 -280.028878) (xy 418.187179 -279.998657) (xy 418.150823 -279.962301)
			(xy 418.120602 -279.920705) (xy 418.097259 -279.874893) (xy 418.081371 -279.825994) (xy 418.073328 -279.775212)
			(xy 417.754691 -279.775212) (xy 417.746934 -279.822942) (xy 417.73135 -279.869623) (xy 417.708479 -279.9132)
			(xy 417.678914 -279.952544) (xy 417.643421 -279.986636) (xy 417.602918 -280.014592) (xy 417.558456 -280.03569)
			(xy 417.511185 -280.049382) (xy 417.46233 -280.055314) (xy 417.413155 -280.053333) (xy 417.364936 -280.043489)
			(xy 417.31892 -280.026037) (xy 417.276299 -280.00143) (xy 417.238178 -279.970305) (xy 417.205543 -279.933468)
			(xy 417.17924 -279.891872) (xy 417.159949 -279.846596) (xy 417.148172 -279.798812) (xy 417.144212 -279.749758)
			(xy 416.826949 -279.749758) (xy 416.82645 -279.775212) (xy 416.818407 -279.825994) (xy 416.802519 -279.874893)
			(xy 416.779176 -279.920705) (xy 416.748955 -279.962301) (xy 416.712599 -279.998657) (xy 416.671003 -280.028878)
			(xy 416.625191 -280.052221) (xy 416.576292 -280.068109) (xy 416.52551 -280.076152) (xy 416.474094 -280.076152)
			(xy 416.423312 -280.068109) (xy 416.374413 -280.052221) (xy 416.328601 -280.028878) (xy 416.287005 -279.998657)
			(xy 416.250649 -279.962301) (xy 416.220428 -279.920705) (xy 416.197085 -279.874893) (xy 416.181197 -279.825994)
			(xy 416.173154 -279.775212) (xy 415.854517 -279.775212) (xy 415.84676 -279.822942) (xy 415.831176 -279.869623)
			(xy 415.808305 -279.9132) (xy 415.77874 -279.952544) (xy 415.743247 -279.986636) (xy 415.702744 -280.014592)
			(xy 415.658282 -280.03569) (xy 415.611011 -280.049382) (xy 415.562156 -280.055314) (xy 415.512981 -280.053333)
			(xy 415.464762 -280.043489) (xy 415.418746 -280.026037) (xy 415.376125 -280.00143) (xy 415.338004 -279.970305)
			(xy 415.305369 -279.933468) (xy 415.279066 -279.891872) (xy 415.259775 -279.846596) (xy 415.247998 -279.798812)
			(xy 415.244038 -279.749758) (xy 414.927029 -279.749758) (xy 414.92653 -279.775212) (xy 414.918487 -279.825994)
			(xy 414.902599 -279.874893) (xy 414.879256 -279.920705) (xy 414.849035 -279.962301) (xy 414.812679 -279.998657)
			(xy 414.771083 -280.028878) (xy 414.725271 -280.052221) (xy 414.676372 -280.068109) (xy 414.62559 -280.076152)
			(xy 414.574174 -280.076152) (xy 414.523392 -280.068109) (xy 414.474493 -280.052221) (xy 414.428681 -280.028878)
			(xy 414.387085 -279.998657) (xy 414.350729 -279.962301) (xy 414.320508 -279.920705) (xy 414.297165 -279.874893)
			(xy 414.281277 -279.825994) (xy 414.273234 -279.775212) (xy 413.954597 -279.775212) (xy 413.94684 -279.822942)
			(xy 413.931256 -279.869623) (xy 413.908385 -279.9132) (xy 413.87882 -279.952544) (xy 413.843327 -279.986636)
			(xy 413.802824 -280.014592) (xy 413.758362 -280.03569) (xy 413.711091 -280.049382) (xy 413.662236 -280.055314)
			(xy 413.613061 -280.053333) (xy 413.564842 -280.043489) (xy 413.518826 -280.026037) (xy 413.476205 -280.00143)
			(xy 413.438084 -279.970305) (xy 413.405449 -279.933468) (xy 413.379146 -279.891872) (xy 413.359855 -279.846596)
			(xy 413.348078 -279.798812) (xy 413.344118 -279.749758) (xy 413.027109 -279.749758) (xy 413.02661 -279.775212)
			(xy 413.018567 -279.825994) (xy 413.002679 -279.874893) (xy 412.979336 -279.920705) (xy 412.949115 -279.962301)
			(xy 412.912759 -279.998657) (xy 412.871163 -280.028878) (xy 412.825351 -280.052221) (xy 412.776452 -280.068109)
			(xy 412.72567 -280.076152) (xy 412.674254 -280.076152) (xy 412.623472 -280.068109) (xy 412.574573 -280.052221)
			(xy 412.528761 -280.028878) (xy 412.487165 -279.998657) (xy 412.450809 -279.962301) (xy 412.420588 -279.920705)
			(xy 412.397245 -279.874893) (xy 412.381357 -279.825994) (xy 412.373314 -279.775212) (xy 412.054677 -279.775212)
			(xy 412.04692 -279.822942) (xy 412.031336 -279.869623) (xy 412.008465 -279.9132) (xy 411.9789 -279.952544)
			(xy 411.943407 -279.986636) (xy 411.902904 -280.014592) (xy 411.858442 -280.03569) (xy 411.811171 -280.049382)
			(xy 411.762316 -280.055314) (xy 411.713141 -280.053333) (xy 411.664922 -280.043489) (xy 411.618906 -280.026037)
			(xy 411.576285 -280.00143) (xy 411.538164 -279.970305) (xy 411.505529 -279.933468) (xy 411.479226 -279.891872)
			(xy 411.459935 -279.846596) (xy 411.448158 -279.798812) (xy 411.444198 -279.749758) (xy 411.126935 -279.749758)
			(xy 411.126436 -279.775212) (xy 411.118393 -279.825994) (xy 411.102505 -279.874893) (xy 411.079162 -279.920705)
			(xy 411.048941 -279.962301) (xy 411.012585 -279.998657) (xy 410.970989 -280.028878) (xy 410.925177 -280.052221)
			(xy 410.876278 -280.068109) (xy 410.825496 -280.076152) (xy 410.77408 -280.076152) (xy 410.723298 -280.068109)
			(xy 410.674399 -280.052221) (xy 410.628587 -280.028878) (xy 410.586991 -279.998657) (xy 410.550635 -279.962301)
			(xy 410.520414 -279.920705) (xy 410.497071 -279.874893) (xy 410.481183 -279.825994) (xy 410.47314 -279.775212)
			(xy 410.154503 -279.775212) (xy 410.146746 -279.822942) (xy 410.131162 -279.869623) (xy 410.108291 -279.9132)
			(xy 410.078726 -279.952544) (xy 410.043233 -279.986636) (xy 410.00273 -280.014592) (xy 409.958268 -280.03569)
			(xy 409.910997 -280.049382) (xy 409.862142 -280.055314) (xy 409.812967 -280.053333) (xy 409.764748 -280.043489)
			(xy 409.718732 -280.026037) (xy 409.676111 -280.00143) (xy 409.63799 -279.970305) (xy 409.605355 -279.933468)
			(xy 409.579052 -279.891872) (xy 409.559761 -279.846596) (xy 409.547984 -279.798812) (xy 409.544024 -279.749758)
			(xy 409.227015 -279.749758) (xy 409.226516 -279.775212) (xy 409.218473 -279.825994) (xy 409.202585 -279.874893)
			(xy 409.179242 -279.920705) (xy 409.149021 -279.962301) (xy 409.112665 -279.998657) (xy 409.071069 -280.028878)
			(xy 409.025257 -280.052221) (xy 408.976358 -280.068109) (xy 408.925576 -280.076152) (xy 408.87416 -280.076152)
			(xy 408.823378 -280.068109) (xy 408.774479 -280.052221) (xy 408.728667 -280.028878) (xy 408.687071 -279.998657)
			(xy 408.650715 -279.962301) (xy 408.620494 -279.920705) (xy 408.597151 -279.874893) (xy 408.581263 -279.825994)
			(xy 408.57322 -279.775212) (xy 408.254583 -279.775212) (xy 408.246826 -279.822942) (xy 408.231242 -279.869623)
			(xy 408.208371 -279.9132) (xy 408.178806 -279.952544) (xy 408.143313 -279.986636) (xy 408.10281 -280.014592)
			(xy 408.058348 -280.03569) (xy 408.011077 -280.049382) (xy 407.962222 -280.055314) (xy 407.913047 -280.053333)
			(xy 407.864828 -280.043489) (xy 407.818812 -280.026037) (xy 407.776191 -280.00143) (xy 407.73807 -279.970305)
			(xy 407.705435 -279.933468) (xy 407.679132 -279.891872) (xy 407.659841 -279.846596) (xy 407.648064 -279.798812)
			(xy 407.644104 -279.749758) (xy 407.327095 -279.749758) (xy 407.326596 -279.775212) (xy 407.318553 -279.825994)
			(xy 407.302665 -279.874893) (xy 407.279322 -279.920705) (xy 407.249101 -279.962301) (xy 407.212745 -279.998657)
			(xy 407.171149 -280.028878) (xy 407.125337 -280.052221) (xy 407.076438 -280.068109) (xy 407.025656 -280.076152)
			(xy 406.97424 -280.076152) (xy 406.923458 -280.068109) (xy 406.874559 -280.052221) (xy 406.828747 -280.028878)
			(xy 406.787151 -279.998657) (xy 406.750795 -279.962301) (xy 406.720574 -279.920705) (xy 406.697231 -279.874893)
			(xy 406.681343 -279.825994) (xy 406.6733 -279.775212) (xy 406.354663 -279.775212) (xy 406.346906 -279.822942)
			(xy 406.331322 -279.869623) (xy 406.308451 -279.9132) (xy 406.278886 -279.952544) (xy 406.243393 -279.986636)
			(xy 406.20289 -280.014592) (xy 406.158428 -280.03569) (xy 406.111157 -280.049382) (xy 406.062302 -280.055314)
			(xy 406.013127 -280.053333) (xy 405.964908 -280.043489) (xy 405.918892 -280.026037) (xy 405.876271 -280.00143)
			(xy 405.83815 -279.970305) (xy 405.805515 -279.933468) (xy 405.779212 -279.891872) (xy 405.759921 -279.846596)
			(xy 405.748144 -279.798812) (xy 405.744184 -279.749758) (xy 405.426921 -279.749758) (xy 405.426422 -279.775212)
			(xy 405.418379 -279.825994) (xy 405.402491 -279.874893) (xy 405.379148 -279.920705) (xy 405.348927 -279.962301)
			(xy 405.312571 -279.998657) (xy 405.270975 -280.028878) (xy 405.225163 -280.052221) (xy 405.176264 -280.068109)
			(xy 405.125482 -280.076152) (xy 405.074066 -280.076152) (xy 405.023284 -280.068109) (xy 404.974385 -280.052221)
			(xy 404.928573 -280.028878) (xy 404.886977 -279.998657) (xy 404.850621 -279.962301) (xy 404.8204 -279.920705)
			(xy 404.797057 -279.874893) (xy 404.781169 -279.825994) (xy 404.773126 -279.775212) (xy 404.454489 -279.775212)
			(xy 404.446732 -279.822942) (xy 404.431148 -279.869623) (xy 404.408277 -279.9132) (xy 404.378712 -279.952544)
			(xy 404.343219 -279.986636) (xy 404.302716 -280.014592) (xy 404.258254 -280.03569) (xy 404.210983 -280.049382)
			(xy 404.162128 -280.055314) (xy 404.112953 -280.053333) (xy 404.064734 -280.043489) (xy 404.018718 -280.026037)
			(xy 403.976097 -280.00143) (xy 403.937976 -279.970305) (xy 403.905341 -279.933468) (xy 403.879038 -279.891872)
			(xy 403.859747 -279.846596) (xy 403.84797 -279.798812) (xy 403.84401 -279.749758) (xy 403.527001 -279.749758)
			(xy 403.526502 -279.775212) (xy 403.518459 -279.825994) (xy 403.502571 -279.874893) (xy 403.479228 -279.920705)
			(xy 403.449007 -279.962301) (xy 403.412651 -279.998657) (xy 403.371055 -280.028878) (xy 403.325243 -280.052221)
			(xy 403.276344 -280.068109) (xy 403.225562 -280.076152) (xy 403.174146 -280.076152) (xy 403.123364 -280.068109)
			(xy 403.074465 -280.052221) (xy 403.028653 -280.028878) (xy 402.987057 -279.998657) (xy 402.950701 -279.962301)
			(xy 402.92048 -279.920705) (xy 402.897137 -279.874893) (xy 402.881249 -279.825994) (xy 402.873206 -279.775212)
			(xy 402.554569 -279.775212) (xy 402.546812 -279.822942) (xy 402.531228 -279.869623) (xy 402.508357 -279.9132)
			(xy 402.478792 -279.952544) (xy 402.443299 -279.986636) (xy 402.402796 -280.014592) (xy 402.358334 -280.03569)
			(xy 402.311063 -280.049382) (xy 402.262208 -280.055314) (xy 402.213033 -280.053333) (xy 402.164814 -280.043489)
			(xy 402.118798 -280.026037) (xy 402.076177 -280.00143) (xy 402.038056 -279.970305) (xy 402.005421 -279.933468)
			(xy 401.979118 -279.891872) (xy 401.959827 -279.846596) (xy 401.94805 -279.798812) (xy 401.94409 -279.749758)
			(xy 401.627081 -279.749758) (xy 401.626582 -279.775212) (xy 401.618539 -279.825994) (xy 401.602651 -279.874893)
			(xy 401.579308 -279.920705) (xy 401.549087 -279.962301) (xy 401.512731 -279.998657) (xy 401.471135 -280.028878)
			(xy 401.425323 -280.052221) (xy 401.376424 -280.068109) (xy 401.325642 -280.076152) (xy 401.274226 -280.076152)
			(xy 401.223444 -280.068109) (xy 401.174545 -280.052221) (xy 401.128733 -280.028878) (xy 401.087137 -279.998657)
			(xy 401.050781 -279.962301) (xy 401.02056 -279.920705) (xy 400.997217 -279.874893) (xy 400.981329 -279.825994)
			(xy 400.973286 -279.775212) (xy 400.654649 -279.775212) (xy 400.646892 -279.822942) (xy 400.631308 -279.869623)
			(xy 400.608437 -279.9132) (xy 400.578872 -279.952544) (xy 400.543379 -279.986636) (xy 400.502876 -280.014592)
			(xy 400.458414 -280.03569) (xy 400.411143 -280.049382) (xy 400.362288 -280.055314) (xy 400.313113 -280.053333)
			(xy 400.264894 -280.043489) (xy 400.218878 -280.026037) (xy 400.176257 -280.00143) (xy 400.138136 -279.970305)
			(xy 400.105501 -279.933468) (xy 400.079198 -279.891872) (xy 400.059907 -279.846596) (xy 400.04813 -279.798812)
			(xy 400.04417 -279.749758) (xy 399.727161 -279.749758) (xy 399.726662 -279.775212) (xy 399.718619 -279.825994)
			(xy 399.702731 -279.874893) (xy 399.679388 -279.920705) (xy 399.649167 -279.962301) (xy 399.612811 -279.998657)
			(xy 399.571215 -280.028878) (xy 399.525403 -280.052221) (xy 399.476504 -280.068109) (xy 399.425722 -280.076152)
			(xy 399.374306 -280.076152) (xy 399.323524 -280.068109) (xy 399.274625 -280.052221) (xy 399.228813 -280.028878)
			(xy 399.187217 -279.998657) (xy 399.150861 -279.962301) (xy 399.12064 -279.920705) (xy 399.097297 -279.874893)
			(xy 399.081409 -279.825994) (xy 399.073366 -279.775212) (xy 398.753567 -279.775212) (xy 398.751501 -279.800145)
			(xy 398.7391 -279.849117) (xy 398.718807 -279.895379) (xy 398.691177 -279.937671) (xy 398.656962 -279.974838)
			(xy 398.617097 -280.005867) (xy 398.572668 -280.02991) (xy 398.524887 -280.046313) (xy 398.475059 -280.054628)
			(xy 398.4498 -280.055066) (xy 398.435618 -280.05488) (xy 398.407378 -280.052207) (xy 398.393412 -280.049732)
			(xy 398.380966 -280.047446) (xy 398.357344 -280.054812) (xy 398.279874 -280.132282) (xy 398.272508 -280.155904)
			(xy 398.274794 -280.16835) (xy 398.277277 -280.182315) (xy 398.279946 -280.210555) (xy 398.280128 -280.224738)
			(xy 398.279944 -280.238921) (xy 398.277277 -280.267161) (xy 398.274794 -280.281126) (xy 398.272508 -280.293572)
			(xy 398.279874 -280.317194) (xy 398.357344 -280.394664) (xy 398.380966 -280.40203) (xy 398.393412 -280.399744)
			(xy 398.407377 -280.397259) (xy 398.435617 -280.394586) (xy 398.4498 -280.39441) (xy 398.475054 -280.394932)
			(xy 398.524873 -280.403245) (xy 398.572644 -280.419645) (xy 398.617064 -280.443684) (xy 398.656922 -280.474706)
			(xy 398.691129 -280.511866) (xy 398.718755 -280.554149) (xy 398.739043 -280.600403) (xy 398.751442 -280.649365)
			(xy 398.755613 -280.6997) (xy 398.753481 -280.725426) (xy 399.073366 -280.725426) (xy 399.073366 -280.67401)
			(xy 399.081409 -280.623228) (xy 399.097297 -280.574329) (xy 399.12064 -280.528517) (xy 399.150861 -280.486921)
			(xy 399.187217 -280.450565) (xy 399.228813 -280.420344) (xy 399.274625 -280.397001) (xy 399.323524 -280.381113)
			(xy 399.374306 -280.37307) (xy 399.425722 -280.37307) (xy 399.476504 -280.381113) (xy 399.525403 -280.397001)
			(xy 399.571215 -280.420344) (xy 399.612811 -280.450565) (xy 399.649167 -280.486921) (xy 399.679388 -280.528517)
			(xy 399.702731 -280.574329) (xy 399.718619 -280.623228) (xy 399.726662 -280.67401) (xy 399.727166 -280.699718)
			(xy 400.04417 -280.699718) (xy 400.04813 -280.650664) (xy 400.059907 -280.60288) (xy 400.079198 -280.557604)
			(xy 400.105501 -280.516008) (xy 400.138136 -280.479171) (xy 400.176257 -280.448046) (xy 400.218878 -280.423439)
			(xy 400.264894 -280.405987) (xy 400.313113 -280.396143) (xy 400.362288 -280.394162) (xy 400.411143 -280.400094)
			(xy 400.458414 -280.413786) (xy 400.502876 -280.434884) (xy 400.543379 -280.46284) (xy 400.578872 -280.496932)
			(xy 400.608437 -280.536276) (xy 400.631308 -280.579853) (xy 400.646892 -280.626534) (xy 400.654787 -280.675111)
			(xy 400.655282 -280.699718) (xy 400.654787 -280.724325) (xy 400.654608 -280.725426) (xy 400.973286 -280.725426)
			(xy 400.973286 -280.67401) (xy 400.981329 -280.623228) (xy 400.997217 -280.574329) (xy 401.02056 -280.528517)
			(xy 401.050781 -280.486921) (xy 401.087137 -280.450565) (xy 401.128733 -280.420344) (xy 401.174545 -280.397001)
			(xy 401.223444 -280.381113) (xy 401.274226 -280.37307) (xy 401.325642 -280.37307) (xy 401.376424 -280.381113)
			(xy 401.425323 -280.397001) (xy 401.471135 -280.420344) (xy 401.512731 -280.450565) (xy 401.549087 -280.486921)
			(xy 401.579308 -280.528517) (xy 401.602651 -280.574329) (xy 401.618539 -280.623228) (xy 401.626582 -280.67401)
			(xy 401.627086 -280.699718) (xy 401.94409 -280.699718) (xy 401.94805 -280.650664) (xy 401.959827 -280.60288)
			(xy 401.979118 -280.557604) (xy 402.005421 -280.516008) (xy 402.038056 -280.479171) (xy 402.076177 -280.448046)
			(xy 402.118798 -280.423439) (xy 402.164814 -280.405987) (xy 402.213033 -280.396143) (xy 402.262208 -280.394162)
			(xy 402.311063 -280.400094) (xy 402.358334 -280.413786) (xy 402.402796 -280.434884) (xy 402.443299 -280.46284)
			(xy 402.478792 -280.496932) (xy 402.508357 -280.536276) (xy 402.531228 -280.579853) (xy 402.546812 -280.626534)
			(xy 402.554707 -280.675111) (xy 402.555202 -280.699718) (xy 402.554707 -280.724325) (xy 402.554528 -280.725426)
			(xy 402.873206 -280.725426) (xy 402.873206 -280.67401) (xy 402.881249 -280.623228) (xy 402.897137 -280.574329)
			(xy 402.92048 -280.528517) (xy 402.950701 -280.486921) (xy 402.987057 -280.450565) (xy 403.028653 -280.420344)
			(xy 403.074465 -280.397001) (xy 403.123364 -280.381113) (xy 403.174146 -280.37307) (xy 403.225562 -280.37307)
			(xy 403.276344 -280.381113) (xy 403.325243 -280.397001) (xy 403.371055 -280.420344) (xy 403.412651 -280.450565)
			(xy 403.449007 -280.486921) (xy 403.479228 -280.528517) (xy 403.502571 -280.574329) (xy 403.518459 -280.623228)
			(xy 403.526502 -280.67401) (xy 403.527006 -280.699718) (xy 403.84401 -280.699718) (xy 403.84797 -280.650664)
			(xy 403.859747 -280.60288) (xy 403.879038 -280.557604) (xy 403.905341 -280.516008) (xy 403.937976 -280.479171)
			(xy 403.976097 -280.448046) (xy 404.018718 -280.423439) (xy 404.064734 -280.405987) (xy 404.112953 -280.396143)
			(xy 404.162128 -280.394162) (xy 404.210983 -280.400094) (xy 404.258254 -280.413786) (xy 404.302716 -280.434884)
			(xy 404.343219 -280.46284) (xy 404.378712 -280.496932) (xy 404.408277 -280.536276) (xy 404.431148 -280.579853)
			(xy 404.446732 -280.626534) (xy 404.454627 -280.675111) (xy 404.455122 -280.699718) (xy 404.454627 -280.724325)
			(xy 404.454448 -280.725426) (xy 404.773126 -280.725426) (xy 404.773126 -280.67401) (xy 404.781169 -280.623228)
			(xy 404.797057 -280.574329) (xy 404.8204 -280.528517) (xy 404.850621 -280.486921) (xy 404.886977 -280.450565)
			(xy 404.928573 -280.420344) (xy 404.974385 -280.397001) (xy 405.023284 -280.381113) (xy 405.074066 -280.37307)
			(xy 405.125482 -280.37307) (xy 405.176264 -280.381113) (xy 405.225163 -280.397001) (xy 405.270975 -280.420344)
			(xy 405.312571 -280.450565) (xy 405.348927 -280.486921) (xy 405.379148 -280.528517) (xy 405.402491 -280.574329)
			(xy 405.418379 -280.623228) (xy 405.426422 -280.67401) (xy 405.426926 -280.699718) (xy 405.744184 -280.699718)
			(xy 405.748144 -280.650664) (xy 405.759921 -280.60288) (xy 405.779212 -280.557604) (xy 405.805515 -280.516008)
			(xy 405.83815 -280.479171) (xy 405.876271 -280.448046) (xy 405.918892 -280.423439) (xy 405.964908 -280.405987)
			(xy 406.013127 -280.396143) (xy 406.062302 -280.394162) (xy 406.111157 -280.400094) (xy 406.158428 -280.413786)
			(xy 406.20289 -280.434884) (xy 406.243393 -280.46284) (xy 406.278886 -280.496932) (xy 406.308451 -280.536276)
			(xy 406.331322 -280.579853) (xy 406.346906 -280.626534) (xy 406.354801 -280.675111) (xy 406.355296 -280.699718)
			(xy 406.354801 -280.724325) (xy 406.354622 -280.725426) (xy 406.6733 -280.725426) (xy 406.6733 -280.67401)
			(xy 406.681343 -280.623228) (xy 406.697231 -280.574329) (xy 406.720574 -280.528517) (xy 406.750795 -280.486921)
			(xy 406.787151 -280.450565) (xy 406.828747 -280.420344) (xy 406.874559 -280.397001) (xy 406.923458 -280.381113)
			(xy 406.97424 -280.37307) (xy 407.025656 -280.37307) (xy 407.076438 -280.381113) (xy 407.125337 -280.397001)
			(xy 407.171149 -280.420344) (xy 407.212745 -280.450565) (xy 407.249101 -280.486921) (xy 407.279322 -280.528517)
			(xy 407.302665 -280.574329) (xy 407.318553 -280.623228) (xy 407.326596 -280.67401) (xy 407.3271 -280.699718)
			(xy 407.644104 -280.699718) (xy 407.648064 -280.650664) (xy 407.659841 -280.60288) (xy 407.679132 -280.557604)
			(xy 407.705435 -280.516008) (xy 407.73807 -280.479171) (xy 407.776191 -280.448046) (xy 407.818812 -280.423439)
			(xy 407.864828 -280.405987) (xy 407.913047 -280.396143) (xy 407.962222 -280.394162) (xy 408.011077 -280.400094)
			(xy 408.058348 -280.413786) (xy 408.10281 -280.434884) (xy 408.143313 -280.46284) (xy 408.178806 -280.496932)
			(xy 408.208371 -280.536276) (xy 408.231242 -280.579853) (xy 408.246826 -280.626534) (xy 408.254721 -280.675111)
			(xy 408.255216 -280.699718) (xy 408.254721 -280.724325) (xy 408.254542 -280.725426) (xy 408.57322 -280.725426)
			(xy 408.57322 -280.67401) (xy 408.581263 -280.623228) (xy 408.597151 -280.574329) (xy 408.620494 -280.528517)
			(xy 408.650715 -280.486921) (xy 408.687071 -280.450565) (xy 408.728667 -280.420344) (xy 408.774479 -280.397001)
			(xy 408.823378 -280.381113) (xy 408.87416 -280.37307) (xy 408.925576 -280.37307) (xy 408.976358 -280.381113)
			(xy 409.025257 -280.397001) (xy 409.071069 -280.420344) (xy 409.112665 -280.450565) (xy 409.149021 -280.486921)
			(xy 409.179242 -280.528517) (xy 409.202585 -280.574329) (xy 409.218473 -280.623228) (xy 409.226516 -280.67401)
			(xy 409.22702 -280.699718) (xy 409.544024 -280.699718) (xy 409.547984 -280.650664) (xy 409.559761 -280.60288)
			(xy 409.579052 -280.557604) (xy 409.605355 -280.516008) (xy 409.63799 -280.479171) (xy 409.676111 -280.448046)
			(xy 409.718732 -280.423439) (xy 409.764748 -280.405987) (xy 409.812967 -280.396143) (xy 409.862142 -280.394162)
			(xy 409.910997 -280.400094) (xy 409.958268 -280.413786) (xy 410.00273 -280.434884) (xy 410.043233 -280.46284)
			(xy 410.078726 -280.496932) (xy 410.108291 -280.536276) (xy 410.131162 -280.579853) (xy 410.146746 -280.626534)
			(xy 410.154641 -280.675111) (xy 410.155136 -280.699718) (xy 410.154641 -280.724325) (xy 410.154462 -280.725426)
			(xy 410.47314 -280.725426) (xy 410.47314 -280.67401) (xy 410.481183 -280.623228) (xy 410.497071 -280.574329)
			(xy 410.520414 -280.528517) (xy 410.550635 -280.486921) (xy 410.586991 -280.450565) (xy 410.628587 -280.420344)
			(xy 410.674399 -280.397001) (xy 410.723298 -280.381113) (xy 410.77408 -280.37307) (xy 410.825496 -280.37307)
			(xy 410.876278 -280.381113) (xy 410.925177 -280.397001) (xy 410.970989 -280.420344) (xy 411.012585 -280.450565)
			(xy 411.048941 -280.486921) (xy 411.079162 -280.528517) (xy 411.102505 -280.574329) (xy 411.118393 -280.623228)
			(xy 411.126436 -280.67401) (xy 411.12694 -280.699718) (xy 411.444198 -280.699718) (xy 411.448158 -280.650664)
			(xy 411.459935 -280.60288) (xy 411.479226 -280.557604) (xy 411.505529 -280.516008) (xy 411.538164 -280.479171)
			(xy 411.576285 -280.448046) (xy 411.618906 -280.423439) (xy 411.664922 -280.405987) (xy 411.713141 -280.396143)
			(xy 411.762316 -280.394162) (xy 411.811171 -280.400094) (xy 411.858442 -280.413786) (xy 411.902904 -280.434884)
			(xy 411.943407 -280.46284) (xy 411.9789 -280.496932) (xy 412.008465 -280.536276) (xy 412.031336 -280.579853)
			(xy 412.04692 -280.626534) (xy 412.054815 -280.675111) (xy 412.05531 -280.699718) (xy 412.054815 -280.724325)
			(xy 412.054636 -280.725426) (xy 412.373314 -280.725426) (xy 412.373314 -280.67401) (xy 412.381357 -280.623228)
			(xy 412.397245 -280.574329) (xy 412.420588 -280.528517) (xy 412.450809 -280.486921) (xy 412.487165 -280.450565)
			(xy 412.528761 -280.420344) (xy 412.574573 -280.397001) (xy 412.623472 -280.381113) (xy 412.674254 -280.37307)
			(xy 412.72567 -280.37307) (xy 412.776452 -280.381113) (xy 412.825351 -280.397001) (xy 412.871163 -280.420344)
			(xy 412.912759 -280.450565) (xy 412.949115 -280.486921) (xy 412.979336 -280.528517) (xy 413.002679 -280.574329)
			(xy 413.018567 -280.623228) (xy 413.02661 -280.67401) (xy 413.027114 -280.699718) (xy 413.344118 -280.699718)
			(xy 413.348078 -280.650664) (xy 413.359855 -280.60288) (xy 413.379146 -280.557604) (xy 413.405449 -280.516008)
			(xy 413.438084 -280.479171) (xy 413.476205 -280.448046) (xy 413.518826 -280.423439) (xy 413.564842 -280.405987)
			(xy 413.613061 -280.396143) (xy 413.662236 -280.394162) (xy 413.711091 -280.400094) (xy 413.758362 -280.413786)
			(xy 413.802824 -280.434884) (xy 413.843327 -280.46284) (xy 413.87882 -280.496932) (xy 413.908385 -280.536276)
			(xy 413.931256 -280.579853) (xy 413.94684 -280.626534) (xy 413.954735 -280.675111) (xy 413.95523 -280.699718)
			(xy 413.954735 -280.724325) (xy 413.954556 -280.725426) (xy 414.273234 -280.725426) (xy 414.273234 -280.67401)
			(xy 414.281277 -280.623228) (xy 414.297165 -280.574329) (xy 414.320508 -280.528517) (xy 414.350729 -280.486921)
			(xy 414.387085 -280.450565) (xy 414.428681 -280.420344) (xy 414.474493 -280.397001) (xy 414.523392 -280.381113)
			(xy 414.574174 -280.37307) (xy 414.62559 -280.37307) (xy 414.676372 -280.381113) (xy 414.725271 -280.397001)
			(xy 414.771083 -280.420344) (xy 414.812679 -280.450565) (xy 414.849035 -280.486921) (xy 414.879256 -280.528517)
			(xy 414.902599 -280.574329) (xy 414.918487 -280.623228) (xy 414.92653 -280.67401) (xy 414.927034 -280.699718)
			(xy 415.244038 -280.699718) (xy 415.247998 -280.650664) (xy 415.259775 -280.60288) (xy 415.279066 -280.557604)
			(xy 415.305369 -280.516008) (xy 415.338004 -280.479171) (xy 415.376125 -280.448046) (xy 415.418746 -280.423439)
			(xy 415.464762 -280.405987) (xy 415.512981 -280.396143) (xy 415.562156 -280.394162) (xy 415.611011 -280.400094)
			(xy 415.658282 -280.413786) (xy 415.702744 -280.434884) (xy 415.743247 -280.46284) (xy 415.77874 -280.496932)
			(xy 415.808305 -280.536276) (xy 415.831176 -280.579853) (xy 415.84676 -280.626534) (xy 415.854655 -280.675111)
			(xy 415.85515 -280.699718) (xy 415.854655 -280.724325) (xy 415.854476 -280.725426) (xy 416.173154 -280.725426)
			(xy 416.173154 -280.67401) (xy 416.181197 -280.623228) (xy 416.197085 -280.574329) (xy 416.220428 -280.528517)
			(xy 416.250649 -280.486921) (xy 416.287005 -280.450565) (xy 416.328601 -280.420344) (xy 416.374413 -280.397001)
			(xy 416.423312 -280.381113) (xy 416.474094 -280.37307) (xy 416.52551 -280.37307) (xy 416.576292 -280.381113)
			(xy 416.625191 -280.397001) (xy 416.671003 -280.420344) (xy 416.712599 -280.450565) (xy 416.748955 -280.486921)
			(xy 416.779176 -280.528517) (xy 416.802519 -280.574329) (xy 416.818407 -280.623228) (xy 416.82645 -280.67401)
			(xy 416.826954 -280.699718) (xy 417.144212 -280.699718) (xy 417.148172 -280.650664) (xy 417.159949 -280.60288)
			(xy 417.17924 -280.557604) (xy 417.205543 -280.516008) (xy 417.238178 -280.479171) (xy 417.276299 -280.448046)
			(xy 417.31892 -280.423439) (xy 417.364936 -280.405987) (xy 417.413155 -280.396143) (xy 417.46233 -280.394162)
			(xy 417.511185 -280.400094) (xy 417.558456 -280.413786) (xy 417.602918 -280.434884) (xy 417.643421 -280.46284)
			(xy 417.678914 -280.496932) (xy 417.708479 -280.536276) (xy 417.73135 -280.579853) (xy 417.746934 -280.626534)
			(xy 417.754829 -280.675111) (xy 417.755324 -280.699718) (xy 417.754829 -280.724325) (xy 417.75465 -280.725426)
			(xy 418.073328 -280.725426) (xy 418.073328 -280.67401) (xy 418.081371 -280.623228) (xy 418.097259 -280.574329)
			(xy 418.120602 -280.528517) (xy 418.150823 -280.486921) (xy 418.187179 -280.450565) (xy 418.228775 -280.420344)
			(xy 418.274587 -280.397001) (xy 418.323486 -280.381113) (xy 418.374268 -280.37307) (xy 418.425684 -280.37307)
			(xy 418.476466 -280.381113) (xy 418.525365 -280.397001) (xy 418.571177 -280.420344) (xy 418.612773 -280.450565)
			(xy 418.649129 -280.486921) (xy 418.67935 -280.528517) (xy 418.702693 -280.574329) (xy 418.718581 -280.623228)
			(xy 418.726624 -280.67401) (xy 418.727128 -280.699718) (xy 419.044132 -280.699718) (xy 419.048092 -280.650664)
			(xy 419.059869 -280.60288) (xy 419.07916 -280.557604) (xy 419.105463 -280.516008) (xy 419.138098 -280.479171)
			(xy 419.176219 -280.448046) (xy 419.21884 -280.423439) (xy 419.264856 -280.405987) (xy 419.313075 -280.396143)
			(xy 419.36225 -280.394162) (xy 419.411105 -280.400094) (xy 419.458376 -280.413786) (xy 419.502838 -280.434884)
			(xy 419.543341 -280.46284) (xy 419.578834 -280.496932) (xy 419.608399 -280.536276) (xy 419.63127 -280.579853)
			(xy 419.646854 -280.626534) (xy 419.654749 -280.675111) (xy 419.655244 -280.699718) (xy 419.654749 -280.724325)
			(xy 419.65457 -280.725426) (xy 419.973248 -280.725426) (xy 419.973248 -280.67401) (xy 419.981291 -280.623228)
			(xy 419.997179 -280.574329) (xy 420.020522 -280.528517) (xy 420.050743 -280.486921) (xy 420.087099 -280.450565)
			(xy 420.128695 -280.420344) (xy 420.174507 -280.397001) (xy 420.223406 -280.381113) (xy 420.274188 -280.37307)
			(xy 420.325604 -280.37307) (xy 420.376386 -280.381113) (xy 420.425285 -280.397001) (xy 420.471097 -280.420344)
			(xy 420.512693 -280.450565) (xy 420.549049 -280.486921) (xy 420.57927 -280.528517) (xy 420.602613 -280.574329)
			(xy 420.618501 -280.623228) (xy 420.626544 -280.67401) (xy 420.627048 -280.699718) (xy 420.944052 -280.699718)
			(xy 420.948012 -280.650664) (xy 420.959789 -280.60288) (xy 420.97908 -280.557604) (xy 421.005383 -280.516008)
			(xy 421.038018 -280.479171) (xy 421.076139 -280.448046) (xy 421.11876 -280.423439) (xy 421.164776 -280.405987)
			(xy 421.212995 -280.396143) (xy 421.26217 -280.394162) (xy 421.311025 -280.400094) (xy 421.358296 -280.413786)
			(xy 421.402758 -280.434884) (xy 421.443261 -280.46284) (xy 421.478754 -280.496932) (xy 421.508319 -280.536276)
			(xy 421.53119 -280.579853) (xy 421.546774 -280.626534) (xy 421.554669 -280.675111) (xy 421.555164 -280.699718)
			(xy 421.554669 -280.724325) (xy 421.55449 -280.725426) (xy 421.873168 -280.725426) (xy 421.873168 -280.67401)
			(xy 421.881211 -280.623228) (xy 421.897099 -280.574329) (xy 421.920442 -280.528517) (xy 421.950663 -280.486921)
			(xy 421.987019 -280.450565) (xy 422.028615 -280.420344) (xy 422.074427 -280.397001) (xy 422.123326 -280.381113)
			(xy 422.174108 -280.37307) (xy 422.225524 -280.37307) (xy 422.276306 -280.381113) (xy 422.325205 -280.397001)
			(xy 422.371017 -280.420344) (xy 422.412613 -280.450565) (xy 422.448969 -280.486921) (xy 422.47919 -280.528517)
			(xy 422.502533 -280.574329) (xy 422.518421 -280.623228) (xy 422.526464 -280.67401) (xy 422.526968 -280.699718)
			(xy 422.844226 -280.699718) (xy 422.848186 -280.650664) (xy 422.859963 -280.60288) (xy 422.879254 -280.557604)
			(xy 422.905557 -280.516008) (xy 422.938192 -280.479171) (xy 422.976313 -280.448046) (xy 423.018934 -280.423439)
			(xy 423.06495 -280.405987) (xy 423.113169 -280.396143) (xy 423.162344 -280.394162) (xy 423.211199 -280.400094)
			(xy 423.25847 -280.413786) (xy 423.302932 -280.434884) (xy 423.343435 -280.46284) (xy 423.378928 -280.496932)
			(xy 423.408493 -280.536276) (xy 423.431364 -280.579853) (xy 423.446948 -280.626534) (xy 423.454843 -280.675111)
			(xy 423.455338 -280.699718) (xy 423.454843 -280.724325) (xy 423.454664 -280.725426) (xy 423.773342 -280.725426)
			(xy 423.773342 -280.67401) (xy 423.781385 -280.623228) (xy 423.797273 -280.574329) (xy 423.820616 -280.528517)
			(xy 423.850837 -280.486921) (xy 423.887193 -280.450565) (xy 423.928789 -280.420344) (xy 423.974601 -280.397001)
			(xy 424.0235 -280.381113) (xy 424.074282 -280.37307) (xy 424.125698 -280.37307) (xy 424.17648 -280.381113)
			(xy 424.225379 -280.397001) (xy 424.271191 -280.420344) (xy 424.312787 -280.450565) (xy 424.349143 -280.486921)
			(xy 424.379364 -280.528517) (xy 424.402707 -280.574329) (xy 424.418595 -280.623228) (xy 424.426638 -280.67401)
			(xy 424.427142 -280.699718) (xy 424.744146 -280.699718) (xy 424.748106 -280.650664) (xy 424.759883 -280.60288)
			(xy 424.779174 -280.557604) (xy 424.805477 -280.516008) (xy 424.838112 -280.479171) (xy 424.876233 -280.448046)
			(xy 424.918854 -280.423439) (xy 424.96487 -280.405987) (xy 425.013089 -280.396143) (xy 425.062264 -280.394162)
			(xy 425.111119 -280.400094) (xy 425.15839 -280.413786) (xy 425.202852 -280.434884) (xy 425.243355 -280.46284)
			(xy 425.278848 -280.496932) (xy 425.308413 -280.536276) (xy 425.331284 -280.579853) (xy 425.346868 -280.626534)
			(xy 425.354763 -280.675111) (xy 425.355258 -280.699718) (xy 425.354763 -280.724325) (xy 425.354584 -280.725426)
			(xy 425.673262 -280.725426) (xy 425.673262 -280.67401) (xy 425.681305 -280.623228) (xy 425.697193 -280.574329)
			(xy 425.720536 -280.528517) (xy 425.750757 -280.486921) (xy 425.787113 -280.450565) (xy 425.828709 -280.420344)
			(xy 425.874521 -280.397001) (xy 425.92342 -280.381113) (xy 425.974202 -280.37307) (xy 426.025618 -280.37307)
			(xy 426.0764 -280.381113) (xy 426.125299 -280.397001) (xy 426.171111 -280.420344) (xy 426.212707 -280.450565)
			(xy 426.249063 -280.486921) (xy 426.279284 -280.528517) (xy 426.302627 -280.574329) (xy 426.318515 -280.623228)
			(xy 426.326558 -280.67401) (xy 426.327062 -280.699718) (xy 426.644066 -280.699718) (xy 426.648026 -280.650664)
			(xy 426.659803 -280.60288) (xy 426.679094 -280.557604) (xy 426.705397 -280.516008) (xy 426.738032 -280.479171)
			(xy 426.776153 -280.448046) (xy 426.818774 -280.423439) (xy 426.86479 -280.405987) (xy 426.913009 -280.396143)
			(xy 426.962184 -280.394162) (xy 427.011039 -280.400094) (xy 427.05831 -280.413786) (xy 427.102772 -280.434884)
			(xy 427.143275 -280.46284) (xy 427.178768 -280.496932) (xy 427.208333 -280.536276) (xy 427.231204 -280.579853)
			(xy 427.246788 -280.626534) (xy 427.254683 -280.675111) (xy 427.255178 -280.699718) (xy 427.254683 -280.724325)
			(xy 427.254504 -280.725426) (xy 427.573182 -280.725426) (xy 427.573182 -280.67401) (xy 427.581225 -280.623228)
			(xy 427.597113 -280.574329) (xy 427.620456 -280.528517) (xy 427.650677 -280.486921) (xy 427.687033 -280.450565)
			(xy 427.728629 -280.420344) (xy 427.774441 -280.397001) (xy 427.82334 -280.381113) (xy 427.874122 -280.37307)
			(xy 427.925538 -280.37307) (xy 427.97632 -280.381113) (xy 428.025219 -280.397001) (xy 428.071031 -280.420344)
			(xy 428.112627 -280.450565) (xy 428.148983 -280.486921) (xy 428.179204 -280.528517) (xy 428.202547 -280.574329)
			(xy 428.218435 -280.623228) (xy 428.226478 -280.67401) (xy 428.226982 -280.699718) (xy 428.54424 -280.699718)
			(xy 428.5482 -280.650664) (xy 428.559977 -280.60288) (xy 428.579268 -280.557604) (xy 428.605571 -280.516008)
			(xy 428.638206 -280.479171) (xy 428.676327 -280.448046) (xy 428.718948 -280.423439) (xy 428.764964 -280.405987)
			(xy 428.813183 -280.396143) (xy 428.862358 -280.394162) (xy 428.911213 -280.400094) (xy 428.958484 -280.413786)
			(xy 429.002946 -280.434884) (xy 429.043449 -280.46284) (xy 429.078942 -280.496932) (xy 429.108507 -280.536276)
			(xy 429.131378 -280.579853) (xy 429.146962 -280.626534) (xy 429.154857 -280.675111) (xy 429.155352 -280.699718)
			(xy 429.4942 -280.699718) (xy 429.49816 -280.650664) (xy 429.509937 -280.60288) (xy 429.529228 -280.557604)
			(xy 429.555531 -280.516008) (xy 429.588166 -280.479171) (xy 429.626287 -280.448046) (xy 429.668908 -280.423439)
			(xy 429.714924 -280.405987) (xy 429.763143 -280.396143) (xy 429.812318 -280.394162) (xy 429.861173 -280.400094)
			(xy 429.908444 -280.413786) (xy 429.952906 -280.434884) (xy 429.993409 -280.46284) (xy 430.028902 -280.496932)
			(xy 430.058467 -280.536276) (xy 430.081338 -280.579853) (xy 430.096922 -280.626534) (xy 430.104817 -280.675111)
			(xy 430.105312 -280.699718) (xy 430.44416 -280.699718) (xy 430.44812 -280.650664) (xy 430.459897 -280.60288)
			(xy 430.479188 -280.557604) (xy 430.505491 -280.516008) (xy 430.538126 -280.479171) (xy 430.576247 -280.448046)
			(xy 430.618868 -280.423439) (xy 430.664884 -280.405987) (xy 430.713103 -280.396143) (xy 430.762278 -280.394162)
			(xy 430.811133 -280.400094) (xy 430.858404 -280.413786) (xy 430.902866 -280.434884) (xy 430.943369 -280.46284)
			(xy 430.978862 -280.496932) (xy 431.008427 -280.536276) (xy 431.031298 -280.579853) (xy 431.046045 -280.624026)
			(xy 459.436722 -280.624026) (xy 459.440793 -280.568404) (xy 459.452919 -280.513967) (xy 459.472842 -280.461876)
			(xy 459.500138 -280.413241) (xy 459.534224 -280.369098) (xy 459.574373 -280.330389) (xy 459.619731 -280.297938)
			(xy 459.669331 -280.272437) (xy 459.722115 -280.25443) (xy 459.776958 -280.2443) (xy 459.832692 -280.242263)
			(xy 459.888129 -280.248363) (xy 459.942086 -280.262469) (xy 459.993415 -280.284281) (xy 460.041021 -280.313335)
			(xy 460.083889 -280.34901) (xy 460.121106 -280.390547) (xy 460.151879 -280.43706) (xy 460.175551 -280.487557)
			(xy 460.191619 -280.540964) (xy 460.199739 -280.59614) (xy 460.200248 -280.624026) (xy 460.199739 -280.651912)
			(xy 460.191619 -280.707088) (xy 460.175551 -280.760495) (xy 460.151879 -280.810992) (xy 460.121106 -280.857505)
			(xy 460.083889 -280.899042) (xy 460.041021 -280.934717) (xy 459.993415 -280.963771) (xy 459.942086 -280.985583)
			(xy 459.888129 -280.999689) (xy 459.832692 -281.005789) (xy 459.776958 -281.003752) (xy 459.722115 -280.993622)
			(xy 459.669331 -280.975615) (xy 459.619731 -280.950114) (xy 459.574373 -280.917663) (xy 459.534224 -280.878954)
			(xy 459.500138 -280.834811) (xy 459.472842 -280.786176) (xy 459.452919 -280.734085) (xy 459.440793 -280.679648)
			(xy 459.436722 -280.624026) (xy 431.046045 -280.624026) (xy 431.046882 -280.626534) (xy 431.054777 -280.675111)
			(xy 431.055272 -280.699718) (xy 431.054777 -280.724325) (xy 431.046882 -280.772902) (xy 431.031298 -280.819583)
			(xy 431.008427 -280.86316) (xy 430.978862 -280.902504) (xy 430.943369 -280.936596) (xy 430.902866 -280.964552)
			(xy 430.858404 -280.98565) (xy 430.811133 -280.999342) (xy 430.762278 -281.005274) (xy 430.713103 -281.003293)
			(xy 430.664884 -280.993449) (xy 430.618868 -280.975997) (xy 430.576247 -280.95139) (xy 430.538126 -280.920265)
			(xy 430.505491 -280.883428) (xy 430.479188 -280.841832) (xy 430.459897 -280.796556) (xy 430.44812 -280.748772)
			(xy 430.44416 -280.699718) (xy 430.105312 -280.699718) (xy 430.104817 -280.724325) (xy 430.096922 -280.772902)
			(xy 430.081338 -280.819583) (xy 430.058467 -280.86316) (xy 430.028902 -280.902504) (xy 429.993409 -280.936596)
			(xy 429.952906 -280.964552) (xy 429.908444 -280.98565) (xy 429.861173 -280.999342) (xy 429.812318 -281.005274)
			(xy 429.763143 -281.003293) (xy 429.714924 -280.993449) (xy 429.668908 -280.975997) (xy 429.626287 -280.95139)
			(xy 429.588166 -280.920265) (xy 429.555531 -280.883428) (xy 429.529228 -280.841832) (xy 429.509937 -280.796556)
			(xy 429.49816 -280.748772) (xy 429.4942 -280.699718) (xy 429.155352 -280.699718) (xy 429.154857 -280.724325)
			(xy 429.146962 -280.772902) (xy 429.131378 -280.819583) (xy 429.108507 -280.86316) (xy 429.078942 -280.902504)
			(xy 429.043449 -280.936596) (xy 429.002946 -280.964552) (xy 428.958484 -280.98565) (xy 428.911213 -280.999342)
			(xy 428.862358 -281.005274) (xy 428.813183 -281.003293) (xy 428.764964 -280.993449) (xy 428.718948 -280.975997)
			(xy 428.676327 -280.95139) (xy 428.638206 -280.920265) (xy 428.605571 -280.883428) (xy 428.579268 -280.841832)
			(xy 428.559977 -280.796556) (xy 428.5482 -280.748772) (xy 428.54424 -280.699718) (xy 428.226982 -280.699718)
			(xy 428.226478 -280.725426) (xy 428.218435 -280.776208) (xy 428.202547 -280.825107) (xy 428.179204 -280.870919)
			(xy 428.148983 -280.912515) (xy 428.112627 -280.948871) (xy 428.071031 -280.979092) (xy 428.025219 -281.002435)
			(xy 427.97632 -281.018323) (xy 427.925538 -281.026366) (xy 427.874122 -281.026366) (xy 427.82334 -281.018323)
			(xy 427.774441 -281.002435) (xy 427.728629 -280.979092) (xy 427.687033 -280.948871) (xy 427.650677 -280.912515)
			(xy 427.620456 -280.870919) (xy 427.597113 -280.825107) (xy 427.581225 -280.776208) (xy 427.573182 -280.725426)
			(xy 427.254504 -280.725426) (xy 427.246788 -280.772902) (xy 427.231204 -280.819583) (xy 427.208333 -280.86316)
			(xy 427.178768 -280.902504) (xy 427.143275 -280.936596) (xy 427.102772 -280.964552) (xy 427.05831 -280.98565)
			(xy 427.011039 -280.999342) (xy 426.962184 -281.005274) (xy 426.913009 -281.003293) (xy 426.86479 -280.993449)
			(xy 426.818774 -280.975997) (xy 426.776153 -280.95139) (xy 426.738032 -280.920265) (xy 426.705397 -280.883428)
			(xy 426.679094 -280.841832) (xy 426.659803 -280.796556) (xy 426.648026 -280.748772) (xy 426.644066 -280.699718)
			(xy 426.327062 -280.699718) (xy 426.326558 -280.725426) (xy 426.318515 -280.776208) (xy 426.302627 -280.825107)
			(xy 426.279284 -280.870919) (xy 426.249063 -280.912515) (xy 426.212707 -280.948871) (xy 426.171111 -280.979092)
			(xy 426.125299 -281.002435) (xy 426.0764 -281.018323) (xy 426.025618 -281.026366) (xy 425.974202 -281.026366)
			(xy 425.92342 -281.018323) (xy 425.874521 -281.002435) (xy 425.828709 -280.979092) (xy 425.787113 -280.948871)
			(xy 425.750757 -280.912515) (xy 425.720536 -280.870919) (xy 425.697193 -280.825107) (xy 425.681305 -280.776208)
			(xy 425.673262 -280.725426) (xy 425.354584 -280.725426) (xy 425.346868 -280.772902) (xy 425.331284 -280.819583)
			(xy 425.308413 -280.86316) (xy 425.278848 -280.902504) (xy 425.243355 -280.936596) (xy 425.202852 -280.964552)
			(xy 425.15839 -280.98565) (xy 425.111119 -280.999342) (xy 425.062264 -281.005274) (xy 425.013089 -281.003293)
			(xy 424.96487 -280.993449) (xy 424.918854 -280.975997) (xy 424.876233 -280.95139) (xy 424.838112 -280.920265)
			(xy 424.805477 -280.883428) (xy 424.779174 -280.841832) (xy 424.759883 -280.796556) (xy 424.748106 -280.748772)
			(xy 424.744146 -280.699718) (xy 424.427142 -280.699718) (xy 424.426638 -280.725426) (xy 424.418595 -280.776208)
			(xy 424.402707 -280.825107) (xy 424.379364 -280.870919) (xy 424.349143 -280.912515) (xy 424.312787 -280.948871)
			(xy 424.271191 -280.979092) (xy 424.225379 -281.002435) (xy 424.17648 -281.018323) (xy 424.125698 -281.026366)
			(xy 424.074282 -281.026366) (xy 424.0235 -281.018323) (xy 423.974601 -281.002435) (xy 423.928789 -280.979092)
			(xy 423.887193 -280.948871) (xy 423.850837 -280.912515) (xy 423.820616 -280.870919) (xy 423.797273 -280.825107)
			(xy 423.781385 -280.776208) (xy 423.773342 -280.725426) (xy 423.454664 -280.725426) (xy 423.446948 -280.772902)
			(xy 423.431364 -280.819583) (xy 423.408493 -280.86316) (xy 423.378928 -280.902504) (xy 423.343435 -280.936596)
			(xy 423.302932 -280.964552) (xy 423.25847 -280.98565) (xy 423.211199 -280.999342) (xy 423.162344 -281.005274)
			(xy 423.113169 -281.003293) (xy 423.06495 -280.993449) (xy 423.018934 -280.975997) (xy 422.976313 -280.95139)
			(xy 422.938192 -280.920265) (xy 422.905557 -280.883428) (xy 422.879254 -280.841832) (xy 422.859963 -280.796556)
			(xy 422.848186 -280.748772) (xy 422.844226 -280.699718) (xy 422.526968 -280.699718) (xy 422.526464 -280.725426)
			(xy 422.518421 -280.776208) (xy 422.502533 -280.825107) (xy 422.47919 -280.870919) (xy 422.448969 -280.912515)
			(xy 422.412613 -280.948871) (xy 422.371017 -280.979092) (xy 422.325205 -281.002435) (xy 422.276306 -281.018323)
			(xy 422.225524 -281.026366) (xy 422.174108 -281.026366) (xy 422.123326 -281.018323) (xy 422.074427 -281.002435)
			(xy 422.028615 -280.979092) (xy 421.987019 -280.948871) (xy 421.950663 -280.912515) (xy 421.920442 -280.870919)
			(xy 421.897099 -280.825107) (xy 421.881211 -280.776208) (xy 421.873168 -280.725426) (xy 421.55449 -280.725426)
			(xy 421.546774 -280.772902) (xy 421.53119 -280.819583) (xy 421.508319 -280.86316) (xy 421.478754 -280.902504)
			(xy 421.443261 -280.936596) (xy 421.402758 -280.964552) (xy 421.358296 -280.98565) (xy 421.311025 -280.999342)
			(xy 421.26217 -281.005274) (xy 421.212995 -281.003293) (xy 421.164776 -280.993449) (xy 421.11876 -280.975997)
			(xy 421.076139 -280.95139) (xy 421.038018 -280.920265) (xy 421.005383 -280.883428) (xy 420.97908 -280.841832)
			(xy 420.959789 -280.796556) (xy 420.948012 -280.748772) (xy 420.944052 -280.699718) (xy 420.627048 -280.699718)
			(xy 420.626544 -280.725426) (xy 420.618501 -280.776208) (xy 420.602613 -280.825107) (xy 420.57927 -280.870919)
			(xy 420.549049 -280.912515) (xy 420.512693 -280.948871) (xy 420.471097 -280.979092) (xy 420.425285 -281.002435)
			(xy 420.376386 -281.018323) (xy 420.325604 -281.026366) (xy 420.274188 -281.026366) (xy 420.223406 -281.018323)
			(xy 420.174507 -281.002435) (xy 420.128695 -280.979092) (xy 420.087099 -280.948871) (xy 420.050743 -280.912515)
			(xy 420.020522 -280.870919) (xy 419.997179 -280.825107) (xy 419.981291 -280.776208) (xy 419.973248 -280.725426)
			(xy 419.65457 -280.725426) (xy 419.646854 -280.772902) (xy 419.63127 -280.819583) (xy 419.608399 -280.86316)
			(xy 419.578834 -280.902504) (xy 419.543341 -280.936596) (xy 419.502838 -280.964552) (xy 419.458376 -280.98565)
			(xy 419.411105 -280.999342) (xy 419.36225 -281.005274) (xy 419.313075 -281.003293) (xy 419.264856 -280.993449)
			(xy 419.21884 -280.975997) (xy 419.176219 -280.95139) (xy 419.138098 -280.920265) (xy 419.105463 -280.883428)
			(xy 419.07916 -280.841832) (xy 419.059869 -280.796556) (xy 419.048092 -280.748772) (xy 419.044132 -280.699718)
			(xy 418.727128 -280.699718) (xy 418.726624 -280.725426) (xy 418.718581 -280.776208) (xy 418.702693 -280.825107)
			(xy 418.67935 -280.870919) (xy 418.649129 -280.912515) (xy 418.612773 -280.948871) (xy 418.571177 -280.979092)
			(xy 418.525365 -281.002435) (xy 418.476466 -281.018323) (xy 418.425684 -281.026366) (xy 418.374268 -281.026366)
			(xy 418.323486 -281.018323) (xy 418.274587 -281.002435) (xy 418.228775 -280.979092) (xy 418.187179 -280.948871)
			(xy 418.150823 -280.912515) (xy 418.120602 -280.870919) (xy 418.097259 -280.825107) (xy 418.081371 -280.776208)
			(xy 418.073328 -280.725426) (xy 417.75465 -280.725426) (xy 417.746934 -280.772902) (xy 417.73135 -280.819583)
			(xy 417.708479 -280.86316) (xy 417.678914 -280.902504) (xy 417.643421 -280.936596) (xy 417.602918 -280.964552)
			(xy 417.558456 -280.98565) (xy 417.511185 -280.999342) (xy 417.46233 -281.005274) (xy 417.413155 -281.003293)
			(xy 417.364936 -280.993449) (xy 417.31892 -280.975997) (xy 417.276299 -280.95139) (xy 417.238178 -280.920265)
			(xy 417.205543 -280.883428) (xy 417.17924 -280.841832) (xy 417.159949 -280.796556) (xy 417.148172 -280.748772)
			(xy 417.144212 -280.699718) (xy 416.826954 -280.699718) (xy 416.82645 -280.725426) (xy 416.818407 -280.776208)
			(xy 416.802519 -280.825107) (xy 416.779176 -280.870919) (xy 416.748955 -280.912515) (xy 416.712599 -280.948871)
			(xy 416.671003 -280.979092) (xy 416.625191 -281.002435) (xy 416.576292 -281.018323) (xy 416.52551 -281.026366)
			(xy 416.474094 -281.026366) (xy 416.423312 -281.018323) (xy 416.374413 -281.002435) (xy 416.328601 -280.979092)
			(xy 416.287005 -280.948871) (xy 416.250649 -280.912515) (xy 416.220428 -280.870919) (xy 416.197085 -280.825107)
			(xy 416.181197 -280.776208) (xy 416.173154 -280.725426) (xy 415.854476 -280.725426) (xy 415.84676 -280.772902)
			(xy 415.831176 -280.819583) (xy 415.808305 -280.86316) (xy 415.77874 -280.902504) (xy 415.743247 -280.936596)
			(xy 415.702744 -280.964552) (xy 415.658282 -280.98565) (xy 415.611011 -280.999342) (xy 415.562156 -281.005274)
			(xy 415.512981 -281.003293) (xy 415.464762 -280.993449) (xy 415.418746 -280.975997) (xy 415.376125 -280.95139)
			(xy 415.338004 -280.920265) (xy 415.305369 -280.883428) (xy 415.279066 -280.841832) (xy 415.259775 -280.796556)
			(xy 415.247998 -280.748772) (xy 415.244038 -280.699718) (xy 414.927034 -280.699718) (xy 414.92653 -280.725426)
			(xy 414.918487 -280.776208) (xy 414.902599 -280.825107) (xy 414.879256 -280.870919) (xy 414.849035 -280.912515)
			(xy 414.812679 -280.948871) (xy 414.771083 -280.979092) (xy 414.725271 -281.002435) (xy 414.676372 -281.018323)
			(xy 414.62559 -281.026366) (xy 414.574174 -281.026366) (xy 414.523392 -281.018323) (xy 414.474493 -281.002435)
			(xy 414.428681 -280.979092) (xy 414.387085 -280.948871) (xy 414.350729 -280.912515) (xy 414.320508 -280.870919)
			(xy 414.297165 -280.825107) (xy 414.281277 -280.776208) (xy 414.273234 -280.725426) (xy 413.954556 -280.725426)
			(xy 413.94684 -280.772902) (xy 413.931256 -280.819583) (xy 413.908385 -280.86316) (xy 413.87882 -280.902504)
			(xy 413.843327 -280.936596) (xy 413.802824 -280.964552) (xy 413.758362 -280.98565) (xy 413.711091 -280.999342)
			(xy 413.662236 -281.005274) (xy 413.613061 -281.003293) (xy 413.564842 -280.993449) (xy 413.518826 -280.975997)
			(xy 413.476205 -280.95139) (xy 413.438084 -280.920265) (xy 413.405449 -280.883428) (xy 413.379146 -280.841832)
			(xy 413.359855 -280.796556) (xy 413.348078 -280.748772) (xy 413.344118 -280.699718) (xy 413.027114 -280.699718)
			(xy 413.02661 -280.725426) (xy 413.018567 -280.776208) (xy 413.002679 -280.825107) (xy 412.979336 -280.870919)
			(xy 412.949115 -280.912515) (xy 412.912759 -280.948871) (xy 412.871163 -280.979092) (xy 412.825351 -281.002435)
			(xy 412.776452 -281.018323) (xy 412.72567 -281.026366) (xy 412.674254 -281.026366) (xy 412.623472 -281.018323)
			(xy 412.574573 -281.002435) (xy 412.528761 -280.979092) (xy 412.487165 -280.948871) (xy 412.450809 -280.912515)
			(xy 412.420588 -280.870919) (xy 412.397245 -280.825107) (xy 412.381357 -280.776208) (xy 412.373314 -280.725426)
			(xy 412.054636 -280.725426) (xy 412.04692 -280.772902) (xy 412.031336 -280.819583) (xy 412.008465 -280.86316)
			(xy 411.9789 -280.902504) (xy 411.943407 -280.936596) (xy 411.902904 -280.964552) (xy 411.858442 -280.98565)
			(xy 411.811171 -280.999342) (xy 411.762316 -281.005274) (xy 411.713141 -281.003293) (xy 411.664922 -280.993449)
			(xy 411.618906 -280.975997) (xy 411.576285 -280.95139) (xy 411.538164 -280.920265) (xy 411.505529 -280.883428)
			(xy 411.479226 -280.841832) (xy 411.459935 -280.796556) (xy 411.448158 -280.748772) (xy 411.444198 -280.699718)
			(xy 411.12694 -280.699718) (xy 411.126436 -280.725426) (xy 411.118393 -280.776208) (xy 411.102505 -280.825107)
			(xy 411.079162 -280.870919) (xy 411.048941 -280.912515) (xy 411.012585 -280.948871) (xy 410.970989 -280.979092)
			(xy 410.925177 -281.002435) (xy 410.876278 -281.018323) (xy 410.825496 -281.026366) (xy 410.77408 -281.026366)
			(xy 410.723298 -281.018323) (xy 410.674399 -281.002435) (xy 410.628587 -280.979092) (xy 410.586991 -280.948871)
			(xy 410.550635 -280.912515) (xy 410.520414 -280.870919) (xy 410.497071 -280.825107) (xy 410.481183 -280.776208)
			(xy 410.47314 -280.725426) (xy 410.154462 -280.725426) (xy 410.146746 -280.772902) (xy 410.131162 -280.819583)
			(xy 410.108291 -280.86316) (xy 410.078726 -280.902504) (xy 410.043233 -280.936596) (xy 410.00273 -280.964552)
			(xy 409.958268 -280.98565) (xy 409.910997 -280.999342) (xy 409.862142 -281.005274) (xy 409.812967 -281.003293)
			(xy 409.764748 -280.993449) (xy 409.718732 -280.975997) (xy 409.676111 -280.95139) (xy 409.63799 -280.920265)
			(xy 409.605355 -280.883428) (xy 409.579052 -280.841832) (xy 409.559761 -280.796556) (xy 409.547984 -280.748772)
			(xy 409.544024 -280.699718) (xy 409.22702 -280.699718) (xy 409.226516 -280.725426) (xy 409.218473 -280.776208)
			(xy 409.202585 -280.825107) (xy 409.179242 -280.870919) (xy 409.149021 -280.912515) (xy 409.112665 -280.948871)
			(xy 409.071069 -280.979092) (xy 409.025257 -281.002435) (xy 408.976358 -281.018323) (xy 408.925576 -281.026366)
			(xy 408.87416 -281.026366) (xy 408.823378 -281.018323) (xy 408.774479 -281.002435) (xy 408.728667 -280.979092)
			(xy 408.687071 -280.948871) (xy 408.650715 -280.912515) (xy 408.620494 -280.870919) (xy 408.597151 -280.825107)
			(xy 408.581263 -280.776208) (xy 408.57322 -280.725426) (xy 408.254542 -280.725426) (xy 408.246826 -280.772902)
			(xy 408.231242 -280.819583) (xy 408.208371 -280.86316) (xy 408.178806 -280.902504) (xy 408.143313 -280.936596)
			(xy 408.10281 -280.964552) (xy 408.058348 -280.98565) (xy 408.011077 -280.999342) (xy 407.962222 -281.005274)
			(xy 407.913047 -281.003293) (xy 407.864828 -280.993449) (xy 407.818812 -280.975997) (xy 407.776191 -280.95139)
			(xy 407.73807 -280.920265) (xy 407.705435 -280.883428) (xy 407.679132 -280.841832) (xy 407.659841 -280.796556)
			(xy 407.648064 -280.748772) (xy 407.644104 -280.699718) (xy 407.3271 -280.699718) (xy 407.326596 -280.725426)
			(xy 407.318553 -280.776208) (xy 407.302665 -280.825107) (xy 407.279322 -280.870919) (xy 407.249101 -280.912515)
			(xy 407.212745 -280.948871) (xy 407.171149 -280.979092) (xy 407.125337 -281.002435) (xy 407.076438 -281.018323)
			(xy 407.025656 -281.026366) (xy 406.97424 -281.026366) (xy 406.923458 -281.018323) (xy 406.874559 -281.002435)
			(xy 406.828747 -280.979092) (xy 406.787151 -280.948871) (xy 406.750795 -280.912515) (xy 406.720574 -280.870919)
			(xy 406.697231 -280.825107) (xy 406.681343 -280.776208) (xy 406.6733 -280.725426) (xy 406.354622 -280.725426)
			(xy 406.346906 -280.772902) (xy 406.331322 -280.819583) (xy 406.308451 -280.86316) (xy 406.278886 -280.902504)
			(xy 406.243393 -280.936596) (xy 406.20289 -280.964552) (xy 406.158428 -280.98565) (xy 406.111157 -280.999342)
			(xy 406.062302 -281.005274) (xy 406.013127 -281.003293) (xy 405.964908 -280.993449) (xy 405.918892 -280.975997)
			(xy 405.876271 -280.95139) (xy 405.83815 -280.920265) (xy 405.805515 -280.883428) (xy 405.779212 -280.841832)
			(xy 405.759921 -280.796556) (xy 405.748144 -280.748772) (xy 405.744184 -280.699718) (xy 405.426926 -280.699718)
			(xy 405.426422 -280.725426) (xy 405.418379 -280.776208) (xy 405.402491 -280.825107) (xy 405.379148 -280.870919)
			(xy 405.348927 -280.912515) (xy 405.312571 -280.948871) (xy 405.270975 -280.979092) (xy 405.225163 -281.002435)
			(xy 405.176264 -281.018323) (xy 405.125482 -281.026366) (xy 405.074066 -281.026366) (xy 405.023284 -281.018323)
			(xy 404.974385 -281.002435) (xy 404.928573 -280.979092) (xy 404.886977 -280.948871) (xy 404.850621 -280.912515)
			(xy 404.8204 -280.870919) (xy 404.797057 -280.825107) (xy 404.781169 -280.776208) (xy 404.773126 -280.725426)
			(xy 404.454448 -280.725426) (xy 404.446732 -280.772902) (xy 404.431148 -280.819583) (xy 404.408277 -280.86316)
			(xy 404.378712 -280.902504) (xy 404.343219 -280.936596) (xy 404.302716 -280.964552) (xy 404.258254 -280.98565)
			(xy 404.210983 -280.999342) (xy 404.162128 -281.005274) (xy 404.112953 -281.003293) (xy 404.064734 -280.993449)
			(xy 404.018718 -280.975997) (xy 403.976097 -280.95139) (xy 403.937976 -280.920265) (xy 403.905341 -280.883428)
			(xy 403.879038 -280.841832) (xy 403.859747 -280.796556) (xy 403.84797 -280.748772) (xy 403.84401 -280.699718)
			(xy 403.527006 -280.699718) (xy 403.526502 -280.725426) (xy 403.518459 -280.776208) (xy 403.502571 -280.825107)
			(xy 403.479228 -280.870919) (xy 403.449007 -280.912515) (xy 403.412651 -280.948871) (xy 403.371055 -280.979092)
			(xy 403.325243 -281.002435) (xy 403.276344 -281.018323) (xy 403.225562 -281.026366) (xy 403.174146 -281.026366)
			(xy 403.123364 -281.018323) (xy 403.074465 -281.002435) (xy 403.028653 -280.979092) (xy 402.987057 -280.948871)
			(xy 402.950701 -280.912515) (xy 402.92048 -280.870919) (xy 402.897137 -280.825107) (xy 402.881249 -280.776208)
			(xy 402.873206 -280.725426) (xy 402.554528 -280.725426) (xy 402.546812 -280.772902) (xy 402.531228 -280.819583)
			(xy 402.508357 -280.86316) (xy 402.478792 -280.902504) (xy 402.443299 -280.936596) (xy 402.402796 -280.964552)
			(xy 402.358334 -280.98565) (xy 402.311063 -280.999342) (xy 402.262208 -281.005274) (xy 402.213033 -281.003293)
			(xy 402.164814 -280.993449) (xy 402.118798 -280.975997) (xy 402.076177 -280.95139) (xy 402.038056 -280.920265)
			(xy 402.005421 -280.883428) (xy 401.979118 -280.841832) (xy 401.959827 -280.796556) (xy 401.94805 -280.748772)
			(xy 401.94409 -280.699718) (xy 401.627086 -280.699718) (xy 401.626582 -280.725426) (xy 401.618539 -280.776208)
			(xy 401.602651 -280.825107) (xy 401.579308 -280.870919) (xy 401.549087 -280.912515) (xy 401.512731 -280.948871)
			(xy 401.471135 -280.979092) (xy 401.425323 -281.002435) (xy 401.376424 -281.018323) (xy 401.325642 -281.026366)
			(xy 401.274226 -281.026366) (xy 401.223444 -281.018323) (xy 401.174545 -281.002435) (xy 401.128733 -280.979092)
			(xy 401.087137 -280.948871) (xy 401.050781 -280.912515) (xy 401.02056 -280.870919) (xy 400.997217 -280.825107)
			(xy 400.981329 -280.776208) (xy 400.973286 -280.725426) (xy 400.654608 -280.725426) (xy 400.646892 -280.772902)
			(xy 400.631308 -280.819583) (xy 400.608437 -280.86316) (xy 400.578872 -280.902504) (xy 400.543379 -280.936596)
			(xy 400.502876 -280.964552) (xy 400.458414 -280.98565) (xy 400.411143 -280.999342) (xy 400.362288 -281.005274)
			(xy 400.313113 -281.003293) (xy 400.264894 -280.993449) (xy 400.218878 -280.975997) (xy 400.176257 -280.95139)
			(xy 400.138136 -280.920265) (xy 400.105501 -280.883428) (xy 400.079198 -280.841832) (xy 400.059907 -280.796556)
			(xy 400.04813 -280.748772) (xy 400.04417 -280.699718) (xy 399.727166 -280.699718) (xy 399.726662 -280.725426)
			(xy 399.718619 -280.776208) (xy 399.702731 -280.825107) (xy 399.679388 -280.870919) (xy 399.649167 -280.912515)
			(xy 399.612811 -280.948871) (xy 399.571215 -280.979092) (xy 399.525403 -281.002435) (xy 399.476504 -281.018323)
			(xy 399.425722 -281.026366) (xy 399.374306 -281.026366) (xy 399.323524 -281.018323) (xy 399.274625 -281.002435)
			(xy 399.228813 -280.979092) (xy 399.187217 -280.948871) (xy 399.150861 -280.912515) (xy 399.12064 -280.870919)
			(xy 399.097297 -280.825107) (xy 399.081409 -280.776208) (xy 399.073366 -280.725426) (xy 398.753481 -280.725426)
			(xy 398.751442 -280.750035) (xy 398.739043 -280.798997) (xy 398.718755 -280.845251) (xy 398.691129 -280.887534)
			(xy 398.656922 -280.924694) (xy 398.617064 -280.955716) (xy 398.572644 -280.979755) (xy 398.524873 -280.996155)
			(xy 398.475054 -281.004468) (xy 398.4498 -281.005026) (xy 398.435618 -281.004839) (xy 398.407378 -281.002166)
			(xy 398.393412 -280.999692) (xy 398.380966 -280.997406) (xy 398.35709 -281.004772) (xy 398.279874 -281.081988)
			(xy 398.272508 -281.106118) (xy 398.274794 -281.11831) (xy 398.277294 -281.132337) (xy 398.279967 -281.160705)
			(xy 398.280128 -281.174952) (xy 398.279944 -281.189135) (xy 398.277275 -281.217375) (xy 398.274794 -281.23134)
			(xy 398.272508 -281.243786) (xy 398.279874 -281.267408) (xy 398.357344 -281.344878) (xy 398.380966 -281.352244)
			(xy 398.393412 -281.349958) (xy 398.407377 -281.347472) (xy 398.435617 -281.3448) (xy 398.4498 -281.344624)
			(xy 398.475053 -281.345145) (xy 398.524869 -281.353458) (xy 398.572638 -281.369857) (xy 398.617056 -281.393895)
			(xy 398.656912 -281.424916) (xy 398.691118 -281.462074) (xy 398.718742 -281.504356) (xy 398.73903 -281.550607)
			(xy 398.751428 -281.599567) (xy 398.755599 -281.6499) (xy 398.755596 -281.649932) (xy 399.09421 -281.649932)
			(xy 399.09817 -281.600878) (xy 399.109947 -281.553094) (xy 399.129238 -281.507818) (xy 399.155541 -281.466222)
			(xy 399.188176 -281.429385) (xy 399.226297 -281.39826) (xy 399.268918 -281.373653) (xy 399.314934 -281.356201)
			(xy 399.363153 -281.346357) (xy 399.412328 -281.344376) (xy 399.461183 -281.350308) (xy 399.508454 -281.364)
			(xy 399.552916 -281.385098) (xy 399.593419 -281.413054) (xy 399.628912 -281.447146) (xy 399.658477 -281.48649)
			(xy 399.681348 -281.530067) (xy 399.696932 -281.576748) (xy 399.704827 -281.625325) (xy 399.705322 -281.649932)
			(xy 400.04417 -281.649932) (xy 400.04813 -281.600878) (xy 400.059907 -281.553094) (xy 400.079198 -281.507818)
			(xy 400.105501 -281.466222) (xy 400.138136 -281.429385) (xy 400.176257 -281.39826) (xy 400.218878 -281.373653)
			(xy 400.264894 -281.356201) (xy 400.313113 -281.346357) (xy 400.362288 -281.344376) (xy 400.411143 -281.350308)
			(xy 400.458414 -281.364) (xy 400.502876 -281.385098) (xy 400.543379 -281.413054) (xy 400.578872 -281.447146)
			(xy 400.608437 -281.48649) (xy 400.631308 -281.530067) (xy 400.646892 -281.576748) (xy 400.654787 -281.625325)
			(xy 400.655282 -281.649932) (xy 400.99413 -281.649932) (xy 400.99809 -281.600878) (xy 401.009867 -281.553094)
			(xy 401.029158 -281.507818) (xy 401.055461 -281.466222) (xy 401.088096 -281.429385) (xy 401.126217 -281.39826)
			(xy 401.168838 -281.373653) (xy 401.214854 -281.356201) (xy 401.263073 -281.346357) (xy 401.312248 -281.344376)
			(xy 401.361103 -281.350308) (xy 401.408374 -281.364) (xy 401.452836 -281.385098) (xy 401.493339 -281.413054)
			(xy 401.528832 -281.447146) (xy 401.558397 -281.48649) (xy 401.581268 -281.530067) (xy 401.596852 -281.576748)
			(xy 401.604747 -281.625325) (xy 401.605242 -281.649932) (xy 401.94409 -281.649932) (xy 401.94805 -281.600878)
			(xy 401.959827 -281.553094) (xy 401.979118 -281.507818) (xy 402.005421 -281.466222) (xy 402.038056 -281.429385)
			(xy 402.076177 -281.39826) (xy 402.118798 -281.373653) (xy 402.164814 -281.356201) (xy 402.213033 -281.346357)
			(xy 402.262208 -281.344376) (xy 402.311063 -281.350308) (xy 402.358334 -281.364) (xy 402.402796 -281.385098)
			(xy 402.443299 -281.413054) (xy 402.478792 -281.447146) (xy 402.508357 -281.48649) (xy 402.531228 -281.530067)
			(xy 402.546812 -281.576748) (xy 402.554707 -281.625325) (xy 402.555202 -281.649932) (xy 402.89405 -281.649932)
			(xy 402.89801 -281.600878) (xy 402.909787 -281.553094) (xy 402.929078 -281.507818) (xy 402.955381 -281.466222)
			(xy 402.988016 -281.429385) (xy 403.026137 -281.39826) (xy 403.068758 -281.373653) (xy 403.114774 -281.356201)
			(xy 403.162993 -281.346357) (xy 403.212168 -281.344376) (xy 403.261023 -281.350308) (xy 403.308294 -281.364)
			(xy 403.352756 -281.385098) (xy 403.393259 -281.413054) (xy 403.428752 -281.447146) (xy 403.458317 -281.48649)
			(xy 403.481188 -281.530067) (xy 403.496772 -281.576748) (xy 403.504667 -281.625325) (xy 403.505162 -281.649932)
			(xy 403.84401 -281.649932) (xy 403.84797 -281.600878) (xy 403.859747 -281.553094) (xy 403.879038 -281.507818)
			(xy 403.905341 -281.466222) (xy 403.937976 -281.429385) (xy 403.976097 -281.39826) (xy 404.018718 -281.373653)
			(xy 404.064734 -281.356201) (xy 404.112953 -281.346357) (xy 404.162128 -281.344376) (xy 404.210983 -281.350308)
			(xy 404.258254 -281.364) (xy 404.302716 -281.385098) (xy 404.343219 -281.413054) (xy 404.378712 -281.447146)
			(xy 404.408277 -281.48649) (xy 404.431148 -281.530067) (xy 404.446732 -281.576748) (xy 404.454627 -281.625325)
			(xy 404.455122 -281.649932) (xy 404.794224 -281.649932) (xy 404.798184 -281.600878) (xy 404.809961 -281.553094)
			(xy 404.829252 -281.507818) (xy 404.855555 -281.466222) (xy 404.88819 -281.429385) (xy 404.926311 -281.39826)
			(xy 404.968932 -281.373653) (xy 405.014948 -281.356201) (xy 405.063167 -281.346357) (xy 405.112342 -281.344376)
			(xy 405.161197 -281.350308) (xy 405.208468 -281.364) (xy 405.25293 -281.385098) (xy 405.293433 -281.413054)
			(xy 405.328926 -281.447146) (xy 405.358491 -281.48649) (xy 405.381362 -281.530067) (xy 405.396946 -281.576748)
			(xy 405.404841 -281.625325) (xy 405.405336 -281.649932) (xy 405.744184 -281.649932) (xy 405.748144 -281.600878)
			(xy 405.759921 -281.553094) (xy 405.779212 -281.507818) (xy 405.805515 -281.466222) (xy 405.83815 -281.429385)
			(xy 405.876271 -281.39826) (xy 405.918892 -281.373653) (xy 405.964908 -281.356201) (xy 406.013127 -281.346357)
			(xy 406.062302 -281.344376) (xy 406.111157 -281.350308) (xy 406.158428 -281.364) (xy 406.20289 -281.385098)
			(xy 406.243393 -281.413054) (xy 406.278886 -281.447146) (xy 406.308451 -281.48649) (xy 406.331322 -281.530067)
			(xy 406.346906 -281.576748) (xy 406.354801 -281.625325) (xy 406.355296 -281.649932) (xy 406.694144 -281.649932)
			(xy 406.698104 -281.600878) (xy 406.709881 -281.553094) (xy 406.729172 -281.507818) (xy 406.755475 -281.466222)
			(xy 406.78811 -281.429385) (xy 406.826231 -281.39826) (xy 406.868852 -281.373653) (xy 406.914868 -281.356201)
			(xy 406.963087 -281.346357) (xy 407.012262 -281.344376) (xy 407.061117 -281.350308) (xy 407.108388 -281.364)
			(xy 407.15285 -281.385098) (xy 407.193353 -281.413054) (xy 407.228846 -281.447146) (xy 407.258411 -281.48649)
			(xy 407.281282 -281.530067) (xy 407.296866 -281.576748) (xy 407.304761 -281.625325) (xy 407.305256 -281.649932)
			(xy 407.644104 -281.649932) (xy 407.648064 -281.600878) (xy 407.659841 -281.553094) (xy 407.679132 -281.507818)
			(xy 407.705435 -281.466222) (xy 407.73807 -281.429385) (xy 407.776191 -281.39826) (xy 407.818812 -281.373653)
			(xy 407.864828 -281.356201) (xy 407.913047 -281.346357) (xy 407.962222 -281.344376) (xy 408.011077 -281.350308)
			(xy 408.058348 -281.364) (xy 408.10281 -281.385098) (xy 408.143313 -281.413054) (xy 408.178806 -281.447146)
			(xy 408.208371 -281.48649) (xy 408.231242 -281.530067) (xy 408.246826 -281.576748) (xy 408.254721 -281.625325)
			(xy 408.255216 -281.649932) (xy 408.594064 -281.649932) (xy 408.598024 -281.600878) (xy 408.609801 -281.553094)
			(xy 408.629092 -281.507818) (xy 408.655395 -281.466222) (xy 408.68803 -281.429385) (xy 408.726151 -281.39826)
			(xy 408.768772 -281.373653) (xy 408.814788 -281.356201) (xy 408.863007 -281.346357) (xy 408.912182 -281.344376)
			(xy 408.961037 -281.350308) (xy 409.008308 -281.364) (xy 409.05277 -281.385098) (xy 409.093273 -281.413054)
			(xy 409.128766 -281.447146) (xy 409.158331 -281.48649) (xy 409.181202 -281.530067) (xy 409.196786 -281.576748)
			(xy 409.204681 -281.625325) (xy 409.205176 -281.649932) (xy 409.544024 -281.649932) (xy 409.547984 -281.600878)
			(xy 409.559761 -281.553094) (xy 409.579052 -281.507818) (xy 409.605355 -281.466222) (xy 409.63799 -281.429385)
			(xy 409.676111 -281.39826) (xy 409.718732 -281.373653) (xy 409.764748 -281.356201) (xy 409.812967 -281.346357)
			(xy 409.862142 -281.344376) (xy 409.910997 -281.350308) (xy 409.958268 -281.364) (xy 410.00273 -281.385098)
			(xy 410.043233 -281.413054) (xy 410.078726 -281.447146) (xy 410.108291 -281.48649) (xy 410.131162 -281.530067)
			(xy 410.146746 -281.576748) (xy 410.154641 -281.625325) (xy 410.155136 -281.649932) (xy 410.493984 -281.649932)
			(xy 410.497944 -281.600878) (xy 410.509721 -281.553094) (xy 410.529012 -281.507818) (xy 410.555315 -281.466222)
			(xy 410.58795 -281.429385) (xy 410.626071 -281.39826) (xy 410.668692 -281.373653) (xy 410.714708 -281.356201)
			(xy 410.762927 -281.346357) (xy 410.812102 -281.344376) (xy 410.860957 -281.350308) (xy 410.908228 -281.364)
			(xy 410.95269 -281.385098) (xy 410.993193 -281.413054) (xy 411.028686 -281.447146) (xy 411.058251 -281.48649)
			(xy 411.081122 -281.530067) (xy 411.096706 -281.576748) (xy 411.104601 -281.625325) (xy 411.105096 -281.649932)
			(xy 411.444198 -281.649932) (xy 411.448158 -281.600878) (xy 411.459935 -281.553094) (xy 411.479226 -281.507818)
			(xy 411.505529 -281.466222) (xy 411.538164 -281.429385) (xy 411.576285 -281.39826) (xy 411.618906 -281.373653)
			(xy 411.664922 -281.356201) (xy 411.713141 -281.346357) (xy 411.762316 -281.344376) (xy 411.811171 -281.350308)
			(xy 411.858442 -281.364) (xy 411.902904 -281.385098) (xy 411.943407 -281.413054) (xy 411.9789 -281.447146)
			(xy 412.008465 -281.48649) (xy 412.031336 -281.530067) (xy 412.04692 -281.576748) (xy 412.054815 -281.625325)
			(xy 412.05531 -281.649932) (xy 412.394158 -281.649932) (xy 412.398118 -281.600878) (xy 412.409895 -281.553094)
			(xy 412.429186 -281.507818) (xy 412.455489 -281.466222) (xy 412.488124 -281.429385) (xy 412.526245 -281.39826)
			(xy 412.568866 -281.373653) (xy 412.614882 -281.356201) (xy 412.663101 -281.346357) (xy 412.712276 -281.344376)
			(xy 412.761131 -281.350308) (xy 412.808402 -281.364) (xy 412.852864 -281.385098) (xy 412.893367 -281.413054)
			(xy 412.92886 -281.447146) (xy 412.958425 -281.48649) (xy 412.981296 -281.530067) (xy 412.99688 -281.576748)
			(xy 413.004775 -281.625325) (xy 413.00527 -281.649932) (xy 413.344118 -281.649932) (xy 413.348078 -281.600878)
			(xy 413.359855 -281.553094) (xy 413.379146 -281.507818) (xy 413.405449 -281.466222) (xy 413.438084 -281.429385)
			(xy 413.476205 -281.39826) (xy 413.518826 -281.373653) (xy 413.564842 -281.356201) (xy 413.613061 -281.346357)
			(xy 413.662236 -281.344376) (xy 413.711091 -281.350308) (xy 413.758362 -281.364) (xy 413.802824 -281.385098)
			(xy 413.843327 -281.413054) (xy 413.87882 -281.447146) (xy 413.908385 -281.48649) (xy 413.931256 -281.530067)
			(xy 413.94684 -281.576748) (xy 413.954735 -281.625325) (xy 413.95523 -281.649932) (xy 414.294078 -281.649932)
			(xy 414.298038 -281.600878) (xy 414.309815 -281.553094) (xy 414.329106 -281.507818) (xy 414.355409 -281.466222)
			(xy 414.388044 -281.429385) (xy 414.426165 -281.39826) (xy 414.468786 -281.373653) (xy 414.514802 -281.356201)
			(xy 414.563021 -281.346357) (xy 414.612196 -281.344376) (xy 414.661051 -281.350308) (xy 414.708322 -281.364)
			(xy 414.752784 -281.385098) (xy 414.793287 -281.413054) (xy 414.82878 -281.447146) (xy 414.858345 -281.48649)
			(xy 414.881216 -281.530067) (xy 414.8968 -281.576748) (xy 414.904695 -281.625325) (xy 414.90519 -281.649932)
			(xy 415.244038 -281.649932) (xy 415.247998 -281.600878) (xy 415.259775 -281.553094) (xy 415.279066 -281.507818)
			(xy 415.305369 -281.466222) (xy 415.338004 -281.429385) (xy 415.376125 -281.39826) (xy 415.418746 -281.373653)
			(xy 415.464762 -281.356201) (xy 415.512981 -281.346357) (xy 415.562156 -281.344376) (xy 415.611011 -281.350308)
			(xy 415.658282 -281.364) (xy 415.702744 -281.385098) (xy 415.743247 -281.413054) (xy 415.77874 -281.447146)
			(xy 415.808305 -281.48649) (xy 415.831176 -281.530067) (xy 415.84676 -281.576748) (xy 415.854655 -281.625325)
			(xy 415.85515 -281.649932) (xy 416.193998 -281.649932) (xy 416.197958 -281.600878) (xy 416.209735 -281.553094)
			(xy 416.229026 -281.507818) (xy 416.255329 -281.466222) (xy 416.287964 -281.429385) (xy 416.326085 -281.39826)
			(xy 416.368706 -281.373653) (xy 416.414722 -281.356201) (xy 416.462941 -281.346357) (xy 416.512116 -281.344376)
			(xy 416.560971 -281.350308) (xy 416.608242 -281.364) (xy 416.652704 -281.385098) (xy 416.693207 -281.413054)
			(xy 416.7287 -281.447146) (xy 416.758265 -281.48649) (xy 416.781136 -281.530067) (xy 416.79672 -281.576748)
			(xy 416.804615 -281.625325) (xy 416.80511 -281.649932) (xy 417.144212 -281.649932) (xy 417.148172 -281.600878)
			(xy 417.159949 -281.553094) (xy 417.17924 -281.507818) (xy 417.205543 -281.466222) (xy 417.238178 -281.429385)
			(xy 417.276299 -281.39826) (xy 417.31892 -281.373653) (xy 417.364936 -281.356201) (xy 417.413155 -281.346357)
			(xy 417.46233 -281.344376) (xy 417.511185 -281.350308) (xy 417.558456 -281.364) (xy 417.602918 -281.385098)
			(xy 417.643421 -281.413054) (xy 417.678914 -281.447146) (xy 417.708479 -281.48649) (xy 417.73135 -281.530067)
			(xy 417.746934 -281.576748) (xy 417.754829 -281.625325) (xy 417.755324 -281.649932) (xy 418.094172 -281.649932)
			(xy 418.098132 -281.600878) (xy 418.109909 -281.553094) (xy 418.1292 -281.507818) (xy 418.155503 -281.466222)
			(xy 418.188138 -281.429385) (xy 418.226259 -281.39826) (xy 418.26888 -281.373653) (xy 418.314896 -281.356201)
			(xy 418.363115 -281.346357) (xy 418.41229 -281.344376) (xy 418.461145 -281.350308) (xy 418.508416 -281.364)
			(xy 418.552878 -281.385098) (xy 418.593381 -281.413054) (xy 418.628874 -281.447146) (xy 418.658439 -281.48649)
			(xy 418.68131 -281.530067) (xy 418.696894 -281.576748) (xy 418.704789 -281.625325) (xy 418.705284 -281.649932)
			(xy 419.044132 -281.649932) (xy 419.048092 -281.600878) (xy 419.059869 -281.553094) (xy 419.07916 -281.507818)
			(xy 419.105463 -281.466222) (xy 419.138098 -281.429385) (xy 419.176219 -281.39826) (xy 419.21884 -281.373653)
			(xy 419.264856 -281.356201) (xy 419.313075 -281.346357) (xy 419.36225 -281.344376) (xy 419.411105 -281.350308)
			(xy 419.458376 -281.364) (xy 419.502838 -281.385098) (xy 419.543341 -281.413054) (xy 419.578834 -281.447146)
			(xy 419.608399 -281.48649) (xy 419.63127 -281.530067) (xy 419.646854 -281.576748) (xy 419.654749 -281.625325)
			(xy 419.655244 -281.649932) (xy 419.994092 -281.649932) (xy 419.998052 -281.600878) (xy 420.009829 -281.553094)
			(xy 420.02912 -281.507818) (xy 420.055423 -281.466222) (xy 420.088058 -281.429385) (xy 420.126179 -281.39826)
			(xy 420.1688 -281.373653) (xy 420.214816 -281.356201) (xy 420.263035 -281.346357) (xy 420.31221 -281.344376)
			(xy 420.361065 -281.350308) (xy 420.408336 -281.364) (xy 420.452798 -281.385098) (xy 420.493301 -281.413054)
			(xy 420.528794 -281.447146) (xy 420.558359 -281.48649) (xy 420.58123 -281.530067) (xy 420.596814 -281.576748)
			(xy 420.604709 -281.625325) (xy 420.605204 -281.649932) (xy 420.944052 -281.649932) (xy 420.948012 -281.600878)
			(xy 420.959789 -281.553094) (xy 420.97908 -281.507818) (xy 421.005383 -281.466222) (xy 421.038018 -281.429385)
			(xy 421.076139 -281.39826) (xy 421.11876 -281.373653) (xy 421.164776 -281.356201) (xy 421.212995 -281.346357)
			(xy 421.26217 -281.344376) (xy 421.311025 -281.350308) (xy 421.358296 -281.364) (xy 421.402758 -281.385098)
			(xy 421.443261 -281.413054) (xy 421.478754 -281.447146) (xy 421.508319 -281.48649) (xy 421.53119 -281.530067)
			(xy 421.546774 -281.576748) (xy 421.554669 -281.625325) (xy 421.555164 -281.649932) (xy 421.894012 -281.649932)
			(xy 421.897972 -281.600878) (xy 421.909749 -281.553094) (xy 421.92904 -281.507818) (xy 421.955343 -281.466222)
			(xy 421.987978 -281.429385) (xy 422.026099 -281.39826) (xy 422.06872 -281.373653) (xy 422.114736 -281.356201)
			(xy 422.162955 -281.346357) (xy 422.21213 -281.344376) (xy 422.260985 -281.350308) (xy 422.308256 -281.364)
			(xy 422.352718 -281.385098) (xy 422.393221 -281.413054) (xy 422.428714 -281.447146) (xy 422.458279 -281.48649)
			(xy 422.48115 -281.530067) (xy 422.496734 -281.576748) (xy 422.504629 -281.625325) (xy 422.505124 -281.649932)
			(xy 422.844226 -281.649932) (xy 422.848186 -281.600878) (xy 422.859963 -281.553094) (xy 422.879254 -281.507818)
			(xy 422.905557 -281.466222) (xy 422.938192 -281.429385) (xy 422.976313 -281.39826) (xy 423.018934 -281.373653)
			(xy 423.06495 -281.356201) (xy 423.113169 -281.346357) (xy 423.162344 -281.344376) (xy 423.211199 -281.350308)
			(xy 423.25847 -281.364) (xy 423.302932 -281.385098) (xy 423.343435 -281.413054) (xy 423.378928 -281.447146)
			(xy 423.408493 -281.48649) (xy 423.431364 -281.530067) (xy 423.446948 -281.576748) (xy 423.454843 -281.625325)
			(xy 423.455338 -281.649932) (xy 423.794186 -281.649932) (xy 423.798146 -281.600878) (xy 423.809923 -281.553094)
			(xy 423.829214 -281.507818) (xy 423.855517 -281.466222) (xy 423.888152 -281.429385) (xy 423.926273 -281.39826)
			(xy 423.968894 -281.373653) (xy 424.01491 -281.356201) (xy 424.063129 -281.346357) (xy 424.112304 -281.344376)
			(xy 424.161159 -281.350308) (xy 424.20843 -281.364) (xy 424.252892 -281.385098) (xy 424.293395 -281.413054)
			(xy 424.328888 -281.447146) (xy 424.358453 -281.48649) (xy 424.381324 -281.530067) (xy 424.396908 -281.576748)
			(xy 424.404803 -281.625325) (xy 424.405298 -281.649932) (xy 424.744146 -281.649932) (xy 424.748106 -281.600878)
			(xy 424.759883 -281.553094) (xy 424.779174 -281.507818) (xy 424.805477 -281.466222) (xy 424.838112 -281.429385)
			(xy 424.876233 -281.39826) (xy 424.918854 -281.373653) (xy 424.96487 -281.356201) (xy 425.013089 -281.346357)
			(xy 425.062264 -281.344376) (xy 425.111119 -281.350308) (xy 425.15839 -281.364) (xy 425.202852 -281.385098)
			(xy 425.243355 -281.413054) (xy 425.278848 -281.447146) (xy 425.308413 -281.48649) (xy 425.331284 -281.530067)
			(xy 425.346868 -281.576748) (xy 425.354763 -281.625325) (xy 425.355253 -281.649678) (xy 425.693852 -281.649678)
			(xy 425.697812 -281.600624) (xy 425.709589 -281.55284) (xy 425.72888 -281.507564) (xy 425.755183 -281.465968)
			(xy 425.787818 -281.429131) (xy 425.825939 -281.398006) (xy 425.86856 -281.373399) (xy 425.914576 -281.355947)
			(xy 425.962795 -281.346103) (xy 426.01197 -281.344122) (xy 426.060825 -281.350054) (xy 426.108096 -281.363746)
			(xy 426.152558 -281.384844) (xy 426.193061 -281.4128) (xy 426.228554 -281.446892) (xy 426.258119 -281.486236)
			(xy 426.28099 -281.529813) (xy 426.296574 -281.576494) (xy 426.304469 -281.625071) (xy 426.304964 -281.649678)
			(xy 426.304959 -281.649932) (xy 426.643812 -281.649932) (xy 426.647772 -281.600878) (xy 426.659549 -281.553094)
			(xy 426.67884 -281.507818) (xy 426.705143 -281.466222) (xy 426.737778 -281.429385) (xy 426.775899 -281.39826)
			(xy 426.81852 -281.373653) (xy 426.864536 -281.356201) (xy 426.912755 -281.346357) (xy 426.96193 -281.344376)
			(xy 427.010785 -281.350308) (xy 427.058056 -281.364) (xy 427.102518 -281.385098) (xy 427.143021 -281.413054)
			(xy 427.178514 -281.447146) (xy 427.208079 -281.48649) (xy 427.23095 -281.530067) (xy 427.246534 -281.576748)
			(xy 427.254429 -281.625325) (xy 427.254924 -281.649932) (xy 427.594026 -281.649932) (xy 427.597986 -281.600878)
			(xy 427.609763 -281.553094) (xy 427.629054 -281.507818) (xy 427.655357 -281.466222) (xy 427.687992 -281.429385)
			(xy 427.726113 -281.39826) (xy 427.768734 -281.373653) (xy 427.81475 -281.356201) (xy 427.862969 -281.346357)
			(xy 427.912144 -281.344376) (xy 427.960999 -281.350308) (xy 428.00827 -281.364) (xy 428.052732 -281.385098)
			(xy 428.093235 -281.413054) (xy 428.128728 -281.447146) (xy 428.158293 -281.48649) (xy 428.181164 -281.530067)
			(xy 428.196748 -281.576748) (xy 428.204643 -281.625325) (xy 428.205138 -281.649932) (xy 428.543986 -281.649932)
			(xy 428.547946 -281.600878) (xy 428.559723 -281.553094) (xy 428.579014 -281.507818) (xy 428.605317 -281.466222)
			(xy 428.637952 -281.429385) (xy 428.676073 -281.39826) (xy 428.718694 -281.373653) (xy 428.76471 -281.356201)
			(xy 428.812929 -281.346357) (xy 428.862104 -281.344376) (xy 428.910959 -281.350308) (xy 428.95823 -281.364)
			(xy 429.002692 -281.385098) (xy 429.043195 -281.413054) (xy 429.078688 -281.447146) (xy 429.108253 -281.48649)
			(xy 429.131124 -281.530067) (xy 429.146708 -281.576748) (xy 429.154603 -281.625325) (xy 429.155098 -281.649932)
			(xy 429.154603 -281.674539) (xy 429.154424 -281.67564) (xy 429.473356 -281.67564) (xy 429.473356 -281.624224)
			(xy 429.481399 -281.573442) (xy 429.497287 -281.524543) (xy 429.52063 -281.478731) (xy 429.550851 -281.437135)
			(xy 429.587207 -281.400779) (xy 429.628803 -281.370558) (xy 429.674615 -281.347215) (xy 429.723514 -281.331327)
			(xy 429.774296 -281.323284) (xy 429.825712 -281.323284) (xy 429.876494 -281.331327) (xy 429.925393 -281.347215)
			(xy 429.971205 -281.370558) (xy 430.012801 -281.400779) (xy 430.049157 -281.437135) (xy 430.079378 -281.478731)
			(xy 430.102721 -281.524543) (xy 430.118609 -281.573442) (xy 430.126652 -281.624224) (xy 430.127156 -281.649932)
			(xy 430.126652 -281.67564) (xy 430.423316 -281.67564) (xy 430.423316 -281.624224) (xy 430.431359 -281.573442)
			(xy 430.447247 -281.524543) (xy 430.47059 -281.478731) (xy 430.500811 -281.437135) (xy 430.537167 -281.400779)
			(xy 430.578763 -281.370558) (xy 430.624575 -281.347215) (xy 430.673474 -281.331327) (xy 430.724256 -281.323284)
			(xy 430.775672 -281.323284) (xy 430.826454 -281.331327) (xy 430.875353 -281.347215) (xy 430.921165 -281.370558)
			(xy 430.962761 -281.400779) (xy 430.999117 -281.437135) (xy 431.029338 -281.478731) (xy 431.052681 -281.524543)
			(xy 431.068569 -281.573442) (xy 431.076612 -281.624224) (xy 431.077116 -281.649932) (xy 431.077111 -281.650186)
			(xy 431.394374 -281.650186) (xy 431.398334 -281.601132) (xy 431.410111 -281.553348) (xy 431.429402 -281.508072)
			(xy 431.455705 -281.466476) (xy 431.48834 -281.429639) (xy 431.526461 -281.398514) (xy 431.569082 -281.373907)
			(xy 431.615098 -281.356455) (xy 431.663317 -281.346611) (xy 431.712492 -281.34463) (xy 431.761347 -281.350562)
			(xy 431.808618 -281.364254) (xy 431.85308 -281.385352) (xy 431.893583 -281.413308) (xy 431.929076 -281.4474)
			(xy 431.958641 -281.486744) (xy 431.981512 -281.530321) (xy 431.997096 -281.577002) (xy 432.004991 -281.625579)
			(xy 432.005486 -281.650186) (xy 432.004991 -281.674793) (xy 431.997096 -281.72337) (xy 431.981512 -281.770051)
			(xy 431.958641 -281.813628) (xy 431.929076 -281.852972) (xy 431.893583 -281.887064) (xy 431.85308 -281.91502)
			(xy 431.808618 -281.936118) (xy 431.761347 -281.94981) (xy 431.712492 -281.955742) (xy 431.663317 -281.953761)
			(xy 431.615098 -281.943917) (xy 431.569082 -281.926465) (xy 431.526461 -281.901858) (xy 431.48834 -281.870733)
			(xy 431.455705 -281.833896) (xy 431.429402 -281.7923) (xy 431.410111 -281.747024) (xy 431.398334 -281.69924)
			(xy 431.394374 -281.650186) (xy 431.077111 -281.650186) (xy 431.076612 -281.67564) (xy 431.068569 -281.726422)
			(xy 431.052681 -281.775321) (xy 431.029338 -281.821133) (xy 430.999117 -281.862729) (xy 430.962761 -281.899085)
			(xy 430.921165 -281.929306) (xy 430.875353 -281.952649) (xy 430.826454 -281.968537) (xy 430.775672 -281.97658)
			(xy 430.724256 -281.97658) (xy 430.673474 -281.968537) (xy 430.624575 -281.952649) (xy 430.578763 -281.929306)
			(xy 430.537167 -281.899085) (xy 430.500811 -281.862729) (xy 430.47059 -281.821133) (xy 430.447247 -281.775321)
			(xy 430.431359 -281.726422) (xy 430.423316 -281.67564) (xy 430.126652 -281.67564) (xy 430.118609 -281.726422)
			(xy 430.102721 -281.775321) (xy 430.079378 -281.821133) (xy 430.049157 -281.862729) (xy 430.012801 -281.899085)
			(xy 429.971205 -281.929306) (xy 429.925393 -281.952649) (xy 429.876494 -281.968537) (xy 429.825712 -281.97658)
			(xy 429.774296 -281.97658) (xy 429.723514 -281.968537) (xy 429.674615 -281.952649) (xy 429.628803 -281.929306)
			(xy 429.587207 -281.899085) (xy 429.550851 -281.862729) (xy 429.52063 -281.821133) (xy 429.497287 -281.775321)
			(xy 429.481399 -281.726422) (xy 429.473356 -281.67564) (xy 429.154424 -281.67564) (xy 429.146708 -281.723116)
			(xy 429.131124 -281.769797) (xy 429.108253 -281.813374) (xy 429.078688 -281.852718) (xy 429.043195 -281.88681)
			(xy 429.002692 -281.914766) (xy 428.95823 -281.935864) (xy 428.910959 -281.949556) (xy 428.862104 -281.955488)
			(xy 428.812929 -281.953507) (xy 428.76471 -281.943663) (xy 428.718694 -281.926211) (xy 428.676073 -281.901604)
			(xy 428.637952 -281.870479) (xy 428.605317 -281.833642) (xy 428.579014 -281.792046) (xy 428.559723 -281.74677)
			(xy 428.547946 -281.698986) (xy 428.543986 -281.649932) (xy 428.205138 -281.649932) (xy 428.204643 -281.674539)
			(xy 428.196748 -281.723116) (xy 428.181164 -281.769797) (xy 428.158293 -281.813374) (xy 428.128728 -281.852718)
			(xy 428.093235 -281.88681) (xy 428.052732 -281.914766) (xy 428.00827 -281.935864) (xy 427.960999 -281.949556)
			(xy 427.912144 -281.955488) (xy 427.862969 -281.953507) (xy 427.81475 -281.943663) (xy 427.768734 -281.926211)
			(xy 427.726113 -281.901604) (xy 427.687992 -281.870479) (xy 427.655357 -281.833642) (xy 427.629054 -281.792046)
			(xy 427.609763 -281.74677) (xy 427.597986 -281.698986) (xy 427.594026 -281.649932) (xy 427.254924 -281.649932)
			(xy 427.254429 -281.674539) (xy 427.246534 -281.723116) (xy 427.23095 -281.769797) (xy 427.208079 -281.813374)
			(xy 427.178514 -281.852718) (xy 427.143021 -281.88681) (xy 427.102518 -281.914766) (xy 427.058056 -281.935864)
			(xy 427.010785 -281.949556) (xy 426.96193 -281.955488) (xy 426.912755 -281.953507) (xy 426.864536 -281.943663)
			(xy 426.81852 -281.926211) (xy 426.775899 -281.901604) (xy 426.737778 -281.870479) (xy 426.705143 -281.833642)
			(xy 426.67884 -281.792046) (xy 426.659549 -281.74677) (xy 426.647772 -281.698986) (xy 426.643812 -281.649932)
			(xy 426.304959 -281.649932) (xy 426.304469 -281.674285) (xy 426.296574 -281.722862) (xy 426.28099 -281.769543)
			(xy 426.258119 -281.81312) (xy 426.228554 -281.852464) (xy 426.193061 -281.886556) (xy 426.152558 -281.914512)
			(xy 426.108096 -281.93561) (xy 426.060825 -281.949302) (xy 426.01197 -281.955234) (xy 425.962795 -281.953253)
			(xy 425.914576 -281.943409) (xy 425.86856 -281.925957) (xy 425.825939 -281.90135) (xy 425.787818 -281.870225)
			(xy 425.755183 -281.833388) (xy 425.72888 -281.791792) (xy 425.709589 -281.746516) (xy 425.697812 -281.698732)
			(xy 425.693852 -281.649678) (xy 425.355253 -281.649678) (xy 425.355258 -281.649932) (xy 425.354763 -281.674539)
			(xy 425.346868 -281.723116) (xy 425.331284 -281.769797) (xy 425.308413 -281.813374) (xy 425.278848 -281.852718)
			(xy 425.243355 -281.88681) (xy 425.202852 -281.914766) (xy 425.15839 -281.935864) (xy 425.111119 -281.949556)
			(xy 425.062264 -281.955488) (xy 425.013089 -281.953507) (xy 424.96487 -281.943663) (xy 424.918854 -281.926211)
			(xy 424.876233 -281.901604) (xy 424.838112 -281.870479) (xy 424.805477 -281.833642) (xy 424.779174 -281.792046)
			(xy 424.759883 -281.74677) (xy 424.748106 -281.698986) (xy 424.744146 -281.649932) (xy 424.405298 -281.649932)
			(xy 424.404803 -281.674539) (xy 424.396908 -281.723116) (xy 424.381324 -281.769797) (xy 424.358453 -281.813374)
			(xy 424.328888 -281.852718) (xy 424.293395 -281.88681) (xy 424.252892 -281.914766) (xy 424.20843 -281.935864)
			(xy 424.161159 -281.949556) (xy 424.112304 -281.955488) (xy 424.063129 -281.953507) (xy 424.01491 -281.943663)
			(xy 423.968894 -281.926211) (xy 423.926273 -281.901604) (xy 423.888152 -281.870479) (xy 423.855517 -281.833642)
			(xy 423.829214 -281.792046) (xy 423.809923 -281.74677) (xy 423.798146 -281.698986) (xy 423.794186 -281.649932)
			(xy 423.455338 -281.649932) (xy 423.454843 -281.674539) (xy 423.446948 -281.723116) (xy 423.431364 -281.769797)
			(xy 423.408493 -281.813374) (xy 423.378928 -281.852718) (xy 423.343435 -281.88681) (xy 423.302932 -281.914766)
			(xy 423.25847 -281.935864) (xy 423.211199 -281.949556) (xy 423.162344 -281.955488) (xy 423.113169 -281.953507)
			(xy 423.06495 -281.943663) (xy 423.018934 -281.926211) (xy 422.976313 -281.901604) (xy 422.938192 -281.870479)
			(xy 422.905557 -281.833642) (xy 422.879254 -281.792046) (xy 422.859963 -281.74677) (xy 422.848186 -281.698986)
			(xy 422.844226 -281.649932) (xy 422.505124 -281.649932) (xy 422.504629 -281.674539) (xy 422.496734 -281.723116)
			(xy 422.48115 -281.769797) (xy 422.458279 -281.813374) (xy 422.428714 -281.852718) (xy 422.393221 -281.88681)
			(xy 422.352718 -281.914766) (xy 422.308256 -281.935864) (xy 422.260985 -281.949556) (xy 422.21213 -281.955488)
			(xy 422.162955 -281.953507) (xy 422.114736 -281.943663) (xy 422.06872 -281.926211) (xy 422.026099 -281.901604)
			(xy 421.987978 -281.870479) (xy 421.955343 -281.833642) (xy 421.92904 -281.792046) (xy 421.909749 -281.74677)
			(xy 421.897972 -281.698986) (xy 421.894012 -281.649932) (xy 421.555164 -281.649932) (xy 421.554669 -281.674539)
			(xy 421.546774 -281.723116) (xy 421.53119 -281.769797) (xy 421.508319 -281.813374) (xy 421.478754 -281.852718)
			(xy 421.443261 -281.88681) (xy 421.402758 -281.914766) (xy 421.358296 -281.935864) (xy 421.311025 -281.949556)
			(xy 421.26217 -281.955488) (xy 421.212995 -281.953507) (xy 421.164776 -281.943663) (xy 421.11876 -281.926211)
			(xy 421.076139 -281.901604) (xy 421.038018 -281.870479) (xy 421.005383 -281.833642) (xy 420.97908 -281.792046)
			(xy 420.959789 -281.74677) (xy 420.948012 -281.698986) (xy 420.944052 -281.649932) (xy 420.605204 -281.649932)
			(xy 420.604709 -281.674539) (xy 420.596814 -281.723116) (xy 420.58123 -281.769797) (xy 420.558359 -281.813374)
			(xy 420.528794 -281.852718) (xy 420.493301 -281.88681) (xy 420.452798 -281.914766) (xy 420.408336 -281.935864)
			(xy 420.361065 -281.949556) (xy 420.31221 -281.955488) (xy 420.263035 -281.953507) (xy 420.214816 -281.943663)
			(xy 420.1688 -281.926211) (xy 420.126179 -281.901604) (xy 420.088058 -281.870479) (xy 420.055423 -281.833642)
			(xy 420.02912 -281.792046) (xy 420.009829 -281.74677) (xy 419.998052 -281.698986) (xy 419.994092 -281.649932)
			(xy 419.655244 -281.649932) (xy 419.654749 -281.674539) (xy 419.646854 -281.723116) (xy 419.63127 -281.769797)
			(xy 419.608399 -281.813374) (xy 419.578834 -281.852718) (xy 419.543341 -281.88681) (xy 419.502838 -281.914766)
			(xy 419.458376 -281.935864) (xy 419.411105 -281.949556) (xy 419.36225 -281.955488) (xy 419.313075 -281.953507)
			(xy 419.264856 -281.943663) (xy 419.21884 -281.926211) (xy 419.176219 -281.901604) (xy 419.138098 -281.870479)
			(xy 419.105463 -281.833642) (xy 419.07916 -281.792046) (xy 419.059869 -281.74677) (xy 419.048092 -281.698986)
			(xy 419.044132 -281.649932) (xy 418.705284 -281.649932) (xy 418.704789 -281.674539) (xy 418.696894 -281.723116)
			(xy 418.68131 -281.769797) (xy 418.658439 -281.813374) (xy 418.628874 -281.852718) (xy 418.593381 -281.88681)
			(xy 418.552878 -281.914766) (xy 418.508416 -281.935864) (xy 418.461145 -281.949556) (xy 418.41229 -281.955488)
			(xy 418.363115 -281.953507) (xy 418.314896 -281.943663) (xy 418.26888 -281.926211) (xy 418.226259 -281.901604)
			(xy 418.188138 -281.870479) (xy 418.155503 -281.833642) (xy 418.1292 -281.792046) (xy 418.109909 -281.74677)
			(xy 418.098132 -281.698986) (xy 418.094172 -281.649932) (xy 417.755324 -281.649932) (xy 417.754829 -281.674539)
			(xy 417.746934 -281.723116) (xy 417.73135 -281.769797) (xy 417.708479 -281.813374) (xy 417.678914 -281.852718)
			(xy 417.643421 -281.88681) (xy 417.602918 -281.914766) (xy 417.558456 -281.935864) (xy 417.511185 -281.949556)
			(xy 417.46233 -281.955488) (xy 417.413155 -281.953507) (xy 417.364936 -281.943663) (xy 417.31892 -281.926211)
			(xy 417.276299 -281.901604) (xy 417.238178 -281.870479) (xy 417.205543 -281.833642) (xy 417.17924 -281.792046)
			(xy 417.159949 -281.74677) (xy 417.148172 -281.698986) (xy 417.144212 -281.649932) (xy 416.80511 -281.649932)
			(xy 416.804615 -281.674539) (xy 416.79672 -281.723116) (xy 416.781136 -281.769797) (xy 416.758265 -281.813374)
			(xy 416.7287 -281.852718) (xy 416.693207 -281.88681) (xy 416.652704 -281.914766) (xy 416.608242 -281.935864)
			(xy 416.560971 -281.949556) (xy 416.512116 -281.955488) (xy 416.462941 -281.953507) (xy 416.414722 -281.943663)
			(xy 416.368706 -281.926211) (xy 416.326085 -281.901604) (xy 416.287964 -281.870479) (xy 416.255329 -281.833642)
			(xy 416.229026 -281.792046) (xy 416.209735 -281.74677) (xy 416.197958 -281.698986) (xy 416.193998 -281.649932)
			(xy 415.85515 -281.649932) (xy 415.854655 -281.674539) (xy 415.84676 -281.723116) (xy 415.831176 -281.769797)
			(xy 415.808305 -281.813374) (xy 415.77874 -281.852718) (xy 415.743247 -281.88681) (xy 415.702744 -281.914766)
			(xy 415.658282 -281.935864) (xy 415.611011 -281.949556) (xy 415.562156 -281.955488) (xy 415.512981 -281.953507)
			(xy 415.464762 -281.943663) (xy 415.418746 -281.926211) (xy 415.376125 -281.901604) (xy 415.338004 -281.870479)
			(xy 415.305369 -281.833642) (xy 415.279066 -281.792046) (xy 415.259775 -281.74677) (xy 415.247998 -281.698986)
			(xy 415.244038 -281.649932) (xy 414.90519 -281.649932) (xy 414.904695 -281.674539) (xy 414.8968 -281.723116)
			(xy 414.881216 -281.769797) (xy 414.858345 -281.813374) (xy 414.82878 -281.852718) (xy 414.793287 -281.88681)
			(xy 414.752784 -281.914766) (xy 414.708322 -281.935864) (xy 414.661051 -281.949556) (xy 414.612196 -281.955488)
			(xy 414.563021 -281.953507) (xy 414.514802 -281.943663) (xy 414.468786 -281.926211) (xy 414.426165 -281.901604)
			(xy 414.388044 -281.870479) (xy 414.355409 -281.833642) (xy 414.329106 -281.792046) (xy 414.309815 -281.74677)
			(xy 414.298038 -281.698986) (xy 414.294078 -281.649932) (xy 413.95523 -281.649932) (xy 413.954735 -281.674539)
			(xy 413.94684 -281.723116) (xy 413.931256 -281.769797) (xy 413.908385 -281.813374) (xy 413.87882 -281.852718)
			(xy 413.843327 -281.88681) (xy 413.802824 -281.914766) (xy 413.758362 -281.935864) (xy 413.711091 -281.949556)
			(xy 413.662236 -281.955488) (xy 413.613061 -281.953507) (xy 413.564842 -281.943663) (xy 413.518826 -281.926211)
			(xy 413.476205 -281.901604) (xy 413.438084 -281.870479) (xy 413.405449 -281.833642) (xy 413.379146 -281.792046)
			(xy 413.359855 -281.74677) (xy 413.348078 -281.698986) (xy 413.344118 -281.649932) (xy 413.00527 -281.649932)
			(xy 413.004775 -281.674539) (xy 412.99688 -281.723116) (xy 412.981296 -281.769797) (xy 412.958425 -281.813374)
			(xy 412.92886 -281.852718) (xy 412.893367 -281.88681) (xy 412.852864 -281.914766) (xy 412.808402 -281.935864)
			(xy 412.761131 -281.949556) (xy 412.712276 -281.955488) (xy 412.663101 -281.953507) (xy 412.614882 -281.943663)
			(xy 412.568866 -281.926211) (xy 412.526245 -281.901604) (xy 412.488124 -281.870479) (xy 412.455489 -281.833642)
			(xy 412.429186 -281.792046) (xy 412.409895 -281.74677) (xy 412.398118 -281.698986) (xy 412.394158 -281.649932)
			(xy 412.05531 -281.649932) (xy 412.054815 -281.674539) (xy 412.04692 -281.723116) (xy 412.031336 -281.769797)
			(xy 412.008465 -281.813374) (xy 411.9789 -281.852718) (xy 411.943407 -281.88681) (xy 411.902904 -281.914766)
			(xy 411.858442 -281.935864) (xy 411.811171 -281.949556) (xy 411.762316 -281.955488) (xy 411.713141 -281.953507)
			(xy 411.664922 -281.943663) (xy 411.618906 -281.926211) (xy 411.576285 -281.901604) (xy 411.538164 -281.870479)
			(xy 411.505529 -281.833642) (xy 411.479226 -281.792046) (xy 411.459935 -281.74677) (xy 411.448158 -281.698986)
			(xy 411.444198 -281.649932) (xy 411.105096 -281.649932) (xy 411.104601 -281.674539) (xy 411.096706 -281.723116)
			(xy 411.081122 -281.769797) (xy 411.058251 -281.813374) (xy 411.028686 -281.852718) (xy 410.993193 -281.88681)
			(xy 410.95269 -281.914766) (xy 410.908228 -281.935864) (xy 410.860957 -281.949556) (xy 410.812102 -281.955488)
			(xy 410.762927 -281.953507) (xy 410.714708 -281.943663) (xy 410.668692 -281.926211) (xy 410.626071 -281.901604)
			(xy 410.58795 -281.870479) (xy 410.555315 -281.833642) (xy 410.529012 -281.792046) (xy 410.509721 -281.74677)
			(xy 410.497944 -281.698986) (xy 410.493984 -281.649932) (xy 410.155136 -281.649932) (xy 410.154641 -281.674539)
			(xy 410.146746 -281.723116) (xy 410.131162 -281.769797) (xy 410.108291 -281.813374) (xy 410.078726 -281.852718)
			(xy 410.043233 -281.88681) (xy 410.00273 -281.914766) (xy 409.958268 -281.935864) (xy 409.910997 -281.949556)
			(xy 409.862142 -281.955488) (xy 409.812967 -281.953507) (xy 409.764748 -281.943663) (xy 409.718732 -281.926211)
			(xy 409.676111 -281.901604) (xy 409.63799 -281.870479) (xy 409.605355 -281.833642) (xy 409.579052 -281.792046)
			(xy 409.559761 -281.74677) (xy 409.547984 -281.698986) (xy 409.544024 -281.649932) (xy 409.205176 -281.649932)
			(xy 409.204681 -281.674539) (xy 409.196786 -281.723116) (xy 409.181202 -281.769797) (xy 409.158331 -281.813374)
			(xy 409.128766 -281.852718) (xy 409.093273 -281.88681) (xy 409.05277 -281.914766) (xy 409.008308 -281.935864)
			(xy 408.961037 -281.949556) (xy 408.912182 -281.955488) (xy 408.863007 -281.953507) (xy 408.814788 -281.943663)
			(xy 408.768772 -281.926211) (xy 408.726151 -281.901604) (xy 408.68803 -281.870479) (xy 408.655395 -281.833642)
			(xy 408.629092 -281.792046) (xy 408.609801 -281.74677) (xy 408.598024 -281.698986) (xy 408.594064 -281.649932)
			(xy 408.255216 -281.649932) (xy 408.254721 -281.674539) (xy 408.246826 -281.723116) (xy 408.231242 -281.769797)
			(xy 408.208371 -281.813374) (xy 408.178806 -281.852718) (xy 408.143313 -281.88681) (xy 408.10281 -281.914766)
			(xy 408.058348 -281.935864) (xy 408.011077 -281.949556) (xy 407.962222 -281.955488) (xy 407.913047 -281.953507)
			(xy 407.864828 -281.943663) (xy 407.818812 -281.926211) (xy 407.776191 -281.901604) (xy 407.73807 -281.870479)
			(xy 407.705435 -281.833642) (xy 407.679132 -281.792046) (xy 407.659841 -281.74677) (xy 407.648064 -281.698986)
			(xy 407.644104 -281.649932) (xy 407.305256 -281.649932) (xy 407.304761 -281.674539) (xy 407.296866 -281.723116)
			(xy 407.281282 -281.769797) (xy 407.258411 -281.813374) (xy 407.228846 -281.852718) (xy 407.193353 -281.88681)
			(xy 407.15285 -281.914766) (xy 407.108388 -281.935864) (xy 407.061117 -281.949556) (xy 407.012262 -281.955488)
			(xy 406.963087 -281.953507) (xy 406.914868 -281.943663) (xy 406.868852 -281.926211) (xy 406.826231 -281.901604)
			(xy 406.78811 -281.870479) (xy 406.755475 -281.833642) (xy 406.729172 -281.792046) (xy 406.709881 -281.74677)
			(xy 406.698104 -281.698986) (xy 406.694144 -281.649932) (xy 406.355296 -281.649932) (xy 406.354801 -281.674539)
			(xy 406.346906 -281.723116) (xy 406.331322 -281.769797) (xy 406.308451 -281.813374) (xy 406.278886 -281.852718)
			(xy 406.243393 -281.88681) (xy 406.20289 -281.914766) (xy 406.158428 -281.935864) (xy 406.111157 -281.949556)
			(xy 406.062302 -281.955488) (xy 406.013127 -281.953507) (xy 405.964908 -281.943663) (xy 405.918892 -281.926211)
			(xy 405.876271 -281.901604) (xy 405.83815 -281.870479) (xy 405.805515 -281.833642) (xy 405.779212 -281.792046)
			(xy 405.759921 -281.74677) (xy 405.748144 -281.698986) (xy 405.744184 -281.649932) (xy 405.405336 -281.649932)
			(xy 405.404841 -281.674539) (xy 405.396946 -281.723116) (xy 405.381362 -281.769797) (xy 405.358491 -281.813374)
			(xy 405.328926 -281.852718) (xy 405.293433 -281.88681) (xy 405.25293 -281.914766) (xy 405.208468 -281.935864)
			(xy 405.161197 -281.949556) (xy 405.112342 -281.955488) (xy 405.063167 -281.953507) (xy 405.014948 -281.943663)
			(xy 404.968932 -281.926211) (xy 404.926311 -281.901604) (xy 404.88819 -281.870479) (xy 404.855555 -281.833642)
			(xy 404.829252 -281.792046) (xy 404.809961 -281.74677) (xy 404.798184 -281.698986) (xy 404.794224 -281.649932)
			(xy 404.455122 -281.649932) (xy 404.454627 -281.674539) (xy 404.446732 -281.723116) (xy 404.431148 -281.769797)
			(xy 404.408277 -281.813374) (xy 404.378712 -281.852718) (xy 404.343219 -281.88681) (xy 404.302716 -281.914766)
			(xy 404.258254 -281.935864) (xy 404.210983 -281.949556) (xy 404.162128 -281.955488) (xy 404.112953 -281.953507)
			(xy 404.064734 -281.943663) (xy 404.018718 -281.926211) (xy 403.976097 -281.901604) (xy 403.937976 -281.870479)
			(xy 403.905341 -281.833642) (xy 403.879038 -281.792046) (xy 403.859747 -281.74677) (xy 403.84797 -281.698986)
			(xy 403.84401 -281.649932) (xy 403.505162 -281.649932) (xy 403.504667 -281.674539) (xy 403.496772 -281.723116)
			(xy 403.481188 -281.769797) (xy 403.458317 -281.813374) (xy 403.428752 -281.852718) (xy 403.393259 -281.88681)
			(xy 403.352756 -281.914766) (xy 403.308294 -281.935864) (xy 403.261023 -281.949556) (xy 403.212168 -281.955488)
			(xy 403.162993 -281.953507) (xy 403.114774 -281.943663) (xy 403.068758 -281.926211) (xy 403.026137 -281.901604)
			(xy 402.988016 -281.870479) (xy 402.955381 -281.833642) (xy 402.929078 -281.792046) (xy 402.909787 -281.74677)
			(xy 402.89801 -281.698986) (xy 402.89405 -281.649932) (xy 402.555202 -281.649932) (xy 402.554707 -281.674539)
			(xy 402.546812 -281.723116) (xy 402.531228 -281.769797) (xy 402.508357 -281.813374) (xy 402.478792 -281.852718)
			(xy 402.443299 -281.88681) (xy 402.402796 -281.914766) (xy 402.358334 -281.935864) (xy 402.311063 -281.949556)
			(xy 402.262208 -281.955488) (xy 402.213033 -281.953507) (xy 402.164814 -281.943663) (xy 402.118798 -281.926211)
			(xy 402.076177 -281.901604) (xy 402.038056 -281.870479) (xy 402.005421 -281.833642) (xy 401.979118 -281.792046)
			(xy 401.959827 -281.74677) (xy 401.94805 -281.698986) (xy 401.94409 -281.649932) (xy 401.605242 -281.649932)
			(xy 401.604747 -281.674539) (xy 401.596852 -281.723116) (xy 401.581268 -281.769797) (xy 401.558397 -281.813374)
			(xy 401.528832 -281.852718) (xy 401.493339 -281.88681) (xy 401.452836 -281.914766) (xy 401.408374 -281.935864)
			(xy 401.361103 -281.949556) (xy 401.312248 -281.955488) (xy 401.263073 -281.953507) (xy 401.214854 -281.943663)
			(xy 401.168838 -281.926211) (xy 401.126217 -281.901604) (xy 401.088096 -281.870479) (xy 401.055461 -281.833642)
			(xy 401.029158 -281.792046) (xy 401.009867 -281.74677) (xy 400.99809 -281.698986) (xy 400.99413 -281.649932)
			(xy 400.655282 -281.649932) (xy 400.654787 -281.674539) (xy 400.646892 -281.723116) (xy 400.631308 -281.769797)
			(xy 400.608437 -281.813374) (xy 400.578872 -281.852718) (xy 400.543379 -281.88681) (xy 400.502876 -281.914766)
			(xy 400.458414 -281.935864) (xy 400.411143 -281.949556) (xy 400.362288 -281.955488) (xy 400.313113 -281.953507)
			(xy 400.264894 -281.943663) (xy 400.218878 -281.926211) (xy 400.176257 -281.901604) (xy 400.138136 -281.870479)
			(xy 400.105501 -281.833642) (xy 400.079198 -281.792046) (xy 400.059907 -281.74677) (xy 400.04813 -281.698986)
			(xy 400.04417 -281.649932) (xy 399.705322 -281.649932) (xy 399.704827 -281.674539) (xy 399.696932 -281.723116)
			(xy 399.681348 -281.769797) (xy 399.658477 -281.813374) (xy 399.628912 -281.852718) (xy 399.593419 -281.88681)
			(xy 399.552916 -281.914766) (xy 399.508454 -281.935864) (xy 399.461183 -281.949556) (xy 399.412328 -281.955488)
			(xy 399.363153 -281.953507) (xy 399.314934 -281.943663) (xy 399.268918 -281.926211) (xy 399.226297 -281.901604)
			(xy 399.188176 -281.870479) (xy 399.155541 -281.833642) (xy 399.129238 -281.792046) (xy 399.109947 -281.74677)
			(xy 399.09817 -281.698986) (xy 399.09421 -281.649932) (xy 398.755596 -281.649932) (xy 398.751428 -281.700233)
			(xy 398.73903 -281.749193) (xy 398.718742 -281.795444) (xy 398.691118 -281.837726) (xy 398.656912 -281.874884)
			(xy 398.617056 -281.905905) (xy 398.572638 -281.929943) (xy 398.524869 -281.946342) (xy 398.475053 -281.954655)
			(xy 398.4498 -281.95524) (xy 398.435618 -281.955053) (xy 398.407378 -281.95238) (xy 398.393412 -281.949906)
			(xy 398.380966 -281.94762) (xy 398.357344 -281.954986) (xy 398.279874 -282.032456) (xy 398.272508 -282.056078)
			(xy 398.274794 -282.068524) (xy 398.277279 -282.082489) (xy 398.279949 -282.110729) (xy 398.280128 -282.124912)
			(xy 398.279664 -282.148802) (xy 398.27222 -282.195998) (xy 398.269744 -282.203652) (xy 450.561456 -282.203652)
			(xy 450.561883 -282.178253) (xy 450.568618 -282.127905) (xy 450.581977 -282.078896) (xy 450.601722 -282.032094)
			(xy 450.627505 -281.988326) (xy 450.658869 -281.948369) (xy 450.676772 -281.930348) (xy 450.683884 -281.92349)
			(xy 450.691758 -281.90571) (xy 450.69506 -281.815794) (xy 450.688456 -281.797506) (xy 450.681852 -281.79014)
			(xy 450.663863 -281.76907) (xy 450.633481 -281.722746) (xy 450.610128 -281.67251) (xy 450.594295 -281.619423)
			(xy 450.586316 -281.564602) (xy 450.58584 -281.536902) (xy 450.586257 -281.509647) (xy 450.594015 -281.455692)
			(xy 450.609373 -281.40339) (xy 450.632019 -281.353807) (xy 450.661492 -281.307952) (xy 450.69719 -281.266758)
			(xy 450.738388 -281.231064) (xy 450.784247 -281.201597) (xy 450.833833 -281.178957) (xy 450.886137 -281.163605)
			(xy 450.940093 -281.155854) (xy 450.967348 -281.155394) (xy 450.996088 -281.15589) (xy 451.052916 -281.16452)
			(xy 451.107807 -281.181576) (xy 451.159519 -281.206674) (xy 451.20688 -281.239245) (xy 451.228206 -281.258518)
			(xy 451.235318 -281.265122) (xy 451.252844 -281.272234) (xy 451.342252 -281.272234) (xy 451.359778 -281.265122)
			(xy 451.36689 -281.258518) (xy 451.388217 -281.239248) (xy 451.43558 -281.206683) (xy 451.487291 -281.181592)
			(xy 451.542182 -281.164542) (xy 451.599009 -281.15592) (xy 451.656487 -281.15592) (xy 451.713314 -281.164542)
			(xy 451.768205 -281.181592) (xy 451.819916 -281.206683) (xy 451.867279 -281.239248) (xy 451.888606 -281.258518)
			(xy 451.895718 -281.265122) (xy 451.913244 -281.272234) (xy 452.002652 -281.272234) (xy 452.020178 -281.265122)
			(xy 452.02729 -281.258518) (xy 452.048617 -281.239248) (xy 452.09598 -281.206683) (xy 452.147691 -281.181592)
			(xy 452.202582 -281.164542) (xy 452.259409 -281.15592) (xy 452.316887 -281.15592) (xy 452.373714 -281.164542)
			(xy 452.428605 -281.181592) (xy 452.480316 -281.206683) (xy 452.527679 -281.239248) (xy 452.549006 -281.258518)
			(xy 452.556118 -281.265122) (xy 452.573644 -281.272234) (xy 452.663052 -281.272234) (xy 452.680578 -281.265122)
			(xy 452.68769 -281.258518) (xy 452.708994 -281.239221) (xy 452.756363 -281.206659) (xy 452.80808 -281.181572)
			(xy 452.862976 -281.164528) (xy 452.919807 -281.155911) (xy 452.948548 -281.155394) (xy 452.975801 -281.155833)
			(xy 453.02975 -281.163596) (xy 453.082046 -281.178958) (xy 453.131623 -281.201604) (xy 453.177474 -281.231076)
			(xy 453.218663 -281.266772) (xy 453.254354 -281.307967) (xy 453.28382 -281.353821) (xy 453.30646 -281.403401)
			(xy 453.321814 -281.455699) (xy 453.32957 -281.509649) (xy 453.330056 -281.536902) (xy 453.329661 -281.562302)
			(xy 453.322919 -281.612651) (xy 453.309553 -281.661661) (xy 453.289802 -281.708463) (xy 453.264014 -281.752229)
			(xy 453.232645 -281.792186) (xy 453.21474 -281.810206) (xy 453.207628 -281.817064) (xy 453.199754 -281.834844)
			(xy 453.196452 -281.92476) (xy 453.203056 -281.943048) (xy 453.20966 -281.950414) (xy 453.227676 -281.971461)
			(xy 453.258054 -282.017792) (xy 453.281402 -282.068033) (xy 453.297228 -282.121126) (xy 453.3052 -282.175951)
			(xy 453.305672 -282.203652) (xy 453.3052 -282.230905) (xy 453.297449 -282.284858) (xy 453.282097 -282.337158)
			(xy 453.259457 -282.38674) (xy 453.229991 -282.432595) (xy 453.194298 -282.473789) (xy 453.153105 -282.509484)
			(xy 453.107251 -282.538951) (xy 453.057669 -282.561593) (xy 453.00537 -282.576946) (xy 452.951417 -282.584699)
			(xy 452.924164 -282.58516) (xy 452.895425 -282.584642) (xy 452.838598 -282.576016) (xy 452.783708 -282.558963)
			(xy 452.731996 -282.533871) (xy 452.684633 -282.501306) (xy 452.663306 -282.482036) (xy 452.656194 -282.475432)
			(xy 452.638668 -282.46832) (xy 452.54926 -282.46832) (xy 452.531734 -282.475432) (xy 452.524622 -282.482036)
			(xy 452.503295 -282.501306) (xy 452.455932 -282.533871) (xy 452.404221 -282.558962) (xy 452.34933 -282.576012)
			(xy 452.292503 -282.584634) (xy 452.235025 -282.584634) (xy 452.178198 -282.576012) (xy 452.123307 -282.558962)
			(xy 452.071596 -282.533871) (xy 452.024233 -282.501306) (xy 452.002906 -282.482036) (xy 451.995794 -282.475432)
			(xy 451.978268 -282.46832) (xy 451.88886 -282.46832) (xy 451.871334 -282.475432) (xy 451.864222 -282.482036)
			(xy 451.842895 -282.501306) (xy 451.795532 -282.533871) (xy 451.743821 -282.558962) (xy 451.68893 -282.576012)
			(xy 451.632103 -282.584634) (xy 451.574625 -282.584634) (xy 451.517798 -282.576012) (xy 451.462907 -282.558962)
			(xy 451.411196 -282.533871) (xy 451.363833 -282.501306) (xy 451.342506 -282.482036) (xy 451.335394 -282.475432)
			(xy 451.317868 -282.46832) (xy 451.22846 -282.46832) (xy 451.210934 -282.475432) (xy 451.203822 -282.482036)
			(xy 451.182506 -282.501319) (xy 451.135141 -282.533885) (xy 451.083427 -282.558975) (xy 451.028534 -282.576023)
			(xy 450.971704 -282.584642) (xy 450.942964 -282.58516) (xy 450.915708 -282.584778) (xy 450.861752 -282.577015)
			(xy 450.809449 -282.561652) (xy 450.759866 -282.539002) (xy 450.71401 -282.509526) (xy 450.672817 -282.473824)
			(xy 450.637124 -282.432622) (xy 450.607658 -282.38676) (xy 450.585018 -282.337172) (xy 450.569667 -282.284866)
			(xy 450.561916 -282.230908) (xy 450.561456 -282.203652) (xy 398.269744 -282.203652) (xy 398.257515 -282.241458)
			(xy 398.235908 -282.284073) (xy 398.207927 -282.322802) (xy 398.174255 -282.3567) (xy 398.135714 -282.384939)
			(xy 398.093244 -282.40683) (xy 398.047883 -282.421838) (xy 398.000738 -282.429598) (xy 397.976852 -282.43022)
			(xy 397.921988 -282.425902) (xy 397.898353 -282.421299) (xy 397.852821 -282.405644) (xy 397.81031 -282.383036)
			(xy 397.771875 -282.354035) (xy 397.754856 -282.337002) (xy 397.743934 -282.325572) (xy 397.713962 -282.319222)
			(xy 397.611854 -282.36037) (xy 397.602689 -282.364562) (xy 397.588371 -282.378725) (xy 397.58057 -282.397292)
			(xy 397.580104 -282.40736) (xy 397.580104 -282.792424) (xy 397.580529 -282.802503) (xy 397.588302 -282.821102)
			(xy 397.602667 -282.835242) (xy 397.611854 -282.839414) (xy 397.713962 -282.880562) (xy 397.744188 -282.874212)
			(xy 397.75511 -282.862782) (xy 397.77251 -282.84548) (xy 397.811807 -282.816098) (xy 397.855294 -282.793371)
			(xy 397.901852 -282.777883) (xy 397.950287 -282.770032) (xy 397.97482 -282.769564) (xy 398.000077 -282.770087)
			(xy 398.0499 -282.778404) (xy 398.097676 -282.794808) (xy 398.1421 -282.818852) (xy 398.18196 -282.849879)
			(xy 398.216171 -282.887044) (xy 398.243798 -282.929333) (xy 398.264088 -282.975592) (xy 398.276488 -283.024559)
			(xy 398.280657 -283.074872) (xy 398.61923 -283.074872) (xy 398.62319 -283.025818) (xy 398.634967 -282.978034)
			(xy 398.654258 -282.932758) (xy 398.680561 -282.891162) (xy 398.713196 -282.854325) (xy 398.751317 -282.8232)
			(xy 398.793938 -282.798593) (xy 398.839954 -282.781141) (xy 398.888173 -282.771297) (xy 398.937348 -282.769316)
			(xy 398.986203 -282.775248) (xy 399.033474 -282.78894) (xy 399.077936 -282.810038) (xy 399.118439 -282.837994)
			(xy 399.153932 -282.872086) (xy 399.183497 -282.91143) (xy 399.206368 -282.955007) (xy 399.221952 -283.001688)
			(xy 399.229847 -283.050265) (xy 399.230342 -283.074872) (xy 399.56919 -283.074872) (xy 399.57315 -283.025818)
			(xy 399.584927 -282.978034) (xy 399.604218 -282.932758) (xy 399.630521 -282.891162) (xy 399.663156 -282.854325)
			(xy 399.701277 -282.8232) (xy 399.743898 -282.798593) (xy 399.789914 -282.781141) (xy 399.838133 -282.771297)
			(xy 399.887308 -282.769316) (xy 399.936163 -282.775248) (xy 399.983434 -282.78894) (xy 400.027896 -282.810038)
			(xy 400.068399 -282.837994) (xy 400.103892 -282.872086) (xy 400.133457 -282.91143) (xy 400.156328 -282.955007)
			(xy 400.171912 -283.001688) (xy 400.179807 -283.050265) (xy 400.180302 -283.074872) (xy 400.51915 -283.074872)
			(xy 400.52311 -283.025818) (xy 400.534887 -282.978034) (xy 400.554178 -282.932758) (xy 400.580481 -282.891162)
			(xy 400.613116 -282.854325) (xy 400.651237 -282.8232) (xy 400.693858 -282.798593) (xy 400.739874 -282.781141)
			(xy 400.788093 -282.771297) (xy 400.837268 -282.769316) (xy 400.886123 -282.775248) (xy 400.933394 -282.78894)
			(xy 400.977856 -282.810038) (xy 401.018359 -282.837994) (xy 401.053852 -282.872086) (xy 401.083417 -282.91143)
			(xy 401.106288 -282.955007) (xy 401.121872 -283.001688) (xy 401.129767 -283.050265) (xy 401.130262 -283.074872)
			(xy 401.46911 -283.074872) (xy 401.47307 -283.025818) (xy 401.484847 -282.978034) (xy 401.504138 -282.932758)
			(xy 401.530441 -282.891162) (xy 401.563076 -282.854325) (xy 401.601197 -282.8232) (xy 401.643818 -282.798593)
			(xy 401.689834 -282.781141) (xy 401.738053 -282.771297) (xy 401.787228 -282.769316) (xy 401.836083 -282.775248)
			(xy 401.883354 -282.78894) (xy 401.927816 -282.810038) (xy 401.968319 -282.837994) (xy 402.003812 -282.872086)
			(xy 402.033377 -282.91143) (xy 402.056248 -282.955007) (xy 402.071832 -283.001688) (xy 402.079727 -283.050265)
			(xy 402.080056 -283.066644) (xy 402.419152 -283.066644) (xy 402.424516 -283.017288) (xy 402.437793 -282.969451)
			(xy 402.458636 -282.924391) (xy 402.486493 -282.883297) (xy 402.520631 -282.847251) (xy 402.560152 -282.817203)
			(xy 402.604013 -282.793944) (xy 402.651059 -282.778088) (xy 402.700051 -282.770052) (xy 402.724874 -282.769564)
			(xy 402.739057 -282.769745) (xy 402.767297 -282.772414) (xy 402.781262 -282.774898) (xy 402.793708 -282.777184)
			(xy 402.81733 -282.769818) (xy 402.8948 -282.692348) (xy 402.902166 -282.668726) (xy 402.89988 -282.65628)
			(xy 402.897404 -282.642314) (xy 402.894732 -282.614074) (xy 402.894546 -282.599892) (xy 402.895068 -282.574637)
			(xy 402.903381 -282.524815) (xy 402.919782 -282.477041) (xy 402.943823 -282.432618) (xy 402.974847 -282.392758)
			(xy 403.012009 -282.358548) (xy 403.054295 -282.330922) (xy 403.100551 -282.310632) (xy 403.149516 -282.298232)
			(xy 403.199854 -282.294061) (xy 403.250192 -282.298232) (xy 403.299157 -282.310632) (xy 403.345413 -282.330922)
			(xy 403.387699 -282.358548) (xy 403.424861 -282.392758) (xy 403.455885 -282.432618) (xy 403.479926 -282.477041)
			(xy 403.496327 -282.524815) (xy 403.50464 -282.574637) (xy 403.505162 -282.599892) (xy 422.843972 -282.599892)
			(xy 422.847932 -282.550838) (xy 422.859709 -282.503054) (xy 422.879 -282.457778) (xy 422.905303 -282.416182)
			(xy 422.937938 -282.379345) (xy 422.976059 -282.34822) (xy 423.01868 -282.323613) (xy 423.064696 -282.306161)
			(xy 423.112915 -282.296317) (xy 423.16209 -282.294336) (xy 423.210945 -282.300268) (xy 423.258216 -282.31396)
			(xy 423.302678 -282.335058) (xy 423.343181 -282.363014) (xy 423.378674 -282.397106) (xy 423.408239 -282.43645)
			(xy 423.43111 -282.480027) (xy 423.446694 -282.526708) (xy 423.454589 -282.575285) (xy 423.455084 -282.599892)
			(xy 423.794186 -282.599892) (xy 423.798146 -282.550838) (xy 423.809923 -282.503054) (xy 423.829214 -282.457778)
			(xy 423.855517 -282.416182) (xy 423.888152 -282.379345) (xy 423.926273 -282.34822) (xy 423.968894 -282.323613)
			(xy 424.01491 -282.306161) (xy 424.063129 -282.296317) (xy 424.112304 -282.294336) (xy 424.161159 -282.300268)
			(xy 424.20843 -282.31396) (xy 424.252892 -282.335058) (xy 424.293395 -282.363014) (xy 424.328888 -282.397106)
			(xy 424.358453 -282.43645) (xy 424.381324 -282.480027) (xy 424.396908 -282.526708) (xy 424.404803 -282.575285)
			(xy 424.405298 -282.599892) (xy 424.404803 -282.624499) (xy 424.404624 -282.6256) (xy 424.723302 -282.6256)
			(xy 424.723302 -282.574184) (xy 424.731345 -282.523402) (xy 424.747233 -282.474503) (xy 424.770576 -282.428691)
			(xy 424.800797 -282.387095) (xy 424.837153 -282.350739) (xy 424.878749 -282.320518) (xy 424.924561 -282.297175)
			(xy 424.97346 -282.281287) (xy 425.024242 -282.273244) (xy 425.075658 -282.273244) (xy 425.12644 -282.281287)
			(xy 425.175339 -282.297175) (xy 425.221151 -282.320518) (xy 425.262747 -282.350739) (xy 425.299103 -282.387095)
			(xy 425.329324 -282.428691) (xy 425.352667 -282.474503) (xy 425.368555 -282.523402) (xy 425.376598 -282.574184)
			(xy 425.377102 -282.599892) (xy 425.376598 -282.6256) (xy 425.673262 -282.6256) (xy 425.673262 -282.574184)
			(xy 425.681305 -282.523402) (xy 425.697193 -282.474503) (xy 425.720536 -282.428691) (xy 425.750757 -282.387095)
			(xy 425.787113 -282.350739) (xy 425.828709 -282.320518) (xy 425.874521 -282.297175) (xy 425.92342 -282.281287)
			(xy 425.974202 -282.273244) (xy 426.025618 -282.273244) (xy 426.0764 -282.281287) (xy 426.125299 -282.297175)
			(xy 426.171111 -282.320518) (xy 426.212707 -282.350739) (xy 426.249063 -282.387095) (xy 426.279284 -282.428691)
			(xy 426.302627 -282.474503) (xy 426.318515 -282.523402) (xy 426.326558 -282.574184) (xy 426.327062 -282.599892)
			(xy 426.644066 -282.599892) (xy 426.648026 -282.550838) (xy 426.659803 -282.503054) (xy 426.679094 -282.457778)
			(xy 426.705397 -282.416182) (xy 426.738032 -282.379345) (xy 426.776153 -282.34822) (xy 426.818774 -282.323613)
			(xy 426.86479 -282.306161) (xy 426.913009 -282.296317) (xy 426.962184 -282.294336) (xy 427.011039 -282.300268)
			(xy 427.05831 -282.31396) (xy 427.102772 -282.335058) (xy 427.143275 -282.363014) (xy 427.178768 -282.397106)
			(xy 427.208333 -282.43645) (xy 427.231204 -282.480027) (xy 427.246788 -282.526708) (xy 427.254683 -282.575285)
			(xy 427.255178 -282.599892) (xy 427.254683 -282.624499) (xy 427.254504 -282.6256) (xy 427.573182 -282.6256)
			(xy 427.573182 -282.574184) (xy 427.581225 -282.523402) (xy 427.597113 -282.474503) (xy 427.620456 -282.428691)
			(xy 427.650677 -282.387095) (xy 427.687033 -282.350739) (xy 427.728629 -282.320518) (xy 427.774441 -282.297175)
			(xy 427.82334 -282.281287) (xy 427.874122 -282.273244) (xy 427.925538 -282.273244) (xy 427.97632 -282.281287)
			(xy 428.025219 -282.297175) (xy 428.071031 -282.320518) (xy 428.112627 -282.350739) (xy 428.148983 -282.387095)
			(xy 428.179204 -282.428691) (xy 428.202547 -282.474503) (xy 428.218435 -282.523402) (xy 428.226478 -282.574184)
			(xy 428.226982 -282.599892) (xy 428.226478 -282.6256) (xy 428.523142 -282.6256) (xy 428.523142 -282.574184)
			(xy 428.531185 -282.523402) (xy 428.547073 -282.474503) (xy 428.570416 -282.428691) (xy 428.600637 -282.387095)
			(xy 428.636993 -282.350739) (xy 428.678589 -282.320518) (xy 428.724401 -282.297175) (xy 428.7733 -282.281287)
			(xy 428.824082 -282.273244) (xy 428.875498 -282.273244) (xy 428.92628 -282.281287) (xy 428.975179 -282.297175)
			(xy 429.020991 -282.320518) (xy 429.062587 -282.350739) (xy 429.098943 -282.387095) (xy 429.129164 -282.428691)
			(xy 429.152507 -282.474503) (xy 429.168395 -282.523402) (xy 429.176438 -282.574184) (xy 429.176942 -282.599892)
			(xy 429.4942 -282.599892) (xy 429.49816 -282.550838) (xy 429.509937 -282.503054) (xy 429.529228 -282.457778)
			(xy 429.555531 -282.416182) (xy 429.588166 -282.379345) (xy 429.626287 -282.34822) (xy 429.668908 -282.323613)
			(xy 429.714924 -282.306161) (xy 429.763143 -282.296317) (xy 429.812318 -282.294336) (xy 429.861173 -282.300268)
			(xy 429.908444 -282.31396) (xy 429.952906 -282.335058) (xy 429.993409 -282.363014) (xy 430.028902 -282.397106)
			(xy 430.058467 -282.43645) (xy 430.081338 -282.480027) (xy 430.096922 -282.526708) (xy 430.104817 -282.575285)
			(xy 430.105312 -282.599892) (xy 430.44416 -282.599892) (xy 430.44812 -282.550838) (xy 430.459897 -282.503054)
			(xy 430.479188 -282.457778) (xy 430.505491 -282.416182) (xy 430.538126 -282.379345) (xy 430.576247 -282.34822)
			(xy 430.618868 -282.323613) (xy 430.664884 -282.306161) (xy 430.713103 -282.296317) (xy 430.762278 -282.294336)
			(xy 430.811133 -282.300268) (xy 430.858404 -282.31396) (xy 430.902866 -282.335058) (xy 430.943369 -282.363014)
			(xy 430.978862 -282.397106) (xy 431.008427 -282.43645) (xy 431.031298 -282.480027) (xy 431.046882 -282.526708)
			(xy 431.054777 -282.575285) (xy 431.055272 -282.599892) (xy 431.054777 -282.624499) (xy 431.046882 -282.673076)
			(xy 431.031298 -282.719757) (xy 431.008427 -282.763334) (xy 430.978862 -282.802678) (xy 430.943369 -282.83677)
			(xy 430.902866 -282.864726) (xy 430.858404 -282.885824) (xy 430.811133 -282.899516) (xy 430.762278 -282.905448)
			(xy 430.713103 -282.903467) (xy 430.664884 -282.893623) (xy 430.618868 -282.876171) (xy 430.576247 -282.851564)
			(xy 430.538126 -282.820439) (xy 430.505491 -282.783602) (xy 430.479188 -282.742006) (xy 430.459897 -282.69673)
			(xy 430.44812 -282.648946) (xy 430.44416 -282.599892) (xy 430.105312 -282.599892) (xy 430.104817 -282.624499)
			(xy 430.096922 -282.673076) (xy 430.081338 -282.719757) (xy 430.058467 -282.763334) (xy 430.028902 -282.802678)
			(xy 429.993409 -282.83677) (xy 429.952906 -282.864726) (xy 429.908444 -282.885824) (xy 429.861173 -282.899516)
			(xy 429.812318 -282.905448) (xy 429.763143 -282.903467) (xy 429.714924 -282.893623) (xy 429.668908 -282.876171)
			(xy 429.626287 -282.851564) (xy 429.588166 -282.820439) (xy 429.555531 -282.783602) (xy 429.529228 -282.742006)
			(xy 429.509937 -282.69673) (xy 429.49816 -282.648946) (xy 429.4942 -282.599892) (xy 429.176942 -282.599892)
			(xy 429.176438 -282.6256) (xy 429.168395 -282.676382) (xy 429.152507 -282.725281) (xy 429.129164 -282.771093)
			(xy 429.098943 -282.812689) (xy 429.062587 -282.849045) (xy 429.020991 -282.879266) (xy 428.975179 -282.902609)
			(xy 428.92628 -282.918497) (xy 428.875498 -282.92654) (xy 428.824082 -282.92654) (xy 428.7733 -282.918497)
			(xy 428.724401 -282.902609) (xy 428.678589 -282.879266) (xy 428.636993 -282.849045) (xy 428.600637 -282.812689)
			(xy 428.570416 -282.771093) (xy 428.547073 -282.725281) (xy 428.531185 -282.676382) (xy 428.523142 -282.6256)
			(xy 428.226478 -282.6256) (xy 428.218435 -282.676382) (xy 428.202547 -282.725281) (xy 428.179204 -282.771093)
			(xy 428.148983 -282.812689) (xy 428.112627 -282.849045) (xy 428.071031 -282.879266) (xy 428.025219 -282.902609)
			(xy 427.97632 -282.918497) (xy 427.925538 -282.92654) (xy 427.874122 -282.92654) (xy 427.82334 -282.918497)
			(xy 427.774441 -282.902609) (xy 427.728629 -282.879266) (xy 427.687033 -282.849045) (xy 427.650677 -282.812689)
			(xy 427.620456 -282.771093) (xy 427.597113 -282.725281) (xy 427.581225 -282.676382) (xy 427.573182 -282.6256)
			(xy 427.254504 -282.6256) (xy 427.246788 -282.673076) (xy 427.231204 -282.719757) (xy 427.208333 -282.763334)
			(xy 427.178768 -282.802678) (xy 427.143275 -282.83677) (xy 427.102772 -282.864726) (xy 427.05831 -282.885824)
			(xy 427.011039 -282.899516) (xy 426.962184 -282.905448) (xy 426.913009 -282.903467) (xy 426.86479 -282.893623)
			(xy 426.818774 -282.876171) (xy 426.776153 -282.851564) (xy 426.738032 -282.820439) (xy 426.705397 -282.783602)
			(xy 426.679094 -282.742006) (xy 426.659803 -282.69673) (xy 426.648026 -282.648946) (xy 426.644066 -282.599892)
			(xy 426.327062 -282.599892) (xy 426.326558 -282.6256) (xy 426.318515 -282.676382) (xy 426.302627 -282.725281)
			(xy 426.279284 -282.771093) (xy 426.249063 -282.812689) (xy 426.212707 -282.849045) (xy 426.171111 -282.879266)
			(xy 426.125299 -282.902609) (xy 426.0764 -282.918497) (xy 426.025618 -282.92654) (xy 425.974202 -282.92654)
			(xy 425.92342 -282.918497) (xy 425.874521 -282.902609) (xy 425.828709 -282.879266) (xy 425.787113 -282.849045)
			(xy 425.750757 -282.812689) (xy 425.720536 -282.771093) (xy 425.697193 -282.725281) (xy 425.681305 -282.676382)
			(xy 425.673262 -282.6256) (xy 425.376598 -282.6256) (xy 425.368555 -282.676382) (xy 425.352667 -282.725281)
			(xy 425.329324 -282.771093) (xy 425.299103 -282.812689) (xy 425.262747 -282.849045) (xy 425.221151 -282.879266)
			(xy 425.175339 -282.902609) (xy 425.12644 -282.918497) (xy 425.075658 -282.92654) (xy 425.024242 -282.92654)
			(xy 424.97346 -282.918497) (xy 424.924561 -282.902609) (xy 424.878749 -282.879266) (xy 424.837153 -282.849045)
			(xy 424.800797 -282.812689) (xy 424.770576 -282.771093) (xy 424.747233 -282.725281) (xy 424.731345 -282.676382)
			(xy 424.723302 -282.6256) (xy 424.404624 -282.6256) (xy 424.396908 -282.673076) (xy 424.381324 -282.719757)
			(xy 424.358453 -282.763334) (xy 424.328888 -282.802678) (xy 424.293395 -282.83677) (xy 424.252892 -282.864726)
			(xy 424.20843 -282.885824) (xy 424.161159 -282.899516) (xy 424.112304 -282.905448) (xy 424.063129 -282.903467)
			(xy 424.01491 -282.893623) (xy 423.968894 -282.876171) (xy 423.926273 -282.851564) (xy 423.888152 -282.820439)
			(xy 423.855517 -282.783602) (xy 423.829214 -282.742006) (xy 423.809923 -282.69673) (xy 423.798146 -282.648946)
			(xy 423.794186 -282.599892) (xy 423.455084 -282.599892) (xy 423.454589 -282.624499) (xy 423.446694 -282.673076)
			(xy 423.43111 -282.719757) (xy 423.408239 -282.763334) (xy 423.378674 -282.802678) (xy 423.343181 -282.83677)
			(xy 423.302678 -282.864726) (xy 423.258216 -282.885824) (xy 423.210945 -282.899516) (xy 423.16209 -282.905448)
			(xy 423.112915 -282.903467) (xy 423.064696 -282.893623) (xy 423.01868 -282.876171) (xy 422.976059 -282.851564)
			(xy 422.937938 -282.820439) (xy 422.905303 -282.783602) (xy 422.879 -282.742006) (xy 422.859709 -282.69673)
			(xy 422.847932 -282.648946) (xy 422.843972 -282.599892) (xy 403.505162 -282.599892) (xy 403.504985 -282.614075)
			(xy 403.502313 -282.642315) (xy 403.499828 -282.65628) (xy 403.497542 -282.668726) (xy 403.504908 -282.692348)
			(xy 403.582378 -282.769818) (xy 403.606 -282.777184) (xy 403.618446 -282.774898) (xy 403.632411 -282.772419)
			(xy 403.660651 -282.769749) (xy 403.674834 -282.769564) (xy 403.699652 -282.770115) (xy 403.748633 -282.77815)
			(xy 403.795669 -282.794004) (xy 403.839521 -282.817259) (xy 403.879032 -282.847302) (xy 403.913163 -282.883341)
			(xy 403.941014 -282.924427) (xy 403.96185 -282.969478) (xy 403.975124 -283.017306) (xy 403.980486 -283.066651)
			(xy 403.980039 -283.074872) (xy 404.319244 -283.074872) (xy 404.323204 -283.025818) (xy 404.334981 -282.978034)
			(xy 404.354272 -282.932758) (xy 404.380575 -282.891162) (xy 404.41321 -282.854325) (xy 404.451331 -282.8232)
			(xy 404.493952 -282.798593) (xy 404.539968 -282.781141) (xy 404.588187 -282.771297) (xy 404.637362 -282.769316)
			(xy 404.686217 -282.775248) (xy 404.733488 -282.78894) (xy 404.77795 -282.810038) (xy 404.818453 -282.837994)
			(xy 404.853946 -282.872086) (xy 404.883511 -282.91143) (xy 404.906382 -282.955007) (xy 404.921966 -283.001688)
			(xy 404.929861 -283.050265) (xy 404.930356 -283.074872) (xy 405.269204 -283.074872) (xy 405.273164 -283.025818)
			(xy 405.284941 -282.978034) (xy 405.304232 -282.932758) (xy 405.330535 -282.891162) (xy 405.36317 -282.854325)
			(xy 405.401291 -282.8232) (xy 405.443912 -282.798593) (xy 405.489928 -282.781141) (xy 405.538147 -282.771297)
			(xy 405.587322 -282.769316) (xy 405.636177 -282.775248) (xy 405.683448 -282.78894) (xy 405.72791 -282.810038)
			(xy 405.768413 -282.837994) (xy 405.803906 -282.872086) (xy 405.833471 -282.91143) (xy 405.856342 -282.955007)
			(xy 405.871926 -283.001688) (xy 405.879821 -283.050265) (xy 405.880316 -283.074872) (xy 406.219164 -283.074872)
			(xy 406.223124 -283.025818) (xy 406.234901 -282.978034) (xy 406.254192 -282.932758) (xy 406.280495 -282.891162)
			(xy 406.31313 -282.854325) (xy 406.351251 -282.8232) (xy 406.393872 -282.798593) (xy 406.439888 -282.781141)
			(xy 406.488107 -282.771297) (xy 406.537282 -282.769316) (xy 406.586137 -282.775248) (xy 406.633408 -282.78894)
			(xy 406.67787 -282.810038) (xy 406.718373 -282.837994) (xy 406.753866 -282.872086) (xy 406.783431 -282.91143)
			(xy 406.806302 -282.955007) (xy 406.821886 -283.001688) (xy 406.829781 -283.050265) (xy 406.830276 -283.074872)
			(xy 408.119084 -283.074872) (xy 408.123044 -283.025818) (xy 408.134821 -282.978034) (xy 408.154112 -282.932758)
			(xy 408.180415 -282.891162) (xy 408.21305 -282.854325) (xy 408.251171 -282.8232) (xy 408.293792 -282.798593)
			(xy 408.339808 -282.781141) (xy 408.388027 -282.771297) (xy 408.437202 -282.769316) (xy 408.486057 -282.775248)
			(xy 408.533328 -282.78894) (xy 408.57779 -282.810038) (xy 408.618293 -282.837994) (xy 408.653786 -282.872086)
			(xy 408.683351 -282.91143) (xy 408.706222 -282.955007) (xy 408.721806 -283.001688) (xy 408.729701 -283.050265)
			(xy 408.730196 -283.074872) (xy 409.069044 -283.074872) (xy 409.073004 -283.025818) (xy 409.084781 -282.978034)
			(xy 409.104072 -282.932758) (xy 409.130375 -282.891162) (xy 409.16301 -282.854325) (xy 409.201131 -282.8232)
			(xy 409.243752 -282.798593) (xy 409.289768 -282.781141) (xy 409.337987 -282.771297) (xy 409.387162 -282.769316)
			(xy 409.436017 -282.775248) (xy 409.483288 -282.78894) (xy 409.52775 -282.810038) (xy 409.568253 -282.837994)
			(xy 409.603746 -282.872086) (xy 409.633311 -282.91143) (xy 409.656182 -282.955007) (xy 409.671766 -283.001688)
			(xy 409.679661 -283.050265) (xy 409.680156 -283.074872) (xy 410.019004 -283.074872) (xy 410.022964 -283.025818)
			(xy 410.034741 -282.978034) (xy 410.054032 -282.932758) (xy 410.080335 -282.891162) (xy 410.11297 -282.854325)
			(xy 410.151091 -282.8232) (xy 410.193712 -282.798593) (xy 410.239728 -282.781141) (xy 410.287947 -282.771297)
			(xy 410.337122 -282.769316) (xy 410.385977 -282.775248) (xy 410.433248 -282.78894) (xy 410.47771 -282.810038)
			(xy 410.518213 -282.837994) (xy 410.553706 -282.872086) (xy 410.583271 -282.91143) (xy 410.606142 -282.955007)
			(xy 410.621726 -283.001688) (xy 410.629621 -283.050265) (xy 410.630116 -283.074872) (xy 410.969218 -283.074872)
			(xy 410.973178 -283.025818) (xy 410.984955 -282.978034) (xy 411.004246 -282.932758) (xy 411.030549 -282.891162)
			(xy 411.063184 -282.854325) (xy 411.101305 -282.8232) (xy 411.143926 -282.798593) (xy 411.189942 -282.781141)
			(xy 411.238161 -282.771297) (xy 411.287336 -282.769316) (xy 411.336191 -282.775248) (xy 411.383462 -282.78894)
			(xy 411.427924 -282.810038) (xy 411.468427 -282.837994) (xy 411.50392 -282.872086) (xy 411.533485 -282.91143)
			(xy 411.556356 -282.955007) (xy 411.57194 -283.001688) (xy 411.579835 -283.050265) (xy 411.58033 -283.074872)
			(xy 411.919178 -283.074872) (xy 411.923138 -283.025818) (xy 411.934915 -282.978034) (xy 411.954206 -282.932758)
			(xy 411.980509 -282.891162) (xy 412.013144 -282.854325) (xy 412.051265 -282.8232) (xy 412.093886 -282.798593)
			(xy 412.139902 -282.781141) (xy 412.188121 -282.771297) (xy 412.237296 -282.769316) (xy 412.286151 -282.775248)
			(xy 412.333422 -282.78894) (xy 412.377884 -282.810038) (xy 412.418387 -282.837994) (xy 412.45388 -282.872086)
			(xy 412.483445 -282.91143) (xy 412.506316 -282.955007) (xy 412.5219 -283.001688) (xy 412.529795 -283.050265)
			(xy 412.53029 -283.074872) (xy 412.869138 -283.074872) (xy 412.873098 -283.025818) (xy 412.884875 -282.978034)
			(xy 412.904166 -282.932758) (xy 412.930469 -282.891162) (xy 412.963104 -282.854325) (xy 413.001225 -282.8232)
			(xy 413.043846 -282.798593) (xy 413.089862 -282.781141) (xy 413.138081 -282.771297) (xy 413.187256 -282.769316)
			(xy 413.236111 -282.775248) (xy 413.283382 -282.78894) (xy 413.327844 -282.810038) (xy 413.368347 -282.837994)
			(xy 413.40384 -282.872086) (xy 413.433405 -282.91143) (xy 413.456276 -282.955007) (xy 413.47186 -283.001688)
			(xy 413.479755 -283.050265) (xy 413.48025 -283.074872) (xy 413.819098 -283.074872) (xy 413.823058 -283.025818)
			(xy 413.834835 -282.978034) (xy 413.854126 -282.932758) (xy 413.880429 -282.891162) (xy 413.913064 -282.854325)
			(xy 413.951185 -282.8232) (xy 413.993806 -282.798593) (xy 414.039822 -282.781141) (xy 414.088041 -282.771297)
			(xy 414.137216 -282.769316) (xy 414.186071 -282.775248) (xy 414.233342 -282.78894) (xy 414.277804 -282.810038)
			(xy 414.318307 -282.837994) (xy 414.3538 -282.872086) (xy 414.383365 -282.91143) (xy 414.406236 -282.955007)
			(xy 414.42182 -283.001688) (xy 414.429715 -283.050265) (xy 414.43021 -283.074872) (xy 414.769058 -283.074872)
			(xy 414.773018 -283.025818) (xy 414.784795 -282.978034) (xy 414.804086 -282.932758) (xy 414.830389 -282.891162)
			(xy 414.863024 -282.854325) (xy 414.901145 -282.8232) (xy 414.943766 -282.798593) (xy 414.989782 -282.781141)
			(xy 415.038001 -282.771297) (xy 415.087176 -282.769316) (xy 415.136031 -282.775248) (xy 415.183302 -282.78894)
			(xy 415.227764 -282.810038) (xy 415.268267 -282.837994) (xy 415.30376 -282.872086) (xy 415.333325 -282.91143)
			(xy 415.356196 -282.955007) (xy 415.37178 -283.001688) (xy 415.379675 -283.050265) (xy 415.38017 -283.074872)
			(xy 415.719018 -283.074872) (xy 415.722978 -283.025818) (xy 415.734755 -282.978034) (xy 415.754046 -282.932758)
			(xy 415.780349 -282.891162) (xy 415.812984 -282.854325) (xy 415.851105 -282.8232) (xy 415.893726 -282.798593)
			(xy 415.939742 -282.781141) (xy 415.987961 -282.771297) (xy 416.037136 -282.769316) (xy 416.085991 -282.775248)
			(xy 416.133262 -282.78894) (xy 416.177724 -282.810038) (xy 416.218227 -282.837994) (xy 416.25372 -282.872086)
			(xy 416.283285 -282.91143) (xy 416.306156 -282.955007) (xy 416.32174 -283.001688) (xy 416.329635 -283.050265)
			(xy 416.33013 -283.074872) (xy 416.668978 -283.074872) (xy 416.672938 -283.025818) (xy 416.684715 -282.978034)
			(xy 416.704006 -282.932758) (xy 416.730309 -282.891162) (xy 416.762944 -282.854325) (xy 416.801065 -282.8232)
			(xy 416.843686 -282.798593) (xy 416.889702 -282.781141) (xy 416.937921 -282.771297) (xy 416.987096 -282.769316)
			(xy 417.035951 -282.775248) (xy 417.083222 -282.78894) (xy 417.127684 -282.810038) (xy 417.168187 -282.837994)
			(xy 417.20368 -282.872086) (xy 417.233245 -282.91143) (xy 417.256116 -282.955007) (xy 417.2717 -283.001688)
			(xy 417.279595 -283.050265) (xy 417.28009 -283.074872) (xy 417.619192 -283.074872) (xy 417.623152 -283.025818)
			(xy 417.634929 -282.978034) (xy 417.65422 -282.932758) (xy 417.680523 -282.891162) (xy 417.713158 -282.854325)
			(xy 417.751279 -282.8232) (xy 417.7939 -282.798593) (xy 417.839916 -282.781141) (xy 417.888135 -282.771297)
			(xy 417.93731 -282.769316) (xy 417.986165 -282.775248) (xy 418.033436 -282.78894) (xy 418.077898 -282.810038)
			(xy 418.118401 -282.837994) (xy 418.153894 -282.872086) (xy 418.183459 -282.91143) (xy 418.20633 -282.955007)
			(xy 418.221914 -283.001688) (xy 418.229809 -283.050265) (xy 418.230304 -283.074872) (xy 418.569152 -283.074872)
			(xy 418.573112 -283.025818) (xy 418.584889 -282.978034) (xy 418.60418 -282.932758) (xy 418.630483 -282.891162)
			(xy 418.663118 -282.854325) (xy 418.701239 -282.8232) (xy 418.74386 -282.798593) (xy 418.789876 -282.781141)
			(xy 418.838095 -282.771297) (xy 418.88727 -282.769316) (xy 418.936125 -282.775248) (xy 418.983396 -282.78894)
			(xy 419.027858 -282.810038) (xy 419.068361 -282.837994) (xy 419.103854 -282.872086) (xy 419.133419 -282.91143)
			(xy 419.15629 -282.955007) (xy 419.171874 -283.001688) (xy 419.179769 -283.050265) (xy 419.180264 -283.074872)
			(xy 419.519112 -283.074872) (xy 419.523072 -283.025818) (xy 419.534849 -282.978034) (xy 419.55414 -282.932758)
			(xy 419.580443 -282.891162) (xy 419.613078 -282.854325) (xy 419.651199 -282.8232) (xy 419.69382 -282.798593)
			(xy 419.739836 -282.781141) (xy 419.788055 -282.771297) (xy 419.83723 -282.769316) (xy 419.886085 -282.775248)
			(xy 419.933356 -282.78894) (xy 419.977818 -282.810038) (xy 420.018321 -282.837994) (xy 420.053814 -282.872086)
			(xy 420.083379 -282.91143) (xy 420.10625 -282.955007) (xy 420.121834 -283.001688) (xy 420.129729 -283.050265)
			(xy 420.130224 -283.074872) (xy 420.469072 -283.074872) (xy 420.473032 -283.025818) (xy 420.484809 -282.978034)
			(xy 420.5041 -282.932758) (xy 420.530403 -282.891162) (xy 420.563038 -282.854325) (xy 420.601159 -282.8232)
			(xy 420.64378 -282.798593) (xy 420.689796 -282.781141) (xy 420.738015 -282.771297) (xy 420.78719 -282.769316)
			(xy 420.836045 -282.775248) (xy 420.883316 -282.78894) (xy 420.927778 -282.810038) (xy 420.968281 -282.837994)
			(xy 421.003774 -282.872086) (xy 421.033339 -282.91143) (xy 421.05621 -282.955007) (xy 421.071794 -283.001688)
			(xy 421.079689 -283.050265) (xy 421.080184 -283.074872) (xy 421.079689 -283.099479) (xy 421.074265 -283.132854)
			(xy 456.388661 -283.132854) (xy 456.388661 -283.078346) (xy 456.396419 -283.024394) (xy 456.411776 -282.972095)
			(xy 456.43442 -282.922514) (xy 456.46389 -282.876661) (xy 456.499585 -282.835468) (xy 456.54078 -282.799775)
			(xy 456.586636 -282.770308) (xy 456.636218 -282.747667) (xy 456.688518 -282.732314) (xy 456.74247 -282.72456)
			(xy 456.769724 -282.724098) (xy 456.798463 -282.724608) (xy 456.855291 -282.733234) (xy 456.910182 -282.750287)
			(xy 456.961894 -282.775382) (xy 457.009256 -282.80795) (xy 457.030582 -282.827222) (xy 457.037694 -282.833826)
			(xy 457.05522 -282.840938) (xy 457.144628 -282.840938) (xy 457.162154 -282.833826) (xy 457.169266 -282.827222)
			(xy 457.190593 -282.807952) (xy 457.237956 -282.775387) (xy 457.289667 -282.750296) (xy 457.344558 -282.733246)
			(xy 457.401385 -282.724624) (xy 457.458863 -282.724624) (xy 457.51569 -282.733246) (xy 457.570581 -282.750296)
			(xy 457.622292 -282.775387) (xy 457.669655 -282.807952) (xy 457.690982 -282.827222) (xy 457.698094 -282.833826)
			(xy 457.71562 -282.840938) (xy 457.805028 -282.840938) (xy 457.822554 -282.833826) (xy 457.829666 -282.827222)
			(xy 457.850981 -282.807937) (xy 457.898346 -282.775373) (xy 457.950061 -282.750284) (xy 458.004955 -282.733237)
			(xy 458.061784 -282.724617) (xy 458.090524 -282.724098) (xy 458.120649 -282.724639) (xy 458.180147 -282.734126)
			(xy 458.237416 -282.752843) (xy 458.291033 -282.780325) (xy 458.339665 -282.815891) (xy 458.361288 -282.836874)
			(xy 458.3684 -282.84424) (xy 458.387196 -282.85186) (xy 458.479652 -282.85186) (xy 458.498448 -282.84424)
			(xy 458.50556 -282.836874) (xy 458.527192 -282.815901) (xy 458.575817 -282.780329) (xy 458.629432 -282.752846)
			(xy 458.686701 -282.734137) (xy 458.7462 -282.724666) (xy 458.776324 -282.724098) (xy 458.803575 -282.724573)
			(xy 458.857521 -282.732333) (xy 458.909813 -282.74769) (xy 458.959388 -282.770333) (xy 459.005236 -282.799801)
			(xy 459.046424 -282.835493) (xy 459.082114 -282.876683) (xy 459.111578 -282.922533) (xy 459.134218 -282.972109)
			(xy 459.149572 -283.024403) (xy 459.157328 -283.078349) (xy 459.157328 -283.132851) (xy 459.157328 -283.132853)
			(xy 460.636061 -283.132853) (xy 460.636061 -283.078347) (xy 460.643819 -283.024396) (xy 460.659175 -282.972098)
			(xy 460.681818 -282.922518) (xy 460.711287 -282.876665) (xy 460.746981 -282.835472) (xy 460.788174 -282.799779)
			(xy 460.834028 -282.770312) (xy 460.883609 -282.747671) (xy 460.935908 -282.732316) (xy 460.989859 -282.724561)
			(xy 461.017112 -282.724098) (xy 461.045851 -282.724615) (xy 461.102679 -282.733239) (xy 461.15757 -282.750291)
			(xy 461.209281 -282.775384) (xy 461.256643 -282.807951) (xy 461.27797 -282.827222) (xy 461.285082 -282.833826)
			(xy 461.302608 -282.840938) (xy 461.392016 -282.840938) (xy 461.409542 -282.833826) (xy 461.416654 -282.827222)
			(xy 461.437981 -282.807952) (xy 461.485344 -282.775387) (xy 461.537055 -282.750296) (xy 461.591946 -282.733246)
			(xy 461.648773 -282.724624) (xy 461.706251 -282.724624) (xy 461.763078 -282.733246) (xy 461.817969 -282.750296)
			(xy 461.86968 -282.775387) (xy 461.917043 -282.807952) (xy 461.93837 -282.827222) (xy 461.945482 -282.833826)
			(xy 461.963008 -282.840938) (xy 462.052416 -282.840938) (xy 462.069942 -282.833826) (xy 462.077054 -282.827222)
			(xy 462.098374 -282.807943) (xy 462.145738 -282.775378) (xy 462.197452 -282.750288) (xy 462.252344 -282.733239)
			(xy 462.309173 -282.724618) (xy 462.337912 -282.724098) (xy 462.368036 -282.724647) (xy 462.427534 -282.734131)
			(xy 462.484803 -282.752846) (xy 462.53842 -282.780328) (xy 462.587053 -282.815892) (xy 462.608676 -282.836874)
			(xy 462.615788 -282.84424) (xy 462.634584 -282.85186) (xy 462.72704 -282.85186) (xy 462.745836 -282.84424)
			(xy 462.752948 -282.836874) (xy 462.774585 -282.815907) (xy 462.823209 -282.780334) (xy 462.876822 -282.75285)
			(xy 462.93409 -282.734139) (xy 462.993588 -282.724667) (xy 463.023712 -282.724098) (xy 463.050963 -282.724573)
			(xy 463.10491 -282.732331) (xy 463.157205 -282.747687) (xy 463.206781 -282.770329) (xy 463.252631 -282.799796)
			(xy 463.29382 -282.835488) (xy 463.329511 -282.876679) (xy 463.358977 -282.92253) (xy 463.381617 -282.972107)
			(xy 463.396972 -283.024401) (xy 463.404728 -283.078349) (xy 463.404728 -283.132851) (xy 463.396972 -283.186799)
			(xy 463.381617 -283.239093) (xy 463.358977 -283.28867) (xy 463.329511 -283.334521) (xy 463.29382 -283.375712)
			(xy 463.252631 -283.411404) (xy 463.206781 -283.440871) (xy 463.157205 -283.463513) (xy 463.10491 -283.478869)
			(xy 463.050963 -283.486627) (xy 463.023712 -283.487114) (xy 462.993588 -283.486546) (xy 462.934091 -283.477066)
			(xy 462.876823 -283.458355) (xy 462.823206 -283.430878) (xy 462.774572 -283.395318) (xy 462.752948 -283.374338)
			(xy 462.745836 -283.366972) (xy 462.72704 -283.359352) (xy 462.634584 -283.359352) (xy 462.615788 -283.366972)
			(xy 462.608676 -283.374338) (xy 462.58703 -283.395296) (xy 462.538408 -283.43087) (xy 462.484797 -283.458355)
			(xy 462.427531 -283.477068) (xy 462.368035 -283.486544) (xy 462.337912 -283.487114) (xy 462.309174 -283.486579)
			(xy 462.252347 -283.477959) (xy 462.197456 -283.460911) (xy 462.145744 -283.435822) (xy 462.098381 -283.403259)
			(xy 462.077054 -283.38399) (xy 462.069942 -283.377386) (xy 462.052416 -283.370274) (xy 461.963008 -283.370274)
			(xy 461.945482 -283.377386) (xy 461.93837 -283.38399) (xy 461.917043 -283.40326) (xy 461.86968 -283.435825)
			(xy 461.817969 -283.460916) (xy 461.763078 -283.477966) (xy 461.706251 -283.486588) (xy 461.648773 -283.486588)
			(xy 461.591946 -283.477966) (xy 461.537055 -283.460916) (xy 461.485344 -283.435825) (xy 461.437981 -283.40326)
			(xy 461.416654 -283.38399) (xy 461.409542 -283.377386) (xy 461.392016 -283.370274) (xy 461.302608 -283.370274)
			(xy 461.285082 -283.377386) (xy 461.27797 -283.38399) (xy 461.256642 -283.40326) (xy 461.20928 -283.435825)
			(xy 461.157568 -283.460917) (xy 461.102678 -283.477968) (xy 461.045851 -283.486592) (xy 461.017112 -283.487114)
			(xy 460.989859 -283.486639) (xy 460.935908 -283.478884) (xy 460.883609 -283.463529) (xy 460.834028 -283.440888)
			(xy 460.788174 -283.411421) (xy 460.746981 -283.375728) (xy 460.711287 -283.334535) (xy 460.681818 -283.288682)
			(xy 460.659175 -283.239102) (xy 460.643819 -283.186804) (xy 460.636061 -283.132853) (xy 459.157328 -283.132853)
			(xy 459.149572 -283.186797) (xy 459.134218 -283.239091) (xy 459.111578 -283.288667) (xy 459.082114 -283.334517)
			(xy 459.046424 -283.375707) (xy 459.005236 -283.411399) (xy 458.959388 -283.440867) (xy 458.909813 -283.46351)
			(xy 458.857521 -283.478867) (xy 458.803575 -283.486627) (xy 458.776324 -283.487114) (xy 458.746201 -283.486538)
			(xy 458.686704 -283.47706) (xy 458.629436 -283.458351) (xy 458.575819 -283.430876) (xy 458.527185 -283.395317)
			(xy 458.50556 -283.374338) (xy 458.498448 -283.366972) (xy 458.479652 -283.359352) (xy 458.387196 -283.359352)
			(xy 458.3684 -283.366972) (xy 458.361288 -283.374338) (xy 458.339681 -283.395338) (xy 458.291049 -283.430906)
			(xy 458.237428 -283.458384) (xy 458.180153 -283.477087) (xy 458.12065 -283.486551) (xy 458.090524 -283.487114)
			(xy 458.061786 -283.486572) (xy 458.004959 -283.477953) (xy 457.950069 -283.460907) (xy 457.898357 -283.43582)
			(xy 457.850994 -283.403259) (xy 457.829666 -283.38399) (xy 457.822554 -283.377386) (xy 457.805028 -283.370274)
			(xy 457.71562 -283.370274) (xy 457.698094 -283.377386) (xy 457.690982 -283.38399) (xy 457.669655 -283.40326)
			(xy 457.622292 -283.435825) (xy 457.570581 -283.460916) (xy 457.51569 -283.477966) (xy 457.458863 -283.486588)
			(xy 457.401385 -283.486588) (xy 457.344558 -283.477966) (xy 457.289667 -283.460916) (xy 457.237956 -283.435825)
			(xy 457.190593 -283.40326) (xy 457.169266 -283.38399) (xy 457.162154 -283.377386) (xy 457.144628 -283.370274)
			(xy 457.05522 -283.370274) (xy 457.037694 -283.377386) (xy 457.030582 -283.38399) (xy 457.009249 -283.403254)
			(xy 456.961888 -283.43582) (xy 456.910178 -283.460913) (xy 456.855289 -283.477966) (xy 456.798463 -283.486591)
			(xy 456.769724 -283.487114) (xy 456.74247 -283.48664) (xy 456.688518 -283.478886) (xy 456.636218 -283.463533)
			(xy 456.586636 -283.440892) (xy 456.54078 -283.411425) (xy 456.499585 -283.375732) (xy 456.46389 -283.334539)
			(xy 456.43442 -283.288686) (xy 456.411776 -283.239105) (xy 456.396419 -283.186806) (xy 456.388661 -283.132854)
			(xy 421.074265 -283.132854) (xy 421.071794 -283.148056) (xy 421.05621 -283.194737) (xy 421.033339 -283.238314)
			(xy 421.003774 -283.277658) (xy 420.968281 -283.31175) (xy 420.927778 -283.339706) (xy 420.883316 -283.360804)
			(xy 420.836045 -283.374496) (xy 420.78719 -283.380428) (xy 420.738015 -283.378447) (xy 420.689796 -283.368603)
			(xy 420.64378 -283.351151) (xy 420.601159 -283.326544) (xy 420.563038 -283.295419) (xy 420.530403 -283.258582)
			(xy 420.5041 -283.216986) (xy 420.484809 -283.17171) (xy 420.473032 -283.123926) (xy 420.469072 -283.074872)
			(xy 420.130224 -283.074872) (xy 420.129729 -283.099479) (xy 420.121834 -283.148056) (xy 420.10625 -283.194737)
			(xy 420.083379 -283.238314) (xy 420.053814 -283.277658) (xy 420.018321 -283.31175) (xy 419.977818 -283.339706)
			(xy 419.933356 -283.360804) (xy 419.886085 -283.374496) (xy 419.83723 -283.380428) (xy 419.788055 -283.378447)
			(xy 419.739836 -283.368603) (xy 419.69382 -283.351151) (xy 419.651199 -283.326544) (xy 419.613078 -283.295419)
			(xy 419.580443 -283.258582) (xy 419.55414 -283.216986) (xy 419.534849 -283.17171) (xy 419.523072 -283.123926)
			(xy 419.519112 -283.074872) (xy 419.180264 -283.074872) (xy 419.179769 -283.099479) (xy 419.171874 -283.148056)
			(xy 419.15629 -283.194737) (xy 419.133419 -283.238314) (xy 419.103854 -283.277658) (xy 419.068361 -283.31175)
			(xy 419.027858 -283.339706) (xy 418.983396 -283.360804) (xy 418.936125 -283.374496) (xy 418.88727 -283.380428)
			(xy 418.838095 -283.378447) (xy 418.789876 -283.368603) (xy 418.74386 -283.351151) (xy 418.701239 -283.326544)
			(xy 418.663118 -283.295419) (xy 418.630483 -283.258582) (xy 418.60418 -283.216986) (xy 418.584889 -283.17171)
			(xy 418.573112 -283.123926) (xy 418.569152 -283.074872) (xy 418.230304 -283.074872) (xy 418.229809 -283.099479)
			(xy 418.221914 -283.148056) (xy 418.20633 -283.194737) (xy 418.183459 -283.238314) (xy 418.153894 -283.277658)
			(xy 418.118401 -283.31175) (xy 418.077898 -283.339706) (xy 418.033436 -283.360804) (xy 417.986165 -283.374496)
			(xy 417.93731 -283.380428) (xy 417.888135 -283.378447) (xy 417.839916 -283.368603) (xy 417.7939 -283.351151)
			(xy 417.751279 -283.326544) (xy 417.713158 -283.295419) (xy 417.680523 -283.258582) (xy 417.65422 -283.216986)
			(xy 417.634929 -283.17171) (xy 417.623152 -283.123926) (xy 417.619192 -283.074872) (xy 417.28009 -283.074872)
			(xy 417.279595 -283.099479) (xy 417.2717 -283.148056) (xy 417.256116 -283.194737) (xy 417.233245 -283.238314)
			(xy 417.20368 -283.277658) (xy 417.168187 -283.31175) (xy 417.127684 -283.339706) (xy 417.083222 -283.360804)
			(xy 417.035951 -283.374496) (xy 416.987096 -283.380428) (xy 416.937921 -283.378447) (xy 416.889702 -283.368603)
			(xy 416.843686 -283.351151) (xy 416.801065 -283.326544) (xy 416.762944 -283.295419) (xy 416.730309 -283.258582)
			(xy 416.704006 -283.216986) (xy 416.684715 -283.17171) (xy 416.672938 -283.123926) (xy 416.668978 -283.074872)
			(xy 416.33013 -283.074872) (xy 416.329635 -283.099479) (xy 416.32174 -283.148056) (xy 416.306156 -283.194737)
			(xy 416.283285 -283.238314) (xy 416.25372 -283.277658) (xy 416.218227 -283.31175) (xy 416.177724 -283.339706)
			(xy 416.133262 -283.360804) (xy 416.085991 -283.374496) (xy 416.037136 -283.380428) (xy 415.987961 -283.378447)
			(xy 415.939742 -283.368603) (xy 415.893726 -283.351151) (xy 415.851105 -283.326544) (xy 415.812984 -283.295419)
			(xy 415.780349 -283.258582) (xy 415.754046 -283.216986) (xy 415.734755 -283.17171) (xy 415.722978 -283.123926)
			(xy 415.719018 -283.074872) (xy 415.38017 -283.074872) (xy 415.379675 -283.099479) (xy 415.37178 -283.148056)
			(xy 415.356196 -283.194737) (xy 415.333325 -283.238314) (xy 415.30376 -283.277658) (xy 415.268267 -283.31175)
			(xy 415.227764 -283.339706) (xy 415.183302 -283.360804) (xy 415.136031 -283.374496) (xy 415.087176 -283.380428)
			(xy 415.038001 -283.378447) (xy 414.989782 -283.368603) (xy 414.943766 -283.351151) (xy 414.901145 -283.326544)
			(xy 414.863024 -283.295419) (xy 414.830389 -283.258582) (xy 414.804086 -283.216986) (xy 414.784795 -283.17171)
			(xy 414.773018 -283.123926) (xy 414.769058 -283.074872) (xy 414.43021 -283.074872) (xy 414.429715 -283.099479)
			(xy 414.42182 -283.148056) (xy 414.406236 -283.194737) (xy 414.383365 -283.238314) (xy 414.3538 -283.277658)
			(xy 414.318307 -283.31175) (xy 414.277804 -283.339706) (xy 414.233342 -283.360804) (xy 414.186071 -283.374496)
			(xy 414.137216 -283.380428) (xy 414.088041 -283.378447) (xy 414.039822 -283.368603) (xy 413.993806 -283.351151)
			(xy 413.951185 -283.326544) (xy 413.913064 -283.295419) (xy 413.880429 -283.258582) (xy 413.854126 -283.216986)
			(xy 413.834835 -283.17171) (xy 413.823058 -283.123926) (xy 413.819098 -283.074872) (xy 413.48025 -283.074872)
			(xy 413.479755 -283.099479) (xy 413.47186 -283.148056) (xy 413.456276 -283.194737) (xy 413.433405 -283.238314)
			(xy 413.40384 -283.277658) (xy 413.368347 -283.31175) (xy 413.327844 -283.339706) (xy 413.283382 -283.360804)
			(xy 413.236111 -283.374496) (xy 413.187256 -283.380428) (xy 413.138081 -283.378447) (xy 413.089862 -283.368603)
			(xy 413.043846 -283.351151) (xy 413.001225 -283.326544) (xy 412.963104 -283.295419) (xy 412.930469 -283.258582)
			(xy 412.904166 -283.216986) (xy 412.884875 -283.17171) (xy 412.873098 -283.123926) (xy 412.869138 -283.074872)
			(xy 412.53029 -283.074872) (xy 412.529795 -283.099479) (xy 412.5219 -283.148056) (xy 412.506316 -283.194737)
			(xy 412.483445 -283.238314) (xy 412.45388 -283.277658) (xy 412.418387 -283.31175) (xy 412.377884 -283.339706)
			(xy 412.333422 -283.360804) (xy 412.286151 -283.374496) (xy 412.237296 -283.380428) (xy 412.188121 -283.378447)
			(xy 412.139902 -283.368603) (xy 412.093886 -283.351151) (xy 412.051265 -283.326544) (xy 412.013144 -283.295419)
			(xy 411.980509 -283.258582) (xy 411.954206 -283.216986) (xy 411.934915 -283.17171) (xy 411.923138 -283.123926)
			(xy 411.919178 -283.074872) (xy 411.58033 -283.074872) (xy 411.579835 -283.099479) (xy 411.57194 -283.148056)
			(xy 411.556356 -283.194737) (xy 411.533485 -283.238314) (xy 411.50392 -283.277658) (xy 411.468427 -283.31175)
			(xy 411.427924 -283.339706) (xy 411.383462 -283.360804) (xy 411.336191 -283.374496) (xy 411.287336 -283.380428)
			(xy 411.238161 -283.378447) (xy 411.189942 -283.368603) (xy 411.143926 -283.351151) (xy 411.101305 -283.326544)
			(xy 411.063184 -283.295419) (xy 411.030549 -283.258582) (xy 411.004246 -283.216986) (xy 410.984955 -283.17171)
			(xy 410.973178 -283.123926) (xy 410.969218 -283.074872) (xy 410.630116 -283.074872) (xy 410.629621 -283.099479)
			(xy 410.621726 -283.148056) (xy 410.606142 -283.194737) (xy 410.583271 -283.238314) (xy 410.553706 -283.277658)
			(xy 410.518213 -283.31175) (xy 410.47771 -283.339706) (xy 410.433248 -283.360804) (xy 410.385977 -283.374496)
			(xy 410.337122 -283.380428) (xy 410.287947 -283.378447) (xy 410.239728 -283.368603) (xy 410.193712 -283.351151)
			(xy 410.151091 -283.326544) (xy 410.11297 -283.295419) (xy 410.080335 -283.258582) (xy 410.054032 -283.216986)
			(xy 410.034741 -283.17171) (xy 410.022964 -283.123926) (xy 410.019004 -283.074872) (xy 409.680156 -283.074872)
			(xy 409.679661 -283.099479) (xy 409.671766 -283.148056) (xy 409.656182 -283.194737) (xy 409.633311 -283.238314)
			(xy 409.603746 -283.277658) (xy 409.568253 -283.31175) (xy 409.52775 -283.339706) (xy 409.483288 -283.360804)
			(xy 409.436017 -283.374496) (xy 409.387162 -283.380428) (xy 409.337987 -283.378447) (xy 409.289768 -283.368603)
			(xy 409.243752 -283.351151) (xy 409.201131 -283.326544) (xy 409.16301 -283.295419) (xy 409.130375 -283.258582)
			(xy 409.104072 -283.216986) (xy 409.084781 -283.17171) (xy 409.073004 -283.123926) (xy 409.069044 -283.074872)
			(xy 408.730196 -283.074872) (xy 408.729701 -283.099479) (xy 408.721806 -283.148056) (xy 408.706222 -283.194737)
			(xy 408.683351 -283.238314) (xy 408.653786 -283.277658) (xy 408.618293 -283.31175) (xy 408.57779 -283.339706)
			(xy 408.533328 -283.360804) (xy 408.486057 -283.374496) (xy 408.437202 -283.380428) (xy 408.388027 -283.378447)
			(xy 408.339808 -283.368603) (xy 408.293792 -283.351151) (xy 408.251171 -283.326544) (xy 408.21305 -283.295419)
			(xy 408.180415 -283.258582) (xy 408.154112 -283.216986) (xy 408.134821 -283.17171) (xy 408.123044 -283.123926)
			(xy 408.119084 -283.074872) (xy 406.830276 -283.074872) (xy 406.829781 -283.099479) (xy 406.821886 -283.148056)
			(xy 406.806302 -283.194737) (xy 406.783431 -283.238314) (xy 406.753866 -283.277658) (xy 406.718373 -283.31175)
			(xy 406.67787 -283.339706) (xy 406.633408 -283.360804) (xy 406.586137 -283.374496) (xy 406.537282 -283.380428)
			(xy 406.488107 -283.378447) (xy 406.439888 -283.368603) (xy 406.393872 -283.351151) (xy 406.351251 -283.326544)
			(xy 406.31313 -283.295419) (xy 406.280495 -283.258582) (xy 406.254192 -283.216986) (xy 406.234901 -283.17171)
			(xy 406.223124 -283.123926) (xy 406.219164 -283.074872) (xy 405.880316 -283.074872) (xy 405.879821 -283.099479)
			(xy 405.871926 -283.148056) (xy 405.856342 -283.194737) (xy 405.833471 -283.238314) (xy 405.803906 -283.277658)
			(xy 405.768413 -283.31175) (xy 405.72791 -283.339706) (xy 405.683448 -283.360804) (xy 405.636177 -283.374496)
			(xy 405.587322 -283.380428) (xy 405.538147 -283.378447) (xy 405.489928 -283.368603) (xy 405.443912 -283.351151)
			(xy 405.401291 -283.326544) (xy 405.36317 -283.295419) (xy 405.330535 -283.258582) (xy 405.304232 -283.216986)
			(xy 405.284941 -283.17171) (xy 405.273164 -283.123926) (xy 405.269204 -283.074872) (xy 404.930356 -283.074872)
			(xy 404.929861 -283.099479) (xy 404.921966 -283.148056) (xy 404.906382 -283.194737) (xy 404.883511 -283.238314)
			(xy 404.853946 -283.277658) (xy 404.818453 -283.31175) (xy 404.77795 -283.339706) (xy 404.733488 -283.360804)
			(xy 404.686217 -283.374496) (xy 404.637362 -283.380428) (xy 404.588187 -283.378447) (xy 404.539968 -283.368603)
			(xy 404.493952 -283.351151) (xy 404.451331 -283.326544) (xy 404.41321 -283.295419) (xy 404.380575 -283.258582)
			(xy 404.354272 -283.216986) (xy 404.334981 -283.17171) (xy 404.323204 -283.123926) (xy 404.319244 -283.074872)
			(xy 403.980039 -283.074872) (xy 403.977793 -283.116214) (xy 403.967118 -283.164689) (xy 403.948741 -283.210797)
			(xy 403.923147 -283.253326) (xy 403.891009 -283.291153) (xy 403.853175 -283.323283) (xy 403.810642 -283.348869)
			(xy 403.764529 -283.367236) (xy 403.716053 -283.377902) (xy 403.666489 -283.380584) (xy 403.617145 -283.375213)
			(xy 403.569319 -283.361929) (xy 403.524273 -283.341083) (xy 403.483192 -283.313224) (xy 403.44716 -283.279086)
			(xy 403.417125 -283.239568) (xy 403.39388 -283.195712) (xy 403.378035 -283.148673) (xy 403.370009 -283.09969)
			(xy 403.369526 -283.074872) (xy 403.369698 -283.060689) (xy 403.372373 -283.032449) (xy 403.37486 -283.018484)
			(xy 403.377146 -283.006038) (xy 403.36978 -282.982416) (xy 403.29231 -282.904946) (xy 403.268688 -282.89758)
			(xy 403.256242 -282.899866) (xy 403.242277 -282.902346) (xy 403.214037 -282.905016) (xy 403.199854 -282.9052)
			(xy 403.185671 -282.905016) (xy 403.157431 -282.902349) (xy 403.143466 -282.899866) (xy 403.13102 -282.89758)
			(xy 403.107398 -282.904946) (xy 403.029928 -282.982416) (xy 403.022562 -283.006038) (xy 403.024848 -283.018484)
			(xy 403.027332 -283.032449) (xy 403.029999 -283.060689) (xy 403.030182 -283.074872) (xy 403.029752 -283.099695)
			(xy 403.021725 -283.148688) (xy 403.005877 -283.195737) (xy 402.982626 -283.239602) (xy 402.952585 -283.279128)
			(xy 402.916545 -283.313273) (xy 402.875456 -283.341138) (xy 402.8304 -283.361988) (xy 402.782565 -283.375274)
			(xy 402.73321 -283.380646) (xy 402.683636 -283.377963) (xy 402.63515 -283.367295) (xy 402.589028 -283.348923)
			(xy 402.546486 -283.323331) (xy 402.508644 -283.291194) (xy 402.4765 -283.253358) (xy 402.450901 -283.210821)
			(xy 402.432521 -283.164702) (xy 402.421845 -283.116217) (xy 402.419152 -283.066644) (xy 402.080056 -283.066644)
			(xy 402.080222 -283.074872) (xy 402.079727 -283.099479) (xy 402.071832 -283.148056) (xy 402.056248 -283.194737)
			(xy 402.033377 -283.238314) (xy 402.003812 -283.277658) (xy 401.968319 -283.31175) (xy 401.927816 -283.339706)
			(xy 401.883354 -283.360804) (xy 401.836083 -283.374496) (xy 401.787228 -283.380428) (xy 401.738053 -283.378447)
			(xy 401.689834 -283.368603) (xy 401.643818 -283.351151) (xy 401.601197 -283.326544) (xy 401.563076 -283.295419)
			(xy 401.530441 -283.258582) (xy 401.504138 -283.216986) (xy 401.484847 -283.17171) (xy 401.47307 -283.123926)
			(xy 401.46911 -283.074872) (xy 401.130262 -283.074872) (xy 401.129767 -283.099479) (xy 401.121872 -283.148056)
			(xy 401.106288 -283.194737) (xy 401.083417 -283.238314) (xy 401.053852 -283.277658) (xy 401.018359 -283.31175)
			(xy 400.977856 -283.339706) (xy 400.933394 -283.360804) (xy 400.886123 -283.374496) (xy 400.837268 -283.380428)
			(xy 400.788093 -283.378447) (xy 400.739874 -283.368603) (xy 400.693858 -283.351151) (xy 400.651237 -283.326544)
			(xy 400.613116 -283.295419) (xy 400.580481 -283.258582) (xy 400.554178 -283.216986) (xy 400.534887 -283.17171)
			(xy 400.52311 -283.123926) (xy 400.51915 -283.074872) (xy 400.180302 -283.074872) (xy 400.179807 -283.099479)
			(xy 400.171912 -283.148056) (xy 400.156328 -283.194737) (xy 400.133457 -283.238314) (xy 400.103892 -283.277658)
			(xy 400.068399 -283.31175) (xy 400.027896 -283.339706) (xy 399.983434 -283.360804) (xy 399.936163 -283.374496)
			(xy 399.887308 -283.380428) (xy 399.838133 -283.378447) (xy 399.789914 -283.368603) (xy 399.743898 -283.351151)
			(xy 399.701277 -283.326544) (xy 399.663156 -283.295419) (xy 399.630521 -283.258582) (xy 399.604218 -283.216986)
			(xy 399.584927 -283.17171) (xy 399.57315 -283.123926) (xy 399.56919 -283.074872) (xy 399.230342 -283.074872)
			(xy 399.229847 -283.099479) (xy 399.221952 -283.148056) (xy 399.206368 -283.194737) (xy 399.183497 -283.238314)
			(xy 399.153932 -283.277658) (xy 399.118439 -283.31175) (xy 399.077936 -283.339706) (xy 399.033474 -283.360804)
			(xy 398.986203 -283.374496) (xy 398.937348 -283.380428) (xy 398.888173 -283.378447) (xy 398.839954 -283.368603)
			(xy 398.793938 -283.351151) (xy 398.751317 -283.326544) (xy 398.713196 -283.295419) (xy 398.680561 -283.258582)
			(xy 398.654258 -283.216986) (xy 398.634967 -283.17171) (xy 398.62319 -283.123926) (xy 398.61923 -283.074872)
			(xy 398.280657 -283.074872) (xy 398.280659 -283.0749) (xy 398.276488 -283.125241) (xy 398.264088 -283.174208)
			(xy 398.243798 -283.220467) (xy 398.216171 -283.262756) (xy 398.18196 -283.299921) (xy 398.1421 -283.330948)
			(xy 398.097676 -283.354992) (xy 398.0499 -283.371396) (xy 398.000077 -283.379713) (xy 397.97482 -283.38018)
			(xy 397.96328 -283.380054) (xy 397.940268 -283.378277) (xy 397.928846 -283.376624) (xy 397.925036 -283.376116)
			(xy 397.92402 -283.376116) (xy 397.900114 -283.371603) (xy 397.854032 -283.356016) (xy 397.810996 -283.333336)
			(xy 397.772088 -283.304134) (xy 397.754856 -283.286962) (xy 397.743934 -283.275532) (xy 397.713962 -283.269182)
			(xy 397.611854 -283.31033) (xy 397.602695 -283.314525) (xy 397.588394 -283.328691) (xy 397.580614 -283.347257)
			(xy 397.580104 -283.35732) (xy 397.580104 -283.549852) (xy 421.894012 -283.549852) (xy 421.897972 -283.500798)
			(xy 421.909749 -283.453014) (xy 421.92904 -283.407738) (xy 421.955343 -283.366142) (xy 421.987978 -283.329305)
			(xy 422.026099 -283.29818) (xy 422.06872 -283.273573) (xy 422.114736 -283.256121) (xy 422.162955 -283.246277)
			(xy 422.21213 -283.244296) (xy 422.260985 -283.250228) (xy 422.308256 -283.26392) (xy 422.352718 -283.285018)
			(xy 422.393221 -283.312974) (xy 422.428714 -283.347066) (xy 422.458279 -283.38641) (xy 422.48115 -283.429987)
			(xy 422.496734 -283.476668) (xy 422.504629 -283.525245) (xy 422.505124 -283.549852) (xy 422.504629 -283.574459)
			(xy 422.50445 -283.57556) (xy 422.823128 -283.57556) (xy 422.823128 -283.524144) (xy 422.831171 -283.473362)
			(xy 422.847059 -283.424463) (xy 422.870402 -283.378651) (xy 422.900623 -283.337055) (xy 422.936979 -283.300699)
			(xy 422.978575 -283.270478) (xy 423.024387 -283.247135) (xy 423.073286 -283.231247) (xy 423.124068 -283.223204)
			(xy 423.175484 -283.223204) (xy 423.226266 -283.231247) (xy 423.275165 -283.247135) (xy 423.320977 -283.270478)
			(xy 423.362573 -283.300699) (xy 423.398929 -283.337055) (xy 423.42915 -283.378651) (xy 423.452493 -283.424463)
			(xy 423.468381 -283.473362) (xy 423.476424 -283.524144) (xy 423.476928 -283.549852) (xy 423.476424 -283.57556)
			(xy 423.773342 -283.57556) (xy 423.773342 -283.524144) (xy 423.781385 -283.473362) (xy 423.797273 -283.424463)
			(xy 423.820616 -283.378651) (xy 423.850837 -283.337055) (xy 423.887193 -283.300699) (xy 423.928789 -283.270478)
			(xy 423.974601 -283.247135) (xy 424.0235 -283.231247) (xy 424.074282 -283.223204) (xy 424.125698 -283.223204)
			(xy 424.17648 -283.231247) (xy 424.225379 -283.247135) (xy 424.271191 -283.270478) (xy 424.312787 -283.300699)
			(xy 424.349143 -283.337055) (xy 424.379364 -283.378651) (xy 424.402707 -283.424463) (xy 424.418595 -283.473362)
			(xy 424.426638 -283.524144) (xy 424.427142 -283.549852) (xy 424.744146 -283.549852) (xy 424.748106 -283.500798)
			(xy 424.759883 -283.453014) (xy 424.779174 -283.407738) (xy 424.805477 -283.366142) (xy 424.838112 -283.329305)
			(xy 424.876233 -283.29818) (xy 424.918854 -283.273573) (xy 424.96487 -283.256121) (xy 425.013089 -283.246277)
			(xy 425.062264 -283.244296) (xy 425.111119 -283.250228) (xy 425.15839 -283.26392) (xy 425.202852 -283.285018)
			(xy 425.243355 -283.312974) (xy 425.278848 -283.347066) (xy 425.308413 -283.38641) (xy 425.331284 -283.429987)
			(xy 425.346868 -283.476668) (xy 425.354763 -283.525245) (xy 425.355258 -283.549852) (xy 425.694106 -283.549852)
			(xy 425.698066 -283.500798) (xy 425.709843 -283.453014) (xy 425.729134 -283.407738) (xy 425.755437 -283.366142)
			(xy 425.788072 -283.329305) (xy 425.826193 -283.29818) (xy 425.868814 -283.273573) (xy 425.91483 -283.256121)
			(xy 425.963049 -283.246277) (xy 426.012224 -283.244296) (xy 426.061079 -283.250228) (xy 426.10835 -283.26392)
			(xy 426.152812 -283.285018) (xy 426.193315 -283.312974) (xy 426.228808 -283.347066) (xy 426.258373 -283.38641)
			(xy 426.281244 -283.429987) (xy 426.296828 -283.476668) (xy 426.304723 -283.525245) (xy 426.305218 -283.549852)
			(xy 426.644066 -283.549852) (xy 426.648026 -283.500798) (xy 426.659803 -283.453014) (xy 426.679094 -283.407738)
			(xy 426.705397 -283.366142) (xy 426.738032 -283.329305) (xy 426.776153 -283.29818) (xy 426.818774 -283.273573)
			(xy 426.86479 -283.256121) (xy 426.913009 -283.246277) (xy 426.962184 -283.244296) (xy 427.011039 -283.250228)
			(xy 427.05831 -283.26392) (xy 427.102772 -283.285018) (xy 427.143275 -283.312974) (xy 427.178768 -283.347066)
			(xy 427.208333 -283.38641) (xy 427.231204 -283.429987) (xy 427.246788 -283.476668) (xy 427.254683 -283.525245)
			(xy 427.255178 -283.549852) (xy 427.594026 -283.549852) (xy 427.597986 -283.500798) (xy 427.609763 -283.453014)
			(xy 427.629054 -283.407738) (xy 427.655357 -283.366142) (xy 427.687992 -283.329305) (xy 427.726113 -283.29818)
			(xy 427.768734 -283.273573) (xy 427.81475 -283.256121) (xy 427.862969 -283.246277) (xy 427.912144 -283.244296)
			(xy 427.960999 -283.250228) (xy 428.00827 -283.26392) (xy 428.052732 -283.285018) (xy 428.093235 -283.312974)
			(xy 428.128728 -283.347066) (xy 428.158293 -283.38641) (xy 428.181164 -283.429987) (xy 428.196748 -283.476668)
			(xy 428.204643 -283.525245) (xy 428.205138 -283.549852) (xy 428.543986 -283.549852) (xy 428.547946 -283.500798)
			(xy 428.559723 -283.453014) (xy 428.579014 -283.407738) (xy 428.605317 -283.366142) (xy 428.637952 -283.329305)
			(xy 428.676073 -283.29818) (xy 428.718694 -283.273573) (xy 428.76471 -283.256121) (xy 428.812929 -283.246277)
			(xy 428.862104 -283.244296) (xy 428.910959 -283.250228) (xy 428.95823 -283.26392) (xy 429.002692 -283.285018)
			(xy 429.043195 -283.312974) (xy 429.078688 -283.347066) (xy 429.108253 -283.38641) (xy 429.131124 -283.429987)
			(xy 429.146708 -283.476668) (xy 429.154603 -283.525245) (xy 429.155098 -283.549852) (xy 429.154603 -283.574459)
			(xy 429.154424 -283.57556) (xy 429.473356 -283.57556) (xy 429.473356 -283.524144) (xy 429.481399 -283.473362)
			(xy 429.497287 -283.424463) (xy 429.52063 -283.378651) (xy 429.550851 -283.337055) (xy 429.587207 -283.300699)
			(xy 429.628803 -283.270478) (xy 429.674615 -283.247135) (xy 429.723514 -283.231247) (xy 429.774296 -283.223204)
			(xy 429.825712 -283.223204) (xy 429.876494 -283.231247) (xy 429.925393 -283.247135) (xy 429.971205 -283.270478)
			(xy 430.012801 -283.300699) (xy 430.049157 -283.337055) (xy 430.079378 -283.378651) (xy 430.102721 -283.424463)
			(xy 430.118609 -283.473362) (xy 430.126652 -283.524144) (xy 430.127156 -283.549852) (xy 430.126652 -283.57556)
			(xy 430.423316 -283.57556) (xy 430.423316 -283.524144) (xy 430.431359 -283.473362) (xy 430.447247 -283.424463)
			(xy 430.47059 -283.378651) (xy 430.500811 -283.337055) (xy 430.537167 -283.300699) (xy 430.578763 -283.270478)
			(xy 430.624575 -283.247135) (xy 430.673474 -283.231247) (xy 430.724256 -283.223204) (xy 430.775672 -283.223204)
			(xy 430.826454 -283.231247) (xy 430.875353 -283.247135) (xy 430.921165 -283.270478) (xy 430.962761 -283.300699)
			(xy 430.999117 -283.337055) (xy 431.029338 -283.378651) (xy 431.052681 -283.424463) (xy 431.068569 -283.473362)
			(xy 431.076612 -283.524144) (xy 431.077116 -283.549852) (xy 431.077111 -283.550106) (xy 431.394374 -283.550106)
			(xy 431.398334 -283.501052) (xy 431.410111 -283.453268) (xy 431.429402 -283.407992) (xy 431.455705 -283.366396)
			(xy 431.48834 -283.329559) (xy 431.526461 -283.298434) (xy 431.569082 -283.273827) (xy 431.615098 -283.256375)
			(xy 431.663317 -283.246531) (xy 431.712492 -283.24455) (xy 431.761347 -283.250482) (xy 431.808618 -283.264174)
			(xy 431.85308 -283.285272) (xy 431.893583 -283.313228) (xy 431.929076 -283.34732) (xy 431.958641 -283.386664)
			(xy 431.981512 -283.430241) (xy 431.997096 -283.476922) (xy 432.004991 -283.525499) (xy 432.005036 -283.527754)
			(xy 442.093858 -283.527754) (xy 442.094335 -283.500503) (xy 442.102097 -283.446557) (xy 442.117456 -283.394264)
			(xy 442.1401 -283.344689) (xy 442.169568 -283.29884) (xy 442.20526 -283.257652) (xy 442.24645 -283.221961)
			(xy 442.292299 -283.192494) (xy 442.341875 -283.169852) (xy 442.394169 -283.154494) (xy 442.448115 -283.146734)
			(xy 442.475366 -283.146246) (xy 442.502736 -283.146721) (xy 442.556915 -283.154535) (xy 442.609419 -283.170021)
			(xy 442.659166 -283.192861) (xy 442.705132 -283.222585) (xy 442.726064 -283.240226) (xy 442.733176 -283.246322)
			(xy 442.750194 -283.252672) (xy 442.835538 -283.252672) (xy 442.852556 -283.246322) (xy 442.859668 -283.240226)
			(xy 442.880605 -283.222592) (xy 442.926576 -283.192879) (xy 442.976322 -283.170041) (xy 443.028822 -283.154549)
			(xy 443.082997 -283.14672) (xy 443.110366 -283.146246) (xy 443.137614 -283.14681) (xy 443.191557 -283.15456)
			(xy 443.243847 -283.169909) (xy 443.293421 -283.192543) (xy 443.33927 -283.222001) (xy 443.380459 -283.257684)
			(xy 443.416151 -283.298866) (xy 443.445619 -283.344709) (xy 443.468263 -283.394278) (xy 443.483623 -283.446565)
			(xy 443.491385 -283.500506) (xy 443.491874 -283.527754) (xy 443.491373 -283.556232) (xy 443.482886 -283.612552)
			(xy 443.466121 -283.666984) (xy 443.441453 -283.718321) (xy 443.409429 -283.765421) (xy 443.37076 -283.807238)
			(xy 443.326305 -283.842844) (xy 443.277052 -283.871447) (xy 443.224095 -283.892411) (xy 443.196472 -283.899356)
			(xy 443.184788 -283.90215) (xy 443.1665 -283.917136) (xy 443.123828 -284.012894) (xy 443.12459 -284.03677)
			(xy 443.130432 -284.047184) (xy 443.142168 -284.069425) (xy 443.16062 -284.116206) (xy 443.173073 -284.164928)
			(xy 443.179332 -284.214825) (xy 443.179708 -284.23997) (xy 443.179197 -284.2686) (xy 443.171048 -284.325278)
			(xy 443.154916 -284.380218) (xy 443.13113 -284.432304) (xy 443.100172 -284.480475) (xy 443.062675 -284.523749)
			(xy 443.019401 -284.561246) (xy 442.97123 -284.592204) (xy 442.919144 -284.61599) (xy 442.864204 -284.632122)
			(xy 442.807526 -284.640271) (xy 442.750266 -284.640271) (xy 442.693588 -284.632122) (xy 442.638648 -284.61599)
			(xy 442.586562 -284.592204) (xy 442.538391 -284.561246) (xy 442.495117 -284.523749) (xy 442.45762 -284.480475)
			(xy 442.426662 -284.432304) (xy 442.402876 -284.380218) (xy 442.386744 -284.325278) (xy 442.378595 -284.2686)
			(xy 442.378084 -284.23997) (xy 442.378446 -284.214097) (xy 442.385064 -284.162777) (xy 442.398237 -284.112737)
			(xy 442.417747 -284.064811) (xy 442.430154 -284.042104) (xy 442.435996 -284.031944) (xy 442.43752 -284.00883)
			(xy 442.398404 -283.913072) (xy 442.381132 -283.897578) (xy 442.369956 -283.894276) (xy 442.343795 -283.88623)
			(xy 442.293889 -283.863761) (xy 442.247708 -283.834389) (xy 442.2062 -283.798716) (xy 442.170218 -283.757476)
			(xy 442.140502 -283.711515) (xy 442.117661 -283.661778) (xy 442.102166 -283.609287) (xy 442.094334 -283.555119)
			(xy 442.093858 -283.527754) (xy 432.005036 -283.527754) (xy 432.005486 -283.550106) (xy 432.004991 -283.574713)
			(xy 431.997096 -283.62329) (xy 431.981512 -283.669971) (xy 431.958641 -283.713548) (xy 431.929076 -283.752892)
			(xy 431.893583 -283.786984) (xy 431.85308 -283.81494) (xy 431.808618 -283.836038) (xy 431.761347 -283.84973)
			(xy 431.712492 -283.855662) (xy 431.663317 -283.853681) (xy 431.615098 -283.843837) (xy 431.569082 -283.826385)
			(xy 431.526461 -283.801778) (xy 431.48834 -283.770653) (xy 431.455705 -283.733816) (xy 431.429402 -283.69222)
			(xy 431.410111 -283.646944) (xy 431.398334 -283.59916) (xy 431.394374 -283.550106) (xy 431.077111 -283.550106)
			(xy 431.076612 -283.57556) (xy 431.068569 -283.626342) (xy 431.052681 -283.675241) (xy 431.029338 -283.721053)
			(xy 430.999117 -283.762649) (xy 430.962761 -283.799005) (xy 430.921165 -283.829226) (xy 430.875353 -283.852569)
			(xy 430.826454 -283.868457) (xy 430.775672 -283.8765) (xy 430.724256 -283.8765) (xy 430.673474 -283.868457)
			(xy 430.624575 -283.852569) (xy 430.578763 -283.829226) (xy 430.537167 -283.799005) (xy 430.500811 -283.762649)
			(xy 430.47059 -283.721053) (xy 430.447247 -283.675241) (xy 430.431359 -283.626342) (xy 430.423316 -283.57556)
			(xy 430.126652 -283.57556) (xy 430.118609 -283.626342) (xy 430.102721 -283.675241) (xy 430.079378 -283.721053)
			(xy 430.049157 -283.762649) (xy 430.012801 -283.799005) (xy 429.971205 -283.829226) (xy 429.925393 -283.852569)
			(xy 429.876494 -283.868457) (xy 429.825712 -283.8765) (xy 429.774296 -283.8765) (xy 429.723514 -283.868457)
			(xy 429.674615 -283.852569) (xy 429.628803 -283.829226) (xy 429.587207 -283.799005) (xy 429.550851 -283.762649)
			(xy 429.52063 -283.721053) (xy 429.497287 -283.675241) (xy 429.481399 -283.626342) (xy 429.473356 -283.57556)
			(xy 429.154424 -283.57556) (xy 429.146708 -283.623036) (xy 429.131124 -283.669717) (xy 429.108253 -283.713294)
			(xy 429.078688 -283.752638) (xy 429.043195 -283.78673) (xy 429.002692 -283.814686) (xy 428.95823 -283.835784)
			(xy 428.910959 -283.849476) (xy 428.862104 -283.855408) (xy 428.812929 -283.853427) (xy 428.76471 -283.843583)
			(xy 428.718694 -283.826131) (xy 428.676073 -283.801524) (xy 428.637952 -283.770399) (xy 428.605317 -283.733562)
			(xy 428.579014 -283.691966) (xy 428.559723 -283.64669) (xy 428.547946 -283.598906) (xy 428.543986 -283.549852)
			(xy 428.205138 -283.549852) (xy 428.204643 -283.574459) (xy 428.196748 -283.623036) (xy 428.181164 -283.669717)
			(xy 428.158293 -283.713294) (xy 428.128728 -283.752638) (xy 428.093235 -283.78673) (xy 428.052732 -283.814686)
			(xy 428.00827 -283.835784) (xy 427.960999 -283.849476) (xy 427.912144 -283.855408) (xy 427.862969 -283.853427)
			(xy 427.81475 -283.843583) (xy 427.768734 -283.826131) (xy 427.726113 -283.801524) (xy 427.687992 -283.770399)
			(xy 427.655357 -283.733562) (xy 427.629054 -283.691966) (xy 427.609763 -283.64669) (xy 427.597986 -283.598906)
			(xy 427.594026 -283.549852) (xy 427.255178 -283.549852) (xy 427.254683 -283.574459) (xy 427.246788 -283.623036)
			(xy 427.231204 -283.669717) (xy 427.208333 -283.713294) (xy 427.178768 -283.752638) (xy 427.143275 -283.78673)
			(xy 427.102772 -283.814686) (xy 427.05831 -283.835784) (xy 427.011039 -283.849476) (xy 426.962184 -283.855408)
			(xy 426.913009 -283.853427) (xy 426.86479 -283.843583) (xy 426.818774 -283.826131) (xy 426.776153 -283.801524)
			(xy 426.738032 -283.770399) (xy 426.705397 -283.733562) (xy 426.679094 -283.691966) (xy 426.659803 -283.64669)
			(xy 426.648026 -283.598906) (xy 426.644066 -283.549852) (xy 426.305218 -283.549852) (xy 426.304723 -283.574459)
			(xy 426.296828 -283.623036) (xy 426.281244 -283.669717) (xy 426.258373 -283.713294) (xy 426.228808 -283.752638)
			(xy 426.193315 -283.78673) (xy 426.152812 -283.814686) (xy 426.10835 -283.835784) (xy 426.061079 -283.849476)
			(xy 426.012224 -283.855408) (xy 425.963049 -283.853427) (xy 425.91483 -283.843583) (xy 425.868814 -283.826131)
			(xy 425.826193 -283.801524) (xy 425.788072 -283.770399) (xy 425.755437 -283.733562) (xy 425.729134 -283.691966)
			(xy 425.709843 -283.64669) (xy 425.698066 -283.598906) (xy 425.694106 -283.549852) (xy 425.355258 -283.549852)
			(xy 425.354763 -283.574459) (xy 425.346868 -283.623036) (xy 425.331284 -283.669717) (xy 425.308413 -283.713294)
			(xy 425.278848 -283.752638) (xy 425.243355 -283.78673) (xy 425.202852 -283.814686) (xy 425.15839 -283.835784)
			(xy 425.111119 -283.849476) (xy 425.062264 -283.855408) (xy 425.013089 -283.853427) (xy 424.96487 -283.843583)
			(xy 424.918854 -283.826131) (xy 424.876233 -283.801524) (xy 424.838112 -283.770399) (xy 424.805477 -283.733562)
			(xy 424.779174 -283.691966) (xy 424.759883 -283.64669) (xy 424.748106 -283.598906) (xy 424.744146 -283.549852)
			(xy 424.427142 -283.549852) (xy 424.426638 -283.57556) (xy 424.418595 -283.626342) (xy 424.402707 -283.675241)
			(xy 424.379364 -283.721053) (xy 424.349143 -283.762649) (xy 424.312787 -283.799005) (xy 424.271191 -283.829226)
			(xy 424.225379 -283.852569) (xy 424.17648 -283.868457) (xy 424.125698 -283.8765) (xy 424.074282 -283.8765)
			(xy 424.0235 -283.868457) (xy 423.974601 -283.852569) (xy 423.928789 -283.829226) (xy 423.887193 -283.799005)
			(xy 423.850837 -283.762649) (xy 423.820616 -283.721053) (xy 423.797273 -283.675241) (xy 423.781385 -283.626342)
			(xy 423.773342 -283.57556) (xy 423.476424 -283.57556) (xy 423.468381 -283.626342) (xy 423.452493 -283.675241)
			(xy 423.42915 -283.721053) (xy 423.398929 -283.762649) (xy 423.362573 -283.799005) (xy 423.320977 -283.829226)
			(xy 423.275165 -283.852569) (xy 423.226266 -283.868457) (xy 423.175484 -283.8765) (xy 423.124068 -283.8765)
			(xy 423.073286 -283.868457) (xy 423.024387 -283.852569) (xy 422.978575 -283.829226) (xy 422.936979 -283.799005)
			(xy 422.900623 -283.762649) (xy 422.870402 -283.721053) (xy 422.847059 -283.675241) (xy 422.831171 -283.626342)
			(xy 422.823128 -283.57556) (xy 422.50445 -283.57556) (xy 422.496734 -283.623036) (xy 422.48115 -283.669717)
			(xy 422.458279 -283.713294) (xy 422.428714 -283.752638) (xy 422.393221 -283.78673) (xy 422.352718 -283.814686)
			(xy 422.308256 -283.835784) (xy 422.260985 -283.849476) (xy 422.21213 -283.855408) (xy 422.162955 -283.853427)
			(xy 422.114736 -283.843583) (xy 422.06872 -283.826131) (xy 422.026099 -283.801524) (xy 421.987978 -283.770399)
			(xy 421.955343 -283.733562) (xy 421.92904 -283.691966) (xy 421.909749 -283.64669) (xy 421.897972 -283.598906)
			(xy 421.894012 -283.549852) (xy 397.580104 -283.549852) (xy 397.580104 -283.742384) (xy 397.580522 -283.752468)
			(xy 397.588287 -283.771079) (xy 397.602651 -283.785232) (xy 397.611854 -283.789374) (xy 397.713962 -283.830522)
			(xy 397.744188 -283.824172) (xy 397.75511 -283.812742) (xy 397.772508 -283.795437) (xy 397.811804 -283.766049)
			(xy 397.85529 -283.743318) (xy 397.901849 -283.727827) (xy 397.950286 -283.719974) (xy 397.97482 -283.719524)
			(xy 398.000072 -283.720047) (xy 398.049886 -283.728363) (xy 398.097652 -283.744763) (xy 398.142067 -283.768802)
			(xy 398.18192 -283.799824) (xy 398.216124 -283.836981) (xy 398.243745 -283.879261) (xy 398.264031 -283.925511)
			(xy 398.276429 -283.974469) (xy 398.280599 -284.0248) (xy 398.280596 -284.024832) (xy 398.61923 -284.024832)
			(xy 398.62319 -283.975778) (xy 398.634967 -283.927994) (xy 398.654258 -283.882718) (xy 398.680561 -283.841122)
			(xy 398.713196 -283.804285) (xy 398.751317 -283.77316) (xy 398.793938 -283.748553) (xy 398.839954 -283.731101)
			(xy 398.888173 -283.721257) (xy 398.937348 -283.719276) (xy 398.986203 -283.725208) (xy 399.033474 -283.7389)
			(xy 399.077936 -283.759998) (xy 399.118439 -283.787954) (xy 399.153932 -283.822046) (xy 399.183497 -283.86139)
			(xy 399.206368 -283.904967) (xy 399.221952 -283.951648) (xy 399.229847 -284.000225) (xy 399.230342 -284.024832)
			(xy 399.56919 -284.024832) (xy 399.57315 -283.975778) (xy 399.584927 -283.927994) (xy 399.604218 -283.882718)
			(xy 399.630521 -283.841122) (xy 399.663156 -283.804285) (xy 399.701277 -283.77316) (xy 399.743898 -283.748553)
			(xy 399.789914 -283.731101) (xy 399.838133 -283.721257) (xy 399.887308 -283.719276) (xy 399.936163 -283.725208)
			(xy 399.983434 -283.7389) (xy 400.027896 -283.759998) (xy 400.068399 -283.787954) (xy 400.103892 -283.822046)
			(xy 400.133457 -283.86139) (xy 400.156328 -283.904967) (xy 400.171912 -283.951648) (xy 400.179807 -284.000225)
			(xy 400.180302 -284.024832) (xy 400.51915 -284.024832) (xy 400.52311 -283.975778) (xy 400.534887 -283.927994)
			(xy 400.554178 -283.882718) (xy 400.580481 -283.841122) (xy 400.613116 -283.804285) (xy 400.651237 -283.77316)
			(xy 400.693858 -283.748553) (xy 400.739874 -283.731101) (xy 400.788093 -283.721257) (xy 400.837268 -283.719276)
			(xy 400.886123 -283.725208) (xy 400.933394 -283.7389) (xy 400.977856 -283.759998) (xy 401.018359 -283.787954)
			(xy 401.053852 -283.822046) (xy 401.083417 -283.86139) (xy 401.106288 -283.904967) (xy 401.121872 -283.951648)
			(xy 401.129767 -284.000225) (xy 401.130262 -284.024832) (xy 401.46911 -284.024832) (xy 401.47307 -283.975778)
			(xy 401.484847 -283.927994) (xy 401.504138 -283.882718) (xy 401.530441 -283.841122) (xy 401.563076 -283.804285)
			(xy 401.601197 -283.77316) (xy 401.643818 -283.748553) (xy 401.689834 -283.731101) (xy 401.738053 -283.721257)
			(xy 401.787228 -283.719276) (xy 401.836083 -283.725208) (xy 401.883354 -283.7389) (xy 401.927816 -283.759998)
			(xy 401.968319 -283.787954) (xy 402.003812 -283.822046) (xy 402.033377 -283.86139) (xy 402.056248 -283.904967)
			(xy 402.071832 -283.951648) (xy 402.079727 -284.000225) (xy 402.080222 -284.024832) (xy 402.41907 -284.024832)
			(xy 402.42303 -283.975778) (xy 402.434807 -283.927994) (xy 402.454098 -283.882718) (xy 402.480401 -283.841122)
			(xy 402.513036 -283.804285) (xy 402.551157 -283.77316) (xy 402.593778 -283.748553) (xy 402.639794 -283.731101)
			(xy 402.688013 -283.721257) (xy 402.737188 -283.719276) (xy 402.786043 -283.725208) (xy 402.833314 -283.7389)
			(xy 402.877776 -283.759998) (xy 402.918279 -283.787954) (xy 402.953772 -283.822046) (xy 402.983337 -283.86139)
			(xy 403.006208 -283.904967) (xy 403.021792 -283.951648) (xy 403.029687 -284.000225) (xy 403.030182 -284.024832)
			(xy 403.36903 -284.024832) (xy 403.37299 -283.975778) (xy 403.384767 -283.927994) (xy 403.404058 -283.882718)
			(xy 403.430361 -283.841122) (xy 403.462996 -283.804285) (xy 403.501117 -283.77316) (xy 403.543738 -283.748553)
			(xy 403.589754 -283.731101) (xy 403.637973 -283.721257) (xy 403.687148 -283.719276) (xy 403.736003 -283.725208)
			(xy 403.783274 -283.7389) (xy 403.827736 -283.759998) (xy 403.868239 -283.787954) (xy 403.903732 -283.822046)
			(xy 403.933297 -283.86139) (xy 403.956168 -283.904967) (xy 403.971752 -283.951648) (xy 403.979647 -284.000225)
			(xy 403.980142 -284.024832) (xy 404.31899 -284.024832) (xy 404.32295 -283.975778) (xy 404.334727 -283.927994)
			(xy 404.354018 -283.882718) (xy 404.380321 -283.841122) (xy 404.412956 -283.804285) (xy 404.451077 -283.77316)
			(xy 404.493698 -283.748553) (xy 404.539714 -283.731101) (xy 404.587933 -283.721257) (xy 404.637108 -283.719276)
			(xy 404.685963 -283.725208) (xy 404.733234 -283.7389) (xy 404.777696 -283.759998) (xy 404.818199 -283.787954)
			(xy 404.853692 -283.822046) (xy 404.883257 -283.86139) (xy 404.906128 -283.904967) (xy 404.921712 -283.951648)
			(xy 404.929607 -284.000225) (xy 404.930102 -284.024832) (xy 405.269204 -284.024832) (xy 405.273164 -283.975778)
			(xy 405.284941 -283.927994) (xy 405.304232 -283.882718) (xy 405.330535 -283.841122) (xy 405.36317 -283.804285)
			(xy 405.401291 -283.77316) (xy 405.443912 -283.748553) (xy 405.489928 -283.731101) (xy 405.538147 -283.721257)
			(xy 405.587322 -283.719276) (xy 405.636177 -283.725208) (xy 405.683448 -283.7389) (xy 405.72791 -283.759998)
			(xy 405.768413 -283.787954) (xy 405.803906 -283.822046) (xy 405.833471 -283.86139) (xy 405.856342 -283.904967)
			(xy 405.871926 -283.951648) (xy 405.879821 -284.000225) (xy 405.880316 -284.024832) (xy 406.219164 -284.024832)
			(xy 406.223124 -283.975778) (xy 406.234901 -283.927994) (xy 406.254192 -283.882718) (xy 406.280495 -283.841122)
			(xy 406.31313 -283.804285) (xy 406.351251 -283.77316) (xy 406.393872 -283.748553) (xy 406.439888 -283.731101)
			(xy 406.488107 -283.721257) (xy 406.537282 -283.719276) (xy 406.586137 -283.725208) (xy 406.633408 -283.7389)
			(xy 406.67787 -283.759998) (xy 406.718373 -283.787954) (xy 406.753866 -283.822046) (xy 406.783431 -283.86139)
			(xy 406.806302 -283.904967) (xy 406.821886 -283.951648) (xy 406.829781 -284.000225) (xy 406.830276 -284.024832)
			(xy 408.119084 -284.024832) (xy 408.123044 -283.975778) (xy 408.134821 -283.927994) (xy 408.154112 -283.882718)
			(xy 408.180415 -283.841122) (xy 408.21305 -283.804285) (xy 408.251171 -283.77316) (xy 408.293792 -283.748553)
			(xy 408.339808 -283.731101) (xy 408.388027 -283.721257) (xy 408.437202 -283.719276) (xy 408.486057 -283.725208)
			(xy 408.533328 -283.7389) (xy 408.57779 -283.759998) (xy 408.618293 -283.787954) (xy 408.653786 -283.822046)
			(xy 408.683351 -283.86139) (xy 408.706222 -283.904967) (xy 408.721806 -283.951648) (xy 408.729701 -284.000225)
			(xy 408.730196 -284.024832) (xy 409.069044 -284.024832) (xy 409.073004 -283.975778) (xy 409.084781 -283.927994)
			(xy 409.104072 -283.882718) (xy 409.130375 -283.841122) (xy 409.16301 -283.804285) (xy 409.201131 -283.77316)
			(xy 409.243752 -283.748553) (xy 409.289768 -283.731101) (xy 409.337987 -283.721257) (xy 409.387162 -283.719276)
			(xy 409.436017 -283.725208) (xy 409.483288 -283.7389) (xy 409.52775 -283.759998) (xy 409.568253 -283.787954)
			(xy 409.603746 -283.822046) (xy 409.633311 -283.86139) (xy 409.656182 -283.904967) (xy 409.671766 -283.951648)
			(xy 409.679661 -284.000225) (xy 409.680156 -284.024832) (xy 410.019004 -284.024832) (xy 410.022964 -283.975778)
			(xy 410.034741 -283.927994) (xy 410.054032 -283.882718) (xy 410.080335 -283.841122) (xy 410.11297 -283.804285)
			(xy 410.151091 -283.77316) (xy 410.193712 -283.748553) (xy 410.239728 -283.731101) (xy 410.287947 -283.721257)
			(xy 410.337122 -283.719276) (xy 410.385977 -283.725208) (xy 410.433248 -283.7389) (xy 410.47771 -283.759998)
			(xy 410.518213 -283.787954) (xy 410.553706 -283.822046) (xy 410.583271 -283.86139) (xy 410.606142 -283.904967)
			(xy 410.621726 -283.951648) (xy 410.629621 -284.000225) (xy 410.630116 -284.024832) (xy 410.969218 -284.024832)
			(xy 410.973178 -283.975778) (xy 410.984955 -283.927994) (xy 411.004246 -283.882718) (xy 411.030549 -283.841122)
			(xy 411.063184 -283.804285) (xy 411.101305 -283.77316) (xy 411.143926 -283.748553) (xy 411.189942 -283.731101)
			(xy 411.238161 -283.721257) (xy 411.287336 -283.719276) (xy 411.336191 -283.725208) (xy 411.383462 -283.7389)
			(xy 411.427924 -283.759998) (xy 411.468427 -283.787954) (xy 411.50392 -283.822046) (xy 411.533485 -283.86139)
			(xy 411.556356 -283.904967) (xy 411.57194 -283.951648) (xy 411.579835 -284.000225) (xy 411.58033 -284.024832)
			(xy 411.919178 -284.024832) (xy 411.923138 -283.975778) (xy 411.934915 -283.927994) (xy 411.954206 -283.882718)
			(xy 411.980509 -283.841122) (xy 412.013144 -283.804285) (xy 412.051265 -283.77316) (xy 412.093886 -283.748553)
			(xy 412.139902 -283.731101) (xy 412.188121 -283.721257) (xy 412.237296 -283.719276) (xy 412.286151 -283.725208)
			(xy 412.333422 -283.7389) (xy 412.377884 -283.759998) (xy 412.418387 -283.787954) (xy 412.45388 -283.822046)
			(xy 412.483445 -283.86139) (xy 412.506316 -283.904967) (xy 412.5219 -283.951648) (xy 412.529795 -284.000225)
			(xy 412.53029 -284.024832) (xy 412.869138 -284.024832) (xy 412.873098 -283.975778) (xy 412.884875 -283.927994)
			(xy 412.904166 -283.882718) (xy 412.930469 -283.841122) (xy 412.963104 -283.804285) (xy 413.001225 -283.77316)
			(xy 413.043846 -283.748553) (xy 413.089862 -283.731101) (xy 413.138081 -283.721257) (xy 413.187256 -283.719276)
			(xy 413.236111 -283.725208) (xy 413.283382 -283.7389) (xy 413.327844 -283.759998) (xy 413.368347 -283.787954)
			(xy 413.40384 -283.822046) (xy 413.433405 -283.86139) (xy 413.456276 -283.904967) (xy 413.47186 -283.951648)
			(xy 413.479755 -284.000225) (xy 413.48025 -284.024832) (xy 413.819098 -284.024832) (xy 413.823058 -283.975778)
			(xy 413.834835 -283.927994) (xy 413.854126 -283.882718) (xy 413.880429 -283.841122) (xy 413.913064 -283.804285)
			(xy 413.951185 -283.77316) (xy 413.993806 -283.748553) (xy 414.039822 -283.731101) (xy 414.088041 -283.721257)
			(xy 414.137216 -283.719276) (xy 414.186071 -283.725208) (xy 414.233342 -283.7389) (xy 414.277804 -283.759998)
			(xy 414.318307 -283.787954) (xy 414.3538 -283.822046) (xy 414.383365 -283.86139) (xy 414.406236 -283.904967)
			(xy 414.42182 -283.951648) (xy 414.429715 -284.000225) (xy 414.43021 -284.024832) (xy 414.769058 -284.024832)
			(xy 414.773018 -283.975778) (xy 414.784795 -283.927994) (xy 414.804086 -283.882718) (xy 414.830389 -283.841122)
			(xy 414.863024 -283.804285) (xy 414.901145 -283.77316) (xy 414.943766 -283.748553) (xy 414.989782 -283.731101)
			(xy 415.038001 -283.721257) (xy 415.087176 -283.719276) (xy 415.136031 -283.725208) (xy 415.183302 -283.7389)
			(xy 415.227764 -283.759998) (xy 415.268267 -283.787954) (xy 415.30376 -283.822046) (xy 415.333325 -283.86139)
			(xy 415.356196 -283.904967) (xy 415.37178 -283.951648) (xy 415.379675 -284.000225) (xy 415.38017 -284.024832)
			(xy 415.719018 -284.024832) (xy 415.722978 -283.975778) (xy 415.734755 -283.927994) (xy 415.754046 -283.882718)
			(xy 415.780349 -283.841122) (xy 415.812984 -283.804285) (xy 415.851105 -283.77316) (xy 415.893726 -283.748553)
			(xy 415.939742 -283.731101) (xy 415.987961 -283.721257) (xy 416.037136 -283.719276) (xy 416.085991 -283.725208)
			(xy 416.133262 -283.7389) (xy 416.177724 -283.759998) (xy 416.218227 -283.787954) (xy 416.25372 -283.822046)
			(xy 416.283285 -283.86139) (xy 416.306156 -283.904967) (xy 416.32174 -283.951648) (xy 416.329635 -284.000225)
			(xy 416.33013 -284.024832) (xy 416.668978 -284.024832) (xy 416.672938 -283.975778) (xy 416.684715 -283.927994)
			(xy 416.704006 -283.882718) (xy 416.730309 -283.841122) (xy 416.762944 -283.804285) (xy 416.801065 -283.77316)
			(xy 416.843686 -283.748553) (xy 416.889702 -283.731101) (xy 416.937921 -283.721257) (xy 416.987096 -283.719276)
			(xy 417.035951 -283.725208) (xy 417.083222 -283.7389) (xy 417.127684 -283.759998) (xy 417.168187 -283.787954)
			(xy 417.20368 -283.822046) (xy 417.233245 -283.86139) (xy 417.256116 -283.904967) (xy 417.2717 -283.951648)
			(xy 417.279595 -284.000225) (xy 417.28009 -284.024832) (xy 417.619192 -284.024832) (xy 417.623152 -283.975778)
			(xy 417.634929 -283.927994) (xy 417.65422 -283.882718) (xy 417.680523 -283.841122) (xy 417.713158 -283.804285)
			(xy 417.751279 -283.77316) (xy 417.7939 -283.748553) (xy 417.839916 -283.731101) (xy 417.888135 -283.721257)
			(xy 417.93731 -283.719276) (xy 417.986165 -283.725208) (xy 418.033436 -283.7389) (xy 418.077898 -283.759998)
			(xy 418.118401 -283.787954) (xy 418.153894 -283.822046) (xy 418.183459 -283.86139) (xy 418.20633 -283.904967)
			(xy 418.221914 -283.951648) (xy 418.229809 -284.000225) (xy 418.230304 -284.024832) (xy 418.569152 -284.024832)
			(xy 418.573112 -283.975778) (xy 418.584889 -283.927994) (xy 418.60418 -283.882718) (xy 418.630483 -283.841122)
			(xy 418.663118 -283.804285) (xy 418.701239 -283.77316) (xy 418.74386 -283.748553) (xy 418.789876 -283.731101)
			(xy 418.838095 -283.721257) (xy 418.88727 -283.719276) (xy 418.936125 -283.725208) (xy 418.983396 -283.7389)
			(xy 419.027858 -283.759998) (xy 419.068361 -283.787954) (xy 419.103854 -283.822046) (xy 419.133419 -283.86139)
			(xy 419.15629 -283.904967) (xy 419.171874 -283.951648) (xy 419.179769 -284.000225) (xy 419.180264 -284.024832)
			(xy 419.519112 -284.024832) (xy 419.523072 -283.975778) (xy 419.534849 -283.927994) (xy 419.55414 -283.882718)
			(xy 419.580443 -283.841122) (xy 419.613078 -283.804285) (xy 419.651199 -283.77316) (xy 419.69382 -283.748553)
			(xy 419.739836 -283.731101) (xy 419.788055 -283.721257) (xy 419.83723 -283.719276) (xy 419.886085 -283.725208)
			(xy 419.933356 -283.7389) (xy 419.977818 -283.759998) (xy 420.018321 -283.787954) (xy 420.053814 -283.822046)
			(xy 420.083379 -283.86139) (xy 420.10625 -283.904967) (xy 420.121834 -283.951648) (xy 420.129729 -284.000225)
			(xy 420.130224 -284.024832) (xy 420.469072 -284.024832) (xy 420.473032 -283.975778) (xy 420.484809 -283.927994)
			(xy 420.5041 -283.882718) (xy 420.530403 -283.841122) (xy 420.563038 -283.804285) (xy 420.601159 -283.77316)
			(xy 420.64378 -283.748553) (xy 420.689796 -283.731101) (xy 420.738015 -283.721257) (xy 420.78719 -283.719276)
			(xy 420.836045 -283.725208) (xy 420.883316 -283.7389) (xy 420.927778 -283.759998) (xy 420.968281 -283.787954)
			(xy 421.003774 -283.822046) (xy 421.033339 -283.86139) (xy 421.05621 -283.904967) (xy 421.071794 -283.951648)
			(xy 421.079689 -284.000225) (xy 421.080184 -284.024832) (xy 421.079689 -284.049439) (xy 421.071794 -284.098016)
			(xy 421.05621 -284.144697) (xy 421.033339 -284.188274) (xy 421.003774 -284.227618) (xy 420.968281 -284.26171)
			(xy 420.927778 -284.289666) (xy 420.883316 -284.310764) (xy 420.836045 -284.324456) (xy 420.78719 -284.330388)
			(xy 420.738015 -284.328407) (xy 420.689796 -284.318563) (xy 420.64378 -284.301111) (xy 420.601159 -284.276504)
			(xy 420.563038 -284.245379) (xy 420.530403 -284.208542) (xy 420.5041 -284.166946) (xy 420.484809 -284.12167)
			(xy 420.473032 -284.073886) (xy 420.469072 -284.024832) (xy 420.130224 -284.024832) (xy 420.129729 -284.049439)
			(xy 420.121834 -284.098016) (xy 420.10625 -284.144697) (xy 420.083379 -284.188274) (xy 420.053814 -284.227618)
			(xy 420.018321 -284.26171) (xy 419.977818 -284.289666) (xy 419.933356 -284.310764) (xy 419.886085 -284.324456)
			(xy 419.83723 -284.330388) (xy 419.788055 -284.328407) (xy 419.739836 -284.318563) (xy 419.69382 -284.301111)
			(xy 419.651199 -284.276504) (xy 419.613078 -284.245379) (xy 419.580443 -284.208542) (xy 419.55414 -284.166946)
			(xy 419.534849 -284.12167) (xy 419.523072 -284.073886) (xy 419.519112 -284.024832) (xy 419.180264 -284.024832)
			(xy 419.179769 -284.049439) (xy 419.171874 -284.098016) (xy 419.15629 -284.144697) (xy 419.133419 -284.188274)
			(xy 419.103854 -284.227618) (xy 419.068361 -284.26171) (xy 419.027858 -284.289666) (xy 418.983396 -284.310764)
			(xy 418.936125 -284.324456) (xy 418.88727 -284.330388) (xy 418.838095 -284.328407) (xy 418.789876 -284.318563)
			(xy 418.74386 -284.301111) (xy 418.701239 -284.276504) (xy 418.663118 -284.245379) (xy 418.630483 -284.208542)
			(xy 418.60418 -284.166946) (xy 418.584889 -284.12167) (xy 418.573112 -284.073886) (xy 418.569152 -284.024832)
			(xy 418.230304 -284.024832) (xy 418.229809 -284.049439) (xy 418.221914 -284.098016) (xy 418.20633 -284.144697)
			(xy 418.183459 -284.188274) (xy 418.153894 -284.227618) (xy 418.118401 -284.26171) (xy 418.077898 -284.289666)
			(xy 418.033436 -284.310764) (xy 417.986165 -284.324456) (xy 417.93731 -284.330388) (xy 417.888135 -284.328407)
			(xy 417.839916 -284.318563) (xy 417.7939 -284.301111) (xy 417.751279 -284.276504) (xy 417.713158 -284.245379)
			(xy 417.680523 -284.208542) (xy 417.65422 -284.166946) (xy 417.634929 -284.12167) (xy 417.623152 -284.073886)
			(xy 417.619192 -284.024832) (xy 417.28009 -284.024832) (xy 417.279595 -284.049439) (xy 417.2717 -284.098016)
			(xy 417.256116 -284.144697) (xy 417.233245 -284.188274) (xy 417.20368 -284.227618) (xy 417.168187 -284.26171)
			(xy 417.127684 -284.289666) (xy 417.083222 -284.310764) (xy 417.035951 -284.324456) (xy 416.987096 -284.330388)
			(xy 416.937921 -284.328407) (xy 416.889702 -284.318563) (xy 416.843686 -284.301111) (xy 416.801065 -284.276504)
			(xy 416.762944 -284.245379) (xy 416.730309 -284.208542) (xy 416.704006 -284.166946) (xy 416.684715 -284.12167)
			(xy 416.672938 -284.073886) (xy 416.668978 -284.024832) (xy 416.33013 -284.024832) (xy 416.329635 -284.049439)
			(xy 416.32174 -284.098016) (xy 416.306156 -284.144697) (xy 416.283285 -284.188274) (xy 416.25372 -284.227618)
			(xy 416.218227 -284.26171) (xy 416.177724 -284.289666) (xy 416.133262 -284.310764) (xy 416.085991 -284.324456)
			(xy 416.037136 -284.330388) (xy 415.987961 -284.328407) (xy 415.939742 -284.318563) (xy 415.893726 -284.301111)
			(xy 415.851105 -284.276504) (xy 415.812984 -284.245379) (xy 415.780349 -284.208542) (xy 415.754046 -284.166946)
			(xy 415.734755 -284.12167) (xy 415.722978 -284.073886) (xy 415.719018 -284.024832) (xy 415.38017 -284.024832)
			(xy 415.379675 -284.049439) (xy 415.37178 -284.098016) (xy 415.356196 -284.144697) (xy 415.333325 -284.188274)
			(xy 415.30376 -284.227618) (xy 415.268267 -284.26171) (xy 415.227764 -284.289666) (xy 415.183302 -284.310764)
			(xy 415.136031 -284.324456) (xy 415.087176 -284.330388) (xy 415.038001 -284.328407) (xy 414.989782 -284.318563)
			(xy 414.943766 -284.301111) (xy 414.901145 -284.276504) (xy 414.863024 -284.245379) (xy 414.830389 -284.208542)
			(xy 414.804086 -284.166946) (xy 414.784795 -284.12167) (xy 414.773018 -284.073886) (xy 414.769058 -284.024832)
			(xy 414.43021 -284.024832) (xy 414.429715 -284.049439) (xy 414.42182 -284.098016) (xy 414.406236 -284.144697)
			(xy 414.383365 -284.188274) (xy 414.3538 -284.227618) (xy 414.318307 -284.26171) (xy 414.277804 -284.289666)
			(xy 414.233342 -284.310764) (xy 414.186071 -284.324456) (xy 414.137216 -284.330388) (xy 414.088041 -284.328407)
			(xy 414.039822 -284.318563) (xy 413.993806 -284.301111) (xy 413.951185 -284.276504) (xy 413.913064 -284.245379)
			(xy 413.880429 -284.208542) (xy 413.854126 -284.166946) (xy 413.834835 -284.12167) (xy 413.823058 -284.073886)
			(xy 413.819098 -284.024832) (xy 413.48025 -284.024832) (xy 413.479755 -284.049439) (xy 413.47186 -284.098016)
			(xy 413.456276 -284.144697) (xy 413.433405 -284.188274) (xy 413.40384 -284.227618) (xy 413.368347 -284.26171)
			(xy 413.327844 -284.289666) (xy 413.283382 -284.310764) (xy 413.236111 -284.324456) (xy 413.187256 -284.330388)
			(xy 413.138081 -284.328407) (xy 413.089862 -284.318563) (xy 413.043846 -284.301111) (xy 413.001225 -284.276504)
			(xy 412.963104 -284.245379) (xy 412.930469 -284.208542) (xy 412.904166 -284.166946) (xy 412.884875 -284.12167)
			(xy 412.873098 -284.073886) (xy 412.869138 -284.024832) (xy 412.53029 -284.024832) (xy 412.529795 -284.049439)
			(xy 412.5219 -284.098016) (xy 412.506316 -284.144697) (xy 412.483445 -284.188274) (xy 412.45388 -284.227618)
			(xy 412.418387 -284.26171) (xy 412.377884 -284.289666) (xy 412.333422 -284.310764) (xy 412.286151 -284.324456)
			(xy 412.237296 -284.330388) (xy 412.188121 -284.328407) (xy 412.139902 -284.318563) (xy 412.093886 -284.301111)
			(xy 412.051265 -284.276504) (xy 412.013144 -284.245379) (xy 411.980509 -284.208542) (xy 411.954206 -284.166946)
			(xy 411.934915 -284.12167) (xy 411.923138 -284.073886) (xy 411.919178 -284.024832) (xy 411.58033 -284.024832)
			(xy 411.579835 -284.049439) (xy 411.57194 -284.098016) (xy 411.556356 -284.144697) (xy 411.533485 -284.188274)
			(xy 411.50392 -284.227618) (xy 411.468427 -284.26171) (xy 411.427924 -284.289666) (xy 411.383462 -284.310764)
			(xy 411.336191 -284.324456) (xy 411.287336 -284.330388) (xy 411.238161 -284.328407) (xy 411.189942 -284.318563)
			(xy 411.143926 -284.301111) (xy 411.101305 -284.276504) (xy 411.063184 -284.245379) (xy 411.030549 -284.208542)
			(xy 411.004246 -284.166946) (xy 410.984955 -284.12167) (xy 410.973178 -284.073886) (xy 410.969218 -284.024832)
			(xy 410.630116 -284.024832) (xy 410.629621 -284.049439) (xy 410.621726 -284.098016) (xy 410.606142 -284.144697)
			(xy 410.583271 -284.188274) (xy 410.553706 -284.227618) (xy 410.518213 -284.26171) (xy 410.47771 -284.289666)
			(xy 410.433248 -284.310764) (xy 410.385977 -284.324456) (xy 410.337122 -284.330388) (xy 410.287947 -284.328407)
			(xy 410.239728 -284.318563) (xy 410.193712 -284.301111) (xy 410.151091 -284.276504) (xy 410.11297 -284.245379)
			(xy 410.080335 -284.208542) (xy 410.054032 -284.166946) (xy 410.034741 -284.12167) (xy 410.022964 -284.073886)
			(xy 410.019004 -284.024832) (xy 409.680156 -284.024832) (xy 409.679661 -284.049439) (xy 409.671766 -284.098016)
			(xy 409.656182 -284.144697) (xy 409.633311 -284.188274) (xy 409.603746 -284.227618) (xy 409.568253 -284.26171)
			(xy 409.52775 -284.289666) (xy 409.483288 -284.310764) (xy 409.436017 -284.324456) (xy 409.387162 -284.330388)
			(xy 409.337987 -284.328407) (xy 409.289768 -284.318563) (xy 409.243752 -284.301111) (xy 409.201131 -284.276504)
			(xy 409.16301 -284.245379) (xy 409.130375 -284.208542) (xy 409.104072 -284.166946) (xy 409.084781 -284.12167)
			(xy 409.073004 -284.073886) (xy 409.069044 -284.024832) (xy 408.730196 -284.024832) (xy 408.729701 -284.049439)
			(xy 408.721806 -284.098016) (xy 408.706222 -284.144697) (xy 408.683351 -284.188274) (xy 408.653786 -284.227618)
			(xy 408.618293 -284.26171) (xy 408.57779 -284.289666) (xy 408.533328 -284.310764) (xy 408.486057 -284.324456)
			(xy 408.437202 -284.330388) (xy 408.388027 -284.328407) (xy 408.339808 -284.318563) (xy 408.293792 -284.301111)
			(xy 408.251171 -284.276504) (xy 408.21305 -284.245379) (xy 408.180415 -284.208542) (xy 408.154112 -284.166946)
			(xy 408.134821 -284.12167) (xy 408.123044 -284.073886) (xy 408.119084 -284.024832) (xy 406.830276 -284.024832)
			(xy 406.829781 -284.049439) (xy 406.821886 -284.098016) (xy 406.806302 -284.144697) (xy 406.783431 -284.188274)
			(xy 406.753866 -284.227618) (xy 406.718373 -284.26171) (xy 406.67787 -284.289666) (xy 406.633408 -284.310764)
			(xy 406.586137 -284.324456) (xy 406.537282 -284.330388) (xy 406.488107 -284.328407) (xy 406.439888 -284.318563)
			(xy 406.393872 -284.301111) (xy 406.351251 -284.276504) (xy 406.31313 -284.245379) (xy 406.280495 -284.208542)
			(xy 406.254192 -284.166946) (xy 406.234901 -284.12167) (xy 406.223124 -284.073886) (xy 406.219164 -284.024832)
			(xy 405.880316 -284.024832) (xy 405.879821 -284.049439) (xy 405.871926 -284.098016) (xy 405.856342 -284.144697)
			(xy 405.833471 -284.188274) (xy 405.803906 -284.227618) (xy 405.768413 -284.26171) (xy 405.72791 -284.289666)
			(xy 405.683448 -284.310764) (xy 405.636177 -284.324456) (xy 405.587322 -284.330388) (xy 405.538147 -284.328407)
			(xy 405.489928 -284.318563) (xy 405.443912 -284.301111) (xy 405.401291 -284.276504) (xy 405.36317 -284.245379)
			(xy 405.330535 -284.208542) (xy 405.304232 -284.166946) (xy 405.284941 -284.12167) (xy 405.273164 -284.073886)
			(xy 405.269204 -284.024832) (xy 404.930102 -284.024832) (xy 404.929607 -284.049439) (xy 404.921712 -284.098016)
			(xy 404.906128 -284.144697) (xy 404.883257 -284.188274) (xy 404.853692 -284.227618) (xy 404.818199 -284.26171)
			(xy 404.777696 -284.289666) (xy 404.733234 -284.310764) (xy 404.685963 -284.324456) (xy 404.637108 -284.330388)
			(xy 404.587933 -284.328407) (xy 404.539714 -284.318563) (xy 404.493698 -284.301111) (xy 404.451077 -284.276504)
			(xy 404.412956 -284.245379) (xy 404.380321 -284.208542) (xy 404.354018 -284.166946) (xy 404.334727 -284.12167)
			(xy 404.32295 -284.073886) (xy 404.31899 -284.024832) (xy 403.980142 -284.024832) (xy 403.979647 -284.049439)
			(xy 403.971752 -284.098016) (xy 403.956168 -284.144697) (xy 403.933297 -284.188274) (xy 403.903732 -284.227618)
			(xy 403.868239 -284.26171) (xy 403.827736 -284.289666) (xy 403.783274 -284.310764) (xy 403.736003 -284.324456)
			(xy 403.687148 -284.330388) (xy 403.637973 -284.328407) (xy 403.589754 -284.318563) (xy 403.543738 -284.301111)
			(xy 403.501117 -284.276504) (xy 403.462996 -284.245379) (xy 403.430361 -284.208542) (xy 403.404058 -284.166946)
			(xy 403.384767 -284.12167) (xy 403.37299 -284.073886) (xy 403.36903 -284.024832) (xy 403.030182 -284.024832)
			(xy 403.029687 -284.049439) (xy 403.021792 -284.098016) (xy 403.006208 -284.144697) (xy 402.983337 -284.188274)
			(xy 402.953772 -284.227618) (xy 402.918279 -284.26171) (xy 402.877776 -284.289666) (xy 402.833314 -284.310764)
			(xy 402.786043 -284.324456) (xy 402.737188 -284.330388) (xy 402.688013 -284.328407) (xy 402.639794 -284.318563)
			(xy 402.593778 -284.301111) (xy 402.551157 -284.276504) (xy 402.513036 -284.245379) (xy 402.480401 -284.208542)
			(xy 402.454098 -284.166946) (xy 402.434807 -284.12167) (xy 402.42303 -284.073886) (xy 402.41907 -284.024832)
			(xy 402.080222 -284.024832) (xy 402.079727 -284.049439) (xy 402.071832 -284.098016) (xy 402.056248 -284.144697)
			(xy 402.033377 -284.188274) (xy 402.003812 -284.227618) (xy 401.968319 -284.26171) (xy 401.927816 -284.289666)
			(xy 401.883354 -284.310764) (xy 401.836083 -284.324456) (xy 401.787228 -284.330388) (xy 401.738053 -284.328407)
			(xy 401.689834 -284.318563) (xy 401.643818 -284.301111) (xy 401.601197 -284.276504) (xy 401.563076 -284.245379)
			(xy 401.530441 -284.208542) (xy 401.504138 -284.166946) (xy 401.484847 -284.12167) (xy 401.47307 -284.073886)
			(xy 401.46911 -284.024832) (xy 401.130262 -284.024832) (xy 401.129767 -284.049439) (xy 401.121872 -284.098016)
			(xy 401.106288 -284.144697) (xy 401.083417 -284.188274) (xy 401.053852 -284.227618) (xy 401.018359 -284.26171)
			(xy 400.977856 -284.289666) (xy 400.933394 -284.310764) (xy 400.886123 -284.324456) (xy 400.837268 -284.330388)
			(xy 400.788093 -284.328407) (xy 400.739874 -284.318563) (xy 400.693858 -284.301111) (xy 400.651237 -284.276504)
			(xy 400.613116 -284.245379) (xy 400.580481 -284.208542) (xy 400.554178 -284.166946) (xy 400.534887 -284.12167)
			(xy 400.52311 -284.073886) (xy 400.51915 -284.024832) (xy 400.180302 -284.024832) (xy 400.179807 -284.049439)
			(xy 400.171912 -284.098016) (xy 400.156328 -284.144697) (xy 400.133457 -284.188274) (xy 400.103892 -284.227618)
			(xy 400.068399 -284.26171) (xy 400.027896 -284.289666) (xy 399.983434 -284.310764) (xy 399.936163 -284.324456)
			(xy 399.887308 -284.330388) (xy 399.838133 -284.328407) (xy 399.789914 -284.318563) (xy 399.743898 -284.301111)
			(xy 399.701277 -284.276504) (xy 399.663156 -284.245379) (xy 399.630521 -284.208542) (xy 399.604218 -284.166946)
			(xy 399.584927 -284.12167) (xy 399.57315 -284.073886) (xy 399.56919 -284.024832) (xy 399.230342 -284.024832)
			(xy 399.229847 -284.049439) (xy 399.221952 -284.098016) (xy 399.206368 -284.144697) (xy 399.183497 -284.188274)
			(xy 399.153932 -284.227618) (xy 399.118439 -284.26171) (xy 399.077936 -284.289666) (xy 399.033474 -284.310764)
			(xy 398.986203 -284.324456) (xy 398.937348 -284.330388) (xy 398.888173 -284.328407) (xy 398.839954 -284.318563)
			(xy 398.793938 -284.301111) (xy 398.751317 -284.276504) (xy 398.713196 -284.245379) (xy 398.680561 -284.208542)
			(xy 398.654258 -284.166946) (xy 398.634967 -284.12167) (xy 398.62319 -284.073886) (xy 398.61923 -284.024832)
			(xy 398.280596 -284.024832) (xy 398.276429 -284.075131) (xy 398.264031 -284.124089) (xy 398.243745 -284.170339)
			(xy 398.216124 -284.212619) (xy 398.18192 -284.249776) (xy 398.142067 -284.280798) (xy 398.097652 -284.304837)
			(xy 398.049886 -284.321237) (xy 398.000072 -284.329553) (xy 397.97482 -284.33014) (xy 397.96328 -284.330014)
			(xy 397.940268 -284.328237) (xy 397.928846 -284.326584) (xy 397.925036 -284.326076) (xy 397.92402 -284.326076)
			(xy 397.900114 -284.321564) (xy 397.85403 -284.305979) (xy 397.81099 -284.283302) (xy 397.772078 -284.254105)
			(xy 397.754856 -284.236922) (xy 397.743934 -284.225492) (xy 397.713962 -284.219142) (xy 397.611854 -284.26029)
			(xy 397.602691 -284.264483) (xy 397.588379 -284.278647) (xy 397.580585 -284.297214) (xy 397.580104 -284.30728)
			(xy 397.580104 -284.499812) (xy 421.894012 -284.499812) (xy 421.897972 -284.450758) (xy 421.909749 -284.402974)
			(xy 421.92904 -284.357698) (xy 421.955343 -284.316102) (xy 421.987978 -284.279265) (xy 422.026099 -284.24814)
			(xy 422.06872 -284.223533) (xy 422.114736 -284.206081) (xy 422.162955 -284.196237) (xy 422.21213 -284.194256)
			(xy 422.260985 -284.200188) (xy 422.308256 -284.21388) (xy 422.352718 -284.234978) (xy 422.393221 -284.262934)
			(xy 422.428714 -284.297026) (xy 422.458279 -284.33637) (xy 422.48115 -284.379947) (xy 422.496734 -284.426628)
			(xy 422.504629 -284.475205) (xy 422.505124 -284.499812) (xy 422.843972 -284.499812) (xy 422.847932 -284.450758)
			(xy 422.859709 -284.402974) (xy 422.879 -284.357698) (xy 422.905303 -284.316102) (xy 422.937938 -284.279265)
			(xy 422.976059 -284.24814) (xy 423.01868 -284.223533) (xy 423.064696 -284.206081) (xy 423.112915 -284.196237)
			(xy 423.16209 -284.194256) (xy 423.210945 -284.200188) (xy 423.258216 -284.21388) (xy 423.302678 -284.234978)
			(xy 423.343181 -284.262934) (xy 423.378674 -284.297026) (xy 423.408239 -284.33637) (xy 423.43111 -284.379947)
			(xy 423.446694 -284.426628) (xy 423.454589 -284.475205) (xy 423.455084 -284.499812) (xy 423.794186 -284.499812)
			(xy 423.798146 -284.450758) (xy 423.809923 -284.402974) (xy 423.829214 -284.357698) (xy 423.855517 -284.316102)
			(xy 423.888152 -284.279265) (xy 423.926273 -284.24814) (xy 423.968894 -284.223533) (xy 424.01491 -284.206081)
			(xy 424.063129 -284.196237) (xy 424.112304 -284.194256) (xy 424.161159 -284.200188) (xy 424.20843 -284.21388)
			(xy 424.252892 -284.234978) (xy 424.293395 -284.262934) (xy 424.328888 -284.297026) (xy 424.358453 -284.33637)
			(xy 424.381324 -284.379947) (xy 424.396908 -284.426628) (xy 424.404803 -284.475205) (xy 424.405298 -284.499812)
			(xy 424.404803 -284.524419) (xy 424.404624 -284.52552) (xy 424.723302 -284.52552) (xy 424.723302 -284.474104)
			(xy 424.731345 -284.423322) (xy 424.747233 -284.374423) (xy 424.770576 -284.328611) (xy 424.800797 -284.287015)
			(xy 424.837153 -284.250659) (xy 424.878749 -284.220438) (xy 424.924561 -284.197095) (xy 424.97346 -284.181207)
			(xy 425.024242 -284.173164) (xy 425.075658 -284.173164) (xy 425.12644 -284.181207) (xy 425.175339 -284.197095)
			(xy 425.221151 -284.220438) (xy 425.262747 -284.250659) (xy 425.299103 -284.287015) (xy 425.329324 -284.328611)
			(xy 425.352667 -284.374423) (xy 425.368555 -284.423322) (xy 425.376598 -284.474104) (xy 425.377102 -284.499812)
			(xy 425.376598 -284.52552) (xy 425.673262 -284.52552) (xy 425.673262 -284.474104) (xy 425.681305 -284.423322)
			(xy 425.697193 -284.374423) (xy 425.720536 -284.328611) (xy 425.750757 -284.287015) (xy 425.787113 -284.250659)
			(xy 425.828709 -284.220438) (xy 425.874521 -284.197095) (xy 425.92342 -284.181207) (xy 425.974202 -284.173164)
			(xy 426.025618 -284.173164) (xy 426.0764 -284.181207) (xy 426.125299 -284.197095) (xy 426.171111 -284.220438)
			(xy 426.212707 -284.250659) (xy 426.249063 -284.287015) (xy 426.279284 -284.328611) (xy 426.302627 -284.374423)
			(xy 426.318515 -284.423322) (xy 426.326558 -284.474104) (xy 426.327062 -284.499812) (xy 426.644066 -284.499812)
			(xy 426.648026 -284.450758) (xy 426.659803 -284.402974) (xy 426.679094 -284.357698) (xy 426.705397 -284.316102)
			(xy 426.738032 -284.279265) (xy 426.776153 -284.24814) (xy 426.818774 -284.223533) (xy 426.86479 -284.206081)
			(xy 426.913009 -284.196237) (xy 426.962184 -284.194256) (xy 427.011039 -284.200188) (xy 427.05831 -284.21388)
			(xy 427.102772 -284.234978) (xy 427.143275 -284.262934) (xy 427.178768 -284.297026) (xy 427.208333 -284.33637)
			(xy 427.231204 -284.379947) (xy 427.246788 -284.426628) (xy 427.254683 -284.475205) (xy 427.255178 -284.499812)
			(xy 427.254683 -284.524419) (xy 427.254504 -284.52552) (xy 427.573182 -284.52552) (xy 427.573182 -284.474104)
			(xy 427.581225 -284.423322) (xy 427.597113 -284.374423) (xy 427.620456 -284.328611) (xy 427.650677 -284.287015)
			(xy 427.687033 -284.250659) (xy 427.728629 -284.220438) (xy 427.774441 -284.197095) (xy 427.82334 -284.181207)
			(xy 427.874122 -284.173164) (xy 427.925538 -284.173164) (xy 427.97632 -284.181207) (xy 428.025219 -284.197095)
			(xy 428.071031 -284.220438) (xy 428.112627 -284.250659) (xy 428.148983 -284.287015) (xy 428.179204 -284.328611)
			(xy 428.202547 -284.374423) (xy 428.218435 -284.423322) (xy 428.226478 -284.474104) (xy 428.226982 -284.499812)
			(xy 428.226478 -284.52552) (xy 428.523142 -284.52552) (xy 428.523142 -284.474104) (xy 428.531185 -284.423322)
			(xy 428.547073 -284.374423) (xy 428.570416 -284.328611) (xy 428.600637 -284.287015) (xy 428.636993 -284.250659)
			(xy 428.678589 -284.220438) (xy 428.724401 -284.197095) (xy 428.7733 -284.181207) (xy 428.824082 -284.173164)
			(xy 428.875498 -284.173164) (xy 428.92628 -284.181207) (xy 428.975179 -284.197095) (xy 429.020991 -284.220438)
			(xy 429.062587 -284.250659) (xy 429.098943 -284.287015) (xy 429.129164 -284.328611) (xy 429.152507 -284.374423)
			(xy 429.168395 -284.423322) (xy 429.176438 -284.474104) (xy 429.176942 -284.499812) (xy 429.4942 -284.499812)
			(xy 429.49816 -284.450758) (xy 429.509937 -284.402974) (xy 429.529228 -284.357698) (xy 429.555531 -284.316102)
			(xy 429.588166 -284.279265) (xy 429.626287 -284.24814) (xy 429.668908 -284.223533) (xy 429.714924 -284.206081)
			(xy 429.763143 -284.196237) (xy 429.812318 -284.194256) (xy 429.861173 -284.200188) (xy 429.908444 -284.21388)
			(xy 429.952906 -284.234978) (xy 429.993409 -284.262934) (xy 430.028902 -284.297026) (xy 430.058467 -284.33637)
			(xy 430.081338 -284.379947) (xy 430.096922 -284.426628) (xy 430.104817 -284.475205) (xy 430.105312 -284.499812)
			(xy 430.44416 -284.499812) (xy 430.44812 -284.450758) (xy 430.459897 -284.402974) (xy 430.479188 -284.357698)
			(xy 430.505491 -284.316102) (xy 430.538126 -284.279265) (xy 430.576247 -284.24814) (xy 430.618868 -284.223533)
			(xy 430.664884 -284.206081) (xy 430.713103 -284.196237) (xy 430.762278 -284.194256) (xy 430.811133 -284.200188)
			(xy 430.858404 -284.21388) (xy 430.902866 -284.234978) (xy 430.943369 -284.262934) (xy 430.978862 -284.297026)
			(xy 431.008427 -284.33637) (xy 431.031298 -284.379947) (xy 431.046882 -284.426628) (xy 431.054777 -284.475205)
			(xy 431.055272 -284.499812) (xy 431.054777 -284.524419) (xy 431.046882 -284.572996) (xy 431.031298 -284.619677)
			(xy 431.008427 -284.663254) (xy 430.978862 -284.702598) (xy 430.943369 -284.73669) (xy 430.902866 -284.764646)
			(xy 430.858404 -284.785744) (xy 430.835922 -284.792256) (xy 448.411243 -284.792256) (xy 448.411243 -284.737744)
			(xy 448.419001 -284.683787) (xy 448.43436 -284.631484) (xy 448.457007 -284.581899) (xy 448.48648 -284.536043)
			(xy 448.52218 -284.494847) (xy 448.563379 -284.459153) (xy 448.60924 -284.429685) (xy 448.658827 -284.407044)
			(xy 448.711132 -284.391692) (xy 448.76509 -284.38394) (xy 448.792346 -284.38348) (xy 448.821086 -284.383981)
			(xy 448.877914 -284.39261) (xy 448.932805 -284.409666) (xy 448.984516 -284.434762) (xy 449.031878 -284.467331)
			(xy 449.053204 -284.486604) (xy 449.060316 -284.493208) (xy 449.077842 -284.50032) (xy 449.16725 -284.50032)
			(xy 449.184776 -284.493208) (xy 449.191888 -284.486604) (xy 449.213215 -284.467334) (xy 449.260578 -284.434769)
			(xy 449.312289 -284.409678) (xy 449.36718 -284.392628) (xy 449.424007 -284.384006) (xy 449.481485 -284.384006)
			(xy 449.538312 -284.392628) (xy 449.593203 -284.409678) (xy 449.644914 -284.434769) (xy 449.692277 -284.467334)
			(xy 449.713604 -284.486604) (xy 449.720716 -284.493208) (xy 449.738242 -284.50032) (xy 449.82765 -284.50032)
			(xy 449.845176 -284.493208) (xy 449.852288 -284.486604) (xy 449.873606 -284.467323) (xy 449.920969 -284.434756)
			(xy 449.972683 -284.409664) (xy 450.027576 -284.392616) (xy 450.084406 -284.383998) (xy 450.113146 -284.38348)
			(xy 450.143268 -284.384076) (xy 450.202764 -284.39355) (xy 450.260032 -284.412254) (xy 450.31365 -284.439725)
			(xy 450.362285 -284.475279) (xy 450.38391 -284.496256) (xy 450.391022 -284.503622) (xy 450.409818 -284.511242)
			(xy 450.502274 -284.511242) (xy 450.52107 -284.503622) (xy 450.528182 -284.496256) (xy 450.549801 -284.475269)
			(xy 450.59843 -284.439699) (xy 450.652048 -284.412219) (xy 450.70932 -284.393513) (xy 450.768821 -284.384046)
			(xy 450.798946 -284.38348) (xy 450.826194 -284.383993) (xy 450.880135 -284.391755) (xy 450.932423 -284.407114)
			(xy 450.981993 -284.429757) (xy 451.027836 -284.459223) (xy 451.069019 -284.494914) (xy 451.104704 -284.536101)
			(xy 451.134165 -284.581948) (xy 451.156803 -284.63152) (xy 451.172155 -284.68381) (xy 451.17991 -284.737752)
			(xy 451.17991 -284.792248) (xy 451.179909 -284.792255) (xy 453.090443 -284.792255) (xy 453.090443 -284.737745)
			(xy 453.098201 -284.683789) (xy 453.113559 -284.631487) (xy 453.136205 -284.581903) (xy 453.165677 -284.536047)
			(xy 453.201376 -284.494852) (xy 453.242574 -284.459157) (xy 453.288433 -284.429689) (xy 453.338019 -284.407047)
			(xy 453.390322 -284.391694) (xy 453.444279 -284.383941) (xy 453.471534 -284.38348) (xy 453.500273 -284.383988)
			(xy 453.557101 -284.392616) (xy 453.611992 -284.409669) (xy 453.663703 -284.434764) (xy 453.711065 -284.467332)
			(xy 453.732392 -284.486604) (xy 453.739504 -284.493208) (xy 453.75703 -284.50032) (xy 453.846438 -284.50032)
			(xy 453.863964 -284.493208) (xy 453.871076 -284.486604) (xy 453.892403 -284.467334) (xy 453.939766 -284.434769)
			(xy 453.991477 -284.409678) (xy 454.046368 -284.392628) (xy 454.103195 -284.384006) (xy 454.160673 -284.384006)
			(xy 454.2175 -284.392628) (xy 454.272391 -284.409678) (xy 454.324102 -284.434769) (xy 454.371465 -284.467334)
			(xy 454.392792 -284.486604) (xy 454.399904 -284.493208) (xy 454.41743 -284.50032) (xy 454.506838 -284.50032)
			(xy 454.524364 -284.493208) (xy 454.531476 -284.486604) (xy 454.552799 -284.467328) (xy 454.600161 -284.43476)
			(xy 454.651873 -284.409668) (xy 454.706766 -284.392619) (xy 454.763595 -284.383999) (xy 454.792334 -284.38348)
			(xy 454.822459 -284.38402) (xy 454.881957 -284.393508) (xy 454.939226 -284.412225) (xy 454.992842 -284.439708)
			(xy 455.041475 -284.475274) (xy 455.063098 -284.496256) (xy 455.07021 -284.503622) (xy 455.089006 -284.511242)
			(xy 455.181462 -284.511242) (xy 455.200258 -284.503622) (xy 455.20737 -284.496256) (xy 455.228994 -284.475275)
			(xy 455.277622 -284.439704) (xy 455.331239 -284.412223) (xy 455.388509 -284.393516) (xy 455.44801 -284.384047)
			(xy 455.478134 -284.38348) (xy 455.505383 -284.383993) (xy 455.559325 -284.391753) (xy 455.611614 -284.40711)
			(xy 455.661185 -284.429753) (xy 455.70703 -284.459219) (xy 455.748215 -284.494909) (xy 455.783901 -284.536097)
			(xy 455.813364 -284.581945) (xy 455.836002 -284.631518) (xy 455.851354 -284.683808) (xy 455.85911 -284.737751)
			(xy 455.85911 -284.792249) (xy 455.851354 -284.846192) (xy 455.836002 -284.898482) (xy 455.813364 -284.948055)
			(xy 455.783901 -284.993903) (xy 455.748215 -285.035091) (xy 455.70703 -285.070781) (xy 455.661185 -285.100247)
			(xy 455.611614 -285.12289) (xy 455.559325 -285.138247) (xy 455.505383 -285.146007) (xy 455.478134 -285.146496)
			(xy 455.448011 -285.145919) (xy 455.388514 -285.136442) (xy 455.331245 -285.117733) (xy 455.277628 -285.090258)
			(xy 455.228994 -285.054699) (xy 455.20737 -285.03372) (xy 455.200258 -285.026354) (xy 455.181462 -285.018734)
			(xy 455.089006 -285.018734) (xy 455.07021 -285.026354) (xy 455.063098 -285.03372) (xy 455.041501 -285.05473)
			(xy 454.992864 -285.090293) (xy 454.939241 -285.117768) (xy 454.881964 -285.136469) (xy 454.82246 -285.145932)
			(xy 454.792334 -285.146496) (xy 454.763594 -285.146013) (xy 454.706764 -285.137381) (xy 454.651873 -285.120321)
			(xy 454.600162 -285.095221) (xy 454.552801 -285.062647) (xy 454.531476 -285.043372) (xy 454.524364 -285.036768)
			(xy 454.506838 -285.029656) (xy 454.41743 -285.029656) (xy 454.399904 -285.036768) (xy 454.392792 -285.043372)
			(xy 454.371465 -285.062642) (xy 454.324102 -285.095207) (xy 454.272391 -285.120298) (xy 454.2175 -285.137348)
			(xy 454.160673 -285.14597) (xy 454.103195 -285.14597) (xy 454.046368 -285.137348) (xy 453.991477 -285.120298)
			(xy 453.939766 -285.095207) (xy 453.892403 -285.062642) (xy 453.871076 -285.043372) (xy 453.863964 -285.036768)
			(xy 453.846438 -285.029656) (xy 453.75703 -285.029656) (xy 453.739504 -285.036768) (xy 453.732392 -285.043372)
			(xy 453.711052 -285.062628) (xy 453.663694 -285.095196) (xy 453.611985 -285.120291) (xy 453.557097 -285.137345)
			(xy 453.500272 -285.145973) (xy 453.471534 -285.146496) (xy 453.444279 -285.146059) (xy 453.390322 -285.138306)
			(xy 453.338019 -285.122953) (xy 453.288433 -285.100311) (xy 453.242574 -285.070843) (xy 453.201376 -285.035148)
			(xy 453.165677 -284.993953) (xy 453.136205 -284.948097) (xy 453.113559 -284.898513) (xy 453.098201 -284.846211)
			(xy 453.090443 -284.792255) (xy 451.179909 -284.792255) (xy 451.172155 -284.84619) (xy 451.156803 -284.89848)
			(xy 451.134165 -284.948052) (xy 451.104704 -284.993899) (xy 451.069019 -285.035086) (xy 451.027836 -285.070777)
			(xy 450.981993 -285.100243) (xy 450.932423 -285.122886) (xy 450.880135 -285.138245) (xy 450.826194 -285.146007)
			(xy 450.798946 -285.146496) (xy 450.768823 -285.145912) (xy 450.709327 -285.136436) (xy 450.652058 -285.117729)
			(xy 450.598441 -285.090256) (xy 450.549807 -285.054699) (xy 450.528182 -285.03372) (xy 450.52107 -285.026354)
			(xy 450.502274 -285.018734) (xy 450.409818 -285.018734) (xy 450.391022 -285.026354) (xy 450.38391 -285.03372)
			(xy 450.362307 -285.054724) (xy 450.313672 -285.090288) (xy 450.26005 -285.117764) (xy 450.202775 -285.136466)
			(xy 450.143272 -285.145931) (xy 450.113146 -285.146496) (xy 450.084406 -285.146006) (xy 450.027577 -285.137375)
			(xy 449.972686 -285.120318) (xy 449.920975 -285.095218) (xy 449.873614 -285.062646) (xy 449.852288 -285.043372)
			(xy 449.845176 -285.036768) (xy 449.82765 -285.029656) (xy 449.738242 -285.029656) (xy 449.720716 -285.036768)
			(xy 449.713604 -285.043372) (xy 449.692277 -285.062642) (xy 449.644914 -285.095207) (xy 449.593203 -285.120298)
			(xy 449.538312 -285.137348) (xy 449.481485 -285.14597) (xy 449.424007 -285.14597) (xy 449.36718 -285.137348)
			(xy 449.312289 -285.120298) (xy 449.260578 -285.095207) (xy 449.213215 -285.062642) (xy 449.191888 -285.043372)
			(xy 449.184776 -285.036768) (xy 449.16725 -285.029656) (xy 449.077842 -285.029656) (xy 449.060316 -285.036768)
			(xy 449.053204 -285.043372) (xy 449.031901 -285.06267) (xy 448.984532 -285.095232) (xy 448.932814 -285.120319)
			(xy 448.877918 -285.137363) (xy 448.821087 -285.145979) (xy 448.792346 -285.146496) (xy 448.76509 -285.14606)
			(xy 448.711132 -285.138308) (xy 448.658827 -285.122956) (xy 448.60924 -285.100315) (xy 448.563379 -285.070847)
			(xy 448.52218 -285.035153) (xy 448.48648 -284.993957) (xy 448.457007 -284.948101) (xy 448.43436 -284.898516)
			(xy 448.419001 -284.846213) (xy 448.411243 -284.792256) (xy 430.835922 -284.792256) (xy 430.811133 -284.799436)
			(xy 430.762278 -284.805368) (xy 430.713103 -284.803387) (xy 430.664884 -284.793543) (xy 430.618868 -284.776091)
			(xy 430.576247 -284.751484) (xy 430.538126 -284.720359) (xy 430.505491 -284.683522) (xy 430.479188 -284.641926)
			(xy 430.459897 -284.59665) (xy 430.44812 -284.548866) (xy 430.44416 -284.499812) (xy 430.105312 -284.499812)
			(xy 430.104817 -284.524419) (xy 430.096922 -284.572996) (xy 430.081338 -284.619677) (xy 430.058467 -284.663254)
			(xy 430.028902 -284.702598) (xy 429.993409 -284.73669) (xy 429.952906 -284.764646) (xy 429.908444 -284.785744)
			(xy 429.861173 -284.799436) (xy 429.812318 -284.805368) (xy 429.763143 -284.803387) (xy 429.714924 -284.793543)
			(xy 429.668908 -284.776091) (xy 429.626287 -284.751484) (xy 429.588166 -284.720359) (xy 429.555531 -284.683522)
			(xy 429.529228 -284.641926) (xy 429.509937 -284.59665) (xy 429.49816 -284.548866) (xy 429.4942 -284.499812)
			(xy 429.176942 -284.499812) (xy 429.176438 -284.52552) (xy 429.168395 -284.576302) (xy 429.152507 -284.625201)
			(xy 429.129164 -284.671013) (xy 429.098943 -284.712609) (xy 429.062587 -284.748965) (xy 429.020991 -284.779186)
			(xy 428.975179 -284.802529) (xy 428.92628 -284.818417) (xy 428.875498 -284.82646) (xy 428.824082 -284.82646)
			(xy 428.7733 -284.818417) (xy 428.724401 -284.802529) (xy 428.678589 -284.779186) (xy 428.636993 -284.748965)
			(xy 428.600637 -284.712609) (xy 428.570416 -284.671013) (xy 428.547073 -284.625201) (xy 428.531185 -284.576302)
			(xy 428.523142 -284.52552) (xy 428.226478 -284.52552) (xy 428.218435 -284.576302) (xy 428.202547 -284.625201)
			(xy 428.179204 -284.671013) (xy 428.148983 -284.712609) (xy 428.112627 -284.748965) (xy 428.071031 -284.779186)
			(xy 428.025219 -284.802529) (xy 427.97632 -284.818417) (xy 427.925538 -284.82646) (xy 427.874122 -284.82646)
			(xy 427.82334 -284.818417) (xy 427.774441 -284.802529) (xy 427.728629 -284.779186) (xy 427.687033 -284.748965)
			(xy 427.650677 -284.712609) (xy 427.620456 -284.671013) (xy 427.597113 -284.625201) (xy 427.581225 -284.576302)
			(xy 427.573182 -284.52552) (xy 427.254504 -284.52552) (xy 427.246788 -284.572996) (xy 427.231204 -284.619677)
			(xy 427.208333 -284.663254) (xy 427.178768 -284.702598) (xy 427.143275 -284.73669) (xy 427.102772 -284.764646)
			(xy 427.05831 -284.785744) (xy 427.011039 -284.799436) (xy 426.962184 -284.805368) (xy 426.913009 -284.803387)
			(xy 426.86479 -284.793543) (xy 426.818774 -284.776091) (xy 426.776153 -284.751484) (xy 426.738032 -284.720359)
			(xy 426.705397 -284.683522) (xy 426.679094 -284.641926) (xy 426.659803 -284.59665) (xy 426.648026 -284.548866)
			(xy 426.644066 -284.499812) (xy 426.327062 -284.499812) (xy 426.326558 -284.52552) (xy 426.318515 -284.576302)
			(xy 426.302627 -284.625201) (xy 426.279284 -284.671013) (xy 426.249063 -284.712609) (xy 426.212707 -284.748965)
			(xy 426.171111 -284.779186) (xy 426.125299 -284.802529) (xy 426.0764 -284.818417) (xy 426.025618 -284.82646)
			(xy 425.974202 -284.82646) (xy 425.92342 -284.818417) (xy 425.874521 -284.802529) (xy 425.828709 -284.779186)
			(xy 425.787113 -284.748965) (xy 425.750757 -284.712609) (xy 425.720536 -284.671013) (xy 425.697193 -284.625201)
			(xy 425.681305 -284.576302) (xy 425.673262 -284.52552) (xy 425.376598 -284.52552) (xy 425.368555 -284.576302)
			(xy 425.352667 -284.625201) (xy 425.329324 -284.671013) (xy 425.299103 -284.712609) (xy 425.262747 -284.748965)
			(xy 425.221151 -284.779186) (xy 425.175339 -284.802529) (xy 425.12644 -284.818417) (xy 425.075658 -284.82646)
			(xy 425.024242 -284.82646) (xy 424.97346 -284.818417) (xy 424.924561 -284.802529) (xy 424.878749 -284.779186)
			(xy 424.837153 -284.748965) (xy 424.800797 -284.712609) (xy 424.770576 -284.671013) (xy 424.747233 -284.625201)
			(xy 424.731345 -284.576302) (xy 424.723302 -284.52552) (xy 424.404624 -284.52552) (xy 424.396908 -284.572996)
			(xy 424.381324 -284.619677) (xy 424.358453 -284.663254) (xy 424.328888 -284.702598) (xy 424.293395 -284.73669)
			(xy 424.252892 -284.764646) (xy 424.20843 -284.785744) (xy 424.161159 -284.799436) (xy 424.112304 -284.805368)
			(xy 424.063129 -284.803387) (xy 424.01491 -284.793543) (xy 423.968894 -284.776091) (xy 423.926273 -284.751484)
			(xy 423.888152 -284.720359) (xy 423.855517 -284.683522) (xy 423.829214 -284.641926) (xy 423.809923 -284.59665)
			(xy 423.798146 -284.548866) (xy 423.794186 -284.499812) (xy 423.455084 -284.499812) (xy 423.454589 -284.524419)
			(xy 423.446694 -284.572996) (xy 423.43111 -284.619677) (xy 423.408239 -284.663254) (xy 423.378674 -284.702598)
			(xy 423.343181 -284.73669) (xy 423.302678 -284.764646) (xy 423.258216 -284.785744) (xy 423.210945 -284.799436)
			(xy 423.16209 -284.805368) (xy 423.112915 -284.803387) (xy 423.064696 -284.793543) (xy 423.01868 -284.776091)
			(xy 422.976059 -284.751484) (xy 422.937938 -284.720359) (xy 422.905303 -284.683522) (xy 422.879 -284.641926)
			(xy 422.859709 -284.59665) (xy 422.847932 -284.548866) (xy 422.843972 -284.499812) (xy 422.505124 -284.499812)
			(xy 422.504629 -284.524419) (xy 422.496734 -284.572996) (xy 422.48115 -284.619677) (xy 422.458279 -284.663254)
			(xy 422.428714 -284.702598) (xy 422.393221 -284.73669) (xy 422.352718 -284.764646) (xy 422.308256 -284.785744)
			(xy 422.260985 -284.799436) (xy 422.21213 -284.805368) (xy 422.162955 -284.803387) (xy 422.114736 -284.793543)
			(xy 422.06872 -284.776091) (xy 422.026099 -284.751484) (xy 421.987978 -284.720359) (xy 421.955343 -284.683522)
			(xy 421.92904 -284.641926) (xy 421.909749 -284.59665) (xy 421.897972 -284.548866) (xy 421.894012 -284.499812)
			(xy 397.580104 -284.499812) (xy 397.580104 -284.692344) (xy 397.580533 -284.702421) (xy 397.58831 -284.721013)
			(xy 397.602676 -284.735148) (xy 397.611854 -284.739334) (xy 397.713962 -284.780482) (xy 397.744188 -284.774132)
			(xy 397.75511 -284.762702) (xy 397.772509 -284.745399) (xy 397.811806 -284.716015) (xy 397.855292 -284.693287)
			(xy 397.901851 -284.677798) (xy 397.950286 -284.669946) (xy 397.97482 -284.669484) (xy 398.000075 -284.670007)
			(xy 398.049895 -284.678324) (xy 398.097668 -284.694727) (xy 398.142089 -284.718769) (xy 398.181947 -284.749794)
			(xy 398.216155 -284.786956) (xy 398.24378 -284.829242) (xy 398.264069 -284.875498) (xy 398.276468 -284.924463)
			(xy 398.280638 -284.974792) (xy 398.61923 -284.974792) (xy 398.62319 -284.925738) (xy 398.634967 -284.877954)
			(xy 398.654258 -284.832678) (xy 398.680561 -284.791082) (xy 398.713196 -284.754245) (xy 398.751317 -284.72312)
			(xy 398.793938 -284.698513) (xy 398.839954 -284.681061) (xy 398.888173 -284.671217) (xy 398.937348 -284.669236)
			(xy 398.986203 -284.675168) (xy 399.033474 -284.68886) (xy 399.077936 -284.709958) (xy 399.118439 -284.737914)
			(xy 399.153932 -284.772006) (xy 399.183497 -284.81135) (xy 399.206368 -284.854927) (xy 399.221952 -284.901608)
			(xy 399.229847 -284.950185) (xy 399.230342 -284.974792) (xy 399.56919 -284.974792) (xy 399.57315 -284.925738)
			(xy 399.584927 -284.877954) (xy 399.604218 -284.832678) (xy 399.630521 -284.791082) (xy 399.663156 -284.754245)
			(xy 399.701277 -284.72312) (xy 399.743898 -284.698513) (xy 399.789914 -284.681061) (xy 399.838133 -284.671217)
			(xy 399.887308 -284.669236) (xy 399.936163 -284.675168) (xy 399.983434 -284.68886) (xy 400.027896 -284.709958)
			(xy 400.068399 -284.737914) (xy 400.103892 -284.772006) (xy 400.133457 -284.81135) (xy 400.156328 -284.854927)
			(xy 400.171912 -284.901608) (xy 400.179807 -284.950185) (xy 400.180302 -284.974792) (xy 400.51915 -284.974792)
			(xy 400.52311 -284.925738) (xy 400.534887 -284.877954) (xy 400.554178 -284.832678) (xy 400.580481 -284.791082)
			(xy 400.613116 -284.754245) (xy 400.651237 -284.72312) (xy 400.693858 -284.698513) (xy 400.739874 -284.681061)
			(xy 400.788093 -284.671217) (xy 400.837268 -284.669236) (xy 400.886123 -284.675168) (xy 400.933394 -284.68886)
			(xy 400.977856 -284.709958) (xy 401.018359 -284.737914) (xy 401.053852 -284.772006) (xy 401.083417 -284.81135)
			(xy 401.106288 -284.854927) (xy 401.121872 -284.901608) (xy 401.129767 -284.950185) (xy 401.130262 -284.974792)
			(xy 401.46911 -284.974792) (xy 401.47307 -284.925738) (xy 401.484847 -284.877954) (xy 401.504138 -284.832678)
			(xy 401.530441 -284.791082) (xy 401.563076 -284.754245) (xy 401.601197 -284.72312) (xy 401.643818 -284.698513)
			(xy 401.689834 -284.681061) (xy 401.738053 -284.671217) (xy 401.787228 -284.669236) (xy 401.836083 -284.675168)
			(xy 401.883354 -284.68886) (xy 401.927816 -284.709958) (xy 401.968319 -284.737914) (xy 402.003812 -284.772006)
			(xy 402.033377 -284.81135) (xy 402.056248 -284.854927) (xy 402.071832 -284.901608) (xy 402.079727 -284.950185)
			(xy 402.080222 -284.974792) (xy 402.41907 -284.974792) (xy 402.42303 -284.925738) (xy 402.434807 -284.877954)
			(xy 402.454098 -284.832678) (xy 402.480401 -284.791082) (xy 402.513036 -284.754245) (xy 402.551157 -284.72312)
			(xy 402.593778 -284.698513) (xy 402.639794 -284.681061) (xy 402.688013 -284.671217) (xy 402.737188 -284.669236)
			(xy 402.786043 -284.675168) (xy 402.833314 -284.68886) (xy 402.877776 -284.709958) (xy 402.918279 -284.737914)
			(xy 402.953772 -284.772006) (xy 402.983337 -284.81135) (xy 403.006208 -284.854927) (xy 403.021792 -284.901608)
			(xy 403.029687 -284.950185) (xy 403.030182 -284.974792) (xy 403.36903 -284.974792) (xy 403.37299 -284.925738)
			(xy 403.384767 -284.877954) (xy 403.404058 -284.832678) (xy 403.430361 -284.791082) (xy 403.462996 -284.754245)
			(xy 403.501117 -284.72312) (xy 403.543738 -284.698513) (xy 403.589754 -284.681061) (xy 403.637973 -284.671217)
			(xy 403.687148 -284.669236) (xy 403.736003 -284.675168) (xy 403.783274 -284.68886) (xy 403.827736 -284.709958)
			(xy 403.868239 -284.737914) (xy 403.903732 -284.772006) (xy 403.933297 -284.81135) (xy 403.956168 -284.854927)
			(xy 403.971752 -284.901608) (xy 403.979647 -284.950185) (xy 403.980142 -284.974792) (xy 404.31899 -284.974792)
			(xy 404.32295 -284.925738) (xy 404.334727 -284.877954) (xy 404.354018 -284.832678) (xy 404.380321 -284.791082)
			(xy 404.412956 -284.754245) (xy 404.451077 -284.72312) (xy 404.493698 -284.698513) (xy 404.539714 -284.681061)
			(xy 404.587933 -284.671217) (xy 404.637108 -284.669236) (xy 404.685963 -284.675168) (xy 404.733234 -284.68886)
			(xy 404.777696 -284.709958) (xy 404.818199 -284.737914) (xy 404.853692 -284.772006) (xy 404.883257 -284.81135)
			(xy 404.906128 -284.854927) (xy 404.921712 -284.901608) (xy 404.929607 -284.950185) (xy 404.930102 -284.974792)
			(xy 405.269204 -284.974792) (xy 405.273164 -284.925738) (xy 405.284941 -284.877954) (xy 405.304232 -284.832678)
			(xy 405.330535 -284.791082) (xy 405.36317 -284.754245) (xy 405.401291 -284.72312) (xy 405.443912 -284.698513)
			(xy 405.489928 -284.681061) (xy 405.538147 -284.671217) (xy 405.587322 -284.669236) (xy 405.636177 -284.675168)
			(xy 405.683448 -284.68886) (xy 405.72791 -284.709958) (xy 405.768413 -284.737914) (xy 405.803906 -284.772006)
			(xy 405.833471 -284.81135) (xy 405.856342 -284.854927) (xy 405.871926 -284.901608) (xy 405.879821 -284.950185)
			(xy 405.880316 -284.974792) (xy 406.219164 -284.974792) (xy 406.223124 -284.925738) (xy 406.234901 -284.877954)
			(xy 406.254192 -284.832678) (xy 406.280495 -284.791082) (xy 406.31313 -284.754245) (xy 406.351251 -284.72312)
			(xy 406.393872 -284.698513) (xy 406.439888 -284.681061) (xy 406.488107 -284.671217) (xy 406.537282 -284.669236)
			(xy 406.586137 -284.675168) (xy 406.633408 -284.68886) (xy 406.67787 -284.709958) (xy 406.718373 -284.737914)
			(xy 406.753866 -284.772006) (xy 406.783431 -284.81135) (xy 406.806302 -284.854927) (xy 406.821886 -284.901608)
			(xy 406.829781 -284.950185) (xy 406.830276 -284.974792) (xy 408.119084 -284.974792) (xy 408.123044 -284.925738)
			(xy 408.134821 -284.877954) (xy 408.154112 -284.832678) (xy 408.180415 -284.791082) (xy 408.21305 -284.754245)
			(xy 408.251171 -284.72312) (xy 408.293792 -284.698513) (xy 408.339808 -284.681061) (xy 408.388027 -284.671217)
			(xy 408.437202 -284.669236) (xy 408.486057 -284.675168) (xy 408.533328 -284.68886) (xy 408.57779 -284.709958)
			(xy 408.618293 -284.737914) (xy 408.653786 -284.772006) (xy 408.683351 -284.81135) (xy 408.706222 -284.854927)
			(xy 408.721806 -284.901608) (xy 408.729701 -284.950185) (xy 408.730196 -284.974792) (xy 409.069044 -284.974792)
			(xy 409.073004 -284.925738) (xy 409.084781 -284.877954) (xy 409.104072 -284.832678) (xy 409.130375 -284.791082)
			(xy 409.16301 -284.754245) (xy 409.201131 -284.72312) (xy 409.243752 -284.698513) (xy 409.289768 -284.681061)
			(xy 409.337987 -284.671217) (xy 409.387162 -284.669236) (xy 409.436017 -284.675168) (xy 409.483288 -284.68886)
			(xy 409.52775 -284.709958) (xy 409.568253 -284.737914) (xy 409.603746 -284.772006) (xy 409.633311 -284.81135)
			(xy 409.656182 -284.854927) (xy 409.671766 -284.901608) (xy 409.679661 -284.950185) (xy 409.680156 -284.974792)
			(xy 410.019004 -284.974792) (xy 410.022964 -284.925738) (xy 410.034741 -284.877954) (xy 410.054032 -284.832678)
			(xy 410.080335 -284.791082) (xy 410.11297 -284.754245) (xy 410.151091 -284.72312) (xy 410.193712 -284.698513)
			(xy 410.239728 -284.681061) (xy 410.287947 -284.671217) (xy 410.337122 -284.669236) (xy 410.385977 -284.675168)
			(xy 410.433248 -284.68886) (xy 410.47771 -284.709958) (xy 410.518213 -284.737914) (xy 410.553706 -284.772006)
			(xy 410.583271 -284.81135) (xy 410.606142 -284.854927) (xy 410.621726 -284.901608) (xy 410.629621 -284.950185)
			(xy 410.630116 -284.974792) (xy 410.969218 -284.974792) (xy 410.973178 -284.925738) (xy 410.984955 -284.877954)
			(xy 411.004246 -284.832678) (xy 411.030549 -284.791082) (xy 411.063184 -284.754245) (xy 411.101305 -284.72312)
			(xy 411.143926 -284.698513) (xy 411.189942 -284.681061) (xy 411.238161 -284.671217) (xy 411.287336 -284.669236)
			(xy 411.336191 -284.675168) (xy 411.383462 -284.68886) (xy 411.427924 -284.709958) (xy 411.468427 -284.737914)
			(xy 411.50392 -284.772006) (xy 411.533485 -284.81135) (xy 411.556356 -284.854927) (xy 411.57194 -284.901608)
			(xy 411.579835 -284.950185) (xy 411.58033 -284.974792) (xy 411.919178 -284.974792) (xy 411.923138 -284.925738)
			(xy 411.934915 -284.877954) (xy 411.954206 -284.832678) (xy 411.980509 -284.791082) (xy 412.013144 -284.754245)
			(xy 412.051265 -284.72312) (xy 412.093886 -284.698513) (xy 412.139902 -284.681061) (xy 412.188121 -284.671217)
			(xy 412.237296 -284.669236) (xy 412.286151 -284.675168) (xy 412.333422 -284.68886) (xy 412.377884 -284.709958)
			(xy 412.418387 -284.737914) (xy 412.45388 -284.772006) (xy 412.483445 -284.81135) (xy 412.506316 -284.854927)
			(xy 412.5219 -284.901608) (xy 412.529795 -284.950185) (xy 412.53029 -284.974792) (xy 412.869138 -284.974792)
			(xy 412.873098 -284.925738) (xy 412.884875 -284.877954) (xy 412.904166 -284.832678) (xy 412.930469 -284.791082)
			(xy 412.963104 -284.754245) (xy 413.001225 -284.72312) (xy 413.043846 -284.698513) (xy 413.089862 -284.681061)
			(xy 413.138081 -284.671217) (xy 413.187256 -284.669236) (xy 413.236111 -284.675168) (xy 413.283382 -284.68886)
			(xy 413.327844 -284.709958) (xy 413.368347 -284.737914) (xy 413.40384 -284.772006) (xy 413.433405 -284.81135)
			(xy 413.456276 -284.854927) (xy 413.47186 -284.901608) (xy 413.479755 -284.950185) (xy 413.48025 -284.974792)
			(xy 413.819098 -284.974792) (xy 413.823058 -284.925738) (xy 413.834835 -284.877954) (xy 413.854126 -284.832678)
			(xy 413.880429 -284.791082) (xy 413.913064 -284.754245) (xy 413.951185 -284.72312) (xy 413.993806 -284.698513)
			(xy 414.039822 -284.681061) (xy 414.088041 -284.671217) (xy 414.137216 -284.669236) (xy 414.186071 -284.675168)
			(xy 414.233342 -284.68886) (xy 414.277804 -284.709958) (xy 414.318307 -284.737914) (xy 414.3538 -284.772006)
			(xy 414.383365 -284.81135) (xy 414.406236 -284.854927) (xy 414.42182 -284.901608) (xy 414.429715 -284.950185)
			(xy 414.43021 -284.974792) (xy 414.769058 -284.974792) (xy 414.773018 -284.925738) (xy 414.784795 -284.877954)
			(xy 414.804086 -284.832678) (xy 414.830389 -284.791082) (xy 414.863024 -284.754245) (xy 414.901145 -284.72312)
			(xy 414.943766 -284.698513) (xy 414.989782 -284.681061) (xy 415.038001 -284.671217) (xy 415.087176 -284.669236)
			(xy 415.136031 -284.675168) (xy 415.183302 -284.68886) (xy 415.227764 -284.709958) (xy 415.268267 -284.737914)
			(xy 415.30376 -284.772006) (xy 415.333325 -284.81135) (xy 415.356196 -284.854927) (xy 415.37178 -284.901608)
			(xy 415.379675 -284.950185) (xy 415.38017 -284.974792) (xy 415.719018 -284.974792) (xy 415.722978 -284.925738)
			(xy 415.734755 -284.877954) (xy 415.754046 -284.832678) (xy 415.780349 -284.791082) (xy 415.812984 -284.754245)
			(xy 415.851105 -284.72312) (xy 415.893726 -284.698513) (xy 415.939742 -284.681061) (xy 415.987961 -284.671217)
			(xy 416.037136 -284.669236) (xy 416.085991 -284.675168) (xy 416.133262 -284.68886) (xy 416.177724 -284.709958)
			(xy 416.218227 -284.737914) (xy 416.25372 -284.772006) (xy 416.283285 -284.81135) (xy 416.306156 -284.854927)
			(xy 416.32174 -284.901608) (xy 416.329635 -284.950185) (xy 416.33013 -284.974792) (xy 416.668978 -284.974792)
			(xy 416.672938 -284.925738) (xy 416.684715 -284.877954) (xy 416.704006 -284.832678) (xy 416.730309 -284.791082)
			(xy 416.762944 -284.754245) (xy 416.801065 -284.72312) (xy 416.843686 -284.698513) (xy 416.889702 -284.681061)
			(xy 416.937921 -284.671217) (xy 416.987096 -284.669236) (xy 417.035951 -284.675168) (xy 417.083222 -284.68886)
			(xy 417.127684 -284.709958) (xy 417.168187 -284.737914) (xy 417.20368 -284.772006) (xy 417.233245 -284.81135)
			(xy 417.256116 -284.854927) (xy 417.2717 -284.901608) (xy 417.279595 -284.950185) (xy 417.28009 -284.974792)
			(xy 417.619192 -284.974792) (xy 417.623152 -284.925738) (xy 417.634929 -284.877954) (xy 417.65422 -284.832678)
			(xy 417.680523 -284.791082) (xy 417.713158 -284.754245) (xy 417.751279 -284.72312) (xy 417.7939 -284.698513)
			(xy 417.839916 -284.681061) (xy 417.888135 -284.671217) (xy 417.93731 -284.669236) (xy 417.986165 -284.675168)
			(xy 418.033436 -284.68886) (xy 418.077898 -284.709958) (xy 418.118401 -284.737914) (xy 418.153894 -284.772006)
			(xy 418.183459 -284.81135) (xy 418.20633 -284.854927) (xy 418.221914 -284.901608) (xy 418.229809 -284.950185)
			(xy 418.230304 -284.974792) (xy 418.569152 -284.974792) (xy 418.573112 -284.925738) (xy 418.584889 -284.877954)
			(xy 418.60418 -284.832678) (xy 418.630483 -284.791082) (xy 418.663118 -284.754245) (xy 418.701239 -284.72312)
			(xy 418.74386 -284.698513) (xy 418.789876 -284.681061) (xy 418.838095 -284.671217) (xy 418.88727 -284.669236)
			(xy 418.936125 -284.675168) (xy 418.983396 -284.68886) (xy 419.027858 -284.709958) (xy 419.068361 -284.737914)
			(xy 419.103854 -284.772006) (xy 419.133419 -284.81135) (xy 419.15629 -284.854927) (xy 419.171874 -284.901608)
			(xy 419.179769 -284.950185) (xy 419.180264 -284.974792) (xy 419.179769 -284.999399) (xy 419.171874 -285.047976)
			(xy 419.15629 -285.094657) (xy 419.133419 -285.138234) (xy 419.103854 -285.177578) (xy 419.068361 -285.21167)
			(xy 419.027858 -285.239626) (xy 418.983396 -285.260724) (xy 418.936125 -285.274416) (xy 418.88727 -285.280348)
			(xy 418.838095 -285.278367) (xy 418.789876 -285.268523) (xy 418.74386 -285.251071) (xy 418.701239 -285.226464)
			(xy 418.663118 -285.195339) (xy 418.630483 -285.158502) (xy 418.60418 -285.116906) (xy 418.584889 -285.07163)
			(xy 418.573112 -285.023846) (xy 418.569152 -284.974792) (xy 418.230304 -284.974792) (xy 418.229809 -284.999399)
			(xy 418.221914 -285.047976) (xy 418.20633 -285.094657) (xy 418.183459 -285.138234) (xy 418.153894 -285.177578)
			(xy 418.118401 -285.21167) (xy 418.077898 -285.239626) (xy 418.033436 -285.260724) (xy 417.986165 -285.274416)
			(xy 417.93731 -285.280348) (xy 417.888135 -285.278367) (xy 417.839916 -285.268523) (xy 417.7939 -285.251071)
			(xy 417.751279 -285.226464) (xy 417.713158 -285.195339) (xy 417.680523 -285.158502) (xy 417.65422 -285.116906)
			(xy 417.634929 -285.07163) (xy 417.623152 -285.023846) (xy 417.619192 -284.974792) (xy 417.28009 -284.974792)
			(xy 417.279595 -284.999399) (xy 417.2717 -285.047976) (xy 417.256116 -285.094657) (xy 417.233245 -285.138234)
			(xy 417.20368 -285.177578) (xy 417.168187 -285.21167) (xy 417.127684 -285.239626) (xy 417.083222 -285.260724)
			(xy 417.035951 -285.274416) (xy 416.987096 -285.280348) (xy 416.937921 -285.278367) (xy 416.889702 -285.268523)
			(xy 416.843686 -285.251071) (xy 416.801065 -285.226464) (xy 416.762944 -285.195339) (xy 416.730309 -285.158502)
			(xy 416.704006 -285.116906) (xy 416.684715 -285.07163) (xy 416.672938 -285.023846) (xy 416.668978 -284.974792)
			(xy 416.33013 -284.974792) (xy 416.329635 -284.999399) (xy 416.32174 -285.047976) (xy 416.306156 -285.094657)
			(xy 416.283285 -285.138234) (xy 416.25372 -285.177578) (xy 416.218227 -285.21167) (xy 416.177724 -285.239626)
			(xy 416.133262 -285.260724) (xy 416.085991 -285.274416) (xy 416.037136 -285.280348) (xy 415.987961 -285.278367)
			(xy 415.939742 -285.268523) (xy 415.893726 -285.251071) (xy 415.851105 -285.226464) (xy 415.812984 -285.195339)
			(xy 415.780349 -285.158502) (xy 415.754046 -285.116906) (xy 415.734755 -285.07163) (xy 415.722978 -285.023846)
			(xy 415.719018 -284.974792) (xy 415.38017 -284.974792) (xy 415.379675 -284.999399) (xy 415.37178 -285.047976)
			(xy 415.356196 -285.094657) (xy 415.333325 -285.138234) (xy 415.30376 -285.177578) (xy 415.268267 -285.21167)
			(xy 415.227764 -285.239626) (xy 415.183302 -285.260724) (xy 415.136031 -285.274416) (xy 415.087176 -285.280348)
			(xy 415.038001 -285.278367) (xy 414.989782 -285.268523) (xy 414.943766 -285.251071) (xy 414.901145 -285.226464)
			(xy 414.863024 -285.195339) (xy 414.830389 -285.158502) (xy 414.804086 -285.116906) (xy 414.784795 -285.07163)
			(xy 414.773018 -285.023846) (xy 414.769058 -284.974792) (xy 414.43021 -284.974792) (xy 414.429715 -284.999399)
			(xy 414.42182 -285.047976) (xy 414.406236 -285.094657) (xy 414.383365 -285.138234) (xy 414.3538 -285.177578)
			(xy 414.318307 -285.21167) (xy 414.277804 -285.239626) (xy 414.233342 -285.260724) (xy 414.186071 -285.274416)
			(xy 414.137216 -285.280348) (xy 414.088041 -285.278367) (xy 414.039822 -285.268523) (xy 413.993806 -285.251071)
			(xy 413.951185 -285.226464) (xy 413.913064 -285.195339) (xy 413.880429 -285.158502) (xy 413.854126 -285.116906)
			(xy 413.834835 -285.07163) (xy 413.823058 -285.023846) (xy 413.819098 -284.974792) (xy 413.48025 -284.974792)
			(xy 413.479755 -284.999399) (xy 413.47186 -285.047976) (xy 413.456276 -285.094657) (xy 413.433405 -285.138234)
			(xy 413.40384 -285.177578) (xy 413.368347 -285.21167) (xy 413.327844 -285.239626) (xy 413.283382 -285.260724)
			(xy 413.236111 -285.274416) (xy 413.187256 -285.280348) (xy 413.138081 -285.278367) (xy 413.089862 -285.268523)
			(xy 413.043846 -285.251071) (xy 413.001225 -285.226464) (xy 412.963104 -285.195339) (xy 412.930469 -285.158502)
			(xy 412.904166 -285.116906) (xy 412.884875 -285.07163) (xy 412.873098 -285.023846) (xy 412.869138 -284.974792)
			(xy 412.53029 -284.974792) (xy 412.529795 -284.999399) (xy 412.5219 -285.047976) (xy 412.506316 -285.094657)
			(xy 412.483445 -285.138234) (xy 412.45388 -285.177578) (xy 412.418387 -285.21167) (xy 412.377884 -285.239626)
			(xy 412.333422 -285.260724) (xy 412.286151 -285.274416) (xy 412.237296 -285.280348) (xy 412.188121 -285.278367)
			(xy 412.139902 -285.268523) (xy 412.093886 -285.251071) (xy 412.051265 -285.226464) (xy 412.013144 -285.195339)
			(xy 411.980509 -285.158502) (xy 411.954206 -285.116906) (xy 411.934915 -285.07163) (xy 411.923138 -285.023846)
			(xy 411.919178 -284.974792) (xy 411.58033 -284.974792) (xy 411.579835 -284.999399) (xy 411.57194 -285.047976)
			(xy 411.556356 -285.094657) (xy 411.533485 -285.138234) (xy 411.50392 -285.177578) (xy 411.468427 -285.21167)
			(xy 411.427924 -285.239626) (xy 411.383462 -285.260724) (xy 411.336191 -285.274416) (xy 411.287336 -285.280348)
			(xy 411.238161 -285.278367) (xy 411.189942 -285.268523) (xy 411.143926 -285.251071) (xy 411.101305 -285.226464)
			(xy 411.063184 -285.195339) (xy 411.030549 -285.158502) (xy 411.004246 -285.116906) (xy 410.984955 -285.07163)
			(xy 410.973178 -285.023846) (xy 410.969218 -284.974792) (xy 410.630116 -284.974792) (xy 410.629621 -284.999399)
			(xy 410.621726 -285.047976) (xy 410.606142 -285.094657) (xy 410.583271 -285.138234) (xy 410.553706 -285.177578)
			(xy 410.518213 -285.21167) (xy 410.47771 -285.239626) (xy 410.433248 -285.260724) (xy 410.385977 -285.274416)
			(xy 410.337122 -285.280348) (xy 410.287947 -285.278367) (xy 410.239728 -285.268523) (xy 410.193712 -285.251071)
			(xy 410.151091 -285.226464) (xy 410.11297 -285.195339) (xy 410.080335 -285.158502) (xy 410.054032 -285.116906)
			(xy 410.034741 -285.07163) (xy 410.022964 -285.023846) (xy 410.019004 -284.974792) (xy 409.680156 -284.974792)
			(xy 409.679661 -284.999399) (xy 409.671766 -285.047976) (xy 409.656182 -285.094657) (xy 409.633311 -285.138234)
			(xy 409.603746 -285.177578) (xy 409.568253 -285.21167) (xy 409.52775 -285.239626) (xy 409.483288 -285.260724)
			(xy 409.436017 -285.274416) (xy 409.387162 -285.280348) (xy 409.337987 -285.278367) (xy 409.289768 -285.268523)
			(xy 409.243752 -285.251071) (xy 409.201131 -285.226464) (xy 409.16301 -285.195339) (xy 409.130375 -285.158502)
			(xy 409.104072 -285.116906) (xy 409.084781 -285.07163) (xy 409.073004 -285.023846) (xy 409.069044 -284.974792)
			(xy 408.730196 -284.974792) (xy 408.729701 -284.999399) (xy 408.721806 -285.047976) (xy 408.706222 -285.094657)
			(xy 408.683351 -285.138234) (xy 408.653786 -285.177578) (xy 408.618293 -285.21167) (xy 408.57779 -285.239626)
			(xy 408.533328 -285.260724) (xy 408.486057 -285.274416) (xy 408.437202 -285.280348) (xy 408.388027 -285.278367)
			(xy 408.339808 -285.268523) (xy 408.293792 -285.251071) (xy 408.251171 -285.226464) (xy 408.21305 -285.195339)
			(xy 408.180415 -285.158502) (xy 408.154112 -285.116906) (xy 408.134821 -285.07163) (xy 408.123044 -285.023846)
			(xy 408.119084 -284.974792) (xy 406.830276 -284.974792) (xy 406.829781 -284.999399) (xy 406.821886 -285.047976)
			(xy 406.806302 -285.094657) (xy 406.783431 -285.138234) (xy 406.753866 -285.177578) (xy 406.718373 -285.21167)
			(xy 406.67787 -285.239626) (xy 406.633408 -285.260724) (xy 406.586137 -285.274416) (xy 406.537282 -285.280348)
			(xy 406.488107 -285.278367) (xy 406.439888 -285.268523) (xy 406.393872 -285.251071) (xy 406.351251 -285.226464)
			(xy 406.31313 -285.195339) (xy 406.280495 -285.158502) (xy 406.254192 -285.116906) (xy 406.234901 -285.07163)
			(xy 406.223124 -285.023846) (xy 406.219164 -284.974792) (xy 405.880316 -284.974792) (xy 405.879821 -284.999399)
			(xy 405.871926 -285.047976) (xy 405.856342 -285.094657) (xy 405.833471 -285.138234) (xy 405.803906 -285.177578)
			(xy 405.768413 -285.21167) (xy 405.72791 -285.239626) (xy 405.683448 -285.260724) (xy 405.636177 -285.274416)
			(xy 405.587322 -285.280348) (xy 405.538147 -285.278367) (xy 405.489928 -285.268523) (xy 405.443912 -285.251071)
			(xy 405.401291 -285.226464) (xy 405.36317 -285.195339) (xy 405.330535 -285.158502) (xy 405.304232 -285.116906)
			(xy 405.284941 -285.07163) (xy 405.273164 -285.023846) (xy 405.269204 -284.974792) (xy 404.930102 -284.974792)
			(xy 404.929607 -284.999399) (xy 404.921712 -285.047976) (xy 404.906128 -285.094657) (xy 404.883257 -285.138234)
			(xy 404.853692 -285.177578) (xy 404.818199 -285.21167) (xy 404.777696 -285.239626) (xy 404.733234 -285.260724)
			(xy 404.685963 -285.274416) (xy 404.637108 -285.280348) (xy 404.587933 -285.278367) (xy 404.539714 -285.268523)
			(xy 404.493698 -285.251071) (xy 404.451077 -285.226464) (xy 404.412956 -285.195339) (xy 404.380321 -285.158502)
			(xy 404.354018 -285.116906) (xy 404.334727 -285.07163) (xy 404.32295 -285.023846) (xy 404.31899 -284.974792)
			(xy 403.980142 -284.974792) (xy 403.979647 -284.999399) (xy 403.971752 -285.047976) (xy 403.956168 -285.094657)
			(xy 403.933297 -285.138234) (xy 403.903732 -285.177578) (xy 403.868239 -285.21167) (xy 403.827736 -285.239626)
			(xy 403.783274 -285.260724) (xy 403.736003 -285.274416) (xy 403.687148 -285.280348) (xy 403.637973 -285.278367)
			(xy 403.589754 -285.268523) (xy 403.543738 -285.251071) (xy 403.501117 -285.226464) (xy 403.462996 -285.195339)
			(xy 403.430361 -285.158502) (xy 403.404058 -285.116906) (xy 403.384767 -285.07163) (xy 403.37299 -285.023846)
			(xy 403.36903 -284.974792) (xy 403.030182 -284.974792) (xy 403.029687 -284.999399) (xy 403.021792 -285.047976)
			(xy 403.006208 -285.094657) (xy 402.983337 -285.138234) (xy 402.953772 -285.177578) (xy 402.918279 -285.21167)
			(xy 402.877776 -285.239626) (xy 402.833314 -285.260724) (xy 402.786043 -285.274416) (xy 402.737188 -285.280348)
			(xy 402.688013 -285.278367) (xy 402.639794 -285.268523) (xy 402.593778 -285.251071) (xy 402.551157 -285.226464)
			(xy 402.513036 -285.195339) (xy 402.480401 -285.158502) (xy 402.454098 -285.116906) (xy 402.434807 -285.07163)
			(xy 402.42303 -285.023846) (xy 402.41907 -284.974792) (xy 402.080222 -284.974792) (xy 402.079727 -284.999399)
			(xy 402.071832 -285.047976) (xy 402.056248 -285.094657) (xy 402.033377 -285.138234) (xy 402.003812 -285.177578)
			(xy 401.968319 -285.21167) (xy 401.927816 -285.239626) (xy 401.883354 -285.260724) (xy 401.836083 -285.274416)
			(xy 401.787228 -285.280348) (xy 401.738053 -285.278367) (xy 401.689834 -285.268523) (xy 401.643818 -285.251071)
			(xy 401.601197 -285.226464) (xy 401.563076 -285.195339) (xy 401.530441 -285.158502) (xy 401.504138 -285.116906)
			(xy 401.484847 -285.07163) (xy 401.47307 -285.023846) (xy 401.46911 -284.974792) (xy 401.130262 -284.974792)
			(xy 401.129767 -284.999399) (xy 401.121872 -285.047976) (xy 401.106288 -285.094657) (xy 401.083417 -285.138234)
			(xy 401.053852 -285.177578) (xy 401.018359 -285.21167) (xy 400.977856 -285.239626) (xy 400.933394 -285.260724)
			(xy 400.886123 -285.274416) (xy 400.837268 -285.280348) (xy 400.788093 -285.278367) (xy 400.739874 -285.268523)
			(xy 400.693858 -285.251071) (xy 400.651237 -285.226464) (xy 400.613116 -285.195339) (xy 400.580481 -285.158502)
			(xy 400.554178 -285.116906) (xy 400.534887 -285.07163) (xy 400.52311 -285.023846) (xy 400.51915 -284.974792)
			(xy 400.180302 -284.974792) (xy 400.179807 -284.999399) (xy 400.171912 -285.047976) (xy 400.156328 -285.094657)
			(xy 400.133457 -285.138234) (xy 400.103892 -285.177578) (xy 400.068399 -285.21167) (xy 400.027896 -285.239626)
			(xy 399.983434 -285.260724) (xy 399.936163 -285.274416) (xy 399.887308 -285.280348) (xy 399.838133 -285.278367)
			(xy 399.789914 -285.268523) (xy 399.743898 -285.251071) (xy 399.701277 -285.226464) (xy 399.663156 -285.195339)
			(xy 399.630521 -285.158502) (xy 399.604218 -285.116906) (xy 399.584927 -285.07163) (xy 399.57315 -285.023846)
			(xy 399.56919 -284.974792) (xy 399.230342 -284.974792) (xy 399.229847 -284.999399) (xy 399.221952 -285.047976)
			(xy 399.206368 -285.094657) (xy 399.183497 -285.138234) (xy 399.153932 -285.177578) (xy 399.118439 -285.21167)
			(xy 399.077936 -285.239626) (xy 399.033474 -285.260724) (xy 398.986203 -285.274416) (xy 398.937348 -285.280348)
			(xy 398.888173 -285.278367) (xy 398.839954 -285.268523) (xy 398.793938 -285.251071) (xy 398.751317 -285.226464)
			(xy 398.713196 -285.195339) (xy 398.680561 -285.158502) (xy 398.654258 -285.116906) (xy 398.634967 -285.07163)
			(xy 398.62319 -285.023846) (xy 398.61923 -284.974792) (xy 398.280638 -284.974792) (xy 398.280639 -284.9748)
			(xy 398.276468 -285.025137) (xy 398.264069 -285.074102) (xy 398.24378 -285.120358) (xy 398.216155 -285.162644)
			(xy 398.181947 -285.199806) (xy 398.142089 -285.230831) (xy 398.097668 -285.254873) (xy 398.049895 -285.271276)
			(xy 398.000075 -285.279593) (xy 397.97482 -285.2801) (xy 397.96328 -285.279974) (xy 397.940268 -285.278197)
			(xy 397.928846 -285.276544) (xy 397.925036 -285.276036) (xy 397.92402 -285.276036) (xy 397.900114 -285.271523)
			(xy 397.854031 -285.255937) (xy 397.810994 -285.233258) (xy 397.772085 -285.204058) (xy 397.754856 -285.186882)
			(xy 397.743934 -285.175452) (xy 397.713962 -285.169102) (xy 397.611854 -285.21025) (xy 397.602686 -285.214441)
			(xy 397.588363 -285.228603) (xy 397.580555 -285.247171) (xy 397.580104 -285.25724) (xy 397.580104 -285.449772)
			(xy 421.894012 -285.449772) (xy 421.897972 -285.400718) (xy 421.909749 -285.352934) (xy 421.92904 -285.307658)
			(xy 421.955343 -285.266062) (xy 421.987978 -285.229225) (xy 422.026099 -285.1981) (xy 422.06872 -285.173493)
			(xy 422.114736 -285.156041) (xy 422.162955 -285.146197) (xy 422.21213 -285.144216) (xy 422.260985 -285.150148)
			(xy 422.308256 -285.16384) (xy 422.352718 -285.184938) (xy 422.393221 -285.212894) (xy 422.428714 -285.246986)
			(xy 422.458279 -285.28633) (xy 422.48115 -285.329907) (xy 422.496734 -285.376588) (xy 422.504629 -285.425165)
			(xy 422.505124 -285.449772) (xy 422.504629 -285.474379) (xy 422.50445 -285.47548) (xy 422.823128 -285.47548)
			(xy 422.823128 -285.424064) (xy 422.831171 -285.373282) (xy 422.847059 -285.324383) (xy 422.870402 -285.278571)
			(xy 422.900623 -285.236975) (xy 422.936979 -285.200619) (xy 422.978575 -285.170398) (xy 423.024387 -285.147055)
			(xy 423.073286 -285.131167) (xy 423.124068 -285.123124) (xy 423.175484 -285.123124) (xy 423.226266 -285.131167)
			(xy 423.275165 -285.147055) (xy 423.320977 -285.170398) (xy 423.362573 -285.200619) (xy 423.398929 -285.236975)
			(xy 423.42915 -285.278571) (xy 423.452493 -285.324383) (xy 423.468381 -285.373282) (xy 423.476424 -285.424064)
			(xy 423.476928 -285.449772) (xy 423.476424 -285.47548) (xy 423.773342 -285.47548) (xy 423.773342 -285.424064)
			(xy 423.781385 -285.373282) (xy 423.797273 -285.324383) (xy 423.820616 -285.278571) (xy 423.850837 -285.236975)
			(xy 423.887193 -285.200619) (xy 423.928789 -285.170398) (xy 423.974601 -285.147055) (xy 424.0235 -285.131167)
			(xy 424.074282 -285.123124) (xy 424.125698 -285.123124) (xy 424.17648 -285.131167) (xy 424.225379 -285.147055)
			(xy 424.271191 -285.170398) (xy 424.312787 -285.200619) (xy 424.349143 -285.236975) (xy 424.379364 -285.278571)
			(xy 424.402707 -285.324383) (xy 424.418595 -285.373282) (xy 424.426638 -285.424064) (xy 424.427142 -285.449772)
			(xy 424.744146 -285.449772) (xy 424.748106 -285.400718) (xy 424.759883 -285.352934) (xy 424.779174 -285.307658)
			(xy 424.805477 -285.266062) (xy 424.838112 -285.229225) (xy 424.876233 -285.1981) (xy 424.918854 -285.173493)
			(xy 424.96487 -285.156041) (xy 425.013089 -285.146197) (xy 425.062264 -285.144216) (xy 425.111119 -285.150148)
			(xy 425.15839 -285.16384) (xy 425.202852 -285.184938) (xy 425.243355 -285.212894) (xy 425.278848 -285.246986)
			(xy 425.308413 -285.28633) (xy 425.331284 -285.329907) (xy 425.346868 -285.376588) (xy 425.354763 -285.425165)
			(xy 425.355258 -285.449772) (xy 425.694106 -285.449772) (xy 425.698066 -285.400718) (xy 425.709843 -285.352934)
			(xy 425.729134 -285.307658) (xy 425.755437 -285.266062) (xy 425.788072 -285.229225) (xy 425.826193 -285.1981)
			(xy 425.868814 -285.173493) (xy 425.91483 -285.156041) (xy 425.963049 -285.146197) (xy 426.012224 -285.144216)
			(xy 426.061079 -285.150148) (xy 426.10835 -285.16384) (xy 426.152812 -285.184938) (xy 426.193315 -285.212894)
			(xy 426.228808 -285.246986) (xy 426.258373 -285.28633) (xy 426.281244 -285.329907) (xy 426.296828 -285.376588)
			(xy 426.304723 -285.425165) (xy 426.305218 -285.449772) (xy 426.644066 -285.449772) (xy 426.648026 -285.400718)
			(xy 426.659803 -285.352934) (xy 426.679094 -285.307658) (xy 426.705397 -285.266062) (xy 426.738032 -285.229225)
			(xy 426.776153 -285.1981) (xy 426.818774 -285.173493) (xy 426.86479 -285.156041) (xy 426.913009 -285.146197)
			(xy 426.962184 -285.144216) (xy 427.011039 -285.150148) (xy 427.05831 -285.16384) (xy 427.102772 -285.184938)
			(xy 427.143275 -285.212894) (xy 427.178768 -285.246986) (xy 427.208333 -285.28633) (xy 427.231204 -285.329907)
			(xy 427.246788 -285.376588) (xy 427.254683 -285.425165) (xy 427.255178 -285.449772) (xy 427.594026 -285.449772)
			(xy 427.597986 -285.400718) (xy 427.609763 -285.352934) (xy 427.629054 -285.307658) (xy 427.655357 -285.266062)
			(xy 427.687992 -285.229225) (xy 427.726113 -285.1981) (xy 427.768734 -285.173493) (xy 427.81475 -285.156041)
			(xy 427.862969 -285.146197) (xy 427.912144 -285.144216) (xy 427.960999 -285.150148) (xy 428.00827 -285.16384)
			(xy 428.052732 -285.184938) (xy 428.093235 -285.212894) (xy 428.128728 -285.246986) (xy 428.158293 -285.28633)
			(xy 428.181164 -285.329907) (xy 428.196748 -285.376588) (xy 428.204643 -285.425165) (xy 428.205138 -285.449772)
			(xy 428.543986 -285.449772) (xy 428.547946 -285.400718) (xy 428.559723 -285.352934) (xy 428.579014 -285.307658)
			(xy 428.605317 -285.266062) (xy 428.637952 -285.229225) (xy 428.676073 -285.1981) (xy 428.718694 -285.173493)
			(xy 428.76471 -285.156041) (xy 428.812929 -285.146197) (xy 428.862104 -285.144216) (xy 428.910959 -285.150148)
			(xy 428.95823 -285.16384) (xy 429.002692 -285.184938) (xy 429.043195 -285.212894) (xy 429.078688 -285.246986)
			(xy 429.108253 -285.28633) (xy 429.131124 -285.329907) (xy 429.146708 -285.376588) (xy 429.154603 -285.425165)
			(xy 429.155098 -285.449772) (xy 429.154603 -285.474379) (xy 429.154424 -285.47548) (xy 429.473356 -285.47548)
			(xy 429.473356 -285.424064) (xy 429.481399 -285.373282) (xy 429.497287 -285.324383) (xy 429.52063 -285.278571)
			(xy 429.550851 -285.236975) (xy 429.587207 -285.200619) (xy 429.628803 -285.170398) (xy 429.674615 -285.147055)
			(xy 429.723514 -285.131167) (xy 429.774296 -285.123124) (xy 429.825712 -285.123124) (xy 429.876494 -285.131167)
			(xy 429.925393 -285.147055) (xy 429.971205 -285.170398) (xy 430.012801 -285.200619) (xy 430.049157 -285.236975)
			(xy 430.079378 -285.278571) (xy 430.102721 -285.324383) (xy 430.118609 -285.373282) (xy 430.126652 -285.424064)
			(xy 430.127156 -285.449772) (xy 430.126652 -285.47548) (xy 430.423316 -285.47548) (xy 430.423316 -285.424064)
			(xy 430.431359 -285.373282) (xy 430.447247 -285.324383) (xy 430.47059 -285.278571) (xy 430.500811 -285.236975)
			(xy 430.537167 -285.200619) (xy 430.578763 -285.170398) (xy 430.624575 -285.147055) (xy 430.673474 -285.131167)
			(xy 430.724256 -285.123124) (xy 430.775672 -285.123124) (xy 430.826454 -285.131167) (xy 430.875353 -285.147055)
			(xy 430.921165 -285.170398) (xy 430.962761 -285.200619) (xy 430.999117 -285.236975) (xy 431.029338 -285.278571)
			(xy 431.052681 -285.324383) (xy 431.068569 -285.373282) (xy 431.076612 -285.424064) (xy 431.077116 -285.449772)
			(xy 431.077111 -285.450026) (xy 431.394374 -285.450026) (xy 431.398334 -285.400972) (xy 431.410111 -285.353188)
			(xy 431.429402 -285.307912) (xy 431.455705 -285.266316) (xy 431.48834 -285.229479) (xy 431.526461 -285.198354)
			(xy 431.569082 -285.173747) (xy 431.615098 -285.156295) (xy 431.663317 -285.146451) (xy 431.712492 -285.14447)
			(xy 431.761347 -285.150402) (xy 431.808618 -285.164094) (xy 431.85308 -285.185192) (xy 431.893583 -285.213148)
			(xy 431.929076 -285.24724) (xy 431.958641 -285.286584) (xy 431.981512 -285.330161) (xy 431.997096 -285.376842)
			(xy 432.004991 -285.425419) (xy 432.005486 -285.450026) (xy 432.004991 -285.474633) (xy 431.997096 -285.52321)
			(xy 431.981512 -285.569891) (xy 431.962271 -285.606552) (xy 456.489267 -285.606552) (xy 456.489267 -285.552048)
			(xy 456.497024 -285.498098) (xy 456.51238 -285.445801) (xy 456.535023 -285.396222) (xy 456.56449 -285.35037)
			(xy 456.600184 -285.309178) (xy 456.641376 -285.273486) (xy 456.687229 -285.244019) (xy 456.736808 -285.221377)
			(xy 456.789106 -285.206023) (xy 456.843056 -285.198267) (xy 456.870308 -285.197804) (xy 456.899047 -285.198322)
			(xy 456.955875 -285.206946) (xy 457.010766 -285.223997) (xy 457.062477 -285.24909) (xy 457.109839 -285.281657)
			(xy 457.131166 -285.300928) (xy 457.138278 -285.307532) (xy 457.155804 -285.314644) (xy 457.245212 -285.314644)
			(xy 457.262738 -285.307532) (xy 457.26985 -285.300928) (xy 457.291177 -285.281658) (xy 457.33854 -285.249093)
			(xy 457.390251 -285.224002) (xy 457.445142 -285.206952) (xy 457.501969 -285.19833) (xy 457.559447 -285.19833)
			(xy 457.616274 -285.206952) (xy 457.671165 -285.224002) (xy 457.722876 -285.249093) (xy 457.770239 -285.281658)
			(xy 457.791566 -285.300928) (xy 457.798678 -285.307532) (xy 457.816204 -285.314644) (xy 457.905612 -285.314644)
			(xy 457.923138 -285.307532) (xy 457.93025 -285.300928) (xy 457.951572 -285.281652) (xy 457.998936 -285.249087)
			(xy 458.050649 -285.223995) (xy 458.10554 -285.206946) (xy 458.162369 -285.198324) (xy 458.191108 -285.197804)
			(xy 458.221232 -285.198354) (xy 458.280731 -285.207838) (xy 458.337999 -285.226552) (xy 458.391616 -285.254033)
			(xy 458.440249 -285.289598) (xy 458.461872 -285.31058) (xy 458.468984 -285.317946) (xy 458.48778 -285.325566)
			(xy 458.580236 -285.325566) (xy 458.599032 -285.317946) (xy 458.606144 -285.31058) (xy 458.627767 -285.289598)
			(xy 458.676397 -285.254031) (xy 458.730014 -285.226551) (xy 458.787284 -285.207844) (xy 458.846784 -285.198372)
			(xy 458.876908 -285.197804) (xy 458.90416 -285.198266) (xy 458.958108 -285.206024) (xy 459.010404 -285.22138)
			(xy 459.059982 -285.244023) (xy 459.105832 -285.27349) (xy 459.147023 -285.309183) (xy 459.182715 -285.350374)
			(xy 459.212181 -285.396226) (xy 459.234822 -285.445804) (xy 459.250178 -285.4981) (xy 459.257934 -285.552048)
			(xy 459.257934 -285.596653) (xy 460.661461 -285.596653) (xy 460.661461 -285.542147) (xy 460.669219 -285.488196)
			(xy 460.684575 -285.435898) (xy 460.707218 -285.386318) (xy 460.736687 -285.340465) (xy 460.772381 -285.299272)
			(xy 460.813574 -285.263579) (xy 460.859428 -285.234112) (xy 460.909009 -285.211471) (xy 460.961308 -285.196116)
			(xy 461.015259 -285.188361) (xy 461.042512 -285.187898) (xy 461.071251 -285.188415) (xy 461.128079 -285.197039)
			(xy 461.18297 -285.214091) (xy 461.234681 -285.239184) (xy 461.282043 -285.271751) (xy 461.30337 -285.291022)
			(xy 461.310482 -285.297626) (xy 461.328008 -285.304738) (xy 461.417416 -285.304738) (xy 461.434942 -285.297626)
			(xy 461.442054 -285.291022) (xy 461.463381 -285.271752) (xy 461.510744 -285.239187) (xy 461.562455 -285.214096)
			(xy 461.617346 -285.197046) (xy 461.674173 -285.188424) (xy 461.731651 -285.188424) (xy 461.788478 -285.197046)
			(xy 461.843369 -285.214096) (xy 461.89508 -285.239187) (xy 461.942443 -285.271752) (xy 461.96377 -285.291022)
			(xy 461.970882 -285.297626) (xy 461.988408 -285.304738) (xy 462.077816 -285.304738) (xy 462.095342 -285.297626)
			(xy 462.102454 -285.291022) (xy 462.123774 -285.271743) (xy 462.171138 -285.239178) (xy 462.222852 -285.214088)
			(xy 462.277744 -285.197039) (xy 462.334573 -285.188418) (xy 462.363312 -285.187898) (xy 462.393436 -285.188447)
			(xy 462.452934 -285.197931) (xy 462.510203 -285.216646) (xy 462.56382 -285.244128) (xy 462.612453 -285.279692)
			(xy 462.634076 -285.300674) (xy 462.641188 -285.30804) (xy 462.659984 -285.31566) (xy 462.75244 -285.31566)
			(xy 462.771236 -285.30804) (xy 462.778348 -285.300674) (xy 462.799985 -285.279707) (xy 462.848609 -285.244134)
			(xy 462.902222 -285.21665) (xy 462.95949 -285.197939) (xy 463.018988 -285.188467) (xy 463.049112 -285.187898)
			(xy 463.076363 -285.188373) (xy 463.13031 -285.196131) (xy 463.182605 -285.211487) (xy 463.232181 -285.234129)
			(xy 463.278031 -285.263596) (xy 463.31922 -285.299288) (xy 463.354911 -285.340479) (xy 463.384377 -285.38633)
			(xy 463.407017 -285.435907) (xy 463.422372 -285.488201) (xy 463.430128 -285.542149) (xy 463.430128 -285.596651)
			(xy 463.422372 -285.650599) (xy 463.407017 -285.702893) (xy 463.384377 -285.75247) (xy 463.354911 -285.798321)
			(xy 463.31922 -285.839512) (xy 463.278031 -285.875204) (xy 463.232181 -285.904671) (xy 463.182605 -285.927313)
			(xy 463.13031 -285.942669) (xy 463.076363 -285.950427) (xy 463.049112 -285.950914) (xy 463.018988 -285.950346)
			(xy 462.959491 -285.940866) (xy 462.902223 -285.922155) (xy 462.848606 -285.894678) (xy 462.799972 -285.859118)
			(xy 462.778348 -285.838138) (xy 462.771236 -285.830772) (xy 462.75244 -285.823152) (xy 462.659984 -285.823152)
			(xy 462.641188 -285.830772) (xy 462.634076 -285.838138) (xy 462.61243 -285.859096) (xy 462.563808 -285.89467)
			(xy 462.510197 -285.922155) (xy 462.452931 -285.940868) (xy 462.393435 -285.950344) (xy 462.363312 -285.950914)
			(xy 462.334574 -285.950379) (xy 462.277747 -285.941759) (xy 462.222856 -285.924711) (xy 462.171144 -285.899622)
			(xy 462.123781 -285.867059) (xy 462.102454 -285.84779) (xy 462.095342 -285.841186) (xy 462.077816 -285.834074)
			(xy 461.988408 -285.834074) (xy 461.970882 -285.841186) (xy 461.96377 -285.84779) (xy 461.942443 -285.86706)
			(xy 461.89508 -285.899625) (xy 461.843369 -285.924716) (xy 461.788478 -285.941766) (xy 461.731651 -285.950388)
			(xy 461.674173 -285.950388) (xy 461.617346 -285.941766) (xy 461.562455 -285.924716) (xy 461.510744 -285.899625)
			(xy 461.463381 -285.86706) (xy 461.442054 -285.84779) (xy 461.434942 -285.841186) (xy 461.417416 -285.834074)
			(xy 461.328008 -285.834074) (xy 461.310482 -285.841186) (xy 461.30337 -285.84779) (xy 461.282042 -285.86706)
			(xy 461.23468 -285.899625) (xy 461.182968 -285.924717) (xy 461.128078 -285.941768) (xy 461.071251 -285.950392)
			(xy 461.042512 -285.950914) (xy 461.015259 -285.950439) (xy 460.961308 -285.942684) (xy 460.909009 -285.927329)
			(xy 460.859428 -285.904688) (xy 460.813574 -285.875221) (xy 460.772381 -285.839528) (xy 460.736687 -285.798335)
			(xy 460.707218 -285.752482) (xy 460.684575 -285.702902) (xy 460.669219 -285.650604) (xy 460.661461 -285.596653)
			(xy 459.257934 -285.596653) (xy 459.257934 -285.606552) (xy 459.250178 -285.6605) (xy 459.234822 -285.712796)
			(xy 459.212181 -285.762374) (xy 459.182715 -285.808226) (xy 459.147023 -285.849417) (xy 459.105832 -285.88511)
			(xy 459.059982 -285.914577) (xy 459.010404 -285.93722) (xy 458.958108 -285.952576) (xy 458.90416 -285.960334)
			(xy 458.876908 -285.96082) (xy 458.846784 -285.960253) (xy 458.787287 -285.950772) (xy 458.730019 -285.932061)
			(xy 458.676402 -285.904584) (xy 458.627768 -285.869024) (xy 458.606144 -285.848044) (xy 458.599032 -285.840678)
			(xy 458.580236 -285.833058) (xy 458.48778 -285.833058) (xy 458.468984 -285.840678) (xy 458.461872 -285.848044)
			(xy 458.440229 -285.869005) (xy 458.391606 -285.904578) (xy 458.337995 -285.932063) (xy 458.280728 -285.950775)
			(xy 458.221231 -285.96025) (xy 458.191108 -285.96082) (xy 458.16237 -285.960286) (xy 458.105543 -285.951665)
			(xy 458.050652 -285.934617) (xy 457.998941 -285.909528) (xy 457.951577 -285.876965) (xy 457.93025 -285.857696)
			(xy 457.923138 -285.851092) (xy 457.905612 -285.84398) (xy 457.816204 -285.84398) (xy 457.798678 -285.851092)
			(xy 457.791566 -285.857696) (xy 457.770239 -285.876966) (xy 457.722876 -285.909531) (xy 457.671165 -285.934622)
			(xy 457.616274 -285.951672) (xy 457.559447 -285.960294) (xy 457.501969 -285.960294) (xy 457.445142 -285.951672)
			(xy 457.390251 -285.934622) (xy 457.33854 -285.909531) (xy 457.291177 -285.876966) (xy 457.26985 -285.857696)
			(xy 457.262738 -285.851092) (xy 457.245212 -285.84398) (xy 457.155804 -285.84398) (xy 457.138278 -285.851092)
			(xy 457.131166 -285.857696) (xy 457.109826 -285.876952) (xy 457.062468 -285.909522) (xy 457.01076 -285.934619)
			(xy 456.955872 -285.951673) (xy 456.899046 -285.960298) (xy 456.870308 -285.96082) (xy 456.843056 -285.960333)
			(xy 456.789106 -285.952577) (xy 456.736808 -285.937223) (xy 456.687229 -285.914581) (xy 456.641376 -285.885114)
			(xy 456.600184 -285.849422) (xy 456.56449 -285.80823) (xy 456.535023 -285.762378) (xy 456.51238 -285.712799)
			(xy 456.497024 -285.660502) (xy 456.489267 -285.606552) (xy 431.962271 -285.606552) (xy 431.958641 -285.613468)
			(xy 431.929076 -285.652812) (xy 431.893583 -285.686904) (xy 431.85308 -285.71486) (xy 431.808618 -285.735958)
			(xy 431.761347 -285.74965) (xy 431.712492 -285.755582) (xy 431.663317 -285.753601) (xy 431.615098 -285.743757)
			(xy 431.569082 -285.726305) (xy 431.526461 -285.701698) (xy 431.48834 -285.670573) (xy 431.455705 -285.633736)
			(xy 431.429402 -285.59214) (xy 431.410111 -285.546864) (xy 431.398334 -285.49908) (xy 431.394374 -285.450026)
			(xy 431.077111 -285.450026) (xy 431.076612 -285.47548) (xy 431.068569 -285.526262) (xy 431.052681 -285.575161)
			(xy 431.029338 -285.620973) (xy 430.999117 -285.662569) (xy 430.962761 -285.698925) (xy 430.921165 -285.729146)
			(xy 430.875353 -285.752489) (xy 430.826454 -285.768377) (xy 430.775672 -285.77642) (xy 430.724256 -285.77642)
			(xy 430.673474 -285.768377) (xy 430.624575 -285.752489) (xy 430.578763 -285.729146) (xy 430.537167 -285.698925)
			(xy 430.500811 -285.662569) (xy 430.47059 -285.620973) (xy 430.447247 -285.575161) (xy 430.431359 -285.526262)
			(xy 430.423316 -285.47548) (xy 430.126652 -285.47548) (xy 430.118609 -285.526262) (xy 430.102721 -285.575161)
			(xy 430.079378 -285.620973) (xy 430.049157 -285.662569) (xy 430.012801 -285.698925) (xy 429.971205 -285.729146)
			(xy 429.925393 -285.752489) (xy 429.876494 -285.768377) (xy 429.825712 -285.77642) (xy 429.774296 -285.77642)
			(xy 429.723514 -285.768377) (xy 429.674615 -285.752489) (xy 429.628803 -285.729146) (xy 429.587207 -285.698925)
			(xy 429.550851 -285.662569) (xy 429.52063 -285.620973) (xy 429.497287 -285.575161) (xy 429.481399 -285.526262)
			(xy 429.473356 -285.47548) (xy 429.154424 -285.47548) (xy 429.146708 -285.522956) (xy 429.131124 -285.569637)
			(xy 429.108253 -285.613214) (xy 429.078688 -285.652558) (xy 429.043195 -285.68665) (xy 429.002692 -285.714606)
			(xy 428.95823 -285.735704) (xy 428.910959 -285.749396) (xy 428.862104 -285.755328) (xy 428.812929 -285.753347)
			(xy 428.76471 -285.743503) (xy 428.718694 -285.726051) (xy 428.676073 -285.701444) (xy 428.637952 -285.670319)
			(xy 428.605317 -285.633482) (xy 428.579014 -285.591886) (xy 428.559723 -285.54661) (xy 428.547946 -285.498826)
			(xy 428.543986 -285.449772) (xy 428.205138 -285.449772) (xy 428.204643 -285.474379) (xy 428.196748 -285.522956)
			(xy 428.181164 -285.569637) (xy 428.158293 -285.613214) (xy 428.128728 -285.652558) (xy 428.093235 -285.68665)
			(xy 428.052732 -285.714606) (xy 428.00827 -285.735704) (xy 427.960999 -285.749396) (xy 427.912144 -285.755328)
			(xy 427.862969 -285.753347) (xy 427.81475 -285.743503) (xy 427.768734 -285.726051) (xy 427.726113 -285.701444)
			(xy 427.687992 -285.670319) (xy 427.655357 -285.633482) (xy 427.629054 -285.591886) (xy 427.609763 -285.54661)
			(xy 427.597986 -285.498826) (xy 427.594026 -285.449772) (xy 427.255178 -285.449772) (xy 427.254683 -285.474379)
			(xy 427.246788 -285.522956) (xy 427.231204 -285.569637) (xy 427.208333 -285.613214) (xy 427.178768 -285.652558)
			(xy 427.143275 -285.68665) (xy 427.102772 -285.714606) (xy 427.05831 -285.735704) (xy 427.011039 -285.749396)
			(xy 426.962184 -285.755328) (xy 426.913009 -285.753347) (xy 426.86479 -285.743503) (xy 426.818774 -285.726051)
			(xy 426.776153 -285.701444) (xy 426.738032 -285.670319) (xy 426.705397 -285.633482) (xy 426.679094 -285.591886)
			(xy 426.659803 -285.54661) (xy 426.648026 -285.498826) (xy 426.644066 -285.449772) (xy 426.305218 -285.449772)
			(xy 426.304723 -285.474379) (xy 426.296828 -285.522956) (xy 426.281244 -285.569637) (xy 426.258373 -285.613214)
			(xy 426.228808 -285.652558) (xy 426.193315 -285.68665) (xy 426.152812 -285.714606) (xy 426.10835 -285.735704)
			(xy 426.061079 -285.749396) (xy 426.012224 -285.755328) (xy 425.963049 -285.753347) (xy 425.91483 -285.743503)
			(xy 425.868814 -285.726051) (xy 425.826193 -285.701444) (xy 425.788072 -285.670319) (xy 425.755437 -285.633482)
			(xy 425.729134 -285.591886) (xy 425.709843 -285.54661) (xy 425.698066 -285.498826) (xy 425.694106 -285.449772)
			(xy 425.355258 -285.449772) (xy 425.354763 -285.474379) (xy 425.346868 -285.522956) (xy 425.331284 -285.569637)
			(xy 425.308413 -285.613214) (xy 425.278848 -285.652558) (xy 425.243355 -285.68665) (xy 425.202852 -285.714606)
			(xy 425.15839 -285.735704) (xy 425.111119 -285.749396) (xy 425.062264 -285.755328) (xy 425.013089 -285.753347)
			(xy 424.96487 -285.743503) (xy 424.918854 -285.726051) (xy 424.876233 -285.701444) (xy 424.838112 -285.670319)
			(xy 424.805477 -285.633482) (xy 424.779174 -285.591886) (xy 424.759883 -285.54661) (xy 424.748106 -285.498826)
			(xy 424.744146 -285.449772) (xy 424.427142 -285.449772) (xy 424.426638 -285.47548) (xy 424.418595 -285.526262)
			(xy 424.402707 -285.575161) (xy 424.379364 -285.620973) (xy 424.349143 -285.662569) (xy 424.312787 -285.698925)
			(xy 424.271191 -285.729146) (xy 424.225379 -285.752489) (xy 424.17648 -285.768377) (xy 424.125698 -285.77642)
			(xy 424.074282 -285.77642) (xy 424.0235 -285.768377) (xy 423.974601 -285.752489) (xy 423.928789 -285.729146)
			(xy 423.887193 -285.698925) (xy 423.850837 -285.662569) (xy 423.820616 -285.620973) (xy 423.797273 -285.575161)
			(xy 423.781385 -285.526262) (xy 423.773342 -285.47548) (xy 423.476424 -285.47548) (xy 423.468381 -285.526262)
			(xy 423.452493 -285.575161) (xy 423.42915 -285.620973) (xy 423.398929 -285.662569) (xy 423.362573 -285.698925)
			(xy 423.320977 -285.729146) (xy 423.275165 -285.752489) (xy 423.226266 -285.768377) (xy 423.175484 -285.77642)
			(xy 423.124068 -285.77642) (xy 423.073286 -285.768377) (xy 423.024387 -285.752489) (xy 422.978575 -285.729146)
			(xy 422.936979 -285.698925) (xy 422.900623 -285.662569) (xy 422.870402 -285.620973) (xy 422.847059 -285.575161)
			(xy 422.831171 -285.526262) (xy 422.823128 -285.47548) (xy 422.50445 -285.47548) (xy 422.496734 -285.522956)
			(xy 422.48115 -285.569637) (xy 422.458279 -285.613214) (xy 422.428714 -285.652558) (xy 422.393221 -285.68665)
			(xy 422.352718 -285.714606) (xy 422.308256 -285.735704) (xy 422.260985 -285.749396) (xy 422.21213 -285.755328)
			(xy 422.162955 -285.753347) (xy 422.114736 -285.743503) (xy 422.06872 -285.726051) (xy 422.026099 -285.701444)
			(xy 421.987978 -285.670319) (xy 421.955343 -285.633482) (xy 421.92904 -285.591886) (xy 421.909749 -285.54661)
			(xy 421.897972 -285.498826) (xy 421.894012 -285.449772) (xy 397.580104 -285.449772) (xy 397.580104 -285.642304)
			(xy 397.580526 -285.652386) (xy 397.588295 -285.67099) (xy 397.602659 -285.685137) (xy 397.611854 -285.689294)
			(xy 397.713962 -285.730442) (xy 397.744188 -285.724092) (xy 397.75511 -285.712662) (xy 397.772511 -285.695361)
			(xy 397.811808 -285.665981) (xy 397.855295 -285.643256) (xy 397.901853 -285.627769) (xy 397.950287 -285.619918)
			(xy 397.97482 -285.619444) (xy 398.000078 -285.619967) (xy 398.049905 -285.628284) (xy 398.097684 -285.64469)
			(xy 398.142111 -285.668735) (xy 398.181974 -285.699764) (xy 398.216187 -285.736932) (xy 398.243816 -285.779223)
			(xy 398.264107 -285.825485) (xy 398.276508 -285.874456) (xy 398.280676 -285.924752) (xy 398.61923 -285.924752)
			(xy 398.62319 -285.875698) (xy 398.634967 -285.827914) (xy 398.654258 -285.782638) (xy 398.680561 -285.741042)
			(xy 398.713196 -285.704205) (xy 398.751317 -285.67308) (xy 398.793938 -285.648473) (xy 398.839954 -285.631021)
			(xy 398.888173 -285.621177) (xy 398.937348 -285.619196) (xy 398.986203 -285.625128) (xy 399.033474 -285.63882)
			(xy 399.077936 -285.659918) (xy 399.118439 -285.687874) (xy 399.153932 -285.721966) (xy 399.183497 -285.76131)
			(xy 399.206368 -285.804887) (xy 399.221952 -285.851568) (xy 399.229847 -285.900145) (xy 399.230342 -285.924752)
			(xy 399.56919 -285.924752) (xy 399.57315 -285.875698) (xy 399.584927 -285.827914) (xy 399.604218 -285.782638)
			(xy 399.630521 -285.741042) (xy 399.663156 -285.704205) (xy 399.701277 -285.67308) (xy 399.743898 -285.648473)
			(xy 399.789914 -285.631021) (xy 399.838133 -285.621177) (xy 399.887308 -285.619196) (xy 399.936163 -285.625128)
			(xy 399.983434 -285.63882) (xy 400.027896 -285.659918) (xy 400.068399 -285.687874) (xy 400.103892 -285.721966)
			(xy 400.133457 -285.76131) (xy 400.156328 -285.804887) (xy 400.171912 -285.851568) (xy 400.179807 -285.900145)
			(xy 400.180302 -285.924752) (xy 400.51915 -285.924752) (xy 400.52311 -285.875698) (xy 400.534887 -285.827914)
			(xy 400.554178 -285.782638) (xy 400.580481 -285.741042) (xy 400.613116 -285.704205) (xy 400.651237 -285.67308)
			(xy 400.693858 -285.648473) (xy 400.739874 -285.631021) (xy 400.788093 -285.621177) (xy 400.837268 -285.619196)
			(xy 400.886123 -285.625128) (xy 400.933394 -285.63882) (xy 400.977856 -285.659918) (xy 401.018359 -285.687874)
			(xy 401.053852 -285.721966) (xy 401.083417 -285.76131) (xy 401.106288 -285.804887) (xy 401.121872 -285.851568)
			(xy 401.129767 -285.900145) (xy 401.130262 -285.924752) (xy 401.46911 -285.924752) (xy 401.47307 -285.875698)
			(xy 401.484847 -285.827914) (xy 401.504138 -285.782638) (xy 401.530441 -285.741042) (xy 401.563076 -285.704205)
			(xy 401.601197 -285.67308) (xy 401.643818 -285.648473) (xy 401.689834 -285.631021) (xy 401.738053 -285.621177)
			(xy 401.787228 -285.619196) (xy 401.836083 -285.625128) (xy 401.883354 -285.63882) (xy 401.927816 -285.659918)
			(xy 401.968319 -285.687874) (xy 402.003812 -285.721966) (xy 402.033377 -285.76131) (xy 402.056248 -285.804887)
			(xy 402.071832 -285.851568) (xy 402.079727 -285.900145) (xy 402.080222 -285.924752) (xy 402.41907 -285.924752)
			(xy 402.42303 -285.875698) (xy 402.434807 -285.827914) (xy 402.454098 -285.782638) (xy 402.480401 -285.741042)
			(xy 402.513036 -285.704205) (xy 402.551157 -285.67308) (xy 402.593778 -285.648473) (xy 402.639794 -285.631021)
			(xy 402.688013 -285.621177) (xy 402.737188 -285.619196) (xy 402.786043 -285.625128) (xy 402.833314 -285.63882)
			(xy 402.877776 -285.659918) (xy 402.918279 -285.687874) (xy 402.953772 -285.721966) (xy 402.983337 -285.76131)
			(xy 403.006208 -285.804887) (xy 403.021792 -285.851568) (xy 403.029687 -285.900145) (xy 403.030182 -285.924752)
			(xy 403.36903 -285.924752) (xy 403.37299 -285.875698) (xy 403.384767 -285.827914) (xy 403.404058 -285.782638)
			(xy 403.430361 -285.741042) (xy 403.462996 -285.704205) (xy 403.501117 -285.67308) (xy 403.543738 -285.648473)
			(xy 403.589754 -285.631021) (xy 403.637973 -285.621177) (xy 403.687148 -285.619196) (xy 403.736003 -285.625128)
			(xy 403.783274 -285.63882) (xy 403.827736 -285.659918) (xy 403.868239 -285.687874) (xy 403.903732 -285.721966)
			(xy 403.933297 -285.76131) (xy 403.956168 -285.804887) (xy 403.971752 -285.851568) (xy 403.979647 -285.900145)
			(xy 403.980142 -285.924752) (xy 404.31899 -285.924752) (xy 404.32295 -285.875698) (xy 404.334727 -285.827914)
			(xy 404.354018 -285.782638) (xy 404.380321 -285.741042) (xy 404.412956 -285.704205) (xy 404.451077 -285.67308)
			(xy 404.493698 -285.648473) (xy 404.539714 -285.631021) (xy 404.587933 -285.621177) (xy 404.637108 -285.619196)
			(xy 404.685963 -285.625128) (xy 404.733234 -285.63882) (xy 404.777696 -285.659918) (xy 404.818199 -285.687874)
			(xy 404.853692 -285.721966) (xy 404.883257 -285.76131) (xy 404.906128 -285.804887) (xy 404.921712 -285.851568)
			(xy 404.929607 -285.900145) (xy 404.930102 -285.924752) (xy 405.269204 -285.924752) (xy 405.273164 -285.875698)
			(xy 405.284941 -285.827914) (xy 405.304232 -285.782638) (xy 405.330535 -285.741042) (xy 405.36317 -285.704205)
			(xy 405.401291 -285.67308) (xy 405.443912 -285.648473) (xy 405.489928 -285.631021) (xy 405.538147 -285.621177)
			(xy 405.587322 -285.619196) (xy 405.636177 -285.625128) (xy 405.683448 -285.63882) (xy 405.72791 -285.659918)
			(xy 405.768413 -285.687874) (xy 405.803906 -285.721966) (xy 405.833471 -285.76131) (xy 405.856342 -285.804887)
			(xy 405.871926 -285.851568) (xy 405.879821 -285.900145) (xy 405.880316 -285.924752) (xy 406.219164 -285.924752)
			(xy 406.223124 -285.875698) (xy 406.234901 -285.827914) (xy 406.254192 -285.782638) (xy 406.280495 -285.741042)
			(xy 406.31313 -285.704205) (xy 406.351251 -285.67308) (xy 406.393872 -285.648473) (xy 406.439888 -285.631021)
			(xy 406.488107 -285.621177) (xy 406.537282 -285.619196) (xy 406.586137 -285.625128) (xy 406.633408 -285.63882)
			(xy 406.67787 -285.659918) (xy 406.718373 -285.687874) (xy 406.753866 -285.721966) (xy 406.783431 -285.76131)
			(xy 406.806302 -285.804887) (xy 406.821886 -285.851568) (xy 406.829781 -285.900145) (xy 406.830276 -285.924752)
			(xy 408.119084 -285.924752) (xy 408.123044 -285.875698) (xy 408.134821 -285.827914) (xy 408.154112 -285.782638)
			(xy 408.180415 -285.741042) (xy 408.21305 -285.704205) (xy 408.251171 -285.67308) (xy 408.293792 -285.648473)
			(xy 408.339808 -285.631021) (xy 408.388027 -285.621177) (xy 408.437202 -285.619196) (xy 408.486057 -285.625128)
			(xy 408.533328 -285.63882) (xy 408.57779 -285.659918) (xy 408.618293 -285.687874) (xy 408.653786 -285.721966)
			(xy 408.683351 -285.76131) (xy 408.706222 -285.804887) (xy 408.721806 -285.851568) (xy 408.729701 -285.900145)
			(xy 408.730196 -285.924752) (xy 409.069044 -285.924752) (xy 409.073004 -285.875698) (xy 409.084781 -285.827914)
			(xy 409.104072 -285.782638) (xy 409.130375 -285.741042) (xy 409.16301 -285.704205) (xy 409.201131 -285.67308)
			(xy 409.243752 -285.648473) (xy 409.289768 -285.631021) (xy 409.337987 -285.621177) (xy 409.387162 -285.619196)
			(xy 409.436017 -285.625128) (xy 409.483288 -285.63882) (xy 409.52775 -285.659918) (xy 409.568253 -285.687874)
			(xy 409.603746 -285.721966) (xy 409.633311 -285.76131) (xy 409.656182 -285.804887) (xy 409.671766 -285.851568)
			(xy 409.679661 -285.900145) (xy 409.680156 -285.924752) (xy 410.019004 -285.924752) (xy 410.022964 -285.875698)
			(xy 410.034741 -285.827914) (xy 410.054032 -285.782638) (xy 410.080335 -285.741042) (xy 410.11297 -285.704205)
			(xy 410.151091 -285.67308) (xy 410.193712 -285.648473) (xy 410.239728 -285.631021) (xy 410.287947 -285.621177)
			(xy 410.337122 -285.619196) (xy 410.385977 -285.625128) (xy 410.433248 -285.63882) (xy 410.47771 -285.659918)
			(xy 410.518213 -285.687874) (xy 410.553706 -285.721966) (xy 410.583271 -285.76131) (xy 410.606142 -285.804887)
			(xy 410.621726 -285.851568) (xy 410.629621 -285.900145) (xy 410.630116 -285.924752) (xy 410.969218 -285.924752)
			(xy 410.973178 -285.875698) (xy 410.984955 -285.827914) (xy 411.004246 -285.782638) (xy 411.030549 -285.741042)
			(xy 411.063184 -285.704205) (xy 411.101305 -285.67308) (xy 411.143926 -285.648473) (xy 411.189942 -285.631021)
			(xy 411.238161 -285.621177) (xy 411.287336 -285.619196) (xy 411.336191 -285.625128) (xy 411.383462 -285.63882)
			(xy 411.427924 -285.659918) (xy 411.468427 -285.687874) (xy 411.50392 -285.721966) (xy 411.533485 -285.76131)
			(xy 411.556356 -285.804887) (xy 411.57194 -285.851568) (xy 411.579835 -285.900145) (xy 411.58033 -285.924752)
			(xy 411.919178 -285.924752) (xy 411.923138 -285.875698) (xy 411.934915 -285.827914) (xy 411.954206 -285.782638)
			(xy 411.980509 -285.741042) (xy 412.013144 -285.704205) (xy 412.051265 -285.67308) (xy 412.093886 -285.648473)
			(xy 412.139902 -285.631021) (xy 412.188121 -285.621177) (xy 412.237296 -285.619196) (xy 412.286151 -285.625128)
			(xy 412.333422 -285.63882) (xy 412.377884 -285.659918) (xy 412.418387 -285.687874) (xy 412.45388 -285.721966)
			(xy 412.483445 -285.76131) (xy 412.506316 -285.804887) (xy 412.5219 -285.851568) (xy 412.529795 -285.900145)
			(xy 412.53029 -285.924752) (xy 412.869138 -285.924752) (xy 412.873098 -285.875698) (xy 412.884875 -285.827914)
			(xy 412.904166 -285.782638) (xy 412.930469 -285.741042) (xy 412.963104 -285.704205) (xy 413.001225 -285.67308)
			(xy 413.043846 -285.648473) (xy 413.089862 -285.631021) (xy 413.138081 -285.621177) (xy 413.187256 -285.619196)
			(xy 413.236111 -285.625128) (xy 413.283382 -285.63882) (xy 413.327844 -285.659918) (xy 413.368347 -285.687874)
			(xy 413.40384 -285.721966) (xy 413.433405 -285.76131) (xy 413.456276 -285.804887) (xy 413.47186 -285.851568)
			(xy 413.479755 -285.900145) (xy 413.48025 -285.924752) (xy 413.819098 -285.924752) (xy 413.823058 -285.875698)
			(xy 413.834835 -285.827914) (xy 413.854126 -285.782638) (xy 413.880429 -285.741042) (xy 413.913064 -285.704205)
			(xy 413.951185 -285.67308) (xy 413.993806 -285.648473) (xy 414.039822 -285.631021) (xy 414.088041 -285.621177)
			(xy 414.137216 -285.619196) (xy 414.186071 -285.625128) (xy 414.233342 -285.63882) (xy 414.277804 -285.659918)
			(xy 414.318307 -285.687874) (xy 414.3538 -285.721966) (xy 414.383365 -285.76131) (xy 414.406236 -285.804887)
			(xy 414.42182 -285.851568) (xy 414.429715 -285.900145) (xy 414.43021 -285.924752) (xy 414.769058 -285.924752)
			(xy 414.773018 -285.875698) (xy 414.784795 -285.827914) (xy 414.804086 -285.782638) (xy 414.830389 -285.741042)
			(xy 414.863024 -285.704205) (xy 414.901145 -285.67308) (xy 414.943766 -285.648473) (xy 414.989782 -285.631021)
			(xy 415.038001 -285.621177) (xy 415.087176 -285.619196) (xy 415.136031 -285.625128) (xy 415.183302 -285.63882)
			(xy 415.227764 -285.659918) (xy 415.268267 -285.687874) (xy 415.30376 -285.721966) (xy 415.333325 -285.76131)
			(xy 415.356196 -285.804887) (xy 415.37178 -285.851568) (xy 415.379675 -285.900145) (xy 415.38017 -285.924752)
			(xy 415.719018 -285.924752) (xy 415.722978 -285.875698) (xy 415.734755 -285.827914) (xy 415.754046 -285.782638)
			(xy 415.780349 -285.741042) (xy 415.812984 -285.704205) (xy 415.851105 -285.67308) (xy 415.893726 -285.648473)
			(xy 415.939742 -285.631021) (xy 415.987961 -285.621177) (xy 416.037136 -285.619196) (xy 416.085991 -285.625128)
			(xy 416.133262 -285.63882) (xy 416.177724 -285.659918) (xy 416.218227 -285.687874) (xy 416.25372 -285.721966)
			(xy 416.283285 -285.76131) (xy 416.306156 -285.804887) (xy 416.32174 -285.851568) (xy 416.329635 -285.900145)
			(xy 416.33013 -285.924752) (xy 416.668978 -285.924752) (xy 416.672938 -285.875698) (xy 416.684715 -285.827914)
			(xy 416.704006 -285.782638) (xy 416.730309 -285.741042) (xy 416.762944 -285.704205) (xy 416.801065 -285.67308)
			(xy 416.843686 -285.648473) (xy 416.889702 -285.631021) (xy 416.937921 -285.621177) (xy 416.987096 -285.619196)
			(xy 417.035951 -285.625128) (xy 417.083222 -285.63882) (xy 417.127684 -285.659918) (xy 417.168187 -285.687874)
			(xy 417.20368 -285.721966) (xy 417.233245 -285.76131) (xy 417.256116 -285.804887) (xy 417.2717 -285.851568)
			(xy 417.279595 -285.900145) (xy 417.28009 -285.924752) (xy 417.619192 -285.924752) (xy 417.623152 -285.875698)
			(xy 417.634929 -285.827914) (xy 417.65422 -285.782638) (xy 417.680523 -285.741042) (xy 417.713158 -285.704205)
			(xy 417.751279 -285.67308) (xy 417.7939 -285.648473) (xy 417.839916 -285.631021) (xy 417.888135 -285.621177)
			(xy 417.93731 -285.619196) (xy 417.986165 -285.625128) (xy 418.033436 -285.63882) (xy 418.077898 -285.659918)
			(xy 418.118401 -285.687874) (xy 418.153894 -285.721966) (xy 418.183459 -285.76131) (xy 418.20633 -285.804887)
			(xy 418.221914 -285.851568) (xy 418.229809 -285.900145) (xy 418.230304 -285.924752) (xy 418.569152 -285.924752)
			(xy 418.573112 -285.875698) (xy 418.584889 -285.827914) (xy 418.60418 -285.782638) (xy 418.630483 -285.741042)
			(xy 418.663118 -285.704205) (xy 418.701239 -285.67308) (xy 418.74386 -285.648473) (xy 418.789876 -285.631021)
			(xy 418.838095 -285.621177) (xy 418.88727 -285.619196) (xy 418.936125 -285.625128) (xy 418.983396 -285.63882)
			(xy 419.027858 -285.659918) (xy 419.068361 -285.687874) (xy 419.103854 -285.721966) (xy 419.133419 -285.76131)
			(xy 419.15629 -285.804887) (xy 419.171874 -285.851568) (xy 419.179769 -285.900145) (xy 419.180264 -285.924752)
			(xy 419.179769 -285.949359) (xy 419.171874 -285.997936) (xy 419.15629 -286.044617) (xy 419.133419 -286.088194)
			(xy 419.103854 -286.127538) (xy 419.068361 -286.16163) (xy 419.027858 -286.189586) (xy 418.983396 -286.210684)
			(xy 418.936125 -286.224376) (xy 418.88727 -286.230308) (xy 418.838095 -286.228327) (xy 418.789876 -286.218483)
			(xy 418.74386 -286.201031) (xy 418.701239 -286.176424) (xy 418.663118 -286.145299) (xy 418.630483 -286.108462)
			(xy 418.60418 -286.066866) (xy 418.584889 -286.02159) (xy 418.573112 -285.973806) (xy 418.569152 -285.924752)
			(xy 418.230304 -285.924752) (xy 418.229809 -285.949359) (xy 418.221914 -285.997936) (xy 418.20633 -286.044617)
			(xy 418.183459 -286.088194) (xy 418.153894 -286.127538) (xy 418.118401 -286.16163) (xy 418.077898 -286.189586)
			(xy 418.033436 -286.210684) (xy 417.986165 -286.224376) (xy 417.93731 -286.230308) (xy 417.888135 -286.228327)
			(xy 417.839916 -286.218483) (xy 417.7939 -286.201031) (xy 417.751279 -286.176424) (xy 417.713158 -286.145299)
			(xy 417.680523 -286.108462) (xy 417.65422 -286.066866) (xy 417.634929 -286.02159) (xy 417.623152 -285.973806)
			(xy 417.619192 -285.924752) (xy 417.28009 -285.924752) (xy 417.279595 -285.949359) (xy 417.2717 -285.997936)
			(xy 417.256116 -286.044617) (xy 417.233245 -286.088194) (xy 417.20368 -286.127538) (xy 417.168187 -286.16163)
			(xy 417.127684 -286.189586) (xy 417.083222 -286.210684) (xy 417.035951 -286.224376) (xy 416.987096 -286.230308)
			(xy 416.937921 -286.228327) (xy 416.889702 -286.218483) (xy 416.843686 -286.201031) (xy 416.801065 -286.176424)
			(xy 416.762944 -286.145299) (xy 416.730309 -286.108462) (xy 416.704006 -286.066866) (xy 416.684715 -286.02159)
			(xy 416.672938 -285.973806) (xy 416.668978 -285.924752) (xy 416.33013 -285.924752) (xy 416.329635 -285.949359)
			(xy 416.32174 -285.997936) (xy 416.306156 -286.044617) (xy 416.283285 -286.088194) (xy 416.25372 -286.127538)
			(xy 416.218227 -286.16163) (xy 416.177724 -286.189586) (xy 416.133262 -286.210684) (xy 416.085991 -286.224376)
			(xy 416.037136 -286.230308) (xy 415.987961 -286.228327) (xy 415.939742 -286.218483) (xy 415.893726 -286.201031)
			(xy 415.851105 -286.176424) (xy 415.812984 -286.145299) (xy 415.780349 -286.108462) (xy 415.754046 -286.066866)
			(xy 415.734755 -286.02159) (xy 415.722978 -285.973806) (xy 415.719018 -285.924752) (xy 415.38017 -285.924752)
			(xy 415.379675 -285.949359) (xy 415.37178 -285.997936) (xy 415.356196 -286.044617) (xy 415.333325 -286.088194)
			(xy 415.30376 -286.127538) (xy 415.268267 -286.16163) (xy 415.227764 -286.189586) (xy 415.183302 -286.210684)
			(xy 415.136031 -286.224376) (xy 415.087176 -286.230308) (xy 415.038001 -286.228327) (xy 414.989782 -286.218483)
			(xy 414.943766 -286.201031) (xy 414.901145 -286.176424) (xy 414.863024 -286.145299) (xy 414.830389 -286.108462)
			(xy 414.804086 -286.066866) (xy 414.784795 -286.02159) (xy 414.773018 -285.973806) (xy 414.769058 -285.924752)
			(xy 414.43021 -285.924752) (xy 414.429715 -285.949359) (xy 414.42182 -285.997936) (xy 414.406236 -286.044617)
			(xy 414.383365 -286.088194) (xy 414.3538 -286.127538) (xy 414.318307 -286.16163) (xy 414.277804 -286.189586)
			(xy 414.233342 -286.210684) (xy 414.186071 -286.224376) (xy 414.137216 -286.230308) (xy 414.088041 -286.228327)
			(xy 414.039822 -286.218483) (xy 413.993806 -286.201031) (xy 413.951185 -286.176424) (xy 413.913064 -286.145299)
			(xy 413.880429 -286.108462) (xy 413.854126 -286.066866) (xy 413.834835 -286.02159) (xy 413.823058 -285.973806)
			(xy 413.819098 -285.924752) (xy 413.48025 -285.924752) (xy 413.479755 -285.949359) (xy 413.47186 -285.997936)
			(xy 413.456276 -286.044617) (xy 413.433405 -286.088194) (xy 413.40384 -286.127538) (xy 413.368347 -286.16163)
			(xy 413.327844 -286.189586) (xy 413.283382 -286.210684) (xy 413.236111 -286.224376) (xy 413.187256 -286.230308)
			(xy 413.138081 -286.228327) (xy 413.089862 -286.218483) (xy 413.043846 -286.201031) (xy 413.001225 -286.176424)
			(xy 412.963104 -286.145299) (xy 412.930469 -286.108462) (xy 412.904166 -286.066866) (xy 412.884875 -286.02159)
			(xy 412.873098 -285.973806) (xy 412.869138 -285.924752) (xy 412.53029 -285.924752) (xy 412.529795 -285.949359)
			(xy 412.5219 -285.997936) (xy 412.506316 -286.044617) (xy 412.483445 -286.088194) (xy 412.45388 -286.127538)
			(xy 412.418387 -286.16163) (xy 412.377884 -286.189586) (xy 412.333422 -286.210684) (xy 412.286151 -286.224376)
			(xy 412.237296 -286.230308) (xy 412.188121 -286.228327) (xy 412.139902 -286.218483) (xy 412.093886 -286.201031)
			(xy 412.051265 -286.176424) (xy 412.013144 -286.145299) (xy 411.980509 -286.108462) (xy 411.954206 -286.066866)
			(xy 411.934915 -286.02159) (xy 411.923138 -285.973806) (xy 411.919178 -285.924752) (xy 411.58033 -285.924752)
			(xy 411.579835 -285.949359) (xy 411.57194 -285.997936) (xy 411.556356 -286.044617) (xy 411.533485 -286.088194)
			(xy 411.50392 -286.127538) (xy 411.468427 -286.16163) (xy 411.427924 -286.189586) (xy 411.383462 -286.210684)
			(xy 411.336191 -286.224376) (xy 411.287336 -286.230308) (xy 411.238161 -286.228327) (xy 411.189942 -286.218483)
			(xy 411.143926 -286.201031) (xy 411.101305 -286.176424) (xy 411.063184 -286.145299) (xy 411.030549 -286.108462)
			(xy 411.004246 -286.066866) (xy 410.984955 -286.02159) (xy 410.973178 -285.973806) (xy 410.969218 -285.924752)
			(xy 410.630116 -285.924752) (xy 410.629621 -285.949359) (xy 410.621726 -285.997936) (xy 410.606142 -286.044617)
			(xy 410.583271 -286.088194) (xy 410.553706 -286.127538) (xy 410.518213 -286.16163) (xy 410.47771 -286.189586)
			(xy 410.433248 -286.210684) (xy 410.385977 -286.224376) (xy 410.337122 -286.230308) (xy 410.287947 -286.228327)
			(xy 410.239728 -286.218483) (xy 410.193712 -286.201031) (xy 410.151091 -286.176424) (xy 410.11297 -286.145299)
			(xy 410.080335 -286.108462) (xy 410.054032 -286.066866) (xy 410.034741 -286.02159) (xy 410.022964 -285.973806)
			(xy 410.019004 -285.924752) (xy 409.680156 -285.924752) (xy 409.679661 -285.949359) (xy 409.671766 -285.997936)
			(xy 409.656182 -286.044617) (xy 409.633311 -286.088194) (xy 409.603746 -286.127538) (xy 409.568253 -286.16163)
			(xy 409.52775 -286.189586) (xy 409.483288 -286.210684) (xy 409.436017 -286.224376) (xy 409.387162 -286.230308)
			(xy 409.337987 -286.228327) (xy 409.289768 -286.218483) (xy 409.243752 -286.201031) (xy 409.201131 -286.176424)
			(xy 409.16301 -286.145299) (xy 409.130375 -286.108462) (xy 409.104072 -286.066866) (xy 409.084781 -286.02159)
			(xy 409.073004 -285.973806) (xy 409.069044 -285.924752) (xy 408.730196 -285.924752) (xy 408.729701 -285.949359)
			(xy 408.721806 -285.997936) (xy 408.706222 -286.044617) (xy 408.683351 -286.088194) (xy 408.653786 -286.127538)
			(xy 408.618293 -286.16163) (xy 408.57779 -286.189586) (xy 408.533328 -286.210684) (xy 408.486057 -286.224376)
			(xy 408.437202 -286.230308) (xy 408.388027 -286.228327) (xy 408.339808 -286.218483) (xy 408.293792 -286.201031)
			(xy 408.251171 -286.176424) (xy 408.21305 -286.145299) (xy 408.180415 -286.108462) (xy 408.154112 -286.066866)
			(xy 408.134821 -286.02159) (xy 408.123044 -285.973806) (xy 408.119084 -285.924752) (xy 406.830276 -285.924752)
			(xy 406.829781 -285.949359) (xy 406.821886 -285.997936) (xy 406.806302 -286.044617) (xy 406.783431 -286.088194)
			(xy 406.753866 -286.127538) (xy 406.718373 -286.16163) (xy 406.67787 -286.189586) (xy 406.633408 -286.210684)
			(xy 406.586137 -286.224376) (xy 406.537282 -286.230308) (xy 406.488107 -286.228327) (xy 406.439888 -286.218483)
			(xy 406.393872 -286.201031) (xy 406.351251 -286.176424) (xy 406.31313 -286.145299) (xy 406.280495 -286.108462)
			(xy 406.254192 -286.066866) (xy 406.234901 -286.02159) (xy 406.223124 -285.973806) (xy 406.219164 -285.924752)
			(xy 405.880316 -285.924752) (xy 405.879821 -285.949359) (xy 405.871926 -285.997936) (xy 405.856342 -286.044617)
			(xy 405.833471 -286.088194) (xy 405.803906 -286.127538) (xy 405.768413 -286.16163) (xy 405.72791 -286.189586)
			(xy 405.683448 -286.210684) (xy 405.636177 -286.224376) (xy 405.587322 -286.230308) (xy 405.538147 -286.228327)
			(xy 405.489928 -286.218483) (xy 405.443912 -286.201031) (xy 405.401291 -286.176424) (xy 405.36317 -286.145299)
			(xy 405.330535 -286.108462) (xy 405.304232 -286.066866) (xy 405.284941 -286.02159) (xy 405.273164 -285.973806)
			(xy 405.269204 -285.924752) (xy 404.930102 -285.924752) (xy 404.929607 -285.949359) (xy 404.921712 -285.997936)
			(xy 404.906128 -286.044617) (xy 404.883257 -286.088194) (xy 404.853692 -286.127538) (xy 404.818199 -286.16163)
			(xy 404.777696 -286.189586) (xy 404.733234 -286.210684) (xy 404.685963 -286.224376) (xy 404.637108 -286.230308)
			(xy 404.587933 -286.228327) (xy 404.539714 -286.218483) (xy 404.493698 -286.201031) (xy 404.451077 -286.176424)
			(xy 404.412956 -286.145299) (xy 404.380321 -286.108462) (xy 404.354018 -286.066866) (xy 404.334727 -286.02159)
			(xy 404.32295 -285.973806) (xy 404.31899 -285.924752) (xy 403.980142 -285.924752) (xy 403.979647 -285.949359)
			(xy 403.971752 -285.997936) (xy 403.956168 -286.044617) (xy 403.933297 -286.088194) (xy 403.903732 -286.127538)
			(xy 403.868239 -286.16163) (xy 403.827736 -286.189586) (xy 403.783274 -286.210684) (xy 403.736003 -286.224376)
			(xy 403.687148 -286.230308) (xy 403.637973 -286.228327) (xy 403.589754 -286.218483) (xy 403.543738 -286.201031)
			(xy 403.501117 -286.176424) (xy 403.462996 -286.145299) (xy 403.430361 -286.108462) (xy 403.404058 -286.066866)
			(xy 403.384767 -286.02159) (xy 403.37299 -285.973806) (xy 403.36903 -285.924752) (xy 403.030182 -285.924752)
			(xy 403.029687 -285.949359) (xy 403.021792 -285.997936) (xy 403.006208 -286.044617) (xy 402.983337 -286.088194)
			(xy 402.953772 -286.127538) (xy 402.918279 -286.16163) (xy 402.877776 -286.189586) (xy 402.833314 -286.210684)
			(xy 402.786043 -286.224376) (xy 402.737188 -286.230308) (xy 402.688013 -286.228327) (xy 402.639794 -286.218483)
			(xy 402.593778 -286.201031) (xy 402.551157 -286.176424) (xy 402.513036 -286.145299) (xy 402.480401 -286.108462)
			(xy 402.454098 -286.066866) (xy 402.434807 -286.02159) (xy 402.42303 -285.973806) (xy 402.41907 -285.924752)
			(xy 402.080222 -285.924752) (xy 402.079727 -285.949359) (xy 402.071832 -285.997936) (xy 402.056248 -286.044617)
			(xy 402.033377 -286.088194) (xy 402.003812 -286.127538) (xy 401.968319 -286.16163) (xy 401.927816 -286.189586)
			(xy 401.883354 -286.210684) (xy 401.836083 -286.224376) (xy 401.787228 -286.230308) (xy 401.738053 -286.228327)
			(xy 401.689834 -286.218483) (xy 401.643818 -286.201031) (xy 401.601197 -286.176424) (xy 401.563076 -286.145299)
			(xy 401.530441 -286.108462) (xy 401.504138 -286.066866) (xy 401.484847 -286.02159) (xy 401.47307 -285.973806)
			(xy 401.46911 -285.924752) (xy 401.130262 -285.924752) (xy 401.129767 -285.949359) (xy 401.121872 -285.997936)
			(xy 401.106288 -286.044617) (xy 401.083417 -286.088194) (xy 401.053852 -286.127538) (xy 401.018359 -286.16163)
			(xy 400.977856 -286.189586) (xy 400.933394 -286.210684) (xy 400.886123 -286.224376) (xy 400.837268 -286.230308)
			(xy 400.788093 -286.228327) (xy 400.739874 -286.218483) (xy 400.693858 -286.201031) (xy 400.651237 -286.176424)
			(xy 400.613116 -286.145299) (xy 400.580481 -286.108462) (xy 400.554178 -286.066866) (xy 400.534887 -286.02159)
			(xy 400.52311 -285.973806) (xy 400.51915 -285.924752) (xy 400.180302 -285.924752) (xy 400.179807 -285.949359)
			(xy 400.171912 -285.997936) (xy 400.156328 -286.044617) (xy 400.133457 -286.088194) (xy 400.103892 -286.127538)
			(xy 400.068399 -286.16163) (xy 400.027896 -286.189586) (xy 399.983434 -286.210684) (xy 399.936163 -286.224376)
			(xy 399.887308 -286.230308) (xy 399.838133 -286.228327) (xy 399.789914 -286.218483) (xy 399.743898 -286.201031)
			(xy 399.701277 -286.176424) (xy 399.663156 -286.145299) (xy 399.630521 -286.108462) (xy 399.604218 -286.066866)
			(xy 399.584927 -286.02159) (xy 399.57315 -285.973806) (xy 399.56919 -285.924752) (xy 399.230342 -285.924752)
			(xy 399.229847 -285.949359) (xy 399.221952 -285.997936) (xy 399.206368 -286.044617) (xy 399.183497 -286.088194)
			(xy 399.153932 -286.127538) (xy 399.118439 -286.16163) (xy 399.077936 -286.189586) (xy 399.033474 -286.210684)
			(xy 398.986203 -286.224376) (xy 398.937348 -286.230308) (xy 398.888173 -286.228327) (xy 398.839954 -286.218483)
			(xy 398.793938 -286.201031) (xy 398.751317 -286.176424) (xy 398.713196 -286.145299) (xy 398.680561 -286.108462)
			(xy 398.654258 -286.066866) (xy 398.634967 -286.02159) (xy 398.62319 -285.973806) (xy 398.61923 -285.924752)
			(xy 398.280676 -285.924752) (xy 398.28068 -285.9248) (xy 398.276508 -285.975144) (xy 398.264107 -286.024115)
			(xy 398.243816 -286.070377) (xy 398.216187 -286.112668) (xy 398.181974 -286.149836) (xy 398.142111 -286.180865)
			(xy 398.097684 -286.20491) (xy 398.049905 -286.221316) (xy 398.000078 -286.229633) (xy 397.97482 -286.23006)
			(xy 397.96328 -286.229934) (xy 397.940268 -286.228157) (xy 397.928846 -286.226504) (xy 397.925036 -286.225996)
			(xy 397.92402 -286.225996) (xy 397.900115 -286.221483) (xy 397.854033 -286.205895) (xy 397.810998 -286.183214)
			(xy 397.772092 -286.154011) (xy 397.754856 -286.136842) (xy 397.743934 -286.125412) (xy 397.713962 -286.119062)
			(xy 397.611854 -286.16021) (xy 397.602693 -286.164403) (xy 397.588386 -286.178569) (xy 397.580599 -286.197135)
			(xy 397.580104 -286.2072) (xy 397.580104 -286.392366) (xy 397.579786 -286.399732) (xy 421.894012 -286.399732)
			(xy 421.897972 -286.350678) (xy 421.909749 -286.302894) (xy 421.92904 -286.257618) (xy 421.955343 -286.216022)
			(xy 421.987978 -286.179185) (xy 422.026099 -286.14806) (xy 422.06872 -286.123453) (xy 422.114736 -286.106001)
			(xy 422.162955 -286.096157) (xy 422.21213 -286.094176) (xy 422.260985 -286.100108) (xy 422.308256 -286.1138)
			(xy 422.352718 -286.134898) (xy 422.393221 -286.162854) (xy 422.428714 -286.196946) (xy 422.458279 -286.23629)
			(xy 422.48115 -286.279867) (xy 422.496734 -286.326548) (xy 422.504629 -286.375125) (xy 422.505124 -286.399732)
			(xy 422.844226 -286.399732) (xy 422.848186 -286.350678) (xy 422.859963 -286.302894) (xy 422.879254 -286.257618)
			(xy 422.905557 -286.216022) (xy 422.938192 -286.179185) (xy 422.976313 -286.14806) (xy 423.018934 -286.123453)
			(xy 423.06495 -286.106001) (xy 423.113169 -286.096157) (xy 423.162344 -286.094176) (xy 423.211199 -286.100108)
			(xy 423.25847 -286.1138) (xy 423.302932 -286.134898) (xy 423.343435 -286.162854) (xy 423.378928 -286.196946)
			(xy 423.408493 -286.23629) (xy 423.431364 -286.279867) (xy 423.446948 -286.326548) (xy 423.454843 -286.375125)
			(xy 423.455338 -286.399732) (xy 423.794186 -286.399732) (xy 423.798146 -286.350678) (xy 423.809923 -286.302894)
			(xy 423.829214 -286.257618) (xy 423.855517 -286.216022) (xy 423.888152 -286.179185) (xy 423.926273 -286.14806)
			(xy 423.968894 -286.123453) (xy 424.01491 -286.106001) (xy 424.063129 -286.096157) (xy 424.112304 -286.094176)
			(xy 424.161159 -286.100108) (xy 424.20843 -286.1138) (xy 424.252892 -286.134898) (xy 424.293395 -286.162854)
			(xy 424.328888 -286.196946) (xy 424.358453 -286.23629) (xy 424.381324 -286.279867) (xy 424.396908 -286.326548)
			(xy 424.404803 -286.375125) (xy 424.405298 -286.399732) (xy 424.404803 -286.424339) (xy 424.404583 -286.425694)
			(xy 424.723302 -286.425694) (xy 424.723302 -286.374278) (xy 424.731345 -286.323496) (xy 424.747233 -286.274597)
			(xy 424.770576 -286.228785) (xy 424.800797 -286.187189) (xy 424.837153 -286.150833) (xy 424.878749 -286.120612)
			(xy 424.924561 -286.097269) (xy 424.97346 -286.081381) (xy 425.024242 -286.073338) (xy 425.075658 -286.073338)
			(xy 425.12644 -286.081381) (xy 425.175339 -286.097269) (xy 425.221151 -286.120612) (xy 425.262747 -286.150833)
			(xy 425.299103 -286.187189) (xy 425.329324 -286.228785) (xy 425.352667 -286.274597) (xy 425.368555 -286.323496)
			(xy 425.376598 -286.374278) (xy 425.377102 -286.399986) (xy 425.376598 -286.425694) (xy 425.673262 -286.425694)
			(xy 425.673262 -286.374278) (xy 425.681305 -286.323496) (xy 425.697193 -286.274597) (xy 425.720536 -286.228785)
			(xy 425.750757 -286.187189) (xy 425.787113 -286.150833) (xy 425.828709 -286.120612) (xy 425.874521 -286.097269)
			(xy 425.92342 -286.081381) (xy 425.974202 -286.073338) (xy 426.025618 -286.073338) (xy 426.0764 -286.081381)
			(xy 426.125299 -286.097269) (xy 426.171111 -286.120612) (xy 426.212707 -286.150833) (xy 426.249063 -286.187189)
			(xy 426.279284 -286.228785) (xy 426.302627 -286.274597) (xy 426.318515 -286.323496) (xy 426.326558 -286.374278)
			(xy 426.327057 -286.399732) (xy 426.644066 -286.399732) (xy 426.648026 -286.350678) (xy 426.659803 -286.302894)
			(xy 426.679094 -286.257618) (xy 426.705397 -286.216022) (xy 426.738032 -286.179185) (xy 426.776153 -286.14806)
			(xy 426.818774 -286.123453) (xy 426.86479 -286.106001) (xy 426.913009 -286.096157) (xy 426.962184 -286.094176)
			(xy 427.011039 -286.100108) (xy 427.05831 -286.1138) (xy 427.102772 -286.134898) (xy 427.143275 -286.162854)
			(xy 427.178768 -286.196946) (xy 427.208333 -286.23629) (xy 427.231204 -286.279867) (xy 427.246788 -286.326548)
			(xy 427.254683 -286.375125) (xy 427.255178 -286.399732) (xy 427.254683 -286.424339) (xy 427.254504 -286.42544)
			(xy 427.573182 -286.42544) (xy 427.573182 -286.374024) (xy 427.581225 -286.323242) (xy 427.597113 -286.274343)
			(xy 427.620456 -286.228531) (xy 427.650677 -286.186935) (xy 427.687033 -286.150579) (xy 427.728629 -286.120358)
			(xy 427.774441 -286.097015) (xy 427.82334 -286.081127) (xy 427.874122 -286.073084) (xy 427.925538 -286.073084)
			(xy 427.97632 -286.081127) (xy 428.025219 -286.097015) (xy 428.071031 -286.120358) (xy 428.112627 -286.150579)
			(xy 428.148983 -286.186935) (xy 428.179204 -286.228531) (xy 428.202547 -286.274343) (xy 428.218435 -286.323242)
			(xy 428.226478 -286.374024) (xy 428.226982 -286.399732) (xy 428.226478 -286.42544) (xy 428.523142 -286.42544)
			(xy 428.523142 -286.374024) (xy 428.531185 -286.323242) (xy 428.547073 -286.274343) (xy 428.570416 -286.228531)
			(xy 428.600637 -286.186935) (xy 428.636993 -286.150579) (xy 428.678589 -286.120358) (xy 428.724401 -286.097015)
			(xy 428.7733 -286.081127) (xy 428.824082 -286.073084) (xy 428.875498 -286.073084) (xy 428.92628 -286.081127)
			(xy 428.975179 -286.097015) (xy 429.020991 -286.120358) (xy 429.062587 -286.150579) (xy 429.098943 -286.186935)
			(xy 429.129164 -286.228531) (xy 429.152507 -286.274343) (xy 429.168395 -286.323242) (xy 429.176438 -286.374024)
			(xy 429.176942 -286.399732) (xy 429.4942 -286.399732) (xy 429.49816 -286.350678) (xy 429.509937 -286.302894)
			(xy 429.529228 -286.257618) (xy 429.555531 -286.216022) (xy 429.588166 -286.179185) (xy 429.626287 -286.14806)
			(xy 429.668908 -286.123453) (xy 429.714924 -286.106001) (xy 429.763143 -286.096157) (xy 429.812318 -286.094176)
			(xy 429.861173 -286.100108) (xy 429.908444 -286.1138) (xy 429.952906 -286.134898) (xy 429.993409 -286.162854)
			(xy 430.028902 -286.196946) (xy 430.058467 -286.23629) (xy 430.081338 -286.279867) (xy 430.096922 -286.326548)
			(xy 430.104817 -286.375125) (xy 430.105312 -286.399732) (xy 430.44416 -286.399732) (xy 430.44812 -286.350678)
			(xy 430.459897 -286.302894) (xy 430.479188 -286.257618) (xy 430.505491 -286.216022) (xy 430.538126 -286.179185)
			(xy 430.576247 -286.14806) (xy 430.618868 -286.123453) (xy 430.664884 -286.106001) (xy 430.713103 -286.096157)
			(xy 430.762278 -286.094176) (xy 430.811133 -286.100108) (xy 430.858404 -286.1138) (xy 430.902866 -286.134898)
			(xy 430.943369 -286.162854) (xy 430.978862 -286.196946) (xy 431.008427 -286.23629) (xy 431.031298 -286.279867)
			(xy 431.046882 -286.326548) (xy 431.054777 -286.375125) (xy 431.055272 -286.399732) (xy 431.054777 -286.424339)
			(xy 431.046882 -286.472916) (xy 431.031298 -286.519597) (xy 431.008427 -286.563174) (xy 430.978862 -286.602518)
			(xy 430.943369 -286.63661) (xy 430.902866 -286.664566) (xy 430.858404 -286.685664) (xy 430.811133 -286.699356)
			(xy 430.762278 -286.705288) (xy 430.713103 -286.703307) (xy 430.664884 -286.693463) (xy 430.618868 -286.676011)
			(xy 430.576247 -286.651404) (xy 430.538126 -286.620279) (xy 430.505491 -286.583442) (xy 430.479188 -286.541846)
			(xy 430.459897 -286.49657) (xy 430.44812 -286.448786) (xy 430.44416 -286.399732) (xy 430.105312 -286.399732)
			(xy 430.104817 -286.424339) (xy 430.096922 -286.472916) (xy 430.081338 -286.519597) (xy 430.058467 -286.563174)
			(xy 430.028902 -286.602518) (xy 429.993409 -286.63661) (xy 429.952906 -286.664566) (xy 429.908444 -286.685664)
			(xy 429.861173 -286.699356) (xy 429.812318 -286.705288) (xy 429.763143 -286.703307) (xy 429.714924 -286.693463)
			(xy 429.668908 -286.676011) (xy 429.626287 -286.651404) (xy 429.588166 -286.620279) (xy 429.555531 -286.583442)
			(xy 429.529228 -286.541846) (xy 429.509937 -286.49657) (xy 429.49816 -286.448786) (xy 429.4942 -286.399732)
			(xy 429.176942 -286.399732) (xy 429.176438 -286.42544) (xy 429.168395 -286.476222) (xy 429.152507 -286.525121)
			(xy 429.129164 -286.570933) (xy 429.098943 -286.612529) (xy 429.062587 -286.648885) (xy 429.020991 -286.679106)
			(xy 428.975179 -286.702449) (xy 428.92628 -286.718337) (xy 428.875498 -286.72638) (xy 428.824082 -286.72638)
			(xy 428.7733 -286.718337) (xy 428.724401 -286.702449) (xy 428.678589 -286.679106) (xy 428.636993 -286.648885)
			(xy 428.600637 -286.612529) (xy 428.570416 -286.570933) (xy 428.547073 -286.525121) (xy 428.531185 -286.476222)
			(xy 428.523142 -286.42544) (xy 428.226478 -286.42544) (xy 428.218435 -286.476222) (xy 428.202547 -286.525121)
			(xy 428.179204 -286.570933) (xy 428.148983 -286.612529) (xy 428.112627 -286.648885) (xy 428.071031 -286.679106)
			(xy 428.025219 -286.702449) (xy 427.97632 -286.718337) (xy 427.925538 -286.72638) (xy 427.874122 -286.72638)
			(xy 427.82334 -286.718337) (xy 427.774441 -286.702449) (xy 427.728629 -286.679106) (xy 427.687033 -286.648885)
			(xy 427.650677 -286.612529) (xy 427.620456 -286.570933) (xy 427.597113 -286.525121) (xy 427.581225 -286.476222)
			(xy 427.573182 -286.42544) (xy 427.254504 -286.42544) (xy 427.246788 -286.472916) (xy 427.231204 -286.519597)
			(xy 427.208333 -286.563174) (xy 427.178768 -286.602518) (xy 427.143275 -286.63661) (xy 427.102772 -286.664566)
			(xy 427.05831 -286.685664) (xy 427.011039 -286.699356) (xy 426.962184 -286.705288) (xy 426.913009 -286.703307)
			(xy 426.86479 -286.693463) (xy 426.818774 -286.676011) (xy 426.776153 -286.651404) (xy 426.738032 -286.620279)
			(xy 426.705397 -286.583442) (xy 426.679094 -286.541846) (xy 426.659803 -286.49657) (xy 426.648026 -286.448786)
			(xy 426.644066 -286.399732) (xy 426.327057 -286.399732) (xy 426.327062 -286.399986) (xy 426.326558 -286.425694)
			(xy 426.318515 -286.476476) (xy 426.302627 -286.525375) (xy 426.279284 -286.571187) (xy 426.249063 -286.612783)
			(xy 426.212707 -286.649139) (xy 426.171111 -286.67936) (xy 426.125299 -286.702703) (xy 426.0764 -286.718591)
			(xy 426.025618 -286.726634) (xy 425.974202 -286.726634) (xy 425.92342 -286.718591) (xy 425.874521 -286.702703)
			(xy 425.828709 -286.67936) (xy 425.787113 -286.649139) (xy 425.750757 -286.612783) (xy 425.720536 -286.571187)
			(xy 425.697193 -286.525375) (xy 425.681305 -286.476476) (xy 425.673262 -286.425694) (xy 425.376598 -286.425694)
			(xy 425.368555 -286.476476) (xy 425.352667 -286.525375) (xy 425.329324 -286.571187) (xy 425.299103 -286.612783)
			(xy 425.262747 -286.649139) (xy 425.221151 -286.67936) (xy 425.175339 -286.702703) (xy 425.12644 -286.718591)
			(xy 425.075658 -286.726634) (xy 425.024242 -286.726634) (xy 424.97346 -286.718591) (xy 424.924561 -286.702703)
			(xy 424.878749 -286.67936) (xy 424.837153 -286.649139) (xy 424.800797 -286.612783) (xy 424.770576 -286.571187)
			(xy 424.747233 -286.525375) (xy 424.731345 -286.476476) (xy 424.723302 -286.425694) (xy 424.404583 -286.425694)
			(xy 424.396908 -286.472916) (xy 424.381324 -286.519597) (xy 424.358453 -286.563174) (xy 424.328888 -286.602518)
			(xy 424.293395 -286.63661) (xy 424.252892 -286.664566) (xy 424.20843 -286.685664) (xy 424.161159 -286.699356)
			(xy 424.112304 -286.705288) (xy 424.063129 -286.703307) (xy 424.01491 -286.693463) (xy 423.968894 -286.676011)
			(xy 423.926273 -286.651404) (xy 423.888152 -286.620279) (xy 423.855517 -286.583442) (xy 423.829214 -286.541846)
			(xy 423.809923 -286.49657) (xy 423.798146 -286.448786) (xy 423.794186 -286.399732) (xy 423.455338 -286.399732)
			(xy 423.454843 -286.424339) (xy 423.446948 -286.472916) (xy 423.431364 -286.519597) (xy 423.408493 -286.563174)
			(xy 423.378928 -286.602518) (xy 423.343435 -286.63661) (xy 423.302932 -286.664566) (xy 423.25847 -286.685664)
			(xy 423.211199 -286.699356) (xy 423.162344 -286.705288) (xy 423.113169 -286.703307) (xy 423.06495 -286.693463)
			(xy 423.018934 -286.676011) (xy 422.976313 -286.651404) (xy 422.938192 -286.620279) (xy 422.905557 -286.583442)
			(xy 422.879254 -286.541846) (xy 422.859963 -286.49657) (xy 422.848186 -286.448786) (xy 422.844226 -286.399732)
			(xy 422.505124 -286.399732) (xy 422.504629 -286.424339) (xy 422.496734 -286.472916) (xy 422.48115 -286.519597)
			(xy 422.458279 -286.563174) (xy 422.428714 -286.602518) (xy 422.393221 -286.63661) (xy 422.352718 -286.664566)
			(xy 422.308256 -286.685664) (xy 422.260985 -286.699356) (xy 422.21213 -286.705288) (xy 422.162955 -286.703307)
			(xy 422.114736 -286.693463) (xy 422.06872 -286.676011) (xy 422.026099 -286.651404) (xy 421.987978 -286.620279)
			(xy 421.955343 -286.583442) (xy 421.92904 -286.541846) (xy 421.909749 -286.49657) (xy 421.897972 -286.448786)
			(xy 421.894012 -286.399732) (xy 397.579786 -286.399732) (xy 397.579669 -286.402431) (xy 397.571938 -286.421018)
			(xy 397.565118 -286.428434) (xy 397.498062 -286.49549) (xy 397.491207 -286.502885) (xy 397.483459 -286.521484)
			(xy 397.483076 -286.531558) (xy 397.483076 -287.11398) (xy 397.48356 -287.123992) (xy 397.491215 -287.142495)
			(xy 397.505368 -287.15666) (xy 397.523864 -287.164331) (xy 397.533876 -287.16478) (xy 397.670528 -287.16478)
			(xy 397.703294 -287.166558) (xy 397.71574 -287.167828) (xy 397.727932 -287.163002) (xy 397.736983 -287.158862)
			(xy 397.751242 -287.145005) (xy 397.75917 -287.126771) (xy 397.759577 -287.106893) (xy 397.75638 -287.09747)
			(xy 397.750792 -287.082484) (xy 397.74495 -287.07588) (xy 397.727361 -287.054822) (xy 397.699214 -287.007732)
			(xy 397.679927 -286.956373) (xy 397.670119 -286.902396) (xy 397.669512 -286.874966) (xy 397.670034 -286.849711)
			(xy 397.678347 -286.799889) (xy 397.694748 -286.752115) (xy 397.718789 -286.707692) (xy 397.749813 -286.667832)
			(xy 397.786975 -286.633622) (xy 397.829261 -286.605996) (xy 397.875517 -286.585706) (xy 397.924482 -286.573306)
			(xy 397.97482 -286.569135) (xy 398.025158 -286.573306) (xy 398.074123 -286.585706) (xy 398.120379 -286.605996)
			(xy 398.162665 -286.633622) (xy 398.199827 -286.667832) (xy 398.230851 -286.707692) (xy 398.254892 -286.752115)
			(xy 398.271293 -286.799889) (xy 398.279606 -286.849711) (xy 398.280128 -286.874966) (xy 398.279552 -286.9024)
			(xy 398.269756 -286.956388) (xy 398.250471 -287.007756) (xy 398.22232 -287.054853) (xy 398.20469 -287.07588)
			(xy 398.198848 -287.082484) (xy 398.15516 -287.194752) (xy 398.176633 -287.184649) (xy 398.221927 -287.170493)
			(xy 398.24533 -287.166558) (xy 398.246346 -287.166558) (xy 398.248886 -287.166304) (xy 398.279112 -287.16478)
			(xy 398.618202 -287.16478) (xy 398.643345 -287.165286) (xy 398.69295 -287.173523) (xy 398.740531 -287.18979)
			(xy 398.784797 -287.213645) (xy 398.824548 -287.244442) (xy 398.841976 -287.26257) (xy 398.849342 -287.270444)
			(xy 398.877536 -287.282636) (xy 398.882375 -287.284642) (xy 398.892619 -287.286824) (xy 398.897856 -287.286954)
			(xy 398.947132 -287.286954) (xy 398.957546 -287.285938) (xy 398.96796 -287.283652) (xy 398.973548 -287.282636)
			(xy 399.000726 -287.270444) (xy 399.007838 -287.262824) (xy 399.025304 -287.244685) (xy 399.065085 -287.213818)
			(xy 399.109392 -287.189897) (xy 399.157025 -287.173573) (xy 399.20669 -287.165288) (xy 399.231866 -287.16478)
			(xy 399.568162 -287.16478) (xy 399.593303 -287.165291) (xy 399.642903 -287.173537) (xy 399.690477 -287.18981)
			(xy 399.734736 -287.213671) (xy 399.774479 -287.244471) (xy 399.791936 -287.26257) (xy 399.799302 -287.270444)
			(xy 399.827496 -287.282636) (xy 399.832336 -287.284636) (xy 399.84258 -287.286806) (xy 399.847816 -287.286954)
			(xy 399.897092 -287.286954) (xy 399.907506 -287.285938) (xy 399.91792 -287.283652) (xy 399.923508 -287.282636)
			(xy 399.950686 -287.270444) (xy 399.957798 -287.262824) (xy 399.975265 -287.244689) (xy 400.015048 -287.213829)
			(xy 400.059356 -287.189918) (xy 400.106988 -287.173603) (xy 400.156652 -287.165327) (xy 400.181826 -287.16478)
			(xy 400.518122 -287.16478) (xy 400.543264 -287.165288) (xy 400.592868 -287.173528) (xy 400.640446 -287.189797)
			(xy 400.68471 -287.213654) (xy 400.724458 -287.244452) (xy 400.741896 -287.26257) (xy 400.749262 -287.270444)
			(xy 400.777456 -287.282636) (xy 400.782296 -287.28464) (xy 400.79254 -287.286818) (xy 400.797776 -287.286954)
			(xy 400.847052 -287.286954) (xy 400.857466 -287.285938) (xy 400.86788 -287.283652) (xy 400.873468 -287.282636)
			(xy 400.900646 -287.270444) (xy 400.907758 -287.262824) (xy 400.925225 -287.244686) (xy 400.965006 -287.213821)
			(xy 401.009314 -287.189904) (xy 401.056946 -287.173583) (xy 401.106611 -287.165301) (xy 401.131786 -287.16478)
			(xy 401.468082 -287.16478) (xy 401.493222 -287.165293) (xy 401.54282 -287.173541) (xy 401.590393 -287.189817)
			(xy 401.634649 -287.213679) (xy 401.67439 -287.244481) (xy 401.691856 -287.26257) (xy 401.699222 -287.270444)
			(xy 401.727416 -287.282636) (xy 401.732255 -287.284644) (xy 401.742499 -287.28683) (xy 401.747736 -287.286954)
			(xy 401.797012 -287.286954) (xy 401.807426 -287.285938) (xy 401.81784 -287.283652) (xy 401.823428 -287.282636)
			(xy 401.850606 -287.270444) (xy 401.857718 -287.262824) (xy 401.875186 -287.24469) (xy 401.914969 -287.213833)
			(xy 401.959278 -287.189924) (xy 402.006909 -287.173613) (xy 402.056572 -287.16534) (xy 402.081746 -287.16478)
			(xy 402.418042 -287.16478) (xy 402.443183 -287.16529) (xy 402.492785 -287.173532) (xy 402.540362 -287.189803)
			(xy 402.584623 -287.213662) (xy 402.624369 -287.244462) (xy 402.641816 -287.26257) (xy 402.649182 -287.270444)
			(xy 402.677376 -287.282636) (xy 402.682216 -287.284638) (xy 402.69246 -287.286812) (xy 402.697696 -287.286954)
			(xy 402.746972 -287.286954) (xy 402.757386 -287.285938) (xy 402.7678 -287.283652) (xy 402.773388 -287.282636)
			(xy 402.800566 -287.270444) (xy 402.807678 -287.262824) (xy 402.825145 -287.244687) (xy 402.864927 -287.213825)
			(xy 402.909235 -287.189911) (xy 402.956867 -287.173593) (xy 403.006531 -287.165314) (xy 403.031706 -287.16478)
			(xy 403.368002 -287.16478) (xy 403.393145 -287.165286) (xy 403.44275 -287.173523) (xy 403.490331 -287.18979)
			(xy 403.534597 -287.213645) (xy 403.574348 -287.244442) (xy 403.591776 -287.26257) (xy 403.599142 -287.270444)
			(xy 403.627336 -287.282636) (xy 403.632175 -287.284642) (xy 403.642419 -287.286824) (xy 403.647656 -287.286954)
			(xy 403.696932 -287.286954) (xy 403.707346 -287.285938) (xy 403.71776 -287.283652) (xy 403.723348 -287.282636)
			(xy 403.750526 -287.270444) (xy 403.757638 -287.262824) (xy 403.775104 -287.244685) (xy 403.814885 -287.213818)
			(xy 403.859192 -287.189897) (xy 403.906825 -287.173573) (xy 403.95649 -287.165288) (xy 403.981666 -287.16478)
			(xy 404.317962 -287.16478) (xy 404.343103 -287.165291) (xy 404.392703 -287.173537) (xy 404.440277 -287.18981)
			(xy 404.484536 -287.213671) (xy 404.524279 -287.244471) (xy 404.541736 -287.26257) (xy 404.549102 -287.270444)
			(xy 404.577296 -287.282636) (xy 404.582136 -287.284636) (xy 404.59238 -287.286806) (xy 404.597616 -287.286954)
			(xy 404.646892 -287.286954) (xy 404.657306 -287.285938) (xy 404.66772 -287.283652) (xy 404.673308 -287.282636)
			(xy 404.700486 -287.270444) (xy 404.707598 -287.262824) (xy 404.725065 -287.244689) (xy 404.764848 -287.213829)
			(xy 404.809156 -287.189918) (xy 404.856788 -287.173603) (xy 404.906452 -287.165327) (xy 404.931626 -287.16478)
			(xy 405.268176 -287.16478) (xy 405.293316 -287.165292) (xy 405.342915 -287.17354) (xy 405.390488 -287.189815)
			(xy 405.434745 -287.213677) (xy 405.474486 -287.244478) (xy 405.49195 -287.26257) (xy 405.499316 -287.270444)
			(xy 405.52751 -287.282636) (xy 405.532349 -287.284644) (xy 405.542593 -287.286832) (xy 405.54783 -287.286954)
			(xy 405.597106 -287.286954) (xy 405.60752 -287.285938) (xy 405.617934 -287.283652) (xy 405.623522 -287.282636)
			(xy 405.6507 -287.270444) (xy 405.657812 -287.262824) (xy 405.67528 -287.244689) (xy 405.715063 -287.213832)
			(xy 405.759371 -287.189922) (xy 405.807003 -287.17361) (xy 405.856666 -287.165336) (xy 405.88184 -287.16478)
			(xy 406.156922 -287.16478) (xy 406.182343 -287.165313) (xy 406.232475 -287.173785) (xy 406.280513 -287.190442)
			(xy 406.325128 -287.214823) (xy 406.365091 -287.246257) (xy 406.399296 -287.283873) (xy 406.413462 -287.304988)
			(xy 406.458674 -287.374584) (xy 406.463918 -287.382047) (xy 406.478529 -287.392943) (xy 406.496039 -287.398001)
			(xy 406.505156 -287.397698) (xy 406.50795 -287.397444) (xy 406.509474 -287.39719) (xy 406.519462 -287.395971)
			(xy 406.539544 -287.394699) (xy 406.549606 -287.39465) (xy 406.550114 -287.39465) (xy 406.560175 -287.394708)
			(xy 406.580258 -287.39598) (xy 406.590246 -287.39719) (xy 406.59177 -287.397444) (xy 406.594564 -287.397698)
			(xy 406.603674 -287.397994) (xy 406.62116 -287.392898) (xy 406.635762 -287.382012) (xy 406.641046 -287.374584)
			(xy 406.686258 -287.304988) (xy 406.700413 -287.283858) (xy 406.734591 -287.2462) (xy 406.774545 -287.214737)
			(xy 406.819168 -287.190342) (xy 406.86722 -287.173693) (xy 406.91737 -287.165251) (xy 406.942798 -287.16478)
			(xy 409.068016 -287.16478) (xy 409.093158 -287.165287) (xy 409.142762 -287.173526) (xy 409.190342 -287.189795)
			(xy 409.234606 -287.213651) (xy 409.274355 -287.244449) (xy 409.29179 -287.26257) (xy 409.299156 -287.270444)
			(xy 409.32735 -287.282636) (xy 409.33219 -287.284641) (xy 409.342433 -287.28682) (xy 409.34767 -287.286954)
			(xy 409.396946 -287.286954) (xy 409.40736 -287.285938) (xy 409.417774 -287.283652) (xy 409.423362 -287.282636)
			(xy 409.45054 -287.270444) (xy 409.457652 -287.262824) (xy 409.475118 -287.244686) (xy 409.5149 -287.21382)
			(xy 409.559207 -287.189902) (xy 409.60684 -287.17358) (xy 409.656505 -287.165297) (xy 409.68168 -287.16478)
			(xy 410.017976 -287.16478) (xy 410.043116 -287.165292) (xy 410.092715 -287.17354) (xy 410.140288 -287.189815)
			(xy 410.184545 -287.213677) (xy 410.224286 -287.244478) (xy 410.24175 -287.26257) (xy 410.249116 -287.270444)
			(xy 410.27731 -287.282636) (xy 410.282149 -287.284644) (xy 410.292393 -287.286832) (xy 410.29763 -287.286954)
			(xy 410.346906 -287.286954) (xy 410.35732 -287.285938) (xy 410.367734 -287.283652) (xy 410.373322 -287.282636)
			(xy 410.4005 -287.270444) (xy 410.407612 -287.262824) (xy 410.42508 -287.244689) (xy 410.464863 -287.213832)
			(xy 410.509171 -287.189922) (xy 410.556803 -287.17361) (xy 410.606466 -287.165336) (xy 410.63164 -287.16478)
			(xy 410.96819 -287.16478) (xy 410.99333 -287.165293) (xy 411.042927 -287.173543) (xy 411.090499 -287.18982)
			(xy 411.134754 -287.213683) (xy 411.174494 -287.244485) (xy 411.191964 -287.26257) (xy 411.19933 -287.270444)
			(xy 411.227524 -287.282636) (xy 411.232363 -287.284643) (xy 411.242607 -287.286828) (xy 411.247844 -287.286954)
			(xy 411.29712 -287.286954) (xy 411.307534 -287.285938) (xy 411.317948 -287.283652) (xy 411.323536 -287.282636)
			(xy 411.350714 -287.270444) (xy 411.357826 -287.262824) (xy 411.375294 -287.24469) (xy 411.415078 -287.213834)
			(xy 411.459386 -287.189927) (xy 411.507018 -287.173616) (xy 411.556681 -287.165345) (xy 411.581854 -287.16478)
			(xy 411.91815 -287.16478) (xy 411.943291 -287.16529) (xy 411.992892 -287.173534) (xy 412.040468 -287.189806)
			(xy 412.084728 -287.213666) (xy 412.124473 -287.244465) (xy 412.141924 -287.26257) (xy 412.14929 -287.270444)
			(xy 412.177484 -287.282636) (xy 412.182324 -287.284637) (xy 412.192568 -287.28681) (xy 412.197804 -287.286954)
			(xy 412.24708 -287.286954) (xy 412.257494 -287.285938) (xy 412.267908 -287.283652) (xy 412.273496 -287.282636)
			(xy 412.300674 -287.270444) (xy 412.307786 -287.262824) (xy 412.325253 -287.244688) (xy 412.365036 -287.213827)
			(xy 412.409344 -287.189914) (xy 412.456976 -287.173597) (xy 412.50664 -287.165319) (xy 412.531814 -287.16478)
			(xy 412.86811 -287.16478) (xy 412.893252 -287.165287) (xy 412.942857 -287.173525) (xy 412.990437 -287.189793)
			(xy 413.034702 -287.213649) (xy 413.074452 -287.244446) (xy 413.091884 -287.26257) (xy 413.09925 -287.270444)
			(xy 413.127444 -287.282636) (xy 413.132283 -287.284641) (xy 413.142527 -287.286822) (xy 413.147764 -287.286954)
			(xy 413.19704 -287.286954) (xy 413.207454 -287.285938) (xy 413.217868 -287.283652) (xy 413.223456 -287.282636)
			(xy 413.250634 -287.270444) (xy 413.257746 -287.262824) (xy 413.275212 -287.244685) (xy 413.314993 -287.213819)
			(xy 413.359301 -287.1899) (xy 413.406933 -287.173577) (xy 413.456598 -287.165293) (xy 413.481774 -287.16478)
			(xy 413.81807 -287.16478) (xy 413.84321 -287.165292) (xy 413.89281 -287.173538) (xy 413.940383 -287.189813)
			(xy 413.984641 -287.213674) (xy 414.024383 -287.244475) (xy 414.041844 -287.26257) (xy 414.04921 -287.270444)
			(xy 414.077404 -287.282636) (xy 414.082243 -287.284645) (xy 414.092487 -287.286834) (xy 414.097724 -287.286954)
			(xy 414.147 -287.286954) (xy 414.157414 -287.285938) (xy 414.167828 -287.283652) (xy 414.173416 -287.282636)
			(xy 414.200594 -287.270444) (xy 414.207706 -287.262824) (xy 414.225174 -287.244689) (xy 414.264957 -287.213831)
			(xy 414.309265 -287.18992) (xy 414.356897 -287.173607) (xy 414.40656 -287.165332) (xy 414.431734 -287.16478)
			(xy 414.76803 -287.16478) (xy 414.793172 -287.165289) (xy 414.842775 -287.173529) (xy 414.890353 -287.189799)
			(xy 414.934615 -287.213657) (xy 414.974362 -287.244456) (xy 414.991804 -287.26257) (xy 414.99917 -287.270444)
			(xy 415.027364 -287.282636) (xy 415.032204 -287.284639) (xy 415.042448 -287.286816) (xy 415.047684 -287.286954)
			(xy 415.09696 -287.286954) (xy 415.107374 -287.285938) (xy 415.117788 -287.283652) (xy 415.123376 -287.282636)
			(xy 415.150554 -287.270444) (xy 415.157666 -287.262824) (xy 415.175133 -287.244687) (xy 415.214915 -287.213823)
			(xy 415.259222 -287.189907) (xy 415.306854 -287.173587) (xy 415.356519 -287.165306) (xy 415.381694 -287.16478)
			(xy 415.71799 -287.16478) (xy 415.74313 -287.165293) (xy 415.792727 -287.173543) (xy 415.840299 -287.18982)
			(xy 415.884554 -287.213683) (xy 415.924294 -287.244485) (xy 415.941764 -287.26257) (xy 415.94913 -287.270444)
			(xy 415.977324 -287.282636) (xy 415.982163 -287.284643) (xy 415.992407 -287.286828) (xy 415.997644 -287.286954)
			(xy 416.04692 -287.286954) (xy 416.057334 -287.285938) (xy 416.067748 -287.283652) (xy 416.073336 -287.282636)
			(xy 416.100514 -287.270444) (xy 416.107626 -287.262824) (xy 416.125094 -287.24469) (xy 416.164878 -287.213834)
			(xy 416.209186 -287.189927) (xy 416.256818 -287.173616) (xy 416.306481 -287.165345) (xy 416.331654 -287.16478)
			(xy 416.613594 -287.16478) (xy 416.622297 -287.164431) (xy 416.638706 -287.158621) (xy 416.652231 -287.147664)
			(xy 416.657028 -287.140396) (xy 416.70224 -287.065974) (xy 416.706485 -287.058312) (xy 416.710015 -287.041167)
			(xy 416.707544 -287.023838) (xy 416.703764 -287.015936) (xy 416.70224 -287.012888) (xy 416.700462 -287.009078)
			(xy 416.700208 -287.00857) (xy 416.699954 -287.008062) (xy 416.690312 -286.987215) (xy 416.676714 -286.943346)
			(xy 416.669862 -286.897931) (xy 416.669474 -286.874966) (xy 416.669474 -286.869632) (xy 416.670334 -286.845914)
			(xy 416.678486 -286.79916) (xy 416.693776 -286.754232) (xy 416.715835 -286.712211) (xy 416.74413 -286.67411)
			(xy 416.777982 -286.640847) (xy 416.816573 -286.613223) (xy 416.858974 -286.591904) (xy 416.904163 -286.577404)
			(xy 416.951052 -286.570072) (xy 416.974782 -286.569658) (xy 416.998775 -286.570127) (xy 417.046171 -286.577631)
			(xy 417.09181 -286.592456) (xy 417.134567 -286.614238) (xy 417.173391 -286.642441) (xy 417.207325 -286.676369)
			(xy 417.235534 -286.715188) (xy 417.257324 -286.757942) (xy 417.272157 -286.803578) (xy 417.279669 -286.850973)
			(xy 417.28009 -286.874966) (xy 417.619192 -286.874966) (xy 417.623152 -286.825912) (xy 417.634929 -286.778128)
			(xy 417.65422 -286.732852) (xy 417.680523 -286.691256) (xy 417.713158 -286.654419) (xy 417.751279 -286.623294)
			(xy 417.7939 -286.598687) (xy 417.839916 -286.581235) (xy 417.888135 -286.571391) (xy 417.93731 -286.56941)
			(xy 417.986165 -286.575342) (xy 418.033436 -286.589034) (xy 418.077898 -286.610132) (xy 418.118401 -286.638088)
			(xy 418.153894 -286.67218) (xy 418.183459 -286.711524) (xy 418.20633 -286.755101) (xy 418.221914 -286.801782)
			(xy 418.229809 -286.850359) (xy 418.230304 -286.874966) (xy 418.569152 -286.874966) (xy 418.573112 -286.825912)
			(xy 418.584889 -286.778128) (xy 418.60418 -286.732852) (xy 418.630483 -286.691256) (xy 418.663118 -286.654419)
			(xy 418.701239 -286.623294) (xy 418.74386 -286.598687) (xy 418.789876 -286.581235) (xy 418.838095 -286.571391)
			(xy 418.88727 -286.56941) (xy 418.936125 -286.575342) (xy 418.983396 -286.589034) (xy 419.027858 -286.610132)
			(xy 419.068361 -286.638088) (xy 419.103854 -286.67218) (xy 419.133419 -286.711524) (xy 419.15629 -286.755101)
			(xy 419.171874 -286.801782) (xy 419.179769 -286.850359) (xy 419.180264 -286.874966) (xy 419.179769 -286.899573)
			(xy 419.171874 -286.94815) (xy 419.15629 -286.994831) (xy 419.133419 -287.038408) (xy 419.103854 -287.077752)
			(xy 419.068361 -287.111844) (xy 419.027858 -287.1398) (xy 418.983396 -287.160898) (xy 418.936125 -287.17459)
			(xy 418.88727 -287.180522) (xy 418.838095 -287.178541) (xy 418.789876 -287.168697) (xy 418.74386 -287.151245)
			(xy 418.701239 -287.126638) (xy 418.663118 -287.095513) (xy 418.630483 -287.058676) (xy 418.60418 -287.01708)
			(xy 418.584889 -286.971804) (xy 418.573112 -286.92402) (xy 418.569152 -286.874966) (xy 418.230304 -286.874966)
			(xy 418.229809 -286.899573) (xy 418.221914 -286.94815) (xy 418.20633 -286.994831) (xy 418.183459 -287.038408)
			(xy 418.153894 -287.077752) (xy 418.118401 -287.111844) (xy 418.077898 -287.1398) (xy 418.033436 -287.160898)
			(xy 417.986165 -287.17459) (xy 417.93731 -287.180522) (xy 417.888135 -287.178541) (xy 417.839916 -287.168697)
			(xy 417.7939 -287.151245) (xy 417.751279 -287.126638) (xy 417.713158 -287.095513) (xy 417.680523 -287.058676)
			(xy 417.65422 -287.01708) (xy 417.634929 -286.971804) (xy 417.623152 -286.92402) (xy 417.619192 -286.874966)
			(xy 417.28009 -286.874966) (xy 417.27958 -286.899838) (xy 417.27148 -286.948919) (xy 417.255538 -286.99604)
			(xy 417.244276 -287.018222) (xy 417.242498 -287.021778) (xy 417.229255 -287.044744) (xy 417.19613 -287.086128)
			(xy 417.156367 -287.121183) (xy 417.111157 -287.14886) (xy 417.061852 -287.168329) (xy 417.035996 -287.174178)
			(xy 417.035234 -287.174178) (xy 417.03244 -287.17494) (xy 417.028122 -287.17621) (xy 417.019752 -287.179042)
			(xy 417.005484 -287.189442) (xy 416.995584 -287.204062) (xy 416.99307 -287.212532) (xy 416.99307 -287.212786)
			(xy 416.99133 -287.221252) (xy 416.992982 -287.238445) (xy 417.000236 -287.25412) (xy 417.006024 -287.260538)
			(xy 417.015422 -287.27019) (xy 417.015676 -287.270444) (xy 417.03406 -287.289715) (xy 417.064539 -287.333387)
			(xy 417.072237 -287.349946) (xy 421.894012 -287.349946) (xy 421.897972 -287.300892) (xy 421.909749 -287.253108)
			(xy 421.92904 -287.207832) (xy 421.955343 -287.166236) (xy 421.987978 -287.129399) (xy 422.026099 -287.098274)
			(xy 422.06872 -287.073667) (xy 422.114736 -287.056215) (xy 422.162955 -287.046371) (xy 422.21213 -287.04439)
			(xy 422.260985 -287.050322) (xy 422.308256 -287.064014) (xy 422.352718 -287.085112) (xy 422.393221 -287.113068)
			(xy 422.428714 -287.14716) (xy 422.458279 -287.186504) (xy 422.48115 -287.230081) (xy 422.496734 -287.276762)
			(xy 422.504629 -287.325339) (xy 422.505124 -287.349946) (xy 422.504629 -287.374553) (xy 422.50445 -287.375654)
			(xy 422.823128 -287.375654) (xy 422.823128 -287.324238) (xy 422.831171 -287.273456) (xy 422.847059 -287.224557)
			(xy 422.870402 -287.178745) (xy 422.900623 -287.137149) (xy 422.936979 -287.100793) (xy 422.978575 -287.070572)
			(xy 423.024387 -287.047229) (xy 423.073286 -287.031341) (xy 423.124068 -287.023298) (xy 423.175484 -287.023298)
			(xy 423.226266 -287.031341) (xy 423.275165 -287.047229) (xy 423.320977 -287.070572) (xy 423.362573 -287.100793)
			(xy 423.398929 -287.137149) (xy 423.42915 -287.178745) (xy 423.452493 -287.224557) (xy 423.468381 -287.273456)
			(xy 423.476424 -287.324238) (xy 423.476928 -287.349946) (xy 423.476424 -287.375654) (xy 423.773342 -287.375654)
			(xy 423.773342 -287.324238) (xy 423.781385 -287.273456) (xy 423.797273 -287.224557) (xy 423.820616 -287.178745)
			(xy 423.850837 -287.137149) (xy 423.887193 -287.100793) (xy 423.928789 -287.070572) (xy 423.974601 -287.047229)
			(xy 424.0235 -287.031341) (xy 424.074282 -287.023298) (xy 424.125698 -287.023298) (xy 424.17648 -287.031341)
			(xy 424.225379 -287.047229) (xy 424.271191 -287.070572) (xy 424.312787 -287.100793) (xy 424.349143 -287.137149)
			(xy 424.379364 -287.178745) (xy 424.402707 -287.224557) (xy 424.418595 -287.273456) (xy 424.426638 -287.324238)
			(xy 424.427142 -287.349946) (xy 424.744146 -287.349946) (xy 424.748106 -287.300892) (xy 424.759883 -287.253108)
			(xy 424.779174 -287.207832) (xy 424.805477 -287.166236) (xy 424.838112 -287.129399) (xy 424.876233 -287.098274)
			(xy 424.918854 -287.073667) (xy 424.96487 -287.056215) (xy 425.013089 -287.046371) (xy 425.062264 -287.04439)
			(xy 425.111119 -287.050322) (xy 425.15839 -287.064014) (xy 425.202852 -287.085112) (xy 425.243355 -287.113068)
			(xy 425.278848 -287.14716) (xy 425.308413 -287.186504) (xy 425.331284 -287.230081) (xy 425.346868 -287.276762)
			(xy 425.354763 -287.325339) (xy 425.355258 -287.349946) (xy 425.694106 -287.349946) (xy 425.698066 -287.300892)
			(xy 425.709843 -287.253108) (xy 425.729134 -287.207832) (xy 425.755437 -287.166236) (xy 425.788072 -287.129399)
			(xy 425.826193 -287.098274) (xy 425.868814 -287.073667) (xy 425.91483 -287.056215) (xy 425.963049 -287.046371)
			(xy 426.012224 -287.04439) (xy 426.061079 -287.050322) (xy 426.10835 -287.064014) (xy 426.152812 -287.085112)
			(xy 426.193315 -287.113068) (xy 426.228808 -287.14716) (xy 426.258373 -287.186504) (xy 426.281244 -287.230081)
			(xy 426.296828 -287.276762) (xy 426.304723 -287.325339) (xy 426.305218 -287.349946) (xy 426.644066 -287.349946)
			(xy 426.648026 -287.300892) (xy 426.659803 -287.253108) (xy 426.679094 -287.207832) (xy 426.705397 -287.166236)
			(xy 426.738032 -287.129399) (xy 426.776153 -287.098274) (xy 426.818774 -287.073667) (xy 426.86479 -287.056215)
			(xy 426.913009 -287.046371) (xy 426.962184 -287.04439) (xy 427.011039 -287.050322) (xy 427.05831 -287.064014)
			(xy 427.102772 -287.085112) (xy 427.143275 -287.113068) (xy 427.178768 -287.14716) (xy 427.208333 -287.186504)
			(xy 427.231204 -287.230081) (xy 427.246788 -287.276762) (xy 427.254683 -287.325339) (xy 427.255178 -287.349946)
			(xy 427.593772 -287.349946) (xy 427.597732 -287.300892) (xy 427.609509 -287.253108) (xy 427.6288 -287.207832)
			(xy 427.655103 -287.166236) (xy 427.687738 -287.129399) (xy 427.725859 -287.098274) (xy 427.76848 -287.073667)
			(xy 427.814496 -287.056215) (xy 427.862715 -287.046371) (xy 427.91189 -287.04439) (xy 427.960745 -287.050322)
			(xy 428.008016 -287.064014) (xy 428.052478 -287.085112) (xy 428.092981 -287.113068) (xy 428.128474 -287.14716)
			(xy 428.158039 -287.186504) (xy 428.18091 -287.230081) (xy 428.196494 -287.276762) (xy 428.204389 -287.325339)
			(xy 428.204884 -287.349946) (xy 428.543986 -287.349946) (xy 428.547946 -287.300892) (xy 428.559723 -287.253108)
			(xy 428.579014 -287.207832) (xy 428.605317 -287.166236) (xy 428.637952 -287.129399) (xy 428.676073 -287.098274)
			(xy 428.718694 -287.073667) (xy 428.76471 -287.056215) (xy 428.812929 -287.046371) (xy 428.862104 -287.04439)
			(xy 428.910959 -287.050322) (xy 428.95823 -287.064014) (xy 429.002692 -287.085112) (xy 429.043195 -287.113068)
			(xy 429.078688 -287.14716) (xy 429.108253 -287.186504) (xy 429.131124 -287.230081) (xy 429.146708 -287.276762)
			(xy 429.154603 -287.325339) (xy 429.155098 -287.349946) (xy 429.154603 -287.374553) (xy 429.154424 -287.375654)
			(xy 429.473356 -287.375654) (xy 429.473356 -287.324238) (xy 429.481399 -287.273456) (xy 429.497287 -287.224557)
			(xy 429.52063 -287.178745) (xy 429.550851 -287.137149) (xy 429.587207 -287.100793) (xy 429.628803 -287.070572)
			(xy 429.674615 -287.047229) (xy 429.723514 -287.031341) (xy 429.774296 -287.023298) (xy 429.825712 -287.023298)
			(xy 429.876494 -287.031341) (xy 429.925393 -287.047229) (xy 429.971205 -287.070572) (xy 430.012801 -287.100793)
			(xy 430.049157 -287.137149) (xy 430.079378 -287.178745) (xy 430.102721 -287.224557) (xy 430.118609 -287.273456)
			(xy 430.126652 -287.324238) (xy 430.127156 -287.349946) (xy 430.126652 -287.375654) (xy 430.423316 -287.375654)
			(xy 430.423316 -287.324238) (xy 430.431359 -287.273456) (xy 430.447247 -287.224557) (xy 430.47059 -287.178745)
			(xy 430.500811 -287.137149) (xy 430.537167 -287.100793) (xy 430.578763 -287.070572) (xy 430.624575 -287.047229)
			(xy 430.673474 -287.031341) (xy 430.724256 -287.023298) (xy 430.775672 -287.023298) (xy 430.826454 -287.031341)
			(xy 430.875353 -287.047229) (xy 430.921165 -287.070572) (xy 430.962761 -287.100793) (xy 430.999117 -287.137149)
			(xy 431.029338 -287.178745) (xy 431.052681 -287.224557) (xy 431.068569 -287.273456) (xy 431.076612 -287.324238)
			(xy 431.077116 -287.349946) (xy 431.077111 -287.3502) (xy 431.394374 -287.3502) (xy 431.398334 -287.301146)
			(xy 431.410111 -287.253362) (xy 431.429402 -287.208086) (xy 431.455705 -287.16649) (xy 431.48834 -287.129653)
			(xy 431.526461 -287.098528) (xy 431.569082 -287.073921) (xy 431.615098 -287.056469) (xy 431.663317 -287.046625)
			(xy 431.712492 -287.044644) (xy 431.761347 -287.050576) (xy 431.808618 -287.064268) (xy 431.85308 -287.085366)
			(xy 431.893583 -287.113322) (xy 431.929076 -287.147414) (xy 431.958641 -287.186758) (xy 431.981512 -287.230335)
			(xy 431.997096 -287.277016) (xy 432.004991 -287.325593) (xy 432.005486 -287.3502) (xy 432.004991 -287.374807)
			(xy 431.997096 -287.423384) (xy 431.981512 -287.470065) (xy 431.958641 -287.513642) (xy 431.929076 -287.552986)
			(xy 431.893583 -287.587078) (xy 431.85308 -287.615034) (xy 431.808618 -287.636132) (xy 431.761347 -287.649824)
			(xy 431.712492 -287.655756) (xy 431.663317 -287.653775) (xy 431.615098 -287.643931) (xy 431.569082 -287.626479)
			(xy 431.526461 -287.601872) (xy 431.48834 -287.570747) (xy 431.455705 -287.53391) (xy 431.429402 -287.492314)
			(xy 431.410111 -287.447038) (xy 431.398334 -287.399254) (xy 431.394374 -287.3502) (xy 431.077111 -287.3502)
			(xy 431.076612 -287.375654) (xy 431.068569 -287.426436) (xy 431.052681 -287.475335) (xy 431.029338 -287.521147)
			(xy 430.999117 -287.562743) (xy 430.962761 -287.599099) (xy 430.921165 -287.62932) (xy 430.875353 -287.652663)
			(xy 430.826454 -287.668551) (xy 430.775672 -287.676594) (xy 430.724256 -287.676594) (xy 430.673474 -287.668551)
			(xy 430.624575 -287.652663) (xy 430.578763 -287.62932) (xy 430.537167 -287.599099) (xy 430.500811 -287.562743)
			(xy 430.47059 -287.521147) (xy 430.447247 -287.475335) (xy 430.431359 -287.426436) (xy 430.423316 -287.375654)
			(xy 430.126652 -287.375654) (xy 430.118609 -287.426436) (xy 430.102721 -287.475335) (xy 430.079378 -287.521147)
			(xy 430.049157 -287.562743) (xy 430.012801 -287.599099) (xy 429.971205 -287.62932) (xy 429.925393 -287.652663)
			(xy 429.876494 -287.668551) (xy 429.825712 -287.676594) (xy 429.774296 -287.676594) (xy 429.723514 -287.668551)
			(xy 429.674615 -287.652663) (xy 429.628803 -287.62932) (xy 429.587207 -287.599099) (xy 429.550851 -287.562743)
			(xy 429.52063 -287.521147) (xy 429.497287 -287.475335) (xy 429.481399 -287.426436) (xy 429.473356 -287.375654)
			(xy 429.154424 -287.375654) (xy 429.146708 -287.42313) (xy 429.131124 -287.469811) (xy 429.108253 -287.513388)
			(xy 429.078688 -287.552732) (xy 429.043195 -287.586824) (xy 429.002692 -287.61478) (xy 428.95823 -287.635878)
			(xy 428.910959 -287.64957) (xy 428.862104 -287.655502) (xy 428.812929 -287.653521) (xy 428.76471 -287.643677)
			(xy 428.718694 -287.626225) (xy 428.676073 -287.601618) (xy 428.637952 -287.570493) (xy 428.605317 -287.533656)
			(xy 428.579014 -287.49206) (xy 428.559723 -287.446784) (xy 428.547946 -287.399) (xy 428.543986 -287.349946)
			(xy 428.204884 -287.349946) (xy 428.204389 -287.374553) (xy 428.196494 -287.42313) (xy 428.18091 -287.469811)
			(xy 428.158039 -287.513388) (xy 428.128474 -287.552732) (xy 428.092981 -287.586824) (xy 428.052478 -287.61478)
			(xy 428.008016 -287.635878) (xy 427.960745 -287.64957) (xy 427.91189 -287.655502) (xy 427.862715 -287.653521)
			(xy 427.814496 -287.643677) (xy 427.76848 -287.626225) (xy 427.725859 -287.601618) (xy 427.687738 -287.570493)
			(xy 427.655103 -287.533656) (xy 427.6288 -287.49206) (xy 427.609509 -287.446784) (xy 427.597732 -287.399)
			(xy 427.593772 -287.349946) (xy 427.255178 -287.349946) (xy 427.254683 -287.374553) (xy 427.246788 -287.42313)
			(xy 427.231204 -287.469811) (xy 427.208333 -287.513388) (xy 427.178768 -287.552732) (xy 427.143275 -287.586824)
			(xy 427.102772 -287.61478) (xy 427.05831 -287.635878) (xy 427.011039 -287.64957) (xy 426.962184 -287.655502)
			(xy 426.913009 -287.653521) (xy 426.86479 -287.643677) (xy 426.818774 -287.626225) (xy 426.776153 -287.601618)
			(xy 426.738032 -287.570493) (xy 426.705397 -287.533656) (xy 426.679094 -287.49206) (xy 426.659803 -287.446784)
			(xy 426.648026 -287.399) (xy 426.644066 -287.349946) (xy 426.305218 -287.349946) (xy 426.304723 -287.374553)
			(xy 426.296828 -287.42313) (xy 426.281244 -287.469811) (xy 426.258373 -287.513388) (xy 426.228808 -287.552732)
			(xy 426.193315 -287.586824) (xy 426.152812 -287.61478) (xy 426.10835 -287.635878) (xy 426.061079 -287.64957)
			(xy 426.012224 -287.655502) (xy 425.963049 -287.653521) (xy 425.91483 -287.643677) (xy 425.868814 -287.626225)
			(xy 425.826193 -287.601618) (xy 425.788072 -287.570493) (xy 425.755437 -287.533656) (xy 425.729134 -287.49206)
			(xy 425.709843 -287.446784) (xy 425.698066 -287.399) (xy 425.694106 -287.349946) (xy 425.355258 -287.349946)
			(xy 425.354763 -287.374553) (xy 425.346868 -287.42313) (xy 425.331284 -287.469811) (xy 425.308413 -287.513388)
			(xy 425.278848 -287.552732) (xy 425.243355 -287.586824) (xy 425.202852 -287.61478) (xy 425.15839 -287.635878)
			(xy 425.111119 -287.64957) (xy 425.062264 -287.655502) (xy 425.013089 -287.653521) (xy 424.96487 -287.643677)
			(xy 424.918854 -287.626225) (xy 424.876233 -287.601618) (xy 424.838112 -287.570493) (xy 424.805477 -287.533656)
			(xy 424.779174 -287.49206) (xy 424.759883 -287.446784) (xy 424.748106 -287.399) (xy 424.744146 -287.349946)
			(xy 424.427142 -287.349946) (xy 424.426638 -287.375654) (xy 424.418595 -287.426436) (xy 424.402707 -287.475335)
			(xy 424.379364 -287.521147) (xy 424.349143 -287.562743) (xy 424.312787 -287.599099) (xy 424.271191 -287.62932)
			(xy 424.225379 -287.652663) (xy 424.17648 -287.668551) (xy 424.125698 -287.676594) (xy 424.074282 -287.676594)
			(xy 424.0235 -287.668551) (xy 423.974601 -287.652663) (xy 423.928789 -287.62932) (xy 423.887193 -287.599099)
			(xy 423.850837 -287.562743) (xy 423.820616 -287.521147) (xy 423.797273 -287.475335) (xy 423.781385 -287.426436)
			(xy 423.773342 -287.375654) (xy 423.476424 -287.375654) (xy 423.468381 -287.426436) (xy 423.452493 -287.475335)
			(xy 423.42915 -287.521147) (xy 423.398929 -287.562743) (xy 423.362573 -287.599099) (xy 423.320977 -287.62932)
			(xy 423.275165 -287.652663) (xy 423.226266 -287.668551) (xy 423.175484 -287.676594) (xy 423.124068 -287.676594)
			(xy 423.073286 -287.668551) (xy 423.024387 -287.652663) (xy 422.978575 -287.62932) (xy 422.936979 -287.599099)
			(xy 422.900623 -287.562743) (xy 422.870402 -287.521147) (xy 422.847059 -287.475335) (xy 422.831171 -287.426436)
			(xy 422.823128 -287.375654) (xy 422.50445 -287.375654) (xy 422.496734 -287.42313) (xy 422.48115 -287.469811)
			(xy 422.458279 -287.513388) (xy 422.428714 -287.552732) (xy 422.393221 -287.586824) (xy 422.352718 -287.61478)
			(xy 422.308256 -287.635878) (xy 422.260985 -287.64957) (xy 422.21213 -287.655502) (xy 422.162955 -287.653521)
			(xy 422.114736 -287.643677) (xy 422.06872 -287.626225) (xy 422.026099 -287.601618) (xy 421.987978 -287.570493)
			(xy 421.955343 -287.533656) (xy 421.92904 -287.49206) (xy 421.909749 -287.446784) (xy 421.897972 -287.399)
			(xy 421.894012 -287.349946) (xy 417.072237 -287.349946) (xy 417.086989 -287.381679) (xy 417.100731 -287.433132)
			(xy 417.105348 -287.486187) (xy 417.10356 -287.51276) (xy 417.103126 -287.522375) (xy 417.108583 -287.540816)
			(xy 417.12041 -287.555981) (xy 417.128452 -287.561274) (xy 417.15101 -287.575049) (xy 417.19143 -287.609099)
			(xy 417.225381 -287.649602) (xy 417.251849 -287.695347) (xy 417.270042 -287.744968) (xy 417.279417 -287.79698)
			(xy 417.28009 -287.823402) (xy 417.28009 -287.824418) (xy 417.28009 -287.824926) (xy 418.569152 -287.824926)
			(xy 418.573112 -287.775872) (xy 418.584889 -287.728088) (xy 418.60418 -287.682812) (xy 418.630483 -287.641216)
			(xy 418.663118 -287.604379) (xy 418.701239 -287.573254) (xy 418.74386 -287.548647) (xy 418.789876 -287.531195)
			(xy 418.838095 -287.521351) (xy 418.88727 -287.51937) (xy 418.936125 -287.525302) (xy 418.983396 -287.538994)
			(xy 419.027858 -287.560092) (xy 419.068361 -287.588048) (xy 419.103854 -287.62214) (xy 419.133419 -287.661484)
			(xy 419.15629 -287.705061) (xy 419.171874 -287.751742) (xy 419.179769 -287.800319) (xy 419.180264 -287.824926)
			(xy 420.469072 -287.824926) (xy 420.473032 -287.775872) (xy 420.484809 -287.728088) (xy 420.5041 -287.682812)
			(xy 420.530403 -287.641216) (xy 420.563038 -287.604379) (xy 420.601159 -287.573254) (xy 420.64378 -287.548647)
			(xy 420.689796 -287.531195) (xy 420.738015 -287.521351) (xy 420.78719 -287.51937) (xy 420.836045 -287.525302)
			(xy 420.883316 -287.538994) (xy 420.927778 -287.560092) (xy 420.968281 -287.588048) (xy 421.003774 -287.62214)
			(xy 421.033339 -287.661484) (xy 421.05621 -287.705061) (xy 421.071794 -287.751742) (xy 421.079689 -287.800319)
			(xy 421.080184 -287.824926) (xy 421.079689 -287.849533) (xy 421.071794 -287.89811) (xy 421.05621 -287.944791)
			(xy 421.033339 -287.988368) (xy 421.003774 -288.027712) (xy 420.968281 -288.061804) (xy 420.927778 -288.08976)
			(xy 420.883316 -288.110858) (xy 420.836045 -288.12455) (xy 420.78719 -288.130482) (xy 420.738015 -288.128501)
			(xy 420.689796 -288.118657) (xy 420.64378 -288.101205) (xy 420.601159 -288.076598) (xy 420.563038 -288.045473)
			(xy 420.530403 -288.008636) (xy 420.5041 -287.96704) (xy 420.484809 -287.921764) (xy 420.473032 -287.87398)
			(xy 420.469072 -287.824926) (xy 419.180264 -287.824926) (xy 419.179769 -287.849533) (xy 419.171874 -287.89811)
			(xy 419.15629 -287.944791) (xy 419.133419 -287.988368) (xy 419.103854 -288.027712) (xy 419.068361 -288.061804)
			(xy 419.027858 -288.08976) (xy 418.983396 -288.110858) (xy 418.936125 -288.12455) (xy 418.88727 -288.130482)
			(xy 418.838095 -288.128501) (xy 418.789876 -288.118657) (xy 418.74386 -288.101205) (xy 418.701239 -288.076598)
			(xy 418.663118 -288.045473) (xy 418.630483 -288.008636) (xy 418.60418 -287.96704) (xy 418.584889 -287.921764)
			(xy 418.573112 -287.87398) (xy 418.569152 -287.824926) (xy 417.28009 -287.824926) (xy 417.28009 -287.825942)
			(xy 417.28009 -287.831276) (xy 417.278058 -287.860232) (xy 417.274478 -287.886362) (xy 417.25954 -287.936938)
			(xy 417.24834 -287.960816) (xy 417.24453 -287.968436) (xy 417.242244 -287.9852) (xy 417.244022 -287.993836)
			(xy 417.246058 -288.001668) (xy 417.254214 -288.015634) (xy 417.260024 -288.021268) (xy 417.26993 -288.030412)
			(xy 417.28827 -288.047858) (xy 417.319479 -288.087707) (xy 417.343691 -288.132156) (xy 417.360245 -288.179989)
			(xy 417.368686 -288.229895) (xy 417.369244 -288.255202) (xy 417.369244 -288.299906) (xy 421.894012 -288.299906)
			(xy 421.897972 -288.250852) (xy 421.909749 -288.203068) (xy 421.92904 -288.157792) (xy 421.955343 -288.116196)
			(xy 421.987978 -288.079359) (xy 422.026099 -288.048234) (xy 422.06872 -288.023627) (xy 422.114736 -288.006175)
			(xy 422.162955 -287.996331) (xy 422.21213 -287.99435) (xy 422.260985 -288.000282) (xy 422.308256 -288.013974)
			(xy 422.352718 -288.035072) (xy 422.393221 -288.063028) (xy 422.428714 -288.09712) (xy 422.458279 -288.136464)
			(xy 422.48115 -288.180041) (xy 422.496734 -288.226722) (xy 422.504629 -288.275299) (xy 422.505124 -288.299906)
			(xy 422.844226 -288.299906) (xy 422.848186 -288.250852) (xy 422.859963 -288.203068) (xy 422.879254 -288.157792)
			(xy 422.905557 -288.116196) (xy 422.938192 -288.079359) (xy 422.976313 -288.048234) (xy 423.018934 -288.023627)
			(xy 423.06495 -288.006175) (xy 423.113169 -287.996331) (xy 423.162344 -287.99435) (xy 423.211199 -288.000282)
			(xy 423.25847 -288.013974) (xy 423.302932 -288.035072) (xy 423.343435 -288.063028) (xy 423.378928 -288.09712)
			(xy 423.408493 -288.136464) (xy 423.431364 -288.180041) (xy 423.446948 -288.226722) (xy 423.454843 -288.275299)
			(xy 423.455338 -288.299906) (xy 423.455172 -288.308173) (xy 423.794291 -288.308173) (xy 423.79698 -288.258606)
			(xy 423.807652 -288.210127) (xy 423.826027 -288.164013) (xy 423.85162 -288.121479) (xy 423.883758 -288.083646)
			(xy 423.921592 -288.051511) (xy 423.964127 -288.02592) (xy 424.010242 -288.007548) (xy 424.058722 -287.996878)
			(xy 424.108289 -287.994191) (xy 424.157638 -287.99956) (xy 424.205468 -288.012841) (xy 424.250519 -288.033685)
			(xy 424.291605 -288.061543) (xy 424.327643 -288.095681) (xy 424.357683 -288.1352) (xy 424.380934 -288.179058)
			(xy 424.396783 -288.2261) (xy 424.404813 -288.275086) (xy 424.405298 -288.299906) (xy 424.405122 -288.314089)
			(xy 424.40245 -288.342329) (xy 424.399964 -288.356294) (xy 424.397678 -288.36874) (xy 424.405044 -288.392362)
			(xy 424.482514 -288.469832) (xy 424.506136 -288.477198) (xy 424.518582 -288.474912) (xy 424.532547 -288.472428)
			(xy 424.560787 -288.469761) (xy 424.57497 -288.469578) (xy 424.584841 -288.469654) (xy 424.604542 -288.470923)
			(xy 424.61434 -288.472118) (xy 424.626278 -288.473642) (xy 424.648884 -288.465768) (xy 424.722544 -288.389314)
			(xy 424.729402 -288.366454) (xy 424.727624 -288.354516) (xy 424.725467 -288.340967) (xy 424.72318 -288.313625)
			(xy 424.723052 -288.299906) (xy 424.723573 -288.274215) (xy 424.731611 -288.223465) (xy 424.747489 -288.174597)
			(xy 424.770816 -288.128815) (xy 424.801018 -288.087246) (xy 424.837351 -288.050913) (xy 424.878921 -288.020712)
			(xy 424.924703 -287.997386) (xy 424.973571 -287.981509) (xy 425.024321 -287.973473) (xy 425.075704 -287.973475)
			(xy 425.126453 -287.981515) (xy 425.17532 -287.997396) (xy 425.221101 -288.020725) (xy 425.262668 -288.05093)
			(xy 425.298999 -288.087265) (xy 425.329198 -288.128837) (xy 425.352521 -288.174621) (xy 425.368395 -288.223489)
			(xy 425.376429 -288.27424) (xy 425.376424 -288.325614) (xy 425.673262 -288.325614) (xy 425.673262 -288.274198)
			(xy 425.681305 -288.223416) (xy 425.697193 -288.174517) (xy 425.720536 -288.128705) (xy 425.750757 -288.087109)
			(xy 425.787113 -288.050753) (xy 425.828709 -288.020532) (xy 425.874521 -287.997189) (xy 425.92342 -287.981301)
			(xy 425.974202 -287.973258) (xy 426.025618 -287.973258) (xy 426.0764 -287.981301) (xy 426.125299 -287.997189)
			(xy 426.171111 -288.020532) (xy 426.212707 -288.050753) (xy 426.249063 -288.087109) (xy 426.279284 -288.128705)
			(xy 426.302627 -288.174517) (xy 426.318515 -288.223416) (xy 426.326558 -288.274198) (xy 426.327062 -288.299906)
			(xy 426.3269 -288.308159) (xy 426.644211 -288.308159) (xy 426.646901 -288.258596) (xy 426.657575 -288.210121)
			(xy 426.67595 -288.164011) (xy 426.701543 -288.121482) (xy 426.733679 -288.083653) (xy 426.771511 -288.051522)
			(xy 426.814044 -288.025934) (xy 426.860155 -288.007564) (xy 426.908631 -287.996896) (xy 426.958195 -287.994212)
			(xy 427.00754 -287.99958) (xy 427.055366 -288.012861) (xy 427.100413 -288.033705) (xy 427.141496 -288.061561)
			(xy 427.17753 -288.095697) (xy 427.207567 -288.135213) (xy 427.230816 -288.179068) (xy 427.246664 -288.226106)
			(xy 427.254693 -288.275088) (xy 427.255178 -288.299906) (xy 427.255003 -288.314089) (xy 427.25233 -288.342329)
			(xy 427.249844 -288.356294) (xy 427.247558 -288.36874) (xy 427.254924 -288.392362) (xy 427.332394 -288.469832)
			(xy 427.356016 -288.477198) (xy 427.368462 -288.474912) (xy 427.382427 -288.472431) (xy 427.410667 -288.469762)
			(xy 427.42485 -288.469578) (xy 427.434721 -288.469655) (xy 427.454421 -288.470924) (xy 427.46422 -288.472118)
			(xy 427.476158 -288.473642) (xy 427.498764 -288.465768) (xy 427.572424 -288.389314) (xy 427.579282 -288.366454)
			(xy 427.577504 -288.354516) (xy 427.575348 -288.340967) (xy 427.57306 -288.313625) (xy 427.572932 -288.299906)
			(xy 427.573436 -288.274218) (xy 427.581473 -288.223475) (xy 427.597349 -288.174614) (xy 427.620673 -288.128838)
			(xy 427.65087 -288.087274) (xy 427.687198 -288.050946) (xy 427.728762 -288.020749) (xy 427.774538 -287.997425)
			(xy 427.823399 -287.981549) (xy 427.874142 -287.973512) (xy 427.925518 -287.973512) (xy 427.976261 -287.981549)
			(xy 428.025122 -287.997425) (xy 428.070898 -288.020749) (xy 428.112462 -288.050946) (xy 428.14879 -288.087274)
			(xy 428.178987 -288.128838) (xy 428.202311 -288.174614) (xy 428.218187 -288.223475) (xy 428.226224 -288.274218)
			(xy 428.226728 -288.299906) (xy 428.226581 -288.313624) (xy 428.224293 -288.340965) (xy 428.222156 -288.354516)
			(xy 428.220378 -288.366454) (xy 428.227236 -288.389314) (xy 428.300896 -288.465768) (xy 428.323502 -288.473642)
			(xy 428.33544 -288.472118) (xy 428.345239 -288.470931) (xy 428.364939 -288.469659) (xy 428.37481 -288.469578)
			(xy 428.384681 -288.46965) (xy 428.404382 -288.470922) (xy 428.41418 -288.472118) (xy 428.426118 -288.473642)
			(xy 428.448724 -288.465768) (xy 428.522384 -288.389314) (xy 428.529242 -288.366454) (xy 428.527464 -288.354516)
			(xy 428.525308 -288.340967) (xy 428.52302 -288.313625) (xy 428.522892 -288.299906) (xy 428.523396 -288.274218)
			(xy 428.531433 -288.223475) (xy 428.547309 -288.174614) (xy 428.570633 -288.128838) (xy 428.60083 -288.087274)
			(xy 428.637158 -288.050946) (xy 428.678722 -288.020749) (xy 428.724498 -287.997425) (xy 428.773359 -287.981549)
			(xy 428.824102 -287.973512) (xy 428.875478 -287.973512) (xy 428.926221 -287.981549) (xy 428.975082 -287.997425)
			(xy 429.020858 -288.020749) (xy 429.062422 -288.050946) (xy 429.09875 -288.087274) (xy 429.128947 -288.128838)
			(xy 429.152271 -288.174614) (xy 429.168147 -288.223475) (xy 429.176184 -288.274218) (xy 429.176688 -288.299906)
			(xy 429.176541 -288.313624) (xy 429.174253 -288.340965) (xy 429.172116 -288.354516) (xy 429.170084 -288.366454)
			(xy 429.177196 -288.389314) (xy 429.250856 -288.465768) (xy 429.273462 -288.473642) (xy 429.285654 -288.472118)
			(xy 429.295453 -288.47093) (xy 429.315153 -288.469658) (xy 429.325024 -288.469578) (xy 429.339207 -288.469752)
			(xy 429.367447 -288.472426) (xy 429.381412 -288.474912) (xy 429.393858 -288.477198) (xy 429.41748 -288.469832)
			(xy 429.49495 -288.392362) (xy 429.502316 -288.36874) (xy 429.50003 -288.356294) (xy 429.497557 -288.342328)
			(xy 429.494883 -288.314088) (xy 429.494696 -288.299906) (xy 429.495218 -288.274651) (xy 429.503531 -288.224829)
			(xy 429.519932 -288.177055) (xy 429.543973 -288.132632) (xy 429.574997 -288.092772) (xy 429.612159 -288.058562)
			(xy 429.654445 -288.030936) (xy 429.700701 -288.010646) (xy 429.749666 -287.998246) (xy 429.800004 -287.994075)
			(xy 429.850342 -287.998246) (xy 429.899307 -288.010646) (xy 429.945563 -288.030936) (xy 429.987849 -288.058562)
			(xy 430.025011 -288.092772) (xy 430.056035 -288.132632) (xy 430.080076 -288.177055) (xy 430.096477 -288.224829)
			(xy 430.10479 -288.274651) (xy 430.105312 -288.299906) (xy 430.105136 -288.314089) (xy 430.102464 -288.342329)
			(xy 430.099978 -288.356294) (xy 430.097692 -288.36874) (xy 430.105058 -288.392362) (xy 430.182528 -288.469832)
			(xy 430.20615 -288.477198) (xy 430.218596 -288.474912) (xy 430.232563 -288.47244) (xy 430.260802 -288.469765)
			(xy 430.274984 -288.469578) (xy 430.289167 -288.469757) (xy 430.317407 -288.472428) (xy 430.331372 -288.474912)
			(xy 430.343818 -288.477198) (xy 430.36744 -288.469832) (xy 430.44491 -288.392362) (xy 430.452276 -288.36874)
			(xy 430.44999 -288.356294) (xy 430.447516 -288.342328) (xy 430.444843 -288.314088) (xy 430.444656 -288.299906)
			(xy 430.445178 -288.274651) (xy 430.453491 -288.224829) (xy 430.469892 -288.177055) (xy 430.493933 -288.132632)
			(xy 430.524957 -288.092772) (xy 430.562119 -288.058562) (xy 430.604405 -288.030936) (xy 430.650661 -288.010646)
			(xy 430.699626 -287.998246) (xy 430.749964 -287.994075) (xy 430.800302 -287.998246) (xy 430.849267 -288.010646)
			(xy 430.895523 -288.030936) (xy 430.937809 -288.058562) (xy 430.974971 -288.092772) (xy 431.005995 -288.132632)
			(xy 431.030036 -288.177055) (xy 431.046437 -288.224829) (xy 431.050379 -288.248455) (xy 435.895921 -288.248455)
			(xy 435.895921 -288.193945) (xy 435.903679 -288.139988) (xy 435.919036 -288.087685) (xy 435.941681 -288.038101)
			(xy 435.971152 -287.992243) (xy 436.00685 -287.951047) (xy 436.048046 -287.91535) (xy 436.093904 -287.885879)
			(xy 436.143489 -287.863235) (xy 436.195792 -287.847878) (xy 436.249749 -287.840121) (xy 436.277004 -287.839658)
			(xy 436.30312 -287.84011) (xy 436.354864 -287.847248) (xy 436.40515 -287.861376) (xy 436.453039 -287.88223)
			(xy 436.497637 -287.909421) (xy 436.53811 -287.94244) (xy 436.573701 -287.98067) (xy 436.603746 -288.023397)
			(xy 436.616094 -288.046414) (xy 436.622861 -288.058628) (xy 436.641864 -288.079074) (xy 436.66569 -288.093616)
			(xy 436.692561 -288.101168) (xy 436.720475 -288.101168) (xy 436.747346 -288.093616) (xy 436.771172 -288.079074)
			(xy 436.790175 -288.058628) (xy 436.796942 -288.046414) (xy 436.809302 -288.023401) (xy 436.839331 -287.980658)
			(xy 436.874913 -287.942414) (xy 436.915382 -287.909384) (xy 436.95998 -287.882187) (xy 437.007873 -287.861333)
			(xy 437.058165 -287.84721) (xy 437.109914 -287.840085) (xy 437.136032 -287.839658) (xy 437.163279 -287.840214)
			(xy 437.217219 -287.847974) (xy 437.269505 -287.86333) (xy 437.319074 -287.885971) (xy 437.364916 -287.915436)
			(xy 437.406099 -287.951124) (xy 437.441783 -287.99231) (xy 437.471244 -288.038155) (xy 437.493881 -288.087725)
			(xy 437.509233 -288.140013) (xy 437.516988 -288.193953) (xy 437.516988 -288.224712) (xy 437.77102 -288.224712)
			(xy 437.771025 -288.170216) (xy 437.778785 -288.116276) (xy 437.794143 -288.063989) (xy 437.816786 -288.01442)
			(xy 437.846253 -287.968578) (xy 437.881944 -287.927396) (xy 437.923132 -287.891712) (xy 437.96898 -287.862254)
			(xy 438.018553 -287.83962) (xy 438.070842 -287.824271) (xy 438.124784 -287.81652) (xy 438.152032 -287.816036)
			(xy 438.156096 -287.816036) (xy 438.16778 -287.81629) (xy 438.188608 -287.806384) (xy 438.253632 -287.726882)
			(xy 438.258966 -287.70453) (xy 438.25668 -287.6931) (xy 438.252444 -287.672339) (xy 438.247863 -287.630213)
			(xy 438.247536 -287.609026) (xy 438.248047 -287.580378) (xy 438.256201 -287.523664) (xy 438.272344 -287.468689)
			(xy 438.296145 -287.41657) (xy 438.327122 -287.368369) (xy 438.364643 -287.325067) (xy 438.407945 -287.287546)
			(xy 438.456146 -287.256569) (xy 438.508265 -287.232768) (xy 438.56324 -287.216625) (xy 438.619954 -287.208471)
			(xy 438.67725 -287.208471) (xy 438.733964 -287.216625) (xy 438.788939 -287.232768) (xy 438.841058 -287.256569)
			(xy 438.889259 -287.287546) (xy 438.932561 -287.325067) (xy 438.970082 -287.368369) (xy 439.001059 -287.41657)
			(xy 439.02486 -287.468689) (xy 439.041003 -287.523664) (xy 439.049157 -287.580378) (xy 439.049668 -287.609026)
			(xy 439.049118 -287.638801) (xy 439.040315 -287.697698) (xy 439.022891 -287.754642) (xy 439.010552 -287.781746)
			(xy 439.006714 -287.790645) (xy 439.005406 -287.809967) (xy 439.011371 -287.828392) (xy 439.023756 -287.843281)
			(xy 439.040786 -287.852503) (xy 439.060023 -287.854736) (xy 439.06948 -287.852612) (xy 439.081335 -287.84952)
			(xy 439.105358 -287.844693) (xy 439.117486 -287.84296) (xy 439.128408 -287.841436) (xy 439.146696 -287.83026)
			(xy 439.20156 -287.749234) (xy 439.20537 -287.728152) (xy 439.202576 -287.717484) (xy 439.196882 -287.693438)
			(xy 439.190765 -287.644402) (xy 439.190384 -287.619694) (xy 439.190895 -287.591046) (xy 439.199049 -287.534332)
			(xy 439.215192 -287.479357) (xy 439.238993 -287.427238) (xy 439.26997 -287.379037) (xy 439.307491 -287.335735)
			(xy 439.350793 -287.298214) (xy 439.398994 -287.267237) (xy 439.451113 -287.243436) (xy 439.506088 -287.227293)
			(xy 439.562802 -287.219139) (xy 439.620098 -287.219139) (xy 439.676812 -287.227293) (xy 439.731787 -287.243436)
			(xy 439.759422 -287.256056) (xy 448.436643 -287.256056) (xy 448.436643 -287.201544) (xy 448.444401 -287.147587)
			(xy 448.45976 -287.095284) (xy 448.482407 -287.045699) (xy 448.51188 -286.999843) (xy 448.54758 -286.958647)
			(xy 448.588779 -286.922953) (xy 448.63464 -286.893485) (xy 448.684227 -286.870844) (xy 448.736532 -286.855492)
			(xy 448.79049 -286.84774) (xy 448.817746 -286.84728) (xy 448.846486 -286.847781) (xy 448.903314 -286.85641)
			(xy 448.958205 -286.873466) (xy 449.009916 -286.898562) (xy 449.057278 -286.931131) (xy 449.078604 -286.950404)
			(xy 449.085716 -286.957008) (xy 449.103242 -286.96412) (xy 449.19265 -286.96412) (xy 449.210176 -286.957008)
			(xy 449.217288 -286.950404) (xy 449.238615 -286.931134) (xy 449.285978 -286.898569) (xy 449.337689 -286.873478)
			(xy 449.39258 -286.856428) (xy 449.449407 -286.847806) (xy 449.506885 -286.847806) (xy 449.563712 -286.856428)
			(xy 449.618603 -286.873478) (xy 449.670314 -286.898569) (xy 449.717677 -286.931134) (xy 449.739004 -286.950404)
			(xy 449.746116 -286.957008) (xy 449.763642 -286.96412) (xy 449.85305 -286.96412) (xy 449.870576 -286.957008)
			(xy 449.877688 -286.950404) (xy 449.899006 -286.931123) (xy 449.946369 -286.898556) (xy 449.998083 -286.873464)
			(xy 450.052976 -286.856416) (xy 450.109806 -286.847798) (xy 450.138546 -286.84728) (xy 450.168668 -286.847876)
			(xy 450.228164 -286.85735) (xy 450.285432 -286.876054) (xy 450.33905 -286.903525) (xy 450.387685 -286.939079)
			(xy 450.40931 -286.960056) (xy 450.416422 -286.967422) (xy 450.435218 -286.975042) (xy 450.527674 -286.975042)
			(xy 450.54647 -286.967422) (xy 450.553582 -286.960056) (xy 450.575201 -286.939069) (xy 450.62383 -286.903499)
			(xy 450.677448 -286.876019) (xy 450.73472 -286.857313) (xy 450.794221 -286.847846) (xy 450.824346 -286.84728)
			(xy 450.851594 -286.847793) (xy 450.905535 -286.855555) (xy 450.957823 -286.870914) (xy 451.007393 -286.893557)
			(xy 451.053236 -286.923023) (xy 451.094419 -286.958714) (xy 451.130104 -286.999901) (xy 451.159565 -287.045748)
			(xy 451.182203 -287.09532) (xy 451.197555 -287.14761) (xy 451.20531 -287.201552) (xy 451.20531 -287.256048)
			(xy 451.205309 -287.256055) (xy 453.090443 -287.256055) (xy 453.090443 -287.201545) (xy 453.098201 -287.147589)
			(xy 453.113559 -287.095287) (xy 453.136205 -287.045703) (xy 453.165677 -286.999847) (xy 453.201376 -286.958652)
			(xy 453.242574 -286.922957) (xy 453.288433 -286.893489) (xy 453.338019 -286.870847) (xy 453.390322 -286.855494)
			(xy 453.444279 -286.847741) (xy 453.471534 -286.84728) (xy 453.500273 -286.847788) (xy 453.557101 -286.856416)
			(xy 453.611992 -286.873469) (xy 453.663703 -286.898564) (xy 453.711065 -286.931132) (xy 453.732392 -286.950404)
			(xy 453.739504 -286.957008) (xy 453.75703 -286.96412) (xy 453.846438 -286.96412) (xy 453.863964 -286.957008)
			(xy 453.871076 -286.950404) (xy 453.892403 -286.931134) (xy 453.939766 -286.898569) (xy 453.991477 -286.873478)
			(xy 454.046368 -286.856428) (xy 454.103195 -286.847806) (xy 454.160673 -286.847806) (xy 454.2175 -286.856428)
			(xy 454.272391 -286.873478) (xy 454.324102 -286.898569) (xy 454.371465 -286.931134) (xy 454.392792 -286.950404)
			(xy 454.399904 -286.957008) (xy 454.41743 -286.96412) (xy 454.506838 -286.96412) (xy 454.524364 -286.957008)
			(xy 454.531476 -286.950404) (xy 454.552799 -286.931128) (xy 454.600161 -286.89856) (xy 454.651873 -286.873468)
			(xy 454.706766 -286.856419) (xy 454.763595 -286.847799) (xy 454.792334 -286.84728) (xy 454.822459 -286.84782)
			(xy 454.881957 -286.857308) (xy 454.939226 -286.876025) (xy 454.992842 -286.903508) (xy 455.041475 -286.939074)
			(xy 455.063098 -286.960056) (xy 455.07021 -286.967422) (xy 455.089006 -286.975042) (xy 455.181462 -286.975042)
			(xy 455.200258 -286.967422) (xy 455.20737 -286.960056) (xy 455.228994 -286.939075) (xy 455.277622 -286.903504)
			(xy 455.331239 -286.876023) (xy 455.388509 -286.857316) (xy 455.44801 -286.847847) (xy 455.478134 -286.84728)
			(xy 455.505383 -286.847793) (xy 455.559325 -286.855553) (xy 455.611614 -286.87091) (xy 455.661185 -286.893553)
			(xy 455.70703 -286.923019) (xy 455.748215 -286.958709) (xy 455.783901 -286.999897) (xy 455.813364 -287.045745)
			(xy 455.836002 -287.095318) (xy 455.851354 -287.147608) (xy 455.85911 -287.201551) (xy 455.85911 -287.256049)
			(xy 455.851354 -287.309992) (xy 455.836002 -287.362282) (xy 455.813364 -287.411855) (xy 455.783901 -287.457703)
			(xy 455.748215 -287.498891) (xy 455.70703 -287.534581) (xy 455.661185 -287.564047) (xy 455.611614 -287.58669)
			(xy 455.559325 -287.602047) (xy 455.505383 -287.609807) (xy 455.478134 -287.610296) (xy 455.448011 -287.609719)
			(xy 455.388514 -287.600242) (xy 455.331245 -287.581533) (xy 455.277628 -287.554058) (xy 455.228994 -287.518499)
			(xy 455.20737 -287.49752) (xy 455.200258 -287.490154) (xy 455.181462 -287.482534) (xy 455.089006 -287.482534)
			(xy 455.07021 -287.490154) (xy 455.063098 -287.49752) (xy 455.041501 -287.51853) (xy 454.992864 -287.554093)
			(xy 454.939241 -287.581568) (xy 454.881964 -287.600269) (xy 454.82246 -287.609732) (xy 454.792334 -287.610296)
			(xy 454.763594 -287.609813) (xy 454.706764 -287.601181) (xy 454.651873 -287.584121) (xy 454.600162 -287.559021)
			(xy 454.552801 -287.526447) (xy 454.531476 -287.507172) (xy 454.524364 -287.500568) (xy 454.506838 -287.493456)
			(xy 454.41743 -287.493456) (xy 454.399904 -287.500568) (xy 454.392792 -287.507172) (xy 454.371465 -287.526442)
			(xy 454.324102 -287.559007) (xy 454.272391 -287.584098) (xy 454.2175 -287.601148) (xy 454.160673 -287.60977)
			(xy 454.103195 -287.60977) (xy 454.046368 -287.601148) (xy 453.991477 -287.584098) (xy 453.939766 -287.559007)
			(xy 453.892403 -287.526442) (xy 453.871076 -287.507172) (xy 453.863964 -287.500568) (xy 453.846438 -287.493456)
			(xy 453.75703 -287.493456) (xy 453.739504 -287.500568) (xy 453.732392 -287.507172) (xy 453.711052 -287.526428)
			(xy 453.663694 -287.558996) (xy 453.611985 -287.584091) (xy 453.557097 -287.601145) (xy 453.500272 -287.609773)
			(xy 453.471534 -287.610296) (xy 453.444279 -287.609859) (xy 453.390322 -287.602106) (xy 453.338019 -287.586753)
			(xy 453.288433 -287.564111) (xy 453.242574 -287.534643) (xy 453.201376 -287.498948) (xy 453.165677 -287.457753)
			(xy 453.136205 -287.411897) (xy 453.113559 -287.362313) (xy 453.098201 -287.310011) (xy 453.090443 -287.256055)
			(xy 451.205309 -287.256055) (xy 451.197555 -287.30999) (xy 451.182203 -287.36228) (xy 451.159565 -287.411852)
			(xy 451.130104 -287.457699) (xy 451.094419 -287.498886) (xy 451.053236 -287.534577) (xy 451.007393 -287.564043)
			(xy 450.957823 -287.586686) (xy 450.905535 -287.602045) (xy 450.851594 -287.609807) (xy 450.824346 -287.610296)
			(xy 450.794223 -287.609712) (xy 450.734727 -287.600236) (xy 450.677458 -287.581529) (xy 450.623841 -287.554056)
			(xy 450.575207 -287.518499) (xy 450.553582 -287.49752) (xy 450.54647 -287.490154) (xy 450.527674 -287.482534)
			(xy 450.435218 -287.482534) (xy 450.416422 -287.490154) (xy 450.40931 -287.49752) (xy 450.387707 -287.518524)
			(xy 450.339072 -287.554088) (xy 450.28545 -287.581564) (xy 450.228175 -287.600266) (xy 450.168672 -287.609731)
			(xy 450.138546 -287.610296) (xy 450.109806 -287.609806) (xy 450.052977 -287.601175) (xy 449.998086 -287.584118)
			(xy 449.946375 -287.559018) (xy 449.899014 -287.526446) (xy 449.877688 -287.507172) (xy 449.870576 -287.500568)
			(xy 449.85305 -287.493456) (xy 449.763642 -287.493456) (xy 449.746116 -287.500568) (xy 449.739004 -287.507172)
			(xy 449.717677 -287.526442) (xy 449.670314 -287.559007) (xy 449.618603 -287.584098) (xy 449.563712 -287.601148)
			(xy 449.506885 -287.60977) (xy 449.449407 -287.60977) (xy 449.39258 -287.601148) (xy 449.337689 -287.584098)
			(xy 449.285978 -287.559007) (xy 449.238615 -287.526442) (xy 449.217288 -287.507172) (xy 449.210176 -287.500568)
			(xy 449.19265 -287.493456) (xy 449.103242 -287.493456) (xy 449.085716 -287.500568) (xy 449.078604 -287.507172)
			(xy 449.057301 -287.52647) (xy 449.009932 -287.559032) (xy 448.958214 -287.584119) (xy 448.903318 -287.601163)
			(xy 448.846487 -287.609779) (xy 448.817746 -287.610296) (xy 448.79049 -287.60986) (xy 448.736532 -287.602108)
			(xy 448.684227 -287.586756) (xy 448.63464 -287.564115) (xy 448.588779 -287.534647) (xy 448.54758 -287.498953)
			(xy 448.51188 -287.457757) (xy 448.482407 -287.411901) (xy 448.45976 -287.362316) (xy 448.444401 -287.310013)
			(xy 448.436643 -287.256056) (xy 439.759422 -287.256056) (xy 439.783906 -287.267237) (xy 439.832107 -287.298214)
			(xy 439.875409 -287.335735) (xy 439.91293 -287.379037) (xy 439.943907 -287.427238) (xy 439.967708 -287.479357)
			(xy 439.983851 -287.534332) (xy 439.992005 -287.591046) (xy 439.992516 -287.619694) (xy 439.992118 -287.644664)
			(xy 439.985882 -287.694213) (xy 439.98007 -287.7185) (xy 439.976768 -287.730946) (xy 439.983118 -287.755838)
			(xy 440.057286 -287.837626) (xy 440.081162 -287.846008) (xy 440.093862 -287.843976) (xy 440.108251 -287.841919)
			(xy 440.137239 -287.839761) (xy 440.151774 -287.839658) (xy 440.17903 -287.840127) (xy 440.232987 -287.847881)
			(xy 440.285291 -287.863236) (xy 440.334877 -287.885878) (xy 440.356312 -287.899652) (xy 457.970079 -287.899652)
			(xy 457.970079 -287.845148) (xy 457.977837 -287.791198) (xy 457.993193 -287.738901) (xy 458.015836 -287.689322)
			(xy 458.045305 -287.64347) (xy 458.080999 -287.60228) (xy 458.122193 -287.566588) (xy 458.168047 -287.537123)
			(xy 458.217627 -287.514483) (xy 458.269925 -287.499131) (xy 458.323876 -287.491377) (xy 458.351128 -287.490916)
			(xy 458.381252 -287.491479) (xy 458.440748 -287.500963) (xy 458.498016 -287.519677) (xy 458.551632 -287.547154)
			(xy 458.600267 -287.582713) (xy 458.621892 -287.603692) (xy 458.629004 -287.611058) (xy 458.6478 -287.618678)
			(xy 458.740256 -287.618678) (xy 458.759052 -287.611058) (xy 458.766164 -287.603692) (xy 458.78778 -287.582702)
			(xy 458.836412 -287.547136) (xy 458.89003 -287.519658) (xy 458.947302 -287.500952) (xy 459.006803 -287.491483)
			(xy 459.036928 -287.490916) (xy 459.06418 -287.491356) (xy 459.118128 -287.499116) (xy 459.170422 -287.514475)
			(xy 459.219999 -287.537119) (xy 459.265849 -287.566588) (xy 459.307038 -287.602281) (xy 459.342729 -287.643473)
			(xy 459.372195 -287.689325) (xy 459.394835 -287.738904) (xy 459.41019 -287.7912) (xy 459.417946 -287.845148)
			(xy 459.417946 -287.872424) (xy 460.847692 -287.872424) (xy 460.851763 -287.816802) (xy 460.863889 -287.762365)
			(xy 460.883812 -287.710274) (xy 460.911108 -287.661639) (xy 460.945194 -287.617496) (xy 460.985343 -287.578787)
			(xy 461.030701 -287.546336) (xy 461.080301 -287.520835) (xy 461.133085 -287.502828) (xy 461.187928 -287.492698)
			(xy 461.243662 -287.490661) (xy 461.299099 -287.496761) (xy 461.353056 -287.510867) (xy 461.404385 -287.532679)
			(xy 461.451991 -287.561733) (xy 461.494859 -287.597408) (xy 461.532076 -287.638945) (xy 461.562849 -287.685458)
			(xy 461.586521 -287.735955) (xy 461.602589 -287.789362) (xy 461.610709 -287.844538) (xy 461.611218 -287.872424)
			(xy 461.610709 -287.90031) (xy 461.602589 -287.955486) (xy 461.586521 -288.008893) (xy 461.562849 -288.05939)
			(xy 461.532076 -288.105903) (xy 461.494859 -288.14744) (xy 461.451991 -288.183115) (xy 461.404385 -288.212169)
			(xy 461.353056 -288.233981) (xy 461.299099 -288.248087) (xy 461.243662 -288.254187) (xy 461.187928 -288.25215)
			(xy 461.133085 -288.24202) (xy 461.080301 -288.224013) (xy 461.030701 -288.198512) (xy 460.985343 -288.166061)
			(xy 460.945194 -288.127352) (xy 460.911108 -288.083209) (xy 460.883812 -288.034574) (xy 460.863889 -287.982483)
			(xy 460.851763 -287.928046) (xy 460.847692 -287.872424) (xy 459.417946 -287.872424) (xy 459.417946 -287.899652)
			(xy 459.41019 -287.9536) (xy 459.394835 -288.005896) (xy 459.372195 -288.055475) (xy 459.342729 -288.101327)
			(xy 459.307038 -288.142519) (xy 459.265849 -288.178212) (xy 459.219999 -288.207681) (xy 459.170422 -288.230325)
			(xy 459.118128 -288.245684) (xy 459.06418 -288.253444) (xy 459.036928 -288.253932) (xy 459.006805 -288.253349)
			(xy 458.947309 -288.243872) (xy 458.890041 -288.225164) (xy 458.836424 -288.197691) (xy 458.787789 -288.162134)
			(xy 458.766164 -288.141156) (xy 458.759052 -288.13379) (xy 458.740256 -288.12617) (xy 458.6478 -288.12617)
			(xy 458.629004 -288.13379) (xy 458.621892 -288.141156) (xy 458.600287 -288.162158) (xy 458.551653 -288.197725)
			(xy 458.498032 -288.225202) (xy 458.440757 -288.243905) (xy 458.381254 -288.253368) (xy 458.351128 -288.253932)
			(xy 458.323876 -288.253423) (xy 458.269925 -288.245669) (xy 458.217627 -288.230317) (xy 458.168047 -288.207677)
			(xy 458.122193 -288.178212) (xy 458.080999 -288.14252) (xy 458.045305 -288.10133) (xy 458.015836 -288.055478)
			(xy 457.993193 -288.005899) (xy 457.977837 -287.953602) (xy 457.970079 -287.899652) (xy 440.356312 -287.899652)
			(xy 440.380736 -287.915347) (xy 440.421935 -287.951042) (xy 440.457634 -287.992238) (xy 440.487106 -288.038095)
			(xy 440.509753 -288.087679) (xy 440.525112 -288.139982) (xy 440.532871 -288.193938) (xy 440.532871 -288.24845)
			(xy 440.525114 -288.302406) (xy 440.509757 -288.35471) (xy 440.487112 -288.404295) (xy 440.457641 -288.450152)
			(xy 440.421943 -288.491349) (xy 440.380746 -288.527046) (xy 440.334888 -288.556516) (xy 440.285302 -288.57916)
			(xy 440.232998 -288.594516) (xy 440.179042 -288.602272) (xy 440.12453 -288.60227) (xy 440.070574 -288.59451)
			(xy 440.018272 -288.57915) (xy 439.968688 -288.556503) (xy 439.922831 -288.527029) (xy 439.881637 -288.491329)
			(xy 439.845942 -288.45013) (xy 439.816474 -288.40427) (xy 439.793833 -288.354683) (xy 439.77848 -288.302379)
			(xy 439.770727 -288.248422) (xy 439.770266 -288.221166) (xy 439.770548 -288.199904) (xy 439.775262 -288.157642)
			(xy 439.779664 -288.136838) (xy 439.782458 -288.124138) (xy 439.775854 -288.099754) (xy 439.6994 -288.019998)
			(xy 439.67527 -288.01187) (xy 439.66257 -288.014156) (xy 439.630566 -288.018728) (xy 439.61939 -288.019744)
			(xy 439.600848 -288.030412) (xy 439.54319 -288.109406) (xy 439.538618 -288.130234) (xy 439.541158 -288.141156)
			(xy 439.545111 -288.160921) (xy 439.549307 -288.201011) (xy 439.54954 -288.221166) (xy 439.549054 -288.248417)
			(xy 439.541298 -288.302365) (xy 439.525943 -288.35466) (xy 439.503301 -288.404237) (xy 439.473835 -288.450087)
			(xy 439.438144 -288.491278) (xy 439.396953 -288.526969) (xy 439.351103 -288.556435) (xy 439.301526 -288.579077)
			(xy 439.249231 -288.594432) (xy 439.195283 -288.602188) (xy 439.140781 -288.602188) (xy 439.086833 -288.594432)
			(xy 439.034538 -288.579077) (xy 438.984961 -288.556435) (xy 438.939111 -288.526969) (xy 438.89792 -288.491278)
			(xy 438.862229 -288.450087) (xy 438.832763 -288.404237) (xy 438.810121 -288.35466) (xy 438.794766 -288.302365)
			(xy 438.78701 -288.248417) (xy 438.786524 -288.221166) (xy 438.786836 -288.198857) (xy 438.79206 -288.154546)
			(xy 438.796938 -288.132774) (xy 438.799732 -288.120582) (xy 438.79389 -288.09696) (xy 438.723278 -288.01568)
			(xy 438.700418 -288.00679) (xy 438.687972 -288.00806) (xy 438.648602 -288.010092) (xy 438.631584 -288.009584)
			(xy 438.6199 -288.009076) (xy 438.598818 -288.01822) (xy 438.531254 -288.09569) (xy 438.525412 -288.117788)
			(xy 438.527444 -288.129218) (xy 438.530325 -288.146152) (xy 438.533376 -288.180368) (xy 438.53354 -288.197544)
			(xy 438.532975 -288.224792) (xy 438.525213 -288.278732) (xy 438.509854 -288.331019) (xy 438.48721 -288.380587)
			(xy 438.457742 -288.426429) (xy 438.42205 -288.46761) (xy 438.380861 -288.503293) (xy 438.335013 -288.53275)
			(xy 438.28544 -288.555383) (xy 438.23315 -288.570731) (xy 438.179208 -288.578481) (xy 438.124712 -288.578475)
			(xy 438.070772 -288.570714) (xy 438.018485 -288.555355) (xy 437.968916 -288.532712) (xy 437.923075 -288.503245)
			(xy 437.881893 -288.467553) (xy 437.84621 -288.426365) (xy 437.816752 -288.380517) (xy 437.794118 -288.330944)
			(xy 437.77877 -288.278654) (xy 437.77102 -288.224712) (xy 437.516988 -288.224712) (xy 437.516988 -288.248447)
			(xy 437.509233 -288.302387) (xy 437.493881 -288.354675) (xy 437.471244 -288.404245) (xy 437.441783 -288.45009)
			(xy 437.406099 -288.491276) (xy 437.364916 -288.526964) (xy 437.319074 -288.556429) (xy 437.269505 -288.57907)
			(xy 437.217219 -288.594426) (xy 437.163279 -288.602186) (xy 437.136032 -288.602674) (xy 437.109915 -288.602229)
			(xy 437.05817 -288.595095) (xy 437.007882 -288.580969) (xy 436.959991 -288.560115) (xy 436.915392 -288.532923)
			(xy 436.87492 -288.499901) (xy 436.83933 -288.461668) (xy 436.809288 -288.418937) (xy 436.796942 -288.395918)
			(xy 436.790175 -288.383704) (xy 436.771172 -288.363258) (xy 436.747346 -288.348716) (xy 436.720475 -288.341164)
			(xy 436.692561 -288.341164) (xy 436.66569 -288.348716) (xy 436.641864 -288.363258) (xy 436.622861 -288.383704)
			(xy 436.616094 -288.395918) (xy 436.603721 -288.418923) (xy 436.573692 -288.461665) (xy 436.538111 -288.499908)
			(xy 436.497644 -288.532937) (xy 436.453048 -288.560134) (xy 436.405157 -288.58099) (xy 436.354868 -288.595115)
			(xy 436.303122 -288.602245) (xy 436.277004 -288.602674) (xy 436.249749 -288.602279) (xy 436.195792 -288.594522)
			(xy 436.143489 -288.579165) (xy 436.093904 -288.556521) (xy 436.048046 -288.52705) (xy 436.00685 -288.491353)
			(xy 435.971152 -288.450157) (xy 435.941681 -288.404299) (xy 435.919036 -288.354715) (xy 435.903679 -288.302412)
			(xy 435.895921 -288.248455) (xy 431.050379 -288.248455) (xy 431.05475 -288.274651) (xy 431.055272 -288.299906)
			(xy 431.055097 -288.314089) (xy 431.052424 -288.342329) (xy 431.049938 -288.356294) (xy 431.047652 -288.36874)
			(xy 431.055018 -288.392362) (xy 431.132488 -288.469832) (xy 431.15611 -288.477198) (xy 431.168556 -288.474912)
			(xy 431.182521 -288.472432) (xy 431.210761 -288.469763) (xy 431.224944 -288.469578) (xy 431.247727 -288.469994)
			(xy 431.292784 -288.476778) (xy 431.336336 -288.490174) (xy 431.377417 -288.509885) (xy 431.415118 -288.535475)
			(xy 431.448604 -288.566377) (xy 431.463196 -288.583878) (xy 431.470763 -288.592476) (xy 431.491379 -288.6024)
			(xy 431.50282 -288.602928) (xy 431.582068 -288.602928) (xy 431.593481 -288.602268) (xy 431.614058 -288.592386)
			(xy 431.621692 -288.583878) (xy 431.636289 -288.566379) (xy 431.669762 -288.535462) (xy 431.707459 -288.509862)
			(xy 431.748542 -288.49015) (xy 431.792098 -288.476762) (xy 431.83716 -288.469997) (xy 431.859944 -288.469578)
			(xy 431.885196 -288.470131) (xy 431.93501 -288.47845) (xy 431.982775 -288.494854) (xy 432.027189 -288.518895)
			(xy 432.067041 -288.549919) (xy 432.101244 -288.587078) (xy 432.128865 -288.629359) (xy 432.14915 -288.67561)
			(xy 432.161547 -288.724569) (xy 432.165717 -288.7749) (xy 432.161547 -288.825231) (xy 432.14915 -288.87419)
			(xy 432.128865 -288.920441) (xy 432.101244 -288.962722) (xy 432.067041 -288.999881) (xy 432.027189 -289.030905)
			(xy 431.982775 -289.054946) (xy 431.93501 -289.07135) (xy 431.885196 -289.079669) (xy 431.859944 -289.080194)
			(xy 431.837161 -289.079797) (xy 431.792102 -289.07301) (xy 431.748549 -289.059612) (xy 431.707468 -289.039897)
			(xy 431.669767 -289.014303) (xy 431.636283 -288.983397) (xy 431.621692 -288.965894) (xy 431.614135 -288.957286)
			(xy 431.593511 -288.947368) (xy 431.582068 -288.946844) (xy 431.50282 -288.946844) (xy 431.491408 -288.947506)
			(xy 431.470831 -288.957388) (xy 431.463196 -288.965894) (xy 431.448623 -288.983414) (xy 431.415143 -289.014326)
			(xy 431.37744 -289.039921) (xy 431.336353 -289.059629) (xy 431.292793 -289.073013) (xy 431.247729 -289.079776)
			(xy 431.224944 -289.080194) (xy 431.200951 -289.079721) (xy 431.153556 -289.072221) (xy 431.107918 -289.057397)
			(xy 431.065161 -289.035616) (xy 431.026338 -289.007414) (xy 430.992406 -288.973485) (xy 430.9642 -288.934665)
			(xy 430.942414 -288.89191) (xy 430.927586 -288.846273) (xy 430.920081 -288.798879) (xy 430.919636 -288.774886)
			(xy 430.91981 -288.760703) (xy 430.922484 -288.732463) (xy 430.92497 -288.718498) (xy 430.927256 -288.706052)
			(xy 430.91989 -288.68243) (xy 430.84242 -288.60496) (xy 430.818798 -288.597594) (xy 430.806352 -288.59988)
			(xy 430.792387 -288.602359) (xy 430.764147 -288.605029) (xy 430.749964 -288.605214) (xy 430.735781 -288.605042)
			(xy 430.707541 -288.602367) (xy 430.693576 -288.59988) (xy 430.68113 -288.597594) (xy 430.657508 -288.60496)
			(xy 430.580038 -288.68243) (xy 430.572672 -288.706052) (xy 430.574958 -288.718498) (xy 430.57743 -288.732465)
			(xy 430.580105 -288.760704) (xy 430.580292 -288.774886) (xy 430.57977 -288.800141) (xy 430.571457 -288.849963)
			(xy 430.555056 -288.897737) (xy 430.531015 -288.94216) (xy 430.499991 -288.98202) (xy 430.462829 -289.01623)
			(xy 430.420543 -289.043856) (xy 430.374287 -289.064146) (xy 430.325322 -289.076546) (xy 430.274984 -289.080717)
			(xy 430.224646 -289.076546) (xy 430.175681 -289.064146) (xy 430.129425 -289.043856) (xy 430.087139 -289.01623)
			(xy 430.049977 -288.98202) (xy 430.018953 -288.94216) (xy 429.994912 -288.897737) (xy 429.978511 -288.849963)
			(xy 429.970198 -288.800141) (xy 429.969676 -288.774886) (xy 429.969851 -288.760703) (xy 429.972524 -288.732463)
			(xy 429.97501 -288.718498) (xy 429.977296 -288.706052) (xy 429.96993 -288.68243) (xy 429.89246 -288.60496)
			(xy 429.868838 -288.597594) (xy 429.856392 -288.59988) (xy 429.842426 -288.602353) (xy 429.814186 -288.605027)
			(xy 429.800004 -288.605214) (xy 429.785821 -288.605037) (xy 429.757581 -288.602365) (xy 429.743616 -288.59988)
			(xy 429.73117 -288.597594) (xy 429.707548 -288.60496) (xy 429.630078 -288.68243) (xy 429.622712 -288.706052)
			(xy 429.624998 -288.718498) (xy 429.62747 -288.732465) (xy 429.630145 -288.760704) (xy 429.630332 -288.774886)
			(xy 429.62981 -288.800141) (xy 429.621497 -288.849963) (xy 429.605096 -288.897737) (xy 429.581055 -288.94216)
			(xy 429.550031 -288.98202) (xy 429.512869 -289.01623) (xy 429.470583 -289.043856) (xy 429.424327 -289.064146)
			(xy 429.375362 -289.076546) (xy 429.325024 -289.080717) (xy 429.274686 -289.076546) (xy 429.225721 -289.064146)
			(xy 429.179465 -289.043856) (xy 429.137179 -289.01623) (xy 429.100017 -288.98202) (xy 429.068993 -288.94216)
			(xy 429.044952 -288.897737) (xy 429.028551 -288.849963) (xy 429.020238 -288.800141) (xy 429.019716 -288.774886)
			(xy 429.019787 -288.765015) (xy 429.021059 -288.745314) (xy 429.022256 -288.735516) (xy 429.02378 -288.723578)
			(xy 429.015906 -288.700718) (xy 428.939452 -288.627312) (xy 428.916592 -288.6202) (xy 428.9044 -288.622232)
			(xy 428.890851 -288.62439) (xy 428.863509 -288.626677) (xy 428.84979 -288.626804) (xy 428.836072 -288.626658)
			(xy 428.808731 -288.62437) (xy 428.79518 -288.622232) (xy 428.783242 -288.620454) (xy 428.760382 -288.627312)
			(xy 428.683928 -288.700972) (xy 428.676054 -288.723578) (xy 428.677578 -288.735516) (xy 428.678763 -288.745316)
			(xy 428.680036 -288.765015) (xy 428.680118 -288.774886) (xy 428.679596 -288.800141) (xy 428.671283 -288.849963)
			(xy 428.654882 -288.897737) (xy 428.630841 -288.94216) (xy 428.599817 -288.98202) (xy 428.562655 -289.01623)
			(xy 428.520369 -289.043856) (xy 428.474113 -289.064146) (xy 428.425148 -289.076546) (xy 428.37481 -289.080717)
			(xy 428.324472 -289.076546) (xy 428.275507 -289.064146) (xy 428.229251 -289.043856) (xy 428.186965 -289.01623)
			(xy 428.149803 -288.98202) (xy 428.118779 -288.94216) (xy 428.094738 -288.897737) (xy 428.078337 -288.849963)
			(xy 428.070024 -288.800141) (xy 428.069502 -288.774886) (xy 428.069573 -288.765015) (xy 428.070845 -288.745314)
			(xy 428.072042 -288.735516) (xy 428.073566 -288.723578) (xy 428.065692 -288.700972) (xy 427.989238 -288.627312)
			(xy 427.966378 -288.620454) (xy 427.95444 -288.622232) (xy 427.940891 -288.624385) (xy 427.913549 -288.626675)
			(xy 427.89983 -288.626804) (xy 427.886112 -288.626653) (xy 427.858771 -288.624368) (xy 427.84522 -288.622232)
			(xy 427.833282 -288.620454) (xy 427.810422 -288.627312) (xy 427.733968 -288.700972) (xy 427.726094 -288.723578)
			(xy 427.727618 -288.735516) (xy 427.728803 -288.745316) (xy 427.730076 -288.765015) (xy 427.730158 -288.774886)
			(xy 427.729636 -288.800141) (xy 427.721323 -288.849963) (xy 427.704922 -288.897737) (xy 427.680881 -288.94216)
			(xy 427.649857 -288.98202) (xy 427.612695 -289.01623) (xy 427.570409 -289.043856) (xy 427.524153 -289.064146)
			(xy 427.475188 -289.076546) (xy 427.42485 -289.080717) (xy 427.374512 -289.076546) (xy 427.325547 -289.064146)
			(xy 427.279291 -289.043856) (xy 427.237005 -289.01623) (xy 427.199843 -288.98202) (xy 427.168819 -288.94216)
			(xy 427.144778 -288.897737) (xy 427.128377 -288.849963) (xy 427.120064 -288.800141) (xy 427.119542 -288.774886)
			(xy 427.119716 -288.760703) (xy 427.12239 -288.732463) (xy 427.124876 -288.718498) (xy 427.127162 -288.706052)
			(xy 427.119796 -288.68243) (xy 427.042326 -288.60496) (xy 427.018704 -288.597594) (xy 427.006258 -288.59988)
			(xy 426.992292 -288.602358) (xy 426.964053 -288.605029) (xy 426.94987 -288.605214) (xy 426.925052 -288.60469)
			(xy 426.876071 -288.596655) (xy 426.829034 -288.580802) (xy 426.785183 -288.557548) (xy 426.74567 -288.527506)
			(xy 426.711539 -288.491468) (xy 426.683687 -288.450382) (xy 426.662849 -288.405332) (xy 426.649573 -288.357504)
			(xy 426.644211 -288.308159) (xy 426.3269 -288.308159) (xy 426.326558 -288.325614) (xy 426.318515 -288.376396)
			(xy 426.302627 -288.425295) (xy 426.279284 -288.471107) (xy 426.249063 -288.512703) (xy 426.212707 -288.549059)
			(xy 426.171111 -288.57928) (xy 426.125299 -288.602623) (xy 426.0764 -288.618511) (xy 426.025618 -288.626554)
			(xy 425.974202 -288.626554) (xy 425.92342 -288.618511) (xy 425.874521 -288.602623) (xy 425.828709 -288.57928)
			(xy 425.787113 -288.549059) (xy 425.750757 -288.512703) (xy 425.720536 -288.471107) (xy 425.697193 -288.425295)
			(xy 425.681305 -288.376396) (xy 425.673262 -288.325614) (xy 425.376424 -288.325614) (xy 425.376424 -288.325623)
			(xy 425.36838 -288.376372) (xy 425.352497 -288.425237) (xy 425.329165 -288.471017) (xy 425.298958 -288.512583)
			(xy 425.262621 -288.548911) (xy 425.221047 -288.579107) (xy 425.175262 -288.602428) (xy 425.126392 -288.618299)
			(xy 425.075641 -288.62633) (xy 425.04995 -288.626804) (xy 425.036232 -288.626663) (xy 425.008891 -288.624371)
			(xy 424.99534 -288.622232) (xy 424.983402 -288.620454) (xy 424.960542 -288.627312) (xy 424.884088 -288.700972)
			(xy 424.876214 -288.723578) (xy 424.877738 -288.735516) (xy 424.878923 -288.745316) (xy 424.880196 -288.765015)
			(xy 424.880278 -288.774886) (xy 424.879756 -288.800141) (xy 424.871443 -288.849963) (xy 424.855042 -288.897737)
			(xy 424.831001 -288.94216) (xy 424.799977 -288.98202) (xy 424.762815 -289.01623) (xy 424.720529 -289.043856)
			(xy 424.674273 -289.064146) (xy 424.625308 -289.076546) (xy 424.57497 -289.080717) (xy 424.524632 -289.076546)
			(xy 424.475667 -289.064146) (xy 424.429411 -289.043856) (xy 424.387125 -289.01623) (xy 424.349963 -288.98202)
			(xy 424.318939 -288.94216) (xy 424.294898 -288.897737) (xy 424.278497 -288.849963) (xy 424.270184 -288.800141)
			(xy 424.269662 -288.774886) (xy 424.269837 -288.760703) (xy 424.27251 -288.732463) (xy 424.274996 -288.718498)
			(xy 424.277282 -288.706052) (xy 424.269916 -288.68243) (xy 424.192446 -288.60496) (xy 424.168824 -288.597594)
			(xy 424.156378 -288.59988) (xy 424.142412 -288.602355) (xy 424.114172 -288.605028) (xy 424.09999 -288.605214)
			(xy 424.07517 -288.604711) (xy 424.026184 -288.596679) (xy 423.979143 -288.580827) (xy 423.935287 -288.557574)
			(xy 423.895769 -288.527532) (xy 423.861633 -288.491493) (xy 423.833777 -288.450405) (xy 423.812935 -288.405353)
			(xy 423.799657 -288.357522) (xy 423.794291 -288.308173) (xy 423.455172 -288.308173) (xy 423.454843 -288.324513)
			(xy 423.446948 -288.37309) (xy 423.431364 -288.419771) (xy 423.408493 -288.463348) (xy 423.378928 -288.502692)
			(xy 423.343435 -288.536784) (xy 423.302932 -288.56474) (xy 423.25847 -288.585838) (xy 423.211199 -288.59953)
			(xy 423.162344 -288.605462) (xy 423.113169 -288.603481) (xy 423.06495 -288.593637) (xy 423.018934 -288.576185)
			(xy 422.976313 -288.551578) (xy 422.938192 -288.520453) (xy 422.905557 -288.483616) (xy 422.879254 -288.44202)
			(xy 422.859963 -288.396744) (xy 422.848186 -288.34896) (xy 422.844226 -288.299906) (xy 422.505124 -288.299906)
			(xy 422.504629 -288.324513) (xy 422.496734 -288.37309) (xy 422.48115 -288.419771) (xy 422.458279 -288.463348)
			(xy 422.428714 -288.502692) (xy 422.393221 -288.536784) (xy 422.352718 -288.56474) (xy 422.308256 -288.585838)
			(xy 422.260985 -288.59953) (xy 422.21213 -288.605462) (xy 422.162955 -288.603481) (xy 422.114736 -288.593637)
			(xy 422.06872 -288.576185) (xy 422.026099 -288.551578) (xy 421.987978 -288.520453) (xy 421.955343 -288.483616)
			(xy 421.92904 -288.44202) (xy 421.909749 -288.396744) (xy 421.897972 -288.34896) (xy 421.894012 -288.299906)
			(xy 417.369244 -288.299906) (xy 417.369244 -288.34461) (xy 417.368704 -288.369918) (xy 417.360268 -288.419828)
			(xy 417.343712 -288.467661) (xy 417.319489 -288.512107) (xy 417.288265 -288.551946) (xy 417.26993 -288.5694)
			(xy 417.265358 -288.573464) (xy 417.257735 -288.581029) (xy 417.248927 -288.600588) (xy 417.24834 -288.61131)
			(xy 417.24834 -288.638742) (xy 417.252912 -288.648902) (xy 417.261499 -288.668783) (xy 417.273609 -288.710361)
			(xy 417.279726 -288.753233) (xy 417.28009 -288.774886) (xy 417.619192 -288.774886) (xy 417.623152 -288.725832)
			(xy 417.634929 -288.678048) (xy 417.65422 -288.632772) (xy 417.680523 -288.591176) (xy 417.713158 -288.554339)
			(xy 417.751279 -288.523214) (xy 417.7939 -288.498607) (xy 417.839916 -288.481155) (xy 417.888135 -288.471311)
			(xy 417.93731 -288.46933) (xy 417.986165 -288.475262) (xy 418.033436 -288.488954) (xy 418.077898 -288.510052)
			(xy 418.118401 -288.538008) (xy 418.153894 -288.5721) (xy 418.183459 -288.611444) (xy 418.20633 -288.655021)
			(xy 418.221914 -288.701702) (xy 418.229809 -288.750279) (xy 418.230304 -288.774886) (xy 418.569152 -288.774886)
			(xy 418.573112 -288.725832) (xy 418.584889 -288.678048) (xy 418.60418 -288.632772) (xy 418.630483 -288.591176)
			(xy 418.663118 -288.554339) (xy 418.701239 -288.523214) (xy 418.74386 -288.498607) (xy 418.789876 -288.481155)
			(xy 418.838095 -288.471311) (xy 418.88727 -288.46933) (xy 418.936125 -288.475262) (xy 418.983396 -288.488954)
			(xy 419.027858 -288.510052) (xy 419.068361 -288.538008) (xy 419.103854 -288.5721) (xy 419.133419 -288.611444)
			(xy 419.15629 -288.655021) (xy 419.171874 -288.701702) (xy 419.179769 -288.750279) (xy 419.180264 -288.774886)
			(xy 419.519112 -288.774886) (xy 419.523072 -288.725832) (xy 419.534849 -288.678048) (xy 419.55414 -288.632772)
			(xy 419.580443 -288.591176) (xy 419.613078 -288.554339) (xy 419.651199 -288.523214) (xy 419.69382 -288.498607)
			(xy 419.739836 -288.481155) (xy 419.788055 -288.471311) (xy 419.83723 -288.46933) (xy 419.886085 -288.475262)
			(xy 419.933356 -288.488954) (xy 419.977818 -288.510052) (xy 420.018321 -288.538008) (xy 420.053814 -288.5721)
			(xy 420.083379 -288.611444) (xy 420.10625 -288.655021) (xy 420.121834 -288.701702) (xy 420.129729 -288.750279)
			(xy 420.130224 -288.774886) (xy 420.469072 -288.774886) (xy 420.473032 -288.725832) (xy 420.484809 -288.678048)
			(xy 420.5041 -288.632772) (xy 420.530403 -288.591176) (xy 420.563038 -288.554339) (xy 420.601159 -288.523214)
			(xy 420.64378 -288.498607) (xy 420.689796 -288.481155) (xy 420.738015 -288.471311) (xy 420.78719 -288.46933)
			(xy 420.836045 -288.475262) (xy 420.883316 -288.488954) (xy 420.927778 -288.510052) (xy 420.968281 -288.538008)
			(xy 421.003774 -288.5721) (xy 421.033339 -288.611444) (xy 421.05621 -288.655021) (xy 421.071794 -288.701702)
			(xy 421.079689 -288.750279) (xy 421.080184 -288.774886) (xy 421.079689 -288.799493) (xy 421.071794 -288.84807)
			(xy 421.05621 -288.894751) (xy 421.033339 -288.938328) (xy 421.003774 -288.977672) (xy 420.968281 -289.011764)
			(xy 420.927778 -289.03972) (xy 420.883316 -289.060818) (xy 420.836045 -289.07451) (xy 420.78719 -289.080442)
			(xy 420.738015 -289.078461) (xy 420.689796 -289.068617) (xy 420.64378 -289.051165) (xy 420.601159 -289.026558)
			(xy 420.563038 -288.995433) (xy 420.530403 -288.958596) (xy 420.5041 -288.917) (xy 420.484809 -288.871724)
			(xy 420.473032 -288.82394) (xy 420.469072 -288.774886) (xy 420.130224 -288.774886) (xy 420.129729 -288.799493)
			(xy 420.121834 -288.84807) (xy 420.10625 -288.894751) (xy 420.083379 -288.938328) (xy 420.053814 -288.977672)
			(xy 420.018321 -289.011764) (xy 419.977818 -289.03972) (xy 419.933356 -289.060818) (xy 419.886085 -289.07451)
			(xy 419.83723 -289.080442) (xy 419.788055 -289.078461) (xy 419.739836 -289.068617) (xy 419.69382 -289.051165)
			(xy 419.651199 -289.026558) (xy 419.613078 -288.995433) (xy 419.580443 -288.958596) (xy 419.55414 -288.917)
			(xy 419.534849 -288.871724) (xy 419.523072 -288.82394) (xy 419.519112 -288.774886) (xy 419.180264 -288.774886)
			(xy 419.179769 -288.799493) (xy 419.171874 -288.84807) (xy 419.15629 -288.894751) (xy 419.133419 -288.938328)
			(xy 419.103854 -288.977672) (xy 419.068361 -289.011764) (xy 419.027858 -289.03972) (xy 418.983396 -289.060818)
			(xy 418.936125 -289.07451) (xy 418.88727 -289.080442) (xy 418.838095 -289.078461) (xy 418.789876 -289.068617)
			(xy 418.74386 -289.051165) (xy 418.701239 -289.026558) (xy 418.663118 -288.995433) (xy 418.630483 -288.958596)
			(xy 418.60418 -288.917) (xy 418.584889 -288.871724) (xy 418.573112 -288.82394) (xy 418.569152 -288.774886)
			(xy 418.230304 -288.774886) (xy 418.229809 -288.799493) (xy 418.221914 -288.84807) (xy 418.20633 -288.894751)
			(xy 418.183459 -288.938328) (xy 418.153894 -288.977672) (xy 418.118401 -289.011764) (xy 418.077898 -289.03972)
			(xy 418.033436 -289.060818) (xy 417.986165 -289.07451) (xy 417.93731 -289.080442) (xy 417.888135 -289.078461)
			(xy 417.839916 -289.068617) (xy 417.7939 -289.051165) (xy 417.751279 -289.026558) (xy 417.713158 -288.995433)
			(xy 417.680523 -288.958596) (xy 417.65422 -288.917) (xy 417.634929 -288.871724) (xy 417.623152 -288.82394)
			(xy 417.619192 -288.774886) (xy 417.28009 -288.774886) (xy 417.28009 -288.785046) (xy 417.279836 -288.786824)
			(xy 417.279836 -288.788348) (xy 417.279085 -288.802903) (xy 417.275138 -288.831782) (xy 417.271962 -288.846006)
			(xy 417.271708 -288.84626) (xy 417.267457 -288.862861) (xy 417.255746 -288.895068) (xy 417.24834 -288.910522)
			(xy 417.245038 -288.916872) (xy 417.242498 -288.930842) (xy 417.24326 -288.938716) (xy 417.244607 -288.948025)
			(xy 417.25322 -288.964733) (xy 417.260024 -288.971228) (xy 417.26993 -288.980372) (xy 417.288273 -288.997817)
			(xy 417.319487 -289.037665) (xy 417.343705 -289.082114) (xy 417.360264 -289.129946) (xy 417.368713 -289.179854)
			(xy 417.369244 -289.205162) (xy 417.369244 -289.29457) (xy 417.368593 -289.320712) (xy 417.359466 -289.3722)
			(xy 417.341712 -289.421383) (xy 417.31585 -289.46683) (xy 417.299648 -289.487356) (xy 417.29406 -289.494214)
			(xy 417.287456 -289.512248) (xy 417.287964 -289.522154) (xy 417.287964 -289.522916) (xy 417.29152 -289.591496)
			(xy 417.292401 -289.600797) (xy 417.299958 -289.617866) (xy 417.306252 -289.62477) (xy 417.447476 -289.765994)
			(xy 417.454637 -289.77254) (xy 417.472457 -289.780172) (xy 417.491836 -289.780654) (xy 417.50107 -289.777678)
			(xy 417.58743 -289.74542) (xy 417.596355 -289.741665) (xy 417.610718 -289.728703) (xy 417.619256 -289.711342)
			(xy 417.62045 -289.701732) (xy 417.622862 -289.676456) (xy 417.635008 -289.62716) (xy 417.655143 -289.580552)
			(xy 417.682712 -289.537919) (xy 417.716956 -289.500435) (xy 417.75693 -289.469135) (xy 417.801533 -289.444881)
			(xy 417.849534 -289.428341) (xy 417.89961 -289.419972) (xy 417.924996 -289.419538) (xy 417.948988 -289.419984)
			(xy 417.996381 -289.42749) (xy 418.042017 -289.442319) (xy 418.08477 -289.464105) (xy 418.123588 -289.492311)
			(xy 418.157516 -289.526244) (xy 418.185717 -289.565066) (xy 418.207497 -289.607822) (xy 418.222319 -289.65346)
			(xy 418.229819 -289.700854) (xy 418.230304 -289.724846) (xy 418.569152 -289.724846) (xy 418.573112 -289.675792)
			(xy 418.584889 -289.628008) (xy 418.60418 -289.582732) (xy 418.630483 -289.541136) (xy 418.663118 -289.504299)
			(xy 418.701239 -289.473174) (xy 418.74386 -289.448567) (xy 418.789876 -289.431115) (xy 418.838095 -289.421271)
			(xy 418.88727 -289.41929) (xy 418.936125 -289.425222) (xy 418.983396 -289.438914) (xy 419.027858 -289.460012)
			(xy 419.068361 -289.487968) (xy 419.103854 -289.52206) (xy 419.133419 -289.561404) (xy 419.15629 -289.604981)
			(xy 419.171874 -289.651662) (xy 419.179769 -289.700239) (xy 419.180264 -289.724846) (xy 419.519112 -289.724846)
			(xy 419.523072 -289.675792) (xy 419.534849 -289.628008) (xy 419.55414 -289.582732) (xy 419.580443 -289.541136)
			(xy 419.613078 -289.504299) (xy 419.651199 -289.473174) (xy 419.69382 -289.448567) (xy 419.739836 -289.431115)
			(xy 419.788055 -289.421271) (xy 419.83723 -289.41929) (xy 419.886085 -289.425222) (xy 419.933356 -289.438914)
			(xy 419.977818 -289.460012) (xy 420.018321 -289.487968) (xy 420.053814 -289.52206) (xy 420.083379 -289.561404)
			(xy 420.10625 -289.604981) (xy 420.121834 -289.651662) (xy 420.129729 -289.700239) (xy 420.130224 -289.724846)
			(xy 420.469072 -289.724846) (xy 420.473032 -289.675792) (xy 420.484809 -289.628008) (xy 420.5041 -289.582732)
			(xy 420.530403 -289.541136) (xy 420.563038 -289.504299) (xy 420.601159 -289.473174) (xy 420.64378 -289.448567)
			(xy 420.689796 -289.431115) (xy 420.738015 -289.421271) (xy 420.78719 -289.41929) (xy 420.836045 -289.425222)
			(xy 420.883316 -289.438914) (xy 420.927778 -289.460012) (xy 420.968281 -289.487968) (xy 421.003774 -289.52206)
			(xy 421.033339 -289.561404) (xy 421.05621 -289.604981) (xy 421.071794 -289.651662) (xy 421.079689 -289.700239)
			(xy 421.080016 -289.71648) (xy 421.419128 -289.71648) (xy 421.424501 -289.667138) (xy 421.437785 -289.619315)
			(xy 421.458632 -289.574271) (xy 421.486491 -289.533193) (xy 421.520629 -289.497163) (xy 421.560145 -289.467131)
			(xy 421.604 -289.443887) (xy 421.651038 -289.428045) (xy 421.700019 -289.420021) (xy 421.724836 -289.419538)
			(xy 421.739019 -289.419709) (xy 421.767259 -289.422385) (xy 421.781224 -289.424872) (xy 421.79367 -289.427158)
			(xy 421.817292 -289.419792) (xy 421.894762 -289.342322) (xy 421.902128 -289.3187) (xy 421.899842 -289.306254)
			(xy 421.897364 -289.292288) (xy 421.894693 -289.264049) (xy 421.894508 -289.249866) (xy 421.89503 -289.224611)
			(xy 421.903343 -289.174789) (xy 421.919744 -289.127015) (xy 421.943785 -289.082592) (xy 421.974809 -289.042732)
			(xy 422.011971 -289.008522) (xy 422.054257 -288.980896) (xy 422.100513 -288.960606) (xy 422.149478 -288.948206)
			(xy 422.199816 -288.944035) (xy 422.250154 -288.948206) (xy 422.299119 -288.960606) (xy 422.345375 -288.980896)
			(xy 422.387661 -289.008522) (xy 422.424823 -289.042732) (xy 422.455847 -289.082592) (xy 422.457161 -289.08502)
			(xy 434.087776 -289.08502) (xy 434.091847 -289.029398) (xy 434.103973 -288.974961) (xy 434.123896 -288.92287)
			(xy 434.151192 -288.874235) (xy 434.185278 -288.830092) (xy 434.225427 -288.791383) (xy 434.270785 -288.758932)
			(xy 434.320385 -288.733431) (xy 434.373169 -288.715424) (xy 434.428012 -288.705294) (xy 434.483746 -288.703257)
			(xy 434.539183 -288.709357) (xy 434.59314 -288.723463) (xy 434.644469 -288.745275) (xy 434.692075 -288.774329)
			(xy 434.734943 -288.810004) (xy 434.753546 -288.830766) (xy 441.453014 -288.830766) (xy 441.457085 -288.775144)
			(xy 441.469211 -288.720707) (xy 441.489134 -288.668616) (xy 441.51643 -288.619981) (xy 441.550516 -288.575838)
			(xy 441.590665 -288.537129) (xy 441.636023 -288.504678) (xy 441.685623 -288.479177) (xy 441.738407 -288.46117)
			(xy 441.79325 -288.45104) (xy 441.848984 -288.449003) (xy 441.904421 -288.455103) (xy 441.958378 -288.469209)
			(xy 442.009707 -288.491021) (xy 442.057313 -288.520075) (xy 442.100181 -288.55575) (xy 442.137398 -288.597287)
			(xy 442.168171 -288.6438) (xy 442.191843 -288.694297) (xy 442.207911 -288.747704) (xy 442.216026 -288.802847)
			(xy 458.605926 -288.802847) (xy 458.605926 -288.748353) (xy 458.613681 -288.694413) (xy 458.629034 -288.642125)
			(xy 458.651672 -288.592555) (xy 458.681133 -288.546711) (xy 458.716819 -288.505526) (xy 458.758003 -288.469839)
			(xy 458.803846 -288.440376) (xy 458.853416 -288.417738) (xy 458.905703 -288.402384) (xy 458.959643 -288.394627)
			(xy 458.98689 -288.39414) (xy 459.01426 -288.394602) (xy 459.06844 -288.402419) (xy 459.120944 -288.417909)
			(xy 459.17069 -288.440752) (xy 459.216657 -288.470478) (xy 459.237588 -288.48812) (xy 459.2447 -288.494216)
			(xy 459.261718 -288.500566) (xy 459.347062 -288.500566) (xy 459.36408 -288.494216) (xy 459.371192 -288.48812)
			(xy 459.392119 -288.470474) (xy 459.438093 -288.440763) (xy 459.487842 -288.417928) (xy 459.540344 -288.402438)
			(xy 459.59452 -288.394613) (xy 459.62189 -288.39414) (xy 459.649147 -288.394506) (xy 459.703106 -288.402263)
			(xy 459.755411 -288.41762) (xy 459.804999 -288.440265) (xy 459.850859 -288.469736) (xy 459.892058 -288.505435)
			(xy 459.927758 -288.546633) (xy 459.95723 -288.592492) (xy 459.979876 -288.642079) (xy 459.995235 -288.694385)
			(xy 460.002993 -288.748343) (xy 460.002993 -288.802847) (xy 460.345826 -288.802847) (xy 460.345826 -288.748353)
			(xy 460.353581 -288.694413) (xy 460.368934 -288.642125) (xy 460.391572 -288.592555) (xy 460.421033 -288.546711)
			(xy 460.456719 -288.505526) (xy 460.497903 -288.469839) (xy 460.543746 -288.440376) (xy 460.593316 -288.417738)
			(xy 460.645603 -288.402384) (xy 460.699543 -288.394627) (xy 460.72679 -288.39414) (xy 460.75416 -288.394602)
			(xy 460.80834 -288.402419) (xy 460.860844 -288.417909) (xy 460.91059 -288.440752) (xy 460.956557 -288.470478)
			(xy 460.977488 -288.48812) (xy 460.9846 -288.494216) (xy 461.001618 -288.500566) (xy 461.086962 -288.500566)
			(xy 461.10398 -288.494216) (xy 461.111092 -288.48812) (xy 461.132019 -288.470474) (xy 461.177993 -288.440763)
			(xy 461.227742 -288.417928) (xy 461.280244 -288.402438) (xy 461.33442 -288.394613) (xy 461.36179 -288.39414)
			(xy 461.389047 -288.394506) (xy 461.443006 -288.402263) (xy 461.495311 -288.41762) (xy 461.544899 -288.440265)
			(xy 461.590759 -288.469736) (xy 461.631958 -288.505435) (xy 461.667658 -288.546633) (xy 461.69713 -288.592492)
			(xy 461.719776 -288.642079) (xy 461.735135 -288.694385) (xy 461.742893 -288.748343) (xy 461.742893 -288.802857)
			(xy 461.735135 -288.856815) (xy 461.719776 -288.909121) (xy 461.69713 -288.958708) (xy 461.667658 -289.004567)
			(xy 461.631958 -289.045765) (xy 461.590759 -289.081464) (xy 461.544899 -289.110935) (xy 461.495311 -289.13358)
			(xy 461.443006 -289.148937) (xy 461.389047 -289.156694) (xy 461.36179 -289.157156) (xy 461.334419 -289.156707)
			(xy 461.280239 -289.148886) (xy 461.227735 -289.133394) (xy 461.177988 -289.110548) (xy 461.132023 -289.080819)
			(xy 461.111092 -289.063176) (xy 461.10398 -289.05708) (xy 461.086962 -289.05073) (xy 461.001618 -289.05073)
			(xy 460.9846 -289.05708) (xy 460.977488 -289.063176) (xy 460.95653 -289.080784) (xy 460.910565 -289.110501)
			(xy 460.860824 -289.133343) (xy 460.808329 -289.148842) (xy 460.754157 -289.156678) (xy 460.72679 -289.157156)
			(xy 460.699543 -289.156573) (xy 460.645603 -289.148816) (xy 460.593316 -289.133462) (xy 460.543746 -289.110824)
			(xy 460.497903 -289.081361) (xy 460.456719 -289.045674) (xy 460.421033 -289.004489) (xy 460.391572 -288.958645)
			(xy 460.368934 -288.909075) (xy 460.353581 -288.856787) (xy 460.345826 -288.802847) (xy 460.002993 -288.802847)
			(xy 460.002993 -288.802857) (xy 459.995235 -288.856815) (xy 459.979876 -288.909121) (xy 459.95723 -288.958708)
			(xy 459.927758 -289.004567) (xy 459.892058 -289.045765) (xy 459.850859 -289.081464) (xy 459.804999 -289.110935)
			(xy 459.755411 -289.13358) (xy 459.703106 -289.148937) (xy 459.649147 -289.156694) (xy 459.62189 -289.157156)
			(xy 459.594519 -289.156707) (xy 459.540339 -289.148886) (xy 459.487835 -289.133394) (xy 459.438088 -289.110548)
			(xy 459.392123 -289.080819) (xy 459.371192 -289.063176) (xy 459.36408 -289.05708) (xy 459.347062 -289.05073)
			(xy 459.261718 -289.05073) (xy 459.2447 -289.05708) (xy 459.237588 -289.063176) (xy 459.21663 -289.080784)
			(xy 459.170665 -289.110501) (xy 459.120924 -289.133343) (xy 459.068429 -289.148842) (xy 459.014257 -289.156678)
			(xy 458.98689 -289.157156) (xy 458.959643 -289.156573) (xy 458.905703 -289.148816) (xy 458.853416 -289.133462)
			(xy 458.803846 -289.110824) (xy 458.758003 -289.081361) (xy 458.716819 -289.045674) (xy 458.681133 -289.004489)
			(xy 458.651672 -288.958645) (xy 458.629034 -288.909075) (xy 458.613681 -288.856787) (xy 458.605926 -288.802847)
			(xy 442.216026 -288.802847) (xy 442.216031 -288.80288) (xy 442.21654 -288.830766) (xy 442.216031 -288.858652)
			(xy 442.207911 -288.913828) (xy 442.191843 -288.967235) (xy 442.168171 -289.017732) (xy 442.137398 -289.064245)
			(xy 442.100181 -289.105782) (xy 442.057313 -289.141457) (xy 442.009707 -289.170511) (xy 441.958378 -289.192323)
			(xy 441.904421 -289.206429) (xy 441.848984 -289.212529) (xy 441.79325 -289.210492) (xy 441.738407 -289.200362)
			(xy 441.685623 -289.182355) (xy 441.636023 -289.156854) (xy 441.590665 -289.124403) (xy 441.550516 -289.085694)
			(xy 441.51643 -289.041551) (xy 441.489134 -288.992916) (xy 441.469211 -288.940825) (xy 441.457085 -288.886388)
			(xy 441.453014 -288.830766) (xy 434.753546 -288.830766) (xy 434.77216 -288.851541) (xy 434.802933 -288.898054)
			(xy 434.826605 -288.948551) (xy 434.842673 -289.001958) (xy 434.850793 -289.057134) (xy 434.851302 -289.08502)
			(xy 434.850793 -289.112906) (xy 434.842673 -289.168082) (xy 434.826605 -289.221489) (xy 434.802933 -289.271986)
			(xy 434.77216 -289.318499) (xy 434.734943 -289.360036) (xy 434.692075 -289.395711) (xy 434.644469 -289.424765)
			(xy 434.59314 -289.446577) (xy 434.539183 -289.460683) (xy 434.483746 -289.466783) (xy 434.428012 -289.464746)
			(xy 434.373169 -289.454616) (xy 434.320385 -289.436609) (xy 434.270785 -289.411108) (xy 434.225427 -289.378657)
			(xy 434.185278 -289.339948) (xy 434.151192 -289.295805) (xy 434.123896 -289.24717) (xy 434.103973 -289.195079)
			(xy 434.091847 -289.140642) (xy 434.087776 -289.08502) (xy 422.457161 -289.08502) (xy 422.479888 -289.127015)
			(xy 422.496289 -289.174789) (xy 422.504602 -289.224611) (xy 422.505124 -289.249866) (xy 422.504942 -289.264049)
			(xy 422.502274 -289.292289) (xy 422.49979 -289.306254) (xy 422.497504 -289.3187) (xy 422.50487 -289.342576)
			(xy 422.582086 -289.419792) (xy 422.606216 -289.427158) (xy 422.618408 -289.424872) (xy 422.632437 -289.422389)
			(xy 422.660804 -289.419716) (xy 422.67505 -289.419538) (xy 422.699865 -289.420032) (xy 422.74884 -289.428068)
			(xy 422.79587 -289.443922) (xy 422.839716 -289.467175) (xy 422.879223 -289.497215) (xy 422.91335 -289.53325)
			(xy 422.941198 -289.574331) (xy 422.962033 -289.619376) (xy 422.975307 -289.667199) (xy 422.980669 -289.716538)
			(xy 422.980218 -289.724846) (xy 424.269166 -289.724846) (xy 424.273126 -289.675792) (xy 424.284903 -289.628008)
			(xy 424.304194 -289.582732) (xy 424.330497 -289.541136) (xy 424.363132 -289.504299) (xy 424.401253 -289.473174)
			(xy 424.443874 -289.448567) (xy 424.48989 -289.431115) (xy 424.538109 -289.421271) (xy 424.587284 -289.41929)
			(xy 424.636139 -289.425222) (xy 424.68341 -289.438914) (xy 424.727872 -289.460012) (xy 424.768375 -289.487968)
			(xy 424.803868 -289.52206) (xy 424.833433 -289.561404) (xy 424.856304 -289.604981) (xy 424.871888 -289.651662)
			(xy 424.879783 -289.700239) (xy 424.880278 -289.724846) (xy 425.219126 -289.724846) (xy 425.223086 -289.675792)
			(xy 425.234863 -289.628008) (xy 425.254154 -289.582732) (xy 425.280457 -289.541136) (xy 425.313092 -289.504299)
			(xy 425.351213 -289.473174) (xy 425.393834 -289.448567) (xy 425.43985 -289.431115) (xy 425.488069 -289.421271)
			(xy 425.537244 -289.41929) (xy 425.586099 -289.425222) (xy 425.63337 -289.438914) (xy 425.677832 -289.460012)
			(xy 425.718335 -289.487968) (xy 425.753828 -289.52206) (xy 425.783393 -289.561404) (xy 425.806264 -289.604981)
			(xy 425.821848 -289.651662) (xy 425.829743 -289.700239) (xy 425.830238 -289.724846) (xy 426.169086 -289.724846)
			(xy 426.173046 -289.675792) (xy 426.184823 -289.628008) (xy 426.204114 -289.582732) (xy 426.230417 -289.541136)
			(xy 426.263052 -289.504299) (xy 426.301173 -289.473174) (xy 426.343794 -289.448567) (xy 426.38981 -289.431115)
			(xy 426.438029 -289.421271) (xy 426.487204 -289.41929) (xy 426.536059 -289.425222) (xy 426.58333 -289.438914)
			(xy 426.627792 -289.460012) (xy 426.668295 -289.487968) (xy 426.703788 -289.52206) (xy 426.733353 -289.561404)
			(xy 426.756224 -289.604981) (xy 426.771808 -289.651662) (xy 426.779703 -289.700239) (xy 426.780198 -289.724846)
			(xy 427.119046 -289.724846) (xy 427.123006 -289.675792) (xy 427.134783 -289.628008) (xy 427.154074 -289.582732)
			(xy 427.180377 -289.541136) (xy 427.213012 -289.504299) (xy 427.251133 -289.473174) (xy 427.293754 -289.448567)
			(xy 427.33977 -289.431115) (xy 427.387989 -289.421271) (xy 427.437164 -289.41929) (xy 427.486019 -289.425222)
			(xy 427.53329 -289.438914) (xy 427.577752 -289.460012) (xy 427.618255 -289.487968) (xy 427.653748 -289.52206)
			(xy 427.683313 -289.561404) (xy 427.706184 -289.604981) (xy 427.721768 -289.651662) (xy 427.729663 -289.700239)
			(xy 427.730158 -289.724846) (xy 428.069006 -289.724846) (xy 428.072966 -289.675792) (xy 428.084743 -289.628008)
			(xy 428.104034 -289.582732) (xy 428.130337 -289.541136) (xy 428.162972 -289.504299) (xy 428.201093 -289.473174)
			(xy 428.243714 -289.448567) (xy 428.28973 -289.431115) (xy 428.337949 -289.421271) (xy 428.387124 -289.41929)
			(xy 428.435979 -289.425222) (xy 428.48325 -289.438914) (xy 428.527712 -289.460012) (xy 428.568215 -289.487968)
			(xy 428.603708 -289.52206) (xy 428.633273 -289.561404) (xy 428.656144 -289.604981) (xy 428.671728 -289.651662)
			(xy 428.679623 -289.700239) (xy 428.680118 -289.724846) (xy 429.01922 -289.724846) (xy 429.02318 -289.675792)
			(xy 429.034957 -289.628008) (xy 429.054248 -289.582732) (xy 429.080551 -289.541136) (xy 429.113186 -289.504299)
			(xy 429.151307 -289.473174) (xy 429.193928 -289.448567) (xy 429.239944 -289.431115) (xy 429.288163 -289.421271)
			(xy 429.337338 -289.41929) (xy 429.386193 -289.425222) (xy 429.433464 -289.438914) (xy 429.477926 -289.460012)
			(xy 429.518429 -289.487968) (xy 429.553922 -289.52206) (xy 429.583487 -289.561404) (xy 429.606358 -289.604981)
			(xy 429.621942 -289.651662) (xy 429.629837 -289.700239) (xy 429.630332 -289.724846) (xy 429.96918 -289.724846)
			(xy 429.97314 -289.675792) (xy 429.984917 -289.628008) (xy 430.004208 -289.582732) (xy 430.030511 -289.541136)
			(xy 430.063146 -289.504299) (xy 430.101267 -289.473174) (xy 430.143888 -289.448567) (xy 430.189904 -289.431115)
			(xy 430.238123 -289.421271) (xy 430.287298 -289.41929) (xy 430.336153 -289.425222) (xy 430.383424 -289.438914)
			(xy 430.427886 -289.460012) (xy 430.468389 -289.487968) (xy 430.503882 -289.52206) (xy 430.533447 -289.561404)
			(xy 430.556318 -289.604981) (xy 430.571902 -289.651662) (xy 430.579797 -289.700239) (xy 430.580292 -289.724846)
			(xy 430.91914 -289.724846) (xy 430.9231 -289.675792) (xy 430.934877 -289.628008) (xy 430.954168 -289.582732)
			(xy 430.980471 -289.541136) (xy 431.013106 -289.504299) (xy 431.051227 -289.473174) (xy 431.093848 -289.448567)
			(xy 431.139864 -289.431115) (xy 431.188083 -289.421271) (xy 431.237258 -289.41929) (xy 431.286113 -289.425222)
			(xy 431.333384 -289.438914) (xy 431.377846 -289.460012) (xy 431.418349 -289.487968) (xy 431.453842 -289.52206)
			(xy 431.468868 -289.542056) (xy 450.443243 -289.542056) (xy 450.443243 -289.487544) (xy 450.451001 -289.433587)
			(xy 450.46636 -289.381284) (xy 450.489007 -289.331699) (xy 450.51848 -289.285843) (xy 450.55418 -289.244647)
			(xy 450.595379 -289.208953) (xy 450.64124 -289.179485) (xy 450.690827 -289.156844) (xy 450.743132 -289.141492)
			(xy 450.79709 -289.13374) (xy 450.824346 -289.13328) (xy 450.851716 -289.133758) (xy 450.905895 -289.14157)
			(xy 450.958399 -289.157055) (xy 451.008146 -289.179895) (xy 451.054113 -289.209619) (xy 451.075044 -289.22726)
			(xy 451.082156 -289.233356) (xy 451.099174 -289.239706) (xy 451.184518 -289.239706) (xy 451.201536 -289.233356)
			(xy 451.208648 -289.22726) (xy 451.229583 -289.209625) (xy 451.275556 -289.179914) (xy 451.325303 -289.157078)
			(xy 451.377802 -289.141585) (xy 451.431977 -289.133755) (xy 451.459346 -289.13328) (xy 451.486594 -289.133793)
			(xy 451.540535 -289.141555) (xy 451.592823 -289.156914) (xy 451.642393 -289.179557) (xy 451.688236 -289.209023)
			(xy 451.729419 -289.244714) (xy 451.765104 -289.285901) (xy 451.794565 -289.331748) (xy 451.817203 -289.38132)
			(xy 451.832555 -289.43361) (xy 451.84031 -289.487552) (xy 451.84031 -289.542048) (xy 451.840309 -289.542052)
			(xy 452.214966 -289.542052) (xy 452.214966 -289.487548) (xy 452.222722 -289.433599) (xy 452.238078 -289.381303)
			(xy 452.260719 -289.331724) (xy 452.290186 -289.285873) (xy 452.325878 -289.244681) (xy 452.36707 -289.208989)
			(xy 452.412921 -289.179521) (xy 452.462499 -289.156879) (xy 452.514795 -289.141523) (xy 452.568744 -289.133766)
			(xy 452.595996 -289.13328) (xy 452.623367 -289.133729) (xy 452.677548 -289.141548) (xy 452.730052 -289.15704)
			(xy 452.779798 -289.179886) (xy 452.825764 -289.209616) (xy 452.846694 -289.22726) (xy 452.853806 -289.233356)
			(xy 452.870824 -289.239706) (xy 452.956168 -289.239706) (xy 452.973186 -289.233356) (xy 452.980298 -289.22726)
			(xy 453.001215 -289.209602) (xy 453.047192 -289.179894) (xy 453.096944 -289.157062) (xy 453.149448 -289.141576)
			(xy 453.203626 -289.133751) (xy 453.230996 -289.13328) (xy 453.258248 -289.133767) (xy 453.312198 -289.141523)
			(xy 453.364495 -289.156879) (xy 453.414074 -289.17952) (xy 453.459926 -289.208987) (xy 453.501118 -289.24468)
			(xy 453.536811 -289.285871) (xy 453.566278 -289.331723) (xy 453.58892 -289.381302) (xy 453.604276 -289.433598)
			(xy 453.612033 -289.487548) (xy 453.612033 -289.542052) (xy 453.604276 -289.596002) (xy 453.58892 -289.648298)
			(xy 453.566278 -289.697877) (xy 453.536811 -289.743729) (xy 453.501118 -289.78492) (xy 453.459926 -289.820613)
			(xy 453.414074 -289.85008) (xy 453.364495 -289.872721) (xy 453.312198 -289.888077) (xy 453.258248 -289.895833)
			(xy 453.230996 -289.896296) (xy 453.203626 -289.895833) (xy 453.149446 -289.888015) (xy 453.096943 -289.872525)
			(xy 453.047196 -289.849683) (xy 453.00123 -289.819957) (xy 452.980298 -289.802316) (xy 452.973186 -289.79622)
			(xy 452.956168 -289.78987) (xy 452.870824 -289.78987) (xy 452.853806 -289.79622) (xy 452.846694 -289.802316)
			(xy 452.825777 -289.819974) (xy 452.7798 -289.849682) (xy 452.730048 -289.872514) (xy 452.677545 -289.888001)
			(xy 452.623366 -289.895825) (xy 452.595996 -289.896296) (xy 452.568744 -289.895834) (xy 452.514795 -289.888077)
			(xy 452.462499 -289.872721) (xy 452.412921 -289.850079) (xy 452.36707 -289.820611) (xy 452.325878 -289.784919)
			(xy 452.290186 -289.743727) (xy 452.260719 -289.697876) (xy 452.238078 -289.648297) (xy 452.222722 -289.596001)
			(xy 452.214966 -289.542052) (xy 451.840309 -289.542052) (xy 451.832555 -289.59599) (xy 451.817203 -289.64828)
			(xy 451.794565 -289.697852) (xy 451.765104 -289.743699) (xy 451.729419 -289.784886) (xy 451.688236 -289.820577)
			(xy 451.642393 -289.850043) (xy 451.592823 -289.872686) (xy 451.540535 -289.888045) (xy 451.486594 -289.895807)
			(xy 451.459346 -289.896296) (xy 451.431977 -289.895804) (xy 451.377799 -289.887993) (xy 451.325296 -289.87251)
			(xy 451.275549 -289.849674) (xy 451.229581 -289.819955) (xy 451.208648 -289.802316) (xy 451.201536 -289.79622)
			(xy 451.184518 -289.78987) (xy 451.099174 -289.78987) (xy 451.082156 -289.79622) (xy 451.075044 -289.802316)
			(xy 451.054108 -289.81995) (xy 451.008136 -289.849662) (xy 450.95839 -289.872499) (xy 450.90589 -289.887991)
			(xy 450.851715 -289.895821) (xy 450.824346 -289.896296) (xy 450.79709 -289.89586) (xy 450.743132 -289.888108)
			(xy 450.690827 -289.872756) (xy 450.64124 -289.850115) (xy 450.595379 -289.820647) (xy 450.55418 -289.784953)
			(xy 450.51848 -289.743757) (xy 450.489007 -289.697901) (xy 450.46636 -289.648316) (xy 450.451001 -289.596013)
			(xy 450.443243 -289.542056) (xy 431.468868 -289.542056) (xy 431.483407 -289.561404) (xy 431.506278 -289.604981)
			(xy 431.521862 -289.651662) (xy 431.529757 -289.700239) (xy 431.530252 -289.724846) (xy 431.529757 -289.749453)
			(xy 431.521862 -289.79803) (xy 431.506278 -289.844711) (xy 431.483407 -289.888288) (xy 431.453842 -289.927632)
			(xy 431.418349 -289.961724) (xy 431.377846 -289.98968) (xy 431.333384 -290.010778) (xy 431.286113 -290.02447)
			(xy 431.237258 -290.030402) (xy 431.188083 -290.028421) (xy 431.139864 -290.018577) (xy 431.093848 -290.001125)
			(xy 431.051227 -289.976518) (xy 431.013106 -289.945393) (xy 430.980471 -289.908556) (xy 430.954168 -289.86696)
			(xy 430.934877 -289.821684) (xy 430.9231 -289.7739) (xy 430.91914 -289.724846) (xy 430.580292 -289.724846)
			(xy 430.579797 -289.749453) (xy 430.571902 -289.79803) (xy 430.556318 -289.844711) (xy 430.533447 -289.888288)
			(xy 430.503882 -289.927632) (xy 430.468389 -289.961724) (xy 430.427886 -289.98968) (xy 430.383424 -290.010778)
			(xy 430.336153 -290.02447) (xy 430.287298 -290.030402) (xy 430.238123 -290.028421) (xy 430.189904 -290.018577)
			(xy 430.143888 -290.001125) (xy 430.101267 -289.976518) (xy 430.063146 -289.945393) (xy 430.030511 -289.908556)
			(xy 430.004208 -289.86696) (xy 429.984917 -289.821684) (xy 429.97314 -289.7739) (xy 429.96918 -289.724846)
			(xy 429.630332 -289.724846) (xy 429.629837 -289.749453) (xy 429.621942 -289.79803) (xy 429.606358 -289.844711)
			(xy 429.583487 -289.888288) (xy 429.553922 -289.927632) (xy 429.518429 -289.961724) (xy 429.477926 -289.98968)
			(xy 429.433464 -290.010778) (xy 429.386193 -290.02447) (xy 429.337338 -290.030402) (xy 429.288163 -290.028421)
			(xy 429.239944 -290.018577) (xy 429.193928 -290.001125) (xy 429.151307 -289.976518) (xy 429.113186 -289.945393)
			(xy 429.080551 -289.908556) (xy 429.054248 -289.86696) (xy 429.034957 -289.821684) (xy 429.02318 -289.7739)
			(xy 429.01922 -289.724846) (xy 428.680118 -289.724846) (xy 428.679623 -289.749453) (xy 428.671728 -289.79803)
			(xy 428.656144 -289.844711) (xy 428.633273 -289.888288) (xy 428.603708 -289.927632) (xy 428.568215 -289.961724)
			(xy 428.527712 -289.98968) (xy 428.48325 -290.010778) (xy 428.435979 -290.02447) (xy 428.387124 -290.030402)
			(xy 428.337949 -290.028421) (xy 428.28973 -290.018577) (xy 428.243714 -290.001125) (xy 428.201093 -289.976518)
			(xy 428.162972 -289.945393) (xy 428.130337 -289.908556) (xy 428.104034 -289.86696) (xy 428.084743 -289.821684)
			(xy 428.072966 -289.7739) (xy 428.069006 -289.724846) (xy 427.730158 -289.724846) (xy 427.729663 -289.749453)
			(xy 427.721768 -289.79803) (xy 427.706184 -289.844711) (xy 427.683313 -289.888288) (xy 427.653748 -289.927632)
			(xy 427.618255 -289.961724) (xy 427.577752 -289.98968) (xy 427.53329 -290.010778) (xy 427.486019 -290.02447)
			(xy 427.437164 -290.030402) (xy 427.387989 -290.028421) (xy 427.33977 -290.018577) (xy 427.293754 -290.001125)
			(xy 427.251133 -289.976518) (xy 427.213012 -289.945393) (xy 427.180377 -289.908556) (xy 427.154074 -289.86696)
			(xy 427.134783 -289.821684) (xy 427.123006 -289.7739) (xy 427.119046 -289.724846) (xy 426.780198 -289.724846)
			(xy 426.779703 -289.749453) (xy 426.771808 -289.79803) (xy 426.756224 -289.844711) (xy 426.733353 -289.888288)
			(xy 426.703788 -289.927632) (xy 426.668295 -289.961724) (xy 426.627792 -289.98968) (xy 426.58333 -290.010778)
			(xy 426.536059 -290.02447) (xy 426.487204 -290.030402) (xy 426.438029 -290.028421) (xy 426.38981 -290.018577)
			(xy 426.343794 -290.001125) (xy 426.301173 -289.976518) (xy 426.263052 -289.945393) (xy 426.230417 -289.908556)
			(xy 426.204114 -289.86696) (xy 426.184823 -289.821684) (xy 426.173046 -289.7739) (xy 426.169086 -289.724846)
			(xy 425.830238 -289.724846) (xy 425.829743 -289.749453) (xy 425.821848 -289.79803) (xy 425.806264 -289.844711)
			(xy 425.783393 -289.888288) (xy 425.753828 -289.927632) (xy 425.718335 -289.961724) (xy 425.677832 -289.98968)
			(xy 425.63337 -290.010778) (xy 425.586099 -290.02447) (xy 425.537244 -290.030402) (xy 425.488069 -290.028421)
			(xy 425.43985 -290.018577) (xy 425.393834 -290.001125) (xy 425.351213 -289.976518) (xy 425.313092 -289.945393)
			(xy 425.280457 -289.908556) (xy 425.254154 -289.86696) (xy 425.234863 -289.821684) (xy 425.223086 -289.7739)
			(xy 425.219126 -289.724846) (xy 424.880278 -289.724846) (xy 424.879783 -289.749453) (xy 424.871888 -289.79803)
			(xy 424.856304 -289.844711) (xy 424.833433 -289.888288) (xy 424.803868 -289.927632) (xy 424.768375 -289.961724)
			(xy 424.727872 -289.98968) (xy 424.68341 -290.010778) (xy 424.636139 -290.02447) (xy 424.587284 -290.030402)
			(xy 424.538109 -290.028421) (xy 424.48989 -290.018577) (xy 424.443874 -290.001125) (xy 424.401253 -289.976518)
			(xy 424.363132 -289.945393) (xy 424.330497 -289.908556) (xy 424.304194 -289.86696) (xy 424.284903 -289.821684)
			(xy 424.273126 -289.7739) (xy 424.269166 -289.724846) (xy 422.980218 -289.724846) (xy 422.97798 -289.766096)
			(xy 422.967308 -289.814565) (xy 422.948937 -289.86067) (xy 422.923349 -289.903195) (xy 422.891218 -289.941021)
			(xy 422.853392 -289.973151) (xy 422.810866 -289.998739) (xy 422.764761 -290.01711) (xy 422.716292 -290.02778)
			(xy 422.666734 -290.030469) (xy 422.617395 -290.025106) (xy 422.569572 -290.011831) (xy 422.524528 -289.990996)
			(xy 422.483447 -289.963147) (xy 422.447412 -289.92902) (xy 422.417373 -289.889513) (xy 422.394121 -289.845667)
			(xy 422.378267 -289.798636) (xy 422.370231 -289.749661) (xy 422.369742 -289.724846) (xy 422.369924 -289.710663)
			(xy 422.372592 -289.682423) (xy 422.375076 -289.668458) (xy 422.377362 -289.656012) (xy 422.369996 -289.632136)
			(xy 422.29278 -289.55492) (xy 422.26865 -289.547554) (xy 422.256458 -289.54984) (xy 422.24243 -289.552328)
			(xy 422.214062 -289.554998) (xy 422.199816 -289.555174) (xy 422.185633 -289.554996) (xy 422.157393 -289.552325)
			(xy 422.143428 -289.54984) (xy 422.130982 -289.547554) (xy 422.10736 -289.55492) (xy 422.02989 -289.63239)
			(xy 422.022524 -289.656012) (xy 422.02481 -289.668458) (xy 422.027291 -289.682423) (xy 422.02996 -289.710663)
			(xy 422.030144 -289.724846) (xy 422.029573 -289.749663) (xy 422.021535 -289.798642) (xy 422.00568 -289.845675)
			(xy 421.982425 -289.889524) (xy 421.952382 -289.929033) (xy 421.916343 -289.963161) (xy 421.875257 -289.991009)
			(xy 421.830208 -290.011843) (xy 421.782381 -290.025115) (xy 421.733038 -290.030474) (xy 421.683477 -290.02778)
			(xy 421.635005 -290.017103) (xy 421.588899 -289.998726) (xy 421.546373 -289.973131) (xy 421.508548 -289.940994)
			(xy 421.476421 -289.90316) (xy 421.450838 -289.860628) (xy 421.432472 -289.814517) (xy 421.421809 -289.766042)
			(xy 421.419128 -289.71648) (xy 421.080016 -289.71648) (xy 421.080184 -289.724846) (xy 421.079689 -289.749453)
			(xy 421.071794 -289.79803) (xy 421.05621 -289.844711) (xy 421.033339 -289.888288) (xy 421.003774 -289.927632)
			(xy 420.968281 -289.961724) (xy 420.927778 -289.98968) (xy 420.883316 -290.010778) (xy 420.836045 -290.02447)
			(xy 420.78719 -290.030402) (xy 420.738015 -290.028421) (xy 420.689796 -290.018577) (xy 420.64378 -290.001125)
			(xy 420.601159 -289.976518) (xy 420.563038 -289.945393) (xy 420.530403 -289.908556) (xy 420.5041 -289.86696)
			(xy 420.484809 -289.821684) (xy 420.473032 -289.7739) (xy 420.469072 -289.724846) (xy 420.130224 -289.724846)
			(xy 420.129729 -289.749453) (xy 420.121834 -289.79803) (xy 420.10625 -289.844711) (xy 420.083379 -289.888288)
			(xy 420.053814 -289.927632) (xy 420.018321 -289.961724) (xy 419.977818 -289.98968) (xy 419.933356 -290.010778)
			(xy 419.886085 -290.02447) (xy 419.83723 -290.030402) (xy 419.788055 -290.028421) (xy 419.739836 -290.018577)
			(xy 419.69382 -290.001125) (xy 419.651199 -289.976518) (xy 419.613078 -289.945393) (xy 419.580443 -289.908556)
			(xy 419.55414 -289.86696) (xy 419.534849 -289.821684) (xy 419.523072 -289.7739) (xy 419.519112 -289.724846)
			(xy 419.180264 -289.724846) (xy 419.179769 -289.749453) (xy 419.171874 -289.79803) (xy 419.15629 -289.844711)
			(xy 419.133419 -289.888288) (xy 419.103854 -289.927632) (xy 419.068361 -289.961724) (xy 419.027858 -289.98968)
			(xy 418.983396 -290.010778) (xy 418.936125 -290.02447) (xy 418.88727 -290.030402) (xy 418.838095 -290.028421)
			(xy 418.789876 -290.018577) (xy 418.74386 -290.001125) (xy 418.701239 -289.976518) (xy 418.663118 -289.945393)
			(xy 418.630483 -289.908556) (xy 418.60418 -289.86696) (xy 418.584889 -289.821684) (xy 418.573112 -289.7739)
			(xy 418.569152 -289.724846) (xy 418.230304 -289.724846) (xy 418.229837 -289.748746) (xy 418.22238 -289.795961)
			(xy 418.207657 -289.841437) (xy 418.186026 -289.884063) (xy 418.158016 -289.922796) (xy 418.124312 -289.956692)
			(xy 418.085737 -289.98492) (xy 418.043235 -290.006792) (xy 417.997843 -290.021773) (xy 417.950671 -290.029497)
			(xy 417.926774 -290.030154) (xy 417.924234 -290.030154) (xy 417.897097 -290.029494) (xy 417.843695 -290.019784)
			(xy 417.818062 -290.01085) (xy 417.806378 -290.006532) (xy 417.78174 -290.00958) (xy 417.702492 -290.06419)
			(xy 417.692818 -290.071801) (xy 417.681391 -290.093561) (xy 417.680648 -290.105846) (xy 417.680648 -290.2458)
			(xy 433.453792 -290.2458) (xy 433.457863 -290.190178) (xy 433.469989 -290.135741) (xy 433.489912 -290.08365)
			(xy 433.517208 -290.035015) (xy 433.551294 -289.990872) (xy 433.591443 -289.952163) (xy 433.636801 -289.919712)
			(xy 433.686401 -289.894211) (xy 433.739185 -289.876204) (xy 433.794028 -289.866074) (xy 433.849762 -289.864037)
			(xy 433.905199 -289.870137) (xy 433.959156 -289.884243) (xy 434.010485 -289.906055) (xy 434.058091 -289.935109)
			(xy 434.100959 -289.970784) (xy 434.138176 -290.012321) (xy 434.168949 -290.058834) (xy 434.192621 -290.109331)
			(xy 434.208689 -290.162738) (xy 434.216809 -290.217914) (xy 434.21716 -290.237164) (xy 437.464452 -290.237164)
			(xy 437.468523 -290.181542) (xy 437.480649 -290.127105) (xy 437.500572 -290.075014) (xy 437.527868 -290.026379)
			(xy 437.561954 -289.982236) (xy 437.602103 -289.943527) (xy 437.647461 -289.911076) (xy 437.697061 -289.885575)
			(xy 437.749845 -289.867568) (xy 437.804688 -289.857438) (xy 437.860422 -289.855401) (xy 437.915859 -289.861501)
			(xy 437.969816 -289.875607) (xy 438.021145 -289.897419) (xy 438.068751 -289.926473) (xy 438.111619 -289.962148)
			(xy 438.148836 -290.003685) (xy 438.179609 -290.050198) (xy 438.203281 -290.100695) (xy 438.219349 -290.154102)
			(xy 438.227469 -290.209278) (xy 438.227978 -290.237164) (xy 438.227469 -290.26505) (xy 438.219349 -290.320226)
			(xy 438.203281 -290.373633) (xy 438.179609 -290.42413) (xy 438.148836 -290.470643) (xy 438.111619 -290.51218)
			(xy 438.068751 -290.547855) (xy 438.021145 -290.576909) (xy 437.969816 -290.598721) (xy 437.915859 -290.612827)
			(xy 437.860422 -290.618927) (xy 437.804688 -290.61689) (xy 437.749845 -290.60676) (xy 437.697061 -290.588753)
			(xy 437.647461 -290.563252) (xy 437.602103 -290.530801) (xy 437.561954 -290.492092) (xy 437.527868 -290.447949)
			(xy 437.500572 -290.399314) (xy 437.480649 -290.347223) (xy 437.468523 -290.292786) (xy 437.464452 -290.237164)
			(xy 434.21716 -290.237164) (xy 434.217318 -290.2458) (xy 434.216809 -290.273686) (xy 434.208689 -290.328862)
			(xy 434.192621 -290.382269) (xy 434.168949 -290.432766) (xy 434.138176 -290.479279) (xy 434.100959 -290.520816)
			(xy 434.058091 -290.556491) (xy 434.010485 -290.585545) (xy 433.959156 -290.607357) (xy 433.905199 -290.621463)
			(xy 433.849762 -290.627563) (xy 433.794028 -290.625526) (xy 433.739185 -290.615396) (xy 433.686401 -290.597389)
			(xy 433.636801 -290.571888) (xy 433.591443 -290.539437) (xy 433.551294 -290.500728) (xy 433.517208 -290.456585)
			(xy 433.489912 -290.40795) (xy 433.469989 -290.355859) (xy 433.457863 -290.301422) (xy 433.453792 -290.2458)
			(xy 417.680648 -290.2458) (xy 417.680648 -290.293806) (xy 417.681237 -290.306134) (xy 417.692687 -290.327966)
			(xy 417.702492 -290.335462) (xy 417.780978 -290.389564) (xy 417.805616 -290.392612) (xy 417.8173 -290.388294)
			(xy 417.843217 -290.379166) (xy 417.897271 -290.369323) (xy 417.924742 -290.368736) (xy 417.924996 -290.368736)
			(xy 417.950316 -290.369229) (xy 418.000267 -290.377564) (xy 418.048164 -290.394007) (xy 418.092702 -290.418109)
			(xy 418.132665 -290.449213) (xy 418.166963 -290.48647) (xy 418.194661 -290.528865) (xy 418.215004 -290.575241)
			(xy 418.227436 -290.624332) (xy 418.231618 -290.6748) (xy 418.231618 -290.674806) (xy 418.569152 -290.674806)
			(xy 418.573112 -290.625752) (xy 418.584889 -290.577968) (xy 418.60418 -290.532692) (xy 418.630483 -290.491096)
			(xy 418.663118 -290.454259) (xy 418.701239 -290.423134) (xy 418.74386 -290.398527) (xy 418.789876 -290.381075)
			(xy 418.838095 -290.371231) (xy 418.88727 -290.36925) (xy 418.936125 -290.375182) (xy 418.983396 -290.388874)
			(xy 419.027858 -290.409972) (xy 419.068361 -290.437928) (xy 419.103854 -290.47202) (xy 419.133419 -290.511364)
			(xy 419.15629 -290.554941) (xy 419.171874 -290.601622) (xy 419.179769 -290.650199) (xy 419.180264 -290.674806)
			(xy 419.519112 -290.674806) (xy 419.523072 -290.625752) (xy 419.534849 -290.577968) (xy 419.55414 -290.532692)
			(xy 419.580443 -290.491096) (xy 419.613078 -290.454259) (xy 419.651199 -290.423134) (xy 419.69382 -290.398527)
			(xy 419.739836 -290.381075) (xy 419.788055 -290.371231) (xy 419.83723 -290.36925) (xy 419.886085 -290.375182)
			(xy 419.933356 -290.388874) (xy 419.977818 -290.409972) (xy 420.018321 -290.437928) (xy 420.053814 -290.47202)
			(xy 420.083379 -290.511364) (xy 420.10625 -290.554941) (xy 420.121834 -290.601622) (xy 420.129729 -290.650199)
			(xy 420.130224 -290.674806) (xy 420.469072 -290.674806) (xy 420.473032 -290.625752) (xy 420.484809 -290.577968)
			(xy 420.5041 -290.532692) (xy 420.530403 -290.491096) (xy 420.563038 -290.454259) (xy 420.601159 -290.423134)
			(xy 420.64378 -290.398527) (xy 420.689796 -290.381075) (xy 420.738015 -290.371231) (xy 420.78719 -290.36925)
			(xy 420.836045 -290.375182) (xy 420.883316 -290.388874) (xy 420.927778 -290.409972) (xy 420.968281 -290.437928)
			(xy 421.003774 -290.47202) (xy 421.033339 -290.511364) (xy 421.05621 -290.554941) (xy 421.071794 -290.601622)
			(xy 421.079689 -290.650199) (xy 421.080184 -290.674806) (xy 421.419032 -290.674806) (xy 421.422992 -290.625752)
			(xy 421.434769 -290.577968) (xy 421.45406 -290.532692) (xy 421.480363 -290.491096) (xy 421.512998 -290.454259)
			(xy 421.551119 -290.423134) (xy 421.59374 -290.398527) (xy 421.639756 -290.381075) (xy 421.687975 -290.371231)
			(xy 421.73715 -290.36925) (xy 421.786005 -290.375182) (xy 421.833276 -290.388874) (xy 421.877738 -290.409972)
			(xy 421.918241 -290.437928) (xy 421.953734 -290.47202) (xy 421.983299 -290.511364) (xy 422.00617 -290.554941)
			(xy 422.021754 -290.601622) (xy 422.029649 -290.650199) (xy 422.030144 -290.674806) (xy 422.368992 -290.674806)
			(xy 422.372952 -290.625752) (xy 422.384729 -290.577968) (xy 422.40402 -290.532692) (xy 422.430323 -290.491096)
			(xy 422.462958 -290.454259) (xy 422.501079 -290.423134) (xy 422.5437 -290.398527) (xy 422.589716 -290.381075)
			(xy 422.637935 -290.371231) (xy 422.68711 -290.36925) (xy 422.735965 -290.375182) (xy 422.783236 -290.388874)
			(xy 422.827698 -290.409972) (xy 422.868201 -290.437928) (xy 422.903694 -290.47202) (xy 422.933259 -290.511364)
			(xy 422.95613 -290.554941) (xy 422.971714 -290.601622) (xy 422.979609 -290.650199) (xy 422.980104 -290.674806)
			(xy 423.319206 -290.674806) (xy 423.323166 -290.625752) (xy 423.334943 -290.577968) (xy 423.354234 -290.532692)
			(xy 423.380537 -290.491096) (xy 423.413172 -290.454259) (xy 423.451293 -290.423134) (xy 423.493914 -290.398527)
			(xy 423.53993 -290.381075) (xy 423.588149 -290.371231) (xy 423.637324 -290.36925) (xy 423.686179 -290.375182)
			(xy 423.73345 -290.388874) (xy 423.777912 -290.409972) (xy 423.818415 -290.437928) (xy 423.853908 -290.47202)
			(xy 423.883473 -290.511364) (xy 423.906344 -290.554941) (xy 423.921928 -290.601622) (xy 423.929823 -290.650199)
			(xy 423.930318 -290.674806) (xy 424.269166 -290.674806) (xy 424.273126 -290.625752) (xy 424.284903 -290.577968)
			(xy 424.304194 -290.532692) (xy 424.330497 -290.491096) (xy 424.363132 -290.454259) (xy 424.401253 -290.423134)
			(xy 424.443874 -290.398527) (xy 424.48989 -290.381075) (xy 424.538109 -290.371231) (xy 424.587284 -290.36925)
			(xy 424.636139 -290.375182) (xy 424.68341 -290.388874) (xy 424.727872 -290.409972) (xy 424.768375 -290.437928)
			(xy 424.803868 -290.47202) (xy 424.833433 -290.511364) (xy 424.856304 -290.554941) (xy 424.871888 -290.601622)
			(xy 424.879783 -290.650199) (xy 424.880278 -290.674806) (xy 425.219126 -290.674806) (xy 425.223086 -290.625752)
			(xy 425.234863 -290.577968) (xy 425.254154 -290.532692) (xy 425.280457 -290.491096) (xy 425.313092 -290.454259)
			(xy 425.351213 -290.423134) (xy 425.393834 -290.398527) (xy 425.43985 -290.381075) (xy 425.488069 -290.371231)
			(xy 425.537244 -290.36925) (xy 425.586099 -290.375182) (xy 425.63337 -290.388874) (xy 425.677832 -290.409972)
			(xy 425.718335 -290.437928) (xy 425.753828 -290.47202) (xy 425.783393 -290.511364) (xy 425.806264 -290.554941)
			(xy 425.821848 -290.601622) (xy 425.829743 -290.650199) (xy 425.830238 -290.674806) (xy 426.169086 -290.674806)
			(xy 426.173046 -290.625752) (xy 426.184823 -290.577968) (xy 426.204114 -290.532692) (xy 426.230417 -290.491096)
			(xy 426.263052 -290.454259) (xy 426.301173 -290.423134) (xy 426.343794 -290.398527) (xy 426.38981 -290.381075)
			(xy 426.438029 -290.371231) (xy 426.487204 -290.36925) (xy 426.536059 -290.375182) (xy 426.58333 -290.388874)
			(xy 426.627792 -290.409972) (xy 426.668295 -290.437928) (xy 426.703788 -290.47202) (xy 426.733353 -290.511364)
			(xy 426.756224 -290.554941) (xy 426.771808 -290.601622) (xy 426.779703 -290.650199) (xy 426.780198 -290.674806)
			(xy 427.119046 -290.674806) (xy 427.123006 -290.625752) (xy 427.134783 -290.577968) (xy 427.154074 -290.532692)
			(xy 427.180377 -290.491096) (xy 427.213012 -290.454259) (xy 427.251133 -290.423134) (xy 427.293754 -290.398527)
			(xy 427.33977 -290.381075) (xy 427.387989 -290.371231) (xy 427.437164 -290.36925) (xy 427.486019 -290.375182)
			(xy 427.53329 -290.388874) (xy 427.577752 -290.409972) (xy 427.618255 -290.437928) (xy 427.653748 -290.47202)
			(xy 427.683313 -290.511364) (xy 427.706184 -290.554941) (xy 427.721768 -290.601622) (xy 427.729663 -290.650199)
			(xy 427.730158 -290.674806) (xy 428.069006 -290.674806) (xy 428.072966 -290.625752) (xy 428.084743 -290.577968)
			(xy 428.104034 -290.532692) (xy 428.130337 -290.491096) (xy 428.162972 -290.454259) (xy 428.201093 -290.423134)
			(xy 428.243714 -290.398527) (xy 428.28973 -290.381075) (xy 428.337949 -290.371231) (xy 428.387124 -290.36925)
			(xy 428.435979 -290.375182) (xy 428.48325 -290.388874) (xy 428.527712 -290.409972) (xy 428.568215 -290.437928)
			(xy 428.603708 -290.47202) (xy 428.633273 -290.511364) (xy 428.656144 -290.554941) (xy 428.671728 -290.601622)
			(xy 428.679623 -290.650199) (xy 428.680118 -290.674806) (xy 429.01922 -290.674806) (xy 429.02318 -290.625752)
			(xy 429.034957 -290.577968) (xy 429.054248 -290.532692) (xy 429.080551 -290.491096) (xy 429.113186 -290.454259)
			(xy 429.151307 -290.423134) (xy 429.193928 -290.398527) (xy 429.239944 -290.381075) (xy 429.288163 -290.371231)
			(xy 429.337338 -290.36925) (xy 429.386193 -290.375182) (xy 429.433464 -290.388874) (xy 429.477926 -290.409972)
			(xy 429.518429 -290.437928) (xy 429.553922 -290.47202) (xy 429.583487 -290.511364) (xy 429.606358 -290.554941)
			(xy 429.621942 -290.601622) (xy 429.629837 -290.650199) (xy 429.630332 -290.674806) (xy 429.96918 -290.674806)
			(xy 429.97314 -290.625752) (xy 429.984917 -290.577968) (xy 430.004208 -290.532692) (xy 430.030511 -290.491096)
			(xy 430.063146 -290.454259) (xy 430.101267 -290.423134) (xy 430.143888 -290.398527) (xy 430.189904 -290.381075)
			(xy 430.238123 -290.371231) (xy 430.287298 -290.36925) (xy 430.336153 -290.375182) (xy 430.383424 -290.388874)
			(xy 430.427886 -290.409972) (xy 430.468389 -290.437928) (xy 430.503882 -290.47202) (xy 430.533447 -290.511364)
			(xy 430.556318 -290.554941) (xy 430.571902 -290.601622) (xy 430.579797 -290.650199) (xy 430.580292 -290.674806)
			(xy 430.91914 -290.674806) (xy 430.9231 -290.625752) (xy 430.934877 -290.577968) (xy 430.954168 -290.532692)
			(xy 430.980471 -290.491096) (xy 431.013106 -290.454259) (xy 431.051227 -290.423134) (xy 431.093848 -290.398527)
			(xy 431.139864 -290.381075) (xy 431.188083 -290.371231) (xy 431.237258 -290.36925) (xy 431.286113 -290.375182)
			(xy 431.333384 -290.388874) (xy 431.377846 -290.409972) (xy 431.418349 -290.437928) (xy 431.453842 -290.47202)
			(xy 431.483407 -290.511364) (xy 431.506278 -290.554941) (xy 431.521862 -290.601622) (xy 431.529757 -290.650199)
			(xy 431.530252 -290.674806) (xy 431.529757 -290.699413) (xy 431.521862 -290.74799) (xy 431.506278 -290.794671)
			(xy 431.485192 -290.834847) (xy 458.605926 -290.834847) (xy 458.605926 -290.780353) (xy 458.613681 -290.726413)
			(xy 458.629034 -290.674125) (xy 458.651672 -290.624555) (xy 458.681133 -290.578711) (xy 458.716819 -290.537526)
			(xy 458.758003 -290.501839) (xy 458.803846 -290.472376) (xy 458.853416 -290.449738) (xy 458.905703 -290.434384)
			(xy 458.959643 -290.426627) (xy 458.98689 -290.42614) (xy 459.01426 -290.426602) (xy 459.06844 -290.434419)
			(xy 459.120944 -290.449909) (xy 459.17069 -290.472752) (xy 459.216657 -290.502478) (xy 459.237588 -290.52012)
			(xy 459.2447 -290.526216) (xy 459.261718 -290.532566) (xy 459.347062 -290.532566) (xy 459.36408 -290.526216)
			(xy 459.371192 -290.52012) (xy 459.392119 -290.502474) (xy 459.438093 -290.472763) (xy 459.487842 -290.449928)
			(xy 459.540344 -290.434438) (xy 459.59452 -290.426613) (xy 459.62189 -290.42614) (xy 459.649147 -290.426506)
			(xy 459.703106 -290.434263) (xy 459.755411 -290.44962) (xy 459.804999 -290.472265) (xy 459.850859 -290.501736)
			(xy 459.892058 -290.537435) (xy 459.927758 -290.578633) (xy 459.95723 -290.624492) (xy 459.979876 -290.674079)
			(xy 459.995235 -290.726385) (xy 460.002993 -290.780343) (xy 460.002993 -290.834847) (xy 460.345826 -290.834847)
			(xy 460.345826 -290.780353) (xy 460.353581 -290.726413) (xy 460.368934 -290.674125) (xy 460.391572 -290.624555)
			(xy 460.421033 -290.578711) (xy 460.456719 -290.537526) (xy 460.497903 -290.501839) (xy 460.543746 -290.472376)
			(xy 460.593316 -290.449738) (xy 460.645603 -290.434384) (xy 460.699543 -290.426627) (xy 460.72679 -290.42614)
			(xy 460.75416 -290.426602) (xy 460.80834 -290.434419) (xy 460.860844 -290.449909) (xy 460.91059 -290.472752)
			(xy 460.956557 -290.502478) (xy 460.977488 -290.52012) (xy 460.9846 -290.526216) (xy 461.001618 -290.532566)
			(xy 461.086962 -290.532566) (xy 461.10398 -290.526216) (xy 461.111092 -290.52012) (xy 461.132019 -290.502474)
			(xy 461.177993 -290.472763) (xy 461.227742 -290.449928) (xy 461.280244 -290.434438) (xy 461.33442 -290.426613)
			(xy 461.36179 -290.42614) (xy 461.389047 -290.426506) (xy 461.443006 -290.434263) (xy 461.495311 -290.44962)
			(xy 461.544899 -290.472265) (xy 461.590759 -290.501736) (xy 461.631958 -290.537435) (xy 461.667658 -290.578633)
			(xy 461.69713 -290.624492) (xy 461.719776 -290.674079) (xy 461.735135 -290.726385) (xy 461.742893 -290.780343)
			(xy 461.742893 -290.834857) (xy 461.735135 -290.888815) (xy 461.719776 -290.941121) (xy 461.69713 -290.990708)
			(xy 461.667658 -291.036567) (xy 461.631958 -291.077765) (xy 461.590759 -291.113464) (xy 461.544899 -291.142935)
			(xy 461.495311 -291.16558) (xy 461.443006 -291.180937) (xy 461.389047 -291.188694) (xy 461.36179 -291.189156)
			(xy 461.334419 -291.188707) (xy 461.280239 -291.180886) (xy 461.227735 -291.165394) (xy 461.177988 -291.142548)
			(xy 461.132023 -291.112819) (xy 461.111092 -291.095176) (xy 461.10398 -291.08908) (xy 461.086962 -291.08273)
			(xy 461.001618 -291.08273) (xy 460.9846 -291.08908) (xy 460.977488 -291.095176) (xy 460.95653 -291.112784)
			(xy 460.910565 -291.142501) (xy 460.860824 -291.165343) (xy 460.808329 -291.180842) (xy 460.754157 -291.188678)
			(xy 460.72679 -291.189156) (xy 460.699543 -291.188573) (xy 460.645603 -291.180816) (xy 460.593316 -291.165462)
			(xy 460.543746 -291.142824) (xy 460.497903 -291.113361) (xy 460.456719 -291.077674) (xy 460.421033 -291.036489)
			(xy 460.391572 -290.990645) (xy 460.368934 -290.941075) (xy 460.353581 -290.888787) (xy 460.345826 -290.834847)
			(xy 460.002993 -290.834847) (xy 460.002993 -290.834857) (xy 459.995235 -290.888815) (xy 459.979876 -290.941121)
			(xy 459.95723 -290.990708) (xy 459.927758 -291.036567) (xy 459.892058 -291.077765) (xy 459.850859 -291.113464)
			(xy 459.804999 -291.142935) (xy 459.755411 -291.16558) (xy 459.703106 -291.180937) (xy 459.649147 -291.188694)
			(xy 459.62189 -291.189156) (xy 459.594519 -291.188707) (xy 459.540339 -291.180886) (xy 459.487835 -291.165394)
			(xy 459.438088 -291.142548) (xy 459.392123 -291.112819) (xy 459.371192 -291.095176) (xy 459.36408 -291.08908)
			(xy 459.347062 -291.08273) (xy 459.261718 -291.08273) (xy 459.2447 -291.08908) (xy 459.237588 -291.095176)
			(xy 459.21663 -291.112784) (xy 459.170665 -291.142501) (xy 459.120924 -291.165343) (xy 459.068429 -291.180842)
			(xy 459.014257 -291.188678) (xy 458.98689 -291.189156) (xy 458.959643 -291.188573) (xy 458.905703 -291.180816)
			(xy 458.853416 -291.165462) (xy 458.803846 -291.142824) (xy 458.758003 -291.113361) (xy 458.716819 -291.077674)
			(xy 458.681133 -291.036489) (xy 458.651672 -290.990645) (xy 458.629034 -290.941075) (xy 458.613681 -290.888787)
			(xy 458.605926 -290.834847) (xy 431.485192 -290.834847) (xy 431.483407 -290.838248) (xy 431.453842 -290.877592)
			(xy 431.418349 -290.911684) (xy 431.377846 -290.93964) (xy 431.333384 -290.960738) (xy 431.286113 -290.97443)
			(xy 431.237258 -290.980362) (xy 431.188083 -290.978381) (xy 431.139864 -290.968537) (xy 431.093848 -290.951085)
			(xy 431.051227 -290.926478) (xy 431.013106 -290.895353) (xy 430.980471 -290.858516) (xy 430.954168 -290.81692)
			(xy 430.934877 -290.771644) (xy 430.9231 -290.72386) (xy 430.91914 -290.674806) (xy 430.580292 -290.674806)
			(xy 430.579797 -290.699413) (xy 430.571902 -290.74799) (xy 430.556318 -290.794671) (xy 430.533447 -290.838248)
			(xy 430.503882 -290.877592) (xy 430.468389 -290.911684) (xy 430.427886 -290.93964) (xy 430.383424 -290.960738)
			(xy 430.336153 -290.97443) (xy 430.287298 -290.980362) (xy 430.238123 -290.978381) (xy 430.189904 -290.968537)
			(xy 430.143888 -290.951085) (xy 430.101267 -290.926478) (xy 430.063146 -290.895353) (xy 430.030511 -290.858516)
			(xy 430.004208 -290.81692) (xy 429.984917 -290.771644) (xy 429.97314 -290.72386) (xy 429.96918 -290.674806)
			(xy 429.630332 -290.674806) (xy 429.629837 -290.699413) (xy 429.621942 -290.74799) (xy 429.606358 -290.794671)
			(xy 429.583487 -290.838248) (xy 429.553922 -290.877592) (xy 429.518429 -290.911684) (xy 429.477926 -290.93964)
			(xy 429.433464 -290.960738) (xy 429.386193 -290.97443) (xy 429.337338 -290.980362) (xy 429.288163 -290.978381)
			(xy 429.239944 -290.968537) (xy 429.193928 -290.951085) (xy 429.151307 -290.926478) (xy 429.113186 -290.895353)
			(xy 429.080551 -290.858516) (xy 429.054248 -290.81692) (xy 429.034957 -290.771644) (xy 429.02318 -290.72386)
			(xy 429.01922 -290.674806) (xy 428.680118 -290.674806) (xy 428.679623 -290.699413) (xy 428.671728 -290.74799)
			(xy 428.656144 -290.794671) (xy 428.633273 -290.838248) (xy 428.603708 -290.877592) (xy 428.568215 -290.911684)
			(xy 428.527712 -290.93964) (xy 428.48325 -290.960738) (xy 428.435979 -290.97443) (xy 428.387124 -290.980362)
			(xy 428.337949 -290.978381) (xy 428.28973 -290.968537) (xy 428.243714 -290.951085) (xy 428.201093 -290.926478)
			(xy 428.162972 -290.895353) (xy 428.130337 -290.858516) (xy 428.104034 -290.81692) (xy 428.084743 -290.771644)
			(xy 428.072966 -290.72386) (xy 428.069006 -290.674806) (xy 427.730158 -290.674806) (xy 427.729663 -290.699413)
			(xy 427.721768 -290.74799) (xy 427.706184 -290.794671) (xy 427.683313 -290.838248) (xy 427.653748 -290.877592)
			(xy 427.618255 -290.911684) (xy 427.577752 -290.93964) (xy 427.53329 -290.960738) (xy 427.486019 -290.97443)
			(xy 427.437164 -290.980362) (xy 427.387989 -290.978381) (xy 427.33977 -290.968537) (xy 427.293754 -290.951085)
			(xy 427.251133 -290.926478) (xy 427.213012 -290.895353) (xy 427.180377 -290.858516) (xy 427.154074 -290.81692)
			(xy 427.134783 -290.771644) (xy 427.123006 -290.72386) (xy 427.119046 -290.674806) (xy 426.780198 -290.674806)
			(xy 426.779703 -290.699413) (xy 426.771808 -290.74799) (xy 426.756224 -290.794671) (xy 426.733353 -290.838248)
			(xy 426.703788 -290.877592) (xy 426.668295 -290.911684) (xy 426.627792 -290.93964) (xy 426.58333 -290.960738)
			(xy 426.536059 -290.97443) (xy 426.487204 -290.980362) (xy 426.438029 -290.978381) (xy 426.38981 -290.968537)
			(xy 426.343794 -290.951085) (xy 426.301173 -290.926478) (xy 426.263052 -290.895353) (xy 426.230417 -290.858516)
			(xy 426.204114 -290.81692) (xy 426.184823 -290.771644) (xy 426.173046 -290.72386) (xy 426.169086 -290.674806)
			(xy 425.830238 -290.674806) (xy 425.829743 -290.699413) (xy 425.821848 -290.74799) (xy 425.806264 -290.794671)
			(xy 425.783393 -290.838248) (xy 425.753828 -290.877592) (xy 425.718335 -290.911684) (xy 425.677832 -290.93964)
			(xy 425.63337 -290.960738) (xy 425.586099 -290.97443) (xy 425.537244 -290.980362) (xy 425.488069 -290.978381)
			(xy 425.43985 -290.968537) (xy 425.393834 -290.951085) (xy 425.351213 -290.926478) (xy 425.313092 -290.895353)
			(xy 425.280457 -290.858516) (xy 425.254154 -290.81692) (xy 425.234863 -290.771644) (xy 425.223086 -290.72386)
			(xy 425.219126 -290.674806) (xy 424.880278 -290.674806) (xy 424.879783 -290.699413) (xy 424.871888 -290.74799)
			(xy 424.856304 -290.794671) (xy 424.833433 -290.838248) (xy 424.803868 -290.877592) (xy 424.768375 -290.911684)
			(xy 424.727872 -290.93964) (xy 424.68341 -290.960738) (xy 424.636139 -290.97443) (xy 424.587284 -290.980362)
			(xy 424.538109 -290.978381) (xy 424.48989 -290.968537) (xy 424.443874 -290.951085) (xy 424.401253 -290.926478)
			(xy 424.363132 -290.895353) (xy 424.330497 -290.858516) (xy 424.304194 -290.81692) (xy 424.284903 -290.771644)
			(xy 424.273126 -290.72386) (xy 424.269166 -290.674806) (xy 423.930318 -290.674806) (xy 423.929823 -290.699413)
			(xy 423.921928 -290.74799) (xy 423.906344 -290.794671) (xy 423.883473 -290.838248) (xy 423.853908 -290.877592)
			(xy 423.818415 -290.911684) (xy 423.777912 -290.93964) (xy 423.73345 -290.960738) (xy 423.686179 -290.97443)
			(xy 423.637324 -290.980362) (xy 423.588149 -290.978381) (xy 423.53993 -290.968537) (xy 423.493914 -290.951085)
			(xy 423.451293 -290.926478) (xy 423.413172 -290.895353) (xy 423.380537 -290.858516) (xy 423.354234 -290.81692)
			(xy 423.334943 -290.771644) (xy 423.323166 -290.72386) (xy 423.319206 -290.674806) (xy 422.980104 -290.674806)
			(xy 422.979609 -290.699413) (xy 422.971714 -290.74799) (xy 422.95613 -290.794671) (xy 422.933259 -290.838248)
			(xy 422.903694 -290.877592) (xy 422.868201 -290.911684) (xy 422.827698 -290.93964) (xy 422.783236 -290.960738)
			(xy 422.735965 -290.97443) (xy 422.68711 -290.980362) (xy 422.637935 -290.978381) (xy 422.589716 -290.968537)
			(xy 422.5437 -290.951085) (xy 422.501079 -290.926478) (xy 422.462958 -290.895353) (xy 422.430323 -290.858516)
			(xy 422.40402 -290.81692) (xy 422.384729 -290.771644) (xy 422.372952 -290.72386) (xy 422.368992 -290.674806)
			(xy 422.030144 -290.674806) (xy 422.029649 -290.699413) (xy 422.021754 -290.74799) (xy 422.00617 -290.794671)
			(xy 421.983299 -290.838248) (xy 421.953734 -290.877592) (xy 421.918241 -290.911684) (xy 421.877738 -290.93964)
			(xy 421.833276 -290.960738) (xy 421.786005 -290.97443) (xy 421.73715 -290.980362) (xy 421.687975 -290.978381)
			(xy 421.639756 -290.968537) (xy 421.59374 -290.951085) (xy 421.551119 -290.926478) (xy 421.512998 -290.895353)
			(xy 421.480363 -290.858516) (xy 421.45406 -290.81692) (xy 421.434769 -290.771644) (xy 421.422992 -290.72386)
			(xy 421.419032 -290.674806) (xy 421.080184 -290.674806) (xy 421.079689 -290.699413) (xy 421.071794 -290.74799)
			(xy 421.05621 -290.794671) (xy 421.033339 -290.838248) (xy 421.003774 -290.877592) (xy 420.968281 -290.911684)
			(xy 420.927778 -290.93964) (xy 420.883316 -290.960738) (xy 420.836045 -290.97443) (xy 420.78719 -290.980362)
			(xy 420.738015 -290.978381) (xy 420.689796 -290.968537) (xy 420.64378 -290.951085) (xy 420.601159 -290.926478)
			(xy 420.563038 -290.895353) (xy 420.530403 -290.858516) (xy 420.5041 -290.81692) (xy 420.484809 -290.771644)
			(xy 420.473032 -290.72386) (xy 420.469072 -290.674806) (xy 420.130224 -290.674806) (xy 420.129729 -290.699413)
			(xy 420.121834 -290.74799) (xy 420.10625 -290.794671) (xy 420.083379 -290.838248) (xy 420.053814 -290.877592)
			(xy 420.018321 -290.911684) (xy 419.977818 -290.93964) (xy 419.933356 -290.960738) (xy 419.886085 -290.97443)
			(xy 419.83723 -290.980362) (xy 419.788055 -290.978381) (xy 419.739836 -290.968537) (xy 419.69382 -290.951085)
			(xy 419.651199 -290.926478) (xy 419.613078 -290.895353) (xy 419.580443 -290.858516) (xy 419.55414 -290.81692)
			(xy 419.534849 -290.771644) (xy 419.523072 -290.72386) (xy 419.519112 -290.674806) (xy 419.180264 -290.674806)
			(xy 419.179769 -290.699413) (xy 419.171874 -290.74799) (xy 419.15629 -290.794671) (xy 419.133419 -290.838248)
			(xy 419.103854 -290.877592) (xy 419.068361 -290.911684) (xy 419.027858 -290.93964) (xy 418.983396 -290.960738)
			(xy 418.936125 -290.97443) (xy 418.88727 -290.980362) (xy 418.838095 -290.978381) (xy 418.789876 -290.968537)
			(xy 418.74386 -290.951085) (xy 418.701239 -290.926478) (xy 418.663118 -290.895353) (xy 418.630483 -290.858516)
			(xy 418.60418 -290.81692) (xy 418.584889 -290.771644) (xy 418.573112 -290.72386) (xy 418.569152 -290.674806)
			(xy 418.231618 -290.674806) (xy 418.227436 -290.725268) (xy 418.215004 -290.774359) (xy 418.194661 -290.820735)
			(xy 418.166963 -290.86313) (xy 418.132665 -290.900387) (xy 418.092702 -290.931491) (xy 418.048164 -290.955593)
			(xy 418.000267 -290.972036) (xy 417.950316 -290.980371) (xy 417.924996 -290.980876) (xy 417.924742 -290.980876)
			(xy 417.897275 -290.980242) (xy 417.843227 -290.970408) (xy 417.8173 -290.961318) (xy 417.805616 -290.957)
			(xy 417.780978 -290.960048) (xy 417.702492 -291.01415) (xy 417.692828 -291.021765) (xy 417.681426 -291.043526)
			(xy 417.680648 -291.055806) (xy 417.680648 -291.238686) (xy 434.296564 -291.238686) (xy 434.300635 -291.183064)
			(xy 434.312761 -291.128627) (xy 434.332684 -291.076536) (xy 434.35998 -291.027901) (xy 434.394066 -290.983758)
			(xy 434.434215 -290.945049) (xy 434.479573 -290.912598) (xy 434.529173 -290.887097) (xy 434.581957 -290.86909)
			(xy 434.6368 -290.85896) (xy 434.692534 -290.856923) (xy 434.747971 -290.863023) (xy 434.801928 -290.877129)
			(xy 434.853257 -290.898941) (xy 434.900863 -290.927995) (xy 434.943731 -290.96367) (xy 434.980948 -291.005207)
			(xy 435.011721 -291.05172) (xy 435.035393 -291.102217) (xy 435.051461 -291.155624) (xy 435.059581 -291.2108)
			(xy 435.06009 -291.238686) (xy 435.059581 -291.266572) (xy 435.051461 -291.321748) (xy 435.035393 -291.375155)
			(xy 435.011721 -291.425652) (xy 434.980948 -291.472165) (xy 434.943731 -291.513702) (xy 434.900863 -291.549377)
			(xy 434.853257 -291.578431) (xy 434.821326 -291.592) (xy 436.741822 -291.592) (xy 436.745893 -291.536378)
			(xy 436.758019 -291.481941) (xy 436.777942 -291.42985) (xy 436.805238 -291.381215) (xy 436.839324 -291.337072)
			(xy 436.879473 -291.298363) (xy 436.924831 -291.265912) (xy 436.974431 -291.240411) (xy 437.027215 -291.222404)
			(xy 437.082058 -291.212274) (xy 437.137792 -291.210237) (xy 437.193229 -291.216337) (xy 437.247186 -291.230443)
			(xy 437.298515 -291.252255) (xy 437.346121 -291.281309) (xy 437.388989 -291.316984) (xy 437.426206 -291.358521)
			(xy 437.456979 -291.405034) (xy 437.480651 -291.455531) (xy 437.496719 -291.508938) (xy 437.504839 -291.564114)
			(xy 437.505348 -291.592) (xy 437.504839 -291.619886) (xy 437.496719 -291.675062) (xy 437.480651 -291.728469)
			(xy 437.456979 -291.778966) (xy 437.426206 -291.825479) (xy 437.388989 -291.867016) (xy 437.346121 -291.902691)
			(xy 437.298515 -291.931745) (xy 437.247186 -291.953557) (xy 437.193229 -291.967663) (xy 437.137792 -291.973763)
			(xy 437.082058 -291.971726) (xy 437.027215 -291.961596) (xy 436.974431 -291.943589) (xy 436.924831 -291.918088)
			(xy 436.879473 -291.885637) (xy 436.839324 -291.846928) (xy 436.805238 -291.802785) (xy 436.777942 -291.75415)
			(xy 436.758019 -291.702059) (xy 436.745893 -291.647622) (xy 436.741822 -291.592) (xy 434.821326 -291.592)
			(xy 434.801928 -291.600243) (xy 434.747971 -291.614349) (xy 434.692534 -291.620449) (xy 434.6368 -291.618412)
			(xy 434.581957 -291.608282) (xy 434.529173 -291.590275) (xy 434.479573 -291.564774) (xy 434.434215 -291.532323)
			(xy 434.394066 -291.493614) (xy 434.35998 -291.449471) (xy 434.332684 -291.400836) (xy 434.312761 -291.348745)
			(xy 434.300635 -291.294308) (xy 434.296564 -291.238686) (xy 417.680648 -291.238686) (xy 417.680648 -291.243766)
			(xy 417.68125 -291.256086) (xy 417.692715 -291.277897) (xy 417.702492 -291.285422) (xy 417.780978 -291.339524)
			(xy 417.805616 -291.342572) (xy 417.8173 -291.338254) (xy 417.843217 -291.329125) (xy 417.897271 -291.31928)
			(xy 417.924742 -291.318696) (xy 417.924996 -291.318696) (xy 417.95032 -291.31919) (xy 418.000277 -291.327525)
			(xy 418.04818 -291.34397) (xy 418.092724 -291.368075) (xy 418.132692 -291.399183) (xy 418.166995 -291.436446)
			(xy 418.194697 -291.478846) (xy 418.215042 -291.525228) (xy 418.227475 -291.574325) (xy 418.231655 -291.624766)
			(xy 418.569152 -291.624766) (xy 418.573112 -291.575712) (xy 418.584889 -291.527928) (xy 418.60418 -291.482652)
			(xy 418.630483 -291.441056) (xy 418.663118 -291.404219) (xy 418.701239 -291.373094) (xy 418.74386 -291.348487)
			(xy 418.789876 -291.331035) (xy 418.838095 -291.321191) (xy 418.88727 -291.31921) (xy 418.936125 -291.325142)
			(xy 418.983396 -291.338834) (xy 419.027858 -291.359932) (xy 419.068361 -291.387888) (xy 419.103854 -291.42198)
			(xy 419.133419 -291.461324) (xy 419.15629 -291.504901) (xy 419.171874 -291.551582) (xy 419.179769 -291.600159)
			(xy 419.180264 -291.624766) (xy 419.519112 -291.624766) (xy 419.523072 -291.575712) (xy 419.534849 -291.527928)
			(xy 419.55414 -291.482652) (xy 419.580443 -291.441056) (xy 419.613078 -291.404219) (xy 419.651199 -291.373094)
			(xy 419.69382 -291.348487) (xy 419.739836 -291.331035) (xy 419.788055 -291.321191) (xy 419.83723 -291.31921)
			(xy 419.886085 -291.325142) (xy 419.933356 -291.338834) (xy 419.977818 -291.359932) (xy 420.018321 -291.387888)
			(xy 420.053814 -291.42198) (xy 420.083379 -291.461324) (xy 420.10625 -291.504901) (xy 420.121834 -291.551582)
			(xy 420.129729 -291.600159) (xy 420.130224 -291.624766) (xy 420.469072 -291.624766) (xy 420.473032 -291.575712)
			(xy 420.484809 -291.527928) (xy 420.5041 -291.482652) (xy 420.530403 -291.441056) (xy 420.563038 -291.404219)
			(xy 420.601159 -291.373094) (xy 420.64378 -291.348487) (xy 420.689796 -291.331035) (xy 420.738015 -291.321191)
			(xy 420.78719 -291.31921) (xy 420.836045 -291.325142) (xy 420.883316 -291.338834) (xy 420.927778 -291.359932)
			(xy 420.968281 -291.387888) (xy 421.003774 -291.42198) (xy 421.033339 -291.461324) (xy 421.05621 -291.504901)
			(xy 421.071794 -291.551582) (xy 421.079689 -291.600159) (xy 421.080184 -291.624766) (xy 421.419032 -291.624766)
			(xy 421.422992 -291.575712) (xy 421.434769 -291.527928) (xy 421.45406 -291.482652) (xy 421.480363 -291.441056)
			(xy 421.512998 -291.404219) (xy 421.551119 -291.373094) (xy 421.59374 -291.348487) (xy 421.639756 -291.331035)
			(xy 421.687975 -291.321191) (xy 421.73715 -291.31921) (xy 421.786005 -291.325142) (xy 421.833276 -291.338834)
			(xy 421.877738 -291.359932) (xy 421.918241 -291.387888) (xy 421.953734 -291.42198) (xy 421.983299 -291.461324)
			(xy 422.00617 -291.504901) (xy 422.021754 -291.551582) (xy 422.029649 -291.600159) (xy 422.030144 -291.624766)
			(xy 422.369246 -291.624766) (xy 422.373206 -291.575712) (xy 422.384983 -291.527928) (xy 422.404274 -291.482652)
			(xy 422.430577 -291.441056) (xy 422.463212 -291.404219) (xy 422.501333 -291.373094) (xy 422.543954 -291.348487)
			(xy 422.58997 -291.331035) (xy 422.638189 -291.321191) (xy 422.687364 -291.31921) (xy 422.736219 -291.325142)
			(xy 422.78349 -291.338834) (xy 422.827952 -291.359932) (xy 422.868455 -291.387888) (xy 422.903948 -291.42198)
			(xy 422.933513 -291.461324) (xy 422.956384 -291.504901) (xy 422.971968 -291.551582) (xy 422.979863 -291.600159)
			(xy 422.980358 -291.624766) (xy 424.269166 -291.624766) (xy 424.273126 -291.575712) (xy 424.284903 -291.527928)
			(xy 424.304194 -291.482652) (xy 424.330497 -291.441056) (xy 424.363132 -291.404219) (xy 424.401253 -291.373094)
			(xy 424.443874 -291.348487) (xy 424.48989 -291.331035) (xy 424.538109 -291.321191) (xy 424.587284 -291.31921)
			(xy 424.636139 -291.325142) (xy 424.68341 -291.338834) (xy 424.727872 -291.359932) (xy 424.768375 -291.387888)
			(xy 424.803868 -291.42198) (xy 424.833433 -291.461324) (xy 424.856304 -291.504901) (xy 424.871888 -291.551582)
			(xy 424.879783 -291.600159) (xy 424.880278 -291.624766) (xy 425.219126 -291.624766) (xy 425.223086 -291.575712)
			(xy 425.234863 -291.527928) (xy 425.254154 -291.482652) (xy 425.280457 -291.441056) (xy 425.313092 -291.404219)
			(xy 425.351213 -291.373094) (xy 425.393834 -291.348487) (xy 425.43985 -291.331035) (xy 425.488069 -291.321191)
			(xy 425.537244 -291.31921) (xy 425.586099 -291.325142) (xy 425.63337 -291.338834) (xy 425.677832 -291.359932)
			(xy 425.718335 -291.387888) (xy 425.753828 -291.42198) (xy 425.783393 -291.461324) (xy 425.806264 -291.504901)
			(xy 425.821848 -291.551582) (xy 425.829743 -291.600159) (xy 425.830238 -291.624766) (xy 426.169086 -291.624766)
			(xy 426.173046 -291.575712) (xy 426.184823 -291.527928) (xy 426.204114 -291.482652) (xy 426.230417 -291.441056)
			(xy 426.263052 -291.404219) (xy 426.301173 -291.373094) (xy 426.343794 -291.348487) (xy 426.38981 -291.331035)
			(xy 426.438029 -291.321191) (xy 426.487204 -291.31921) (xy 426.536059 -291.325142) (xy 426.58333 -291.338834)
			(xy 426.627792 -291.359932) (xy 426.668295 -291.387888) (xy 426.703788 -291.42198) (xy 426.733353 -291.461324)
			(xy 426.756224 -291.504901) (xy 426.771808 -291.551582) (xy 426.779703 -291.600159) (xy 426.780198 -291.624766)
			(xy 427.119046 -291.624766) (xy 427.123006 -291.575712) (xy 427.134783 -291.527928) (xy 427.154074 -291.482652)
			(xy 427.180377 -291.441056) (xy 427.213012 -291.404219) (xy 427.251133 -291.373094) (xy 427.293754 -291.348487)
			(xy 427.33977 -291.331035) (xy 427.387989 -291.321191) (xy 427.437164 -291.31921) (xy 427.486019 -291.325142)
			(xy 427.53329 -291.338834) (xy 427.577752 -291.359932) (xy 427.618255 -291.387888) (xy 427.653748 -291.42198)
			(xy 427.683313 -291.461324) (xy 427.706184 -291.504901) (xy 427.721768 -291.551582) (xy 427.729663 -291.600159)
			(xy 427.730158 -291.624766) (xy 428.069006 -291.624766) (xy 428.072966 -291.575712) (xy 428.084743 -291.527928)
			(xy 428.104034 -291.482652) (xy 428.130337 -291.441056) (xy 428.162972 -291.404219) (xy 428.201093 -291.373094)
			(xy 428.243714 -291.348487) (xy 428.28973 -291.331035) (xy 428.337949 -291.321191) (xy 428.387124 -291.31921)
			(xy 428.435979 -291.325142) (xy 428.48325 -291.338834) (xy 428.527712 -291.359932) (xy 428.568215 -291.387888)
			(xy 428.603708 -291.42198) (xy 428.633273 -291.461324) (xy 428.656144 -291.504901) (xy 428.671728 -291.551582)
			(xy 428.679623 -291.600159) (xy 428.680118 -291.624766) (xy 429.01922 -291.624766) (xy 429.02318 -291.575712)
			(xy 429.034957 -291.527928) (xy 429.054248 -291.482652) (xy 429.080551 -291.441056) (xy 429.113186 -291.404219)
			(xy 429.151307 -291.373094) (xy 429.193928 -291.348487) (xy 429.239944 -291.331035) (xy 429.288163 -291.321191)
			(xy 429.337338 -291.31921) (xy 429.386193 -291.325142) (xy 429.433464 -291.338834) (xy 429.477926 -291.359932)
			(xy 429.518429 -291.387888) (xy 429.553922 -291.42198) (xy 429.583487 -291.461324) (xy 429.606358 -291.504901)
			(xy 429.621942 -291.551582) (xy 429.629837 -291.600159) (xy 429.630332 -291.624766) (xy 429.96918 -291.624766)
			(xy 429.97314 -291.575712) (xy 429.984917 -291.527928) (xy 430.004208 -291.482652) (xy 430.030511 -291.441056)
			(xy 430.063146 -291.404219) (xy 430.101267 -291.373094) (xy 430.143888 -291.348487) (xy 430.189904 -291.331035)
			(xy 430.238123 -291.321191) (xy 430.287298 -291.31921) (xy 430.336153 -291.325142) (xy 430.383424 -291.338834)
			(xy 430.427886 -291.359932) (xy 430.468389 -291.387888) (xy 430.503882 -291.42198) (xy 430.533447 -291.461324)
			(xy 430.556318 -291.504901) (xy 430.571902 -291.551582) (xy 430.579797 -291.600159) (xy 430.580292 -291.624766)
			(xy 430.91914 -291.624766) (xy 430.9231 -291.575712) (xy 430.934877 -291.527928) (xy 430.954168 -291.482652)
			(xy 430.980471 -291.441056) (xy 431.013106 -291.404219) (xy 431.051227 -291.373094) (xy 431.093848 -291.348487)
			(xy 431.139864 -291.331035) (xy 431.188083 -291.321191) (xy 431.237258 -291.31921) (xy 431.286113 -291.325142)
			(xy 431.333384 -291.338834) (xy 431.377846 -291.359932) (xy 431.418349 -291.387888) (xy 431.453842 -291.42198)
			(xy 431.483407 -291.461324) (xy 431.506278 -291.504901) (xy 431.521862 -291.551582) (xy 431.529757 -291.600159)
			(xy 431.530252 -291.624766) (xy 431.529757 -291.649373) (xy 431.521862 -291.69795) (xy 431.506278 -291.744631)
			(xy 431.483407 -291.788208) (xy 431.453842 -291.827552) (xy 431.418349 -291.861644) (xy 431.377846 -291.8896)
			(xy 431.333384 -291.910698) (xy 431.286113 -291.92439) (xy 431.237258 -291.930322) (xy 431.188083 -291.928341)
			(xy 431.139864 -291.918497) (xy 431.093848 -291.901045) (xy 431.051227 -291.876438) (xy 431.013106 -291.845313)
			(xy 430.980471 -291.808476) (xy 430.954168 -291.76688) (xy 430.934877 -291.721604) (xy 430.9231 -291.67382)
			(xy 430.91914 -291.624766) (xy 430.580292 -291.624766) (xy 430.579797 -291.649373) (xy 430.571902 -291.69795)
			(xy 430.556318 -291.744631) (xy 430.533447 -291.788208) (xy 430.503882 -291.827552) (xy 430.468389 -291.861644)
			(xy 430.427886 -291.8896) (xy 430.383424 -291.910698) (xy 430.336153 -291.92439) (xy 430.287298 -291.930322)
			(xy 430.238123 -291.928341) (xy 430.189904 -291.918497) (xy 430.143888 -291.901045) (xy 430.101267 -291.876438)
			(xy 430.063146 -291.845313) (xy 430.030511 -291.808476) (xy 430.004208 -291.76688) (xy 429.984917 -291.721604)
			(xy 429.97314 -291.67382) (xy 429.96918 -291.624766) (xy 429.630332 -291.624766) (xy 429.629837 -291.649373)
			(xy 429.621942 -291.69795) (xy 429.606358 -291.744631) (xy 429.583487 -291.788208) (xy 429.553922 -291.827552)
			(xy 429.518429 -291.861644) (xy 429.477926 -291.8896) (xy 429.433464 -291.910698) (xy 429.386193 -291.92439)
			(xy 429.337338 -291.930322) (xy 429.288163 -291.928341) (xy 429.239944 -291.918497) (xy 429.193928 -291.901045)
			(xy 429.151307 -291.876438) (xy 429.113186 -291.845313) (xy 429.080551 -291.808476) (xy 429.054248 -291.76688)
			(xy 429.034957 -291.721604) (xy 429.02318 -291.67382) (xy 429.01922 -291.624766) (xy 428.680118 -291.624766)
			(xy 428.679623 -291.649373) (xy 428.671728 -291.69795) (xy 428.656144 -291.744631) (xy 428.633273 -291.788208)
			(xy 428.603708 -291.827552) (xy 428.568215 -291.861644) (xy 428.527712 -291.8896) (xy 428.48325 -291.910698)
			(xy 428.435979 -291.92439) (xy 428.387124 -291.930322) (xy 428.337949 -291.928341) (xy 428.28973 -291.918497)
			(xy 428.243714 -291.901045) (xy 428.201093 -291.876438) (xy 428.162972 -291.845313) (xy 428.130337 -291.808476)
			(xy 428.104034 -291.76688) (xy 428.084743 -291.721604) (xy 428.072966 -291.67382) (xy 428.069006 -291.624766)
			(xy 427.730158 -291.624766) (xy 427.729663 -291.649373) (xy 427.721768 -291.69795) (xy 427.706184 -291.744631)
			(xy 427.683313 -291.788208) (xy 427.653748 -291.827552) (xy 427.618255 -291.861644) (xy 427.577752 -291.8896)
			(xy 427.53329 -291.910698) (xy 427.486019 -291.92439) (xy 427.437164 -291.930322) (xy 427.387989 -291.928341)
			(xy 427.33977 -291.918497) (xy 427.293754 -291.901045) (xy 427.251133 -291.876438) (xy 427.213012 -291.845313)
			(xy 427.180377 -291.808476) (xy 427.154074 -291.76688) (xy 427.134783 -291.721604) (xy 427.123006 -291.67382)
			(xy 427.119046 -291.624766) (xy 426.780198 -291.624766) (xy 426.779703 -291.649373) (xy 426.771808 -291.69795)
			(xy 426.756224 -291.744631) (xy 426.733353 -291.788208) (xy 426.703788 -291.827552) (xy 426.668295 -291.861644)
			(xy 426.627792 -291.8896) (xy 426.58333 -291.910698) (xy 426.536059 -291.92439) (xy 426.487204 -291.930322)
			(xy 426.438029 -291.928341) (xy 426.38981 -291.918497) (xy 426.343794 -291.901045) (xy 426.301173 -291.876438)
			(xy 426.263052 -291.845313) (xy 426.230417 -291.808476) (xy 426.204114 -291.76688) (xy 426.184823 -291.721604)
			(xy 426.173046 -291.67382) (xy 426.169086 -291.624766) (xy 425.830238 -291.624766) (xy 425.829743 -291.649373)
			(xy 425.821848 -291.69795) (xy 425.806264 -291.744631) (xy 425.783393 -291.788208) (xy 425.753828 -291.827552)
			(xy 425.718335 -291.861644) (xy 425.677832 -291.8896) (xy 425.63337 -291.910698) (xy 425.586099 -291.92439)
			(xy 425.537244 -291.930322) (xy 425.488069 -291.928341) (xy 425.43985 -291.918497) (xy 425.393834 -291.901045)
			(xy 425.351213 -291.876438) (xy 425.313092 -291.845313) (xy 425.280457 -291.808476) (xy 425.254154 -291.76688)
			(xy 425.234863 -291.721604) (xy 425.223086 -291.67382) (xy 425.219126 -291.624766) (xy 424.880278 -291.624766)
			(xy 424.879783 -291.649373) (xy 424.871888 -291.69795) (xy 424.856304 -291.744631) (xy 424.833433 -291.788208)
			(xy 424.803868 -291.827552) (xy 424.768375 -291.861644) (xy 424.727872 -291.8896) (xy 424.68341 -291.910698)
			(xy 424.636139 -291.92439) (xy 424.587284 -291.930322) (xy 424.538109 -291.928341) (xy 424.48989 -291.918497)
			(xy 424.443874 -291.901045) (xy 424.401253 -291.876438) (xy 424.363132 -291.845313) (xy 424.330497 -291.808476)
			(xy 424.304194 -291.76688) (xy 424.284903 -291.721604) (xy 424.273126 -291.67382) (xy 424.269166 -291.624766)
			(xy 422.980358 -291.624766) (xy 422.979863 -291.649373) (xy 422.971968 -291.69795) (xy 422.956384 -291.744631)
			(xy 422.933513 -291.788208) (xy 422.903948 -291.827552) (xy 422.868455 -291.861644) (xy 422.827952 -291.8896)
			(xy 422.78349 -291.910698) (xy 422.736219 -291.92439) (xy 422.687364 -291.930322) (xy 422.638189 -291.928341)
			(xy 422.58997 -291.918497) (xy 422.543954 -291.901045) (xy 422.501333 -291.876438) (xy 422.463212 -291.845313)
			(xy 422.430577 -291.808476) (xy 422.404274 -291.76688) (xy 422.384983 -291.721604) (xy 422.373206 -291.67382)
			(xy 422.369246 -291.624766) (xy 422.030144 -291.624766) (xy 422.029649 -291.649373) (xy 422.021754 -291.69795)
			(xy 422.00617 -291.744631) (xy 421.983299 -291.788208) (xy 421.953734 -291.827552) (xy 421.918241 -291.861644)
			(xy 421.877738 -291.8896) (xy 421.833276 -291.910698) (xy 421.786005 -291.92439) (xy 421.73715 -291.930322)
			(xy 421.687975 -291.928341) (xy 421.639756 -291.918497) (xy 421.59374 -291.901045) (xy 421.551119 -291.876438)
			(xy 421.512998 -291.845313) (xy 421.480363 -291.808476) (xy 421.45406 -291.76688) (xy 421.434769 -291.721604)
			(xy 421.422992 -291.67382) (xy 421.419032 -291.624766) (xy 421.080184 -291.624766) (xy 421.079689 -291.649373)
			(xy 421.071794 -291.69795) (xy 421.05621 -291.744631) (xy 421.033339 -291.788208) (xy 421.003774 -291.827552)
			(xy 420.968281 -291.861644) (xy 420.927778 -291.8896) (xy 420.883316 -291.910698) (xy 420.836045 -291.92439)
			(xy 420.78719 -291.930322) (xy 420.738015 -291.928341) (xy 420.689796 -291.918497) (xy 420.64378 -291.901045)
			(xy 420.601159 -291.876438) (xy 420.563038 -291.845313) (xy 420.530403 -291.808476) (xy 420.5041 -291.76688)
			(xy 420.484809 -291.721604) (xy 420.473032 -291.67382) (xy 420.469072 -291.624766) (xy 420.130224 -291.624766)
			(xy 420.129729 -291.649373) (xy 420.121834 -291.69795) (xy 420.10625 -291.744631) (xy 420.083379 -291.788208)
			(xy 420.053814 -291.827552) (xy 420.018321 -291.861644) (xy 419.977818 -291.8896) (xy 419.933356 -291.910698)
			(xy 419.886085 -291.92439) (xy 419.83723 -291.930322) (xy 419.788055 -291.928341) (xy 419.739836 -291.918497)
			(xy 419.69382 -291.901045) (xy 419.651199 -291.876438) (xy 419.613078 -291.845313) (xy 419.580443 -291.808476)
			(xy 419.55414 -291.76688) (xy 419.534849 -291.721604) (xy 419.523072 -291.67382) (xy 419.519112 -291.624766)
			(xy 419.180264 -291.624766) (xy 419.179769 -291.649373) (xy 419.171874 -291.69795) (xy 419.15629 -291.744631)
			(xy 419.133419 -291.788208) (xy 419.103854 -291.827552) (xy 419.068361 -291.861644) (xy 419.027858 -291.8896)
			(xy 418.983396 -291.910698) (xy 418.936125 -291.92439) (xy 418.88727 -291.930322) (xy 418.838095 -291.928341)
			(xy 418.789876 -291.918497) (xy 418.74386 -291.901045) (xy 418.701239 -291.876438) (xy 418.663118 -291.845313)
			(xy 418.630483 -291.808476) (xy 418.60418 -291.76688) (xy 418.584889 -291.721604) (xy 418.573112 -291.67382)
			(xy 418.569152 -291.624766) (xy 418.231655 -291.624766) (xy 418.231658 -291.6248) (xy 418.227475 -291.675275)
			(xy 418.215042 -291.724372) (xy 418.194697 -291.770754) (xy 418.166995 -291.813154) (xy 418.132692 -291.850417)
			(xy 418.092724 -291.881525) (xy 418.04818 -291.90563) (xy 418.000277 -291.922075) (xy 417.95032 -291.93041)
			(xy 417.924996 -291.930836) (xy 417.924742 -291.930836) (xy 417.897275 -291.930202) (xy 417.843226 -291.92037)
			(xy 417.8173 -291.911278) (xy 417.805616 -291.90696) (xy 417.780978 -291.910008) (xy 417.702492 -291.96411)
			(xy 417.692821 -291.971723) (xy 417.681403 -291.993482) (xy 417.680648 -292.005766) (xy 417.680648 -292.122098)
			(xy 441.55741 -292.122098) (xy 441.557853 -292.095494) (xy 441.565235 -292.0428) (xy 441.57987 -291.991644)
			(xy 441.601474 -291.943019) (xy 441.629626 -291.897869) (xy 441.663781 -291.85707) (xy 441.703276 -291.821415)
			(xy 441.72505 -291.806122) (xy 441.736488 -291.797731) (xy 441.754699 -291.776003) (xy 441.766224 -291.750101)
			(xy 441.770172 -291.722027) (xy 441.766239 -291.693951) (xy 441.754727 -291.668043) (xy 441.736528 -291.646305)
			(xy 441.72505 -291.637974) (xy 441.703261 -291.622704) (xy 441.663782 -291.587034) (xy 441.62964 -291.546226)
			(xy 441.601496 -291.501072) (xy 441.579897 -291.452447) (xy 441.565261 -291.401293) (xy 441.557871 -291.348601)
			(xy 441.55741 -291.321998) (xy 441.557896 -291.294747) (xy 441.565652 -291.240799) (xy 441.581007 -291.188504)
			(xy 441.603649 -291.138927) (xy 441.633115 -291.093077) (xy 441.668806 -291.051886) (xy 441.709997 -291.016195)
			(xy 441.755847 -290.986729) (xy 441.805424 -290.964087) (xy 441.857719 -290.948732) (xy 441.911667 -290.940976)
			(xy 441.966169 -290.940976) (xy 442.020117 -290.948732) (xy 442.072412 -290.964087) (xy 442.121989 -290.986729)
			(xy 442.167839 -291.016195) (xy 442.20903 -291.051886) (xy 442.244721 -291.093077) (xy 442.274187 -291.138927)
			(xy 442.296829 -291.188504) (xy 442.312184 -291.240799) (xy 442.31994 -291.294747) (xy 442.320426 -291.321998)
			(xy 442.320008 -291.348603) (xy 442.312625 -291.401299) (xy 442.297988 -291.452457) (xy 442.276381 -291.501083)
			(xy 442.248224 -291.546233) (xy 442.224928 -291.574056) (xy 450.443243 -291.574056) (xy 450.443243 -291.519544)
			(xy 450.451001 -291.465587) (xy 450.46636 -291.413284) (xy 450.489007 -291.363699) (xy 450.51848 -291.317843)
			(xy 450.55418 -291.276647) (xy 450.595379 -291.240953) (xy 450.64124 -291.211485) (xy 450.690827 -291.188844)
			(xy 450.743132 -291.173492) (xy 450.79709 -291.16574) (xy 450.824346 -291.16528) (xy 450.851716 -291.165758)
			(xy 450.905895 -291.17357) (xy 450.958399 -291.189055) (xy 451.008146 -291.211895) (xy 451.054113 -291.241619)
			(xy 451.075044 -291.25926) (xy 451.082156 -291.265356) (xy 451.099174 -291.271706) (xy 451.184518 -291.271706)
			(xy 451.201536 -291.265356) (xy 451.208648 -291.25926) (xy 451.229583 -291.241625) (xy 451.275556 -291.211914)
			(xy 451.325303 -291.189078) (xy 451.377802 -291.173585) (xy 451.431977 -291.165755) (xy 451.459346 -291.16528)
			(xy 451.486594 -291.165793) (xy 451.540535 -291.173555) (xy 451.592823 -291.188914) (xy 451.642393 -291.211557)
			(xy 451.688236 -291.241023) (xy 451.729419 -291.276714) (xy 451.765104 -291.317901) (xy 451.794565 -291.363748)
			(xy 451.817203 -291.41332) (xy 451.832555 -291.46561) (xy 451.84031 -291.519552) (xy 451.84031 -291.574048)
			(xy 451.840309 -291.574054) (xy 452.196643 -291.574054) (xy 452.196643 -291.519546) (xy 452.2044 -291.465593)
			(xy 452.219757 -291.413292) (xy 452.242401 -291.36371) (xy 452.271871 -291.317855) (xy 452.307566 -291.276661)
			(xy 452.348761 -291.240966) (xy 452.394617 -291.211497) (xy 452.4442 -291.188854) (xy 452.4965 -291.173499)
			(xy 452.550454 -291.165742) (xy 452.577708 -291.16528) (xy 452.605079 -291.165722) (xy 452.65926 -291.173543)
			(xy 452.711764 -291.189036) (xy 452.761511 -291.211884) (xy 452.807476 -291.241615) (xy 452.828406 -291.25926)
			(xy 452.835518 -291.265356) (xy 452.852536 -291.271706) (xy 452.93788 -291.271706) (xy 452.954898 -291.265356)
			(xy 452.96201 -291.25926) (xy 452.982922 -291.241596) (xy 453.028901 -291.211889) (xy 453.078654 -291.189059)
			(xy 453.131158 -291.173573) (xy 453.185338 -291.165751) (xy 453.212708 -291.16528) (xy 453.239958 -291.165791)
			(xy 453.293903 -291.173548) (xy 453.346195 -291.188903) (xy 453.39577 -291.211544) (xy 453.441618 -291.24101)
			(xy 453.482806 -291.2767) (xy 453.518495 -291.317889) (xy 453.54796 -291.363737) (xy 453.5706 -291.413312)
			(xy 453.585954 -291.465605) (xy 453.59371 -291.51955) (xy 453.59371 -291.57405) (xy 453.585954 -291.627995)
			(xy 453.5706 -291.680288) (xy 453.54796 -291.729863) (xy 453.518495 -291.775711) (xy 453.482806 -291.8169)
			(xy 453.441618 -291.85259) (xy 453.39577 -291.882056) (xy 453.346195 -291.904697) (xy 453.293903 -291.920052)
			(xy 453.239958 -291.927809) (xy 453.212708 -291.928296) (xy 453.185338 -291.927826) (xy 453.131159 -291.920009)
			(xy 453.078656 -291.904521) (xy 453.028909 -291.88168) (xy 452.982942 -291.851957) (xy 452.96201 -291.834316)
			(xy 452.954898 -291.82822) (xy 452.93788 -291.82187) (xy 452.852536 -291.82187) (xy 452.835518 -291.82822)
			(xy 452.828406 -291.834316) (xy 452.807485 -291.851968) (xy 452.761509 -291.881678) (xy 452.711758 -291.904511)
			(xy 452.659255 -291.919999) (xy 452.605078 -291.927824) (xy 452.577708 -291.928296) (xy 452.550454 -291.927858)
			(xy 452.4965 -291.920101) (xy 452.4442 -291.904746) (xy 452.394617 -291.882103) (xy 452.348761 -291.852634)
			(xy 452.307566 -291.816939) (xy 452.271871 -291.775745) (xy 452.242401 -291.72989) (xy 452.219757 -291.680308)
			(xy 452.2044 -291.628007) (xy 452.196643 -291.574054) (xy 451.840309 -291.574054) (xy 451.832555 -291.62799)
			(xy 451.817203 -291.68028) (xy 451.794565 -291.729852) (xy 451.765104 -291.775699) (xy 451.729419 -291.816886)
			(xy 451.688236 -291.852577) (xy 451.642393 -291.882043) (xy 451.592823 -291.904686) (xy 451.540535 -291.920045)
			(xy 451.486594 -291.927807) (xy 451.459346 -291.928296) (xy 451.431977 -291.927804) (xy 451.377799 -291.919993)
			(xy 451.325296 -291.90451) (xy 451.275549 -291.881674) (xy 451.229581 -291.851955) (xy 451.208648 -291.834316)
			(xy 451.201536 -291.82822) (xy 451.184518 -291.82187) (xy 451.099174 -291.82187) (xy 451.082156 -291.82822)
			(xy 451.075044 -291.834316) (xy 451.054108 -291.85195) (xy 451.008136 -291.881662) (xy 450.95839 -291.904499)
			(xy 450.90589 -291.919991) (xy 450.851715 -291.927821) (xy 450.824346 -291.928296) (xy 450.79709 -291.92786)
			(xy 450.743132 -291.920108) (xy 450.690827 -291.904756) (xy 450.64124 -291.882115) (xy 450.595379 -291.852647)
			(xy 450.55418 -291.816953) (xy 450.51848 -291.775757) (xy 450.489007 -291.729901) (xy 450.46636 -291.680316)
			(xy 450.451001 -291.628013) (xy 450.443243 -291.574056) (xy 442.224928 -291.574056) (xy 442.214064 -291.587031)
			(xy 442.174563 -291.622683) (xy 442.152786 -291.637974) (xy 442.141261 -291.64625) (xy 442.123058 -291.668007)
			(xy 442.111546 -291.693934) (xy 442.107612 -291.722027) (xy 442.11156 -291.750118) (xy 442.123087 -291.776039)
			(xy 442.141301 -291.797786) (xy 442.152786 -291.806122) (xy 442.174581 -291.821383) (xy 442.214058 -291.857056)
			(xy 442.248199 -291.897866) (xy 442.276341 -291.943021) (xy 442.297939 -291.991648) (xy 442.312575 -292.042803)
			(xy 442.319965 -292.095494) (xy 442.320426 -292.122098) (xy 442.31994 -292.149349) (xy 442.312184 -292.203297)
			(xy 442.296829 -292.255592) (xy 442.274187 -292.305169) (xy 442.244721 -292.351019) (xy 442.20903 -292.39221)
			(xy 442.167839 -292.427901) (xy 442.121989 -292.457367) (xy 442.072412 -292.480009) (xy 442.020117 -292.495364)
			(xy 441.966169 -292.50312) (xy 441.911667 -292.50312) (xy 441.857719 -292.495364) (xy 441.805424 -292.480009)
			(xy 441.755847 -292.457367) (xy 441.709997 -292.427901) (xy 441.668806 -292.39221) (xy 441.633115 -292.351019)
			(xy 441.603649 -292.305169) (xy 441.581007 -292.255592) (xy 441.565652 -292.203297) (xy 441.557896 -292.149349)
			(xy 441.55741 -292.122098) (xy 417.680648 -292.122098) (xy 417.680648 -292.193726) (xy 417.681241 -292.206051)
			(xy 417.692697 -292.227876) (xy 417.702492 -292.235382) (xy 417.780978 -292.289484) (xy 417.805616 -292.292532)
			(xy 417.8173 -292.288214) (xy 417.843217 -292.279086) (xy 417.897271 -292.269242) (xy 417.924742 -292.268656)
			(xy 417.924996 -292.268656) (xy 417.950315 -292.269149) (xy 418.000262 -292.277483) (xy 418.048156 -292.293925)
			(xy 418.092691 -292.318025) (xy 418.132651 -292.349127) (xy 418.166947 -292.386383) (xy 418.194644 -292.428775)
			(xy 418.214985 -292.475147) (xy 418.227416 -292.524235) (xy 418.231598 -292.5747) (xy 418.231575 -292.57498)
			(xy 418.569152 -292.57498) (xy 418.573112 -292.525926) (xy 418.584889 -292.478142) (xy 418.60418 -292.432866)
			(xy 418.630483 -292.39127) (xy 418.663118 -292.354433) (xy 418.701239 -292.323308) (xy 418.74386 -292.298701)
			(xy 418.789876 -292.281249) (xy 418.838095 -292.271405) (xy 418.88727 -292.269424) (xy 418.936125 -292.275356)
			(xy 418.983396 -292.289048) (xy 419.027858 -292.310146) (xy 419.068361 -292.338102) (xy 419.103854 -292.372194)
			(xy 419.133419 -292.411538) (xy 419.15629 -292.455115) (xy 419.171874 -292.501796) (xy 419.179769 -292.550373)
			(xy 419.180259 -292.574726) (xy 419.519112 -292.574726) (xy 419.523072 -292.525672) (xy 419.534849 -292.477888)
			(xy 419.55414 -292.432612) (xy 419.580443 -292.391016) (xy 419.613078 -292.354179) (xy 419.651199 -292.323054)
			(xy 419.69382 -292.298447) (xy 419.739836 -292.280995) (xy 419.788055 -292.271151) (xy 419.83723 -292.26917)
			(xy 419.886085 -292.275102) (xy 419.933356 -292.288794) (xy 419.977818 -292.309892) (xy 420.018321 -292.337848)
			(xy 420.053814 -292.37194) (xy 420.083379 -292.411284) (xy 420.10625 -292.454861) (xy 420.121834 -292.501542)
			(xy 420.129729 -292.550119) (xy 420.130224 -292.574726) (xy 420.469072 -292.574726) (xy 420.473032 -292.525672)
			(xy 420.484809 -292.477888) (xy 420.5041 -292.432612) (xy 420.530403 -292.391016) (xy 420.563038 -292.354179)
			(xy 420.601159 -292.323054) (xy 420.64378 -292.298447) (xy 420.689796 -292.280995) (xy 420.738015 -292.271151)
			(xy 420.78719 -292.26917) (xy 420.836045 -292.275102) (xy 420.883316 -292.288794) (xy 420.927778 -292.309892)
			(xy 420.968281 -292.337848) (xy 421.003774 -292.37194) (xy 421.033339 -292.411284) (xy 421.05621 -292.454861)
			(xy 421.071794 -292.501542) (xy 421.079689 -292.550119) (xy 421.080184 -292.574726) (xy 421.419032 -292.574726)
			(xy 421.422992 -292.525672) (xy 421.434769 -292.477888) (xy 421.45406 -292.432612) (xy 421.480363 -292.391016)
			(xy 421.512998 -292.354179) (xy 421.551119 -292.323054) (xy 421.59374 -292.298447) (xy 421.639756 -292.280995)
			(xy 421.687975 -292.271151) (xy 421.73715 -292.26917) (xy 421.786005 -292.275102) (xy 421.833276 -292.288794)
			(xy 421.877738 -292.309892) (xy 421.918241 -292.337848) (xy 421.953734 -292.37194) (xy 421.983299 -292.411284)
			(xy 422.00617 -292.454861) (xy 422.021754 -292.501542) (xy 422.029649 -292.550119) (xy 422.030144 -292.574726)
			(xy 422.368992 -292.574726) (xy 422.372952 -292.525672) (xy 422.384729 -292.477888) (xy 422.40402 -292.432612)
			(xy 422.430323 -292.391016) (xy 422.462958 -292.354179) (xy 422.501079 -292.323054) (xy 422.5437 -292.298447)
			(xy 422.589716 -292.280995) (xy 422.637935 -292.271151) (xy 422.68711 -292.26917) (xy 422.735965 -292.275102)
			(xy 422.783236 -292.288794) (xy 422.827698 -292.309892) (xy 422.868201 -292.337848) (xy 422.903694 -292.37194)
			(xy 422.933259 -292.411284) (xy 422.95613 -292.454861) (xy 422.971714 -292.501542) (xy 422.979609 -292.550119)
			(xy 422.980104 -292.574726) (xy 423.319206 -292.574726) (xy 423.323166 -292.525672) (xy 423.334943 -292.477888)
			(xy 423.354234 -292.432612) (xy 423.380537 -292.391016) (xy 423.413172 -292.354179) (xy 423.451293 -292.323054)
			(xy 423.493914 -292.298447) (xy 423.53993 -292.280995) (xy 423.588149 -292.271151) (xy 423.637324 -292.26917)
			(xy 423.686179 -292.275102) (xy 423.73345 -292.288794) (xy 423.777912 -292.309892) (xy 423.818415 -292.337848)
			(xy 423.853908 -292.37194) (xy 423.883473 -292.411284) (xy 423.906344 -292.454861) (xy 423.921928 -292.501542)
			(xy 423.929823 -292.550119) (xy 423.930318 -292.574726) (xy 424.269166 -292.574726) (xy 424.273126 -292.525672)
			(xy 424.284903 -292.477888) (xy 424.304194 -292.432612) (xy 424.330497 -292.391016) (xy 424.363132 -292.354179)
			(xy 424.401253 -292.323054) (xy 424.443874 -292.298447) (xy 424.48989 -292.280995) (xy 424.538109 -292.271151)
			(xy 424.587284 -292.26917) (xy 424.636139 -292.275102) (xy 424.68341 -292.288794) (xy 424.727872 -292.309892)
			(xy 424.768375 -292.337848) (xy 424.803868 -292.37194) (xy 424.833433 -292.411284) (xy 424.856304 -292.454861)
			(xy 424.871888 -292.501542) (xy 424.879783 -292.550119) (xy 424.880278 -292.574726) (xy 425.219126 -292.574726)
			(xy 425.223086 -292.525672) (xy 425.234863 -292.477888) (xy 425.254154 -292.432612) (xy 425.280457 -292.391016)
			(xy 425.313092 -292.354179) (xy 425.351213 -292.323054) (xy 425.393834 -292.298447) (xy 425.43985 -292.280995)
			(xy 425.488069 -292.271151) (xy 425.537244 -292.26917) (xy 425.586099 -292.275102) (xy 425.63337 -292.288794)
			(xy 425.677832 -292.309892) (xy 425.718335 -292.337848) (xy 425.753828 -292.37194) (xy 425.783393 -292.411284)
			(xy 425.806264 -292.454861) (xy 425.821848 -292.501542) (xy 425.829743 -292.550119) (xy 425.830238 -292.574726)
			(xy 426.169086 -292.574726) (xy 426.173046 -292.525672) (xy 426.184823 -292.477888) (xy 426.204114 -292.432612)
			(xy 426.230417 -292.391016) (xy 426.263052 -292.354179) (xy 426.301173 -292.323054) (xy 426.343794 -292.298447)
			(xy 426.38981 -292.280995) (xy 426.438029 -292.271151) (xy 426.487204 -292.26917) (xy 426.536059 -292.275102)
			(xy 426.58333 -292.288794) (xy 426.627792 -292.309892) (xy 426.668295 -292.337848) (xy 426.703788 -292.37194)
			(xy 426.733353 -292.411284) (xy 426.756224 -292.454861) (xy 426.771808 -292.501542) (xy 426.779703 -292.550119)
			(xy 426.780198 -292.574726) (xy 427.119046 -292.574726) (xy 427.123006 -292.525672) (xy 427.134783 -292.477888)
			(xy 427.154074 -292.432612) (xy 427.180377 -292.391016) (xy 427.213012 -292.354179) (xy 427.251133 -292.323054)
			(xy 427.293754 -292.298447) (xy 427.33977 -292.280995) (xy 427.387989 -292.271151) (xy 427.437164 -292.26917)
			(xy 427.486019 -292.275102) (xy 427.53329 -292.288794) (xy 427.577752 -292.309892) (xy 427.618255 -292.337848)
			(xy 427.653748 -292.37194) (xy 427.683313 -292.411284) (xy 427.706184 -292.454861) (xy 427.721768 -292.501542)
			(xy 427.729663 -292.550119) (xy 427.730158 -292.574726) (xy 428.069006 -292.574726) (xy 428.072966 -292.525672)
			(xy 428.084743 -292.477888) (xy 428.104034 -292.432612) (xy 428.130337 -292.391016) (xy 428.162972 -292.354179)
			(xy 428.201093 -292.323054) (xy 428.243714 -292.298447) (xy 428.28973 -292.280995) (xy 428.337949 -292.271151)
			(xy 428.387124 -292.26917) (xy 428.435979 -292.275102) (xy 428.48325 -292.288794) (xy 428.527712 -292.309892)
			(xy 428.568215 -292.337848) (xy 428.603708 -292.37194) (xy 428.633273 -292.411284) (xy 428.656144 -292.454861)
			(xy 428.671728 -292.501542) (xy 428.679623 -292.550119) (xy 428.680118 -292.574726) (xy 429.01922 -292.574726)
			(xy 429.02318 -292.525672) (xy 429.034957 -292.477888) (xy 429.054248 -292.432612) (xy 429.080551 -292.391016)
			(xy 429.113186 -292.354179) (xy 429.151307 -292.323054) (xy 429.193928 -292.298447) (xy 429.239944 -292.280995)
			(xy 429.288163 -292.271151) (xy 429.337338 -292.26917) (xy 429.386193 -292.275102) (xy 429.433464 -292.288794)
			(xy 429.477926 -292.309892) (xy 429.518429 -292.337848) (xy 429.553922 -292.37194) (xy 429.583487 -292.411284)
			(xy 429.606358 -292.454861) (xy 429.621942 -292.501542) (xy 429.629837 -292.550119) (xy 429.630332 -292.574726)
			(xy 429.630327 -292.57498) (xy 429.96918 -292.57498) (xy 429.97314 -292.525926) (xy 429.984917 -292.478142)
			(xy 430.004208 -292.432866) (xy 430.030511 -292.39127) (xy 430.063146 -292.354433) (xy 430.101267 -292.323308)
			(xy 430.143888 -292.298701) (xy 430.189904 -292.281249) (xy 430.238123 -292.271405) (xy 430.287298 -292.269424)
			(xy 430.336153 -292.275356) (xy 430.383424 -292.289048) (xy 430.427886 -292.310146) (xy 430.468389 -292.338102)
			(xy 430.503882 -292.372194) (xy 430.533447 -292.411538) (xy 430.556318 -292.455115) (xy 430.571902 -292.501796)
			(xy 430.579797 -292.550373) (xy 430.580292 -292.57498) (xy 430.91914 -292.57498) (xy 430.9231 -292.525926)
			(xy 430.934877 -292.478142) (xy 430.954168 -292.432866) (xy 430.980471 -292.39127) (xy 431.013106 -292.354433)
			(xy 431.051227 -292.323308) (xy 431.093848 -292.298701) (xy 431.139864 -292.281249) (xy 431.188083 -292.271405)
			(xy 431.237258 -292.269424) (xy 431.286113 -292.275356) (xy 431.333384 -292.289048) (xy 431.377846 -292.310146)
			(xy 431.418349 -292.338102) (xy 431.453842 -292.372194) (xy 431.483407 -292.411538) (xy 431.506278 -292.455115)
			(xy 431.521862 -292.501796) (xy 431.529757 -292.550373) (xy 431.530252 -292.57498) (xy 431.529757 -292.599587)
			(xy 431.521862 -292.648164) (xy 431.506278 -292.694845) (xy 431.483407 -292.738422) (xy 431.453842 -292.777766)
			(xy 431.418349 -292.811858) (xy 431.377846 -292.839814) (xy 431.333384 -292.860912) (xy 431.286113 -292.874604)
			(xy 431.237258 -292.880536) (xy 431.188083 -292.878555) (xy 431.139864 -292.868711) (xy 431.093848 -292.851259)
			(xy 431.051227 -292.826652) (xy 431.013106 -292.795527) (xy 430.980471 -292.75869) (xy 430.954168 -292.717094)
			(xy 430.934877 -292.671818) (xy 430.9231 -292.624034) (xy 430.91914 -292.57498) (xy 430.580292 -292.57498)
			(xy 430.579797 -292.599587) (xy 430.571902 -292.648164) (xy 430.556318 -292.694845) (xy 430.533447 -292.738422)
			(xy 430.503882 -292.777766) (xy 430.468389 -292.811858) (xy 430.427886 -292.839814) (xy 430.383424 -292.860912)
			(xy 430.336153 -292.874604) (xy 430.287298 -292.880536) (xy 430.238123 -292.878555) (xy 430.189904 -292.868711)
			(xy 430.143888 -292.851259) (xy 430.101267 -292.826652) (xy 430.063146 -292.795527) (xy 430.030511 -292.75869)
			(xy 430.004208 -292.717094) (xy 429.984917 -292.671818) (xy 429.97314 -292.624034) (xy 429.96918 -292.57498)
			(xy 429.630327 -292.57498) (xy 429.629837 -292.599333) (xy 429.621942 -292.64791) (xy 429.606358 -292.694591)
			(xy 429.583487 -292.738168) (xy 429.553922 -292.777512) (xy 429.518429 -292.811604) (xy 429.477926 -292.83956)
			(xy 429.433464 -292.860658) (xy 429.386193 -292.87435) (xy 429.337338 -292.880282) (xy 429.288163 -292.878301)
			(xy 429.239944 -292.868457) (xy 429.193928 -292.851005) (xy 429.151307 -292.826398) (xy 429.113186 -292.795273)
			(xy 429.080551 -292.758436) (xy 429.054248 -292.71684) (xy 429.034957 -292.671564) (xy 429.02318 -292.62378)
			(xy 429.01922 -292.574726) (xy 428.680118 -292.574726) (xy 428.679623 -292.599333) (xy 428.671728 -292.64791)
			(xy 428.656144 -292.694591) (xy 428.633273 -292.738168) (xy 428.603708 -292.777512) (xy 428.568215 -292.811604)
			(xy 428.527712 -292.83956) (xy 428.48325 -292.860658) (xy 428.435979 -292.87435) (xy 428.387124 -292.880282)
			(xy 428.337949 -292.878301) (xy 428.28973 -292.868457) (xy 428.243714 -292.851005) (xy 428.201093 -292.826398)
			(xy 428.162972 -292.795273) (xy 428.130337 -292.758436) (xy 428.104034 -292.71684) (xy 428.084743 -292.671564)
			(xy 428.072966 -292.62378) (xy 428.069006 -292.574726) (xy 427.730158 -292.574726) (xy 427.729663 -292.599333)
			(xy 427.721768 -292.64791) (xy 427.706184 -292.694591) (xy 427.683313 -292.738168) (xy 427.653748 -292.777512)
			(xy 427.618255 -292.811604) (xy 427.577752 -292.83956) (xy 427.53329 -292.860658) (xy 427.486019 -292.87435)
			(xy 427.437164 -292.880282) (xy 427.387989 -292.878301) (xy 427.33977 -292.868457) (xy 427.293754 -292.851005)
			(xy 427.251133 -292.826398) (xy 427.213012 -292.795273) (xy 427.180377 -292.758436) (xy 427.154074 -292.71684)
			(xy 427.134783 -292.671564) (xy 427.123006 -292.62378) (xy 427.119046 -292.574726) (xy 426.780198 -292.574726)
			(xy 426.779703 -292.599333) (xy 426.771808 -292.64791) (xy 426.756224 -292.694591) (xy 426.733353 -292.738168)
			(xy 426.703788 -292.777512) (xy 426.668295 -292.811604) (xy 426.627792 -292.83956) (xy 426.58333 -292.860658)
			(xy 426.536059 -292.87435) (xy 426.487204 -292.880282) (xy 426.438029 -292.878301) (xy 426.38981 -292.868457)
			(xy 426.343794 -292.851005) (xy 426.301173 -292.826398) (xy 426.263052 -292.795273) (xy 426.230417 -292.758436)
			(xy 426.204114 -292.71684) (xy 426.184823 -292.671564) (xy 426.173046 -292.62378) (xy 426.169086 -292.574726)
			(xy 425.830238 -292.574726) (xy 425.829743 -292.599333) (xy 425.821848 -292.64791) (xy 425.806264 -292.694591)
			(xy 425.783393 -292.738168) (xy 425.753828 -292.777512) (xy 425.718335 -292.811604) (xy 425.677832 -292.83956)
			(xy 425.63337 -292.860658) (xy 425.586099 -292.87435) (xy 425.537244 -292.880282) (xy 425.488069 -292.878301)
			(xy 425.43985 -292.868457) (xy 425.393834 -292.851005) (xy 425.351213 -292.826398) (xy 425.313092 -292.795273)
			(xy 425.280457 -292.758436) (xy 425.254154 -292.71684) (xy 425.234863 -292.671564) (xy 425.223086 -292.62378)
			(xy 425.219126 -292.574726) (xy 424.880278 -292.574726) (xy 424.879783 -292.599333) (xy 424.871888 -292.64791)
			(xy 424.856304 -292.694591) (xy 424.833433 -292.738168) (xy 424.803868 -292.777512) (xy 424.768375 -292.811604)
			(xy 424.727872 -292.83956) (xy 424.68341 -292.860658) (xy 424.636139 -292.87435) (xy 424.587284 -292.880282)
			(xy 424.538109 -292.878301) (xy 424.48989 -292.868457) (xy 424.443874 -292.851005) (xy 424.401253 -292.826398)
			(xy 424.363132 -292.795273) (xy 424.330497 -292.758436) (xy 424.304194 -292.71684) (xy 424.284903 -292.671564)
			(xy 424.273126 -292.62378) (xy 424.269166 -292.574726) (xy 423.930318 -292.574726) (xy 423.929823 -292.599333)
			(xy 423.921928 -292.64791) (xy 423.906344 -292.694591) (xy 423.883473 -292.738168) (xy 423.853908 -292.777512)
			(xy 423.818415 -292.811604) (xy 423.777912 -292.83956) (xy 423.73345 -292.860658) (xy 423.686179 -292.87435)
			(xy 423.637324 -292.880282) (xy 423.588149 -292.878301) (xy 423.53993 -292.868457) (xy 423.493914 -292.851005)
			(xy 423.451293 -292.826398) (xy 423.413172 -292.795273) (xy 423.380537 -292.758436) (xy 423.354234 -292.71684)
			(xy 423.334943 -292.671564) (xy 423.323166 -292.62378) (xy 423.319206 -292.574726) (xy 422.980104 -292.574726)
			(xy 422.979609 -292.599333) (xy 422.971714 -292.64791) (xy 422.95613 -292.694591) (xy 422.933259 -292.738168)
			(xy 422.903694 -292.777512) (xy 422.868201 -292.811604) (xy 422.827698 -292.83956) (xy 422.783236 -292.860658)
			(xy 422.735965 -292.87435) (xy 422.68711 -292.880282) (xy 422.637935 -292.878301) (xy 422.589716 -292.868457)
			(xy 422.5437 -292.851005) (xy 422.501079 -292.826398) (xy 422.462958 -292.795273) (xy 422.430323 -292.758436)
			(xy 422.40402 -292.71684) (xy 422.384729 -292.671564) (xy 422.372952 -292.62378) (xy 422.368992 -292.574726)
			(xy 422.030144 -292.574726) (xy 422.029649 -292.599333) (xy 422.021754 -292.64791) (xy 422.00617 -292.694591)
			(xy 421.983299 -292.738168) (xy 421.953734 -292.777512) (xy 421.918241 -292.811604) (xy 421.877738 -292.83956)
			(xy 421.833276 -292.860658) (xy 421.786005 -292.87435) (xy 421.73715 -292.880282) (xy 421.687975 -292.878301)
			(xy 421.639756 -292.868457) (xy 421.59374 -292.851005) (xy 421.551119 -292.826398) (xy 421.512998 -292.795273)
			(xy 421.480363 -292.758436) (xy 421.45406 -292.71684) (xy 421.434769 -292.671564) (xy 421.422992 -292.62378)
			(xy 421.419032 -292.574726) (xy 421.080184 -292.574726) (xy 421.079689 -292.599333) (xy 421.071794 -292.64791)
			(xy 421.05621 -292.694591) (xy 421.033339 -292.738168) (xy 421.003774 -292.777512) (xy 420.968281 -292.811604)
			(xy 420.927778 -292.83956) (xy 420.883316 -292.860658) (xy 420.836045 -292.87435) (xy 420.78719 -292.880282)
			(xy 420.738015 -292.878301) (xy 420.689796 -292.868457) (xy 420.64378 -292.851005) (xy 420.601159 -292.826398)
			(xy 420.563038 -292.795273) (xy 420.530403 -292.758436) (xy 420.5041 -292.71684) (xy 420.484809 -292.671564)
			(xy 420.473032 -292.62378) (xy 420.469072 -292.574726) (xy 420.130224 -292.574726) (xy 420.129729 -292.599333)
			(xy 420.121834 -292.64791) (xy 420.10625 -292.694591) (xy 420.083379 -292.738168) (xy 420.053814 -292.777512)
			(xy 420.018321 -292.811604) (xy 419.977818 -292.83956) (xy 419.933356 -292.860658) (xy 419.886085 -292.87435)
			(xy 419.83723 -292.880282) (xy 419.788055 -292.878301) (xy 419.739836 -292.868457) (xy 419.69382 -292.851005)
			(xy 419.651199 -292.826398) (xy 419.613078 -292.795273) (xy 419.580443 -292.758436) (xy 419.55414 -292.71684)
			(xy 419.534849 -292.671564) (xy 419.523072 -292.62378) (xy 419.519112 -292.574726) (xy 419.180259 -292.574726)
			(xy 419.180264 -292.57498) (xy 419.179769 -292.599587) (xy 419.171874 -292.648164) (xy 419.15629 -292.694845)
			(xy 419.133419 -292.738422) (xy 419.103854 -292.777766) (xy 419.068361 -292.811858) (xy 419.027858 -292.839814)
			(xy 418.983396 -292.860912) (xy 418.936125 -292.874604) (xy 418.88727 -292.880536) (xy 418.838095 -292.878555)
			(xy 418.789876 -292.868711) (xy 418.74386 -292.851259) (xy 418.701239 -292.826652) (xy 418.663118 -292.795527)
			(xy 418.630483 -292.75869) (xy 418.60418 -292.717094) (xy 418.584889 -292.671818) (xy 418.573112 -292.624034)
			(xy 418.569152 -292.57498) (xy 418.231575 -292.57498) (xy 418.227416 -292.625165) (xy 418.214985 -292.674253)
			(xy 418.194644 -292.720625) (xy 418.166947 -292.763017) (xy 418.132651 -292.800273) (xy 418.092691 -292.831375)
			(xy 418.048156 -292.855475) (xy 418.000262 -292.871917) (xy 417.950315 -292.880251) (xy 417.924996 -292.880796)
			(xy 417.924742 -292.880796) (xy 417.897275 -292.880162) (xy 417.843227 -292.870329) (xy 417.8173 -292.861238)
			(xy 417.805616 -292.85692) (xy 417.780978 -292.859968) (xy 417.702492 -292.91407) (xy 417.692831 -292.921687)
			(xy 417.681438 -292.943447) (xy 417.680648 -292.955726) (xy 417.680648 -293.14394) (xy 417.681244 -293.156264)
			(xy 417.692703 -293.178083) (xy 417.702492 -293.185596) (xy 417.780978 -293.239698) (xy 417.805616 -293.242746)
			(xy 417.8173 -293.238428) (xy 417.843217 -293.229299) (xy 417.897271 -293.219456) (xy 417.924742 -293.21887)
			(xy 417.924996 -293.21887) (xy 417.950314 -293.219364) (xy 418.000258 -293.227698) (xy 418.04815 -293.244138)
			(xy 418.092683 -293.268238) (xy 418.132641 -293.299338) (xy 418.166936 -293.336591) (xy 418.194631 -293.378982)
			(xy 418.214971 -293.425352) (xy 418.227402 -293.474438) (xy 418.231583 -293.5249) (xy 418.23158 -293.52494)
			(xy 418.569152 -293.52494) (xy 418.573112 -293.475886) (xy 418.584889 -293.428102) (xy 418.60418 -293.382826)
			(xy 418.630483 -293.34123) (xy 418.663118 -293.304393) (xy 418.701239 -293.273268) (xy 418.74386 -293.248661)
			(xy 418.789876 -293.231209) (xy 418.838095 -293.221365) (xy 418.88727 -293.219384) (xy 418.936125 -293.225316)
			(xy 418.983396 -293.239008) (xy 419.027858 -293.260106) (xy 419.068361 -293.288062) (xy 419.103854 -293.322154)
			(xy 419.133419 -293.361498) (xy 419.15629 -293.405075) (xy 419.171874 -293.451756) (xy 419.179769 -293.500333)
			(xy 419.180264 -293.52494) (xy 419.519112 -293.52494) (xy 419.523072 -293.475886) (xy 419.534849 -293.428102)
			(xy 419.55414 -293.382826) (xy 419.580443 -293.34123) (xy 419.613078 -293.304393) (xy 419.651199 -293.273268)
			(xy 419.69382 -293.248661) (xy 419.739836 -293.231209) (xy 419.788055 -293.221365) (xy 419.83723 -293.219384)
			(xy 419.886085 -293.225316) (xy 419.933356 -293.239008) (xy 419.977818 -293.260106) (xy 420.018321 -293.288062)
			(xy 420.053814 -293.322154) (xy 420.083379 -293.361498) (xy 420.10625 -293.405075) (xy 420.121834 -293.451756)
			(xy 420.129729 -293.500333) (xy 420.130224 -293.52494) (xy 421.419032 -293.52494) (xy 421.422992 -293.475886)
			(xy 421.434769 -293.428102) (xy 421.45406 -293.382826) (xy 421.480363 -293.34123) (xy 421.512998 -293.304393)
			(xy 421.551119 -293.273268) (xy 421.59374 -293.248661) (xy 421.639756 -293.231209) (xy 421.687975 -293.221365)
			(xy 421.73715 -293.219384) (xy 421.786005 -293.225316) (xy 421.833276 -293.239008) (xy 421.877738 -293.260106)
			(xy 421.918241 -293.288062) (xy 421.953734 -293.322154) (xy 421.983299 -293.361498) (xy 422.00617 -293.405075)
			(xy 422.021754 -293.451756) (xy 422.029649 -293.500333) (xy 422.030144 -293.52494) (xy 422.369246 -293.52494)
			(xy 422.373206 -293.475886) (xy 422.384983 -293.428102) (xy 422.404274 -293.382826) (xy 422.430577 -293.34123)
			(xy 422.463212 -293.304393) (xy 422.501333 -293.273268) (xy 422.543954 -293.248661) (xy 422.58997 -293.231209)
			(xy 422.638189 -293.221365) (xy 422.687364 -293.219384) (xy 422.736219 -293.225316) (xy 422.78349 -293.239008)
			(xy 422.827952 -293.260106) (xy 422.868455 -293.288062) (xy 422.903948 -293.322154) (xy 422.933513 -293.361498)
			(xy 422.956384 -293.405075) (xy 422.971968 -293.451756) (xy 422.979863 -293.500333) (xy 422.980358 -293.52494)
			(xy 423.319206 -293.52494) (xy 423.323166 -293.475886) (xy 423.334943 -293.428102) (xy 423.354234 -293.382826)
			(xy 423.380537 -293.34123) (xy 423.413172 -293.304393) (xy 423.451293 -293.273268) (xy 423.493914 -293.248661)
			(xy 423.53993 -293.231209) (xy 423.588149 -293.221365) (xy 423.637324 -293.219384) (xy 423.686179 -293.225316)
			(xy 423.73345 -293.239008) (xy 423.777912 -293.260106) (xy 423.818415 -293.288062) (xy 423.853908 -293.322154)
			(xy 423.883473 -293.361498) (xy 423.906344 -293.405075) (xy 423.921928 -293.451756) (xy 423.929823 -293.500333)
			(xy 423.930318 -293.52494) (xy 424.269166 -293.52494) (xy 424.273126 -293.475886) (xy 424.284903 -293.428102)
			(xy 424.304194 -293.382826) (xy 424.330497 -293.34123) (xy 424.363132 -293.304393) (xy 424.401253 -293.273268)
			(xy 424.443874 -293.248661) (xy 424.48989 -293.231209) (xy 424.538109 -293.221365) (xy 424.587284 -293.219384)
			(xy 424.636139 -293.225316) (xy 424.68341 -293.239008) (xy 424.727872 -293.260106) (xy 424.768375 -293.288062)
			(xy 424.803868 -293.322154) (xy 424.833433 -293.361498) (xy 424.856304 -293.405075) (xy 424.871888 -293.451756)
			(xy 424.879783 -293.500333) (xy 424.880278 -293.52494) (xy 425.219126 -293.52494) (xy 425.223086 -293.475886)
			(xy 425.234863 -293.428102) (xy 425.254154 -293.382826) (xy 425.280457 -293.34123) (xy 425.313092 -293.304393)
			(xy 425.351213 -293.273268) (xy 425.393834 -293.248661) (xy 425.43985 -293.231209) (xy 425.488069 -293.221365)
			(xy 425.537244 -293.219384) (xy 425.586099 -293.225316) (xy 425.63337 -293.239008) (xy 425.677832 -293.260106)
			(xy 425.718335 -293.288062) (xy 425.753828 -293.322154) (xy 425.783393 -293.361498) (xy 425.806264 -293.405075)
			(xy 425.821848 -293.451756) (xy 425.829743 -293.500333) (xy 425.830238 -293.52494) (xy 426.169086 -293.52494)
			(xy 426.173046 -293.475886) (xy 426.184823 -293.428102) (xy 426.204114 -293.382826) (xy 426.230417 -293.34123)
			(xy 426.263052 -293.304393) (xy 426.301173 -293.273268) (xy 426.343794 -293.248661) (xy 426.38981 -293.231209)
			(xy 426.438029 -293.221365) (xy 426.487204 -293.219384) (xy 426.536059 -293.225316) (xy 426.58333 -293.239008)
			(xy 426.627792 -293.260106) (xy 426.668295 -293.288062) (xy 426.703788 -293.322154) (xy 426.733353 -293.361498)
			(xy 426.756224 -293.405075) (xy 426.771808 -293.451756) (xy 426.779703 -293.500333) (xy 426.780198 -293.52494)
			(xy 427.119046 -293.52494) (xy 427.123006 -293.475886) (xy 427.134783 -293.428102) (xy 427.154074 -293.382826)
			(xy 427.180377 -293.34123) (xy 427.213012 -293.304393) (xy 427.251133 -293.273268) (xy 427.293754 -293.248661)
			(xy 427.33977 -293.231209) (xy 427.387989 -293.221365) (xy 427.437164 -293.219384) (xy 427.486019 -293.225316)
			(xy 427.53329 -293.239008) (xy 427.577752 -293.260106) (xy 427.618255 -293.288062) (xy 427.653748 -293.322154)
			(xy 427.683313 -293.361498) (xy 427.706184 -293.405075) (xy 427.721768 -293.451756) (xy 427.729663 -293.500333)
			(xy 427.730158 -293.52494) (xy 428.069006 -293.52494) (xy 428.072966 -293.475886) (xy 428.084743 -293.428102)
			(xy 428.104034 -293.382826) (xy 428.130337 -293.34123) (xy 428.162972 -293.304393) (xy 428.201093 -293.273268)
			(xy 428.243714 -293.248661) (xy 428.28973 -293.231209) (xy 428.337949 -293.221365) (xy 428.387124 -293.219384)
			(xy 428.435979 -293.225316) (xy 428.48325 -293.239008) (xy 428.527712 -293.260106) (xy 428.568215 -293.288062)
			(xy 428.603708 -293.322154) (xy 428.633273 -293.361498) (xy 428.656144 -293.405075) (xy 428.671728 -293.451756)
			(xy 428.679623 -293.500333) (xy 428.680118 -293.52494) (xy 429.01922 -293.52494) (xy 429.02318 -293.475886)
			(xy 429.034957 -293.428102) (xy 429.054248 -293.382826) (xy 429.080551 -293.34123) (xy 429.113186 -293.304393)
			(xy 429.151307 -293.273268) (xy 429.193928 -293.248661) (xy 429.239944 -293.231209) (xy 429.288163 -293.221365)
			(xy 429.337338 -293.219384) (xy 429.386193 -293.225316) (xy 429.433464 -293.239008) (xy 429.477926 -293.260106)
			(xy 429.518429 -293.288062) (xy 429.553922 -293.322154) (xy 429.583487 -293.361498) (xy 429.606358 -293.405075)
			(xy 429.621942 -293.451756) (xy 429.629837 -293.500333) (xy 429.630332 -293.52494) (xy 429.96918 -293.52494)
			(xy 429.97314 -293.475886) (xy 429.984917 -293.428102) (xy 430.004208 -293.382826) (xy 430.030511 -293.34123)
			(xy 430.063146 -293.304393) (xy 430.101267 -293.273268) (xy 430.143888 -293.248661) (xy 430.189904 -293.231209)
			(xy 430.238123 -293.221365) (xy 430.287298 -293.219384) (xy 430.336153 -293.225316) (xy 430.383424 -293.239008)
			(xy 430.427886 -293.260106) (xy 430.468389 -293.288062) (xy 430.503882 -293.322154) (xy 430.533447 -293.361498)
			(xy 430.556318 -293.405075) (xy 430.571902 -293.451756) (xy 430.579797 -293.500333) (xy 430.580292 -293.52494)
			(xy 430.91914 -293.52494) (xy 430.9231 -293.475886) (xy 430.934877 -293.428102) (xy 430.954168 -293.382826)
			(xy 430.980471 -293.34123) (xy 431.013106 -293.304393) (xy 431.051227 -293.273268) (xy 431.093848 -293.248661)
			(xy 431.139864 -293.231209) (xy 431.188083 -293.221365) (xy 431.237258 -293.219384) (xy 431.286113 -293.225316)
			(xy 431.333384 -293.239008) (xy 431.377846 -293.260106) (xy 431.418349 -293.288062) (xy 431.453842 -293.322154)
			(xy 431.483407 -293.361498) (xy 431.506278 -293.405075) (xy 431.521862 -293.451756) (xy 431.529757 -293.500333)
			(xy 431.530252 -293.52494) (xy 431.529757 -293.549547) (xy 431.521862 -293.598124) (xy 431.506278 -293.644805)
			(xy 431.483407 -293.688382) (xy 431.453842 -293.727726) (xy 431.418349 -293.761818) (xy 431.377846 -293.789774)
			(xy 431.333384 -293.810872) (xy 431.286113 -293.824564) (xy 431.237258 -293.830496) (xy 431.188083 -293.828515)
			(xy 431.139864 -293.818671) (xy 431.093848 -293.801219) (xy 431.051227 -293.776612) (xy 431.013106 -293.745487)
			(xy 430.980471 -293.70865) (xy 430.954168 -293.667054) (xy 430.934877 -293.621778) (xy 430.9231 -293.573994)
			(xy 430.91914 -293.52494) (xy 430.580292 -293.52494) (xy 430.579797 -293.549547) (xy 430.571902 -293.598124)
			(xy 430.556318 -293.644805) (xy 430.533447 -293.688382) (xy 430.503882 -293.727726) (xy 430.468389 -293.761818)
			(xy 430.427886 -293.789774) (xy 430.383424 -293.810872) (xy 430.336153 -293.824564) (xy 430.287298 -293.830496)
			(xy 430.238123 -293.828515) (xy 430.189904 -293.818671) (xy 430.143888 -293.801219) (xy 430.101267 -293.776612)
			(xy 430.063146 -293.745487) (xy 430.030511 -293.70865) (xy 430.004208 -293.667054) (xy 429.984917 -293.621778)
			(xy 429.97314 -293.573994) (xy 429.96918 -293.52494) (xy 429.630332 -293.52494) (xy 429.629837 -293.549547)
			(xy 429.621942 -293.598124) (xy 429.606358 -293.644805) (xy 429.583487 -293.688382) (xy 429.553922 -293.727726)
			(xy 429.518429 -293.761818) (xy 429.477926 -293.789774) (xy 429.433464 -293.810872) (xy 429.386193 -293.824564)
			(xy 429.337338 -293.830496) (xy 429.288163 -293.828515) (xy 429.239944 -293.818671) (xy 429.193928 -293.801219)
			(xy 429.151307 -293.776612) (xy 429.113186 -293.745487) (xy 429.080551 -293.70865) (xy 429.054248 -293.667054)
			(xy 429.034957 -293.621778) (xy 429.02318 -293.573994) (xy 429.01922 -293.52494) (xy 428.680118 -293.52494)
			(xy 428.679623 -293.549547) (xy 428.671728 -293.598124) (xy 428.656144 -293.644805) (xy 428.633273 -293.688382)
			(xy 428.603708 -293.727726) (xy 428.568215 -293.761818) (xy 428.527712 -293.789774) (xy 428.48325 -293.810872)
			(xy 428.435979 -293.824564) (xy 428.387124 -293.830496) (xy 428.337949 -293.828515) (xy 428.28973 -293.818671)
			(xy 428.243714 -293.801219) (xy 428.201093 -293.776612) (xy 428.162972 -293.745487) (xy 428.130337 -293.70865)
			(xy 428.104034 -293.667054) (xy 428.084743 -293.621778) (xy 428.072966 -293.573994) (xy 428.069006 -293.52494)
			(xy 427.730158 -293.52494) (xy 427.729663 -293.549547) (xy 427.721768 -293.598124) (xy 427.706184 -293.644805)
			(xy 427.683313 -293.688382) (xy 427.653748 -293.727726) (xy 427.618255 -293.761818) (xy 427.577752 -293.789774)
			(xy 427.53329 -293.810872) (xy 427.486019 -293.824564) (xy 427.437164 -293.830496) (xy 427.387989 -293.828515)
			(xy 427.33977 -293.818671) (xy 427.293754 -293.801219) (xy 427.251133 -293.776612) (xy 427.213012 -293.745487)
			(xy 427.180377 -293.70865) (xy 427.154074 -293.667054) (xy 427.134783 -293.621778) (xy 427.123006 -293.573994)
			(xy 427.119046 -293.52494) (xy 426.780198 -293.52494) (xy 426.779703 -293.549547) (xy 426.771808 -293.598124)
			(xy 426.756224 -293.644805) (xy 426.733353 -293.688382) (xy 426.703788 -293.727726) (xy 426.668295 -293.761818)
			(xy 426.627792 -293.789774) (xy 426.58333 -293.810872) (xy 426.536059 -293.824564) (xy 426.487204 -293.830496)
			(xy 426.438029 -293.828515) (xy 426.38981 -293.818671) (xy 426.343794 -293.801219) (xy 426.301173 -293.776612)
			(xy 426.263052 -293.745487) (xy 426.230417 -293.70865) (xy 426.204114 -293.667054) (xy 426.184823 -293.621778)
			(xy 426.173046 -293.573994) (xy 426.169086 -293.52494) (xy 425.830238 -293.52494) (xy 425.829743 -293.549547)
			(xy 425.821848 -293.598124) (xy 425.806264 -293.644805) (xy 425.783393 -293.688382) (xy 425.753828 -293.727726)
			(xy 425.718335 -293.761818) (xy 425.677832 -293.789774) (xy 425.63337 -293.810872) (xy 425.586099 -293.824564)
			(xy 425.537244 -293.830496) (xy 425.488069 -293.828515) (xy 425.43985 -293.818671) (xy 425.393834 -293.801219)
			(xy 425.351213 -293.776612) (xy 425.313092 -293.745487) (xy 425.280457 -293.70865) (xy 425.254154 -293.667054)
			(xy 425.234863 -293.621778) (xy 425.223086 -293.573994) (xy 425.219126 -293.52494) (xy 424.880278 -293.52494)
			(xy 424.879783 -293.549547) (xy 424.871888 -293.598124) (xy 424.856304 -293.644805) (xy 424.833433 -293.688382)
			(xy 424.803868 -293.727726) (xy 424.768375 -293.761818) (xy 424.727872 -293.789774) (xy 424.68341 -293.810872)
			(xy 424.636139 -293.824564) (xy 424.587284 -293.830496) (xy 424.538109 -293.828515) (xy 424.48989 -293.818671)
			(xy 424.443874 -293.801219) (xy 424.401253 -293.776612) (xy 424.363132 -293.745487) (xy 424.330497 -293.70865)
			(xy 424.304194 -293.667054) (xy 424.284903 -293.621778) (xy 424.273126 -293.573994) (xy 424.269166 -293.52494)
			(xy 423.930318 -293.52494) (xy 423.929823 -293.549547) (xy 423.921928 -293.598124) (xy 423.906344 -293.644805)
			(xy 423.883473 -293.688382) (xy 423.853908 -293.727726) (xy 423.818415 -293.761818) (xy 423.777912 -293.789774)
			(xy 423.73345 -293.810872) (xy 423.686179 -293.824564) (xy 423.637324 -293.830496) (xy 423.588149 -293.828515)
			(xy 423.53993 -293.818671) (xy 423.493914 -293.801219) (xy 423.451293 -293.776612) (xy 423.413172 -293.745487)
			(xy 423.380537 -293.70865) (xy 423.354234 -293.667054) (xy 423.334943 -293.621778) (xy 423.323166 -293.573994)
			(xy 423.319206 -293.52494) (xy 422.980358 -293.52494) (xy 422.979863 -293.549547) (xy 422.971968 -293.598124)
			(xy 422.956384 -293.644805) (xy 422.933513 -293.688382) (xy 422.903948 -293.727726) (xy 422.868455 -293.761818)
			(xy 422.827952 -293.789774) (xy 422.78349 -293.810872) (xy 422.736219 -293.824564) (xy 422.687364 -293.830496)
			(xy 422.638189 -293.828515) (xy 422.58997 -293.818671) (xy 422.543954 -293.801219) (xy 422.501333 -293.776612)
			(xy 422.463212 -293.745487) (xy 422.430577 -293.70865) (xy 422.404274 -293.667054) (xy 422.384983 -293.621778)
			(xy 422.373206 -293.573994) (xy 422.369246 -293.52494) (xy 422.030144 -293.52494) (xy 422.029649 -293.549547)
			(xy 422.021754 -293.598124) (xy 422.00617 -293.644805) (xy 421.983299 -293.688382) (xy 421.953734 -293.727726)
			(xy 421.918241 -293.761818) (xy 421.877738 -293.789774) (xy 421.833276 -293.810872) (xy 421.786005 -293.824564)
			(xy 421.73715 -293.830496) (xy 421.687975 -293.828515) (xy 421.639756 -293.818671) (xy 421.59374 -293.801219)
			(xy 421.551119 -293.776612) (xy 421.512998 -293.745487) (xy 421.480363 -293.70865) (xy 421.45406 -293.667054)
			(xy 421.434769 -293.621778) (xy 421.422992 -293.573994) (xy 421.419032 -293.52494) (xy 420.130224 -293.52494)
			(xy 420.129729 -293.549547) (xy 420.121834 -293.598124) (xy 420.10625 -293.644805) (xy 420.083379 -293.688382)
			(xy 420.053814 -293.727726) (xy 420.018321 -293.761818) (xy 419.977818 -293.789774) (xy 419.933356 -293.810872)
			(xy 419.886085 -293.824564) (xy 419.83723 -293.830496) (xy 419.788055 -293.828515) (xy 419.739836 -293.818671)
			(xy 419.69382 -293.801219) (xy 419.651199 -293.776612) (xy 419.613078 -293.745487) (xy 419.580443 -293.70865)
			(xy 419.55414 -293.667054) (xy 419.534849 -293.621778) (xy 419.523072 -293.573994) (xy 419.519112 -293.52494)
			(xy 419.180264 -293.52494) (xy 419.179769 -293.549547) (xy 419.171874 -293.598124) (xy 419.15629 -293.644805)
			(xy 419.133419 -293.688382) (xy 419.103854 -293.727726) (xy 419.068361 -293.761818) (xy 419.027858 -293.789774)
			(xy 418.983396 -293.810872) (xy 418.936125 -293.824564) (xy 418.88727 -293.830496) (xy 418.838095 -293.828515)
			(xy 418.789876 -293.818671) (xy 418.74386 -293.801219) (xy 418.701239 -293.776612) (xy 418.663118 -293.745487)
			(xy 418.630483 -293.70865) (xy 418.60418 -293.667054) (xy 418.584889 -293.621778) (xy 418.573112 -293.573994)
			(xy 418.569152 -293.52494) (xy 418.23158 -293.52494) (xy 418.227402 -293.575362) (xy 418.214971 -293.624448)
			(xy 418.194631 -293.670818) (xy 418.166936 -293.713209) (xy 418.132641 -293.750462) (xy 418.092683 -293.781562)
			(xy 418.04815 -293.805662) (xy 418.000258 -293.822102) (xy 417.950314 -293.830436) (xy 417.924996 -293.83101)
			(xy 417.924742 -293.83101) (xy 417.897275 -293.830376) (xy 417.843226 -293.820543) (xy 417.8173 -293.811452)
			(xy 417.805616 -293.807134) (xy 417.780978 -293.810182) (xy 417.702492 -293.864284) (xy 417.692834 -293.871902)
			(xy 417.681447 -293.893662) (xy 417.680648 -293.90594) (xy 417.680648 -294.0939) (xy 417.681235 -294.106228)
			(xy 417.692685 -294.128063) (xy 417.702492 -294.135556) (xy 417.780978 -294.189658) (xy 417.805616 -294.192706)
			(xy 417.8173 -294.188388) (xy 417.843217 -294.17926) (xy 417.897271 -294.169417) (xy 417.924742 -294.16883)
			(xy 417.924996 -294.16883) (xy 417.950317 -294.169323) (xy 418.000268 -294.177658) (xy 418.048167 -294.194101)
			(xy 418.092705 -294.218204) (xy 418.132669 -294.249308) (xy 418.166968 -294.286567) (xy 418.194667 -294.328962)
			(xy 418.21501 -294.375339) (xy 418.227441 -294.424431) (xy 418.231624 -294.4749) (xy 418.569152 -294.4749)
			(xy 418.573112 -294.425846) (xy 418.584889 -294.378062) (xy 418.60418 -294.332786) (xy 418.630483 -294.29119)
			(xy 418.663118 -294.254353) (xy 418.701239 -294.223228) (xy 418.74386 -294.198621) (xy 418.789876 -294.181169)
			(xy 418.838095 -294.171325) (xy 418.88727 -294.169344) (xy 418.936125 -294.175276) (xy 418.983396 -294.188968)
			(xy 419.027858 -294.210066) (xy 419.068361 -294.238022) (xy 419.103854 -294.272114) (xy 419.133419 -294.311458)
			(xy 419.15629 -294.355035) (xy 419.171874 -294.401716) (xy 419.179769 -294.450293) (xy 419.180264 -294.4749)
			(xy 419.519112 -294.4749) (xy 419.523072 -294.425846) (xy 419.534849 -294.378062) (xy 419.55414 -294.332786)
			(xy 419.580443 -294.29119) (xy 419.613078 -294.254353) (xy 419.651199 -294.223228) (xy 419.69382 -294.198621)
			(xy 419.739836 -294.181169) (xy 419.788055 -294.171325) (xy 419.83723 -294.169344) (xy 419.886085 -294.175276)
			(xy 419.933356 -294.188968) (xy 419.977818 -294.210066) (xy 420.018321 -294.238022) (xy 420.053814 -294.272114)
			(xy 420.083379 -294.311458) (xy 420.10625 -294.355035) (xy 420.121834 -294.401716) (xy 420.129729 -294.450293)
			(xy 420.130224 -294.4749) (xy 421.419032 -294.4749) (xy 421.422992 -294.425846) (xy 421.434769 -294.378062)
			(xy 421.45406 -294.332786) (xy 421.480363 -294.29119) (xy 421.512998 -294.254353) (xy 421.551119 -294.223228)
			(xy 421.59374 -294.198621) (xy 421.639756 -294.181169) (xy 421.687975 -294.171325) (xy 421.73715 -294.169344)
			(xy 421.786005 -294.175276) (xy 421.833276 -294.188968) (xy 421.877738 -294.210066) (xy 421.918241 -294.238022)
			(xy 421.953734 -294.272114) (xy 421.983299 -294.311458) (xy 422.00617 -294.355035) (xy 422.021754 -294.401716)
			(xy 422.029649 -294.450293) (xy 422.030144 -294.4749) (xy 422.368992 -294.4749) (xy 422.372952 -294.425846)
			(xy 422.384729 -294.378062) (xy 422.40402 -294.332786) (xy 422.430323 -294.29119) (xy 422.462958 -294.254353)
			(xy 422.501079 -294.223228) (xy 422.5437 -294.198621) (xy 422.589716 -294.181169) (xy 422.637935 -294.171325)
			(xy 422.68711 -294.169344) (xy 422.735965 -294.175276) (xy 422.783236 -294.188968) (xy 422.827698 -294.210066)
			(xy 422.868201 -294.238022) (xy 422.903694 -294.272114) (xy 422.933259 -294.311458) (xy 422.95613 -294.355035)
			(xy 422.971714 -294.401716) (xy 422.979609 -294.450293) (xy 422.980104 -294.4749) (xy 423.319206 -294.4749)
			(xy 423.323166 -294.425846) (xy 423.334943 -294.378062) (xy 423.354234 -294.332786) (xy 423.380537 -294.29119)
			(xy 423.413172 -294.254353) (xy 423.451293 -294.223228) (xy 423.493914 -294.198621) (xy 423.53993 -294.181169)
			(xy 423.588149 -294.171325) (xy 423.637324 -294.169344) (xy 423.686179 -294.175276) (xy 423.73345 -294.188968)
			(xy 423.777912 -294.210066) (xy 423.818415 -294.238022) (xy 423.853908 -294.272114) (xy 423.883473 -294.311458)
			(xy 423.906344 -294.355035) (xy 423.921928 -294.401716) (xy 423.929823 -294.450293) (xy 423.930318 -294.4749)
			(xy 424.269166 -294.4749) (xy 424.273126 -294.425846) (xy 424.284903 -294.378062) (xy 424.304194 -294.332786)
			(xy 424.330497 -294.29119) (xy 424.363132 -294.254353) (xy 424.401253 -294.223228) (xy 424.443874 -294.198621)
			(xy 424.48989 -294.181169) (xy 424.538109 -294.171325) (xy 424.587284 -294.169344) (xy 424.636139 -294.175276)
			(xy 424.68341 -294.188968) (xy 424.727872 -294.210066) (xy 424.768375 -294.238022) (xy 424.803868 -294.272114)
			(xy 424.833433 -294.311458) (xy 424.856304 -294.355035) (xy 424.871888 -294.401716) (xy 424.879783 -294.450293)
			(xy 424.880278 -294.4749) (xy 425.219126 -294.4749) (xy 425.223086 -294.425846) (xy 425.234863 -294.378062)
			(xy 425.254154 -294.332786) (xy 425.280457 -294.29119) (xy 425.313092 -294.254353) (xy 425.351213 -294.223228)
			(xy 425.393834 -294.198621) (xy 425.43985 -294.181169) (xy 425.488069 -294.171325) (xy 425.537244 -294.169344)
			(xy 425.586099 -294.175276) (xy 425.63337 -294.188968) (xy 425.677832 -294.210066) (xy 425.718335 -294.238022)
			(xy 425.753828 -294.272114) (xy 425.783393 -294.311458) (xy 425.806264 -294.355035) (xy 425.821848 -294.401716)
			(xy 425.829743 -294.450293) (xy 425.830238 -294.4749) (xy 426.169086 -294.4749) (xy 426.173046 -294.425846)
			(xy 426.184823 -294.378062) (xy 426.204114 -294.332786) (xy 426.230417 -294.29119) (xy 426.263052 -294.254353)
			(xy 426.301173 -294.223228) (xy 426.343794 -294.198621) (xy 426.38981 -294.181169) (xy 426.438029 -294.171325)
			(xy 426.487204 -294.169344) (xy 426.536059 -294.175276) (xy 426.58333 -294.188968) (xy 426.627792 -294.210066)
			(xy 426.668295 -294.238022) (xy 426.703788 -294.272114) (xy 426.733353 -294.311458) (xy 426.756224 -294.355035)
			(xy 426.771808 -294.401716) (xy 426.779703 -294.450293) (xy 426.780198 -294.4749) (xy 427.119046 -294.4749)
			(xy 427.123006 -294.425846) (xy 427.134783 -294.378062) (xy 427.154074 -294.332786) (xy 427.180377 -294.29119)
			(xy 427.213012 -294.254353) (xy 427.251133 -294.223228) (xy 427.293754 -294.198621) (xy 427.33977 -294.181169)
			(xy 427.387989 -294.171325) (xy 427.437164 -294.169344) (xy 427.486019 -294.175276) (xy 427.53329 -294.188968)
			(xy 427.577752 -294.210066) (xy 427.618255 -294.238022) (xy 427.653748 -294.272114) (xy 427.683313 -294.311458)
			(xy 427.706184 -294.355035) (xy 427.721768 -294.401716) (xy 427.729663 -294.450293) (xy 427.730158 -294.4749)
			(xy 428.069006 -294.4749) (xy 428.072966 -294.425846) (xy 428.084743 -294.378062) (xy 428.104034 -294.332786)
			(xy 428.130337 -294.29119) (xy 428.162972 -294.254353) (xy 428.201093 -294.223228) (xy 428.243714 -294.198621)
			(xy 428.28973 -294.181169) (xy 428.337949 -294.171325) (xy 428.387124 -294.169344) (xy 428.435979 -294.175276)
			(xy 428.48325 -294.188968) (xy 428.527712 -294.210066) (xy 428.568215 -294.238022) (xy 428.603708 -294.272114)
			(xy 428.633273 -294.311458) (xy 428.656144 -294.355035) (xy 428.671728 -294.401716) (xy 428.679623 -294.450293)
			(xy 428.680118 -294.4749) (xy 429.01922 -294.4749) (xy 429.02318 -294.425846) (xy 429.034957 -294.378062)
			(xy 429.054248 -294.332786) (xy 429.080551 -294.29119) (xy 429.113186 -294.254353) (xy 429.151307 -294.223228)
			(xy 429.193928 -294.198621) (xy 429.239944 -294.181169) (xy 429.288163 -294.171325) (xy 429.337338 -294.169344)
			(xy 429.386193 -294.175276) (xy 429.433464 -294.188968) (xy 429.477926 -294.210066) (xy 429.518429 -294.238022)
			(xy 429.553922 -294.272114) (xy 429.583487 -294.311458) (xy 429.606358 -294.355035) (xy 429.621942 -294.401716)
			(xy 429.629837 -294.450293) (xy 429.630332 -294.4749) (xy 429.96918 -294.4749) (xy 429.97314 -294.425846)
			(xy 429.984917 -294.378062) (xy 430.004208 -294.332786) (xy 430.030511 -294.29119) (xy 430.063146 -294.254353)
			(xy 430.101267 -294.223228) (xy 430.143888 -294.198621) (xy 430.189904 -294.181169) (xy 430.238123 -294.171325)
			(xy 430.287298 -294.169344) (xy 430.336153 -294.175276) (xy 430.383424 -294.188968) (xy 430.427886 -294.210066)
			(xy 430.468389 -294.238022) (xy 430.503882 -294.272114) (xy 430.533447 -294.311458) (xy 430.556318 -294.355035)
			(xy 430.571902 -294.401716) (xy 430.579797 -294.450293) (xy 430.580292 -294.4749) (xy 430.91914 -294.4749)
			(xy 430.9231 -294.425846) (xy 430.934877 -294.378062) (xy 430.954168 -294.332786) (xy 430.980471 -294.29119)
			(xy 431.013106 -294.254353) (xy 431.051227 -294.223228) (xy 431.093848 -294.198621) (xy 431.139864 -294.181169)
			(xy 431.188083 -294.171325) (xy 431.237258 -294.169344) (xy 431.286113 -294.175276) (xy 431.333384 -294.188968)
			(xy 431.377846 -294.210066) (xy 431.418349 -294.238022) (xy 431.453842 -294.272114) (xy 431.483407 -294.311458)
			(xy 431.506278 -294.355035) (xy 431.521862 -294.401716) (xy 431.529757 -294.450293) (xy 431.530252 -294.4749)
			(xy 431.529757 -294.499507) (xy 431.521862 -294.548084) (xy 431.506278 -294.594765) (xy 431.483407 -294.638342)
			(xy 431.47054 -294.655465) (xy 437.463125 -294.655465) (xy 437.47088 -294.601509) (xy 437.486235 -294.549206)
			(xy 437.508877 -294.499621) (xy 437.538345 -294.453763) (xy 437.57404 -294.412565) (xy 437.615234 -294.376867)
			(xy 437.661089 -294.347394) (xy 437.710673 -294.324748) (xy 437.762974 -294.309388) (xy 437.816929 -294.301628)
			(xy 437.844184 -294.301164) (xy 437.869584 -294.301926) (xy 437.884316 -294.302449) (xy 437.913046 -294.295896)
			(xy 437.938712 -294.281417) (xy 437.959178 -294.260214) (xy 437.97274 -294.234052) (xy 437.978272 -294.205107)
			(xy 437.975313 -294.175788) (xy 437.970168 -294.161972) (xy 437.961006 -294.13877) (xy 437.948116 -294.090579)
			(xy 437.941616 -294.041119) (xy 437.941212 -294.016176) (xy 437.941704 -293.988927) (xy 437.949463 -293.934985)
			(xy 437.96482 -293.882695) (xy 437.987461 -293.833124) (xy 438.016927 -293.787279) (xy 438.052618 -293.746094)
			(xy 438.093806 -293.710407) (xy 438.139653 -293.680945) (xy 438.189227 -293.658308) (xy 438.241517 -293.642956)
			(xy 438.29546 -293.635202) (xy 438.349958 -293.635203) (xy 438.403901 -293.64296) (xy 438.456191 -293.658314)
			(xy 438.505763 -293.680954) (xy 438.551609 -293.710418) (xy 438.592796 -293.746107) (xy 438.628484 -293.787294)
			(xy 438.657948 -293.83314) (xy 438.680587 -293.882713) (xy 438.695941 -293.935003) (xy 438.702499 -293.980616)
			(xy 439.58078 -293.980616) (xy 439.584851 -293.924994) (xy 439.596977 -293.870557) (xy 439.6169 -293.818466)
			(xy 439.644196 -293.769831) (xy 439.678282 -293.725688) (xy 439.718431 -293.686979) (xy 439.763789 -293.654528)
			(xy 439.813389 -293.629027) (xy 439.866173 -293.61102) (xy 439.921016 -293.60089) (xy 439.97675 -293.598853)
			(xy 440.032187 -293.604953) (xy 440.086144 -293.619059) (xy 440.137473 -293.640871) (xy 440.185079 -293.669925)
			(xy 440.227947 -293.7056) (xy 440.265164 -293.747137) (xy 440.295937 -293.79365) (xy 440.319609 -293.844147)
			(xy 440.335677 -293.897554) (xy 440.343797 -293.95273) (xy 440.344306 -293.980616) (xy 440.343797 -294.008502)
			(xy 440.335677 -294.063678) (xy 440.319609 -294.117085) (xy 440.295937 -294.167582) (xy 440.265164 -294.214095)
			(xy 440.227947 -294.255632) (xy 440.185079 -294.291307) (xy 440.137473 -294.320361) (xy 440.086144 -294.342173)
			(xy 440.032187 -294.356279) (xy 439.97675 -294.362379) (xy 439.921016 -294.360342) (xy 439.866173 -294.350212)
			(xy 439.813389 -294.332205) (xy 439.763789 -294.306704) (xy 439.718431 -294.274253) (xy 439.678282 -294.235544)
			(xy 439.644196 -294.191401) (xy 439.6169 -294.142766) (xy 439.596977 -294.090675) (xy 439.584851 -294.036238)
			(xy 439.58078 -293.980616) (xy 438.702499 -293.980616) (xy 438.703697 -293.988946) (xy 438.703698 -294.043444)
			(xy 438.695943 -294.097387) (xy 438.680591 -294.149677) (xy 438.657953 -294.19925) (xy 438.62849 -294.245098)
			(xy 438.592803 -294.286285) (xy 438.551618 -294.321975) (xy 438.505773 -294.351441) (xy 438.456201 -294.374082)
			(xy 438.403911 -294.389438) (xy 438.349969 -294.397196) (xy 438.32272 -294.397684) (xy 438.29732 -294.396922)
			(xy 438.28259 -294.396475) (xy 438.253872 -294.403022) (xy 438.228216 -294.417492) (xy 438.207756 -294.438681)
			(xy 438.194192 -294.464827) (xy 438.188653 -294.493757) (xy 438.189439 -294.50157) (xy 438.83656 -294.50157)
			(xy 438.840631 -294.445948) (xy 438.852757 -294.391511) (xy 438.87268 -294.33942) (xy 438.899976 -294.290785)
			(xy 438.934062 -294.246642) (xy 438.974211 -294.207933) (xy 439.019569 -294.175482) (xy 439.069169 -294.149981)
			(xy 439.121953 -294.131974) (xy 439.176796 -294.121844) (xy 439.23253 -294.119807) (xy 439.287967 -294.125907)
			(xy 439.341924 -294.140013) (xy 439.393253 -294.161825) (xy 439.440859 -294.190879) (xy 439.483727 -294.226554)
			(xy 439.520944 -294.268091) (xy 439.551717 -294.314604) (xy 439.575389 -294.365101) (xy 439.591457 -294.418508)
			(xy 439.599577 -294.473684) (xy 439.600086 -294.50157) (xy 439.599577 -294.529456) (xy 439.591457 -294.584632)
			(xy 439.575389 -294.638039) (xy 439.551717 -294.688536) (xy 439.520944 -294.735049) (xy 439.483727 -294.776586)
			(xy 439.440859 -294.812261) (xy 439.393253 -294.841315) (xy 439.341924 -294.863127) (xy 439.287967 -294.877233)
			(xy 439.23253 -294.883333) (xy 439.176796 -294.881296) (xy 439.121953 -294.871166) (xy 439.069169 -294.853159)
			(xy 439.019569 -294.827658) (xy 438.974211 -294.795207) (xy 438.934062 -294.756498) (xy 438.899976 -294.712355)
			(xy 438.87268 -294.66372) (xy 438.852757 -294.611629) (xy 438.840631 -294.557192) (xy 438.83656 -294.50157)
			(xy 438.189439 -294.50157) (xy 438.1916 -294.523064) (xy 438.196736 -294.536876) (xy 438.205882 -294.560084)
			(xy 438.218779 -294.608272) (xy 438.225284 -294.65773) (xy 438.225692 -294.682672) (xy 438.225275 -294.709927)
			(xy 438.217521 -294.763883) (xy 438.202168 -294.816186) (xy 438.179527 -294.865772) (xy 438.15006 -294.911631)
			(xy 438.114366 -294.952829) (xy 438.073172 -294.988529) (xy 438.027318 -295.018002) (xy 437.977735 -295.04065)
			(xy 437.925434 -295.05601) (xy 437.871479 -295.063771) (xy 437.816969 -295.063775) (xy 437.763013 -295.056021)
			(xy 437.71071 -295.040666) (xy 437.661125 -295.018025) (xy 437.615266 -294.988557) (xy 437.574068 -294.952863)
			(xy 437.538369 -294.911669) (xy 437.508896 -294.865814) (xy 437.486249 -294.816231) (xy 437.470889 -294.76393)
			(xy 437.463128 -294.709975) (xy 437.463125 -294.655465) (xy 431.47054 -294.655465) (xy 431.453842 -294.677686)
			(xy 431.418349 -294.711778) (xy 431.377846 -294.739734) (xy 431.333384 -294.760832) (xy 431.286113 -294.774524)
			(xy 431.237258 -294.780456) (xy 431.188083 -294.778475) (xy 431.139864 -294.768631) (xy 431.093848 -294.751179)
			(xy 431.051227 -294.726572) (xy 431.013106 -294.695447) (xy 430.980471 -294.65861) (xy 430.954168 -294.617014)
			(xy 430.934877 -294.571738) (xy 430.9231 -294.523954) (xy 430.91914 -294.4749) (xy 430.580292 -294.4749)
			(xy 430.579797 -294.499507) (xy 430.571902 -294.548084) (xy 430.556318 -294.594765) (xy 430.533447 -294.638342)
			(xy 430.503882 -294.677686) (xy 430.468389 -294.711778) (xy 430.427886 -294.739734) (xy 430.383424 -294.760832)
			(xy 430.336153 -294.774524) (xy 430.287298 -294.780456) (xy 430.238123 -294.778475) (xy 430.189904 -294.768631)
			(xy 430.143888 -294.751179) (xy 430.101267 -294.726572) (xy 430.063146 -294.695447) (xy 430.030511 -294.65861)
			(xy 430.004208 -294.617014) (xy 429.984917 -294.571738) (xy 429.97314 -294.523954) (xy 429.96918 -294.4749)
			(xy 429.630332 -294.4749) (xy 429.629837 -294.499507) (xy 429.621942 -294.548084) (xy 429.606358 -294.594765)
			(xy 429.583487 -294.638342) (xy 429.553922 -294.677686) (xy 429.518429 -294.711778) (xy 429.477926 -294.739734)
			(xy 429.433464 -294.760832) (xy 429.386193 -294.774524) (xy 429.337338 -294.780456) (xy 429.288163 -294.778475)
			(xy 429.239944 -294.768631) (xy 429.193928 -294.751179) (xy 429.151307 -294.726572) (xy 429.113186 -294.695447)
			(xy 429.080551 -294.65861) (xy 429.054248 -294.617014) (xy 429.034957 -294.571738) (xy 429.02318 -294.523954)
			(xy 429.01922 -294.4749) (xy 428.680118 -294.4749) (xy 428.679623 -294.499507) (xy 428.671728 -294.548084)
			(xy 428.656144 -294.594765) (xy 428.633273 -294.638342) (xy 428.603708 -294.677686) (xy 428.568215 -294.711778)
			(xy 428.527712 -294.739734) (xy 428.48325 -294.760832) (xy 428.435979 -294.774524) (xy 428.387124 -294.780456)
			(xy 428.337949 -294.778475) (xy 428.28973 -294.768631) (xy 428.243714 -294.751179) (xy 428.201093 -294.726572)
			(xy 428.162972 -294.695447) (xy 428.130337 -294.65861) (xy 428.104034 -294.617014) (xy 428.084743 -294.571738)
			(xy 428.072966 -294.523954) (xy 428.069006 -294.4749) (xy 427.730158 -294.4749) (xy 427.729663 -294.499507)
			(xy 427.721768 -294.548084) (xy 427.706184 -294.594765) (xy 427.683313 -294.638342) (xy 427.653748 -294.677686)
			(xy 427.618255 -294.711778) (xy 427.577752 -294.739734) (xy 427.53329 -294.760832) (xy 427.486019 -294.774524)
			(xy 427.437164 -294.780456) (xy 427.387989 -294.778475) (xy 427.33977 -294.768631) (xy 427.293754 -294.751179)
			(xy 427.251133 -294.726572) (xy 427.213012 -294.695447) (xy 427.180377 -294.65861) (xy 427.154074 -294.617014)
			(xy 427.134783 -294.571738) (xy 427.123006 -294.523954) (xy 427.119046 -294.4749) (xy 426.780198 -294.4749)
			(xy 426.779703 -294.499507) (xy 426.771808 -294.548084) (xy 426.756224 -294.594765) (xy 426.733353 -294.638342)
			(xy 426.703788 -294.677686) (xy 426.668295 -294.711778) (xy 426.627792 -294.739734) (xy 426.58333 -294.760832)
			(xy 426.536059 -294.774524) (xy 426.487204 -294.780456) (xy 426.438029 -294.778475) (xy 426.38981 -294.768631)
			(xy 426.343794 -294.751179) (xy 426.301173 -294.726572) (xy 426.263052 -294.695447) (xy 426.230417 -294.65861)
			(xy 426.204114 -294.617014) (xy 426.184823 -294.571738) (xy 426.173046 -294.523954) (xy 426.169086 -294.4749)
			(xy 425.830238 -294.4749) (xy 425.829743 -294.499507) (xy 425.821848 -294.548084) (xy 425.806264 -294.594765)
			(xy 425.783393 -294.638342) (xy 425.753828 -294.677686) (xy 425.718335 -294.711778) (xy 425.677832 -294.739734)
			(xy 425.63337 -294.760832) (xy 425.586099 -294.774524) (xy 425.537244 -294.780456) (xy 425.488069 -294.778475)
			(xy 425.43985 -294.768631) (xy 425.393834 -294.751179) (xy 425.351213 -294.726572) (xy 425.313092 -294.695447)
			(xy 425.280457 -294.65861) (xy 425.254154 -294.617014) (xy 425.234863 -294.571738) (xy 425.223086 -294.523954)
			(xy 425.219126 -294.4749) (xy 424.880278 -294.4749) (xy 424.879783 -294.499507) (xy 424.871888 -294.548084)
			(xy 424.856304 -294.594765) (xy 424.833433 -294.638342) (xy 424.803868 -294.677686) (xy 424.768375 -294.711778)
			(xy 424.727872 -294.739734) (xy 424.68341 -294.760832) (xy 424.636139 -294.774524) (xy 424.587284 -294.780456)
			(xy 424.538109 -294.778475) (xy 424.48989 -294.768631) (xy 424.443874 -294.751179) (xy 424.401253 -294.726572)
			(xy 424.363132 -294.695447) (xy 424.330497 -294.65861) (xy 424.304194 -294.617014) (xy 424.284903 -294.571738)
			(xy 424.273126 -294.523954) (xy 424.269166 -294.4749) (xy 423.930318 -294.4749) (xy 423.929823 -294.499507)
			(xy 423.921928 -294.548084) (xy 423.906344 -294.594765) (xy 423.883473 -294.638342) (xy 423.853908 -294.677686)
			(xy 423.818415 -294.711778) (xy 423.777912 -294.739734) (xy 423.73345 -294.760832) (xy 423.686179 -294.774524)
			(xy 423.637324 -294.780456) (xy 423.588149 -294.778475) (xy 423.53993 -294.768631) (xy 423.493914 -294.751179)
			(xy 423.451293 -294.726572) (xy 423.413172 -294.695447) (xy 423.380537 -294.65861) (xy 423.354234 -294.617014)
			(xy 423.334943 -294.571738) (xy 423.323166 -294.523954) (xy 423.319206 -294.4749) (xy 422.980104 -294.4749)
			(xy 422.979609 -294.499507) (xy 422.971714 -294.548084) (xy 422.95613 -294.594765) (xy 422.933259 -294.638342)
			(xy 422.903694 -294.677686) (xy 422.868201 -294.711778) (xy 422.827698 -294.739734) (xy 422.783236 -294.760832)
			(xy 422.735965 -294.774524) (xy 422.68711 -294.780456) (xy 422.637935 -294.778475) (xy 422.589716 -294.768631)
			(xy 422.5437 -294.751179) (xy 422.501079 -294.726572) (xy 422.462958 -294.695447) (xy 422.430323 -294.65861)
			(xy 422.40402 -294.617014) (xy 422.384729 -294.571738) (xy 422.372952 -294.523954) (xy 422.368992 -294.4749)
			(xy 422.030144 -294.4749) (xy 422.029649 -294.499507) (xy 422.021754 -294.548084) (xy 422.00617 -294.594765)
			(xy 421.983299 -294.638342) (xy 421.953734 -294.677686) (xy 421.918241 -294.711778) (xy 421.877738 -294.739734)
			(xy 421.833276 -294.760832) (xy 421.786005 -294.774524) (xy 421.73715 -294.780456) (xy 421.687975 -294.778475)
			(xy 421.639756 -294.768631) (xy 421.59374 -294.751179) (xy 421.551119 -294.726572) (xy 421.512998 -294.695447)
			(xy 421.480363 -294.65861) (xy 421.45406 -294.617014) (xy 421.434769 -294.571738) (xy 421.422992 -294.523954)
			(xy 421.419032 -294.4749) (xy 420.130224 -294.4749) (xy 420.129729 -294.499507) (xy 420.121834 -294.548084)
			(xy 420.10625 -294.594765) (xy 420.083379 -294.638342) (xy 420.053814 -294.677686) (xy 420.018321 -294.711778)
			(xy 419.977818 -294.739734) (xy 419.933356 -294.760832) (xy 419.886085 -294.774524) (xy 419.83723 -294.780456)
			(xy 419.788055 -294.778475) (xy 419.739836 -294.768631) (xy 419.69382 -294.751179) (xy 419.651199 -294.726572)
			(xy 419.613078 -294.695447) (xy 419.580443 -294.65861) (xy 419.55414 -294.617014) (xy 419.534849 -294.571738)
			(xy 419.523072 -294.523954) (xy 419.519112 -294.4749) (xy 419.180264 -294.4749) (xy 419.179769 -294.499507)
			(xy 419.171874 -294.548084) (xy 419.15629 -294.594765) (xy 419.133419 -294.638342) (xy 419.103854 -294.677686)
			(xy 419.068361 -294.711778) (xy 419.027858 -294.739734) (xy 418.983396 -294.760832) (xy 418.936125 -294.774524)
			(xy 418.88727 -294.780456) (xy 418.838095 -294.778475) (xy 418.789876 -294.768631) (xy 418.74386 -294.751179)
			(xy 418.701239 -294.726572) (xy 418.663118 -294.695447) (xy 418.630483 -294.65861) (xy 418.60418 -294.617014)
			(xy 418.584889 -294.571738) (xy 418.573112 -294.523954) (xy 418.569152 -294.4749) (xy 418.231624 -294.4749)
			(xy 418.227441 -294.525369) (xy 418.21501 -294.574461) (xy 418.194667 -294.620838) (xy 418.166968 -294.663233)
			(xy 418.132669 -294.700492) (xy 418.092705 -294.731596) (xy 418.048167 -294.755699) (xy 418.000268 -294.772142)
			(xy 417.950317 -294.780477) (xy 417.924996 -294.78097) (xy 417.924742 -294.78097) (xy 417.897275 -294.780335)
			(xy 417.843227 -294.770502) (xy 417.8173 -294.761412) (xy 417.805616 -294.757094) (xy 417.780978 -294.760142)
			(xy 417.702492 -294.814244) (xy 417.692827 -294.821859) (xy 417.681423 -294.843619) (xy 417.680648 -294.8559)
			(xy 417.680648 -295.355518) (xy 440.915804 -295.355518) (xy 440.919875 -295.299896) (xy 440.932001 -295.245459)
			(xy 440.951924 -295.193368) (xy 440.97922 -295.144733) (xy 441.013306 -295.10059) (xy 441.053455 -295.061881)
			(xy 441.098813 -295.02943) (xy 441.148413 -295.003929) (xy 441.201197 -294.985922) (xy 441.25604 -294.975792)
			(xy 441.311774 -294.973755) (xy 441.367211 -294.979855) (xy 441.421168 -294.993961) (xy 441.472497 -295.015773)
			(xy 441.520103 -295.044827) (xy 441.562971 -295.080502) (xy 441.600188 -295.122039) (xy 441.630961 -295.168552)
			(xy 441.654633 -295.219049) (xy 441.670701 -295.272456) (xy 441.678821 -295.327632) (xy 441.67933 -295.355518)
			(xy 441.678821 -295.383404) (xy 441.670701 -295.43858) (xy 441.654633 -295.491987) (xy 441.630961 -295.542484)
			(xy 441.600188 -295.588997) (xy 441.562971 -295.630534) (xy 441.520103 -295.666209) (xy 441.472497 -295.695263)
			(xy 441.421168 -295.717075) (xy 441.367211 -295.731181) (xy 441.311774 -295.737281) (xy 441.25604 -295.735244)
			(xy 441.201197 -295.725114) (xy 441.148413 -295.707107) (xy 441.098813 -295.681606) (xy 441.053455 -295.649155)
			(xy 441.013306 -295.610446) (xy 440.97922 -295.566303) (xy 440.951924 -295.517668) (xy 440.932001 -295.465577)
			(xy 440.919875 -295.41114) (xy 440.915804 -295.355518) (xy 417.680648 -295.355518) (xy 417.680648 -295.99382)
			(xy 417.68124 -296.006146) (xy 417.692694 -296.027973) (xy 417.702492 -296.035476) (xy 417.780978 -296.089578)
			(xy 417.805616 -296.092626) (xy 417.8173 -296.088308) (xy 417.843217 -296.07918) (xy 417.897271 -296.069337)
			(xy 417.924742 -296.06875) (xy 417.924996 -296.06875) (xy 417.950315 -296.069243) (xy 418.000263 -296.077578)
			(xy 418.048159 -296.09402) (xy 418.092694 -296.11812) (xy 418.132655 -296.149223) (xy 418.166952 -296.186479)
			(xy 418.194649 -296.228872) (xy 418.214991 -296.275245) (xy 418.227422 -296.324334) (xy 418.231604 -296.3748)
			(xy 418.231602 -296.37482) (xy 418.569152 -296.37482) (xy 418.573112 -296.325766) (xy 418.584889 -296.277982)
			(xy 418.60418 -296.232706) (xy 418.630483 -296.19111) (xy 418.663118 -296.154273) (xy 418.701239 -296.123148)
			(xy 418.74386 -296.098541) (xy 418.789876 -296.081089) (xy 418.838095 -296.071245) (xy 418.88727 -296.069264)
			(xy 418.936125 -296.075196) (xy 418.983396 -296.088888) (xy 419.027858 -296.109986) (xy 419.068361 -296.137942)
			(xy 419.103854 -296.172034) (xy 419.133419 -296.211378) (xy 419.15629 -296.254955) (xy 419.171874 -296.301636)
			(xy 419.179769 -296.350213) (xy 419.180264 -296.37482) (xy 419.519112 -296.37482) (xy 419.523072 -296.325766)
			(xy 419.534849 -296.277982) (xy 419.55414 -296.232706) (xy 419.580443 -296.19111) (xy 419.613078 -296.154273)
			(xy 419.651199 -296.123148) (xy 419.69382 -296.098541) (xy 419.739836 -296.081089) (xy 419.788055 -296.071245)
			(xy 419.83723 -296.069264) (xy 419.886085 -296.075196) (xy 419.933356 -296.088888) (xy 419.977818 -296.109986)
			(xy 420.018321 -296.137942) (xy 420.053814 -296.172034) (xy 420.083379 -296.211378) (xy 420.10625 -296.254955)
			(xy 420.121834 -296.301636) (xy 420.129729 -296.350213) (xy 420.130224 -296.37482) (xy 421.419032 -296.37482)
			(xy 421.422992 -296.325766) (xy 421.434769 -296.277982) (xy 421.45406 -296.232706) (xy 421.480363 -296.19111)
			(xy 421.512998 -296.154273) (xy 421.551119 -296.123148) (xy 421.59374 -296.098541) (xy 421.639756 -296.081089)
			(xy 421.687975 -296.071245) (xy 421.73715 -296.069264) (xy 421.786005 -296.075196) (xy 421.833276 -296.088888)
			(xy 421.877738 -296.109986) (xy 421.918241 -296.137942) (xy 421.953734 -296.172034) (xy 421.983299 -296.211378)
			(xy 422.00617 -296.254955) (xy 422.021754 -296.301636) (xy 422.029649 -296.350213) (xy 422.030144 -296.37482)
			(xy 422.368992 -296.37482) (xy 422.372952 -296.325766) (xy 422.384729 -296.277982) (xy 422.40402 -296.232706)
			(xy 422.430323 -296.19111) (xy 422.462958 -296.154273) (xy 422.501079 -296.123148) (xy 422.5437 -296.098541)
			(xy 422.589716 -296.081089) (xy 422.637935 -296.071245) (xy 422.68711 -296.069264) (xy 422.735965 -296.075196)
			(xy 422.783236 -296.088888) (xy 422.827698 -296.109986) (xy 422.868201 -296.137942) (xy 422.903694 -296.172034)
			(xy 422.933259 -296.211378) (xy 422.95613 -296.254955) (xy 422.971714 -296.301636) (xy 422.979609 -296.350213)
			(xy 422.980104 -296.37482) (xy 423.319206 -296.37482) (xy 423.323166 -296.325766) (xy 423.334943 -296.277982)
			(xy 423.354234 -296.232706) (xy 423.380537 -296.19111) (xy 423.413172 -296.154273) (xy 423.451293 -296.123148)
			(xy 423.493914 -296.098541) (xy 423.53993 -296.081089) (xy 423.588149 -296.071245) (xy 423.637324 -296.069264)
			(xy 423.686179 -296.075196) (xy 423.73345 -296.088888) (xy 423.777912 -296.109986) (xy 423.818415 -296.137942)
			(xy 423.853908 -296.172034) (xy 423.883473 -296.211378) (xy 423.906344 -296.254955) (xy 423.921928 -296.301636)
			(xy 423.929823 -296.350213) (xy 423.930318 -296.37482) (xy 424.269166 -296.37482) (xy 424.273126 -296.325766)
			(xy 424.284903 -296.277982) (xy 424.304194 -296.232706) (xy 424.330497 -296.19111) (xy 424.363132 -296.154273)
			(xy 424.401253 -296.123148) (xy 424.443874 -296.098541) (xy 424.48989 -296.081089) (xy 424.538109 -296.071245)
			(xy 424.587284 -296.069264) (xy 424.636139 -296.075196) (xy 424.68341 -296.088888) (xy 424.727872 -296.109986)
			(xy 424.768375 -296.137942) (xy 424.803868 -296.172034) (xy 424.833433 -296.211378) (xy 424.856304 -296.254955)
			(xy 424.871888 -296.301636) (xy 424.879783 -296.350213) (xy 424.880278 -296.37482) (xy 425.219126 -296.37482)
			(xy 425.223086 -296.325766) (xy 425.234863 -296.277982) (xy 425.254154 -296.232706) (xy 425.280457 -296.19111)
			(xy 425.313092 -296.154273) (xy 425.351213 -296.123148) (xy 425.393834 -296.098541) (xy 425.43985 -296.081089)
			(xy 425.488069 -296.071245) (xy 425.537244 -296.069264) (xy 425.586099 -296.075196) (xy 425.63337 -296.088888)
			(xy 425.677832 -296.109986) (xy 425.718335 -296.137942) (xy 425.753828 -296.172034) (xy 425.783393 -296.211378)
			(xy 425.806264 -296.254955) (xy 425.821848 -296.301636) (xy 425.829743 -296.350213) (xy 425.830238 -296.37482)
			(xy 426.169086 -296.37482) (xy 426.173046 -296.325766) (xy 426.184823 -296.277982) (xy 426.204114 -296.232706)
			(xy 426.230417 -296.19111) (xy 426.263052 -296.154273) (xy 426.301173 -296.123148) (xy 426.343794 -296.098541)
			(xy 426.38981 -296.081089) (xy 426.438029 -296.071245) (xy 426.487204 -296.069264) (xy 426.536059 -296.075196)
			(xy 426.58333 -296.088888) (xy 426.627792 -296.109986) (xy 426.668295 -296.137942) (xy 426.703788 -296.172034)
			(xy 426.733353 -296.211378) (xy 426.756224 -296.254955) (xy 426.771808 -296.301636) (xy 426.779703 -296.350213)
			(xy 426.780198 -296.37482) (xy 427.119046 -296.37482) (xy 427.123006 -296.325766) (xy 427.134783 -296.277982)
			(xy 427.154074 -296.232706) (xy 427.180377 -296.19111) (xy 427.213012 -296.154273) (xy 427.251133 -296.123148)
			(xy 427.293754 -296.098541) (xy 427.33977 -296.081089) (xy 427.387989 -296.071245) (xy 427.437164 -296.069264)
			(xy 427.486019 -296.075196) (xy 427.53329 -296.088888) (xy 427.577752 -296.109986) (xy 427.618255 -296.137942)
			(xy 427.653748 -296.172034) (xy 427.683313 -296.211378) (xy 427.706184 -296.254955) (xy 427.721768 -296.301636)
			(xy 427.729663 -296.350213) (xy 427.730158 -296.37482) (xy 428.069006 -296.37482) (xy 428.072966 -296.325766)
			(xy 428.084743 -296.277982) (xy 428.104034 -296.232706) (xy 428.130337 -296.19111) (xy 428.162972 -296.154273)
			(xy 428.201093 -296.123148) (xy 428.243714 -296.098541) (xy 428.28973 -296.081089) (xy 428.337949 -296.071245)
			(xy 428.387124 -296.069264) (xy 428.435979 -296.075196) (xy 428.48325 -296.088888) (xy 428.527712 -296.109986)
			(xy 428.568215 -296.137942) (xy 428.603708 -296.172034) (xy 428.633273 -296.211378) (xy 428.656144 -296.254955)
			(xy 428.671728 -296.301636) (xy 428.679623 -296.350213) (xy 428.680118 -296.37482) (xy 429.01922 -296.37482)
			(xy 429.02318 -296.325766) (xy 429.034957 -296.277982) (xy 429.054248 -296.232706) (xy 429.080551 -296.19111)
			(xy 429.113186 -296.154273) (xy 429.151307 -296.123148) (xy 429.193928 -296.098541) (xy 429.239944 -296.081089)
			(xy 429.288163 -296.071245) (xy 429.337338 -296.069264) (xy 429.386193 -296.075196) (xy 429.433464 -296.088888)
			(xy 429.477926 -296.109986) (xy 429.518429 -296.137942) (xy 429.553922 -296.172034) (xy 429.583487 -296.211378)
			(xy 429.606358 -296.254955) (xy 429.621942 -296.301636) (xy 429.629837 -296.350213) (xy 429.630332 -296.37482)
			(xy 429.96918 -296.37482) (xy 429.97314 -296.325766) (xy 429.984917 -296.277982) (xy 430.004208 -296.232706)
			(xy 430.030511 -296.19111) (xy 430.063146 -296.154273) (xy 430.101267 -296.123148) (xy 430.143888 -296.098541)
			(xy 430.189904 -296.081089) (xy 430.238123 -296.071245) (xy 430.287298 -296.069264) (xy 430.336153 -296.075196)
			(xy 430.383424 -296.088888) (xy 430.427886 -296.109986) (xy 430.468389 -296.137942) (xy 430.503882 -296.172034)
			(xy 430.533447 -296.211378) (xy 430.556318 -296.254955) (xy 430.571902 -296.301636) (xy 430.579797 -296.350213)
			(xy 430.580292 -296.37482) (xy 430.91914 -296.37482) (xy 430.9231 -296.325766) (xy 430.934877 -296.277982)
			(xy 430.954168 -296.232706) (xy 430.980471 -296.19111) (xy 431.013106 -296.154273) (xy 431.051227 -296.123148)
			(xy 431.093848 -296.098541) (xy 431.139864 -296.081089) (xy 431.188083 -296.071245) (xy 431.237258 -296.069264)
			(xy 431.286113 -296.075196) (xy 431.333384 -296.088888) (xy 431.377846 -296.109986) (xy 431.418349 -296.137942)
			(xy 431.453842 -296.172034) (xy 431.483407 -296.211378) (xy 431.506278 -296.254955) (xy 431.521862 -296.301636)
			(xy 431.529757 -296.350213) (xy 431.530252 -296.37482) (xy 431.529757 -296.399427) (xy 431.521862 -296.448004)
			(xy 431.506278 -296.494685) (xy 431.483407 -296.538262) (xy 431.453842 -296.577606) (xy 431.418349 -296.611698)
			(xy 431.416358 -296.613072) (xy 437.562496 -296.613072) (xy 437.566567 -296.55745) (xy 437.578693 -296.503013)
			(xy 437.598616 -296.450922) (xy 437.625912 -296.402287) (xy 437.659998 -296.358144) (xy 437.700147 -296.319435)
			(xy 437.745505 -296.286984) (xy 437.795105 -296.261483) (xy 437.847889 -296.243476) (xy 437.902732 -296.233346)
			(xy 437.958466 -296.231309) (xy 438.013903 -296.237409) (xy 438.06786 -296.251515) (xy 438.119189 -296.273327)
			(xy 438.166795 -296.302381) (xy 438.209663 -296.338056) (xy 438.24688 -296.379593) (xy 438.277653 -296.426106)
			(xy 438.301325 -296.476603) (xy 438.317393 -296.53001) (xy 438.325513 -296.585186) (xy 438.326022 -296.613072)
			(xy 438.837322 -296.613072) (xy 438.841393 -296.55745) (xy 438.853519 -296.503013) (xy 438.873442 -296.450922)
			(xy 438.900738 -296.402287) (xy 438.934824 -296.358144) (xy 438.974973 -296.319435) (xy 439.020331 -296.286984)
			(xy 439.069931 -296.261483) (xy 439.122715 -296.243476) (xy 439.177558 -296.233346) (xy 439.233292 -296.231309)
			(xy 439.288729 -296.237409) (xy 439.342686 -296.251515) (xy 439.394015 -296.273327) (xy 439.441621 -296.302381)
			(xy 439.484489 -296.338056) (xy 439.521706 -296.379593) (xy 439.552479 -296.426106) (xy 439.576151 -296.476603)
			(xy 439.592219 -296.53001) (xy 439.600339 -296.585186) (xy 439.600848 -296.613072) (xy 439.600339 -296.640958)
			(xy 439.592219 -296.696134) (xy 439.576151 -296.749541) (xy 439.552479 -296.800038) (xy 439.521706 -296.846551)
			(xy 439.484489 -296.888088) (xy 439.441621 -296.923763) (xy 439.394015 -296.952817) (xy 439.342686 -296.974629)
			(xy 439.288729 -296.988735) (xy 439.233292 -296.994835) (xy 439.177558 -296.992798) (xy 439.122715 -296.982668)
			(xy 439.069931 -296.964661) (xy 439.020331 -296.93916) (xy 438.974973 -296.906709) (xy 438.934824 -296.868)
			(xy 438.900738 -296.823857) (xy 438.873442 -296.775222) (xy 438.853519 -296.723131) (xy 438.841393 -296.668694)
			(xy 438.837322 -296.613072) (xy 438.326022 -296.613072) (xy 438.325513 -296.640958) (xy 438.317393 -296.696134)
			(xy 438.301325 -296.749541) (xy 438.277653 -296.800038) (xy 438.24688 -296.846551) (xy 438.209663 -296.888088)
			(xy 438.166795 -296.923763) (xy 438.119189 -296.952817) (xy 438.06786 -296.974629) (xy 438.013903 -296.988735)
			(xy 437.958466 -296.994835) (xy 437.902732 -296.992798) (xy 437.847889 -296.982668) (xy 437.795105 -296.964661)
			(xy 437.745505 -296.93916) (xy 437.700147 -296.906709) (xy 437.659998 -296.868) (xy 437.625912 -296.823857)
			(xy 437.598616 -296.775222) (xy 437.578693 -296.723131) (xy 437.566567 -296.668694) (xy 437.562496 -296.613072)
			(xy 431.416358 -296.613072) (xy 431.377846 -296.639654) (xy 431.333384 -296.660752) (xy 431.286113 -296.674444)
			(xy 431.237258 -296.680376) (xy 431.188083 -296.678395) (xy 431.139864 -296.668551) (xy 431.093848 -296.651099)
			(xy 431.051227 -296.626492) (xy 431.013106 -296.595367) (xy 430.980471 -296.55853) (xy 430.954168 -296.516934)
			(xy 430.934877 -296.471658) (xy 430.9231 -296.423874) (xy 430.91914 -296.37482) (xy 430.580292 -296.37482)
			(xy 430.579797 -296.399427) (xy 430.571902 -296.448004) (xy 430.556318 -296.494685) (xy 430.533447 -296.538262)
			(xy 430.503882 -296.577606) (xy 430.468389 -296.611698) (xy 430.427886 -296.639654) (xy 430.383424 -296.660752)
			(xy 430.336153 -296.674444) (xy 430.287298 -296.680376) (xy 430.238123 -296.678395) (xy 430.189904 -296.668551)
			(xy 430.143888 -296.651099) (xy 430.101267 -296.626492) (xy 430.063146 -296.595367) (xy 430.030511 -296.55853)
			(xy 430.004208 -296.516934) (xy 429.984917 -296.471658) (xy 429.97314 -296.423874) (xy 429.96918 -296.37482)
			(xy 429.630332 -296.37482) (xy 429.629837 -296.399427) (xy 429.621942 -296.448004) (xy 429.606358 -296.494685)
			(xy 429.583487 -296.538262) (xy 429.553922 -296.577606) (xy 429.518429 -296.611698) (xy 429.477926 -296.639654)
			(xy 429.433464 -296.660752) (xy 429.386193 -296.674444) (xy 429.337338 -296.680376) (xy 429.288163 -296.678395)
			(xy 429.239944 -296.668551) (xy 429.193928 -296.651099) (xy 429.151307 -296.626492) (xy 429.113186 -296.595367)
			(xy 429.080551 -296.55853) (xy 429.054248 -296.516934) (xy 429.034957 -296.471658) (xy 429.02318 -296.423874)
			(xy 429.01922 -296.37482) (xy 428.680118 -296.37482) (xy 428.679623 -296.399427) (xy 428.671728 -296.448004)
			(xy 428.656144 -296.494685) (xy 428.633273 -296.538262) (xy 428.603708 -296.577606) (xy 428.568215 -296.611698)
			(xy 428.527712 -296.639654) (xy 428.48325 -296.660752) (xy 428.435979 -296.674444) (xy 428.387124 -296.680376)
			(xy 428.337949 -296.678395) (xy 428.28973 -296.668551) (xy 428.243714 -296.651099) (xy 428.201093 -296.626492)
			(xy 428.162972 -296.595367) (xy 428.130337 -296.55853) (xy 428.104034 -296.516934) (xy 428.084743 -296.471658)
			(xy 428.072966 -296.423874) (xy 428.069006 -296.37482) (xy 427.730158 -296.37482) (xy 427.729663 -296.399427)
			(xy 427.721768 -296.448004) (xy 427.706184 -296.494685) (xy 427.683313 -296.538262) (xy 427.653748 -296.577606)
			(xy 427.618255 -296.611698) (xy 427.577752 -296.639654) (xy 427.53329 -296.660752) (xy 427.486019 -296.674444)
			(xy 427.437164 -296.680376) (xy 427.387989 -296.678395) (xy 427.33977 -296.668551) (xy 427.293754 -296.651099)
			(xy 427.251133 -296.626492) (xy 427.213012 -296.595367) (xy 427.180377 -296.55853) (xy 427.154074 -296.516934)
			(xy 427.134783 -296.471658) (xy 427.123006 -296.423874) (xy 427.119046 -296.37482) (xy 426.780198 -296.37482)
			(xy 426.779703 -296.399427) (xy 426.771808 -296.448004) (xy 426.756224 -296.494685) (xy 426.733353 -296.538262)
			(xy 426.703788 -296.577606) (xy 426.668295 -296.611698) (xy 426.627792 -296.639654) (xy 426.58333 -296.660752)
			(xy 426.536059 -296.674444) (xy 426.487204 -296.680376) (xy 426.438029 -296.678395) (xy 426.38981 -296.668551)
			(xy 426.343794 -296.651099) (xy 426.301173 -296.626492) (xy 426.263052 -296.595367) (xy 426.230417 -296.55853)
			(xy 426.204114 -296.516934) (xy 426.184823 -296.471658) (xy 426.173046 -296.423874) (xy 426.169086 -296.37482)
			(xy 425.830238 -296.37482) (xy 425.829743 -296.399427) (xy 425.821848 -296.448004) (xy 425.806264 -296.494685)
			(xy 425.783393 -296.538262) (xy 425.753828 -296.577606) (xy 425.718335 -296.611698) (xy 425.677832 -296.639654)
			(xy 425.63337 -296.660752) (xy 425.586099 -296.674444) (xy 425.537244 -296.680376) (xy 425.488069 -296.678395)
			(xy 425.43985 -296.668551) (xy 425.393834 -296.651099) (xy 425.351213 -296.626492) (xy 425.313092 -296.595367)
			(xy 425.280457 -296.55853) (xy 425.254154 -296.516934) (xy 425.234863 -296.471658) (xy 425.223086 -296.423874)
			(xy 425.219126 -296.37482) (xy 424.880278 -296.37482) (xy 424.879783 -296.399427) (xy 424.871888 -296.448004)
			(xy 424.856304 -296.494685) (xy 424.833433 -296.538262) (xy 424.803868 -296.577606) (xy 424.768375 -296.611698)
			(xy 424.727872 -296.639654) (xy 424.68341 -296.660752) (xy 424.636139 -296.674444) (xy 424.587284 -296.680376)
			(xy 424.538109 -296.678395) (xy 424.48989 -296.668551) (xy 424.443874 -296.651099) (xy 424.401253 -296.626492)
			(xy 424.363132 -296.595367) (xy 424.330497 -296.55853) (xy 424.304194 -296.516934) (xy 424.284903 -296.471658)
			(xy 424.273126 -296.423874) (xy 424.269166 -296.37482) (xy 423.930318 -296.37482) (xy 423.929823 -296.399427)
			(xy 423.921928 -296.448004) (xy 423.906344 -296.494685) (xy 423.883473 -296.538262) (xy 423.853908 -296.577606)
			(xy 423.818415 -296.611698) (xy 423.777912 -296.639654) (xy 423.73345 -296.660752) (xy 423.686179 -296.674444)
			(xy 423.637324 -296.680376) (xy 423.588149 -296.678395) (xy 423.53993 -296.668551) (xy 423.493914 -296.651099)
			(xy 423.451293 -296.626492) (xy 423.413172 -296.595367) (xy 423.380537 -296.55853) (xy 423.354234 -296.516934)
			(xy 423.334943 -296.471658) (xy 423.323166 -296.423874) (xy 423.319206 -296.37482) (xy 422.980104 -296.37482)
			(xy 422.979609 -296.399427) (xy 422.971714 -296.448004) (xy 422.95613 -296.494685) (xy 422.933259 -296.538262)
			(xy 422.903694 -296.577606) (xy 422.868201 -296.611698) (xy 422.827698 -296.639654) (xy 422.783236 -296.660752)
			(xy 422.735965 -296.674444) (xy 422.68711 -296.680376) (xy 422.637935 -296.678395) (xy 422.589716 -296.668551)
			(xy 422.5437 -296.651099) (xy 422.501079 -296.626492) (xy 422.462958 -296.595367) (xy 422.430323 -296.55853)
			(xy 422.40402 -296.516934) (xy 422.384729 -296.471658) (xy 422.372952 -296.423874) (xy 422.368992 -296.37482)
			(xy 422.030144 -296.37482) (xy 422.029649 -296.399427) (xy 422.021754 -296.448004) (xy 422.00617 -296.494685)
			(xy 421.983299 -296.538262) (xy 421.953734 -296.577606) (xy 421.918241 -296.611698) (xy 421.877738 -296.639654)
			(xy 421.833276 -296.660752) (xy 421.786005 -296.674444) (xy 421.73715 -296.680376) (xy 421.687975 -296.678395)
			(xy 421.639756 -296.668551) (xy 421.59374 -296.651099) (xy 421.551119 -296.626492) (xy 421.512998 -296.595367)
			(xy 421.480363 -296.55853) (xy 421.45406 -296.516934) (xy 421.434769 -296.471658) (xy 421.422992 -296.423874)
			(xy 421.419032 -296.37482) (xy 420.130224 -296.37482) (xy 420.129729 -296.399427) (xy 420.121834 -296.448004)
			(xy 420.10625 -296.494685) (xy 420.083379 -296.538262) (xy 420.053814 -296.577606) (xy 420.018321 -296.611698)
			(xy 419.977818 -296.639654) (xy 419.933356 -296.660752) (xy 419.886085 -296.674444) (xy 419.83723 -296.680376)
			(xy 419.788055 -296.678395) (xy 419.739836 -296.668551) (xy 419.69382 -296.651099) (xy 419.651199 -296.626492)
			(xy 419.613078 -296.595367) (xy 419.580443 -296.55853) (xy 419.55414 -296.516934) (xy 419.534849 -296.471658)
			(xy 419.523072 -296.423874) (xy 419.519112 -296.37482) (xy 419.180264 -296.37482) (xy 419.179769 -296.399427)
			(xy 419.171874 -296.448004) (xy 419.15629 -296.494685) (xy 419.133419 -296.538262) (xy 419.103854 -296.577606)
			(xy 419.068361 -296.611698) (xy 419.027858 -296.639654) (xy 418.983396 -296.660752) (xy 418.936125 -296.674444)
			(xy 418.88727 -296.680376) (xy 418.838095 -296.678395) (xy 418.789876 -296.668551) (xy 418.74386 -296.651099)
			(xy 418.701239 -296.626492) (xy 418.663118 -296.595367) (xy 418.630483 -296.55853) (xy 418.60418 -296.516934)
			(xy 418.584889 -296.471658) (xy 418.573112 -296.423874) (xy 418.569152 -296.37482) (xy 418.231602 -296.37482)
			(xy 418.227422 -296.425266) (xy 418.214991 -296.474355) (xy 418.194649 -296.520728) (xy 418.166952 -296.563121)
			(xy 418.132655 -296.600377) (xy 418.092694 -296.63148) (xy 418.048159 -296.65558) (xy 418.000263 -296.672022)
			(xy 417.950315 -296.680357) (xy 417.924996 -296.68089) (xy 417.924742 -296.68089) (xy 417.897275 -296.680256)
			(xy 417.843227 -296.670423) (xy 417.8173 -296.661332) (xy 417.805616 -296.657014) (xy 417.780978 -296.660062)
			(xy 417.702492 -296.714164) (xy 417.69283 -296.72178) (xy 417.681434 -296.743541) (xy 417.680648 -296.75582)
			(xy 417.680648 -296.94378) (xy 417.681231 -296.956111) (xy 417.692676 -296.977953) (xy 417.702492 -296.985436)
			(xy 417.780978 -297.039538) (xy 417.805616 -297.042586) (xy 417.8173 -297.038268) (xy 417.843217 -297.029138)
			(xy 417.897271 -297.019293) (xy 417.924742 -297.01871) (xy 417.924996 -297.01871) (xy 417.950319 -297.019204)
			(xy 418.000273 -297.027539) (xy 418.048175 -297.043983) (xy 418.092716 -297.068087) (xy 418.132682 -297.099194)
			(xy 418.166984 -297.136454) (xy 418.194684 -297.178853) (xy 418.215028 -297.225232) (xy 418.227461 -297.274328)
			(xy 418.231642 -297.32478) (xy 418.569152 -297.32478) (xy 418.573112 -297.275726) (xy 418.584889 -297.227942)
			(xy 418.60418 -297.182666) (xy 418.630483 -297.14107) (xy 418.663118 -297.104233) (xy 418.701239 -297.073108)
			(xy 418.74386 -297.048501) (xy 418.789876 -297.031049) (xy 418.838095 -297.021205) (xy 418.88727 -297.019224)
			(xy 418.936125 -297.025156) (xy 418.983396 -297.038848) (xy 419.027858 -297.059946) (xy 419.068361 -297.087902)
			(xy 419.103854 -297.121994) (xy 419.133419 -297.161338) (xy 419.15629 -297.204915) (xy 419.171874 -297.251596)
			(xy 419.179769 -297.300173) (xy 419.180264 -297.32478) (xy 419.519112 -297.32478) (xy 419.523072 -297.275726)
			(xy 419.534849 -297.227942) (xy 419.55414 -297.182666) (xy 419.580443 -297.14107) (xy 419.613078 -297.104233)
			(xy 419.651199 -297.073108) (xy 419.69382 -297.048501) (xy 419.739836 -297.031049) (xy 419.788055 -297.021205)
			(xy 419.83723 -297.019224) (xy 419.886085 -297.025156) (xy 419.933356 -297.038848) (xy 419.977818 -297.059946)
			(xy 420.018321 -297.087902) (xy 420.053814 -297.121994) (xy 420.083379 -297.161338) (xy 420.10625 -297.204915)
			(xy 420.121834 -297.251596) (xy 420.129729 -297.300173) (xy 420.130224 -297.32478) (xy 421.419032 -297.32478)
			(xy 421.422992 -297.275726) (xy 421.434769 -297.227942) (xy 421.45406 -297.182666) (xy 421.480363 -297.14107)
			(xy 421.512998 -297.104233) (xy 421.551119 -297.073108) (xy 421.59374 -297.048501) (xy 421.639756 -297.031049)
			(xy 421.687975 -297.021205) (xy 421.73715 -297.019224) (xy 421.786005 -297.025156) (xy 421.833276 -297.038848)
			(xy 421.877738 -297.059946) (xy 421.918241 -297.087902) (xy 421.953734 -297.121994) (xy 421.983299 -297.161338)
			(xy 422.00617 -297.204915) (xy 422.021754 -297.251596) (xy 422.029649 -297.300173) (xy 422.030144 -297.32478)
			(xy 422.369246 -297.32478) (xy 422.373206 -297.275726) (xy 422.384983 -297.227942) (xy 422.404274 -297.182666)
			(xy 422.430577 -297.14107) (xy 422.463212 -297.104233) (xy 422.501333 -297.073108) (xy 422.543954 -297.048501)
			(xy 422.58997 -297.031049) (xy 422.638189 -297.021205) (xy 422.687364 -297.019224) (xy 422.736219 -297.025156)
			(xy 422.78349 -297.038848) (xy 422.827952 -297.059946) (xy 422.868455 -297.087902) (xy 422.903948 -297.121994)
			(xy 422.933513 -297.161338) (xy 422.956384 -297.204915) (xy 422.971968 -297.251596) (xy 422.979863 -297.300173)
			(xy 422.980358 -297.32478) (xy 423.319206 -297.32478) (xy 423.323166 -297.275726) (xy 423.334943 -297.227942)
			(xy 423.354234 -297.182666) (xy 423.380537 -297.14107) (xy 423.413172 -297.104233) (xy 423.451293 -297.073108)
			(xy 423.493914 -297.048501) (xy 423.53993 -297.031049) (xy 423.588149 -297.021205) (xy 423.637324 -297.019224)
			(xy 423.686179 -297.025156) (xy 423.73345 -297.038848) (xy 423.777912 -297.059946) (xy 423.818415 -297.087902)
			(xy 423.853908 -297.121994) (xy 423.883473 -297.161338) (xy 423.906344 -297.204915) (xy 423.921928 -297.251596)
			(xy 423.929823 -297.300173) (xy 423.930318 -297.32478) (xy 424.269166 -297.32478) (xy 424.273126 -297.275726)
			(xy 424.284903 -297.227942) (xy 424.304194 -297.182666) (xy 424.330497 -297.14107) (xy 424.363132 -297.104233)
			(xy 424.401253 -297.073108) (xy 424.443874 -297.048501) (xy 424.48989 -297.031049) (xy 424.538109 -297.021205)
			(xy 424.587284 -297.019224) (xy 424.636139 -297.025156) (xy 424.68341 -297.038848) (xy 424.727872 -297.059946)
			(xy 424.768375 -297.087902) (xy 424.803868 -297.121994) (xy 424.833433 -297.161338) (xy 424.856304 -297.204915)
			(xy 424.871888 -297.251596) (xy 424.879783 -297.300173) (xy 424.880278 -297.32478) (xy 425.219126 -297.32478)
			(xy 425.223086 -297.275726) (xy 425.234863 -297.227942) (xy 425.254154 -297.182666) (xy 425.280457 -297.14107)
			(xy 425.313092 -297.104233) (xy 425.351213 -297.073108) (xy 425.393834 -297.048501) (xy 425.43985 -297.031049)
			(xy 425.488069 -297.021205) (xy 425.537244 -297.019224) (xy 425.586099 -297.025156) (xy 425.63337 -297.038848)
			(xy 425.677832 -297.059946) (xy 425.718335 -297.087902) (xy 425.753828 -297.121994) (xy 425.783393 -297.161338)
			(xy 425.806264 -297.204915) (xy 425.821848 -297.251596) (xy 425.829743 -297.300173) (xy 425.830238 -297.32478)
			(xy 426.169086 -297.32478) (xy 426.173046 -297.275726) (xy 426.184823 -297.227942) (xy 426.204114 -297.182666)
			(xy 426.230417 -297.14107) (xy 426.263052 -297.104233) (xy 426.301173 -297.073108) (xy 426.343794 -297.048501)
			(xy 426.38981 -297.031049) (xy 426.438029 -297.021205) (xy 426.487204 -297.019224) (xy 426.536059 -297.025156)
			(xy 426.58333 -297.038848) (xy 426.627792 -297.059946) (xy 426.668295 -297.087902) (xy 426.703788 -297.121994)
			(xy 426.733353 -297.161338) (xy 426.756224 -297.204915) (xy 426.771808 -297.251596) (xy 426.779703 -297.300173)
			(xy 426.780198 -297.32478) (xy 427.119046 -297.32478) (xy 427.123006 -297.275726) (xy 427.134783 -297.227942)
			(xy 427.154074 -297.182666) (xy 427.180377 -297.14107) (xy 427.213012 -297.104233) (xy 427.251133 -297.073108)
			(xy 427.293754 -297.048501) (xy 427.33977 -297.031049) (xy 427.387989 -297.021205) (xy 427.437164 -297.019224)
			(xy 427.486019 -297.025156) (xy 427.53329 -297.038848) (xy 427.577752 -297.059946) (xy 427.618255 -297.087902)
			(xy 427.653748 -297.121994) (xy 427.683313 -297.161338) (xy 427.706184 -297.204915) (xy 427.721768 -297.251596)
			(xy 427.729663 -297.300173) (xy 427.730158 -297.32478) (xy 428.069006 -297.32478) (xy 428.072966 -297.275726)
			(xy 428.084743 -297.227942) (xy 428.104034 -297.182666) (xy 428.130337 -297.14107) (xy 428.162972 -297.104233)
			(xy 428.201093 -297.073108) (xy 428.243714 -297.048501) (xy 428.28973 -297.031049) (xy 428.337949 -297.021205)
			(xy 428.387124 -297.019224) (xy 428.435979 -297.025156) (xy 428.48325 -297.038848) (xy 428.527712 -297.059946)
			(xy 428.568215 -297.087902) (xy 428.603708 -297.121994) (xy 428.633273 -297.161338) (xy 428.656144 -297.204915)
			(xy 428.671728 -297.251596) (xy 428.679623 -297.300173) (xy 428.680118 -297.32478) (xy 429.01922 -297.32478)
			(xy 429.02318 -297.275726) (xy 429.034957 -297.227942) (xy 429.054248 -297.182666) (xy 429.080551 -297.14107)
			(xy 429.113186 -297.104233) (xy 429.151307 -297.073108) (xy 429.193928 -297.048501) (xy 429.239944 -297.031049)
			(xy 429.288163 -297.021205) (xy 429.337338 -297.019224) (xy 429.386193 -297.025156) (xy 429.433464 -297.038848)
			(xy 429.477926 -297.059946) (xy 429.518429 -297.087902) (xy 429.553922 -297.121994) (xy 429.583487 -297.161338)
			(xy 429.606358 -297.204915) (xy 429.621942 -297.251596) (xy 429.629837 -297.300173) (xy 429.630332 -297.32478)
			(xy 429.96918 -297.32478) (xy 429.97314 -297.275726) (xy 429.984917 -297.227942) (xy 430.004208 -297.182666)
			(xy 430.030511 -297.14107) (xy 430.063146 -297.104233) (xy 430.101267 -297.073108) (xy 430.143888 -297.048501)
			(xy 430.189904 -297.031049) (xy 430.238123 -297.021205) (xy 430.287298 -297.019224) (xy 430.336153 -297.025156)
			(xy 430.383424 -297.038848) (xy 430.427886 -297.059946) (xy 430.468389 -297.087902) (xy 430.503882 -297.121994)
			(xy 430.533447 -297.161338) (xy 430.556318 -297.204915) (xy 430.571902 -297.251596) (xy 430.579797 -297.300173)
			(xy 430.580292 -297.32478) (xy 430.91914 -297.32478) (xy 430.9231 -297.275726) (xy 430.934877 -297.227942)
			(xy 430.954168 -297.182666) (xy 430.980471 -297.14107) (xy 431.013106 -297.104233) (xy 431.051227 -297.073108)
			(xy 431.093848 -297.048501) (xy 431.139864 -297.031049) (xy 431.188083 -297.021205) (xy 431.237258 -297.019224)
			(xy 431.286113 -297.025156) (xy 431.333384 -297.038848) (xy 431.377846 -297.059946) (xy 431.418349 -297.087902)
			(xy 431.453842 -297.121994) (xy 431.483407 -297.161338) (xy 431.506278 -297.204915) (xy 431.521862 -297.251596)
			(xy 431.529757 -297.300173) (xy 431.530252 -297.32478) (xy 431.529757 -297.349387) (xy 431.521862 -297.397964)
			(xy 431.506278 -297.444645) (xy 431.483407 -297.488222) (xy 431.453842 -297.527566) (xy 431.418349 -297.561658)
			(xy 431.377846 -297.589614) (xy 431.333384 -297.610712) (xy 431.286113 -297.624404) (xy 431.237258 -297.630336)
			(xy 431.188083 -297.628355) (xy 431.139864 -297.618511) (xy 431.093848 -297.601059) (xy 431.051227 -297.576452)
			(xy 431.013106 -297.545327) (xy 430.980471 -297.50849) (xy 430.954168 -297.466894) (xy 430.934877 -297.421618)
			(xy 430.9231 -297.373834) (xy 430.91914 -297.32478) (xy 430.580292 -297.32478) (xy 430.579797 -297.349387)
			(xy 430.571902 -297.397964) (xy 430.556318 -297.444645) (xy 430.533447 -297.488222) (xy 430.503882 -297.527566)
			(xy 430.468389 -297.561658) (xy 430.427886 -297.589614) (xy 430.383424 -297.610712) (xy 430.336153 -297.624404)
			(xy 430.287298 -297.630336) (xy 430.238123 -297.628355) (xy 430.189904 -297.618511) (xy 430.143888 -297.601059)
			(xy 430.101267 -297.576452) (xy 430.063146 -297.545327) (xy 430.030511 -297.50849) (xy 430.004208 -297.466894)
			(xy 429.984917 -297.421618) (xy 429.97314 -297.373834) (xy 429.96918 -297.32478) (xy 429.630332 -297.32478)
			(xy 429.629837 -297.349387) (xy 429.621942 -297.397964) (xy 429.606358 -297.444645) (xy 429.583487 -297.488222)
			(xy 429.553922 -297.527566) (xy 429.518429 -297.561658) (xy 429.477926 -297.589614) (xy 429.433464 -297.610712)
			(xy 429.386193 -297.624404) (xy 429.337338 -297.630336) (xy 429.288163 -297.628355) (xy 429.239944 -297.618511)
			(xy 429.193928 -297.601059) (xy 429.151307 -297.576452) (xy 429.113186 -297.545327) (xy 429.080551 -297.50849)
			(xy 429.054248 -297.466894) (xy 429.034957 -297.421618) (xy 429.02318 -297.373834) (xy 429.01922 -297.32478)
			(xy 428.680118 -297.32478) (xy 428.679623 -297.349387) (xy 428.671728 -297.397964) (xy 428.656144 -297.444645)
			(xy 428.633273 -297.488222) (xy 428.603708 -297.527566) (xy 428.568215 -297.561658) (xy 428.527712 -297.589614)
			(xy 428.48325 -297.610712) (xy 428.435979 -297.624404) (xy 428.387124 -297.630336) (xy 428.337949 -297.628355)
			(xy 428.28973 -297.618511) (xy 428.243714 -297.601059) (xy 428.201093 -297.576452) (xy 428.162972 -297.545327)
			(xy 428.130337 -297.50849) (xy 428.104034 -297.466894) (xy 428.084743 -297.421618) (xy 428.072966 -297.373834)
			(xy 428.069006 -297.32478) (xy 427.730158 -297.32478) (xy 427.729663 -297.349387) (xy 427.721768 -297.397964)
			(xy 427.706184 -297.444645) (xy 427.683313 -297.488222) (xy 427.653748 -297.527566) (xy 427.618255 -297.561658)
			(xy 427.577752 -297.589614) (xy 427.53329 -297.610712) (xy 427.486019 -297.624404) (xy 427.437164 -297.630336)
			(xy 427.387989 -297.628355) (xy 427.33977 -297.618511) (xy 427.293754 -297.601059) (xy 427.251133 -297.576452)
			(xy 427.213012 -297.545327) (xy 427.180377 -297.50849) (xy 427.154074 -297.466894) (xy 427.134783 -297.421618)
			(xy 427.123006 -297.373834) (xy 427.119046 -297.32478) (xy 426.780198 -297.32478) (xy 426.779703 -297.349387)
			(xy 426.771808 -297.397964) (xy 426.756224 -297.444645) (xy 426.733353 -297.488222) (xy 426.703788 -297.527566)
			(xy 426.668295 -297.561658) (xy 426.627792 -297.589614) (xy 426.58333 -297.610712) (xy 426.536059 -297.624404)
			(xy 426.487204 -297.630336) (xy 426.438029 -297.628355) (xy 426.38981 -297.618511) (xy 426.343794 -297.601059)
			(xy 426.301173 -297.576452) (xy 426.263052 -297.545327) (xy 426.230417 -297.50849) (xy 426.204114 -297.466894)
			(xy 426.184823 -297.421618) (xy 426.173046 -297.373834) (xy 426.169086 -297.32478) (xy 425.830238 -297.32478)
			(xy 425.829743 -297.349387) (xy 425.821848 -297.397964) (xy 425.806264 -297.444645) (xy 425.783393 -297.488222)
			(xy 425.753828 -297.527566) (xy 425.718335 -297.561658) (xy 425.677832 -297.589614) (xy 425.63337 -297.610712)
			(xy 425.586099 -297.624404) (xy 425.537244 -297.630336) (xy 425.488069 -297.628355) (xy 425.43985 -297.618511)
			(xy 425.393834 -297.601059) (xy 425.351213 -297.576452) (xy 425.313092 -297.545327) (xy 425.280457 -297.50849)
			(xy 425.254154 -297.466894) (xy 425.234863 -297.421618) (xy 425.223086 -297.373834) (xy 425.219126 -297.32478)
			(xy 424.880278 -297.32478) (xy 424.879783 -297.349387) (xy 424.871888 -297.397964) (xy 424.856304 -297.444645)
			(xy 424.833433 -297.488222) (xy 424.803868 -297.527566) (xy 424.768375 -297.561658) (xy 424.727872 -297.589614)
			(xy 424.68341 -297.610712) (xy 424.636139 -297.624404) (xy 424.587284 -297.630336) (xy 424.538109 -297.628355)
			(xy 424.48989 -297.618511) (xy 424.443874 -297.601059) (xy 424.401253 -297.576452) (xy 424.363132 -297.545327)
			(xy 424.330497 -297.50849) (xy 424.304194 -297.466894) (xy 424.284903 -297.421618) (xy 424.273126 -297.373834)
			(xy 424.269166 -297.32478) (xy 423.930318 -297.32478) (xy 423.929823 -297.349387) (xy 423.921928 -297.397964)
			(xy 423.906344 -297.444645) (xy 423.883473 -297.488222) (xy 423.853908 -297.527566) (xy 423.818415 -297.561658)
			(xy 423.777912 -297.589614) (xy 423.73345 -297.610712) (xy 423.686179 -297.624404) (xy 423.637324 -297.630336)
			(xy 423.588149 -297.628355) (xy 423.53993 -297.618511) (xy 423.493914 -297.601059) (xy 423.451293 -297.576452)
			(xy 423.413172 -297.545327) (xy 423.380537 -297.50849) (xy 423.354234 -297.466894) (xy 423.334943 -297.421618)
			(xy 423.323166 -297.373834) (xy 423.319206 -297.32478) (xy 422.980358 -297.32478) (xy 422.979863 -297.349387)
			(xy 422.971968 -297.397964) (xy 422.956384 -297.444645) (xy 422.933513 -297.488222) (xy 422.903948 -297.527566)
			(xy 422.868455 -297.561658) (xy 422.827952 -297.589614) (xy 422.78349 -297.610712) (xy 422.736219 -297.624404)
			(xy 422.687364 -297.630336) (xy 422.638189 -297.628355) (xy 422.58997 -297.618511) (xy 422.543954 -297.601059)
			(xy 422.501333 -297.576452) (xy 422.463212 -297.545327) (xy 422.430577 -297.50849) (xy 422.404274 -297.466894)
			(xy 422.384983 -297.421618) (xy 422.373206 -297.373834) (xy 422.369246 -297.32478) (xy 422.030144 -297.32478)
			(xy 422.029649 -297.349387) (xy 422.021754 -297.397964) (xy 422.00617 -297.444645) (xy 421.983299 -297.488222)
			(xy 421.953734 -297.527566) (xy 421.918241 -297.561658) (xy 421.877738 -297.589614) (xy 421.833276 -297.610712)
			(xy 421.786005 -297.624404) (xy 421.73715 -297.630336) (xy 421.687975 -297.628355) (xy 421.639756 -297.618511)
			(xy 421.59374 -297.601059) (xy 421.551119 -297.576452) (xy 421.512998 -297.545327) (xy 421.480363 -297.50849)
			(xy 421.45406 -297.466894) (xy 421.434769 -297.421618) (xy 421.422992 -297.373834) (xy 421.419032 -297.32478)
			(xy 420.130224 -297.32478) (xy 420.129729 -297.349387) (xy 420.121834 -297.397964) (xy 420.10625 -297.444645)
			(xy 420.083379 -297.488222) (xy 420.053814 -297.527566) (xy 420.018321 -297.561658) (xy 419.977818 -297.589614)
			(xy 419.933356 -297.610712) (xy 419.886085 -297.624404) (xy 419.83723 -297.630336) (xy 419.788055 -297.628355)
			(xy 419.739836 -297.618511) (xy 419.69382 -297.601059) (xy 419.651199 -297.576452) (xy 419.613078 -297.545327)
			(xy 419.580443 -297.50849) (xy 419.55414 -297.466894) (xy 419.534849 -297.421618) (xy 419.523072 -297.373834)
			(xy 419.519112 -297.32478) (xy 419.180264 -297.32478) (xy 419.179769 -297.349387) (xy 419.171874 -297.397964)
			(xy 419.15629 -297.444645) (xy 419.133419 -297.488222) (xy 419.103854 -297.527566) (xy 419.068361 -297.561658)
			(xy 419.027858 -297.589614) (xy 418.983396 -297.610712) (xy 418.936125 -297.624404) (xy 418.88727 -297.630336)
			(xy 418.838095 -297.628355) (xy 418.789876 -297.618511) (xy 418.74386 -297.601059) (xy 418.701239 -297.576452)
			(xy 418.663118 -297.545327) (xy 418.630483 -297.50849) (xy 418.60418 -297.466894) (xy 418.584889 -297.421618)
			(xy 418.573112 -297.373834) (xy 418.569152 -297.32478) (xy 418.231642 -297.32478) (xy 418.231644 -297.3248)
			(xy 418.227461 -297.375272) (xy 418.215028 -297.424368) (xy 418.194684 -297.470747) (xy 418.166984 -297.513146)
			(xy 418.132682 -297.550406) (xy 418.092716 -297.581513) (xy 418.048175 -297.605617) (xy 418.000273 -297.622061)
			(xy 417.950319 -297.630396) (xy 417.924996 -297.63085) (xy 417.924742 -297.63085) (xy 417.897275 -297.630216)
			(xy 417.843226 -297.620385) (xy 417.8173 -297.611292) (xy 417.805616 -297.606974) (xy 417.780978 -297.610022)
			(xy 417.702492 -297.664124) (xy 417.692823 -297.671737) (xy 417.681411 -297.693498) (xy 417.680648 -297.70578)
			(xy 417.680648 -297.89374) (xy 417.681244 -297.906064) (xy 417.692703 -297.927883) (xy 417.702492 -297.935396)
			(xy 417.780978 -297.989498) (xy 417.805616 -297.992546) (xy 417.8173 -297.988228) (xy 417.843217 -297.979099)
			(xy 417.897271 -297.969256) (xy 417.924742 -297.96867) (xy 417.924996 -297.96867) (xy 417.950314 -297.969164)
			(xy 418.000258 -297.977498) (xy 418.04815 -297.993938) (xy 418.092683 -298.018038) (xy 418.132641 -298.049138)
			(xy 418.166936 -298.086391) (xy 418.194631 -298.128782) (xy 418.214971 -298.175152) (xy 418.227402 -298.224238)
			(xy 418.231583 -298.2747) (xy 418.23158 -298.27474) (xy 418.569152 -298.27474) (xy 418.573112 -298.225686)
			(xy 418.584889 -298.177902) (xy 418.60418 -298.132626) (xy 418.630483 -298.09103) (xy 418.663118 -298.054193)
			(xy 418.701239 -298.023068) (xy 418.74386 -297.998461) (xy 418.789876 -297.981009) (xy 418.838095 -297.971165)
			(xy 418.88727 -297.969184) (xy 418.936125 -297.975116) (xy 418.983396 -297.988808) (xy 419.027858 -298.009906)
			(xy 419.068361 -298.037862) (xy 419.103854 -298.071954) (xy 419.133419 -298.111298) (xy 419.15629 -298.154875)
			(xy 419.171874 -298.201556) (xy 419.179769 -298.250133) (xy 419.180264 -298.27474) (xy 419.519112 -298.27474)
			(xy 419.523072 -298.225686) (xy 419.534849 -298.177902) (xy 419.55414 -298.132626) (xy 419.580443 -298.09103)
			(xy 419.613078 -298.054193) (xy 419.651199 -298.023068) (xy 419.69382 -297.998461) (xy 419.739836 -297.981009)
			(xy 419.788055 -297.971165) (xy 419.83723 -297.969184) (xy 419.886085 -297.975116) (xy 419.933356 -297.988808)
			(xy 419.977818 -298.009906) (xy 420.018321 -298.037862) (xy 420.053814 -298.071954) (xy 420.083379 -298.111298)
			(xy 420.10625 -298.154875) (xy 420.121834 -298.201556) (xy 420.129729 -298.250133) (xy 420.130224 -298.27474)
			(xy 421.419032 -298.27474) (xy 421.422992 -298.225686) (xy 421.434769 -298.177902) (xy 421.45406 -298.132626)
			(xy 421.480363 -298.09103) (xy 421.512998 -298.054193) (xy 421.551119 -298.023068) (xy 421.59374 -297.998461)
			(xy 421.639756 -297.981009) (xy 421.687975 -297.971165) (xy 421.73715 -297.969184) (xy 421.786005 -297.975116)
			(xy 421.833276 -297.988808) (xy 421.877738 -298.009906) (xy 421.918241 -298.037862) (xy 421.953734 -298.071954)
			(xy 421.983299 -298.111298) (xy 422.00617 -298.154875) (xy 422.021754 -298.201556) (xy 422.029649 -298.250133)
			(xy 422.030144 -298.27474) (xy 422.368992 -298.27474) (xy 422.372952 -298.225686) (xy 422.384729 -298.177902)
			(xy 422.40402 -298.132626) (xy 422.430323 -298.09103) (xy 422.462958 -298.054193) (xy 422.501079 -298.023068)
			(xy 422.5437 -297.998461) (xy 422.589716 -297.981009) (xy 422.637935 -297.971165) (xy 422.68711 -297.969184)
			(xy 422.735965 -297.975116) (xy 422.783236 -297.988808) (xy 422.827698 -298.009906) (xy 422.868201 -298.037862)
			(xy 422.903694 -298.071954) (xy 422.933259 -298.111298) (xy 422.95613 -298.154875) (xy 422.971714 -298.201556)
			(xy 422.979609 -298.250133) (xy 422.980104 -298.27474) (xy 423.319206 -298.27474) (xy 423.323166 -298.225686)
			(xy 423.334943 -298.177902) (xy 423.354234 -298.132626) (xy 423.380537 -298.09103) (xy 423.413172 -298.054193)
			(xy 423.451293 -298.023068) (xy 423.493914 -297.998461) (xy 423.53993 -297.981009) (xy 423.588149 -297.971165)
			(xy 423.637324 -297.969184) (xy 423.686179 -297.975116) (xy 423.73345 -297.988808) (xy 423.777912 -298.009906)
			(xy 423.818415 -298.037862) (xy 423.853908 -298.071954) (xy 423.883473 -298.111298) (xy 423.906344 -298.154875)
			(xy 423.921928 -298.201556) (xy 423.929823 -298.250133) (xy 423.930318 -298.27474) (xy 424.269166 -298.27474)
			(xy 424.273126 -298.225686) (xy 424.284903 -298.177902) (xy 424.304194 -298.132626) (xy 424.330497 -298.09103)
			(xy 424.363132 -298.054193) (xy 424.401253 -298.023068) (xy 424.443874 -297.998461) (xy 424.48989 -297.981009)
			(xy 424.538109 -297.971165) (xy 424.587284 -297.969184) (xy 424.636139 -297.975116) (xy 424.68341 -297.988808)
			(xy 424.727872 -298.009906) (xy 424.768375 -298.037862) (xy 424.803868 -298.071954) (xy 424.833433 -298.111298)
			(xy 424.856304 -298.154875) (xy 424.871888 -298.201556) (xy 424.879783 -298.250133) (xy 424.880278 -298.27474)
			(xy 425.219126 -298.27474) (xy 425.223086 -298.225686) (xy 425.234863 -298.177902) (xy 425.254154 -298.132626)
			(xy 425.280457 -298.09103) (xy 425.313092 -298.054193) (xy 425.351213 -298.023068) (xy 425.393834 -297.998461)
			(xy 425.43985 -297.981009) (xy 425.488069 -297.971165) (xy 425.537244 -297.969184) (xy 425.586099 -297.975116)
			(xy 425.63337 -297.988808) (xy 425.677832 -298.009906) (xy 425.718335 -298.037862) (xy 425.753828 -298.071954)
			(xy 425.783393 -298.111298) (xy 425.806264 -298.154875) (xy 425.821848 -298.201556) (xy 425.829743 -298.250133)
			(xy 425.830238 -298.27474) (xy 426.169086 -298.27474) (xy 426.173046 -298.225686) (xy 426.184823 -298.177902)
			(xy 426.204114 -298.132626) (xy 426.230417 -298.09103) (xy 426.263052 -298.054193) (xy 426.301173 -298.023068)
			(xy 426.343794 -297.998461) (xy 426.38981 -297.981009) (xy 426.438029 -297.971165) (xy 426.487204 -297.969184)
			(xy 426.536059 -297.975116) (xy 426.58333 -297.988808) (xy 426.627792 -298.009906) (xy 426.668295 -298.037862)
			(xy 426.703788 -298.071954) (xy 426.733353 -298.111298) (xy 426.756224 -298.154875) (xy 426.771808 -298.201556)
			(xy 426.779703 -298.250133) (xy 426.780198 -298.27474) (xy 427.119046 -298.27474) (xy 427.123006 -298.225686)
			(xy 427.134783 -298.177902) (xy 427.154074 -298.132626) (xy 427.180377 -298.09103) (xy 427.213012 -298.054193)
			(xy 427.251133 -298.023068) (xy 427.293754 -297.998461) (xy 427.33977 -297.981009) (xy 427.387989 -297.971165)
			(xy 427.437164 -297.969184) (xy 427.486019 -297.975116) (xy 427.53329 -297.988808) (xy 427.577752 -298.009906)
			(xy 427.618255 -298.037862) (xy 427.653748 -298.071954) (xy 427.683313 -298.111298) (xy 427.706184 -298.154875)
			(xy 427.721768 -298.201556) (xy 427.729663 -298.250133) (xy 427.730158 -298.27474) (xy 428.069006 -298.27474)
			(xy 428.072966 -298.225686) (xy 428.084743 -298.177902) (xy 428.104034 -298.132626) (xy 428.130337 -298.09103)
			(xy 428.162972 -298.054193) (xy 428.201093 -298.023068) (xy 428.243714 -297.998461) (xy 428.28973 -297.981009)
			(xy 428.337949 -297.971165) (xy 428.387124 -297.969184) (xy 428.435979 -297.975116) (xy 428.48325 -297.988808)
			(xy 428.527712 -298.009906) (xy 428.568215 -298.037862) (xy 428.603708 -298.071954) (xy 428.633273 -298.111298)
			(xy 428.656144 -298.154875) (xy 428.671728 -298.201556) (xy 428.679623 -298.250133) (xy 428.680118 -298.27474)
			(xy 429.01922 -298.27474) (xy 429.02318 -298.225686) (xy 429.034957 -298.177902) (xy 429.054248 -298.132626)
			(xy 429.080551 -298.09103) (xy 429.113186 -298.054193) (xy 429.151307 -298.023068) (xy 429.193928 -297.998461)
			(xy 429.239944 -297.981009) (xy 429.288163 -297.971165) (xy 429.337338 -297.969184) (xy 429.386193 -297.975116)
			(xy 429.433464 -297.988808) (xy 429.477926 -298.009906) (xy 429.518429 -298.037862) (xy 429.553922 -298.071954)
			(xy 429.583487 -298.111298) (xy 429.606358 -298.154875) (xy 429.621942 -298.201556) (xy 429.629837 -298.250133)
			(xy 429.630332 -298.27474) (xy 429.96918 -298.27474) (xy 429.97314 -298.225686) (xy 429.984917 -298.177902)
			(xy 430.004208 -298.132626) (xy 430.030511 -298.09103) (xy 430.063146 -298.054193) (xy 430.101267 -298.023068)
			(xy 430.143888 -297.998461) (xy 430.189904 -297.981009) (xy 430.238123 -297.971165) (xy 430.287298 -297.969184)
			(xy 430.336153 -297.975116) (xy 430.383424 -297.988808) (xy 430.427886 -298.009906) (xy 430.468389 -298.037862)
			(xy 430.503882 -298.071954) (xy 430.533447 -298.111298) (xy 430.556318 -298.154875) (xy 430.571902 -298.201556)
			(xy 430.579797 -298.250133) (xy 430.580292 -298.27474) (xy 430.91914 -298.27474) (xy 430.9231 -298.225686)
			(xy 430.934877 -298.177902) (xy 430.954168 -298.132626) (xy 430.980471 -298.09103) (xy 431.013106 -298.054193)
			(xy 431.051227 -298.023068) (xy 431.093848 -297.998461) (xy 431.139864 -297.981009) (xy 431.188083 -297.971165)
			(xy 431.237258 -297.969184) (xy 431.286113 -297.975116) (xy 431.333384 -297.988808) (xy 431.377846 -298.009906)
			(xy 431.418349 -298.037862) (xy 431.453842 -298.071954) (xy 431.483407 -298.111298) (xy 431.506278 -298.154875)
			(xy 431.521862 -298.201556) (xy 431.529757 -298.250133) (xy 431.530252 -298.27474) (xy 431.529757 -298.299347)
			(xy 431.525612 -298.324851) (xy 432.282578 -298.324851) (xy 432.282578 -298.270349) (xy 432.290334 -298.216401)
			(xy 432.305689 -298.164106) (xy 432.328331 -298.114529) (xy 432.357797 -298.068679) (xy 432.393488 -298.027488)
			(xy 432.434679 -297.991797) (xy 432.480529 -297.962331) (xy 432.530106 -297.939689) (xy 432.582401 -297.924334)
			(xy 432.636349 -297.916578) (xy 432.6636 -297.916092) (xy 432.688532 -297.916503) (xy 432.737972 -297.922985)
			(xy 432.786146 -297.935851) (xy 432.832235 -297.954882) (xy 432.875452 -297.979755) (xy 432.895502 -297.994578)
			(xy 432.906521 -298.002476) (xy 432.931603 -298.012733) (xy 432.958502 -298.016018) (xy 432.985316 -298.012099)
			(xy 433.01015 -298.001253) (xy 433.031248 -297.984246) (xy 433.047119 -297.962281) (xy 433.05664 -297.93691)
			(xy 433.058316 -297.923458) (xy 433.061444 -297.895404) (xy 433.074876 -297.84058) (xy 433.096235 -297.788332)
			(xy 433.125056 -297.739799) (xy 433.16071 -297.696039) (xy 433.20242 -297.658008) (xy 433.249276 -297.626534)
			(xy 433.300257 -297.602303) (xy 433.354249 -297.585845) (xy 433.410077 -297.577518) (xy 433.4383 -297.577002)
			(xy 433.465552 -297.577468) (xy 433.519501 -297.585225) (xy 433.571797 -297.60058) (xy 433.621376 -297.623222)
			(xy 433.667227 -297.652689) (xy 433.693322 -297.6753) (xy 434.599586 -297.6753) (xy 434.603657 -297.619678)
			(xy 434.615783 -297.565241) (xy 434.635706 -297.51315) (xy 434.663002 -297.464515) (xy 434.697088 -297.420372)
			(xy 434.737237 -297.381663) (xy 434.782595 -297.349212) (xy 434.832195 -297.323711) (xy 434.884979 -297.305704)
			(xy 434.939822 -297.295574) (xy 434.995556 -297.293537) (xy 435.050993 -297.299637) (xy 435.10495 -297.313743)
			(xy 435.156279 -297.335555) (xy 435.203885 -297.364609) (xy 435.216152 -297.374818) (xy 440.915804 -297.374818)
			(xy 440.919875 -297.319196) (xy 440.932001 -297.264759) (xy 440.951924 -297.212668) (xy 440.97922 -297.164033)
			(xy 441.013306 -297.11989) (xy 441.053455 -297.081181) (xy 441.098813 -297.04873) (xy 441.148413 -297.023229)
			(xy 441.201197 -297.005222) (xy 441.25604 -296.995092) (xy 441.311774 -296.993055) (xy 441.367211 -296.999155)
			(xy 441.421168 -297.013261) (xy 441.472497 -297.035073) (xy 441.520103 -297.064127) (xy 441.562971 -297.099802)
			(xy 441.600188 -297.141339) (xy 441.630961 -297.187852) (xy 441.654633 -297.238349) (xy 441.670701 -297.291756)
			(xy 441.678821 -297.346932) (xy 441.67933 -297.374818) (xy 441.678821 -297.402704) (xy 441.670701 -297.45788)
			(xy 441.654633 -297.511287) (xy 441.630961 -297.561784) (xy 441.600188 -297.608297) (xy 441.562971 -297.649834)
			(xy 441.520103 -297.685509) (xy 441.472497 -297.714563) (xy 441.421168 -297.736375) (xy 441.367211 -297.750481)
			(xy 441.311774 -297.756581) (xy 441.25604 -297.754544) (xy 441.201197 -297.744414) (xy 441.148413 -297.726407)
			(xy 441.098813 -297.700906) (xy 441.053455 -297.668455) (xy 441.013306 -297.629746) (xy 440.97922 -297.585603)
			(xy 440.951924 -297.536968) (xy 440.932001 -297.484877) (xy 440.919875 -297.43044) (xy 440.915804 -297.374818)
			(xy 435.216152 -297.374818) (xy 435.246753 -297.400284) (xy 435.28397 -297.441821) (xy 435.314743 -297.488334)
			(xy 435.338415 -297.538831) (xy 435.354483 -297.592238) (xy 435.362603 -297.647414) (xy 435.363112 -297.6753)
			(xy 435.362603 -297.703186) (xy 435.354483 -297.758362) (xy 435.338415 -297.811769) (xy 435.314743 -297.862266)
			(xy 435.28397 -297.908779) (xy 435.246753 -297.950316) (xy 435.203885 -297.985991) (xy 435.156279 -298.015045)
			(xy 435.10495 -298.036857) (xy 435.050993 -298.050963) (xy 434.995556 -298.057063) (xy 434.939822 -298.055026)
			(xy 434.884979 -298.044896) (xy 434.832195 -298.026889) (xy 434.782595 -298.001388) (xy 434.737237 -297.968937)
			(xy 434.697088 -297.930228) (xy 434.663002 -297.886085) (xy 434.635706 -297.83745) (xy 434.615783 -297.785359)
			(xy 434.603657 -297.730922) (xy 434.599586 -297.6753) (xy 433.693322 -297.6753) (xy 433.708419 -297.688381)
			(xy 433.744111 -297.729573) (xy 433.773578 -297.775424) (xy 433.79622 -297.825003) (xy 433.811575 -297.877299)
			(xy 433.819332 -297.931248) (xy 433.819332 -297.985752) (xy 433.811575 -298.039701) (xy 433.79622 -298.091997)
			(xy 433.773578 -298.141576) (xy 433.744111 -298.187427) (xy 433.708419 -298.228619) (xy 433.667227 -298.264311)
			(xy 433.621376 -298.293778) (xy 433.571797 -298.31642) (xy 433.519501 -298.331775) (xy 433.465552 -298.339532)
			(xy 433.4383 -298.340018) (xy 433.413368 -298.339605) (xy 433.363929 -298.333123) (xy 433.315754 -298.320258)
			(xy 433.269666 -298.301227) (xy 433.226449 -298.276355) (xy 433.206398 -298.261532) (xy 433.195383 -298.253628)
			(xy 433.170299 -298.243369) (xy 433.143399 -298.240082) (xy 433.116583 -298.244002) (xy 433.091748 -298.254849)
			(xy 433.070649 -298.271858) (xy 433.054779 -298.293825) (xy 433.045259 -298.319199) (xy 433.043584 -298.332652)
			(xy 433.040464 -298.360707) (xy 433.027031 -298.415531) (xy 433.00567 -298.467779) (xy 432.976848 -298.516312)
			(xy 432.941193 -298.560071) (xy 432.899482 -298.598103) (xy 432.852626 -298.629577) (xy 432.801645 -298.653807)
			(xy 432.747651 -298.670265) (xy 432.691823 -298.678592) (xy 432.6636 -298.679108) (xy 432.636349 -298.678622)
			(xy 432.582401 -298.670866) (xy 432.530106 -298.655511) (xy 432.480529 -298.632869) (xy 432.434679 -298.603403)
			(xy 432.393488 -298.567712) (xy 432.357797 -298.526521) (xy 432.328331 -298.480671) (xy 432.305689 -298.431094)
			(xy 432.290334 -298.378799) (xy 432.282578 -298.324851) (xy 431.525612 -298.324851) (xy 431.521862 -298.347924)
			(xy 431.506278 -298.394605) (xy 431.483407 -298.438182) (xy 431.453842 -298.477526) (xy 431.418349 -298.511618)
			(xy 431.377846 -298.539574) (xy 431.333384 -298.560672) (xy 431.286113 -298.574364) (xy 431.237258 -298.580296)
			(xy 431.188083 -298.578315) (xy 431.139864 -298.568471) (xy 431.093848 -298.551019) (xy 431.051227 -298.526412)
			(xy 431.013106 -298.495287) (xy 430.980471 -298.45845) (xy 430.954168 -298.416854) (xy 430.934877 -298.371578)
			(xy 430.9231 -298.323794) (xy 430.91914 -298.27474) (xy 430.580292 -298.27474) (xy 430.579797 -298.299347)
			(xy 430.571902 -298.347924) (xy 430.556318 -298.394605) (xy 430.533447 -298.438182) (xy 430.503882 -298.477526)
			(xy 430.468389 -298.511618) (xy 430.427886 -298.539574) (xy 430.383424 -298.560672) (xy 430.336153 -298.574364)
			(xy 430.287298 -298.580296) (xy 430.238123 -298.578315) (xy 430.189904 -298.568471) (xy 430.143888 -298.551019)
			(xy 430.101267 -298.526412) (xy 430.063146 -298.495287) (xy 430.030511 -298.45845) (xy 430.004208 -298.416854)
			(xy 429.984917 -298.371578) (xy 429.97314 -298.323794) (xy 429.96918 -298.27474) (xy 429.630332 -298.27474)
			(xy 429.629837 -298.299347) (xy 429.621942 -298.347924) (xy 429.606358 -298.394605) (xy 429.583487 -298.438182)
			(xy 429.553922 -298.477526) (xy 429.518429 -298.511618) (xy 429.477926 -298.539574) (xy 429.433464 -298.560672)
			(xy 429.386193 -298.574364) (xy 429.337338 -298.580296) (xy 429.288163 -298.578315) (xy 429.239944 -298.568471)
			(xy 429.193928 -298.551019) (xy 429.151307 -298.526412) (xy 429.113186 -298.495287) (xy 429.080551 -298.45845)
			(xy 429.054248 -298.416854) (xy 429.034957 -298.371578) (xy 429.02318 -298.323794) (xy 429.01922 -298.27474)
			(xy 428.680118 -298.27474) (xy 428.679623 -298.299347) (xy 428.671728 -298.347924) (xy 428.656144 -298.394605)
			(xy 428.633273 -298.438182) (xy 428.603708 -298.477526) (xy 428.568215 -298.511618) (xy 428.527712 -298.539574)
			(xy 428.48325 -298.560672) (xy 428.435979 -298.574364) (xy 428.387124 -298.580296) (xy 428.337949 -298.578315)
			(xy 428.28973 -298.568471) (xy 428.243714 -298.551019) (xy 428.201093 -298.526412) (xy 428.162972 -298.495287)
			(xy 428.130337 -298.45845) (xy 428.104034 -298.416854) (xy 428.084743 -298.371578) (xy 428.072966 -298.323794)
			(xy 428.069006 -298.27474) (xy 427.730158 -298.27474) (xy 427.729663 -298.299347) (xy 427.721768 -298.347924)
			(xy 427.706184 -298.394605) (xy 427.683313 -298.438182) (xy 427.653748 -298.477526) (xy 427.618255 -298.511618)
			(xy 427.577752 -298.539574) (xy 427.53329 -298.560672) (xy 427.486019 -298.574364) (xy 427.437164 -298.580296)
			(xy 427.387989 -298.578315) (xy 427.33977 -298.568471) (xy 427.293754 -298.551019) (xy 427.251133 -298.526412)
			(xy 427.213012 -298.495287) (xy 427.180377 -298.45845) (xy 427.154074 -298.416854) (xy 427.134783 -298.371578)
			(xy 427.123006 -298.323794) (xy 427.119046 -298.27474) (xy 426.780198 -298.27474) (xy 426.779703 -298.299347)
			(xy 426.771808 -298.347924) (xy 426.756224 -298.394605) (xy 426.733353 -298.438182) (xy 426.703788 -298.477526)
			(xy 426.668295 -298.511618) (xy 426.627792 -298.539574) (xy 426.58333 -298.560672) (xy 426.536059 -298.574364)
			(xy 426.487204 -298.580296) (xy 426.438029 -298.578315) (xy 426.38981 -298.568471) (xy 426.343794 -298.551019)
			(xy 426.301173 -298.526412) (xy 426.263052 -298.495287) (xy 426.230417 -298.45845) (xy 426.204114 -298.416854)
			(xy 426.184823 -298.371578) (xy 426.173046 -298.323794) (xy 426.169086 -298.27474) (xy 425.830238 -298.27474)
			(xy 425.829743 -298.299347) (xy 425.821848 -298.347924) (xy 425.806264 -298.394605) (xy 425.783393 -298.438182)
			(xy 425.753828 -298.477526) (xy 425.718335 -298.511618) (xy 425.677832 -298.539574) (xy 425.63337 -298.560672)
			(xy 425.586099 -298.574364) (xy 425.537244 -298.580296) (xy 425.488069 -298.578315) (xy 425.43985 -298.568471)
			(xy 425.393834 -298.551019) (xy 425.351213 -298.526412) (xy 425.313092 -298.495287) (xy 425.280457 -298.45845)
			(xy 425.254154 -298.416854) (xy 425.234863 -298.371578) (xy 425.223086 -298.323794) (xy 425.219126 -298.27474)
			(xy 424.880278 -298.27474) (xy 424.879783 -298.299347) (xy 424.871888 -298.347924) (xy 424.856304 -298.394605)
			(xy 424.833433 -298.438182) (xy 424.803868 -298.477526) (xy 424.768375 -298.511618) (xy 424.727872 -298.539574)
			(xy 424.68341 -298.560672) (xy 424.636139 -298.574364) (xy 424.587284 -298.580296) (xy 424.538109 -298.578315)
			(xy 424.48989 -298.568471) (xy 424.443874 -298.551019) (xy 424.401253 -298.526412) (xy 424.363132 -298.495287)
			(xy 424.330497 -298.45845) (xy 424.304194 -298.416854) (xy 424.284903 -298.371578) (xy 424.273126 -298.323794)
			(xy 424.269166 -298.27474) (xy 423.930318 -298.27474) (xy 423.929823 -298.299347) (xy 423.921928 -298.347924)
			(xy 423.906344 -298.394605) (xy 423.883473 -298.438182) (xy 423.853908 -298.477526) (xy 423.818415 -298.511618)
			(xy 423.777912 -298.539574) (xy 423.73345 -298.560672) (xy 423.686179 -298.574364) (xy 423.637324 -298.580296)
			(xy 423.588149 -298.578315) (xy 423.53993 -298.568471) (xy 423.493914 -298.551019) (xy 423.451293 -298.526412)
			(xy 423.413172 -298.495287) (xy 423.380537 -298.45845) (xy 423.354234 -298.416854) (xy 423.334943 -298.371578)
			(xy 423.323166 -298.323794) (xy 423.319206 -298.27474) (xy 422.980104 -298.27474) (xy 422.979609 -298.299347)
			(xy 422.971714 -298.347924) (xy 422.95613 -298.394605) (xy 422.933259 -298.438182) (xy 422.903694 -298.477526)
			(xy 422.868201 -298.511618) (xy 422.827698 -298.539574) (xy 422.783236 -298.560672) (xy 422.735965 -298.574364)
			(xy 422.68711 -298.580296) (xy 422.637935 -298.578315) (xy 422.589716 -298.568471) (xy 422.5437 -298.551019)
			(xy 422.501079 -298.526412) (xy 422.462958 -298.495287) (xy 422.430323 -298.45845) (xy 422.40402 -298.416854)
			(xy 422.384729 -298.371578) (xy 422.372952 -298.323794) (xy 422.368992 -298.27474) (xy 422.030144 -298.27474)
			(xy 422.029649 -298.299347) (xy 422.021754 -298.347924) (xy 422.00617 -298.394605) (xy 421.983299 -298.438182)
			(xy 421.953734 -298.477526) (xy 421.918241 -298.511618) (xy 421.877738 -298.539574) (xy 421.833276 -298.560672)
			(xy 421.786005 -298.574364) (xy 421.73715 -298.580296) (xy 421.687975 -298.578315) (xy 421.639756 -298.568471)
			(xy 421.59374 -298.551019) (xy 421.551119 -298.526412) (xy 421.512998 -298.495287) (xy 421.480363 -298.45845)
			(xy 421.45406 -298.416854) (xy 421.434769 -298.371578) (xy 421.422992 -298.323794) (xy 421.419032 -298.27474)
			(xy 420.130224 -298.27474) (xy 420.129729 -298.299347) (xy 420.121834 -298.347924) (xy 420.10625 -298.394605)
			(xy 420.083379 -298.438182) (xy 420.053814 -298.477526) (xy 420.018321 -298.511618) (xy 419.977818 -298.539574)
			(xy 419.933356 -298.560672) (xy 419.886085 -298.574364) (xy 419.83723 -298.580296) (xy 419.788055 -298.578315)
			(xy 419.739836 -298.568471) (xy 419.69382 -298.551019) (xy 419.651199 -298.526412) (xy 419.613078 -298.495287)
			(xy 419.580443 -298.45845) (xy 419.55414 -298.416854) (xy 419.534849 -298.371578) (xy 419.523072 -298.323794)
			(xy 419.519112 -298.27474) (xy 419.180264 -298.27474) (xy 419.179769 -298.299347) (xy 419.171874 -298.347924)
			(xy 419.15629 -298.394605) (xy 419.133419 -298.438182) (xy 419.103854 -298.477526) (xy 419.068361 -298.511618)
			(xy 419.027858 -298.539574) (xy 418.983396 -298.560672) (xy 418.936125 -298.574364) (xy 418.88727 -298.580296)
			(xy 418.838095 -298.578315) (xy 418.789876 -298.568471) (xy 418.74386 -298.551019) (xy 418.701239 -298.526412)
			(xy 418.663118 -298.495287) (xy 418.630483 -298.45845) (xy 418.60418 -298.416854) (xy 418.584889 -298.371578)
			(xy 418.573112 -298.323794) (xy 418.569152 -298.27474) (xy 418.23158 -298.27474) (xy 418.227402 -298.325162)
			(xy 418.214971 -298.374248) (xy 418.194631 -298.420618) (xy 418.166936 -298.463009) (xy 418.132641 -298.500262)
			(xy 418.092683 -298.531362) (xy 418.04815 -298.555462) (xy 418.000258 -298.571902) (xy 417.950314 -298.580236)
			(xy 417.924996 -298.58081) (xy 417.899045 -298.580255) (xy 417.847889 -298.571491) (xy 417.798941 -298.554231)
			(xy 417.753603 -298.528968) (xy 417.71317 -298.496426) (xy 417.6788 -298.457535) (xy 417.664646 -298.435776)
			(xy 417.661852 -298.431204) (xy 417.65347 -298.422568) (xy 417.647215 -298.41662) (xy 417.631765 -298.408952)
			(xy 417.623244 -298.407582) (xy 417.535614 -298.39666) (xy 417.514278 -298.403772) (xy 417.505896 -298.411392)
			(xy 417.50488 -298.412408) (xy 417.503864 -298.413424) (xy 417.203636 -298.713652) (xy 434.780688 -298.713652)
			(xy 434.784759 -298.65803) (xy 434.796885 -298.603593) (xy 434.816808 -298.551502) (xy 434.844104 -298.502867)
			(xy 434.87819 -298.458724) (xy 434.918339 -298.420015) (xy 434.963697 -298.387564) (xy 435.013297 -298.362063)
			(xy 435.066081 -298.344056) (xy 435.120924 -298.333926) (xy 435.176658 -298.331889) (xy 435.232095 -298.337989)
			(xy 435.286052 -298.352095) (xy 435.337381 -298.373907) (xy 435.384987 -298.402961) (xy 435.427855 -298.438636)
			(xy 435.465072 -298.480173) (xy 435.495845 -298.526686) (xy 435.519517 -298.577183) (xy 435.535585 -298.63059)
			(xy 435.543705 -298.685766) (xy 435.544214 -298.713652) (xy 435.543705 -298.741538) (xy 435.535585 -298.796714)
			(xy 435.519517 -298.850121) (xy 435.495845 -298.900618) (xy 435.465072 -298.947131) (xy 435.427855 -298.988668)
			(xy 435.384987 -299.024343) (xy 435.337381 -299.053397) (xy 435.286052 -299.075209) (xy 435.232095 -299.089315)
			(xy 435.176658 -299.095415) (xy 435.120924 -299.093378) (xy 435.066081 -299.083248) (xy 435.013297 -299.065241)
			(xy 434.963697 -299.03974) (xy 434.918339 -299.007289) (xy 434.87819 -298.96858) (xy 434.844104 -298.924437)
			(xy 434.816808 -298.875802) (xy 434.796885 -298.823711) (xy 434.784759 -298.769274) (xy 434.780688 -298.713652)
			(xy 417.203636 -298.713652) (xy 417.112704 -298.804584) (xy 417.104902 -298.813198) (xy 417.097367 -298.835158)
			(xy 417.098226 -298.846748) (xy 417.100766 -298.867322) (xy 417.109148 -298.937426) (xy 417.121848 -298.956984)
			(xy 417.132008 -298.96308) (xy 417.154209 -298.977061) (xy 417.193895 -299.011373) (xy 417.227137 -299.051959)
			(xy 417.252961 -299.097625) (xy 417.270607 -299.14703) (xy 417.279557 -299.198723) (xy 417.28009 -299.224954)
			(xy 417.619192 -299.224954) (xy 417.623152 -299.1759) (xy 417.634929 -299.128116) (xy 417.65422 -299.08284)
			(xy 417.680523 -299.041244) (xy 417.713158 -299.004407) (xy 417.751279 -298.973282) (xy 417.7939 -298.948675)
			(xy 417.839916 -298.931223) (xy 417.888135 -298.921379) (xy 417.93731 -298.919398) (xy 417.986165 -298.92533)
			(xy 418.033436 -298.939022) (xy 418.077898 -298.96012) (xy 418.118401 -298.988076) (xy 418.153894 -299.022168)
			(xy 418.183459 -299.061512) (xy 418.20633 -299.105089) (xy 418.221914 -299.15177) (xy 418.229809 -299.200347)
			(xy 418.230304 -299.224954) (xy 418.569152 -299.224954) (xy 418.573112 -299.1759) (xy 418.584889 -299.128116)
			(xy 418.60418 -299.08284) (xy 418.630483 -299.041244) (xy 418.663118 -299.004407) (xy 418.701239 -298.973282)
			(xy 418.74386 -298.948675) (xy 418.789876 -298.931223) (xy 418.838095 -298.921379) (xy 418.88727 -298.919398)
			(xy 418.936125 -298.92533) (xy 418.983396 -298.939022) (xy 419.027858 -298.96012) (xy 419.068361 -298.988076)
			(xy 419.103854 -299.022168) (xy 419.133419 -299.061512) (xy 419.15629 -299.105089) (xy 419.171874 -299.15177)
			(xy 419.179769 -299.200347) (xy 419.180264 -299.224954) (xy 419.519112 -299.224954) (xy 419.523072 -299.1759)
			(xy 419.534849 -299.128116) (xy 419.55414 -299.08284) (xy 419.580443 -299.041244) (xy 419.613078 -299.004407)
			(xy 419.651199 -298.973282) (xy 419.69382 -298.948675) (xy 419.739836 -298.931223) (xy 419.788055 -298.921379)
			(xy 419.83723 -298.919398) (xy 419.886085 -298.92533) (xy 419.933356 -298.939022) (xy 419.977818 -298.96012)
			(xy 420.018321 -298.988076) (xy 420.053814 -299.022168) (xy 420.083379 -299.061512) (xy 420.10625 -299.105089)
			(xy 420.121834 -299.15177) (xy 420.129729 -299.200347) (xy 420.130224 -299.224954) (xy 420.469072 -299.224954)
			(xy 420.473032 -299.1759) (xy 420.484809 -299.128116) (xy 420.5041 -299.08284) (xy 420.530403 -299.041244)
			(xy 420.563038 -299.004407) (xy 420.601159 -298.973282) (xy 420.64378 -298.948675) (xy 420.689796 -298.931223)
			(xy 420.738015 -298.921379) (xy 420.78719 -298.919398) (xy 420.836045 -298.92533) (xy 420.883316 -298.939022)
			(xy 420.927778 -298.96012) (xy 420.968281 -298.988076) (xy 421.003774 -299.022168) (xy 421.033339 -299.061512)
			(xy 421.05621 -299.105089) (xy 421.071794 -299.15177) (xy 421.079689 -299.200347) (xy 421.080184 -299.224954)
			(xy 421.419032 -299.224954) (xy 421.422992 -299.1759) (xy 421.434769 -299.128116) (xy 421.45406 -299.08284)
			(xy 421.480363 -299.041244) (xy 421.512998 -299.004407) (xy 421.551119 -298.973282) (xy 421.59374 -298.948675)
			(xy 421.639756 -298.931223) (xy 421.687975 -298.921379) (xy 421.73715 -298.919398) (xy 421.786005 -298.92533)
			(xy 421.833276 -298.939022) (xy 421.877738 -298.96012) (xy 421.918241 -298.988076) (xy 421.953734 -299.022168)
			(xy 421.983299 -299.061512) (xy 422.00617 -299.105089) (xy 422.021754 -299.15177) (xy 422.029649 -299.200347)
			(xy 422.030144 -299.224954) (xy 424.269166 -299.224954) (xy 424.273126 -299.1759) (xy 424.284903 -299.128116)
			(xy 424.304194 -299.08284) (xy 424.330497 -299.041244) (xy 424.363132 -299.004407) (xy 424.401253 -298.973282)
			(xy 424.443874 -298.948675) (xy 424.48989 -298.931223) (xy 424.538109 -298.921379) (xy 424.587284 -298.919398)
			(xy 424.636139 -298.92533) (xy 424.68341 -298.939022) (xy 424.727872 -298.96012) (xy 424.768375 -298.988076)
			(xy 424.803868 -299.022168) (xy 424.833433 -299.061512) (xy 424.856304 -299.105089) (xy 424.871888 -299.15177)
			(xy 424.879783 -299.200347) (xy 424.880278 -299.224954) (xy 425.219126 -299.224954) (xy 425.223086 -299.1759)
			(xy 425.234863 -299.128116) (xy 425.254154 -299.08284) (xy 425.280457 -299.041244) (xy 425.313092 -299.004407)
			(xy 425.351213 -298.973282) (xy 425.393834 -298.948675) (xy 425.43985 -298.931223) (xy 425.488069 -298.921379)
			(xy 425.537244 -298.919398) (xy 425.586099 -298.92533) (xy 425.63337 -298.939022) (xy 425.677832 -298.96012)
			(xy 425.718335 -298.988076) (xy 425.753828 -299.022168) (xy 425.783393 -299.061512) (xy 425.806264 -299.105089)
			(xy 425.821848 -299.15177) (xy 425.829743 -299.200347) (xy 425.830238 -299.224954) (xy 426.169086 -299.224954)
			(xy 426.173046 -299.1759) (xy 426.184823 -299.128116) (xy 426.204114 -299.08284) (xy 426.230417 -299.041244)
			(xy 426.263052 -299.004407) (xy 426.301173 -298.973282) (xy 426.343794 -298.948675) (xy 426.38981 -298.931223)
			(xy 426.438029 -298.921379) (xy 426.487204 -298.919398) (xy 426.536059 -298.92533) (xy 426.58333 -298.939022)
			(xy 426.627792 -298.96012) (xy 426.668295 -298.988076) (xy 426.703788 -299.022168) (xy 426.733353 -299.061512)
			(xy 426.756224 -299.105089) (xy 426.771808 -299.15177) (xy 426.779703 -299.200347) (xy 426.780198 -299.224954)
			(xy 427.119046 -299.224954) (xy 427.123006 -299.1759) (xy 427.134783 -299.128116) (xy 427.154074 -299.08284)
			(xy 427.180377 -299.041244) (xy 427.213012 -299.004407) (xy 427.251133 -298.973282) (xy 427.293754 -298.948675)
			(xy 427.33977 -298.931223) (xy 427.387989 -298.921379) (xy 427.437164 -298.919398) (xy 427.486019 -298.92533)
			(xy 427.53329 -298.939022) (xy 427.577752 -298.96012) (xy 427.618255 -298.988076) (xy 427.653748 -299.022168)
			(xy 427.683313 -299.061512) (xy 427.706184 -299.105089) (xy 427.721768 -299.15177) (xy 427.729663 -299.200347)
			(xy 427.730158 -299.224954) (xy 428.069006 -299.224954) (xy 428.072966 -299.1759) (xy 428.084743 -299.128116)
			(xy 428.104034 -299.08284) (xy 428.130337 -299.041244) (xy 428.162972 -299.004407) (xy 428.201093 -298.973282)
			(xy 428.243714 -298.948675) (xy 428.28973 -298.931223) (xy 428.337949 -298.921379) (xy 428.387124 -298.919398)
			(xy 428.435979 -298.92533) (xy 428.48325 -298.939022) (xy 428.527712 -298.96012) (xy 428.568215 -298.988076)
			(xy 428.603708 -299.022168) (xy 428.633273 -299.061512) (xy 428.656144 -299.105089) (xy 428.671728 -299.15177)
			(xy 428.679623 -299.200347) (xy 428.680118 -299.224954) (xy 429.01922 -299.224954) (xy 429.02318 -299.1759)
			(xy 429.034957 -299.128116) (xy 429.054248 -299.08284) (xy 429.080551 -299.041244) (xy 429.113186 -299.004407)
			(xy 429.151307 -298.973282) (xy 429.193928 -298.948675) (xy 429.239944 -298.931223) (xy 429.288163 -298.921379)
			(xy 429.337338 -298.919398) (xy 429.386193 -298.92533) (xy 429.433464 -298.939022) (xy 429.477926 -298.96012)
			(xy 429.518429 -298.988076) (xy 429.553922 -299.022168) (xy 429.583487 -299.061512) (xy 429.606358 -299.105089)
			(xy 429.621942 -299.15177) (xy 429.629837 -299.200347) (xy 429.630332 -299.224954) (xy 429.96918 -299.224954)
			(xy 429.97314 -299.1759) (xy 429.984917 -299.128116) (xy 430.004208 -299.08284) (xy 430.030511 -299.041244)
			(xy 430.063146 -299.004407) (xy 430.101267 -298.973282) (xy 430.143888 -298.948675) (xy 430.189904 -298.931223)
			(xy 430.238123 -298.921379) (xy 430.287298 -298.919398) (xy 430.336153 -298.92533) (xy 430.383424 -298.939022)
			(xy 430.427886 -298.96012) (xy 430.468389 -298.988076) (xy 430.503882 -299.022168) (xy 430.533447 -299.061512)
			(xy 430.556318 -299.105089) (xy 430.571902 -299.15177) (xy 430.579797 -299.200347) (xy 430.580292 -299.224954)
			(xy 430.91914 -299.224954) (xy 430.9231 -299.1759) (xy 430.934877 -299.128116) (xy 430.954168 -299.08284)
			(xy 430.980471 -299.041244) (xy 431.013106 -299.004407) (xy 431.051227 -298.973282) (xy 431.093848 -298.948675)
			(xy 431.139864 -298.931223) (xy 431.188083 -298.921379) (xy 431.237258 -298.919398) (xy 431.286113 -298.92533)
			(xy 431.333384 -298.939022) (xy 431.377846 -298.96012) (xy 431.418349 -298.988076) (xy 431.453842 -299.022168)
			(xy 431.483407 -299.061512) (xy 431.506278 -299.105089) (xy 431.521862 -299.15177) (xy 431.529757 -299.200347)
			(xy 431.530252 -299.224954) (xy 431.529757 -299.249561) (xy 431.525954 -299.27296) (xy 438.614564 -299.27296)
			(xy 438.618635 -299.217338) (xy 438.630761 -299.162901) (xy 438.650684 -299.11081) (xy 438.67798 -299.062175)
			(xy 438.712066 -299.018032) (xy 438.752215 -298.979323) (xy 438.797573 -298.946872) (xy 438.847173 -298.921371)
			(xy 438.899957 -298.903364) (xy 438.9548 -298.893234) (xy 439.010534 -298.891197) (xy 439.065971 -298.897297)
			(xy 439.119928 -298.911403) (xy 439.171257 -298.933215) (xy 439.218863 -298.962269) (xy 439.261731 -298.997944)
			(xy 439.298948 -299.039481) (xy 439.329721 -299.085994) (xy 439.353393 -299.136491) (xy 439.369461 -299.189898)
			(xy 439.377581 -299.245074) (xy 439.37809 -299.27296) (xy 439.377581 -299.300846) (xy 439.369461 -299.356022)
			(xy 439.353393 -299.409429) (xy 439.329721 -299.459926) (xy 439.298948 -299.506439) (xy 439.261731 -299.547976)
			(xy 439.218863 -299.583651) (xy 439.171257 -299.612705) (xy 439.119928 -299.634517) (xy 439.065971 -299.648623)
			(xy 439.010534 -299.654723) (xy 438.9548 -299.652686) (xy 438.899957 -299.642556) (xy 438.847173 -299.624549)
			(xy 438.797573 -299.599048) (xy 438.752215 -299.566597) (xy 438.712066 -299.527888) (xy 438.67798 -299.483745)
			(xy 438.650684 -299.43511) (xy 438.630761 -299.383019) (xy 438.618635 -299.328582) (xy 438.614564 -299.27296)
			(xy 431.525954 -299.27296) (xy 431.521862 -299.298138) (xy 431.506278 -299.344819) (xy 431.483407 -299.388396)
			(xy 431.453842 -299.42774) (xy 431.418349 -299.461832) (xy 431.377846 -299.489788) (xy 431.333384 -299.510886)
			(xy 431.286113 -299.524578) (xy 431.237258 -299.53051) (xy 431.188083 -299.528529) (xy 431.139864 -299.518685)
			(xy 431.093848 -299.501233) (xy 431.051227 -299.476626) (xy 431.013106 -299.445501) (xy 430.980471 -299.408664)
			(xy 430.954168 -299.367068) (xy 430.934877 -299.321792) (xy 430.9231 -299.274008) (xy 430.91914 -299.224954)
			(xy 430.580292 -299.224954) (xy 430.579797 -299.249561) (xy 430.571902 -299.298138) (xy 430.556318 -299.344819)
			(xy 430.533447 -299.388396) (xy 430.503882 -299.42774) (xy 430.468389 -299.461832) (xy 430.427886 -299.489788)
			(xy 430.383424 -299.510886) (xy 430.336153 -299.524578) (xy 430.287298 -299.53051) (xy 430.238123 -299.528529)
			(xy 430.189904 -299.518685) (xy 430.143888 -299.501233) (xy 430.101267 -299.476626) (xy 430.063146 -299.445501)
			(xy 430.030511 -299.408664) (xy 430.004208 -299.367068) (xy 429.984917 -299.321792) (xy 429.97314 -299.274008)
			(xy 429.96918 -299.224954) (xy 429.630332 -299.224954) (xy 429.629837 -299.249561) (xy 429.621942 -299.298138)
			(xy 429.606358 -299.344819) (xy 429.583487 -299.388396) (xy 429.553922 -299.42774) (xy 429.518429 -299.461832)
			(xy 429.477926 -299.489788) (xy 429.433464 -299.510886) (xy 429.386193 -299.524578) (xy 429.337338 -299.53051)
			(xy 429.288163 -299.528529) (xy 429.239944 -299.518685) (xy 429.193928 -299.501233) (xy 429.151307 -299.476626)
			(xy 429.113186 -299.445501) (xy 429.080551 -299.408664) (xy 429.054248 -299.367068) (xy 429.034957 -299.321792)
			(xy 429.02318 -299.274008) (xy 429.01922 -299.224954) (xy 428.680118 -299.224954) (xy 428.679623 -299.249561)
			(xy 428.671728 -299.298138) (xy 428.656144 -299.344819) (xy 428.633273 -299.388396) (xy 428.603708 -299.42774)
			(xy 428.568215 -299.461832) (xy 428.527712 -299.489788) (xy 428.48325 -299.510886) (xy 428.435979 -299.524578)
			(xy 428.387124 -299.53051) (xy 428.337949 -299.528529) (xy 428.28973 -299.518685) (xy 428.243714 -299.501233)
			(xy 428.201093 -299.476626) (xy 428.162972 -299.445501) (xy 428.130337 -299.408664) (xy 428.104034 -299.367068)
			(xy 428.084743 -299.321792) (xy 428.072966 -299.274008) (xy 428.069006 -299.224954) (xy 427.730158 -299.224954)
			(xy 427.729663 -299.249561) (xy 427.721768 -299.298138) (xy 427.706184 -299.344819) (xy 427.683313 -299.388396)
			(xy 427.653748 -299.42774) (xy 427.618255 -299.461832) (xy 427.577752 -299.489788) (xy 427.53329 -299.510886)
			(xy 427.486019 -299.524578) (xy 427.437164 -299.53051) (xy 427.387989 -299.528529) (xy 427.33977 -299.518685)
			(xy 427.293754 -299.501233) (xy 427.251133 -299.476626) (xy 427.213012 -299.445501) (xy 427.180377 -299.408664)
			(xy 427.154074 -299.367068) (xy 427.134783 -299.321792) (xy 427.123006 -299.274008) (xy 427.119046 -299.224954)
			(xy 426.780198 -299.224954) (xy 426.779703 -299.249561) (xy 426.771808 -299.298138) (xy 426.756224 -299.344819)
			(xy 426.733353 -299.388396) (xy 426.703788 -299.42774) (xy 426.668295 -299.461832) (xy 426.627792 -299.489788)
			(xy 426.58333 -299.510886) (xy 426.536059 -299.524578) (xy 426.487204 -299.53051) (xy 426.438029 -299.528529)
			(xy 426.38981 -299.518685) (xy 426.343794 -299.501233) (xy 426.301173 -299.476626) (xy 426.263052 -299.445501)
			(xy 426.230417 -299.408664) (xy 426.204114 -299.367068) (xy 426.184823 -299.321792) (xy 426.173046 -299.274008)
			(xy 426.169086 -299.224954) (xy 425.830238 -299.224954) (xy 425.829743 -299.249561) (xy 425.821848 -299.298138)
			(xy 425.806264 -299.344819) (xy 425.783393 -299.388396) (xy 425.753828 -299.42774) (xy 425.718335 -299.461832)
			(xy 425.677832 -299.489788) (xy 425.63337 -299.510886) (xy 425.586099 -299.524578) (xy 425.537244 -299.53051)
			(xy 425.488069 -299.528529) (xy 425.43985 -299.518685) (xy 425.393834 -299.501233) (xy 425.351213 -299.476626)
			(xy 425.313092 -299.445501) (xy 425.280457 -299.408664) (xy 425.254154 -299.367068) (xy 425.234863 -299.321792)
			(xy 425.223086 -299.274008) (xy 425.219126 -299.224954) (xy 424.880278 -299.224954) (xy 424.879783 -299.249561)
			(xy 424.871888 -299.298138) (xy 424.856304 -299.344819) (xy 424.833433 -299.388396) (xy 424.803868 -299.42774)
			(xy 424.768375 -299.461832) (xy 424.727872 -299.489788) (xy 424.68341 -299.510886) (xy 424.636139 -299.524578)
			(xy 424.587284 -299.53051) (xy 424.538109 -299.528529) (xy 424.48989 -299.518685) (xy 424.443874 -299.501233)
			(xy 424.401253 -299.476626) (xy 424.363132 -299.445501) (xy 424.330497 -299.408664) (xy 424.304194 -299.367068)
			(xy 424.284903 -299.321792) (xy 424.273126 -299.274008) (xy 424.269166 -299.224954) (xy 422.030144 -299.224954)
			(xy 422.029649 -299.249561) (xy 422.021754 -299.298138) (xy 422.00617 -299.344819) (xy 421.983299 -299.388396)
			(xy 421.953734 -299.42774) (xy 421.918241 -299.461832) (xy 421.877738 -299.489788) (xy 421.833276 -299.510886)
			(xy 421.786005 -299.524578) (xy 421.73715 -299.53051) (xy 421.687975 -299.528529) (xy 421.639756 -299.518685)
			(xy 421.59374 -299.501233) (xy 421.551119 -299.476626) (xy 421.512998 -299.445501) (xy 421.480363 -299.408664)
			(xy 421.45406 -299.367068) (xy 421.434769 -299.321792) (xy 421.422992 -299.274008) (xy 421.419032 -299.224954)
			(xy 421.080184 -299.224954) (xy 421.079689 -299.249561) (xy 421.071794 -299.298138) (xy 421.05621 -299.344819)
			(xy 421.033339 -299.388396) (xy 421.003774 -299.42774) (xy 420.968281 -299.461832) (xy 420.927778 -299.489788)
			(xy 420.883316 -299.510886) (xy 420.836045 -299.524578) (xy 420.78719 -299.53051) (xy 420.738015 -299.528529)
			(xy 420.689796 -299.518685) (xy 420.64378 -299.501233) (xy 420.601159 -299.476626) (xy 420.563038 -299.445501)
			(xy 420.530403 -299.408664) (xy 420.5041 -299.367068) (xy 420.484809 -299.321792) (xy 420.473032 -299.274008)
			(xy 420.469072 -299.224954) (xy 420.130224 -299.224954) (xy 420.129729 -299.249561) (xy 420.121834 -299.298138)
			(xy 420.10625 -299.344819) (xy 420.083379 -299.388396) (xy 420.053814 -299.42774) (xy 420.018321 -299.461832)
			(xy 419.977818 -299.489788) (xy 419.933356 -299.510886) (xy 419.886085 -299.524578) (xy 419.83723 -299.53051)
			(xy 419.788055 -299.528529) (xy 419.739836 -299.518685) (xy 419.69382 -299.501233) (xy 419.651199 -299.476626)
			(xy 419.613078 -299.445501) (xy 419.580443 -299.408664) (xy 419.55414 -299.367068) (xy 419.534849 -299.321792)
			(xy 419.523072 -299.274008) (xy 419.519112 -299.224954) (xy 419.180264 -299.224954) (xy 419.179769 -299.249561)
			(xy 419.171874 -299.298138) (xy 419.15629 -299.344819) (xy 419.133419 -299.388396) (xy 419.103854 -299.42774)
			(xy 419.068361 -299.461832) (xy 419.027858 -299.489788) (xy 418.983396 -299.510886) (xy 418.936125 -299.524578)
			(xy 418.88727 -299.53051) (xy 418.838095 -299.528529) (xy 418.789876 -299.518685) (xy 418.74386 -299.501233)
			(xy 418.701239 -299.476626) (xy 418.663118 -299.445501) (xy 418.630483 -299.408664) (xy 418.60418 -299.367068)
			(xy 418.584889 -299.321792) (xy 418.573112 -299.274008) (xy 418.569152 -299.224954) (xy 418.230304 -299.224954)
			(xy 418.229809 -299.249561) (xy 418.221914 -299.298138) (xy 418.20633 -299.344819) (xy 418.183459 -299.388396)
			(xy 418.153894 -299.42774) (xy 418.118401 -299.461832) (xy 418.077898 -299.489788) (xy 418.033436 -299.510886)
			(xy 417.986165 -299.524578) (xy 417.93731 -299.53051) (xy 417.888135 -299.528529) (xy 417.839916 -299.518685)
			(xy 417.7939 -299.501233) (xy 417.751279 -299.476626) (xy 417.713158 -299.445501) (xy 417.680523 -299.408664)
			(xy 417.65422 -299.367068) (xy 417.634929 -299.321792) (xy 417.623152 -299.274008) (xy 417.619192 -299.224954)
			(xy 417.28009 -299.224954) (xy 417.279647 -299.248949) (xy 417.272146 -299.296349) (xy 417.257321 -299.341992)
			(xy 417.235538 -299.384753) (xy 417.207333 -299.423579) (xy 417.173401 -299.457515) (xy 417.134577 -299.485724)
			(xy 417.091818 -299.507511) (xy 417.046176 -299.52234) (xy 416.998777 -299.529845) (xy 416.974782 -299.530262)
			(xy 416.950831 -299.529793) (xy 416.903517 -299.522308) (xy 416.857954 -299.507525) (xy 416.815258 -299.485806)
			(xy 416.77648 -299.457685) (xy 416.742569 -299.423852) (xy 416.714359 -299.385137) (xy 416.692543 -299.342492)
			(xy 416.677656 -299.296962) (xy 416.670063 -299.249666) (xy 416.669474 -299.225716) (xy 416.669474 -299.224954)
			(xy 416.669546 -299.215595) (xy 416.67069 -299.196913) (xy 416.67176 -299.187616) (xy 416.672268 -299.184314)
			(xy 416.672268 -299.181266) (xy 416.671774 -299.171265) (xy 416.664107 -299.152791) (xy 416.649954 -299.138656)
			(xy 416.631469 -299.131013) (xy 416.621468 -299.130466) (xy 416.616896 -299.130466) (xy 416.607752 -299.126656)
			(xy 416.603188 -299.124649) (xy 416.594873 -299.11915) (xy 416.591242 -299.115734) (xy 416.581082 -299.105574)
			(xy 416.573686 -299.098722) (xy 416.555087 -299.090983) (xy 416.545014 -299.090588) (xy 416.43046 -299.090588)
			(xy 416.425364 -299.090705) (xy 416.415382 -299.092762) (xy 416.410648 -299.094652) (xy 416.400234 -299.09897)
			(xy 416.33521 -299.169836) (xy 416.328352 -299.189648) (xy 416.329114 -299.200316) (xy 416.33013 -299.224954)
			(xy 416.329608 -299.250209) (xy 416.321295 -299.300031) (xy 416.304894 -299.347805) (xy 416.280853 -299.392228)
			(xy 416.249829 -299.432088) (xy 416.212667 -299.466298) (xy 416.170381 -299.493924) (xy 416.124125 -299.514214)
			(xy 416.07516 -299.526614) (xy 416.024822 -299.530785) (xy 415.974484 -299.526614) (xy 415.925519 -299.514214)
			(xy 415.879263 -299.493924) (xy 415.836977 -299.466298) (xy 415.799815 -299.432088) (xy 415.768791 -299.392228)
			(xy 415.74475 -299.347805) (xy 415.728349 -299.300031) (xy 415.720036 -299.250209) (xy 415.719514 -299.224954)
			(xy 415.72053 -299.200316) (xy 415.721292 -299.189648) (xy 415.714434 -299.169836) (xy 415.656776 -299.107098)
			(xy 415.649664 -299.099224) (xy 415.630106 -299.090588) (xy 415.4805 -299.090588) (xy 415.475403 -299.090701)
			(xy 415.465418 -299.092751) (xy 415.460688 -299.094652) (xy 415.450274 -299.09897) (xy 415.38525 -299.169836)
			(xy 415.378392 -299.189648) (xy 415.379154 -299.200316) (xy 415.38017 -299.224954) (xy 415.379648 -299.250209)
			(xy 415.371335 -299.300031) (xy 415.354934 -299.347805) (xy 415.330893 -299.392228) (xy 415.299869 -299.432088)
			(xy 415.262707 -299.466298) (xy 415.220421 -299.493924) (xy 415.174165 -299.514214) (xy 415.1252 -299.526614)
			(xy 415.074862 -299.530785) (xy 415.024524 -299.526614) (xy 414.975559 -299.514214) (xy 414.929303 -299.493924)
			(xy 414.887017 -299.466298) (xy 414.849855 -299.432088) (xy 414.818831 -299.392228) (xy 414.79479 -299.347805)
			(xy 414.778389 -299.300031) (xy 414.770076 -299.250209) (xy 414.769554 -299.224954) (xy 414.77057 -299.200316)
			(xy 414.771332 -299.189648) (xy 414.764474 -299.169836) (xy 414.706816 -299.107098) (xy 414.699704 -299.099224)
			(xy 414.680146 -299.090588) (xy 414.53054 -299.090588) (xy 414.525442 -299.090697) (xy 414.515454 -299.092739)
			(xy 414.510728 -299.094652) (xy 414.500314 -299.09897) (xy 414.43529 -299.169836) (xy 414.428432 -299.189648)
			(xy 414.429194 -299.200316) (xy 414.43021 -299.224954) (xy 414.429688 -299.250209) (xy 414.421375 -299.300031)
			(xy 414.404974 -299.347805) (xy 414.380933 -299.392228) (xy 414.349909 -299.432088) (xy 414.312747 -299.466298)
			(xy 414.270461 -299.493924) (xy 414.224205 -299.514214) (xy 414.17524 -299.526614) (xy 414.124902 -299.530785)
			(xy 414.074564 -299.526614) (xy 414.025599 -299.514214) (xy 413.979343 -299.493924) (xy 413.937057 -299.466298)
			(xy 413.899895 -299.432088) (xy 413.868871 -299.392228) (xy 413.84483 -299.347805) (xy 413.828429 -299.300031)
			(xy 413.820116 -299.250209) (xy 413.819594 -299.224954) (xy 413.82061 -299.200316) (xy 413.821372 -299.189648)
			(xy 413.814514 -299.169836) (xy 413.756856 -299.107098) (xy 413.749744 -299.099224) (xy 413.730186 -299.090588)
			(xy 413.58058 -299.090588) (xy 413.575484 -299.090703) (xy 413.5655 -299.092756) (xy 413.560768 -299.094652)
			(xy 413.550354 -299.09897) (xy 413.48533 -299.169836) (xy 413.478472 -299.189648) (xy 413.479234 -299.200316)
			(xy 413.48025 -299.224954) (xy 413.479728 -299.250209) (xy 413.471415 -299.300031) (xy 413.455014 -299.347805)
			(xy 413.430973 -299.392228) (xy 413.399949 -299.432088) (xy 413.362787 -299.466298) (xy 413.320501 -299.493924)
			(xy 413.274245 -299.514214) (xy 413.22528 -299.526614) (xy 413.174942 -299.530785) (xy 413.124604 -299.526614)
			(xy 413.075639 -299.514214) (xy 413.029383 -299.493924) (xy 412.987097 -299.466298) (xy 412.949935 -299.432088)
			(xy 412.918911 -299.392228) (xy 412.89487 -299.347805) (xy 412.878469 -299.300031) (xy 412.870156 -299.250209)
			(xy 412.869634 -299.224954) (xy 412.87065 -299.200316) (xy 412.871412 -299.189648) (xy 412.864554 -299.169836)
			(xy 412.806896 -299.107098) (xy 412.799784 -299.099224) (xy 412.780226 -299.090588) (xy 412.63062 -299.090588)
			(xy 412.625523 -299.090699) (xy 412.615536 -299.092745) (xy 412.610808 -299.094652) (xy 412.600394 -299.09897)
			(xy 412.53537 -299.169836) (xy 412.528512 -299.189648) (xy 412.529274 -299.200316) (xy 412.53029 -299.224954)
			(xy 412.529768 -299.250209) (xy 412.521455 -299.300031) (xy 412.505054 -299.347805) (xy 412.481013 -299.392228)
			(xy 412.449989 -299.432088) (xy 412.412827 -299.466298) (xy 412.370541 -299.493924) (xy 412.324285 -299.514214)
			(xy 412.27532 -299.526614) (xy 412.224982 -299.530785) (xy 412.174644 -299.526614) (xy 412.125679 -299.514214)
			(xy 412.079423 -299.493924) (xy 412.037137 -299.466298) (xy 411.999975 -299.432088) (xy 411.968951 -299.392228)
			(xy 411.94491 -299.347805) (xy 411.928509 -299.300031) (xy 411.920196 -299.250209) (xy 411.919674 -299.224954)
			(xy 411.92069 -299.200316) (xy 411.921452 -299.189648) (xy 411.914594 -299.169836) (xy 411.856936 -299.107098)
			(xy 411.849824 -299.099224) (xy 411.830266 -299.090588) (xy 411.68066 -299.090588) (xy 411.675564 -299.090705)
			(xy 411.665582 -299.092762) (xy 411.660848 -299.094652) (xy 411.650434 -299.09897) (xy 411.58541 -299.169836)
			(xy 411.578552 -299.189648) (xy 411.579314 -299.200316) (xy 411.58033 -299.224954) (xy 411.579808 -299.250209)
			(xy 411.571495 -299.300031) (xy 411.555094 -299.347805) (xy 411.531053 -299.392228) (xy 411.500029 -299.432088)
			(xy 411.462867 -299.466298) (xy 411.420581 -299.493924) (xy 411.374325 -299.514214) (xy 411.32536 -299.526614)
			(xy 411.275022 -299.530785) (xy 411.224684 -299.526614) (xy 411.175719 -299.514214) (xy 411.129463 -299.493924)
			(xy 411.087177 -299.466298) (xy 411.050015 -299.432088) (xy 411.018991 -299.392228) (xy 410.99495 -299.347805)
			(xy 410.978549 -299.300031) (xy 410.970236 -299.250209) (xy 410.969714 -299.224954) (xy 410.97073 -299.200316)
			(xy 410.971492 -299.189648) (xy 410.964634 -299.169836) (xy 410.906976 -299.107098) (xy 410.899864 -299.099224)
			(xy 410.880306 -299.090588) (xy 410.730446 -299.090588) (xy 410.725348 -299.090697) (xy 410.71536 -299.092738)
			(xy 410.710634 -299.094652) (xy 410.70022 -299.09897) (xy 410.635196 -299.169836) (xy 410.628338 -299.189648)
			(xy 410.6291 -299.200316) (xy 410.630116 -299.224954) (xy 410.629594 -299.250209) (xy 410.621281 -299.300031)
			(xy 410.60488 -299.347805) (xy 410.580839 -299.392228) (xy 410.549815 -299.432088) (xy 410.512653 -299.466298)
			(xy 410.470367 -299.493924) (xy 410.424111 -299.514214) (xy 410.375146 -299.526614) (xy 410.324808 -299.530785)
			(xy 410.27447 -299.526614) (xy 410.225505 -299.514214) (xy 410.179249 -299.493924) (xy 410.136963 -299.466298)
			(xy 410.099801 -299.432088) (xy 410.068777 -299.392228) (xy 410.044736 -299.347805) (xy 410.028335 -299.300031)
			(xy 410.020022 -299.250209) (xy 410.0195 -299.224954) (xy 410.020516 -299.200316) (xy 410.021278 -299.189648)
			(xy 410.01442 -299.169836) (xy 409.956762 -299.107098) (xy 409.94965 -299.099224) (xy 409.930092 -299.090588)
			(xy 409.780486 -299.090588) (xy 409.77539 -299.090703) (xy 409.765406 -299.092755) (xy 409.760674 -299.094652)
			(xy 409.75026 -299.09897) (xy 409.685236 -299.169836) (xy 409.678378 -299.189648) (xy 409.67914 -299.200316)
			(xy 409.680156 -299.224954) (xy 409.679634 -299.250209) (xy 409.671321 -299.300031) (xy 409.65492 -299.347805)
			(xy 409.630879 -299.392228) (xy 409.599855 -299.432088) (xy 409.562693 -299.466298) (xy 409.520407 -299.493924)
			(xy 409.474151 -299.514214) (xy 409.425186 -299.526614) (xy 409.374848 -299.530785) (xy 409.32451 -299.526614)
			(xy 409.275545 -299.514214) (xy 409.229289 -299.493924) (xy 409.187003 -299.466298) (xy 409.149841 -299.432088)
			(xy 409.118817 -299.392228) (xy 409.094776 -299.347805) (xy 409.078375 -299.300031) (xy 409.070062 -299.250209)
			(xy 409.06954 -299.224954) (xy 409.070556 -299.200316) (xy 409.071318 -299.189648) (xy 409.06446 -299.169836)
			(xy 409.006802 -299.107098) (xy 408.99969 -299.099224) (xy 408.980132 -299.090588) (xy 408.830526 -299.090588)
			(xy 408.825429 -299.090699) (xy 408.815442 -299.092743) (xy 408.810714 -299.094652) (xy 408.8003 -299.09897)
			(xy 408.735276 -299.169836) (xy 408.728418 -299.189648) (xy 408.72918 -299.200316) (xy 408.730196 -299.224954)
			(xy 408.729674 -299.250209) (xy 408.721361 -299.300031) (xy 408.70496 -299.347805) (xy 408.680919 -299.392228)
			(xy 408.649895 -299.432088) (xy 408.612733 -299.466298) (xy 408.570447 -299.493924) (xy 408.524191 -299.514214)
			(xy 408.475226 -299.526614) (xy 408.424888 -299.530785) (xy 408.37455 -299.526614) (xy 408.325585 -299.514214)
			(xy 408.279329 -299.493924) (xy 408.237043 -299.466298) (xy 408.199881 -299.432088) (xy 408.168857 -299.392228)
			(xy 408.144816 -299.347805) (xy 408.128415 -299.300031) (xy 408.120102 -299.250209) (xy 408.11958 -299.224954)
			(xy 408.120596 -299.200316) (xy 408.121358 -299.189648) (xy 408.1145 -299.169836) (xy 408.056842 -299.107098)
			(xy 408.04973 -299.099224) (xy 408.030172 -299.090588) (xy 406.930606 -299.090588) (xy 406.925509 -299.090701)
			(xy 406.915524 -299.092749) (xy 406.910794 -299.094652) (xy 406.90038 -299.09897) (xy 406.835356 -299.169836)
			(xy 406.828498 -299.189648) (xy 406.82926 -299.200316) (xy 406.830276 -299.224954) (xy 406.829754 -299.250209)
			(xy 406.821441 -299.300031) (xy 406.80504 -299.347805) (xy 406.780999 -299.392228) (xy 406.749975 -299.432088)
			(xy 406.712813 -299.466298) (xy 406.670527 -299.493924) (xy 406.624271 -299.514214) (xy 406.575306 -299.526614)
			(xy 406.524968 -299.530785) (xy 406.47463 -299.526614) (xy 406.425665 -299.514214) (xy 406.379409 -299.493924)
			(xy 406.337123 -299.466298) (xy 406.299961 -299.432088) (xy 406.268937 -299.392228) (xy 406.244896 -299.347805)
			(xy 406.228495 -299.300031) (xy 406.220182 -299.250209) (xy 406.21966 -299.224954) (xy 406.220676 -299.200316)
			(xy 406.221438 -299.189648) (xy 406.21458 -299.169836) (xy 406.156922 -299.107098) (xy 406.14981 -299.099224)
			(xy 406.130252 -299.090588) (xy 405.980646 -299.090588) (xy 405.975548 -299.090697) (xy 405.96556 -299.092738)
			(xy 405.960834 -299.094652) (xy 405.95042 -299.09897) (xy 405.885396 -299.169836) (xy 405.878538 -299.189648)
			(xy 405.8793 -299.200316) (xy 405.880316 -299.224954) (xy 405.879794 -299.250209) (xy 405.871481 -299.300031)
			(xy 405.85508 -299.347805) (xy 405.831039 -299.392228) (xy 405.800015 -299.432088) (xy 405.762853 -299.466298)
			(xy 405.720567 -299.493924) (xy 405.674311 -299.514214) (xy 405.625346 -299.526614) (xy 405.575008 -299.530785)
			(xy 405.52467 -299.526614) (xy 405.475705 -299.514214) (xy 405.429449 -299.493924) (xy 405.387163 -299.466298)
			(xy 405.350001 -299.432088) (xy 405.318977 -299.392228) (xy 405.294936 -299.347805) (xy 405.278535 -299.300031)
			(xy 405.270222 -299.250209) (xy 405.2697 -299.224954) (xy 405.270716 -299.200316) (xy 405.271478 -299.189648)
			(xy 405.26462 -299.169836) (xy 405.206962 -299.107098) (xy 405.19985 -299.099224) (xy 405.180292 -299.090588)
			(xy 405.030432 -299.090588) (xy 405.025334 -299.090698) (xy 405.015347 -299.092742) (xy 405.01062 -299.094652)
			(xy 405.000206 -299.09897) (xy 404.935182 -299.169836) (xy 404.928324 -299.189648) (xy 404.929086 -299.200316)
			(xy 404.930102 -299.224954) (xy 404.92958 -299.250209) (xy 404.921267 -299.300031) (xy 404.904866 -299.347805)
			(xy 404.880825 -299.392228) (xy 404.849801 -299.432088) (xy 404.812639 -299.466298) (xy 404.770353 -299.493924)
			(xy 404.724097 -299.514214) (xy 404.675132 -299.526614) (xy 404.624794 -299.530785) (xy 404.574456 -299.526614)
			(xy 404.525491 -299.514214) (xy 404.479235 -299.493924) (xy 404.436949 -299.466298) (xy 404.399787 -299.432088)
			(xy 404.368763 -299.392228) (xy 404.344722 -299.347805) (xy 404.328321 -299.300031) (xy 404.320008 -299.250209)
			(xy 404.319486 -299.224954) (xy 404.320502 -299.200316) (xy 404.321264 -299.189648) (xy 404.314406 -299.169836)
			(xy 404.256748 -299.107098) (xy 404.249636 -299.099224) (xy 404.230078 -299.090588) (xy 404.080472 -299.090588)
			(xy 404.075376 -299.090704) (xy 404.065393 -299.092759) (xy 404.06066 -299.094652) (xy 404.050246 -299.09897)
			(xy 403.985222 -299.169836) (xy 403.978364 -299.189648) (xy 403.979126 -299.200316) (xy 403.980142 -299.224954)
			(xy 403.97962 -299.250209) (xy 403.971307 -299.300031) (xy 403.954906 -299.347805) (xy 403.930865 -299.392228)
			(xy 403.899841 -299.432088) (xy 403.862679 -299.466298) (xy 403.820393 -299.493924) (xy 403.774137 -299.514214)
			(xy 403.725172 -299.526614) (xy 403.674834 -299.530785) (xy 403.624496 -299.526614) (xy 403.575531 -299.514214)
			(xy 403.529275 -299.493924) (xy 403.486989 -299.466298) (xy 403.449827 -299.432088) (xy 403.418803 -299.392228)
			(xy 403.394762 -299.347805) (xy 403.378361 -299.300031) (xy 403.370048 -299.250209) (xy 403.369526 -299.224954)
			(xy 403.370542 -299.200316) (xy 403.371304 -299.189648) (xy 403.364446 -299.169836) (xy 403.306788 -299.107098)
			(xy 403.299676 -299.099224) (xy 403.280118 -299.090588) (xy 403.130512 -299.090588) (xy 403.125415 -299.0907)
			(xy 403.115429 -299.092747) (xy 403.1107 -299.094652) (xy 403.100286 -299.09897) (xy 403.035262 -299.169836)
			(xy 403.028404 -299.189648) (xy 403.029166 -299.200316) (xy 403.030182 -299.224954) (xy 403.02966 -299.250209)
			(xy 403.021347 -299.300031) (xy 403.004946 -299.347805) (xy 402.980905 -299.392228) (xy 402.949881 -299.432088)
			(xy 402.912719 -299.466298) (xy 402.870433 -299.493924) (xy 402.824177 -299.514214) (xy 402.775212 -299.526614)
			(xy 402.724874 -299.530785) (xy 402.674536 -299.526614) (xy 402.625571 -299.514214) (xy 402.579315 -299.493924)
			(xy 402.537029 -299.466298) (xy 402.499867 -299.432088) (xy 402.468843 -299.392228) (xy 402.444802 -299.347805)
			(xy 402.428401 -299.300031) (xy 402.420088 -299.250209) (xy 402.419566 -299.224954) (xy 402.420582 -299.200316)
			(xy 402.421344 -299.189648) (xy 402.414486 -299.169836) (xy 402.356828 -299.107098) (xy 402.349716 -299.099224)
			(xy 402.330158 -299.090588) (xy 402.180552 -299.090588) (xy 402.175456 -299.090706) (xy 402.165475 -299.092764)
			(xy 402.16074 -299.094652) (xy 402.150326 -299.09897) (xy 402.085302 -299.169836) (xy 402.078444 -299.189648)
			(xy 402.079206 -299.200316) (xy 402.080222 -299.224954) (xy 402.0797 -299.250209) (xy 402.071387 -299.300031)
			(xy 402.054986 -299.347805) (xy 402.030945 -299.392228) (xy 401.999921 -299.432088) (xy 401.962759 -299.466298)
			(xy 401.920473 -299.493924) (xy 401.874217 -299.514214) (xy 401.825252 -299.526614) (xy 401.774914 -299.530785)
			(xy 401.724576 -299.526614) (xy 401.675611 -299.514214) (xy 401.629355 -299.493924) (xy 401.587069 -299.466298)
			(xy 401.549907 -299.432088) (xy 401.518883 -299.392228) (xy 401.494842 -299.347805) (xy 401.478441 -299.300031)
			(xy 401.470128 -299.250209) (xy 401.469606 -299.224954) (xy 401.470622 -299.200316) (xy 401.471384 -299.189648)
			(xy 401.464526 -299.169836) (xy 401.406868 -299.107098) (xy 401.399756 -299.099224) (xy 401.380198 -299.090588)
			(xy 401.230592 -299.090588) (xy 401.225495 -299.090702) (xy 401.215511 -299.092753) (xy 401.21078 -299.094652)
			(xy 401.200366 -299.09897) (xy 401.135342 -299.169836) (xy 401.128484 -299.189648) (xy 401.129246 -299.200316)
			(xy 401.130262 -299.224954) (xy 401.12974 -299.250209) (xy 401.121427 -299.300031) (xy 401.105026 -299.347805)
			(xy 401.080985 -299.392228) (xy 401.049961 -299.432088) (xy 401.012799 -299.466298) (xy 400.970513 -299.493924)
			(xy 400.924257 -299.514214) (xy 400.875292 -299.526614) (xy 400.824954 -299.530785) (xy 400.774616 -299.526614)
			(xy 400.725651 -299.514214) (xy 400.679395 -299.493924) (xy 400.637109 -299.466298) (xy 400.599947 -299.432088)
			(xy 400.568923 -299.392228) (xy 400.544882 -299.347805) (xy 400.528481 -299.300031) (xy 400.520168 -299.250209)
			(xy 400.519646 -299.224954) (xy 400.520662 -299.200316) (xy 400.521424 -299.189648) (xy 400.514566 -299.169836)
			(xy 400.456908 -299.107098) (xy 400.449796 -299.099224) (xy 400.430238 -299.090588) (xy 400.280632 -299.090588)
			(xy 400.275534 -299.090698) (xy 400.265547 -299.092742) (xy 400.26082 -299.094652) (xy 400.250406 -299.09897)
			(xy 400.185382 -299.169836) (xy 400.178524 -299.189648) (xy 400.179286 -299.200316) (xy 400.180302 -299.224954)
			(xy 400.17978 -299.250209) (xy 400.171467 -299.300031) (xy 400.155066 -299.347805) (xy 400.131025 -299.392228)
			(xy 400.100001 -299.432088) (xy 400.062839 -299.466298) (xy 400.020553 -299.493924) (xy 399.974297 -299.514214)
			(xy 399.925332 -299.526614) (xy 399.874994 -299.530785) (xy 399.824656 -299.526614) (xy 399.775691 -299.514214)
			(xy 399.729435 -299.493924) (xy 399.687149 -299.466298) (xy 399.649987 -299.432088) (xy 399.618963 -299.392228)
			(xy 399.594922 -299.347805) (xy 399.578521 -299.300031) (xy 399.570208 -299.250209) (xy 399.569686 -299.224954)
			(xy 399.570702 -299.200316) (xy 399.571464 -299.189648) (xy 399.564606 -299.169836) (xy 399.506948 -299.107098)
			(xy 399.499836 -299.099224) (xy 399.480278 -299.090588) (xy 399.330672 -299.090588) (xy 399.325576 -299.090704)
			(xy 399.315593 -299.092759) (xy 399.31086 -299.094652) (xy 399.300446 -299.09897) (xy 399.235422 -299.169836)
			(xy 399.228564 -299.189648) (xy 399.229326 -299.200316) (xy 399.230342 -299.224954) (xy 399.229876 -299.248829)
			(xy 399.222435 -299.295997) (xy 399.207742 -299.341431) (xy 399.186155 -299.384023) (xy 399.158201 -299.422737)
			(xy 399.124562 -299.456627) (xy 399.086057 -299.484867) (xy 399.043625 -299.506769) (xy 398.998302 -299.521799)
			(xy 398.951191 -299.52959) (xy 398.92732 -299.530262) (xy 398.925542 -299.530262) (xy 398.89967 -299.529758)
			(xy 398.848653 -299.521126) (xy 398.799815 -299.504032) (xy 398.75455 -299.478965) (xy 398.734026 -299.463206)
			(xy 398.727422 -299.457872) (xy 398.711674 -299.45203) (xy 398.701273 -299.44876) (xy 398.679553 -299.450405)
			(xy 398.660471 -299.460908) (xy 398.653508 -299.469302) (xy 398.643602 -299.482764) (xy 398.643348 -299.516038)
			(xy 398.644364 -299.517562) (xy 398.644364 -299.522134) (xy 398.644364 -299.76445) (xy 436.341772 -299.76445)
			(xy 436.345843 -299.708828) (xy 436.357969 -299.654391) (xy 436.377892 -299.6023) (xy 436.405188 -299.553665)
			(xy 436.439274 -299.509522) (xy 436.479423 -299.470813) (xy 436.524781 -299.438362) (xy 436.574381 -299.412861)
			(xy 436.627165 -299.394854) (xy 436.682008 -299.384724) (xy 436.737742 -299.382687) (xy 436.793179 -299.388787)
			(xy 436.847136 -299.402893) (xy 436.898465 -299.424705) (xy 436.946071 -299.453759) (xy 436.988939 -299.489434)
			(xy 437.026156 -299.530971) (xy 437.056929 -299.577484) (xy 437.080601 -299.627981) (xy 437.096669 -299.681388)
			(xy 437.104789 -299.736564) (xy 437.105298 -299.76445) (xy 437.10502 -299.77969) (xy 440.93841 -299.77969)
			(xy 440.942481 -299.724068) (xy 440.954607 -299.669631) (xy 440.97453 -299.61754) (xy 441.001826 -299.568905)
			(xy 441.035912 -299.524762) (xy 441.076061 -299.486053) (xy 441.121419 -299.453602) (xy 441.171019 -299.428101)
			(xy 441.223803 -299.410094) (xy 441.278646 -299.399964) (xy 441.33438 -299.397927) (xy 441.389817 -299.404027)
			(xy 441.443774 -299.418133) (xy 441.495103 -299.439945) (xy 441.542709 -299.468999) (xy 441.585577 -299.504674)
			(xy 441.622794 -299.546211) (xy 441.653567 -299.592724) (xy 441.677239 -299.643221) (xy 441.693307 -299.696628)
			(xy 441.701427 -299.751804) (xy 441.701936 -299.77969) (xy 441.701427 -299.807576) (xy 441.693307 -299.862752)
			(xy 441.677239 -299.916159) (xy 441.653567 -299.966656) (xy 441.622794 -300.013169) (xy 441.585577 -300.054706)
			(xy 441.542709 -300.090381) (xy 441.495103 -300.119435) (xy 441.443774 -300.141247) (xy 441.389817 -300.155353)
			(xy 441.33438 -300.161453) (xy 441.278646 -300.159416) (xy 441.223803 -300.149286) (xy 441.171019 -300.131279)
			(xy 441.121419 -300.105778) (xy 441.076061 -300.073327) (xy 441.035912 -300.034618) (xy 441.001826 -299.990475)
			(xy 440.97453 -299.94184) (xy 440.954607 -299.889749) (xy 440.942481 -299.835312) (xy 440.93841 -299.77969)
			(xy 437.10502 -299.77969) (xy 437.104789 -299.792336) (xy 437.096669 -299.847512) (xy 437.080601 -299.900919)
			(xy 437.056929 -299.951416) (xy 437.026156 -299.997929) (xy 436.988939 -300.039466) (xy 436.946071 -300.075141)
			(xy 436.898465 -300.104195) (xy 436.847136 -300.126007) (xy 436.793179 -300.140113) (xy 436.737742 -300.146213)
			(xy 436.682008 -300.144176) (xy 436.627165 -300.134046) (xy 436.574381 -300.116039) (xy 436.524781 -300.090538)
			(xy 436.479423 -300.058087) (xy 436.439274 -300.019378) (xy 436.405188 -299.975235) (xy 436.377892 -299.9266)
			(xy 436.357969 -299.874509) (xy 436.345843 -299.820072) (xy 436.341772 -299.76445) (xy 398.644364 -299.76445)
			(xy 398.644364 -299.809154) (xy 398.644863 -299.820238) (xy 398.654082 -299.840393) (xy 398.662144 -299.848016)
			(xy 398.666208 -299.851318) (xy 398.733264 -299.892974) (xy 398.73937 -299.896477) (xy 398.752899 -299.900344)
			(xy 398.759934 -299.900594) (xy 398.790414 -299.900594) (xy 398.80032 -299.896276) (xy 398.826329 -299.885372)
			(xy 398.881161 -299.872209) (xy 398.909286 -299.870114) (xy 398.921732 -299.869606) (xy 398.927066 -299.869606)
			(xy 398.950951 -299.87023) (xy 398.998092 -299.877992) (xy 399.04345 -299.893001) (xy 399.085915 -299.914894)
			(xy 399.124452 -299.943133) (xy 399.15812 -299.977031) (xy 399.186097 -300.01576) (xy 399.207699 -300.058374)
			(xy 399.2224 -300.103832) (xy 399.22984 -300.151026) (xy 399.230342 -300.174914) (xy 399.56919 -300.174914)
			(xy 399.57315 -300.12586) (xy 399.584927 -300.078076) (xy 399.604218 -300.0328) (xy 399.630521 -299.991204)
			(xy 399.663156 -299.954367) (xy 399.701277 -299.923242) (xy 399.743898 -299.898635) (xy 399.789914 -299.881183)
			(xy 399.838133 -299.871339) (xy 399.887308 -299.869358) (xy 399.936163 -299.87529) (xy 399.983434 -299.888982)
			(xy 400.027896 -299.91008) (xy 400.068399 -299.938036) (xy 400.103892 -299.972128) (xy 400.133457 -300.011472)
			(xy 400.156328 -300.055049) (xy 400.171912 -300.10173) (xy 400.179807 -300.150307) (xy 400.180302 -300.174914)
			(xy 400.51915 -300.174914) (xy 400.52311 -300.12586) (xy 400.534887 -300.078076) (xy 400.554178 -300.0328)
			(xy 400.580481 -299.991204) (xy 400.613116 -299.954367) (xy 400.651237 -299.923242) (xy 400.693858 -299.898635)
			(xy 400.739874 -299.881183) (xy 400.788093 -299.871339) (xy 400.837268 -299.869358) (xy 400.886123 -299.87529)
			(xy 400.933394 -299.888982) (xy 400.977856 -299.91008) (xy 401.018359 -299.938036) (xy 401.053852 -299.972128)
			(xy 401.083417 -300.011472) (xy 401.106288 -300.055049) (xy 401.121872 -300.10173) (xy 401.129767 -300.150307)
			(xy 401.130262 -300.174914) (xy 401.46911 -300.174914) (xy 401.47307 -300.12586) (xy 401.484847 -300.078076)
			(xy 401.504138 -300.0328) (xy 401.530441 -299.991204) (xy 401.563076 -299.954367) (xy 401.601197 -299.923242)
			(xy 401.643818 -299.898635) (xy 401.689834 -299.881183) (xy 401.738053 -299.871339) (xy 401.787228 -299.869358)
			(xy 401.836083 -299.87529) (xy 401.883354 -299.888982) (xy 401.927816 -299.91008) (xy 401.968319 -299.938036)
			(xy 402.003812 -299.972128) (xy 402.033377 -300.011472) (xy 402.056248 -300.055049) (xy 402.071832 -300.10173)
			(xy 402.079727 -300.150307) (xy 402.080222 -300.174914) (xy 402.41907 -300.174914) (xy 402.42303 -300.12586)
			(xy 402.434807 -300.078076) (xy 402.454098 -300.0328) (xy 402.480401 -299.991204) (xy 402.513036 -299.954367)
			(xy 402.551157 -299.923242) (xy 402.593778 -299.898635) (xy 402.639794 -299.881183) (xy 402.688013 -299.871339)
			(xy 402.737188 -299.869358) (xy 402.786043 -299.87529) (xy 402.833314 -299.888982) (xy 402.877776 -299.91008)
			(xy 402.918279 -299.938036) (xy 402.953772 -299.972128) (xy 402.983337 -300.011472) (xy 403.006208 -300.055049)
			(xy 403.021792 -300.10173) (xy 403.029687 -300.150307) (xy 403.030182 -300.174914) (xy 403.36903 -300.174914)
			(xy 403.37299 -300.12586) (xy 403.384767 -300.078076) (xy 403.404058 -300.0328) (xy 403.430361 -299.991204)
			(xy 403.462996 -299.954367) (xy 403.501117 -299.923242) (xy 403.543738 -299.898635) (xy 403.589754 -299.881183)
			(xy 403.637973 -299.871339) (xy 403.687148 -299.869358) (xy 403.736003 -299.87529) (xy 403.783274 -299.888982)
			(xy 403.827736 -299.91008) (xy 403.868239 -299.938036) (xy 403.903732 -299.972128) (xy 403.933297 -300.011472)
			(xy 403.956168 -300.055049) (xy 403.971752 -300.10173) (xy 403.979647 -300.150307) (xy 403.980142 -300.174914)
			(xy 404.31899 -300.174914) (xy 404.32295 -300.12586) (xy 404.334727 -300.078076) (xy 404.354018 -300.0328)
			(xy 404.380321 -299.991204) (xy 404.412956 -299.954367) (xy 404.451077 -299.923242) (xy 404.493698 -299.898635)
			(xy 404.539714 -299.881183) (xy 404.587933 -299.871339) (xy 404.637108 -299.869358) (xy 404.685963 -299.87529)
			(xy 404.733234 -299.888982) (xy 404.777696 -299.91008) (xy 404.818199 -299.938036) (xy 404.853692 -299.972128)
			(xy 404.883257 -300.011472) (xy 404.906128 -300.055049) (xy 404.921712 -300.10173) (xy 404.929607 -300.150307)
			(xy 404.930102 -300.174914) (xy 405.269204 -300.174914) (xy 405.273164 -300.12586) (xy 405.284941 -300.078076)
			(xy 405.304232 -300.0328) (xy 405.330535 -299.991204) (xy 405.36317 -299.954367) (xy 405.401291 -299.923242)
			(xy 405.443912 -299.898635) (xy 405.489928 -299.881183) (xy 405.538147 -299.871339) (xy 405.587322 -299.869358)
			(xy 405.636177 -299.87529) (xy 405.683448 -299.888982) (xy 405.72791 -299.91008) (xy 405.768413 -299.938036)
			(xy 405.803906 -299.972128) (xy 405.833471 -300.011472) (xy 405.856342 -300.055049) (xy 405.871926 -300.10173)
			(xy 405.879821 -300.150307) (xy 405.880316 -300.174914) (xy 406.219164 -300.174914) (xy 406.223124 -300.12586)
			(xy 406.234901 -300.078076) (xy 406.254192 -300.0328) (xy 406.280495 -299.991204) (xy 406.31313 -299.954367)
			(xy 406.351251 -299.923242) (xy 406.393872 -299.898635) (xy 406.439888 -299.881183) (xy 406.488107 -299.871339)
			(xy 406.537282 -299.869358) (xy 406.586137 -299.87529) (xy 406.633408 -299.888982) (xy 406.67787 -299.91008)
			(xy 406.718373 -299.938036) (xy 406.753866 -299.972128) (xy 406.783431 -300.011472) (xy 406.806302 -300.055049)
			(xy 406.821886 -300.10173) (xy 406.829781 -300.150307) (xy 406.830276 -300.174914) (xy 408.119084 -300.174914)
			(xy 408.123044 -300.12586) (xy 408.134821 -300.078076) (xy 408.154112 -300.0328) (xy 408.180415 -299.991204)
			(xy 408.21305 -299.954367) (xy 408.251171 -299.923242) (xy 408.293792 -299.898635) (xy 408.339808 -299.881183)
			(xy 408.388027 -299.871339) (xy 408.437202 -299.869358) (xy 408.486057 -299.87529) (xy 408.533328 -299.888982)
			(xy 408.57779 -299.91008) (xy 408.618293 -299.938036) (xy 408.653786 -299.972128) (xy 408.683351 -300.011472)
			(xy 408.706222 -300.055049) (xy 408.721806 -300.10173) (xy 408.729701 -300.150307) (xy 408.730196 -300.174914)
			(xy 409.069044 -300.174914) (xy 409.073004 -300.12586) (xy 409.084781 -300.078076) (xy 409.104072 -300.0328)
			(xy 409.130375 -299.991204) (xy 409.16301 -299.954367) (xy 409.201131 -299.923242) (xy 409.243752 -299.898635)
			(xy 409.289768 -299.881183) (xy 409.337987 -299.871339) (xy 409.387162 -299.869358) (xy 409.436017 -299.87529)
			(xy 409.483288 -299.888982) (xy 409.52775 -299.91008) (xy 409.568253 -299.938036) (xy 409.603746 -299.972128)
			(xy 409.633311 -300.011472) (xy 409.656182 -300.055049) (xy 409.671766 -300.10173) (xy 409.679661 -300.150307)
			(xy 409.680156 -300.174914) (xy 410.019004 -300.174914) (xy 410.022964 -300.12586) (xy 410.034741 -300.078076)
			(xy 410.054032 -300.0328) (xy 410.080335 -299.991204) (xy 410.11297 -299.954367) (xy 410.151091 -299.923242)
			(xy 410.193712 -299.898635) (xy 410.239728 -299.881183) (xy 410.287947 -299.871339) (xy 410.337122 -299.869358)
			(xy 410.385977 -299.87529) (xy 410.433248 -299.888982) (xy 410.47771 -299.91008) (xy 410.518213 -299.938036)
			(xy 410.553706 -299.972128) (xy 410.583271 -300.011472) (xy 410.606142 -300.055049) (xy 410.621726 -300.10173)
			(xy 410.629621 -300.150307) (xy 410.630116 -300.174914) (xy 410.969218 -300.174914) (xy 410.973178 -300.12586)
			(xy 410.984955 -300.078076) (xy 411.004246 -300.0328) (xy 411.030549 -299.991204) (xy 411.063184 -299.954367)
			(xy 411.101305 -299.923242) (xy 411.143926 -299.898635) (xy 411.189942 -299.881183) (xy 411.238161 -299.871339)
			(xy 411.287336 -299.869358) (xy 411.336191 -299.87529) (xy 411.383462 -299.888982) (xy 411.427924 -299.91008)
			(xy 411.468427 -299.938036) (xy 411.50392 -299.972128) (xy 411.533485 -300.011472) (xy 411.556356 -300.055049)
			(xy 411.57194 -300.10173) (xy 411.579835 -300.150307) (xy 411.58033 -300.174914) (xy 411.919178 -300.174914)
			(xy 411.923138 -300.12586) (xy 411.934915 -300.078076) (xy 411.954206 -300.0328) (xy 411.980509 -299.991204)
			(xy 412.013144 -299.954367) (xy 412.051265 -299.923242) (xy 412.093886 -299.898635) (xy 412.139902 -299.881183)
			(xy 412.188121 -299.871339) (xy 412.237296 -299.869358) (xy 412.286151 -299.87529) (xy 412.333422 -299.888982)
			(xy 412.377884 -299.91008) (xy 412.418387 -299.938036) (xy 412.45388 -299.972128) (xy 412.483445 -300.011472)
			(xy 412.506316 -300.055049) (xy 412.5219 -300.10173) (xy 412.529795 -300.150307) (xy 412.53029 -300.174914)
			(xy 412.869138 -300.174914) (xy 412.873098 -300.12586) (xy 412.884875 -300.078076) (xy 412.904166 -300.0328)
			(xy 412.930469 -299.991204) (xy 412.963104 -299.954367) (xy 413.001225 -299.923242) (xy 413.043846 -299.898635)
			(xy 413.089862 -299.881183) (xy 413.138081 -299.871339) (xy 413.187256 -299.869358) (xy 413.236111 -299.87529)
			(xy 413.283382 -299.888982) (xy 413.327844 -299.91008) (xy 413.368347 -299.938036) (xy 413.40384 -299.972128)
			(xy 413.433405 -300.011472) (xy 413.456276 -300.055049) (xy 413.47186 -300.10173) (xy 413.479755 -300.150307)
			(xy 413.48025 -300.174914) (xy 413.819098 -300.174914) (xy 413.823058 -300.12586) (xy 413.834835 -300.078076)
			(xy 413.854126 -300.0328) (xy 413.880429 -299.991204) (xy 413.913064 -299.954367) (xy 413.951185 -299.923242)
			(xy 413.993806 -299.898635) (xy 414.039822 -299.881183) (xy 414.088041 -299.871339) (xy 414.137216 -299.869358)
			(xy 414.186071 -299.87529) (xy 414.233342 -299.888982) (xy 414.277804 -299.91008) (xy 414.318307 -299.938036)
			(xy 414.3538 -299.972128) (xy 414.383365 -300.011472) (xy 414.406236 -300.055049) (xy 414.42182 -300.10173)
			(xy 414.429715 -300.150307) (xy 414.43021 -300.174914) (xy 414.769058 -300.174914) (xy 414.773018 -300.12586)
			(xy 414.784795 -300.078076) (xy 414.804086 -300.0328) (xy 414.830389 -299.991204) (xy 414.863024 -299.954367)
			(xy 414.901145 -299.923242) (xy 414.943766 -299.898635) (xy 414.989782 -299.881183) (xy 415.038001 -299.871339)
			(xy 415.087176 -299.869358) (xy 415.136031 -299.87529) (xy 415.183302 -299.888982) (xy 415.227764 -299.91008)
			(xy 415.268267 -299.938036) (xy 415.30376 -299.972128) (xy 415.333325 -300.011472) (xy 415.356196 -300.055049)
			(xy 415.37178 -300.10173) (xy 415.379675 -300.150307) (xy 415.38017 -300.174914) (xy 415.719018 -300.174914)
			(xy 415.722978 -300.12586) (xy 415.734755 -300.078076) (xy 415.754046 -300.0328) (xy 415.780349 -299.991204)
			(xy 415.812984 -299.954367) (xy 415.851105 -299.923242) (xy 415.893726 -299.898635) (xy 415.939742 -299.881183)
			(xy 415.987961 -299.871339) (xy 416.037136 -299.869358) (xy 416.085991 -299.87529) (xy 416.133262 -299.888982)
			(xy 416.177724 -299.91008) (xy 416.218227 -299.938036) (xy 416.25372 -299.972128) (xy 416.283285 -300.011472)
			(xy 416.306156 -300.055049) (xy 416.32174 -300.10173) (xy 416.329635 -300.150307) (xy 416.33013 -300.174914)
			(xy 416.668978 -300.174914) (xy 416.672938 -300.12586) (xy 416.684715 -300.078076) (xy 416.704006 -300.0328)
			(xy 416.730309 -299.991204) (xy 416.762944 -299.954367) (xy 416.801065 -299.923242) (xy 416.843686 -299.898635)
			(xy 416.889702 -299.881183) (xy 416.937921 -299.871339) (xy 416.987096 -299.869358) (xy 417.035951 -299.87529)
			(xy 417.083222 -299.888982) (xy 417.127684 -299.91008) (xy 417.168187 -299.938036) (xy 417.20368 -299.972128)
			(xy 417.233245 -300.011472) (xy 417.256116 -300.055049) (xy 417.2717 -300.10173) (xy 417.279595 -300.150307)
			(xy 417.28009 -300.174914) (xy 417.619192 -300.174914) (xy 417.623152 -300.12586) (xy 417.634929 -300.078076)
			(xy 417.65422 -300.0328) (xy 417.680523 -299.991204) (xy 417.713158 -299.954367) (xy 417.751279 -299.923242)
			(xy 417.7939 -299.898635) (xy 417.839916 -299.881183) (xy 417.888135 -299.871339) (xy 417.93731 -299.869358)
			(xy 417.986165 -299.87529) (xy 418.033436 -299.888982) (xy 418.077898 -299.91008) (xy 418.118401 -299.938036)
			(xy 418.153894 -299.972128) (xy 418.183459 -300.011472) (xy 418.20633 -300.055049) (xy 418.221914 -300.10173)
			(xy 418.229809 -300.150307) (xy 418.230304 -300.174914) (xy 418.569152 -300.174914) (xy 418.573112 -300.12586)
			(xy 418.584889 -300.078076) (xy 418.60418 -300.0328) (xy 418.630483 -299.991204) (xy 418.663118 -299.954367)
			(xy 418.701239 -299.923242) (xy 418.74386 -299.898635) (xy 418.789876 -299.881183) (xy 418.838095 -299.871339)
			(xy 418.88727 -299.869358) (xy 418.936125 -299.87529) (xy 418.983396 -299.888982) (xy 419.027858 -299.91008)
			(xy 419.068361 -299.938036) (xy 419.103854 -299.972128) (xy 419.133419 -300.011472) (xy 419.15629 -300.055049)
			(xy 419.171874 -300.10173) (xy 419.179769 -300.150307) (xy 419.180264 -300.174914) (xy 419.519112 -300.174914)
			(xy 419.523072 -300.12586) (xy 419.534849 -300.078076) (xy 419.55414 -300.0328) (xy 419.580443 -299.991204)
			(xy 419.613078 -299.954367) (xy 419.651199 -299.923242) (xy 419.69382 -299.898635) (xy 419.739836 -299.881183)
			(xy 419.788055 -299.871339) (xy 419.83723 -299.869358) (xy 419.886085 -299.87529) (xy 419.933356 -299.888982)
			(xy 419.977818 -299.91008) (xy 420.018321 -299.938036) (xy 420.053814 -299.972128) (xy 420.083379 -300.011472)
			(xy 420.10625 -300.055049) (xy 420.121834 -300.10173) (xy 420.129729 -300.150307) (xy 420.130224 -300.174914)
			(xy 420.469072 -300.174914) (xy 420.473032 -300.12586) (xy 420.484809 -300.078076) (xy 420.5041 -300.0328)
			(xy 420.530403 -299.991204) (xy 420.563038 -299.954367) (xy 420.601159 -299.923242) (xy 420.64378 -299.898635)
			(xy 420.689796 -299.881183) (xy 420.738015 -299.871339) (xy 420.78719 -299.869358) (xy 420.836045 -299.87529)
			(xy 420.883316 -299.888982) (xy 420.927778 -299.91008) (xy 420.968281 -299.938036) (xy 421.003774 -299.972128)
			(xy 421.033339 -300.011472) (xy 421.05621 -300.055049) (xy 421.071794 -300.10173) (xy 421.079689 -300.150307)
			(xy 421.080184 -300.174914) (xy 421.419032 -300.174914) (xy 421.422992 -300.12586) (xy 421.434769 -300.078076)
			(xy 421.45406 -300.0328) (xy 421.480363 -299.991204) (xy 421.512998 -299.954367) (xy 421.551119 -299.923242)
			(xy 421.59374 -299.898635) (xy 421.639756 -299.881183) (xy 421.687975 -299.871339) (xy 421.73715 -299.869358)
			(xy 421.786005 -299.87529) (xy 421.833276 -299.888982) (xy 421.877738 -299.91008) (xy 421.918241 -299.938036)
			(xy 421.953734 -299.972128) (xy 421.983299 -300.011472) (xy 422.00617 -300.055049) (xy 422.021754 -300.10173)
			(xy 422.029649 -300.150307) (xy 422.030144 -300.174914) (xy 422.368992 -300.174914) (xy 422.372952 -300.12586)
			(xy 422.384729 -300.078076) (xy 422.40402 -300.0328) (xy 422.430323 -299.991204) (xy 422.462958 -299.954367)
			(xy 422.501079 -299.923242) (xy 422.5437 -299.898635) (xy 422.589716 -299.881183) (xy 422.637935 -299.871339)
			(xy 422.68711 -299.869358) (xy 422.735965 -299.87529) (xy 422.783236 -299.888982) (xy 422.827698 -299.91008)
			(xy 422.868201 -299.938036) (xy 422.903694 -299.972128) (xy 422.933259 -300.011472) (xy 422.95613 -300.055049)
			(xy 422.971714 -300.10173) (xy 422.979609 -300.150307) (xy 422.980104 -300.174914) (xy 423.319206 -300.174914)
			(xy 423.323166 -300.12586) (xy 423.334943 -300.078076) (xy 423.354234 -300.0328) (xy 423.380537 -299.991204)
			(xy 423.413172 -299.954367) (xy 423.451293 -299.923242) (xy 423.493914 -299.898635) (xy 423.53993 -299.881183)
			(xy 423.588149 -299.871339) (xy 423.637324 -299.869358) (xy 423.686179 -299.87529) (xy 423.73345 -299.888982)
			(xy 423.777912 -299.91008) (xy 423.818415 -299.938036) (xy 423.853908 -299.972128) (xy 423.883473 -300.011472)
			(xy 423.906344 -300.055049) (xy 423.921928 -300.10173) (xy 423.929823 -300.150307) (xy 423.930318 -300.174914)
			(xy 424.269166 -300.174914) (xy 424.273126 -300.12586) (xy 424.284903 -300.078076) (xy 424.304194 -300.0328)
			(xy 424.330497 -299.991204) (xy 424.363132 -299.954367) (xy 424.401253 -299.923242) (xy 424.443874 -299.898635)
			(xy 424.48989 -299.881183) (xy 424.538109 -299.871339) (xy 424.587284 -299.869358) (xy 424.636139 -299.87529)
			(xy 424.68341 -299.888982) (xy 424.727872 -299.91008) (xy 424.768375 -299.938036) (xy 424.803868 -299.972128)
			(xy 424.833433 -300.011472) (xy 424.856304 -300.055049) (xy 424.871888 -300.10173) (xy 424.879783 -300.150307)
			(xy 424.880278 -300.174914) (xy 425.219126 -300.174914) (xy 425.223086 -300.12586) (xy 425.234863 -300.078076)
			(xy 425.254154 -300.0328) (xy 425.280457 -299.991204) (xy 425.313092 -299.954367) (xy 425.351213 -299.923242)
			(xy 425.393834 -299.898635) (xy 425.43985 -299.881183) (xy 425.488069 -299.871339) (xy 425.537244 -299.869358)
			(xy 425.586099 -299.87529) (xy 425.63337 -299.888982) (xy 425.677832 -299.91008) (xy 425.718335 -299.938036)
			(xy 425.753828 -299.972128) (xy 425.783393 -300.011472) (xy 425.806264 -300.055049) (xy 425.821848 -300.10173)
			(xy 425.829743 -300.150307) (xy 425.830238 -300.174914) (xy 426.169086 -300.174914) (xy 426.173046 -300.12586)
			(xy 426.184823 -300.078076) (xy 426.204114 -300.0328) (xy 426.230417 -299.991204) (xy 426.263052 -299.954367)
			(xy 426.301173 -299.923242) (xy 426.343794 -299.898635) (xy 426.38981 -299.881183) (xy 426.438029 -299.871339)
			(xy 426.487204 -299.869358) (xy 426.536059 -299.87529) (xy 426.58333 -299.888982) (xy 426.627792 -299.91008)
			(xy 426.668295 -299.938036) (xy 426.703788 -299.972128) (xy 426.733353 -300.011472) (xy 426.756224 -300.055049)
			(xy 426.771808 -300.10173) (xy 426.779703 -300.150307) (xy 426.780198 -300.174914) (xy 427.119046 -300.174914)
			(xy 427.123006 -300.12586) (xy 427.134783 -300.078076) (xy 427.154074 -300.0328) (xy 427.180377 -299.991204)
			(xy 427.213012 -299.954367) (xy 427.251133 -299.923242) (xy 427.293754 -299.898635) (xy 427.33977 -299.881183)
			(xy 427.387989 -299.871339) (xy 427.437164 -299.869358) (xy 427.486019 -299.87529) (xy 427.53329 -299.888982)
			(xy 427.577752 -299.91008) (xy 427.618255 -299.938036) (xy 427.653748 -299.972128) (xy 427.683313 -300.011472)
			(xy 427.706184 -300.055049) (xy 427.721768 -300.10173) (xy 427.729663 -300.150307) (xy 427.730158 -300.174914)
			(xy 428.069006 -300.174914) (xy 428.072966 -300.12586) (xy 428.084743 -300.078076) (xy 428.104034 -300.0328)
			(xy 428.130337 -299.991204) (xy 428.162972 -299.954367) (xy 428.201093 -299.923242) (xy 428.243714 -299.898635)
			(xy 428.28973 -299.881183) (xy 428.337949 -299.871339) (xy 428.387124 -299.869358) (xy 428.435979 -299.87529)
			(xy 428.48325 -299.888982) (xy 428.527712 -299.91008) (xy 428.568215 -299.938036) (xy 428.603708 -299.972128)
			(xy 428.633273 -300.011472) (xy 428.656144 -300.055049) (xy 428.671728 -300.10173) (xy 428.679623 -300.150307)
			(xy 428.680118 -300.174914) (xy 429.01922 -300.174914) (xy 429.02318 -300.12586) (xy 429.034957 -300.078076)
			(xy 429.054248 -300.0328) (xy 429.080551 -299.991204) (xy 429.113186 -299.954367) (xy 429.151307 -299.923242)
			(xy 429.193928 -299.898635) (xy 429.239944 -299.881183) (xy 429.288163 -299.871339) (xy 429.337338 -299.869358)
			(xy 429.386193 -299.87529) (xy 429.433464 -299.888982) (xy 429.477926 -299.91008) (xy 429.518429 -299.938036)
			(xy 429.553922 -299.972128) (xy 429.583487 -300.011472) (xy 429.606358 -300.055049) (xy 429.621942 -300.10173)
			(xy 429.629837 -300.150307) (xy 429.630332 -300.174914) (xy 429.96918 -300.174914) (xy 429.97314 -300.12586)
			(xy 429.984917 -300.078076) (xy 430.004208 -300.0328) (xy 430.030511 -299.991204) (xy 430.063146 -299.954367)
			(xy 430.101267 -299.923242) (xy 430.143888 -299.898635) (xy 430.189904 -299.881183) (xy 430.238123 -299.871339)
			(xy 430.287298 -299.869358) (xy 430.336153 -299.87529) (xy 430.383424 -299.888982) (xy 430.427886 -299.91008)
			(xy 430.468389 -299.938036) (xy 430.503882 -299.972128) (xy 430.533447 -300.011472) (xy 430.556318 -300.055049)
			(xy 430.571902 -300.10173) (xy 430.579797 -300.150307) (xy 430.580292 -300.174914) (xy 430.91914 -300.174914)
			(xy 430.9231 -300.12586) (xy 430.934877 -300.078076) (xy 430.954168 -300.0328) (xy 430.980471 -299.991204)
			(xy 431.013106 -299.954367) (xy 431.051227 -299.923242) (xy 431.093848 -299.898635) (xy 431.139864 -299.881183)
			(xy 431.188083 -299.871339) (xy 431.237258 -299.869358) (xy 431.286113 -299.87529) (xy 431.333384 -299.888982)
			(xy 431.377846 -299.91008) (xy 431.418349 -299.938036) (xy 431.453842 -299.972128) (xy 431.483407 -300.011472)
			(xy 431.506278 -300.055049) (xy 431.521862 -300.10173) (xy 431.529757 -300.150307) (xy 431.530252 -300.174914)
			(xy 431.529757 -300.199521) (xy 431.521862 -300.248098) (xy 431.506278 -300.294779) (xy 431.483407 -300.338356)
			(xy 431.453842 -300.3777) (xy 431.418349 -300.411792) (xy 431.377846 -300.439748) (xy 431.333384 -300.460846)
			(xy 431.286113 -300.474538) (xy 431.237258 -300.48047) (xy 431.188083 -300.478489) (xy 431.139864 -300.468645)
			(xy 431.093848 -300.451193) (xy 431.051227 -300.426586) (xy 431.013106 -300.395461) (xy 430.980471 -300.358624)
			(xy 430.954168 -300.317028) (xy 430.934877 -300.271752) (xy 430.9231 -300.223968) (xy 430.91914 -300.174914)
			(xy 430.580292 -300.174914) (xy 430.579797 -300.199521) (xy 430.571902 -300.248098) (xy 430.556318 -300.294779)
			(xy 430.533447 -300.338356) (xy 430.503882 -300.3777) (xy 430.468389 -300.411792) (xy 430.427886 -300.439748)
			(xy 430.383424 -300.460846) (xy 430.336153 -300.474538) (xy 430.287298 -300.48047) (xy 430.238123 -300.478489)
			(xy 430.189904 -300.468645) (xy 430.143888 -300.451193) (xy 430.101267 -300.426586) (xy 430.063146 -300.395461)
			(xy 430.030511 -300.358624) (xy 430.004208 -300.317028) (xy 429.984917 -300.271752) (xy 429.97314 -300.223968)
			(xy 429.96918 -300.174914) (xy 429.630332 -300.174914) (xy 429.629837 -300.199521) (xy 429.621942 -300.248098)
			(xy 429.606358 -300.294779) (xy 429.583487 -300.338356) (xy 429.553922 -300.3777) (xy 429.518429 -300.411792)
			(xy 429.477926 -300.439748) (xy 429.433464 -300.460846) (xy 429.386193 -300.474538) (xy 429.337338 -300.48047)
			(xy 429.288163 -300.478489) (xy 429.239944 -300.468645) (xy 429.193928 -300.451193) (xy 429.151307 -300.426586)
			(xy 429.113186 -300.395461) (xy 429.080551 -300.358624) (xy 429.054248 -300.317028) (xy 429.034957 -300.271752)
			(xy 429.02318 -300.223968) (xy 429.01922 -300.174914) (xy 428.680118 -300.174914) (xy 428.679623 -300.199521)
			(xy 428.671728 -300.248098) (xy 428.656144 -300.294779) (xy 428.633273 -300.338356) (xy 428.603708 -300.3777)
			(xy 428.568215 -300.411792) (xy 428.527712 -300.439748) (xy 428.48325 -300.460846) (xy 428.435979 -300.474538)
			(xy 428.387124 -300.48047) (xy 428.337949 -300.478489) (xy 428.28973 -300.468645) (xy 428.243714 -300.451193)
			(xy 428.201093 -300.426586) (xy 428.162972 -300.395461) (xy 428.130337 -300.358624) (xy 428.104034 -300.317028)
			(xy 428.084743 -300.271752) (xy 428.072966 -300.223968) (xy 428.069006 -300.174914) (xy 427.730158 -300.174914)
			(xy 427.729663 -300.199521) (xy 427.721768 -300.248098) (xy 427.706184 -300.294779) (xy 427.683313 -300.338356)
			(xy 427.653748 -300.3777) (xy 427.618255 -300.411792) (xy 427.577752 -300.439748) (xy 427.53329 -300.460846)
			(xy 427.486019 -300.474538) (xy 427.437164 -300.48047) (xy 427.387989 -300.478489) (xy 427.33977 -300.468645)
			(xy 427.293754 -300.451193) (xy 427.251133 -300.426586) (xy 427.213012 -300.395461) (xy 427.180377 -300.358624)
			(xy 427.154074 -300.317028) (xy 427.134783 -300.271752) (xy 427.123006 -300.223968) (xy 427.119046 -300.174914)
			(xy 426.780198 -300.174914) (xy 426.779703 -300.199521) (xy 426.771808 -300.248098) (xy 426.756224 -300.294779)
			(xy 426.733353 -300.338356) (xy 426.703788 -300.3777) (xy 426.668295 -300.411792) (xy 426.627792 -300.439748)
			(xy 426.58333 -300.460846) (xy 426.536059 -300.474538) (xy 426.487204 -300.48047) (xy 426.438029 -300.478489)
			(xy 426.38981 -300.468645) (xy 426.343794 -300.451193) (xy 426.301173 -300.426586) (xy 426.263052 -300.395461)
			(xy 426.230417 -300.358624) (xy 426.204114 -300.317028) (xy 426.184823 -300.271752) (xy 426.173046 -300.223968)
			(xy 426.169086 -300.174914) (xy 425.830238 -300.174914) (xy 425.829743 -300.199521) (xy 425.821848 -300.248098)
			(xy 425.806264 -300.294779) (xy 425.783393 -300.338356) (xy 425.753828 -300.3777) (xy 425.718335 -300.411792)
			(xy 425.677832 -300.439748) (xy 425.63337 -300.460846) (xy 425.586099 -300.474538) (xy 425.537244 -300.48047)
			(xy 425.488069 -300.478489) (xy 425.43985 -300.468645) (xy 425.393834 -300.451193) (xy 425.351213 -300.426586)
			(xy 425.313092 -300.395461) (xy 425.280457 -300.358624) (xy 425.254154 -300.317028) (xy 425.234863 -300.271752)
			(xy 425.223086 -300.223968) (xy 425.219126 -300.174914) (xy 424.880278 -300.174914) (xy 424.879783 -300.199521)
			(xy 424.871888 -300.248098) (xy 424.856304 -300.294779) (xy 424.833433 -300.338356) (xy 424.803868 -300.3777)
			(xy 424.768375 -300.411792) (xy 424.727872 -300.439748) (xy 424.68341 -300.460846) (xy 424.636139 -300.474538)
			(xy 424.587284 -300.48047) (xy 424.538109 -300.478489) (xy 424.48989 -300.468645) (xy 424.443874 -300.451193)
			(xy 424.401253 -300.426586) (xy 424.363132 -300.395461) (xy 424.330497 -300.358624) (xy 424.304194 -300.317028)
			(xy 424.284903 -300.271752) (xy 424.273126 -300.223968) (xy 424.269166 -300.174914) (xy 423.930318 -300.174914)
			(xy 423.929823 -300.199521) (xy 423.921928 -300.248098) (xy 423.906344 -300.294779) (xy 423.883473 -300.338356)
			(xy 423.853908 -300.3777) (xy 423.818415 -300.411792) (xy 423.777912 -300.439748) (xy 423.73345 -300.460846)
			(xy 423.686179 -300.474538) (xy 423.637324 -300.48047) (xy 423.588149 -300.478489) (xy 423.53993 -300.468645)
			(xy 423.493914 -300.451193) (xy 423.451293 -300.426586) (xy 423.413172 -300.395461) (xy 423.380537 -300.358624)
			(xy 423.354234 -300.317028) (xy 423.334943 -300.271752) (xy 423.323166 -300.223968) (xy 423.319206 -300.174914)
			(xy 422.980104 -300.174914) (xy 422.979609 -300.199521) (xy 422.971714 -300.248098) (xy 422.95613 -300.294779)
			(xy 422.933259 -300.338356) (xy 422.903694 -300.3777) (xy 422.868201 -300.411792) (xy 422.827698 -300.439748)
			(xy 422.783236 -300.460846) (xy 422.735965 -300.474538) (xy 422.68711 -300.48047) (xy 422.637935 -300.478489)
			(xy 422.589716 -300.468645) (xy 422.5437 -300.451193) (xy 422.501079 -300.426586) (xy 422.462958 -300.395461)
			(xy 422.430323 -300.358624) (xy 422.40402 -300.317028) (xy 422.384729 -300.271752) (xy 422.372952 -300.223968)
			(xy 422.368992 -300.174914) (xy 422.030144 -300.174914) (xy 422.029649 -300.199521) (xy 422.021754 -300.248098)
			(xy 422.00617 -300.294779) (xy 421.983299 -300.338356) (xy 421.953734 -300.3777) (xy 421.918241 -300.411792)
			(xy 421.877738 -300.439748) (xy 421.833276 -300.460846) (xy 421.786005 -300.474538) (xy 421.73715 -300.48047)
			(xy 421.687975 -300.478489) (xy 421.639756 -300.468645) (xy 421.59374 -300.451193) (xy 421.551119 -300.426586)
			(xy 421.512998 -300.395461) (xy 421.480363 -300.358624) (xy 421.45406 -300.317028) (xy 421.434769 -300.271752)
			(xy 421.422992 -300.223968) (xy 421.419032 -300.174914) (xy 421.080184 -300.174914) (xy 421.079689 -300.199521)
			(xy 421.071794 -300.248098) (xy 421.05621 -300.294779) (xy 421.033339 -300.338356) (xy 421.003774 -300.3777)
			(xy 420.968281 -300.411792) (xy 420.927778 -300.439748) (xy 420.883316 -300.460846) (xy 420.836045 -300.474538)
			(xy 420.78719 -300.48047) (xy 420.738015 -300.478489) (xy 420.689796 -300.468645) (xy 420.64378 -300.451193)
			(xy 420.601159 -300.426586) (xy 420.563038 -300.395461) (xy 420.530403 -300.358624) (xy 420.5041 -300.317028)
			(xy 420.484809 -300.271752) (xy 420.473032 -300.223968) (xy 420.469072 -300.174914) (xy 420.130224 -300.174914)
			(xy 420.129729 -300.199521) (xy 420.121834 -300.248098) (xy 420.10625 -300.294779) (xy 420.083379 -300.338356)
			(xy 420.053814 -300.3777) (xy 420.018321 -300.411792) (xy 419.977818 -300.439748) (xy 419.933356 -300.460846)
			(xy 419.886085 -300.474538) (xy 419.83723 -300.48047) (xy 419.788055 -300.478489) (xy 419.739836 -300.468645)
			(xy 419.69382 -300.451193) (xy 419.651199 -300.426586) (xy 419.613078 -300.395461) (xy 419.580443 -300.358624)
			(xy 419.55414 -300.317028) (xy 419.534849 -300.271752) (xy 419.523072 -300.223968) (xy 419.519112 -300.174914)
			(xy 419.180264 -300.174914) (xy 419.179769 -300.199521) (xy 419.171874 -300.248098) (xy 419.15629 -300.294779)
			(xy 419.133419 -300.338356) (xy 419.103854 -300.3777) (xy 419.068361 -300.411792) (xy 419.027858 -300.439748)
			(xy 418.983396 -300.460846) (xy 418.936125 -300.474538) (xy 418.88727 -300.48047) (xy 418.838095 -300.478489)
			(xy 418.789876 -300.468645) (xy 418.74386 -300.451193) (xy 418.701239 -300.426586) (xy 418.663118 -300.395461)
			(xy 418.630483 -300.358624) (xy 418.60418 -300.317028) (xy 418.584889 -300.271752) (xy 418.573112 -300.223968)
			(xy 418.569152 -300.174914) (xy 418.230304 -300.174914) (xy 418.229809 -300.199521) (xy 418.221914 -300.248098)
			(xy 418.20633 -300.294779) (xy 418.183459 -300.338356) (xy 418.153894 -300.3777) (xy 418.118401 -300.411792)
			(xy 418.077898 -300.439748) (xy 418.033436 -300.460846) (xy 417.986165 -300.474538) (xy 417.93731 -300.48047)
			(xy 417.888135 -300.478489) (xy 417.839916 -300.468645) (xy 417.7939 -300.451193) (xy 417.751279 -300.426586)
			(xy 417.713158 -300.395461) (xy 417.680523 -300.358624) (xy 417.65422 -300.317028) (xy 417.634929 -300.271752)
			(xy 417.623152 -300.223968) (xy 417.619192 -300.174914) (xy 417.28009 -300.174914) (xy 417.279595 -300.199521)
			(xy 417.2717 -300.248098) (xy 417.256116 -300.294779) (xy 417.233245 -300.338356) (xy 417.20368 -300.3777)
			(xy 417.168187 -300.411792) (xy 417.127684 -300.439748) (xy 417.083222 -300.460846) (xy 417.035951 -300.474538)
			(xy 416.987096 -300.48047) (xy 416.937921 -300.478489) (xy 416.889702 -300.468645) (xy 416.843686 -300.451193)
			(xy 416.801065 -300.426586) (xy 416.762944 -300.395461) (xy 416.730309 -300.358624) (xy 416.704006 -300.317028)
			(xy 416.684715 -300.271752) (xy 416.672938 -300.223968) (xy 416.668978 -300.174914) (xy 416.33013 -300.174914)
			(xy 416.329635 -300.199521) (xy 416.32174 -300.248098) (xy 416.306156 -300.294779) (xy 416.283285 -300.338356)
			(xy 416.25372 -300.3777) (xy 416.218227 -300.411792) (xy 416.177724 -300.439748) (xy 416.133262 -300.460846)
			(xy 416.085991 -300.474538) (xy 416.037136 -300.48047) (xy 415.987961 -300.478489) (xy 415.939742 -300.468645)
			(xy 415.893726 -300.451193) (xy 415.851105 -300.426586) (xy 415.812984 -300.395461) (xy 415.780349 -300.358624)
			(xy 415.754046 -300.317028) (xy 415.734755 -300.271752) (xy 415.722978 -300.223968) (xy 415.719018 -300.174914)
			(xy 415.38017 -300.174914) (xy 415.379675 -300.199521) (xy 415.37178 -300.248098) (xy 415.356196 -300.294779)
			(xy 415.333325 -300.338356) (xy 415.30376 -300.3777) (xy 415.268267 -300.411792) (xy 415.227764 -300.439748)
			(xy 415.183302 -300.460846) (xy 415.136031 -300.474538) (xy 415.087176 -300.48047) (xy 415.038001 -300.478489)
			(xy 414.989782 -300.468645) (xy 414.943766 -300.451193) (xy 414.901145 -300.426586) (xy 414.863024 -300.395461)
			(xy 414.830389 -300.358624) (xy 414.804086 -300.317028) (xy 414.784795 -300.271752) (xy 414.773018 -300.223968)
			(xy 414.769058 -300.174914) (xy 414.43021 -300.174914) (xy 414.429715 -300.199521) (xy 414.42182 -300.248098)
			(xy 414.406236 -300.294779) (xy 414.383365 -300.338356) (xy 414.3538 -300.3777) (xy 414.318307 -300.411792)
			(xy 414.277804 -300.439748) (xy 414.233342 -300.460846) (xy 414.186071 -300.474538) (xy 414.137216 -300.48047)
			(xy 414.088041 -300.478489) (xy 414.039822 -300.468645) (xy 413.993806 -300.451193) (xy 413.951185 -300.426586)
			(xy 413.913064 -300.395461) (xy 413.880429 -300.358624) (xy 413.854126 -300.317028) (xy 413.834835 -300.271752)
			(xy 413.823058 -300.223968) (xy 413.819098 -300.174914) (xy 413.48025 -300.174914) (xy 413.479755 -300.199521)
			(xy 413.47186 -300.248098) (xy 413.456276 -300.294779) (xy 413.433405 -300.338356) (xy 413.40384 -300.3777)
			(xy 413.368347 -300.411792) (xy 413.327844 -300.439748) (xy 413.283382 -300.460846) (xy 413.236111 -300.474538)
			(xy 413.187256 -300.48047) (xy 413.138081 -300.478489) (xy 413.089862 -300.468645) (xy 413.043846 -300.451193)
			(xy 413.001225 -300.426586) (xy 412.963104 -300.395461) (xy 412.930469 -300.358624) (xy 412.904166 -300.317028)
			(xy 412.884875 -300.271752) (xy 412.873098 -300.223968) (xy 412.869138 -300.174914) (xy 412.53029 -300.174914)
			(xy 412.529795 -300.199521) (xy 412.5219 -300.248098) (xy 412.506316 -300.294779) (xy 412.483445 -300.338356)
			(xy 412.45388 -300.3777) (xy 412.418387 -300.411792) (xy 412.377884 -300.439748) (xy 412.333422 -300.460846)
			(xy 412.286151 -300.474538) (xy 412.237296 -300.48047) (xy 412.188121 -300.478489) (xy 412.139902 -300.468645)
			(xy 412.093886 -300.451193) (xy 412.051265 -300.426586) (xy 412.013144 -300.395461) (xy 411.980509 -300.358624)
			(xy 411.954206 -300.317028) (xy 411.934915 -300.271752) (xy 411.923138 -300.223968) (xy 411.919178 -300.174914)
			(xy 411.58033 -300.174914) (xy 411.579835 -300.199521) (xy 411.57194 -300.248098) (xy 411.556356 -300.294779)
			(xy 411.533485 -300.338356) (xy 411.50392 -300.3777) (xy 411.468427 -300.411792) (xy 411.427924 -300.439748)
			(xy 411.383462 -300.460846) (xy 411.336191 -300.474538) (xy 411.287336 -300.48047) (xy 411.238161 -300.478489)
			(xy 411.189942 -300.468645) (xy 411.143926 -300.451193) (xy 411.101305 -300.426586) (xy 411.063184 -300.395461)
			(xy 411.030549 -300.358624) (xy 411.004246 -300.317028) (xy 410.984955 -300.271752) (xy 410.973178 -300.223968)
			(xy 410.969218 -300.174914) (xy 410.630116 -300.174914) (xy 410.629621 -300.199521) (xy 410.621726 -300.248098)
			(xy 410.606142 -300.294779) (xy 410.583271 -300.338356) (xy 410.553706 -300.3777) (xy 410.518213 -300.411792)
			(xy 410.47771 -300.439748) (xy 410.433248 -300.460846) (xy 410.385977 -300.474538) (xy 410.337122 -300.48047)
			(xy 410.287947 -300.478489) (xy 410.239728 -300.468645) (xy 410.193712 -300.451193) (xy 410.151091 -300.426586)
			(xy 410.11297 -300.395461) (xy 410.080335 -300.358624) (xy 410.054032 -300.317028) (xy 410.034741 -300.271752)
			(xy 410.022964 -300.223968) (xy 410.019004 -300.174914) (xy 409.680156 -300.174914) (xy 409.679661 -300.199521)
			(xy 409.671766 -300.248098) (xy 409.656182 -300.294779) (xy 409.633311 -300.338356) (xy 409.603746 -300.3777)
			(xy 409.568253 -300.411792) (xy 409.52775 -300.439748) (xy 409.483288 -300.460846) (xy 409.436017 -300.474538)
			(xy 409.387162 -300.48047) (xy 409.337987 -300.478489) (xy 409.289768 -300.468645) (xy 409.243752 -300.451193)
			(xy 409.201131 -300.426586) (xy 409.16301 -300.395461) (xy 409.130375 -300.358624) (xy 409.104072 -300.317028)
			(xy 409.084781 -300.271752) (xy 409.073004 -300.223968) (xy 409.069044 -300.174914) (xy 408.730196 -300.174914)
			(xy 408.729701 -300.199521) (xy 408.721806 -300.248098) (xy 408.706222 -300.294779) (xy 408.683351 -300.338356)
			(xy 408.653786 -300.3777) (xy 408.618293 -300.411792) (xy 408.57779 -300.439748) (xy 408.533328 -300.460846)
			(xy 408.486057 -300.474538) (xy 408.437202 -300.48047) (xy 408.388027 -300.478489) (xy 408.339808 -300.468645)
			(xy 408.293792 -300.451193) (xy 408.251171 -300.426586) (xy 408.21305 -300.395461) (xy 408.180415 -300.358624)
			(xy 408.154112 -300.317028) (xy 408.134821 -300.271752) (xy 408.123044 -300.223968) (xy 408.119084 -300.174914)
			(xy 406.830276 -300.174914) (xy 406.829781 -300.199521) (xy 406.821886 -300.248098) (xy 406.806302 -300.294779)
			(xy 406.783431 -300.338356) (xy 406.753866 -300.3777) (xy 406.718373 -300.411792) (xy 406.67787 -300.439748)
			(xy 406.633408 -300.460846) (xy 406.586137 -300.474538) (xy 406.537282 -300.48047) (xy 406.488107 -300.478489)
			(xy 406.439888 -300.468645) (xy 406.393872 -300.451193) (xy 406.351251 -300.426586) (xy 406.31313 -300.395461)
			(xy 406.280495 -300.358624) (xy 406.254192 -300.317028) (xy 406.234901 -300.271752) (xy 406.223124 -300.223968)
			(xy 406.219164 -300.174914) (xy 405.880316 -300.174914) (xy 405.879821 -300.199521) (xy 405.871926 -300.248098)
			(xy 405.856342 -300.294779) (xy 405.833471 -300.338356) (xy 405.803906 -300.3777) (xy 405.768413 -300.411792)
			(xy 405.72791 -300.439748) (xy 405.683448 -300.460846) (xy 405.636177 -300.474538) (xy 405.587322 -300.48047)
			(xy 405.538147 -300.478489) (xy 405.489928 -300.468645) (xy 405.443912 -300.451193) (xy 405.401291 -300.426586)
			(xy 405.36317 -300.395461) (xy 405.330535 -300.358624) (xy 405.304232 -300.317028) (xy 405.284941 -300.271752)
			(xy 405.273164 -300.223968) (xy 405.269204 -300.174914) (xy 404.930102 -300.174914) (xy 404.929607 -300.199521)
			(xy 404.921712 -300.248098) (xy 404.906128 -300.294779) (xy 404.883257 -300.338356) (xy 404.853692 -300.3777)
			(xy 404.818199 -300.411792) (xy 404.777696 -300.439748) (xy 404.733234 -300.460846) (xy 404.685963 -300.474538)
			(xy 404.637108 -300.48047) (xy 404.587933 -300.478489) (xy 404.539714 -300.468645) (xy 404.493698 -300.451193)
			(xy 404.451077 -300.426586) (xy 404.412956 -300.395461) (xy 404.380321 -300.358624) (xy 404.354018 -300.317028)
			(xy 404.334727 -300.271752) (xy 404.32295 -300.223968) (xy 404.31899 -300.174914) (xy 403.980142 -300.174914)
			(xy 403.979647 -300.199521) (xy 403.971752 -300.248098) (xy 403.956168 -300.294779) (xy 403.933297 -300.338356)
			(xy 403.903732 -300.3777) (xy 403.868239 -300.411792) (xy 403.827736 -300.439748) (xy 403.783274 -300.460846)
			(xy 403.736003 -300.474538) (xy 403.687148 -300.48047) (xy 403.637973 -300.478489) (xy 403.589754 -300.468645)
			(xy 403.543738 -300.451193) (xy 403.501117 -300.426586) (xy 403.462996 -300.395461) (xy 403.430361 -300.358624)
			(xy 403.404058 -300.317028) (xy 403.384767 -300.271752) (xy 403.37299 -300.223968) (xy 403.36903 -300.174914)
			(xy 403.030182 -300.174914) (xy 403.029687 -300.199521) (xy 403.021792 -300.248098) (xy 403.006208 -300.294779)
			(xy 402.983337 -300.338356) (xy 402.953772 -300.3777) (xy 402.918279 -300.411792) (xy 402.877776 -300.439748)
			(xy 402.833314 -300.460846) (xy 402.786043 -300.474538) (xy 402.737188 -300.48047) (xy 402.688013 -300.478489)
			(xy 402.639794 -300.468645) (xy 402.593778 -300.451193) (xy 402.551157 -300.426586) (xy 402.513036 -300.395461)
			(xy 402.480401 -300.358624) (xy 402.454098 -300.317028) (xy 402.434807 -300.271752) (xy 402.42303 -300.223968)
			(xy 402.41907 -300.174914) (xy 402.080222 -300.174914) (xy 402.079727 -300.199521) (xy 402.071832 -300.248098)
			(xy 402.056248 -300.294779) (xy 402.033377 -300.338356) (xy 402.003812 -300.3777) (xy 401.968319 -300.411792)
			(xy 401.927816 -300.439748) (xy 401.883354 -300.460846) (xy 401.836083 -300.474538) (xy 401.787228 -300.48047)
			(xy 401.738053 -300.478489) (xy 401.689834 -300.468645) (xy 401.643818 -300.451193) (xy 401.601197 -300.426586)
			(xy 401.563076 -300.395461) (xy 401.530441 -300.358624) (xy 401.504138 -300.317028) (xy 401.484847 -300.271752)
			(xy 401.47307 -300.223968) (xy 401.46911 -300.174914) (xy 401.130262 -300.174914) (xy 401.129767 -300.199521)
			(xy 401.121872 -300.248098) (xy 401.106288 -300.294779) (xy 401.083417 -300.338356) (xy 401.053852 -300.3777)
			(xy 401.018359 -300.411792) (xy 400.977856 -300.439748) (xy 400.933394 -300.460846) (xy 400.886123 -300.474538)
			(xy 400.837268 -300.48047) (xy 400.788093 -300.478489) (xy 400.739874 -300.468645) (xy 400.693858 -300.451193)
			(xy 400.651237 -300.426586) (xy 400.613116 -300.395461) (xy 400.580481 -300.358624) (xy 400.554178 -300.317028)
			(xy 400.534887 -300.271752) (xy 400.52311 -300.223968) (xy 400.51915 -300.174914) (xy 400.180302 -300.174914)
			(xy 400.179807 -300.199521) (xy 400.171912 -300.248098) (xy 400.156328 -300.294779) (xy 400.133457 -300.338356)
			(xy 400.103892 -300.3777) (xy 400.068399 -300.411792) (xy 400.027896 -300.439748) (xy 399.983434 -300.460846)
			(xy 399.936163 -300.474538) (xy 399.887308 -300.48047) (xy 399.838133 -300.478489) (xy 399.789914 -300.468645)
			(xy 399.743898 -300.451193) (xy 399.701277 -300.426586) (xy 399.663156 -300.395461) (xy 399.630521 -300.358624)
			(xy 399.604218 -300.317028) (xy 399.584927 -300.271752) (xy 399.57315 -300.223968) (xy 399.56919 -300.174914)
			(xy 399.230342 -300.174914) (xy 399.229875 -300.198842) (xy 399.222407 -300.246112) (xy 399.207656 -300.291638)
			(xy 399.185983 -300.334305) (xy 399.157919 -300.373069) (xy 399.124151 -300.40698) (xy 399.085506 -300.435207)
			(xy 399.042931 -300.45706) (xy 398.997468 -300.472004) (xy 398.95023 -300.479671) (xy 398.926304 -300.480222)
			(xy 398.92351 -300.480222) (xy 398.902386 -300.479743) (xy 398.860571 -300.473668) (xy 398.819999 -300.461868)
			(xy 398.800574 -300.453552) (xy 398.790668 -300.449234) (xy 398.75968 -300.449234) (xy 398.752561 -300.449501)
			(xy 398.738891 -300.453488) (xy 398.732756 -300.457108) (xy 398.662906 -300.500796) (xy 398.657826 -300.507146)
			(xy 398.657572 -300.5074) (xy 398.651222 -300.514258) (xy 398.644364 -300.531784) (xy 398.644364 -300.827694)
			(xy 398.643856 -300.846744) (xy 398.643348 -300.856904) (xy 398.64665 -300.866556) (xy 398.650446 -300.875813)
			(xy 398.663817 -300.890666) (xy 398.681852 -300.899278) (xy 398.70181 -300.900339) (xy 398.71142 -300.897544)
			(xy 398.726914 -300.89221) (xy 398.733518 -300.886622) (xy 398.754032 -300.870903) (xy 398.799234 -300.845858)
			(xy 398.847999 -300.828755) (xy 398.898942 -300.820079) (xy 398.92478 -300.819566) (xy 398.933162 -300.819566)
			(xy 398.957831 -300.8207) (xy 399.006339 -300.829943) (xy 399.052728 -300.846869) (xy 399.09579 -300.871037)
			(xy 399.134403 -300.901817) (xy 399.167562 -300.938409) (xy 399.194403 -300.979857) (xy 399.214227 -301.025084)
			(xy 399.226517 -301.072911) (xy 399.230954 -301.122092) (xy 399.230754 -301.124874) (xy 399.56919 -301.124874)
			(xy 399.57315 -301.07582) (xy 399.584927 -301.028036) (xy 399.604218 -300.98276) (xy 399.630521 -300.941164)
			(xy 399.663156 -300.904327) (xy 399.701277 -300.873202) (xy 399.743898 -300.848595) (xy 399.789914 -300.831143)
			(xy 399.838133 -300.821299) (xy 399.887308 -300.819318) (xy 399.936163 -300.82525) (xy 399.983434 -300.838942)
			(xy 400.027896 -300.86004) (xy 400.068399 -300.887996) (xy 400.103892 -300.922088) (xy 400.133457 -300.961432)
			(xy 400.156328 -301.005009) (xy 400.171912 -301.05169) (xy 400.179807 -301.100267) (xy 400.180302 -301.124874)
			(xy 400.51915 -301.124874) (xy 400.52311 -301.07582) (xy 400.534887 -301.028036) (xy 400.554178 -300.98276)
			(xy 400.580481 -300.941164) (xy 400.613116 -300.904327) (xy 400.651237 -300.873202) (xy 400.693858 -300.848595)
			(xy 400.739874 -300.831143) (xy 400.788093 -300.821299) (xy 400.837268 -300.819318) (xy 400.886123 -300.82525)
			(xy 400.933394 -300.838942) (xy 400.977856 -300.86004) (xy 401.018359 -300.887996) (xy 401.053852 -300.922088)
			(xy 401.083417 -300.961432) (xy 401.106288 -301.005009) (xy 401.121872 -301.05169) (xy 401.129767 -301.100267)
			(xy 401.130262 -301.124874) (xy 401.46911 -301.124874) (xy 401.47307 -301.07582) (xy 401.484847 -301.028036)
			(xy 401.504138 -300.98276) (xy 401.530441 -300.941164) (xy 401.563076 -300.904327) (xy 401.601197 -300.873202)
			(xy 401.643818 -300.848595) (xy 401.689834 -300.831143) (xy 401.738053 -300.821299) (xy 401.787228 -300.819318)
			(xy 401.836083 -300.82525) (xy 401.883354 -300.838942) (xy 401.927816 -300.86004) (xy 401.968319 -300.887996)
			(xy 402.003812 -300.922088) (xy 402.033377 -300.961432) (xy 402.056248 -301.005009) (xy 402.071832 -301.05169)
			(xy 402.079727 -301.100267) (xy 402.080222 -301.124874) (xy 402.41907 -301.124874) (xy 402.42303 -301.07582)
			(xy 402.434807 -301.028036) (xy 402.454098 -300.98276) (xy 402.480401 -300.941164) (xy 402.513036 -300.904327)
			(xy 402.551157 -300.873202) (xy 402.593778 -300.848595) (xy 402.639794 -300.831143) (xy 402.688013 -300.821299)
			(xy 402.737188 -300.819318) (xy 402.786043 -300.82525) (xy 402.833314 -300.838942) (xy 402.877776 -300.86004)
			(xy 402.918279 -300.887996) (xy 402.953772 -300.922088) (xy 402.983337 -300.961432) (xy 403.006208 -301.005009)
			(xy 403.021792 -301.05169) (xy 403.029687 -301.100267) (xy 403.030182 -301.124874) (xy 403.36903 -301.124874)
			(xy 403.37299 -301.07582) (xy 403.384767 -301.028036) (xy 403.404058 -300.98276) (xy 403.430361 -300.941164)
			(xy 403.462996 -300.904327) (xy 403.501117 -300.873202) (xy 403.543738 -300.848595) (xy 403.589754 -300.831143)
			(xy 403.637973 -300.821299) (xy 403.687148 -300.819318) (xy 403.736003 -300.82525) (xy 403.783274 -300.838942)
			(xy 403.827736 -300.86004) (xy 403.868239 -300.887996) (xy 403.903732 -300.922088) (xy 403.933297 -300.961432)
			(xy 403.956168 -301.005009) (xy 403.971752 -301.05169) (xy 403.979647 -301.100267) (xy 403.980142 -301.124874)
			(xy 404.31899 -301.124874) (xy 404.32295 -301.07582) (xy 404.334727 -301.028036) (xy 404.354018 -300.98276)
			(xy 404.380321 -300.941164) (xy 404.412956 -300.904327) (xy 404.451077 -300.873202) (xy 404.493698 -300.848595)
			(xy 404.539714 -300.831143) (xy 404.587933 -300.821299) (xy 404.637108 -300.819318) (xy 404.685963 -300.82525)
			(xy 404.733234 -300.838942) (xy 404.777696 -300.86004) (xy 404.818199 -300.887996) (xy 404.853692 -300.922088)
			(xy 404.883257 -300.961432) (xy 404.906128 -301.005009) (xy 404.921712 -301.05169) (xy 404.929607 -301.100267)
			(xy 404.930102 -301.124874) (xy 405.269204 -301.124874) (xy 405.273164 -301.07582) (xy 405.284941 -301.028036)
			(xy 405.304232 -300.98276) (xy 405.330535 -300.941164) (xy 405.36317 -300.904327) (xy 405.401291 -300.873202)
			(xy 405.443912 -300.848595) (xy 405.489928 -300.831143) (xy 405.538147 -300.821299) (xy 405.587322 -300.819318)
			(xy 405.636177 -300.82525) (xy 405.683448 -300.838942) (xy 405.72791 -300.86004) (xy 405.768413 -300.887996)
			(xy 405.803906 -300.922088) (xy 405.833471 -300.961432) (xy 405.856342 -301.005009) (xy 405.871926 -301.05169)
			(xy 405.879821 -301.100267) (xy 405.880316 -301.124874) (xy 406.219164 -301.124874) (xy 406.223124 -301.07582)
			(xy 406.234901 -301.028036) (xy 406.254192 -300.98276) (xy 406.280495 -300.941164) (xy 406.31313 -300.904327)
			(xy 406.351251 -300.873202) (xy 406.393872 -300.848595) (xy 406.439888 -300.831143) (xy 406.488107 -300.821299)
			(xy 406.537282 -300.819318) (xy 406.586137 -300.82525) (xy 406.633408 -300.838942) (xy 406.67787 -300.86004)
			(xy 406.718373 -300.887996) (xy 406.753866 -300.922088) (xy 406.783431 -300.961432) (xy 406.806302 -301.005009)
			(xy 406.821886 -301.05169) (xy 406.829781 -301.100267) (xy 406.830276 -301.124874) (xy 408.119084 -301.124874)
			(xy 408.123044 -301.07582) (xy 408.134821 -301.028036) (xy 408.154112 -300.98276) (xy 408.180415 -300.941164)
			(xy 408.21305 -300.904327) (xy 408.251171 -300.873202) (xy 408.293792 -300.848595) (xy 408.339808 -300.831143)
			(xy 408.388027 -300.821299) (xy 408.437202 -300.819318) (xy 408.486057 -300.82525) (xy 408.533328 -300.838942)
			(xy 408.57779 -300.86004) (xy 408.618293 -300.887996) (xy 408.653786 -300.922088) (xy 408.683351 -300.961432)
			(xy 408.706222 -301.005009) (xy 408.721806 -301.05169) (xy 408.729701 -301.100267) (xy 408.730196 -301.124874)
			(xy 409.069044 -301.124874) (xy 409.073004 -301.07582) (xy 409.084781 -301.028036) (xy 409.104072 -300.98276)
			(xy 409.130375 -300.941164) (xy 409.16301 -300.904327) (xy 409.201131 -300.873202) (xy 409.243752 -300.848595)
			(xy 409.289768 -300.831143) (xy 409.337987 -300.821299) (xy 409.387162 -300.819318) (xy 409.436017 -300.82525)
			(xy 409.483288 -300.838942) (xy 409.52775 -300.86004) (xy 409.568253 -300.887996) (xy 409.603746 -300.922088)
			(xy 409.633311 -300.961432) (xy 409.656182 -301.005009) (xy 409.671766 -301.05169) (xy 409.679661 -301.100267)
			(xy 409.680156 -301.124874) (xy 410.019004 -301.124874) (xy 410.022964 -301.07582) (xy 410.034741 -301.028036)
			(xy 410.054032 -300.98276) (xy 410.080335 -300.941164) (xy 410.11297 -300.904327) (xy 410.151091 -300.873202)
			(xy 410.193712 -300.848595) (xy 410.239728 -300.831143) (xy 410.287947 -300.821299) (xy 410.337122 -300.819318)
			(xy 410.385977 -300.82525) (xy 410.433248 -300.838942) (xy 410.47771 -300.86004) (xy 410.518213 -300.887996)
			(xy 410.553706 -300.922088) (xy 410.583271 -300.961432) (xy 410.606142 -301.005009) (xy 410.621726 -301.05169)
			(xy 410.629621 -301.100267) (xy 410.630116 -301.124874) (xy 410.969218 -301.124874) (xy 410.973178 -301.07582)
			(xy 410.984955 -301.028036) (xy 411.004246 -300.98276) (xy 411.030549 -300.941164) (xy 411.063184 -300.904327)
			(xy 411.101305 -300.873202) (xy 411.143926 -300.848595) (xy 411.189942 -300.831143) (xy 411.238161 -300.821299)
			(xy 411.287336 -300.819318) (xy 411.336191 -300.82525) (xy 411.383462 -300.838942) (xy 411.427924 -300.86004)
			(xy 411.468427 -300.887996) (xy 411.50392 -300.922088) (xy 411.533485 -300.961432) (xy 411.556356 -301.005009)
			(xy 411.57194 -301.05169) (xy 411.579835 -301.100267) (xy 411.58033 -301.124874) (xy 411.919178 -301.124874)
			(xy 411.923138 -301.07582) (xy 411.934915 -301.028036) (xy 411.954206 -300.98276) (xy 411.980509 -300.941164)
			(xy 412.013144 -300.904327) (xy 412.051265 -300.873202) (xy 412.093886 -300.848595) (xy 412.139902 -300.831143)
			(xy 412.188121 -300.821299) (xy 412.237296 -300.819318) (xy 412.286151 -300.82525) (xy 412.333422 -300.838942)
			(xy 412.377884 -300.86004) (xy 412.418387 -300.887996) (xy 412.45388 -300.922088) (xy 412.483445 -300.961432)
			(xy 412.506316 -301.005009) (xy 412.5219 -301.05169) (xy 412.529795 -301.100267) (xy 412.53029 -301.124874)
			(xy 412.869138 -301.124874) (xy 412.873098 -301.07582) (xy 412.884875 -301.028036) (xy 412.904166 -300.98276)
			(xy 412.930469 -300.941164) (xy 412.963104 -300.904327) (xy 413.001225 -300.873202) (xy 413.043846 -300.848595)
			(xy 413.089862 -300.831143) (xy 413.138081 -300.821299) (xy 413.187256 -300.819318) (xy 413.236111 -300.82525)
			(xy 413.283382 -300.838942) (xy 413.327844 -300.86004) (xy 413.368347 -300.887996) (xy 413.40384 -300.922088)
			(xy 413.433405 -300.961432) (xy 413.456276 -301.005009) (xy 413.47186 -301.05169) (xy 413.479755 -301.100267)
			(xy 413.48025 -301.124874) (xy 413.819098 -301.124874) (xy 413.823058 -301.07582) (xy 413.834835 -301.028036)
			(xy 413.854126 -300.98276) (xy 413.880429 -300.941164) (xy 413.913064 -300.904327) (xy 413.951185 -300.873202)
			(xy 413.993806 -300.848595) (xy 414.039822 -300.831143) (xy 414.088041 -300.821299) (xy 414.137216 -300.819318)
			(xy 414.186071 -300.82525) (xy 414.233342 -300.838942) (xy 414.277804 -300.86004) (xy 414.318307 -300.887996)
			(xy 414.3538 -300.922088) (xy 414.383365 -300.961432) (xy 414.406236 -301.005009) (xy 414.42182 -301.05169)
			(xy 414.429715 -301.100267) (xy 414.43021 -301.124874) (xy 414.769058 -301.124874) (xy 414.773018 -301.07582)
			(xy 414.784795 -301.028036) (xy 414.804086 -300.98276) (xy 414.830389 -300.941164) (xy 414.863024 -300.904327)
			(xy 414.901145 -300.873202) (xy 414.943766 -300.848595) (xy 414.989782 -300.831143) (xy 415.038001 -300.821299)
			(xy 415.087176 -300.819318) (xy 415.136031 -300.82525) (xy 415.183302 -300.838942) (xy 415.227764 -300.86004)
			(xy 415.268267 -300.887996) (xy 415.30376 -300.922088) (xy 415.333325 -300.961432) (xy 415.356196 -301.005009)
			(xy 415.37178 -301.05169) (xy 415.379675 -301.100267) (xy 415.38017 -301.124874) (xy 415.719018 -301.124874)
			(xy 415.722978 -301.07582) (xy 415.734755 -301.028036) (xy 415.754046 -300.98276) (xy 415.780349 -300.941164)
			(xy 415.812984 -300.904327) (xy 415.851105 -300.873202) (xy 415.893726 -300.848595) (xy 415.939742 -300.831143)
			(xy 415.987961 -300.821299) (xy 416.037136 -300.819318) (xy 416.085991 -300.82525) (xy 416.133262 -300.838942)
			(xy 416.177724 -300.86004) (xy 416.218227 -300.887996) (xy 416.25372 -300.922088) (xy 416.283285 -300.961432)
			(xy 416.306156 -301.005009) (xy 416.32174 -301.05169) (xy 416.329635 -301.100267) (xy 416.33013 -301.124874)
			(xy 416.668978 -301.124874) (xy 416.672938 -301.07582) (xy 416.684715 -301.028036) (xy 416.704006 -300.98276)
			(xy 416.730309 -300.941164) (xy 416.762944 -300.904327) (xy 416.801065 -300.873202) (xy 416.843686 -300.848595)
			(xy 416.889702 -300.831143) (xy 416.937921 -300.821299) (xy 416.987096 -300.819318) (xy 417.035951 -300.82525)
			(xy 417.083222 -300.838942) (xy 417.127684 -300.86004) (xy 417.168187 -300.887996) (xy 417.20368 -300.922088)
			(xy 417.233245 -300.961432) (xy 417.256116 -301.005009) (xy 417.2717 -301.05169) (xy 417.279595 -301.100267)
			(xy 417.28009 -301.124874) (xy 417.619192 -301.124874) (xy 417.623152 -301.07582) (xy 417.634929 -301.028036)
			(xy 417.65422 -300.98276) (xy 417.680523 -300.941164) (xy 417.713158 -300.904327) (xy 417.751279 -300.873202)
			(xy 417.7939 -300.848595) (xy 417.839916 -300.831143) (xy 417.888135 -300.821299) (xy 417.93731 -300.819318)
			(xy 417.986165 -300.82525) (xy 418.033436 -300.838942) (xy 418.077898 -300.86004) (xy 418.118401 -300.887996)
			(xy 418.153894 -300.922088) (xy 418.183459 -300.961432) (xy 418.20633 -301.005009) (xy 418.221914 -301.05169)
			(xy 418.229809 -301.100267) (xy 418.230304 -301.124874) (xy 418.569152 -301.124874) (xy 418.573112 -301.07582)
			(xy 418.584889 -301.028036) (xy 418.60418 -300.98276) (xy 418.630483 -300.941164) (xy 418.663118 -300.904327)
			(xy 418.701239 -300.873202) (xy 418.74386 -300.848595) (xy 418.789876 -300.831143) (xy 418.838095 -300.821299)
			(xy 418.88727 -300.819318) (xy 418.936125 -300.82525) (xy 418.983396 -300.838942) (xy 419.027858 -300.86004)
			(xy 419.068361 -300.887996) (xy 419.103854 -300.922088) (xy 419.133419 -300.961432) (xy 419.15629 -301.005009)
			(xy 419.171874 -301.05169) (xy 419.179769 -301.100267) (xy 419.180264 -301.124874) (xy 419.519112 -301.124874)
			(xy 419.523072 -301.07582) (xy 419.534849 -301.028036) (xy 419.55414 -300.98276) (xy 419.580443 -300.941164)
			(xy 419.613078 -300.904327) (xy 419.651199 -300.873202) (xy 419.69382 -300.848595) (xy 419.739836 -300.831143)
			(xy 419.788055 -300.821299) (xy 419.83723 -300.819318) (xy 419.886085 -300.82525) (xy 419.933356 -300.838942)
			(xy 419.977818 -300.86004) (xy 420.018321 -300.887996) (xy 420.053814 -300.922088) (xy 420.083379 -300.961432)
			(xy 420.10625 -301.005009) (xy 420.121834 -301.05169) (xy 420.129729 -301.100267) (xy 420.130224 -301.124874)
			(xy 420.469072 -301.124874) (xy 420.473032 -301.07582) (xy 420.484809 -301.028036) (xy 420.5041 -300.98276)
			(xy 420.530403 -300.941164) (xy 420.563038 -300.904327) (xy 420.601159 -300.873202) (xy 420.64378 -300.848595)
			(xy 420.689796 -300.831143) (xy 420.738015 -300.821299) (xy 420.78719 -300.819318) (xy 420.836045 -300.82525)
			(xy 420.883316 -300.838942) (xy 420.927778 -300.86004) (xy 420.968281 -300.887996) (xy 421.003774 -300.922088)
			(xy 421.033339 -300.961432) (xy 421.05621 -301.005009) (xy 421.071794 -301.05169) (xy 421.079689 -301.100267)
			(xy 421.080184 -301.124874) (xy 421.419032 -301.124874) (xy 421.422992 -301.07582) (xy 421.434769 -301.028036)
			(xy 421.45406 -300.98276) (xy 421.480363 -300.941164) (xy 421.512998 -300.904327) (xy 421.551119 -300.873202)
			(xy 421.59374 -300.848595) (xy 421.639756 -300.831143) (xy 421.687975 -300.821299) (xy 421.73715 -300.819318)
			(xy 421.786005 -300.82525) (xy 421.833276 -300.838942) (xy 421.877738 -300.86004) (xy 421.918241 -300.887996)
			(xy 421.953734 -300.922088) (xy 421.983299 -300.961432) (xy 422.00617 -301.005009) (xy 422.021754 -301.05169)
			(xy 422.029649 -301.100267) (xy 422.030144 -301.124874) (xy 424.269166 -301.124874) (xy 424.273126 -301.07582)
			(xy 424.284903 -301.028036) (xy 424.304194 -300.98276) (xy 424.330497 -300.941164) (xy 424.363132 -300.904327)
			(xy 424.401253 -300.873202) (xy 424.443874 -300.848595) (xy 424.48989 -300.831143) (xy 424.538109 -300.821299)
			(xy 424.587284 -300.819318) (xy 424.636139 -300.82525) (xy 424.68341 -300.838942) (xy 424.727872 -300.86004)
			(xy 424.768375 -300.887996) (xy 424.803868 -300.922088) (xy 424.833433 -300.961432) (xy 424.856304 -301.005009)
			(xy 424.871888 -301.05169) (xy 424.879783 -301.100267) (xy 424.880278 -301.124874) (xy 425.219126 -301.124874)
			(xy 425.223086 -301.07582) (xy 425.234863 -301.028036) (xy 425.254154 -300.98276) (xy 425.280457 -300.941164)
			(xy 425.313092 -300.904327) (xy 425.351213 -300.873202) (xy 425.393834 -300.848595) (xy 425.43985 -300.831143)
			(xy 425.488069 -300.821299) (xy 425.537244 -300.819318) (xy 425.586099 -300.82525) (xy 425.63337 -300.838942)
			(xy 425.677832 -300.86004) (xy 425.718335 -300.887996) (xy 425.753828 -300.922088) (xy 425.783393 -300.961432)
			(xy 425.806264 -301.005009) (xy 425.821848 -301.05169) (xy 425.829743 -301.100267) (xy 425.830238 -301.124874)
			(xy 426.169086 -301.124874) (xy 426.173046 -301.07582) (xy 426.184823 -301.028036) (xy 426.204114 -300.98276)
			(xy 426.230417 -300.941164) (xy 426.263052 -300.904327) (xy 426.301173 -300.873202) (xy 426.343794 -300.848595)
			(xy 426.38981 -300.831143) (xy 426.438029 -300.821299) (xy 426.487204 -300.819318) (xy 426.536059 -300.82525)
			(xy 426.58333 -300.838942) (xy 426.627792 -300.86004) (xy 426.668295 -300.887996) (xy 426.703788 -300.922088)
			(xy 426.733353 -300.961432) (xy 426.756224 -301.005009) (xy 426.771808 -301.05169) (xy 426.779703 -301.100267)
			(xy 426.780198 -301.124874) (xy 427.119046 -301.124874) (xy 427.123006 -301.07582) (xy 427.134783 -301.028036)
			(xy 427.154074 -300.98276) (xy 427.180377 -300.941164) (xy 427.213012 -300.904327) (xy 427.251133 -300.873202)
			(xy 427.293754 -300.848595) (xy 427.33977 -300.831143) (xy 427.387989 -300.821299) (xy 427.437164 -300.819318)
			(xy 427.486019 -300.82525) (xy 427.53329 -300.838942) (xy 427.577752 -300.86004) (xy 427.618255 -300.887996)
			(xy 427.653748 -300.922088) (xy 427.683313 -300.961432) (xy 427.706184 -301.005009) (xy 427.721768 -301.05169)
			(xy 427.729663 -301.100267) (xy 427.730158 -301.124874) (xy 428.069006 -301.124874) (xy 428.072966 -301.07582)
			(xy 428.084743 -301.028036) (xy 428.104034 -300.98276) (xy 428.130337 -300.941164) (xy 428.162972 -300.904327)
			(xy 428.201093 -300.873202) (xy 428.243714 -300.848595) (xy 428.28973 -300.831143) (xy 428.337949 -300.821299)
			(xy 428.387124 -300.819318) (xy 428.435979 -300.82525) (xy 428.48325 -300.838942) (xy 428.527712 -300.86004)
			(xy 428.568215 -300.887996) (xy 428.603708 -300.922088) (xy 428.633273 -300.961432) (xy 428.656144 -301.005009)
			(xy 428.671728 -301.05169) (xy 428.679623 -301.100267) (xy 428.680118 -301.124874) (xy 429.01922 -301.124874)
			(xy 429.02318 -301.07582) (xy 429.034957 -301.028036) (xy 429.054248 -300.98276) (xy 429.080551 -300.941164)
			(xy 429.113186 -300.904327) (xy 429.151307 -300.873202) (xy 429.193928 -300.848595) (xy 429.239944 -300.831143)
			(xy 429.288163 -300.821299) (xy 429.337338 -300.819318) (xy 429.386193 -300.82525) (xy 429.433464 -300.838942)
			(xy 429.477926 -300.86004) (xy 429.518429 -300.887996) (xy 429.553922 -300.922088) (xy 429.583487 -300.961432)
			(xy 429.606358 -301.005009) (xy 429.621942 -301.05169) (xy 429.629837 -301.100267) (xy 429.630332 -301.124874)
			(xy 429.96918 -301.124874) (xy 429.97314 -301.07582) (xy 429.984917 -301.028036) (xy 430.004208 -300.98276)
			(xy 430.030511 -300.941164) (xy 430.063146 -300.904327) (xy 430.101267 -300.873202) (xy 430.143888 -300.848595)
			(xy 430.189904 -300.831143) (xy 430.238123 -300.821299) (xy 430.287298 -300.819318) (xy 430.336153 -300.82525)
			(xy 430.383424 -300.838942) (xy 430.427886 -300.86004) (xy 430.468389 -300.887996) (xy 430.503882 -300.922088)
			(xy 430.533447 -300.961432) (xy 430.556318 -301.005009) (xy 430.571902 -301.05169) (xy 430.579797 -301.100267)
			(xy 430.580292 -301.124874) (xy 430.91914 -301.124874) (xy 430.9231 -301.07582) (xy 430.934877 -301.028036)
			(xy 430.954168 -300.98276) (xy 430.980471 -300.941164) (xy 431.013106 -300.904327) (xy 431.051227 -300.873202)
			(xy 431.093848 -300.848595) (xy 431.139864 -300.831143) (xy 431.188083 -300.821299) (xy 431.237258 -300.819318)
			(xy 431.286113 -300.82525) (xy 431.333384 -300.838942) (xy 431.377846 -300.86004) (xy 431.418349 -300.887996)
			(xy 431.453842 -300.922088) (xy 431.483407 -300.961432) (xy 431.506278 -301.005009) (xy 431.51865 -301.04207)
			(xy 438.617104 -301.04207) (xy 438.621175 -300.986448) (xy 438.633301 -300.932011) (xy 438.653224 -300.87992)
			(xy 438.68052 -300.831285) (xy 438.714606 -300.787142) (xy 438.754755 -300.748433) (xy 438.800113 -300.715982)
			(xy 438.849713 -300.690481) (xy 438.902497 -300.672474) (xy 438.95734 -300.662344) (xy 439.013074 -300.660307)
			(xy 439.068511 -300.666407) (xy 439.122468 -300.680513) (xy 439.173797 -300.702325) (xy 439.221403 -300.731379)
			(xy 439.264271 -300.767054) (xy 439.301488 -300.808591) (xy 439.332261 -300.855104) (xy 439.355933 -300.905601)
			(xy 439.372001 -300.959008) (xy 439.380121 -301.014184) (xy 439.38063 -301.04207) (xy 439.380477 -301.050452)
			(xy 440.990988 -301.050452) (xy 440.995059 -300.99483) (xy 441.007185 -300.940393) (xy 441.027108 -300.888302)
			(xy 441.054404 -300.839667) (xy 441.08849 -300.795524) (xy 441.128639 -300.756815) (xy 441.173997 -300.724364)
			(xy 441.223597 -300.698863) (xy 441.276381 -300.680856) (xy 441.331224 -300.670726) (xy 441.386958 -300.668689)
			(xy 441.442395 -300.674789) (xy 441.496352 -300.688895) (xy 441.547681 -300.710707) (xy 441.595287 -300.739761)
			(xy 441.638155 -300.775436) (xy 441.675372 -300.816973) (xy 441.706145 -300.863486) (xy 441.729817 -300.913983)
			(xy 441.745885 -300.96739) (xy 441.754005 -301.022566) (xy 441.754514 -301.050452) (xy 441.754005 -301.078338)
			(xy 441.745885 -301.133514) (xy 441.729817 -301.186921) (xy 441.706145 -301.237418) (xy 441.675372 -301.283931)
			(xy 441.638155 -301.325468) (xy 441.595287 -301.361143) (xy 441.547681 -301.390197) (xy 441.496352 -301.412009)
			(xy 441.442395 -301.426115) (xy 441.386958 -301.432215) (xy 441.331224 -301.430178) (xy 441.276381 -301.420048)
			(xy 441.223597 -301.402041) (xy 441.173997 -301.37654) (xy 441.128639 -301.344089) (xy 441.08849 -301.30538)
			(xy 441.054404 -301.261237) (xy 441.027108 -301.212602) (xy 441.007185 -301.160511) (xy 440.995059 -301.106074)
			(xy 440.990988 -301.050452) (xy 439.380477 -301.050452) (xy 439.380121 -301.069956) (xy 439.372001 -301.125132)
			(xy 439.355933 -301.178539) (xy 439.332261 -301.229036) (xy 439.301488 -301.275549) (xy 439.264271 -301.317086)
			(xy 439.221403 -301.352761) (xy 439.173797 -301.381815) (xy 439.122468 -301.403627) (xy 439.068511 -301.417733)
			(xy 439.013074 -301.423833) (xy 438.95734 -301.421796) (xy 438.902497 -301.411666) (xy 438.849713 -301.393659)
			(xy 438.800113 -301.368158) (xy 438.754755 -301.335707) (xy 438.714606 -301.296998) (xy 438.68052 -301.252855)
			(xy 438.653224 -301.20422) (xy 438.633301 -301.152129) (xy 438.621175 -301.097692) (xy 438.617104 -301.04207)
			(xy 431.51865 -301.04207) (xy 431.521862 -301.05169) (xy 431.529757 -301.100267) (xy 431.530252 -301.124874)
			(xy 431.529757 -301.149481) (xy 431.521862 -301.198058) (xy 431.506278 -301.244739) (xy 431.483407 -301.288316)
			(xy 431.453842 -301.32766) (xy 431.418349 -301.361752) (xy 431.377846 -301.389708) (xy 431.333384 -301.410806)
			(xy 431.286113 -301.424498) (xy 431.237258 -301.43043) (xy 431.188083 -301.428449) (xy 431.139864 -301.418605)
			(xy 431.093848 -301.401153) (xy 431.051227 -301.376546) (xy 431.013106 -301.345421) (xy 430.980471 -301.308584)
			(xy 430.954168 -301.266988) (xy 430.934877 -301.221712) (xy 430.9231 -301.173928) (xy 430.91914 -301.124874)
			(xy 430.580292 -301.124874) (xy 430.579797 -301.149481) (xy 430.571902 -301.198058) (xy 430.556318 -301.244739)
			(xy 430.533447 -301.288316) (xy 430.503882 -301.32766) (xy 430.468389 -301.361752) (xy 430.427886 -301.389708)
			(xy 430.383424 -301.410806) (xy 430.336153 -301.424498) (xy 430.287298 -301.43043) (xy 430.238123 -301.428449)
			(xy 430.189904 -301.418605) (xy 430.143888 -301.401153) (xy 430.101267 -301.376546) (xy 430.063146 -301.345421)
			(xy 430.030511 -301.308584) (xy 430.004208 -301.266988) (xy 429.984917 -301.221712) (xy 429.97314 -301.173928)
			(xy 429.96918 -301.124874) (xy 429.630332 -301.124874) (xy 429.629837 -301.149481) (xy 429.621942 -301.198058)
			(xy 429.606358 -301.244739) (xy 429.583487 -301.288316) (xy 429.553922 -301.32766) (xy 429.518429 -301.361752)
			(xy 429.477926 -301.389708) (xy 429.433464 -301.410806) (xy 429.386193 -301.424498) (xy 429.337338 -301.43043)
			(xy 429.288163 -301.428449) (xy 429.239944 -301.418605) (xy 429.193928 -301.401153) (xy 429.151307 -301.376546)
			(xy 429.113186 -301.345421) (xy 429.080551 -301.308584) (xy 429.054248 -301.266988) (xy 429.034957 -301.221712)
			(xy 429.02318 -301.173928) (xy 429.01922 -301.124874) (xy 428.680118 -301.124874) (xy 428.679623 -301.149481)
			(xy 428.671728 -301.198058) (xy 428.656144 -301.244739) (xy 428.633273 -301.288316) (xy 428.603708 -301.32766)
			(xy 428.568215 -301.361752) (xy 428.527712 -301.389708) (xy 428.48325 -301.410806) (xy 428.435979 -301.424498)
			(xy 428.387124 -301.43043) (xy 428.337949 -301.428449) (xy 428.28973 -301.418605) (xy 428.243714 -301.401153)
			(xy 428.201093 -301.376546) (xy 428.162972 -301.345421) (xy 428.130337 -301.308584) (xy 428.104034 -301.266988)
			(xy 428.084743 -301.221712) (xy 428.072966 -301.173928) (xy 428.069006 -301.124874) (xy 427.730158 -301.124874)
			(xy 427.729663 -301.149481) (xy 427.721768 -301.198058) (xy 427.706184 -301.244739) (xy 427.683313 -301.288316)
			(xy 427.653748 -301.32766) (xy 427.618255 -301.361752) (xy 427.577752 -301.389708) (xy 427.53329 -301.410806)
			(xy 427.486019 -301.424498) (xy 427.437164 -301.43043) (xy 427.387989 -301.428449) (xy 427.33977 -301.418605)
			(xy 427.293754 -301.401153) (xy 427.251133 -301.376546) (xy 427.213012 -301.345421) (xy 427.180377 -301.308584)
			(xy 427.154074 -301.266988) (xy 427.134783 -301.221712) (xy 427.123006 -301.173928) (xy 427.119046 -301.124874)
			(xy 426.780198 -301.124874) (xy 426.779703 -301.149481) (xy 426.771808 -301.198058) (xy 426.756224 -301.244739)
			(xy 426.733353 -301.288316) (xy 426.703788 -301.32766) (xy 426.668295 -301.361752) (xy 426.627792 -301.389708)
			(xy 426.58333 -301.410806) (xy 426.536059 -301.424498) (xy 426.487204 -301.43043) (xy 426.438029 -301.428449)
			(xy 426.38981 -301.418605) (xy 426.343794 -301.401153) (xy 426.301173 -301.376546) (xy 426.263052 -301.345421)
			(xy 426.230417 -301.308584) (xy 426.204114 -301.266988) (xy 426.184823 -301.221712) (xy 426.173046 -301.173928)
			(xy 426.169086 -301.124874) (xy 425.830238 -301.124874) (xy 425.829743 -301.149481) (xy 425.821848 -301.198058)
			(xy 425.806264 -301.244739) (xy 425.783393 -301.288316) (xy 425.753828 -301.32766) (xy 425.718335 -301.361752)
			(xy 425.677832 -301.389708) (xy 425.63337 -301.410806) (xy 425.586099 -301.424498) (xy 425.537244 -301.43043)
			(xy 425.488069 -301.428449) (xy 425.43985 -301.418605) (xy 425.393834 -301.401153) (xy 425.351213 -301.376546)
			(xy 425.313092 -301.345421) (xy 425.280457 -301.308584) (xy 425.254154 -301.266988) (xy 425.234863 -301.221712)
			(xy 425.223086 -301.173928) (xy 425.219126 -301.124874) (xy 424.880278 -301.124874) (xy 424.879783 -301.149481)
			(xy 424.871888 -301.198058) (xy 424.856304 -301.244739) (xy 424.833433 -301.288316) (xy 424.803868 -301.32766)
			(xy 424.768375 -301.361752) (xy 424.727872 -301.389708) (xy 424.68341 -301.410806) (xy 424.636139 -301.424498)
			(xy 424.587284 -301.43043) (xy 424.538109 -301.428449) (xy 424.48989 -301.418605) (xy 424.443874 -301.401153)
			(xy 424.401253 -301.376546) (xy 424.363132 -301.345421) (xy 424.330497 -301.308584) (xy 424.304194 -301.266988)
			(xy 424.284903 -301.221712) (xy 424.273126 -301.173928) (xy 424.269166 -301.124874) (xy 422.030144 -301.124874)
			(xy 422.029649 -301.149481) (xy 422.021754 -301.198058) (xy 422.00617 -301.244739) (xy 421.983299 -301.288316)
			(xy 421.953734 -301.32766) (xy 421.918241 -301.361752) (xy 421.877738 -301.389708) (xy 421.833276 -301.410806)
			(xy 421.786005 -301.424498) (xy 421.73715 -301.43043) (xy 421.687975 -301.428449) (xy 421.639756 -301.418605)
			(xy 421.59374 -301.401153) (xy 421.551119 -301.376546) (xy 421.512998 -301.345421) (xy 421.480363 -301.308584)
			(xy 421.45406 -301.266988) (xy 421.434769 -301.221712) (xy 421.422992 -301.173928) (xy 421.419032 -301.124874)
			(xy 421.080184 -301.124874) (xy 421.079689 -301.149481) (xy 421.071794 -301.198058) (xy 421.05621 -301.244739)
			(xy 421.033339 -301.288316) (xy 421.003774 -301.32766) (xy 420.968281 -301.361752) (xy 420.927778 -301.389708)
			(xy 420.883316 -301.410806) (xy 420.836045 -301.424498) (xy 420.78719 -301.43043) (xy 420.738015 -301.428449)
			(xy 420.689796 -301.418605) (xy 420.64378 -301.401153) (xy 420.601159 -301.376546) (xy 420.563038 -301.345421)
			(xy 420.530403 -301.308584) (xy 420.5041 -301.266988) (xy 420.484809 -301.221712) (xy 420.473032 -301.173928)
			(xy 420.469072 -301.124874) (xy 420.130224 -301.124874) (xy 420.129729 -301.149481) (xy 420.121834 -301.198058)
			(xy 420.10625 -301.244739) (xy 420.083379 -301.288316) (xy 420.053814 -301.32766) (xy 420.018321 -301.361752)
			(xy 419.977818 -301.389708) (xy 419.933356 -301.410806) (xy 419.886085 -301.424498) (xy 419.83723 -301.43043)
			(xy 419.788055 -301.428449) (xy 419.739836 -301.418605) (xy 419.69382 -301.401153) (xy 419.651199 -301.376546)
			(xy 419.613078 -301.345421) (xy 419.580443 -301.308584) (xy 419.55414 -301.266988) (xy 419.534849 -301.221712)
			(xy 419.523072 -301.173928) (xy 419.519112 -301.124874) (xy 419.180264 -301.124874) (xy 419.179769 -301.149481)
			(xy 419.171874 -301.198058) (xy 419.15629 -301.244739) (xy 419.133419 -301.288316) (xy 419.103854 -301.32766)
			(xy 419.068361 -301.361752) (xy 419.027858 -301.389708) (xy 418.983396 -301.410806) (xy 418.936125 -301.424498)
			(xy 418.88727 -301.43043) (xy 418.838095 -301.428449) (xy 418.789876 -301.418605) (xy 418.74386 -301.401153)
			(xy 418.701239 -301.376546) (xy 418.663118 -301.345421) (xy 418.630483 -301.308584) (xy 418.60418 -301.266988)
			(xy 418.584889 -301.221712) (xy 418.573112 -301.173928) (xy 418.569152 -301.124874) (xy 418.230304 -301.124874)
			(xy 418.229809 -301.149481) (xy 418.221914 -301.198058) (xy 418.20633 -301.244739) (xy 418.183459 -301.288316)
			(xy 418.153894 -301.32766) (xy 418.118401 -301.361752) (xy 418.077898 -301.389708) (xy 418.033436 -301.410806)
			(xy 417.986165 -301.424498) (xy 417.93731 -301.43043) (xy 417.888135 -301.428449) (xy 417.839916 -301.418605)
			(xy 417.7939 -301.401153) (xy 417.751279 -301.376546) (xy 417.713158 -301.345421) (xy 417.680523 -301.308584)
			(xy 417.65422 -301.266988) (xy 417.634929 -301.221712) (xy 417.623152 -301.173928) (xy 417.619192 -301.124874)
			(xy 417.28009 -301.124874) (xy 417.279595 -301.149481) (xy 417.2717 -301.198058) (xy 417.256116 -301.244739)
			(xy 417.233245 -301.288316) (xy 417.20368 -301.32766) (xy 417.168187 -301.361752) (xy 417.127684 -301.389708)
			(xy 417.083222 -301.410806) (xy 417.035951 -301.424498) (xy 416.987096 -301.43043) (xy 416.937921 -301.428449)
			(xy 416.889702 -301.418605) (xy 416.843686 -301.401153) (xy 416.801065 -301.376546) (xy 416.762944 -301.345421)
			(xy 416.730309 -301.308584) (xy 416.704006 -301.266988) (xy 416.684715 -301.221712) (xy 416.672938 -301.173928)
			(xy 416.668978 -301.124874) (xy 416.33013 -301.124874) (xy 416.329635 -301.149481) (xy 416.32174 -301.198058)
			(xy 416.306156 -301.244739) (xy 416.283285 -301.288316) (xy 416.25372 -301.32766) (xy 416.218227 -301.361752)
			(xy 416.177724 -301.389708) (xy 416.133262 -301.410806) (xy 416.085991 -301.424498) (xy 416.037136 -301.43043)
			(xy 415.987961 -301.428449) (xy 415.939742 -301.418605) (xy 415.893726 -301.401153) (xy 415.851105 -301.376546)
			(xy 415.812984 -301.345421) (xy 415.780349 -301.308584) (xy 415.754046 -301.266988) (xy 415.734755 -301.221712)
			(xy 415.722978 -301.173928) (xy 415.719018 -301.124874) (xy 415.38017 -301.124874) (xy 415.379675 -301.149481)
			(xy 415.37178 -301.198058) (xy 415.356196 -301.244739) (xy 415.333325 -301.288316) (xy 415.30376 -301.32766)
			(xy 415.268267 -301.361752) (xy 415.227764 -301.389708) (xy 415.183302 -301.410806) (xy 415.136031 -301.424498)
			(xy 415.087176 -301.43043) (xy 415.038001 -301.428449) (xy 414.989782 -301.418605) (xy 414.943766 -301.401153)
			(xy 414.901145 -301.376546) (xy 414.863024 -301.345421) (xy 414.830389 -301.308584) (xy 414.804086 -301.266988)
			(xy 414.784795 -301.221712) (xy 414.773018 -301.173928) (xy 414.769058 -301.124874) (xy 414.43021 -301.124874)
			(xy 414.429715 -301.149481) (xy 414.42182 -301.198058) (xy 414.406236 -301.244739) (xy 414.383365 -301.288316)
			(xy 414.3538 -301.32766) (xy 414.318307 -301.361752) (xy 414.277804 -301.389708) (xy 414.233342 -301.410806)
			(xy 414.186071 -301.424498) (xy 414.137216 -301.43043) (xy 414.088041 -301.428449) (xy 414.039822 -301.418605)
			(xy 413.993806 -301.401153) (xy 413.951185 -301.376546) (xy 413.913064 -301.345421) (xy 413.880429 -301.308584)
			(xy 413.854126 -301.266988) (xy 413.834835 -301.221712) (xy 413.823058 -301.173928) (xy 413.819098 -301.124874)
			(xy 413.48025 -301.124874) (xy 413.479755 -301.149481) (xy 413.47186 -301.198058) (xy 413.456276 -301.244739)
			(xy 413.433405 -301.288316) (xy 413.40384 -301.32766) (xy 413.368347 -301.361752) (xy 413.327844 -301.389708)
			(xy 413.283382 -301.410806) (xy 413.236111 -301.424498) (xy 413.187256 -301.43043) (xy 413.138081 -301.428449)
			(xy 413.089862 -301.418605) (xy 413.043846 -301.401153) (xy 413.001225 -301.376546) (xy 412.963104 -301.345421)
			(xy 412.930469 -301.308584) (xy 412.904166 -301.266988) (xy 412.884875 -301.221712) (xy 412.873098 -301.173928)
			(xy 412.869138 -301.124874) (xy 412.53029 -301.124874) (xy 412.529795 -301.149481) (xy 412.5219 -301.198058)
			(xy 412.506316 -301.244739) (xy 412.483445 -301.288316) (xy 412.45388 -301.32766) (xy 412.418387 -301.361752)
			(xy 412.377884 -301.389708) (xy 412.333422 -301.410806) (xy 412.286151 -301.424498) (xy 412.237296 -301.43043)
			(xy 412.188121 -301.428449) (xy 412.139902 -301.418605) (xy 412.093886 -301.401153) (xy 412.051265 -301.376546)
			(xy 412.013144 -301.345421) (xy 411.980509 -301.308584) (xy 411.954206 -301.266988) (xy 411.934915 -301.221712)
			(xy 411.923138 -301.173928) (xy 411.919178 -301.124874) (xy 411.58033 -301.124874) (xy 411.579835 -301.149481)
			(xy 411.57194 -301.198058) (xy 411.556356 -301.244739) (xy 411.533485 -301.288316) (xy 411.50392 -301.32766)
			(xy 411.468427 -301.361752) (xy 411.427924 -301.389708) (xy 411.383462 -301.410806) (xy 411.336191 -301.424498)
			(xy 411.287336 -301.43043) (xy 411.238161 -301.428449) (xy 411.189942 -301.418605) (xy 411.143926 -301.401153)
			(xy 411.101305 -301.376546) (xy 411.063184 -301.345421) (xy 411.030549 -301.308584) (xy 411.004246 -301.266988)
			(xy 410.984955 -301.221712) (xy 410.973178 -301.173928) (xy 410.969218 -301.124874) (xy 410.630116 -301.124874)
			(xy 410.629621 -301.149481) (xy 410.621726 -301.198058) (xy 410.606142 -301.244739) (xy 410.583271 -301.288316)
			(xy 410.553706 -301.32766) (xy 410.518213 -301.361752) (xy 410.47771 -301.389708) (xy 410.433248 -301.410806)
			(xy 410.385977 -301.424498) (xy 410.337122 -301.43043) (xy 410.287947 -301.428449) (xy 410.239728 -301.418605)
			(xy 410.193712 -301.401153) (xy 410.151091 -301.376546) (xy 410.11297 -301.345421) (xy 410.080335 -301.308584)
			(xy 410.054032 -301.266988) (xy 410.034741 -301.221712) (xy 410.022964 -301.173928) (xy 410.019004 -301.124874)
			(xy 409.680156 -301.124874) (xy 409.679661 -301.149481) (xy 409.671766 -301.198058) (xy 409.656182 -301.244739)
			(xy 409.633311 -301.288316) (xy 409.603746 -301.32766) (xy 409.568253 -301.361752) (xy 409.52775 -301.389708)
			(xy 409.483288 -301.410806) (xy 409.436017 -301.424498) (xy 409.387162 -301.43043) (xy 409.337987 -301.428449)
			(xy 409.289768 -301.418605) (xy 409.243752 -301.401153) (xy 409.201131 -301.376546) (xy 409.16301 -301.345421)
			(xy 409.130375 -301.308584) (xy 409.104072 -301.266988) (xy 409.084781 -301.221712) (xy 409.073004 -301.173928)
			(xy 409.069044 -301.124874) (xy 408.730196 -301.124874) (xy 408.729701 -301.149481) (xy 408.721806 -301.198058)
			(xy 408.706222 -301.244739) (xy 408.683351 -301.288316) (xy 408.653786 -301.32766) (xy 408.618293 -301.361752)
			(xy 408.57779 -301.389708) (xy 408.533328 -301.410806) (xy 408.486057 -301.424498) (xy 408.437202 -301.43043)
			(xy 408.388027 -301.428449) (xy 408.339808 -301.418605) (xy 408.293792 -301.401153) (xy 408.251171 -301.376546)
			(xy 408.21305 -301.345421) (xy 408.180415 -301.308584) (xy 408.154112 -301.266988) (xy 408.134821 -301.221712)
			(xy 408.123044 -301.173928) (xy 408.119084 -301.124874) (xy 406.830276 -301.124874) (xy 406.829781 -301.149481)
			(xy 406.821886 -301.198058) (xy 406.806302 -301.244739) (xy 406.783431 -301.288316) (xy 406.753866 -301.32766)
			(xy 406.718373 -301.361752) (xy 406.67787 -301.389708) (xy 406.633408 -301.410806) (xy 406.586137 -301.424498)
			(xy 406.537282 -301.43043) (xy 406.488107 -301.428449) (xy 406.439888 -301.418605) (xy 406.393872 -301.401153)
			(xy 406.351251 -301.376546) (xy 406.31313 -301.345421) (xy 406.280495 -301.308584) (xy 406.254192 -301.266988)
			(xy 406.234901 -301.221712) (xy 406.223124 -301.173928) (xy 406.219164 -301.124874) (xy 405.880316 -301.124874)
			(xy 405.879821 -301.149481) (xy 405.871926 -301.198058) (xy 405.856342 -301.244739) (xy 405.833471 -301.288316)
			(xy 405.803906 -301.32766) (xy 405.768413 -301.361752) (xy 405.72791 -301.389708) (xy 405.683448 -301.410806)
			(xy 405.636177 -301.424498) (xy 405.587322 -301.43043) (xy 405.538147 -301.428449) (xy 405.489928 -301.418605)
			(xy 405.443912 -301.401153) (xy 405.401291 -301.376546) (xy 405.36317 -301.345421) (xy 405.330535 -301.308584)
			(xy 405.304232 -301.266988) (xy 405.284941 -301.221712) (xy 405.273164 -301.173928) (xy 405.269204 -301.124874)
			(xy 404.930102 -301.124874) (xy 404.929607 -301.149481) (xy 404.921712 -301.198058) (xy 404.906128 -301.244739)
			(xy 404.883257 -301.288316) (xy 404.853692 -301.32766) (xy 404.818199 -301.361752) (xy 404.777696 -301.389708)
			(xy 404.733234 -301.410806) (xy 404.685963 -301.424498) (xy 404.637108 -301.43043) (xy 404.587933 -301.428449)
			(xy 404.539714 -301.418605) (xy 404.493698 -301.401153) (xy 404.451077 -301.376546) (xy 404.412956 -301.345421)
			(xy 404.380321 -301.308584) (xy 404.354018 -301.266988) (xy 404.334727 -301.221712) (xy 404.32295 -301.173928)
			(xy 404.31899 -301.124874) (xy 403.980142 -301.124874) (xy 403.979647 -301.149481) (xy 403.971752 -301.198058)
			(xy 403.956168 -301.244739) (xy 403.933297 -301.288316) (xy 403.903732 -301.32766) (xy 403.868239 -301.361752)
			(xy 403.827736 -301.389708) (xy 403.783274 -301.410806) (xy 403.736003 -301.424498) (xy 403.687148 -301.43043)
			(xy 403.637973 -301.428449) (xy 403.589754 -301.418605) (xy 403.543738 -301.401153) (xy 403.501117 -301.376546)
			(xy 403.462996 -301.345421) (xy 403.430361 -301.308584) (xy 403.404058 -301.266988) (xy 403.384767 -301.221712)
			(xy 403.37299 -301.173928) (xy 403.36903 -301.124874) (xy 403.030182 -301.124874) (xy 403.029687 -301.149481)
			(xy 403.021792 -301.198058) (xy 403.006208 -301.244739) (xy 402.983337 -301.288316) (xy 402.953772 -301.32766)
			(xy 402.918279 -301.361752) (xy 402.877776 -301.389708) (xy 402.833314 -301.410806) (xy 402.786043 -301.424498)
			(xy 402.737188 -301.43043) (xy 402.688013 -301.428449) (xy 402.639794 -301.418605) (xy 402.593778 -301.401153)
			(xy 402.551157 -301.376546) (xy 402.513036 -301.345421) (xy 402.480401 -301.308584) (xy 402.454098 -301.266988)
			(xy 402.434807 -301.221712) (xy 402.42303 -301.173928) (xy 402.41907 -301.124874) (xy 402.080222 -301.124874)
			(xy 402.079727 -301.149481) (xy 402.071832 -301.198058) (xy 402.056248 -301.244739) (xy 402.033377 -301.288316)
			(xy 402.003812 -301.32766) (xy 401.968319 -301.361752) (xy 401.927816 -301.389708) (xy 401.883354 -301.410806)
			(xy 401.836083 -301.424498) (xy 401.787228 -301.43043) (xy 401.738053 -301.428449) (xy 401.689834 -301.418605)
			(xy 401.643818 -301.401153) (xy 401.601197 -301.376546) (xy 401.563076 -301.345421) (xy 401.530441 -301.308584)
			(xy 401.504138 -301.266988) (xy 401.484847 -301.221712) (xy 401.47307 -301.173928) (xy 401.46911 -301.124874)
			(xy 401.130262 -301.124874) (xy 401.129767 -301.149481) (xy 401.121872 -301.198058) (xy 401.106288 -301.244739)
			(xy 401.083417 -301.288316) (xy 401.053852 -301.32766) (xy 401.018359 -301.361752) (xy 400.977856 -301.389708)
			(xy 400.933394 -301.410806) (xy 400.886123 -301.424498) (xy 400.837268 -301.43043) (xy 400.788093 -301.428449)
			(xy 400.739874 -301.418605) (xy 400.693858 -301.401153) (xy 400.651237 -301.376546) (xy 400.613116 -301.345421)
			(xy 400.580481 -301.308584) (xy 400.554178 -301.266988) (xy 400.534887 -301.221712) (xy 400.52311 -301.173928)
			(xy 400.51915 -301.124874) (xy 400.180302 -301.124874) (xy 400.179807 -301.149481) (xy 400.171912 -301.198058)
			(xy 400.156328 -301.244739) (xy 400.133457 -301.288316) (xy 400.103892 -301.32766) (xy 400.068399 -301.361752)
			(xy 400.027896 -301.389708) (xy 399.983434 -301.410806) (xy 399.936163 -301.424498) (xy 399.887308 -301.43043)
			(xy 399.838133 -301.428449) (xy 399.789914 -301.418605) (xy 399.743898 -301.401153) (xy 399.701277 -301.376546)
			(xy 399.663156 -301.345421) (xy 399.630521 -301.308584) (xy 399.604218 -301.266988) (xy 399.584927 -301.221712)
			(xy 399.57315 -301.173928) (xy 399.56919 -301.124874) (xy 399.230754 -301.124874) (xy 399.227421 -301.171346)
			(xy 399.222214 -301.195486) (xy 399.221706 -301.19701) (xy 399.221198 -301.199042) (xy 399.215202 -301.221327)
			(xy 399.197415 -301.26391) (xy 399.173418 -301.303327) (xy 399.143758 -301.338681) (xy 399.12671 -301.354236)
			(xy 399.10579 -301.371825) (xy 399.058988 -301.40004) (xy 399.007916 -301.419488) (xy 398.981168 -301.425102)
			(xy 398.979644 -301.425356) (xy 398.977104 -301.425864) (xy 398.965066 -301.427796) (xy 398.94078 -301.429958)
			(xy 398.92859 -301.430182) (xy 398.925542 -301.430182) (xy 398.924526 -301.430182) (xy 398.920208 -301.430182)
			(xy 398.895015 -301.429262) (xy 398.84543 -301.420193) (xy 398.798006 -301.403107) (xy 398.75403 -301.378468)
			(xy 398.734026 -301.363126) (xy 398.727422 -301.357792) (xy 398.711674 -301.35195) (xy 398.701273 -301.348679)
			(xy 398.679554 -301.350324) (xy 398.660474 -301.36083) (xy 398.653508 -301.369222) (xy 398.643602 -301.382684)
			(xy 398.643348 -301.415958) (xy 398.644364 -301.417482) (xy 398.644364 -301.422054) (xy 398.644364 -301.607982)
			(xy 398.643867 -301.631946) (xy 398.636327 -301.679279) (xy 398.621491 -301.724856) (xy 398.599724 -301.767557)
			(xy 398.571558 -301.806338) (xy 398.554956 -301.823628) (xy 398.404334 -301.973996) (xy 398.393629 -301.984568)
			(xy 398.370469 -302.003776) (xy 398.358106 -302.01235) (xy 398.356074 -302.01362) (xy 398.34947 -302.019208)
			(xy 398.344644 -302.02378) (xy 398.341342 -302.027336) (xy 398.335198 -302.034543) (xy 398.328292 -302.052163)
			(xy 398.32788 -302.061626) (xy 398.32788 -302.074834) (xy 398.61923 -302.074834) (xy 398.62319 -302.02578)
			(xy 398.634967 -301.977996) (xy 398.654258 -301.93272) (xy 398.680561 -301.891124) (xy 398.713196 -301.854287)
			(xy 398.751317 -301.823162) (xy 398.793938 -301.798555) (xy 398.839954 -301.781103) (xy 398.888173 -301.771259)
			(xy 398.937348 -301.769278) (xy 398.986203 -301.77521) (xy 399.033474 -301.788902) (xy 399.077936 -301.81)
			(xy 399.118439 -301.837956) (xy 399.153932 -301.872048) (xy 399.183497 -301.911392) (xy 399.206368 -301.954969)
			(xy 399.221952 -302.00165) (xy 399.229847 -302.050227) (xy 399.230342 -302.074834) (xy 399.56919 -302.074834)
			(xy 399.57315 -302.02578) (xy 399.584927 -301.977996) (xy 399.604218 -301.93272) (xy 399.630521 -301.891124)
			(xy 399.663156 -301.854287) (xy 399.701277 -301.823162) (xy 399.743898 -301.798555) (xy 399.789914 -301.781103)
			(xy 399.838133 -301.771259) (xy 399.887308 -301.769278) (xy 399.936163 -301.77521) (xy 399.983434 -301.788902)
			(xy 400.027896 -301.81) (xy 400.068399 -301.837956) (xy 400.103892 -301.872048) (xy 400.133457 -301.911392)
			(xy 400.156328 -301.954969) (xy 400.171912 -302.00165) (xy 400.179807 -302.050227) (xy 400.180302 -302.074834)
			(xy 400.51915 -302.074834) (xy 400.52311 -302.02578) (xy 400.534887 -301.977996) (xy 400.554178 -301.93272)
			(xy 400.580481 -301.891124) (xy 400.613116 -301.854287) (xy 400.651237 -301.823162) (xy 400.693858 -301.798555)
			(xy 400.739874 -301.781103) (xy 400.788093 -301.771259) (xy 400.837268 -301.769278) (xy 400.886123 -301.77521)
			(xy 400.933394 -301.788902) (xy 400.977856 -301.81) (xy 401.018359 -301.837956) (xy 401.053852 -301.872048)
			(xy 401.083417 -301.911392) (xy 401.106288 -301.954969) (xy 401.121872 -302.00165) (xy 401.129767 -302.050227)
			(xy 401.130262 -302.074834) (xy 401.46911 -302.074834) (xy 401.47307 -302.02578) (xy 401.484847 -301.977996)
			(xy 401.504138 -301.93272) (xy 401.530441 -301.891124) (xy 401.563076 -301.854287) (xy 401.601197 -301.823162)
			(xy 401.643818 -301.798555) (xy 401.689834 -301.781103) (xy 401.738053 -301.771259) (xy 401.787228 -301.769278)
			(xy 401.836083 -301.77521) (xy 401.883354 -301.788902) (xy 401.927816 -301.81) (xy 401.968319 -301.837956)
			(xy 402.003812 -301.872048) (xy 402.033377 -301.911392) (xy 402.056248 -301.954969) (xy 402.071832 -302.00165)
			(xy 402.079727 -302.050227) (xy 402.080222 -302.074834) (xy 402.41907 -302.074834) (xy 402.42303 -302.02578)
			(xy 402.434807 -301.977996) (xy 402.454098 -301.93272) (xy 402.480401 -301.891124) (xy 402.513036 -301.854287)
			(xy 402.551157 -301.823162) (xy 402.593778 -301.798555) (xy 402.639794 -301.781103) (xy 402.688013 -301.771259)
			(xy 402.737188 -301.769278) (xy 402.786043 -301.77521) (xy 402.833314 -301.788902) (xy 402.877776 -301.81)
			(xy 402.918279 -301.837956) (xy 402.953772 -301.872048) (xy 402.983337 -301.911392) (xy 403.006208 -301.954969)
			(xy 403.021792 -302.00165) (xy 403.029687 -302.050227) (xy 403.030182 -302.074834) (xy 403.36903 -302.074834)
			(xy 403.37299 -302.02578) (xy 403.384767 -301.977996) (xy 403.404058 -301.93272) (xy 403.430361 -301.891124)
			(xy 403.462996 -301.854287) (xy 403.501117 -301.823162) (xy 403.543738 -301.798555) (xy 403.589754 -301.781103)
			(xy 403.637973 -301.771259) (xy 403.687148 -301.769278) (xy 403.736003 -301.77521) (xy 403.783274 -301.788902)
			(xy 403.827736 -301.81) (xy 403.868239 -301.837956) (xy 403.903732 -301.872048) (xy 403.933297 -301.911392)
			(xy 403.956168 -301.954969) (xy 403.971752 -302.00165) (xy 403.979647 -302.050227) (xy 403.980142 -302.074834)
			(xy 404.31899 -302.074834) (xy 404.32295 -302.02578) (xy 404.334727 -301.977996) (xy 404.354018 -301.93272)
			(xy 404.380321 -301.891124) (xy 404.412956 -301.854287) (xy 404.451077 -301.823162) (xy 404.493698 -301.798555)
			(xy 404.539714 -301.781103) (xy 404.587933 -301.771259) (xy 404.637108 -301.769278) (xy 404.685963 -301.77521)
			(xy 404.733234 -301.788902) (xy 404.777696 -301.81) (xy 404.818199 -301.837956) (xy 404.853692 -301.872048)
			(xy 404.883257 -301.911392) (xy 404.906128 -301.954969) (xy 404.921712 -302.00165) (xy 404.929607 -302.050227)
			(xy 404.930102 -302.074834) (xy 405.269204 -302.074834) (xy 405.273164 -302.02578) (xy 405.284941 -301.977996)
			(xy 405.304232 -301.93272) (xy 405.330535 -301.891124) (xy 405.36317 -301.854287) (xy 405.401291 -301.823162)
			(xy 405.443912 -301.798555) (xy 405.489928 -301.781103) (xy 405.538147 -301.771259) (xy 405.587322 -301.769278)
			(xy 405.636177 -301.77521) (xy 405.683448 -301.788902) (xy 405.72791 -301.81) (xy 405.768413 -301.837956)
			(xy 405.803906 -301.872048) (xy 405.833471 -301.911392) (xy 405.856342 -301.954969) (xy 405.871926 -302.00165)
			(xy 405.879821 -302.050227) (xy 405.880316 -302.074834) (xy 406.219164 -302.074834) (xy 406.223124 -302.02578)
			(xy 406.234901 -301.977996) (xy 406.254192 -301.93272) (xy 406.280495 -301.891124) (xy 406.31313 -301.854287)
			(xy 406.351251 -301.823162) (xy 406.393872 -301.798555) (xy 406.439888 -301.781103) (xy 406.488107 -301.771259)
			(xy 406.537282 -301.769278) (xy 406.586137 -301.77521) (xy 406.633408 -301.788902) (xy 406.67787 -301.81)
			(xy 406.718373 -301.837956) (xy 406.753866 -301.872048) (xy 406.783431 -301.911392) (xy 406.806302 -301.954969)
			(xy 406.821886 -302.00165) (xy 406.829781 -302.050227) (xy 406.830276 -302.074834) (xy 408.119084 -302.074834)
			(xy 408.123044 -302.02578) (xy 408.134821 -301.977996) (xy 408.154112 -301.93272) (xy 408.180415 -301.891124)
			(xy 408.21305 -301.854287) (xy 408.251171 -301.823162) (xy 408.293792 -301.798555) (xy 408.339808 -301.781103)
			(xy 408.388027 -301.771259) (xy 408.437202 -301.769278) (xy 408.486057 -301.77521) (xy 408.533328 -301.788902)
			(xy 408.57779 -301.81) (xy 408.618293 -301.837956) (xy 408.653786 -301.872048) (xy 408.683351 -301.911392)
			(xy 408.706222 -301.954969) (xy 408.721806 -302.00165) (xy 408.729701 -302.050227) (xy 408.730196 -302.074834)
			(xy 409.069044 -302.074834) (xy 409.073004 -302.02578) (xy 409.084781 -301.977996) (xy 409.104072 -301.93272)
			(xy 409.130375 -301.891124) (xy 409.16301 -301.854287) (xy 409.201131 -301.823162) (xy 409.243752 -301.798555)
			(xy 409.289768 -301.781103) (xy 409.337987 -301.771259) (xy 409.387162 -301.769278) (xy 409.436017 -301.77521)
			(xy 409.483288 -301.788902) (xy 409.52775 -301.81) (xy 409.568253 -301.837956) (xy 409.603746 -301.872048)
			(xy 409.633311 -301.911392) (xy 409.656182 -301.954969) (xy 409.671766 -302.00165) (xy 409.679661 -302.050227)
			(xy 409.680156 -302.074834) (xy 410.019004 -302.074834) (xy 410.022964 -302.02578) (xy 410.034741 -301.977996)
			(xy 410.054032 -301.93272) (xy 410.080335 -301.891124) (xy 410.11297 -301.854287) (xy 410.151091 -301.823162)
			(xy 410.193712 -301.798555) (xy 410.239728 -301.781103) (xy 410.287947 -301.771259) (xy 410.337122 -301.769278)
			(xy 410.385977 -301.77521) (xy 410.433248 -301.788902) (xy 410.47771 -301.81) (xy 410.518213 -301.837956)
			(xy 410.553706 -301.872048) (xy 410.583271 -301.911392) (xy 410.606142 -301.954969) (xy 410.621726 -302.00165)
			(xy 410.629621 -302.050227) (xy 410.630116 -302.074834) (xy 410.969218 -302.074834) (xy 410.973178 -302.02578)
			(xy 410.984955 -301.977996) (xy 411.004246 -301.93272) (xy 411.030549 -301.891124) (xy 411.063184 -301.854287)
			(xy 411.101305 -301.823162) (xy 411.143926 -301.798555) (xy 411.189942 -301.781103) (xy 411.238161 -301.771259)
			(xy 411.287336 -301.769278) (xy 411.336191 -301.77521) (xy 411.383462 -301.788902) (xy 411.427924 -301.81)
			(xy 411.468427 -301.837956) (xy 411.50392 -301.872048) (xy 411.533485 -301.911392) (xy 411.556356 -301.954969)
			(xy 411.57194 -302.00165) (xy 411.579835 -302.050227) (xy 411.58033 -302.074834) (xy 411.919178 -302.074834)
			(xy 411.923138 -302.02578) (xy 411.934915 -301.977996) (xy 411.954206 -301.93272) (xy 411.980509 -301.891124)
			(xy 412.013144 -301.854287) (xy 412.051265 -301.823162) (xy 412.093886 -301.798555) (xy 412.139902 -301.781103)
			(xy 412.188121 -301.771259) (xy 412.237296 -301.769278) (xy 412.286151 -301.77521) (xy 412.333422 -301.788902)
			(xy 412.377884 -301.81) (xy 412.418387 -301.837956) (xy 412.45388 -301.872048) (xy 412.483445 -301.911392)
			(xy 412.506316 -301.954969) (xy 412.5219 -302.00165) (xy 412.529795 -302.050227) (xy 412.53029 -302.074834)
			(xy 412.869138 -302.074834) (xy 412.873098 -302.02578) (xy 412.884875 -301.977996) (xy 412.904166 -301.93272)
			(xy 412.930469 -301.891124) (xy 412.963104 -301.854287) (xy 413.001225 -301.823162) (xy 413.043846 -301.798555)
			(xy 413.089862 -301.781103) (xy 413.138081 -301.771259) (xy 413.187256 -301.769278) (xy 413.236111 -301.77521)
			(xy 413.283382 -301.788902) (xy 413.327844 -301.81) (xy 413.368347 -301.837956) (xy 413.40384 -301.872048)
			(xy 413.433405 -301.911392) (xy 413.456276 -301.954969) (xy 413.47186 -302.00165) (xy 413.479755 -302.050227)
			(xy 413.48025 -302.074834) (xy 413.819098 -302.074834) (xy 413.823058 -302.02578) (xy 413.834835 -301.977996)
			(xy 413.854126 -301.93272) (xy 413.880429 -301.891124) (xy 413.913064 -301.854287) (xy 413.951185 -301.823162)
			(xy 413.993806 -301.798555) (xy 414.039822 -301.781103) (xy 414.088041 -301.771259) (xy 414.137216 -301.769278)
			(xy 414.186071 -301.77521) (xy 414.233342 -301.788902) (xy 414.277804 -301.81) (xy 414.318307 -301.837956)
			(xy 414.3538 -301.872048) (xy 414.383365 -301.911392) (xy 414.406236 -301.954969) (xy 414.42182 -302.00165)
			(xy 414.429715 -302.050227) (xy 414.43021 -302.074834) (xy 414.769058 -302.074834) (xy 414.773018 -302.02578)
			(xy 414.784795 -301.977996) (xy 414.804086 -301.93272) (xy 414.830389 -301.891124) (xy 414.863024 -301.854287)
			(xy 414.901145 -301.823162) (xy 414.943766 -301.798555) (xy 414.989782 -301.781103) (xy 415.038001 -301.771259)
			(xy 415.087176 -301.769278) (xy 415.136031 -301.77521) (xy 415.183302 -301.788902) (xy 415.227764 -301.81)
			(xy 415.268267 -301.837956) (xy 415.30376 -301.872048) (xy 415.333325 -301.911392) (xy 415.356196 -301.954969)
			(xy 415.37178 -302.00165) (xy 415.379675 -302.050227) (xy 415.38017 -302.074834) (xy 415.719018 -302.074834)
			(xy 415.722978 -302.02578) (xy 415.734755 -301.977996) (xy 415.754046 -301.93272) (xy 415.780349 -301.891124)
			(xy 415.812984 -301.854287) (xy 415.851105 -301.823162) (xy 415.893726 -301.798555) (xy 415.939742 -301.781103)
			(xy 415.987961 -301.771259) (xy 416.037136 -301.769278) (xy 416.085991 -301.77521) (xy 416.133262 -301.788902)
			(xy 416.177724 -301.81) (xy 416.218227 -301.837956) (xy 416.25372 -301.872048) (xy 416.283285 -301.911392)
			(xy 416.306156 -301.954969) (xy 416.32174 -302.00165) (xy 416.329635 -302.050227) (xy 416.33013 -302.074834)
			(xy 416.668978 -302.074834) (xy 416.672938 -302.02578) (xy 416.684715 -301.977996) (xy 416.704006 -301.93272)
			(xy 416.730309 -301.891124) (xy 416.762944 -301.854287) (xy 416.801065 -301.823162) (xy 416.843686 -301.798555)
			(xy 416.889702 -301.781103) (xy 416.937921 -301.771259) (xy 416.987096 -301.769278) (xy 417.035951 -301.77521)
			(xy 417.083222 -301.788902) (xy 417.127684 -301.81) (xy 417.168187 -301.837956) (xy 417.20368 -301.872048)
			(xy 417.233245 -301.911392) (xy 417.256116 -301.954969) (xy 417.2717 -302.00165) (xy 417.279595 -302.050227)
			(xy 417.28009 -302.074834) (xy 417.619192 -302.074834) (xy 417.623152 -302.02578) (xy 417.634929 -301.977996)
			(xy 417.65422 -301.93272) (xy 417.680523 -301.891124) (xy 417.713158 -301.854287) (xy 417.751279 -301.823162)
			(xy 417.7939 -301.798555) (xy 417.839916 -301.781103) (xy 417.888135 -301.771259) (xy 417.93731 -301.769278)
			(xy 417.986165 -301.77521) (xy 418.033436 -301.788902) (xy 418.077898 -301.81) (xy 418.118401 -301.837956)
			(xy 418.153894 -301.872048) (xy 418.183459 -301.911392) (xy 418.20633 -301.954969) (xy 418.221914 -302.00165)
			(xy 418.229809 -302.050227) (xy 418.230304 -302.074834) (xy 418.569152 -302.074834) (xy 418.573112 -302.02578)
			(xy 418.584889 -301.977996) (xy 418.60418 -301.93272) (xy 418.630483 -301.891124) (xy 418.663118 -301.854287)
			(xy 418.701239 -301.823162) (xy 418.74386 -301.798555) (xy 418.789876 -301.781103) (xy 418.838095 -301.771259)
			(xy 418.88727 -301.769278) (xy 418.936125 -301.77521) (xy 418.983396 -301.788902) (xy 419.027858 -301.81)
			(xy 419.068361 -301.837956) (xy 419.103854 -301.872048) (xy 419.133419 -301.911392) (xy 419.15629 -301.954969)
			(xy 419.171874 -302.00165) (xy 419.179769 -302.050227) (xy 419.180264 -302.074834) (xy 419.519112 -302.074834)
			(xy 419.523072 -302.02578) (xy 419.534849 -301.977996) (xy 419.55414 -301.93272) (xy 419.580443 -301.891124)
			(xy 419.613078 -301.854287) (xy 419.651199 -301.823162) (xy 419.69382 -301.798555) (xy 419.739836 -301.781103)
			(xy 419.788055 -301.771259) (xy 419.83723 -301.769278) (xy 419.886085 -301.77521) (xy 419.933356 -301.788902)
			(xy 419.977818 -301.81) (xy 420.018321 -301.837956) (xy 420.053814 -301.872048) (xy 420.083379 -301.911392)
			(xy 420.10625 -301.954969) (xy 420.121834 -302.00165) (xy 420.129729 -302.050227) (xy 420.130224 -302.074834)
			(xy 420.469072 -302.074834) (xy 420.473032 -302.02578) (xy 420.484809 -301.977996) (xy 420.5041 -301.93272)
			(xy 420.530403 -301.891124) (xy 420.563038 -301.854287) (xy 420.601159 -301.823162) (xy 420.64378 -301.798555)
			(xy 420.689796 -301.781103) (xy 420.738015 -301.771259) (xy 420.78719 -301.769278) (xy 420.836045 -301.77521)
			(xy 420.883316 -301.788902) (xy 420.927778 -301.81) (xy 420.968281 -301.837956) (xy 421.003774 -301.872048)
			(xy 421.033339 -301.911392) (xy 421.05621 -301.954969) (xy 421.071794 -302.00165) (xy 421.079689 -302.050227)
			(xy 421.080184 -302.074834) (xy 421.419032 -302.074834) (xy 421.422992 -302.02578) (xy 421.434769 -301.977996)
			(xy 421.45406 -301.93272) (xy 421.480363 -301.891124) (xy 421.512998 -301.854287) (xy 421.551119 -301.823162)
			(xy 421.59374 -301.798555) (xy 421.639756 -301.781103) (xy 421.687975 -301.771259) (xy 421.73715 -301.769278)
			(xy 421.786005 -301.77521) (xy 421.833276 -301.788902) (xy 421.877738 -301.81) (xy 421.918241 -301.837956)
			(xy 421.953734 -301.872048) (xy 421.983299 -301.911392) (xy 422.00617 -301.954969) (xy 422.021754 -302.00165)
			(xy 422.029649 -302.050227) (xy 422.030144 -302.074834) (xy 422.368992 -302.074834) (xy 422.372952 -302.02578)
			(xy 422.384729 -301.977996) (xy 422.40402 -301.93272) (xy 422.430323 -301.891124) (xy 422.462958 -301.854287)
			(xy 422.501079 -301.823162) (xy 422.5437 -301.798555) (xy 422.589716 -301.781103) (xy 422.637935 -301.771259)
			(xy 422.68711 -301.769278) (xy 422.735965 -301.77521) (xy 422.783236 -301.788902) (xy 422.827698 -301.81)
			(xy 422.868201 -301.837956) (xy 422.903694 -301.872048) (xy 422.933259 -301.911392) (xy 422.95613 -301.954969)
			(xy 422.971714 -302.00165) (xy 422.979609 -302.050227) (xy 422.980104 -302.074834) (xy 423.319206 -302.074834)
			(xy 423.323166 -302.02578) (xy 423.334943 -301.977996) (xy 423.354234 -301.93272) (xy 423.380537 -301.891124)
			(xy 423.413172 -301.854287) (xy 423.451293 -301.823162) (xy 423.493914 -301.798555) (xy 423.53993 -301.781103)
			(xy 423.588149 -301.771259) (xy 423.637324 -301.769278) (xy 423.686179 -301.77521) (xy 423.73345 -301.788902)
			(xy 423.777912 -301.81) (xy 423.818415 -301.837956) (xy 423.853908 -301.872048) (xy 423.883473 -301.911392)
			(xy 423.906344 -301.954969) (xy 423.921928 -302.00165) (xy 423.929823 -302.050227) (xy 423.930318 -302.074834)
			(xy 424.269166 -302.074834) (xy 424.273126 -302.02578) (xy 424.284903 -301.977996) (xy 424.304194 -301.93272)
			(xy 424.330497 -301.891124) (xy 424.363132 -301.854287) (xy 424.401253 -301.823162) (xy 424.443874 -301.798555)
			(xy 424.48989 -301.781103) (xy 424.538109 -301.771259) (xy 424.587284 -301.769278) (xy 424.636139 -301.77521)
			(xy 424.68341 -301.788902) (xy 424.727872 -301.81) (xy 424.768375 -301.837956) (xy 424.803868 -301.872048)
			(xy 424.833433 -301.911392) (xy 424.856304 -301.954969) (xy 424.871888 -302.00165) (xy 424.879783 -302.050227)
			(xy 424.880278 -302.074834) (xy 425.219126 -302.074834) (xy 425.223086 -302.02578) (xy 425.234863 -301.977996)
			(xy 425.254154 -301.93272) (xy 425.280457 -301.891124) (xy 425.313092 -301.854287) (xy 425.351213 -301.823162)
			(xy 425.393834 -301.798555) (xy 425.43985 -301.781103) (xy 425.488069 -301.771259) (xy 425.537244 -301.769278)
			(xy 425.586099 -301.77521) (xy 425.63337 -301.788902) (xy 425.677832 -301.81) (xy 425.718335 -301.837956)
			(xy 425.753828 -301.872048) (xy 425.783393 -301.911392) (xy 425.806264 -301.954969) (xy 425.821848 -302.00165)
			(xy 425.829743 -302.050227) (xy 425.830238 -302.074834) (xy 426.169086 -302.074834) (xy 426.173046 -302.02578)
			(xy 426.184823 -301.977996) (xy 426.204114 -301.93272) (xy 426.230417 -301.891124) (xy 426.263052 -301.854287)
			(xy 426.301173 -301.823162) (xy 426.343794 -301.798555) (xy 426.38981 -301.781103) (xy 426.438029 -301.771259)
			(xy 426.487204 -301.769278) (xy 426.536059 -301.77521) (xy 426.58333 -301.788902) (xy 426.627792 -301.81)
			(xy 426.668295 -301.837956) (xy 426.703788 -301.872048) (xy 426.733353 -301.911392) (xy 426.756224 -301.954969)
			(xy 426.771808 -302.00165) (xy 426.779703 -302.050227) (xy 426.780198 -302.074834) (xy 427.119046 -302.074834)
			(xy 427.123006 -302.02578) (xy 427.134783 -301.977996) (xy 427.154074 -301.93272) (xy 427.180377 -301.891124)
			(xy 427.213012 -301.854287) (xy 427.251133 -301.823162) (xy 427.293754 -301.798555) (xy 427.33977 -301.781103)
			(xy 427.387989 -301.771259) (xy 427.437164 -301.769278) (xy 427.486019 -301.77521) (xy 427.53329 -301.788902)
			(xy 427.577752 -301.81) (xy 427.618255 -301.837956) (xy 427.653748 -301.872048) (xy 427.683313 -301.911392)
			(xy 427.706184 -301.954969) (xy 427.721768 -302.00165) (xy 427.729663 -302.050227) (xy 427.730158 -302.074834)
			(xy 428.069006 -302.074834) (xy 428.072966 -302.02578) (xy 428.084743 -301.977996) (xy 428.104034 -301.93272)
			(xy 428.130337 -301.891124) (xy 428.162972 -301.854287) (xy 428.201093 -301.823162) (xy 428.243714 -301.798555)
			(xy 428.28973 -301.781103) (xy 428.337949 -301.771259) (xy 428.387124 -301.769278) (xy 428.435979 -301.77521)
			(xy 428.48325 -301.788902) (xy 428.527712 -301.81) (xy 428.568215 -301.837956) (xy 428.603708 -301.872048)
			(xy 428.633273 -301.911392) (xy 428.656144 -301.954969) (xy 428.671728 -302.00165) (xy 428.679623 -302.050227)
			(xy 428.680118 -302.074834) (xy 429.01922 -302.074834) (xy 429.02318 -302.02578) (xy 429.034957 -301.977996)
			(xy 429.054248 -301.93272) (xy 429.080551 -301.891124) (xy 429.113186 -301.854287) (xy 429.151307 -301.823162)
			(xy 429.193928 -301.798555) (xy 429.239944 -301.781103) (xy 429.288163 -301.771259) (xy 429.337338 -301.769278)
			(xy 429.386193 -301.77521) (xy 429.433464 -301.788902) (xy 429.477926 -301.81) (xy 429.518429 -301.837956)
			(xy 429.553922 -301.872048) (xy 429.583487 -301.911392) (xy 429.606358 -301.954969) (xy 429.621942 -302.00165)
			(xy 429.629837 -302.050227) (xy 429.630332 -302.074834) (xy 429.96918 -302.074834) (xy 429.97314 -302.02578)
			(xy 429.984917 -301.977996) (xy 430.004208 -301.93272) (xy 430.030511 -301.891124) (xy 430.063146 -301.854287)
			(xy 430.101267 -301.823162) (xy 430.143888 -301.798555) (xy 430.189904 -301.781103) (xy 430.238123 -301.771259)
			(xy 430.287298 -301.769278) (xy 430.336153 -301.77521) (xy 430.383424 -301.788902) (xy 430.427886 -301.81)
			(xy 430.468389 -301.837956) (xy 430.503882 -301.872048) (xy 430.533447 -301.911392) (xy 430.556318 -301.954969)
			(xy 430.571902 -302.00165) (xy 430.579797 -302.050227) (xy 430.580292 -302.074834) (xy 430.91914 -302.074834)
			(xy 430.9231 -302.02578) (xy 430.934877 -301.977996) (xy 430.954168 -301.93272) (xy 430.980471 -301.891124)
			(xy 431.013106 -301.854287) (xy 431.051227 -301.823162) (xy 431.093848 -301.798555) (xy 431.139864 -301.781103)
			(xy 431.188083 -301.771259) (xy 431.237258 -301.769278) (xy 431.286113 -301.77521) (xy 431.333384 -301.788902)
			(xy 431.377846 -301.81) (xy 431.418349 -301.837956) (xy 431.453842 -301.872048) (xy 431.483407 -301.911392)
			(xy 431.506278 -301.954969) (xy 431.521862 -302.00165) (xy 431.529757 -302.050227) (xy 431.529997 -302.062134)
			(xy 433.675788 -302.062134) (xy 433.679859 -302.006512) (xy 433.691985 -301.952075) (xy 433.711908 -301.899984)
			(xy 433.739204 -301.851349) (xy 433.77329 -301.807206) (xy 433.813439 -301.768497) (xy 433.858797 -301.736046)
			(xy 433.908397 -301.710545) (xy 433.961181 -301.692538) (xy 434.016024 -301.682408) (xy 434.071758 -301.680371)
			(xy 434.127195 -301.686471) (xy 434.181152 -301.700577) (xy 434.232481 -301.722389) (xy 434.280087 -301.751443)
			(xy 434.322955 -301.787118) (xy 434.360172 -301.828655) (xy 434.390945 -301.875168) (xy 434.392741 -301.879)
			(xy 434.647592 -301.879) (xy 434.651663 -301.823378) (xy 434.663789 -301.768941) (xy 434.683712 -301.71685)
			(xy 434.711008 -301.668215) (xy 434.745094 -301.624072) (xy 434.785243 -301.585363) (xy 434.830601 -301.552912)
			(xy 434.880201 -301.527411) (xy 434.932985 -301.509404) (xy 434.987828 -301.499274) (xy 435.043562 -301.497237)
			(xy 435.098999 -301.503337) (xy 435.152956 -301.517443) (xy 435.204285 -301.539255) (xy 435.226168 -301.55261)
			(xy 436.41975 -301.55261) (xy 436.423821 -301.496988) (xy 436.435947 -301.442551) (xy 436.45587 -301.39046)
			(xy 436.483166 -301.341825) (xy 436.517252 -301.297682) (xy 436.557401 -301.258973) (xy 436.602759 -301.226522)
			(xy 436.652359 -301.201021) (xy 436.705143 -301.183014) (xy 436.759986 -301.172884) (xy 436.81572 -301.170847)
			(xy 436.871157 -301.176947) (xy 436.925114 -301.191053) (xy 436.976443 -301.212865) (xy 437.024049 -301.241919)
			(xy 437.066917 -301.277594) (xy 437.104134 -301.319131) (xy 437.134907 -301.365644) (xy 437.158579 -301.416141)
			(xy 437.174647 -301.469548) (xy 437.182767 -301.524724) (xy 437.183276 -301.55261) (xy 437.182836 -301.57674)
			(xy 439.81319 -301.57674) (xy 439.817261 -301.521118) (xy 439.829387 -301.466681) (xy 439.84931 -301.41459)
			(xy 439.876606 -301.365955) (xy 439.910692 -301.321812) (xy 439.950841 -301.283103) (xy 439.996199 -301.250652)
			(xy 440.045799 -301.225151) (xy 440.098583 -301.207144) (xy 440.153426 -301.197014) (xy 440.20916 -301.194977)
			(xy 440.264597 -301.201077) (xy 440.318554 -301.215183) (xy 440.369883 -301.236995) (xy 440.417489 -301.266049)
			(xy 440.460357 -301.301724) (xy 440.497574 -301.343261) (xy 440.528347 -301.389774) (xy 440.552019 -301.440271)
			(xy 440.568087 -301.493678) (xy 440.576207 -301.548854) (xy 440.576716 -301.57674) (xy 440.576207 -301.604626)
			(xy 440.568087 -301.659802) (xy 440.552019 -301.713209) (xy 440.528347 -301.763706) (xy 440.497574 -301.810219)
			(xy 440.460357 -301.851756) (xy 440.417489 -301.887431) (xy 440.369883 -301.916485) (xy 440.318554 -301.938297)
			(xy 440.264597 -301.952403) (xy 440.20916 -301.958503) (xy 440.153426 -301.956466) (xy 440.098583 -301.946336)
			(xy 440.045799 -301.928329) (xy 439.996199 -301.902828) (xy 439.950841 -301.870377) (xy 439.910692 -301.831668)
			(xy 439.876606 -301.787525) (xy 439.84931 -301.73889) (xy 439.829387 -301.686799) (xy 439.817261 -301.632362)
			(xy 439.81319 -301.57674) (xy 437.182836 -301.57674) (xy 437.182767 -301.580496) (xy 437.174647 -301.635672)
			(xy 437.158579 -301.689079) (xy 437.134907 -301.739576) (xy 437.104134 -301.786089) (xy 437.066917 -301.827626)
			(xy 437.024049 -301.863301) (xy 436.976443 -301.892355) (xy 436.925114 -301.914167) (xy 436.871157 -301.928273)
			(xy 436.81572 -301.934373) (xy 436.759986 -301.932336) (xy 436.705143 -301.922206) (xy 436.652359 -301.904199)
			(xy 436.602759 -301.878698) (xy 436.557401 -301.846247) (xy 436.517252 -301.807538) (xy 436.483166 -301.763395)
			(xy 436.45587 -301.71476) (xy 436.435947 -301.662669) (xy 436.423821 -301.608232) (xy 436.41975 -301.55261)
			(xy 435.226168 -301.55261) (xy 435.251891 -301.568309) (xy 435.294759 -301.603984) (xy 435.331976 -301.645521)
			(xy 435.362749 -301.692034) (xy 435.386421 -301.742531) (xy 435.402489 -301.795938) (xy 435.410609 -301.851114)
			(xy 435.411118 -301.879) (xy 435.410609 -301.906886) (xy 435.402489 -301.962062) (xy 435.386421 -302.015469)
			(xy 435.362749 -302.065966) (xy 435.331976 -302.112479) (xy 435.294759 -302.154016) (xy 435.251891 -302.189691)
			(xy 435.204285 -302.218745) (xy 435.152956 -302.240557) (xy 435.098999 -302.254663) (xy 435.043562 -302.260763)
			(xy 434.987828 -302.258726) (xy 434.932985 -302.248596) (xy 434.880201 -302.230589) (xy 434.830601 -302.205088)
			(xy 434.785243 -302.172637) (xy 434.745094 -302.133928) (xy 434.711008 -302.089785) (xy 434.683712 -302.04115)
			(xy 434.663789 -301.989059) (xy 434.651663 -301.934622) (xy 434.647592 -301.879) (xy 434.392741 -301.879)
			(xy 434.414617 -301.925665) (xy 434.430685 -301.979072) (xy 434.438805 -302.034248) (xy 434.439314 -302.062134)
			(xy 434.438805 -302.09002) (xy 434.430685 -302.145196) (xy 434.414617 -302.198603) (xy 434.390945 -302.2491)
			(xy 434.360172 -302.295613) (xy 434.322955 -302.33715) (xy 434.280087 -302.372825) (xy 434.232481 -302.401879)
			(xy 434.181152 -302.423691) (xy 434.127195 -302.437797) (xy 434.071758 -302.443897) (xy 434.016024 -302.44186)
			(xy 433.961181 -302.43173) (xy 433.908397 -302.413723) (xy 433.858797 -302.388222) (xy 433.813439 -302.355771)
			(xy 433.77329 -302.317062) (xy 433.739204 -302.272919) (xy 433.711908 -302.224284) (xy 433.691985 -302.172193)
			(xy 433.679859 -302.117756) (xy 433.675788 -302.062134) (xy 431.529997 -302.062134) (xy 431.530252 -302.074834)
			(xy 431.529757 -302.099441) (xy 431.521862 -302.148018) (xy 431.506278 -302.194699) (xy 431.483407 -302.238276)
			(xy 431.453842 -302.27762) (xy 431.418349 -302.311712) (xy 431.377846 -302.339668) (xy 431.333384 -302.360766)
			(xy 431.286113 -302.374458) (xy 431.237258 -302.38039) (xy 431.188083 -302.378409) (xy 431.139864 -302.368565)
			(xy 431.093848 -302.351113) (xy 431.051227 -302.326506) (xy 431.013106 -302.295381) (xy 430.980471 -302.258544)
			(xy 430.954168 -302.216948) (xy 430.934877 -302.171672) (xy 430.9231 -302.123888) (xy 430.91914 -302.074834)
			(xy 430.580292 -302.074834) (xy 430.579797 -302.099441) (xy 430.571902 -302.148018) (xy 430.556318 -302.194699)
			(xy 430.533447 -302.238276) (xy 430.503882 -302.27762) (xy 430.468389 -302.311712) (xy 430.427886 -302.339668)
			(xy 430.383424 -302.360766) (xy 430.336153 -302.374458) (xy 430.287298 -302.38039) (xy 430.238123 -302.378409)
			(xy 430.189904 -302.368565) (xy 430.143888 -302.351113) (xy 430.101267 -302.326506) (xy 430.063146 -302.295381)
			(xy 430.030511 -302.258544) (xy 430.004208 -302.216948) (xy 429.984917 -302.171672) (xy 429.97314 -302.123888)
			(xy 429.96918 -302.074834) (xy 429.630332 -302.074834) (xy 429.629837 -302.099441) (xy 429.621942 -302.148018)
			(xy 429.606358 -302.194699) (xy 429.583487 -302.238276) (xy 429.553922 -302.27762) (xy 429.518429 -302.311712)
			(xy 429.477926 -302.339668) (xy 429.433464 -302.360766) (xy 429.386193 -302.374458) (xy 429.337338 -302.38039)
			(xy 429.288163 -302.378409) (xy 429.239944 -302.368565) (xy 429.193928 -302.351113) (xy 429.151307 -302.326506)
			(xy 429.113186 -302.295381) (xy 429.080551 -302.258544) (xy 429.054248 -302.216948) (xy 429.034957 -302.171672)
			(xy 429.02318 -302.123888) (xy 429.01922 -302.074834) (xy 428.680118 -302.074834) (xy 428.679623 -302.099441)
			(xy 428.671728 -302.148018) (xy 428.656144 -302.194699) (xy 428.633273 -302.238276) (xy 428.603708 -302.27762)
			(xy 428.568215 -302.311712) (xy 428.527712 -302.339668) (xy 428.48325 -302.360766) (xy 428.435979 -302.374458)
			(xy 428.387124 -302.38039) (xy 428.337949 -302.378409) (xy 428.28973 -302.368565) (xy 428.243714 -302.351113)
			(xy 428.201093 -302.326506) (xy 428.162972 -302.295381) (xy 428.130337 -302.258544) (xy 428.104034 -302.216948)
			(xy 428.084743 -302.171672) (xy 428.072966 -302.123888) (xy 428.069006 -302.074834) (xy 427.730158 -302.074834)
			(xy 427.729663 -302.099441) (xy 427.721768 -302.148018) (xy 427.706184 -302.194699) (xy 427.683313 -302.238276)
			(xy 427.653748 -302.27762) (xy 427.618255 -302.311712) (xy 427.577752 -302.339668) (xy 427.53329 -302.360766)
			(xy 427.486019 -302.374458) (xy 427.437164 -302.38039) (xy 427.387989 -302.378409) (xy 427.33977 -302.368565)
			(xy 427.293754 -302.351113) (xy 427.251133 -302.326506) (xy 427.213012 -302.295381) (xy 427.180377 -302.258544)
			(xy 427.154074 -302.216948) (xy 427.134783 -302.171672) (xy 427.123006 -302.123888) (xy 427.119046 -302.074834)
			(xy 426.780198 -302.074834) (xy 426.779703 -302.099441) (xy 426.771808 -302.148018) (xy 426.756224 -302.194699)
			(xy 426.733353 -302.238276) (xy 426.703788 -302.27762) (xy 426.668295 -302.311712) (xy 426.627792 -302.339668)
			(xy 426.58333 -302.360766) (xy 426.536059 -302.374458) (xy 426.487204 -302.38039) (xy 426.438029 -302.378409)
			(xy 426.38981 -302.368565) (xy 426.343794 -302.351113) (xy 426.301173 -302.326506) (xy 426.263052 -302.295381)
			(xy 426.230417 -302.258544) (xy 426.204114 -302.216948) (xy 426.184823 -302.171672) (xy 426.173046 -302.123888)
			(xy 426.169086 -302.074834) (xy 425.830238 -302.074834) (xy 425.829743 -302.099441) (xy 425.821848 -302.148018)
			(xy 425.806264 -302.194699) (xy 425.783393 -302.238276) (xy 425.753828 -302.27762) (xy 425.718335 -302.311712)
			(xy 425.677832 -302.339668) (xy 425.63337 -302.360766) (xy 425.586099 -302.374458) (xy 425.537244 -302.38039)
			(xy 425.488069 -302.378409) (xy 425.43985 -302.368565) (xy 425.393834 -302.351113) (xy 425.351213 -302.326506)
			(xy 425.313092 -302.295381) (xy 425.280457 -302.258544) (xy 425.254154 -302.216948) (xy 425.234863 -302.171672)
			(xy 425.223086 -302.123888) (xy 425.219126 -302.074834) (xy 424.880278 -302.074834) (xy 424.879783 -302.099441)
			(xy 424.871888 -302.148018) (xy 424.856304 -302.194699) (xy 424.833433 -302.238276) (xy 424.803868 -302.27762)
			(xy 424.768375 -302.311712) (xy 424.727872 -302.339668) (xy 424.68341 -302.360766) (xy 424.636139 -302.374458)
			(xy 424.587284 -302.38039) (xy 424.538109 -302.378409) (xy 424.48989 -302.368565) (xy 424.443874 -302.351113)
			(xy 424.401253 -302.326506) (xy 424.363132 -302.295381) (xy 424.330497 -302.258544) (xy 424.304194 -302.216948)
			(xy 424.284903 -302.171672) (xy 424.273126 -302.123888) (xy 424.269166 -302.074834) (xy 423.930318 -302.074834)
			(xy 423.929823 -302.099441) (xy 423.921928 -302.148018) (xy 423.906344 -302.194699) (xy 423.883473 -302.238276)
			(xy 423.853908 -302.27762) (xy 423.818415 -302.311712) (xy 423.777912 -302.339668) (xy 423.73345 -302.360766)
			(xy 423.686179 -302.374458) (xy 423.637324 -302.38039) (xy 423.588149 -302.378409) (xy 423.53993 -302.368565)
			(xy 423.493914 -302.351113) (xy 423.451293 -302.326506) (xy 423.413172 -302.295381) (xy 423.380537 -302.258544)
			(xy 423.354234 -302.216948) (xy 423.334943 -302.171672) (xy 423.323166 -302.123888) (xy 423.319206 -302.074834)
			(xy 422.980104 -302.074834) (xy 422.979609 -302.099441) (xy 422.971714 -302.148018) (xy 422.95613 -302.194699)
			(xy 422.933259 -302.238276) (xy 422.903694 -302.27762) (xy 422.868201 -302.311712) (xy 422.827698 -302.339668)
			(xy 422.783236 -302.360766) (xy 422.735965 -302.374458) (xy 422.68711 -302.38039) (xy 422.637935 -302.378409)
			(xy 422.589716 -302.368565) (xy 422.5437 -302.351113) (xy 422.501079 -302.326506) (xy 422.462958 -302.295381)
			(xy 422.430323 -302.258544) (xy 422.40402 -302.216948) (xy 422.384729 -302.171672) (xy 422.372952 -302.123888)
			(xy 422.368992 -302.074834) (xy 422.030144 -302.074834) (xy 422.029649 -302.099441) (xy 422.021754 -302.148018)
			(xy 422.00617 -302.194699) (xy 421.983299 -302.238276) (xy 421.953734 -302.27762) (xy 421.918241 -302.311712)
			(xy 421.877738 -302.339668) (xy 421.833276 -302.360766) (xy 421.786005 -302.374458) (xy 421.73715 -302.38039)
			(xy 421.687975 -302.378409) (xy 421.639756 -302.368565) (xy 421.59374 -302.351113) (xy 421.551119 -302.326506)
			(xy 421.512998 -302.295381) (xy 421.480363 -302.258544) (xy 421.45406 -302.216948) (xy 421.434769 -302.171672)
			(xy 421.422992 -302.123888) (xy 421.419032 -302.074834) (xy 421.080184 -302.074834) (xy 421.079689 -302.099441)
			(xy 421.071794 -302.148018) (xy 421.05621 -302.194699) (xy 421.033339 -302.238276) (xy 421.003774 -302.27762)
			(xy 420.968281 -302.311712) (xy 420.927778 -302.339668) (xy 420.883316 -302.360766) (xy 420.836045 -302.374458)
			(xy 420.78719 -302.38039) (xy 420.738015 -302.378409) (xy 420.689796 -302.368565) (xy 420.64378 -302.351113)
			(xy 420.601159 -302.326506) (xy 420.563038 -302.295381) (xy 420.530403 -302.258544) (xy 420.5041 -302.216948)
			(xy 420.484809 -302.171672) (xy 420.473032 -302.123888) (xy 420.469072 -302.074834) (xy 420.130224 -302.074834)
			(xy 420.129729 -302.099441) (xy 420.121834 -302.148018) (xy 420.10625 -302.194699) (xy 420.083379 -302.238276)
			(xy 420.053814 -302.27762) (xy 420.018321 -302.311712) (xy 419.977818 -302.339668) (xy 419.933356 -302.360766)
			(xy 419.886085 -302.374458) (xy 419.83723 -302.38039) (xy 419.788055 -302.378409) (xy 419.739836 -302.368565)
			(xy 419.69382 -302.351113) (xy 419.651199 -302.326506) (xy 419.613078 -302.295381) (xy 419.580443 -302.258544)
			(xy 419.55414 -302.216948) (xy 419.534849 -302.171672) (xy 419.523072 -302.123888) (xy 419.519112 -302.074834)
			(xy 419.180264 -302.074834) (xy 419.179769 -302.099441) (xy 419.171874 -302.148018) (xy 419.15629 -302.194699)
			(xy 419.133419 -302.238276) (xy 419.103854 -302.27762) (xy 419.068361 -302.311712) (xy 419.027858 -302.339668)
			(xy 418.983396 -302.360766) (xy 418.936125 -302.374458) (xy 418.88727 -302.38039) (xy 418.838095 -302.378409)
			(xy 418.789876 -302.368565) (xy 418.74386 -302.351113) (xy 418.701239 -302.326506) (xy 418.663118 -302.295381)
			(xy 418.630483 -302.258544) (xy 418.60418 -302.216948) (xy 418.584889 -302.171672) (xy 418.573112 -302.123888)
			(xy 418.569152 -302.074834) (xy 418.230304 -302.074834) (xy 418.229809 -302.099441) (xy 418.221914 -302.148018)
			(xy 418.20633 -302.194699) (xy 418.183459 -302.238276) (xy 418.153894 -302.27762) (xy 418.118401 -302.311712)
			(xy 418.077898 -302.339668) (xy 418.033436 -302.360766) (xy 417.986165 -302.374458) (xy 417.93731 -302.38039)
			(xy 417.888135 -302.378409) (xy 417.839916 -302.368565) (xy 417.7939 -302.351113) (xy 417.751279 -302.326506)
			(xy 417.713158 -302.295381) (xy 417.680523 -302.258544) (xy 417.65422 -302.216948) (xy 417.634929 -302.171672)
			(xy 417.623152 -302.123888) (xy 417.619192 -302.074834) (xy 417.28009 -302.074834) (xy 417.279595 -302.099441)
			(xy 417.2717 -302.148018) (xy 417.256116 -302.194699) (xy 417.233245 -302.238276) (xy 417.20368 -302.27762)
			(xy 417.168187 -302.311712) (xy 417.127684 -302.339668) (xy 417.083222 -302.360766) (xy 417.035951 -302.374458)
			(xy 416.987096 -302.38039) (xy 416.937921 -302.378409) (xy 416.889702 -302.368565) (xy 416.843686 -302.351113)
			(xy 416.801065 -302.326506) (xy 416.762944 -302.295381) (xy 416.730309 -302.258544) (xy 416.704006 -302.216948)
			(xy 416.684715 -302.171672) (xy 416.672938 -302.123888) (xy 416.668978 -302.074834) (xy 416.33013 -302.074834)
			(xy 416.329635 -302.099441) (xy 416.32174 -302.148018) (xy 416.306156 -302.194699) (xy 416.283285 -302.238276)
			(xy 416.25372 -302.27762) (xy 416.218227 -302.311712) (xy 416.177724 -302.339668) (xy 416.133262 -302.360766)
			(xy 416.085991 -302.374458) (xy 416.037136 -302.38039) (xy 415.987961 -302.378409) (xy 415.939742 -302.368565)
			(xy 415.893726 -302.351113) (xy 415.851105 -302.326506) (xy 415.812984 -302.295381) (xy 415.780349 -302.258544)
			(xy 415.754046 -302.216948) (xy 415.734755 -302.171672) (xy 415.722978 -302.123888) (xy 415.719018 -302.074834)
			(xy 415.38017 -302.074834) (xy 415.379675 -302.099441) (xy 415.37178 -302.148018) (xy 415.356196 -302.194699)
			(xy 415.333325 -302.238276) (xy 415.30376 -302.27762) (xy 415.268267 -302.311712) (xy 415.227764 -302.339668)
			(xy 415.183302 -302.360766) (xy 415.136031 -302.374458) (xy 415.087176 -302.38039) (xy 415.038001 -302.378409)
			(xy 414.989782 -302.368565) (xy 414.943766 -302.351113) (xy 414.901145 -302.326506) (xy 414.863024 -302.295381)
			(xy 414.830389 -302.258544) (xy 414.804086 -302.216948) (xy 414.784795 -302.171672) (xy 414.773018 -302.123888)
			(xy 414.769058 -302.074834) (xy 414.43021 -302.074834) (xy 414.429715 -302.099441) (xy 414.42182 -302.148018)
			(xy 414.406236 -302.194699) (xy 414.383365 -302.238276) (xy 414.3538 -302.27762) (xy 414.318307 -302.311712)
			(xy 414.277804 -302.339668) (xy 414.233342 -302.360766) (xy 414.186071 -302.374458) (xy 414.137216 -302.38039)
			(xy 414.088041 -302.378409) (xy 414.039822 -302.368565) (xy 413.993806 -302.351113) (xy 413.951185 -302.326506)
			(xy 413.913064 -302.295381) (xy 413.880429 -302.258544) (xy 413.854126 -302.216948) (xy 413.834835 -302.171672)
			(xy 413.823058 -302.123888) (xy 413.819098 -302.074834) (xy 413.48025 -302.074834) (xy 413.479755 -302.099441)
			(xy 413.47186 -302.148018) (xy 413.456276 -302.194699) (xy 413.433405 -302.238276) (xy 413.40384 -302.27762)
			(xy 413.368347 -302.311712) (xy 413.327844 -302.339668) (xy 413.283382 -302.360766) (xy 413.236111 -302.374458)
			(xy 413.187256 -302.38039) (xy 413.138081 -302.378409) (xy 413.089862 -302.368565) (xy 413.043846 -302.351113)
			(xy 413.001225 -302.326506) (xy 412.963104 -302.295381) (xy 412.930469 -302.258544) (xy 412.904166 -302.216948)
			(xy 412.884875 -302.171672) (xy 412.873098 -302.123888) (xy 412.869138 -302.074834) (xy 412.53029 -302.074834)
			(xy 412.529795 -302.099441) (xy 412.5219 -302.148018) (xy 412.506316 -302.194699) (xy 412.483445 -302.238276)
			(xy 412.45388 -302.27762) (xy 412.418387 -302.311712) (xy 412.377884 -302.339668) (xy 412.333422 -302.360766)
			(xy 412.286151 -302.374458) (xy 412.237296 -302.38039) (xy 412.188121 -302.378409) (xy 412.139902 -302.368565)
			(xy 412.093886 -302.351113) (xy 412.051265 -302.326506) (xy 412.013144 -302.295381) (xy 411.980509 -302.258544)
			(xy 411.954206 -302.216948) (xy 411.934915 -302.171672) (xy 411.923138 -302.123888) (xy 411.919178 -302.074834)
			(xy 411.58033 -302.074834) (xy 411.579835 -302.099441) (xy 411.57194 -302.148018) (xy 411.556356 -302.194699)
			(xy 411.533485 -302.238276) (xy 411.50392 -302.27762) (xy 411.468427 -302.311712) (xy 411.427924 -302.339668)
			(xy 411.383462 -302.360766) (xy 411.336191 -302.374458) (xy 411.287336 -302.38039) (xy 411.238161 -302.378409)
			(xy 411.189942 -302.368565) (xy 411.143926 -302.351113) (xy 411.101305 -302.326506) (xy 411.063184 -302.295381)
			(xy 411.030549 -302.258544) (xy 411.004246 -302.216948) (xy 410.984955 -302.171672) (xy 410.973178 -302.123888)
			(xy 410.969218 -302.074834) (xy 410.630116 -302.074834) (xy 410.629621 -302.099441) (xy 410.621726 -302.148018)
			(xy 410.606142 -302.194699) (xy 410.583271 -302.238276) (xy 410.553706 -302.27762) (xy 410.518213 -302.311712)
			(xy 410.47771 -302.339668) (xy 410.433248 -302.360766) (xy 410.385977 -302.374458) (xy 410.337122 -302.38039)
			(xy 410.287947 -302.378409) (xy 410.239728 -302.368565) (xy 410.193712 -302.351113) (xy 410.151091 -302.326506)
			(xy 410.11297 -302.295381) (xy 410.080335 -302.258544) (xy 410.054032 -302.216948) (xy 410.034741 -302.171672)
			(xy 410.022964 -302.123888) (xy 410.019004 -302.074834) (xy 409.680156 -302.074834) (xy 409.679661 -302.099441)
			(xy 409.671766 -302.148018) (xy 409.656182 -302.194699) (xy 409.633311 -302.238276) (xy 409.603746 -302.27762)
			(xy 409.568253 -302.311712) (xy 409.52775 -302.339668) (xy 409.483288 -302.360766) (xy 409.436017 -302.374458)
			(xy 409.387162 -302.38039) (xy 409.337987 -302.378409) (xy 409.289768 -302.368565) (xy 409.243752 -302.351113)
			(xy 409.201131 -302.326506) (xy 409.16301 -302.295381) (xy 409.130375 -302.258544) (xy 409.104072 -302.216948)
			(xy 409.084781 -302.171672) (xy 409.073004 -302.123888) (xy 409.069044 -302.074834) (xy 408.730196 -302.074834)
			(xy 408.729701 -302.099441) (xy 408.721806 -302.148018) (xy 408.706222 -302.194699) (xy 408.683351 -302.238276)
			(xy 408.653786 -302.27762) (xy 408.618293 -302.311712) (xy 408.57779 -302.339668) (xy 408.533328 -302.360766)
			(xy 408.486057 -302.374458) (xy 408.437202 -302.38039) (xy 408.388027 -302.378409) (xy 408.339808 -302.368565)
			(xy 408.293792 -302.351113) (xy 408.251171 -302.326506) (xy 408.21305 -302.295381) (xy 408.180415 -302.258544)
			(xy 408.154112 -302.216948) (xy 408.134821 -302.171672) (xy 408.123044 -302.123888) (xy 408.119084 -302.074834)
			(xy 406.830276 -302.074834) (xy 406.829781 -302.099441) (xy 406.821886 -302.148018) (xy 406.806302 -302.194699)
			(xy 406.783431 -302.238276) (xy 406.753866 -302.27762) (xy 406.718373 -302.311712) (xy 406.67787 -302.339668)
			(xy 406.633408 -302.360766) (xy 406.586137 -302.374458) (xy 406.537282 -302.38039) (xy 406.488107 -302.378409)
			(xy 406.439888 -302.368565) (xy 406.393872 -302.351113) (xy 406.351251 -302.326506) (xy 406.31313 -302.295381)
			(xy 406.280495 -302.258544) (xy 406.254192 -302.216948) (xy 406.234901 -302.171672) (xy 406.223124 -302.123888)
			(xy 406.219164 -302.074834) (xy 405.880316 -302.074834) (xy 405.879821 -302.099441) (xy 405.871926 -302.148018)
			(xy 405.856342 -302.194699) (xy 405.833471 -302.238276) (xy 405.803906 -302.27762) (xy 405.768413 -302.311712)
			(xy 405.72791 -302.339668) (xy 405.683448 -302.360766) (xy 405.636177 -302.374458) (xy 405.587322 -302.38039)
			(xy 405.538147 -302.378409) (xy 405.489928 -302.368565) (xy 405.443912 -302.351113) (xy 405.401291 -302.326506)
			(xy 405.36317 -302.295381) (xy 405.330535 -302.258544) (xy 405.304232 -302.216948) (xy 405.284941 -302.171672)
			(xy 405.273164 -302.123888) (xy 405.269204 -302.074834) (xy 404.930102 -302.074834) (xy 404.929607 -302.099441)
			(xy 404.921712 -302.148018) (xy 404.906128 -302.194699) (xy 404.883257 -302.238276) (xy 404.853692 -302.27762)
			(xy 404.818199 -302.311712) (xy 404.777696 -302.339668) (xy 404.733234 -302.360766) (xy 404.685963 -302.374458)
			(xy 404.637108 -302.38039) (xy 404.587933 -302.378409) (xy 404.539714 -302.368565) (xy 404.493698 -302.351113)
			(xy 404.451077 -302.326506) (xy 404.412956 -302.295381) (xy 404.380321 -302.258544) (xy 404.354018 -302.216948)
			(xy 404.334727 -302.171672) (xy 404.32295 -302.123888) (xy 404.31899 -302.074834) (xy 403.980142 -302.074834)
			(xy 403.979647 -302.099441) (xy 403.971752 -302.148018) (xy 403.956168 -302.194699) (xy 403.933297 -302.238276)
			(xy 403.903732 -302.27762) (xy 403.868239 -302.311712) (xy 403.827736 -302.339668) (xy 403.783274 -302.360766)
			(xy 403.736003 -302.374458) (xy 403.687148 -302.38039) (xy 403.637973 -302.378409) (xy 403.589754 -302.368565)
			(xy 403.543738 -302.351113) (xy 403.501117 -302.326506) (xy 403.462996 -302.295381) (xy 403.430361 -302.258544)
			(xy 403.404058 -302.216948) (xy 403.384767 -302.171672) (xy 403.37299 -302.123888) (xy 403.36903 -302.074834)
			(xy 403.030182 -302.074834) (xy 403.029687 -302.099441) (xy 403.021792 -302.148018) (xy 403.006208 -302.194699)
			(xy 402.983337 -302.238276) (xy 402.953772 -302.27762) (xy 402.918279 -302.311712) (xy 402.877776 -302.339668)
			(xy 402.833314 -302.360766) (xy 402.786043 -302.374458) (xy 402.737188 -302.38039) (xy 402.688013 -302.378409)
			(xy 402.639794 -302.368565) (xy 402.593778 -302.351113) (xy 402.551157 -302.326506) (xy 402.513036 -302.295381)
			(xy 402.480401 -302.258544) (xy 402.454098 -302.216948) (xy 402.434807 -302.171672) (xy 402.42303 -302.123888)
			(xy 402.41907 -302.074834) (xy 402.080222 -302.074834) (xy 402.079727 -302.099441) (xy 402.071832 -302.148018)
			(xy 402.056248 -302.194699) (xy 402.033377 -302.238276) (xy 402.003812 -302.27762) (xy 401.968319 -302.311712)
			(xy 401.927816 -302.339668) (xy 401.883354 -302.360766) (xy 401.836083 -302.374458) (xy 401.787228 -302.38039)
			(xy 401.738053 -302.378409) (xy 401.689834 -302.368565) (xy 401.643818 -302.351113) (xy 401.601197 -302.326506)
			(xy 401.563076 -302.295381) (xy 401.530441 -302.258544) (xy 401.504138 -302.216948) (xy 401.484847 -302.171672)
			(xy 401.47307 -302.123888) (xy 401.46911 -302.074834) (xy 401.130262 -302.074834) (xy 401.129767 -302.099441)
			(xy 401.121872 -302.148018) (xy 401.106288 -302.194699) (xy 401.083417 -302.238276) (xy 401.053852 -302.27762)
			(xy 401.018359 -302.311712) (xy 400.977856 -302.339668) (xy 400.933394 -302.360766) (xy 400.886123 -302.374458)
			(xy 400.837268 -302.38039) (xy 400.788093 -302.378409) (xy 400.739874 -302.368565) (xy 400.693858 -302.351113)
			(xy 400.651237 -302.326506) (xy 400.613116 -302.295381) (xy 400.580481 -302.258544) (xy 400.554178 -302.216948)
			(xy 400.534887 -302.171672) (xy 400.52311 -302.123888) (xy 400.51915 -302.074834) (xy 400.180302 -302.074834)
			(xy 400.179807 -302.099441) (xy 400.171912 -302.148018) (xy 400.156328 -302.194699) (xy 400.133457 -302.238276)
			(xy 400.103892 -302.27762) (xy 400.068399 -302.311712) (xy 400.027896 -302.339668) (xy 399.983434 -302.360766)
			(xy 399.936163 -302.374458) (xy 399.887308 -302.38039) (xy 399.838133 -302.378409) (xy 399.789914 -302.368565)
			(xy 399.743898 -302.351113) (xy 399.701277 -302.326506) (xy 399.663156 -302.295381) (xy 399.630521 -302.258544)
			(xy 399.604218 -302.216948) (xy 399.584927 -302.171672) (xy 399.57315 -302.123888) (xy 399.56919 -302.074834)
			(xy 399.230342 -302.074834) (xy 399.229847 -302.099441) (xy 399.221952 -302.148018) (xy 399.206368 -302.194699)
			(xy 399.183497 -302.238276) (xy 399.153932 -302.27762) (xy 399.118439 -302.311712) (xy 399.077936 -302.339668)
			(xy 399.033474 -302.360766) (xy 398.986203 -302.374458) (xy 398.937348 -302.38039) (xy 398.888173 -302.378409)
			(xy 398.839954 -302.368565) (xy 398.793938 -302.351113) (xy 398.751317 -302.326506) (xy 398.713196 -302.295381)
			(xy 398.680561 -302.258544) (xy 398.654258 -302.216948) (xy 398.634967 -302.171672) (xy 398.62319 -302.123888)
			(xy 398.61923 -302.074834) (xy 398.32788 -302.074834) (xy 398.32788 -302.837088) (xy 398.327763 -302.842043)
			(xy 398.325849 -302.851766) (xy 398.32407 -302.856392) (xy 398.321022 -302.863758) (xy 398.319245 -302.868385)
			(xy 398.317318 -302.878107) (xy 398.317212 -302.883062) (xy 398.317212 -303.024794) (xy 398.61923 -303.024794)
			(xy 398.62319 -302.97574) (xy 398.634967 -302.927956) (xy 398.654258 -302.88268) (xy 398.680561 -302.841084)
			(xy 398.713196 -302.804247) (xy 398.751317 -302.773122) (xy 398.793938 -302.748515) (xy 398.839954 -302.731063)
			(xy 398.888173 -302.721219) (xy 398.937348 -302.719238) (xy 398.986203 -302.72517) (xy 399.033474 -302.738862)
			(xy 399.077936 -302.75996) (xy 399.118439 -302.787916) (xy 399.153932 -302.822008) (xy 399.183497 -302.861352)
			(xy 399.206368 -302.904929) (xy 399.221952 -302.95161) (xy 399.229847 -303.000187) (xy 399.230342 -303.024794)
			(xy 399.56919 -303.024794) (xy 399.57315 -302.97574) (xy 399.584927 -302.927956) (xy 399.604218 -302.88268)
			(xy 399.630521 -302.841084) (xy 399.663156 -302.804247) (xy 399.701277 -302.773122) (xy 399.743898 -302.748515)
			(xy 399.789914 -302.731063) (xy 399.838133 -302.721219) (xy 399.887308 -302.719238) (xy 399.936163 -302.72517)
			(xy 399.983434 -302.738862) (xy 400.027896 -302.75996) (xy 400.068399 -302.787916) (xy 400.103892 -302.822008)
			(xy 400.133457 -302.861352) (xy 400.156328 -302.904929) (xy 400.171912 -302.95161) (xy 400.179807 -303.000187)
			(xy 400.180302 -303.024794) (xy 400.51915 -303.024794) (xy 400.52311 -302.97574) (xy 400.534887 -302.927956)
			(xy 400.554178 -302.88268) (xy 400.580481 -302.841084) (xy 400.613116 -302.804247) (xy 400.651237 -302.773122)
			(xy 400.693858 -302.748515) (xy 400.739874 -302.731063) (xy 400.788093 -302.721219) (xy 400.837268 -302.719238)
			(xy 400.886123 -302.72517) (xy 400.933394 -302.738862) (xy 400.977856 -302.75996) (xy 401.018359 -302.787916)
			(xy 401.053852 -302.822008) (xy 401.083417 -302.861352) (xy 401.106288 -302.904929) (xy 401.121872 -302.95161)
			(xy 401.129767 -303.000187) (xy 401.130262 -303.024794) (xy 401.46911 -303.024794) (xy 401.47307 -302.97574)
			(xy 401.484847 -302.927956) (xy 401.504138 -302.88268) (xy 401.530441 -302.841084) (xy 401.563076 -302.804247)
			(xy 401.601197 -302.773122) (xy 401.643818 -302.748515) (xy 401.689834 -302.731063) (xy 401.738053 -302.721219)
			(xy 401.787228 -302.719238) (xy 401.836083 -302.72517) (xy 401.883354 -302.738862) (xy 401.927816 -302.75996)
			(xy 401.968319 -302.787916) (xy 402.003812 -302.822008) (xy 402.033377 -302.861352) (xy 402.056248 -302.904929)
			(xy 402.071832 -302.95161) (xy 402.079727 -303.000187) (xy 402.080222 -303.024794) (xy 402.41907 -303.024794)
			(xy 402.42303 -302.97574) (xy 402.434807 -302.927956) (xy 402.454098 -302.88268) (xy 402.480401 -302.841084)
			(xy 402.513036 -302.804247) (xy 402.551157 -302.773122) (xy 402.593778 -302.748515) (xy 402.639794 -302.731063)
			(xy 402.688013 -302.721219) (xy 402.737188 -302.719238) (xy 402.786043 -302.72517) (xy 402.833314 -302.738862)
			(xy 402.877776 -302.75996) (xy 402.918279 -302.787916) (xy 402.953772 -302.822008) (xy 402.983337 -302.861352)
			(xy 403.006208 -302.904929) (xy 403.021792 -302.95161) (xy 403.029687 -303.000187) (xy 403.030182 -303.024794)
			(xy 403.36903 -303.024794) (xy 403.37299 -302.97574) (xy 403.384767 -302.927956) (xy 403.404058 -302.88268)
			(xy 403.430361 -302.841084) (xy 403.462996 -302.804247) (xy 403.501117 -302.773122) (xy 403.543738 -302.748515)
			(xy 403.589754 -302.731063) (xy 403.637973 -302.721219) (xy 403.687148 -302.719238) (xy 403.736003 -302.72517)
			(xy 403.783274 -302.738862) (xy 403.827736 -302.75996) (xy 403.868239 -302.787916) (xy 403.903732 -302.822008)
			(xy 403.933297 -302.861352) (xy 403.956168 -302.904929) (xy 403.971752 -302.95161) (xy 403.979647 -303.000187)
			(xy 403.980142 -303.024794) (xy 404.31899 -303.024794) (xy 404.32295 -302.97574) (xy 404.334727 -302.927956)
			(xy 404.354018 -302.88268) (xy 404.380321 -302.841084) (xy 404.412956 -302.804247) (xy 404.451077 -302.773122)
			(xy 404.493698 -302.748515) (xy 404.539714 -302.731063) (xy 404.587933 -302.721219) (xy 404.637108 -302.719238)
			(xy 404.685963 -302.72517) (xy 404.733234 -302.738862) (xy 404.777696 -302.75996) (xy 404.818199 -302.787916)
			(xy 404.853692 -302.822008) (xy 404.883257 -302.861352) (xy 404.906128 -302.904929) (xy 404.921712 -302.95161)
			(xy 404.929607 -303.000187) (xy 404.930102 -303.024794) (xy 405.269204 -303.024794) (xy 405.273164 -302.97574)
			(xy 405.284941 -302.927956) (xy 405.304232 -302.88268) (xy 405.330535 -302.841084) (xy 405.36317 -302.804247)
			(xy 405.401291 -302.773122) (xy 405.443912 -302.748515) (xy 405.489928 -302.731063) (xy 405.538147 -302.721219)
			(xy 405.587322 -302.719238) (xy 405.636177 -302.72517) (xy 405.683448 -302.738862) (xy 405.72791 -302.75996)
			(xy 405.768413 -302.787916) (xy 405.803906 -302.822008) (xy 405.833471 -302.861352) (xy 405.856342 -302.904929)
			(xy 405.871926 -302.95161) (xy 405.879821 -303.000187) (xy 405.880316 -303.024794) (xy 406.219164 -303.024794)
			(xy 406.223124 -302.97574) (xy 406.234901 -302.927956) (xy 406.254192 -302.88268) (xy 406.280495 -302.841084)
			(xy 406.31313 -302.804247) (xy 406.351251 -302.773122) (xy 406.393872 -302.748515) (xy 406.439888 -302.731063)
			(xy 406.488107 -302.721219) (xy 406.537282 -302.719238) (xy 406.586137 -302.72517) (xy 406.633408 -302.738862)
			(xy 406.67787 -302.75996) (xy 406.718373 -302.787916) (xy 406.753866 -302.822008) (xy 406.783431 -302.861352)
			(xy 406.806302 -302.904929) (xy 406.821886 -302.95161) (xy 406.829781 -303.000187) (xy 406.830276 -303.024794)
			(xy 408.119084 -303.024794) (xy 408.123044 -302.97574) (xy 408.134821 -302.927956) (xy 408.154112 -302.88268)
			(xy 408.180415 -302.841084) (xy 408.21305 -302.804247) (xy 408.251171 -302.773122) (xy 408.293792 -302.748515)
			(xy 408.339808 -302.731063) (xy 408.388027 -302.721219) (xy 408.437202 -302.719238) (xy 408.486057 -302.72517)
			(xy 408.533328 -302.738862) (xy 408.57779 -302.75996) (xy 408.618293 -302.787916) (xy 408.653786 -302.822008)
			(xy 408.683351 -302.861352) (xy 408.706222 -302.904929) (xy 408.721806 -302.95161) (xy 408.729701 -303.000187)
			(xy 408.730196 -303.024794) (xy 409.069044 -303.024794) (xy 409.073004 -302.97574) (xy 409.084781 -302.927956)
			(xy 409.104072 -302.88268) (xy 409.130375 -302.841084) (xy 409.16301 -302.804247) (xy 409.201131 -302.773122)
			(xy 409.243752 -302.748515) (xy 409.289768 -302.731063) (xy 409.337987 -302.721219) (xy 409.387162 -302.719238)
			(xy 409.436017 -302.72517) (xy 409.483288 -302.738862) (xy 409.52775 -302.75996) (xy 409.568253 -302.787916)
			(xy 409.603746 -302.822008) (xy 409.633311 -302.861352) (xy 409.656182 -302.904929) (xy 409.671766 -302.95161)
			(xy 409.679661 -303.000187) (xy 409.680156 -303.024794) (xy 410.019004 -303.024794) (xy 410.022964 -302.97574)
			(xy 410.034741 -302.927956) (xy 410.054032 -302.88268) (xy 410.080335 -302.841084) (xy 410.11297 -302.804247)
			(xy 410.151091 -302.773122) (xy 410.193712 -302.748515) (xy 410.239728 -302.731063) (xy 410.287947 -302.721219)
			(xy 410.337122 -302.719238) (xy 410.385977 -302.72517) (xy 410.433248 -302.738862) (xy 410.47771 -302.75996)
			(xy 410.518213 -302.787916) (xy 410.553706 -302.822008) (xy 410.583271 -302.861352) (xy 410.606142 -302.904929)
			(xy 410.621726 -302.95161) (xy 410.629621 -303.000187) (xy 410.630116 -303.024794) (xy 410.969218 -303.024794)
			(xy 410.973178 -302.97574) (xy 410.984955 -302.927956) (xy 411.004246 -302.88268) (xy 411.030549 -302.841084)
			(xy 411.063184 -302.804247) (xy 411.101305 -302.773122) (xy 411.143926 -302.748515) (xy 411.189942 -302.731063)
			(xy 411.238161 -302.721219) (xy 411.287336 -302.719238) (xy 411.336191 -302.72517) (xy 411.383462 -302.738862)
			(xy 411.427924 -302.75996) (xy 411.468427 -302.787916) (xy 411.50392 -302.822008) (xy 411.533485 -302.861352)
			(xy 411.556356 -302.904929) (xy 411.57194 -302.95161) (xy 411.579835 -303.000187) (xy 411.58033 -303.024794)
			(xy 411.919178 -303.024794) (xy 411.923138 -302.97574) (xy 411.934915 -302.927956) (xy 411.954206 -302.88268)
			(xy 411.980509 -302.841084) (xy 412.013144 -302.804247) (xy 412.051265 -302.773122) (xy 412.093886 -302.748515)
			(xy 412.139902 -302.731063) (xy 412.188121 -302.721219) (xy 412.237296 -302.719238) (xy 412.286151 -302.72517)
			(xy 412.333422 -302.738862) (xy 412.377884 -302.75996) (xy 412.418387 -302.787916) (xy 412.45388 -302.822008)
			(xy 412.483445 -302.861352) (xy 412.506316 -302.904929) (xy 412.5219 -302.95161) (xy 412.529795 -303.000187)
			(xy 412.53029 -303.024794) (xy 412.869138 -303.024794) (xy 412.873098 -302.97574) (xy 412.884875 -302.927956)
			(xy 412.904166 -302.88268) (xy 412.930469 -302.841084) (xy 412.963104 -302.804247) (xy 413.001225 -302.773122)
			(xy 413.043846 -302.748515) (xy 413.089862 -302.731063) (xy 413.138081 -302.721219) (xy 413.187256 -302.719238)
			(xy 413.236111 -302.72517) (xy 413.283382 -302.738862) (xy 413.327844 -302.75996) (xy 413.368347 -302.787916)
			(xy 413.40384 -302.822008) (xy 413.433405 -302.861352) (xy 413.456276 -302.904929) (xy 413.47186 -302.95161)
			(xy 413.479755 -303.000187) (xy 413.48025 -303.024794) (xy 413.819098 -303.024794) (xy 413.823058 -302.97574)
			(xy 413.834835 -302.927956) (xy 413.854126 -302.88268) (xy 413.880429 -302.841084) (xy 413.913064 -302.804247)
			(xy 413.951185 -302.773122) (xy 413.993806 -302.748515) (xy 414.039822 -302.731063) (xy 414.088041 -302.721219)
			(xy 414.137216 -302.719238) (xy 414.186071 -302.72517) (xy 414.233342 -302.738862) (xy 414.277804 -302.75996)
			(xy 414.318307 -302.787916) (xy 414.3538 -302.822008) (xy 414.383365 -302.861352) (xy 414.406236 -302.904929)
			(xy 414.42182 -302.95161) (xy 414.429715 -303.000187) (xy 414.43021 -303.024794) (xy 414.769058 -303.024794)
			(xy 414.773018 -302.97574) (xy 414.784795 -302.927956) (xy 414.804086 -302.88268) (xy 414.830389 -302.841084)
			(xy 414.863024 -302.804247) (xy 414.901145 -302.773122) (xy 414.943766 -302.748515) (xy 414.989782 -302.731063)
			(xy 415.038001 -302.721219) (xy 415.087176 -302.719238) (xy 415.136031 -302.72517) (xy 415.183302 -302.738862)
			(xy 415.227764 -302.75996) (xy 415.268267 -302.787916) (xy 415.30376 -302.822008) (xy 415.333325 -302.861352)
			(xy 415.356196 -302.904929) (xy 415.37178 -302.95161) (xy 415.379675 -303.000187) (xy 415.38017 -303.024794)
			(xy 415.719018 -303.024794) (xy 415.722978 -302.97574) (xy 415.734755 -302.927956) (xy 415.754046 -302.88268)
			(xy 415.780349 -302.841084) (xy 415.812984 -302.804247) (xy 415.851105 -302.773122) (xy 415.893726 -302.748515)
			(xy 415.939742 -302.731063) (xy 415.987961 -302.721219) (xy 416.037136 -302.719238) (xy 416.085991 -302.72517)
			(xy 416.133262 -302.738862) (xy 416.177724 -302.75996) (xy 416.218227 -302.787916) (xy 416.25372 -302.822008)
			(xy 416.283285 -302.861352) (xy 416.306156 -302.904929) (xy 416.32174 -302.95161) (xy 416.329635 -303.000187)
			(xy 416.33013 -303.024794) (xy 416.668978 -303.024794) (xy 416.672938 -302.97574) (xy 416.684715 -302.927956)
			(xy 416.704006 -302.88268) (xy 416.730309 -302.841084) (xy 416.762944 -302.804247) (xy 416.801065 -302.773122)
			(xy 416.843686 -302.748515) (xy 416.889702 -302.731063) (xy 416.937921 -302.721219) (xy 416.987096 -302.719238)
			(xy 417.035951 -302.72517) (xy 417.083222 -302.738862) (xy 417.127684 -302.75996) (xy 417.168187 -302.787916)
			(xy 417.20368 -302.822008) (xy 417.233245 -302.861352) (xy 417.256116 -302.904929) (xy 417.2717 -302.95161)
			(xy 417.279595 -303.000187) (xy 417.28009 -303.024794) (xy 417.619192 -303.024794) (xy 417.623152 -302.97574)
			(xy 417.634929 -302.927956) (xy 417.65422 -302.88268) (xy 417.680523 -302.841084) (xy 417.713158 -302.804247)
			(xy 417.751279 -302.773122) (xy 417.7939 -302.748515) (xy 417.839916 -302.731063) (xy 417.888135 -302.721219)
			(xy 417.93731 -302.719238) (xy 417.986165 -302.72517) (xy 418.033436 -302.738862) (xy 418.077898 -302.75996)
			(xy 418.118401 -302.787916) (xy 418.153894 -302.822008) (xy 418.183459 -302.861352) (xy 418.20633 -302.904929)
			(xy 418.221914 -302.95161) (xy 418.229809 -303.000187) (xy 418.230304 -303.024794) (xy 418.569152 -303.024794)
			(xy 418.573112 -302.97574) (xy 418.584889 -302.927956) (xy 418.60418 -302.88268) (xy 418.630483 -302.841084)
			(xy 418.663118 -302.804247) (xy 418.701239 -302.773122) (xy 418.74386 -302.748515) (xy 418.789876 -302.731063)
			(xy 418.838095 -302.721219) (xy 418.88727 -302.719238) (xy 418.936125 -302.72517) (xy 418.983396 -302.738862)
			(xy 419.027858 -302.75996) (xy 419.068361 -302.787916) (xy 419.103854 -302.822008) (xy 419.133419 -302.861352)
			(xy 419.15629 -302.904929) (xy 419.171874 -302.95161) (xy 419.179769 -303.000187) (xy 419.180264 -303.024794)
			(xy 419.519112 -303.024794) (xy 419.523072 -302.97574) (xy 419.534849 -302.927956) (xy 419.55414 -302.88268)
			(xy 419.580443 -302.841084) (xy 419.613078 -302.804247) (xy 419.651199 -302.773122) (xy 419.69382 -302.748515)
			(xy 419.739836 -302.731063) (xy 419.788055 -302.721219) (xy 419.83723 -302.719238) (xy 419.886085 -302.72517)
			(xy 419.933356 -302.738862) (xy 419.977818 -302.75996) (xy 420.018321 -302.787916) (xy 420.053814 -302.822008)
			(xy 420.083379 -302.861352) (xy 420.10625 -302.904929) (xy 420.121834 -302.95161) (xy 420.129729 -303.000187)
			(xy 420.130224 -303.024794) (xy 420.469072 -303.024794) (xy 420.473032 -302.97574) (xy 420.484809 -302.927956)
			(xy 420.5041 -302.88268) (xy 420.530403 -302.841084) (xy 420.563038 -302.804247) (xy 420.601159 -302.773122)
			(xy 420.64378 -302.748515) (xy 420.689796 -302.731063) (xy 420.738015 -302.721219) (xy 420.78719 -302.719238)
			(xy 420.836045 -302.72517) (xy 420.883316 -302.738862) (xy 420.927778 -302.75996) (xy 420.968281 -302.787916)
			(xy 421.003774 -302.822008) (xy 421.033339 -302.861352) (xy 421.05621 -302.904929) (xy 421.071794 -302.95161)
			(xy 421.079689 -303.000187) (xy 421.080184 -303.024794) (xy 421.419032 -303.024794) (xy 421.422992 -302.97574)
			(xy 421.434769 -302.927956) (xy 421.45406 -302.88268) (xy 421.480363 -302.841084) (xy 421.512998 -302.804247)
			(xy 421.551119 -302.773122) (xy 421.59374 -302.748515) (xy 421.639756 -302.731063) (xy 421.687975 -302.721219)
			(xy 421.73715 -302.719238) (xy 421.786005 -302.72517) (xy 421.833276 -302.738862) (xy 421.877738 -302.75996)
			(xy 421.918241 -302.787916) (xy 421.953734 -302.822008) (xy 421.983299 -302.861352) (xy 422.00617 -302.904929)
			(xy 422.021754 -302.95161) (xy 422.029649 -303.000187) (xy 422.030144 -303.024794) (xy 422.029649 -303.049401)
			(xy 422.021754 -303.097978) (xy 422.00617 -303.144659) (xy 421.983299 -303.188236) (xy 421.953734 -303.22758)
			(xy 421.918241 -303.261672) (xy 421.877738 -303.289628) (xy 421.833276 -303.310726) (xy 421.786005 -303.324418)
			(xy 421.73715 -303.33035) (xy 421.687975 -303.328369) (xy 421.639756 -303.318525) (xy 421.59374 -303.301073)
			(xy 421.551119 -303.276466) (xy 421.512998 -303.245341) (xy 421.480363 -303.208504) (xy 421.45406 -303.166908)
			(xy 421.434769 -303.121632) (xy 421.422992 -303.073848) (xy 421.419032 -303.024794) (xy 421.080184 -303.024794)
			(xy 421.079689 -303.049401) (xy 421.071794 -303.097978) (xy 421.05621 -303.144659) (xy 421.033339 -303.188236)
			(xy 421.003774 -303.22758) (xy 420.968281 -303.261672) (xy 420.927778 -303.289628) (xy 420.883316 -303.310726)
			(xy 420.836045 -303.324418) (xy 420.78719 -303.33035) (xy 420.738015 -303.328369) (xy 420.689796 -303.318525)
			(xy 420.64378 -303.301073) (xy 420.601159 -303.276466) (xy 420.563038 -303.245341) (xy 420.530403 -303.208504)
			(xy 420.5041 -303.166908) (xy 420.484809 -303.121632) (xy 420.473032 -303.073848) (xy 420.469072 -303.024794)
			(xy 420.130224 -303.024794) (xy 420.129729 -303.049401) (xy 420.121834 -303.097978) (xy 420.10625 -303.144659)
			(xy 420.083379 -303.188236) (xy 420.053814 -303.22758) (xy 420.018321 -303.261672) (xy 419.977818 -303.289628)
			(xy 419.933356 -303.310726) (xy 419.886085 -303.324418) (xy 419.83723 -303.33035) (xy 419.788055 -303.328369)
			(xy 419.739836 -303.318525) (xy 419.69382 -303.301073) (xy 419.651199 -303.276466) (xy 419.613078 -303.245341)
			(xy 419.580443 -303.208504) (xy 419.55414 -303.166908) (xy 419.534849 -303.121632) (xy 419.523072 -303.073848)
			(xy 419.519112 -303.024794) (xy 419.180264 -303.024794) (xy 419.179769 -303.049401) (xy 419.171874 -303.097978)
			(xy 419.15629 -303.144659) (xy 419.133419 -303.188236) (xy 419.103854 -303.22758) (xy 419.068361 -303.261672)
			(xy 419.027858 -303.289628) (xy 418.983396 -303.310726) (xy 418.936125 -303.324418) (xy 418.88727 -303.33035)
			(xy 418.838095 -303.328369) (xy 418.789876 -303.318525) (xy 418.74386 -303.301073) (xy 418.701239 -303.276466)
			(xy 418.663118 -303.245341) (xy 418.630483 -303.208504) (xy 418.60418 -303.166908) (xy 418.584889 -303.121632)
			(xy 418.573112 -303.073848) (xy 418.569152 -303.024794) (xy 418.230304 -303.024794) (xy 418.229809 -303.049401)
			(xy 418.221914 -303.097978) (xy 418.20633 -303.144659) (xy 418.183459 -303.188236) (xy 418.153894 -303.22758)
			(xy 418.118401 -303.261672) (xy 418.077898 -303.289628) (xy 418.033436 -303.310726) (xy 417.986165 -303.324418)
			(xy 417.93731 -303.33035) (xy 417.888135 -303.328369) (xy 417.839916 -303.318525) (xy 417.7939 -303.301073)
			(xy 417.751279 -303.276466) (xy 417.713158 -303.245341) (xy 417.680523 -303.208504) (xy 417.65422 -303.166908)
			(xy 417.634929 -303.121632) (xy 417.623152 -303.073848) (xy 417.619192 -303.024794) (xy 417.28009 -303.024794)
			(xy 417.279595 -303.049401) (xy 417.2717 -303.097978) (xy 417.256116 -303.144659) (xy 417.233245 -303.188236)
			(xy 417.20368 -303.22758) (xy 417.168187 -303.261672) (xy 417.127684 -303.289628) (xy 417.083222 -303.310726)
			(xy 417.035951 -303.324418) (xy 416.987096 -303.33035) (xy 416.937921 -303.328369) (xy 416.889702 -303.318525)
			(xy 416.843686 -303.301073) (xy 416.801065 -303.276466) (xy 416.762944 -303.245341) (xy 416.730309 -303.208504)
			(xy 416.704006 -303.166908) (xy 416.684715 -303.121632) (xy 416.672938 -303.073848) (xy 416.668978 -303.024794)
			(xy 416.33013 -303.024794) (xy 416.329635 -303.049401) (xy 416.32174 -303.097978) (xy 416.306156 -303.144659)
			(xy 416.283285 -303.188236) (xy 416.25372 -303.22758) (xy 416.218227 -303.261672) (xy 416.177724 -303.289628)
			(xy 416.133262 -303.310726) (xy 416.085991 -303.324418) (xy 416.037136 -303.33035) (xy 415.987961 -303.328369)
			(xy 415.939742 -303.318525) (xy 415.893726 -303.301073) (xy 415.851105 -303.276466) (xy 415.812984 -303.245341)
			(xy 415.780349 -303.208504) (xy 415.754046 -303.166908) (xy 415.734755 -303.121632) (xy 415.722978 -303.073848)
			(xy 415.719018 -303.024794) (xy 415.38017 -303.024794) (xy 415.379675 -303.049401) (xy 415.37178 -303.097978)
			(xy 415.356196 -303.144659) (xy 415.333325 -303.188236) (xy 415.30376 -303.22758) (xy 415.268267 -303.261672)
			(xy 415.227764 -303.289628) (xy 415.183302 -303.310726) (xy 415.136031 -303.324418) (xy 415.087176 -303.33035)
			(xy 415.038001 -303.328369) (xy 414.989782 -303.318525) (xy 414.943766 -303.301073) (xy 414.901145 -303.276466)
			(xy 414.863024 -303.245341) (xy 414.830389 -303.208504) (xy 414.804086 -303.166908) (xy 414.784795 -303.121632)
			(xy 414.773018 -303.073848) (xy 414.769058 -303.024794) (xy 414.43021 -303.024794) (xy 414.429715 -303.049401)
			(xy 414.42182 -303.097978) (xy 414.406236 -303.144659) (xy 414.383365 -303.188236) (xy 414.3538 -303.22758)
			(xy 414.318307 -303.261672) (xy 414.277804 -303.289628) (xy 414.233342 -303.310726) (xy 414.186071 -303.324418)
			(xy 414.137216 -303.33035) (xy 414.088041 -303.328369) (xy 414.039822 -303.318525) (xy 413.993806 -303.301073)
			(xy 413.951185 -303.276466) (xy 413.913064 -303.245341) (xy 413.880429 -303.208504) (xy 413.854126 -303.166908)
			(xy 413.834835 -303.121632) (xy 413.823058 -303.073848) (xy 413.819098 -303.024794) (xy 413.48025 -303.024794)
			(xy 413.479755 -303.049401) (xy 413.47186 -303.097978) (xy 413.456276 -303.144659) (xy 413.433405 -303.188236)
			(xy 413.40384 -303.22758) (xy 413.368347 -303.261672) (xy 413.327844 -303.289628) (xy 413.283382 -303.310726)
			(xy 413.236111 -303.324418) (xy 413.187256 -303.33035) (xy 413.138081 -303.328369) (xy 413.089862 -303.318525)
			(xy 413.043846 -303.301073) (xy 413.001225 -303.276466) (xy 412.963104 -303.245341) (xy 412.930469 -303.208504)
			(xy 412.904166 -303.166908) (xy 412.884875 -303.121632) (xy 412.873098 -303.073848) (xy 412.869138 -303.024794)
			(xy 412.53029 -303.024794) (xy 412.529795 -303.049401) (xy 412.5219 -303.097978) (xy 412.506316 -303.144659)
			(xy 412.483445 -303.188236) (xy 412.45388 -303.22758) (xy 412.418387 -303.261672) (xy 412.377884 -303.289628)
			(xy 412.333422 -303.310726) (xy 412.286151 -303.324418) (xy 412.237296 -303.33035) (xy 412.188121 -303.328369)
			(xy 412.139902 -303.318525) (xy 412.093886 -303.301073) (xy 412.051265 -303.276466) (xy 412.013144 -303.245341)
			(xy 411.980509 -303.208504) (xy 411.954206 -303.166908) (xy 411.934915 -303.121632) (xy 411.923138 -303.073848)
			(xy 411.919178 -303.024794) (xy 411.58033 -303.024794) (xy 411.579835 -303.049401) (xy 411.57194 -303.097978)
			(xy 411.556356 -303.144659) (xy 411.533485 -303.188236) (xy 411.50392 -303.22758) (xy 411.468427 -303.261672)
			(xy 411.427924 -303.289628) (xy 411.383462 -303.310726) (xy 411.336191 -303.324418) (xy 411.287336 -303.33035)
			(xy 411.238161 -303.328369) (xy 411.189942 -303.318525) (xy 411.143926 -303.301073) (xy 411.101305 -303.276466)
			(xy 411.063184 -303.245341) (xy 411.030549 -303.208504) (xy 411.004246 -303.166908) (xy 410.984955 -303.121632)
			(xy 410.973178 -303.073848) (xy 410.969218 -303.024794) (xy 410.630116 -303.024794) (xy 410.629621 -303.049401)
			(xy 410.621726 -303.097978) (xy 410.606142 -303.144659) (xy 410.583271 -303.188236) (xy 410.553706 -303.22758)
			(xy 410.518213 -303.261672) (xy 410.47771 -303.289628) (xy 410.433248 -303.310726) (xy 410.385977 -303.324418)
			(xy 410.337122 -303.33035) (xy 410.287947 -303.328369) (xy 410.239728 -303.318525) (xy 410.193712 -303.301073)
			(xy 410.151091 -303.276466) (xy 410.11297 -303.245341) (xy 410.080335 -303.208504) (xy 410.054032 -303.166908)
			(xy 410.034741 -303.121632) (xy 410.022964 -303.073848) (xy 410.019004 -303.024794) (xy 409.680156 -303.024794)
			(xy 409.679661 -303.049401) (xy 409.671766 -303.097978) (xy 409.656182 -303.144659) (xy 409.633311 -303.188236)
			(xy 409.603746 -303.22758) (xy 409.568253 -303.261672) (xy 409.52775 -303.289628) (xy 409.483288 -303.310726)
			(xy 409.436017 -303.324418) (xy 409.387162 -303.33035) (xy 409.337987 -303.328369) (xy 409.289768 -303.318525)
			(xy 409.243752 -303.301073) (xy 409.201131 -303.276466) (xy 409.16301 -303.245341) (xy 409.130375 -303.208504)
			(xy 409.104072 -303.166908) (xy 409.084781 -303.121632) (xy 409.073004 -303.073848) (xy 409.069044 -303.024794)
			(xy 408.730196 -303.024794) (xy 408.729701 -303.049401) (xy 408.721806 -303.097978) (xy 408.706222 -303.144659)
			(xy 408.683351 -303.188236) (xy 408.653786 -303.22758) (xy 408.618293 -303.261672) (xy 408.57779 -303.289628)
			(xy 408.533328 -303.310726) (xy 408.486057 -303.324418) (xy 408.437202 -303.33035) (xy 408.388027 -303.328369)
			(xy 408.339808 -303.318525) (xy 408.293792 -303.301073) (xy 408.251171 -303.276466) (xy 408.21305 -303.245341)
			(xy 408.180415 -303.208504) (xy 408.154112 -303.166908) (xy 408.134821 -303.121632) (xy 408.123044 -303.073848)
			(xy 408.119084 -303.024794) (xy 406.830276 -303.024794) (xy 406.829781 -303.049401) (xy 406.821886 -303.097978)
			(xy 406.806302 -303.144659) (xy 406.783431 -303.188236) (xy 406.753866 -303.22758) (xy 406.718373 -303.261672)
			(xy 406.67787 -303.289628) (xy 406.633408 -303.310726) (xy 406.586137 -303.324418) (xy 406.537282 -303.33035)
			(xy 406.488107 -303.328369) (xy 406.439888 -303.318525) (xy 406.393872 -303.301073) (xy 406.351251 -303.276466)
			(xy 406.31313 -303.245341) (xy 406.280495 -303.208504) (xy 406.254192 -303.166908) (xy 406.234901 -303.121632)
			(xy 406.223124 -303.073848) (xy 406.219164 -303.024794) (xy 405.880316 -303.024794) (xy 405.879821 -303.049401)
			(xy 405.871926 -303.097978) (xy 405.856342 -303.144659) (xy 405.833471 -303.188236) (xy 405.803906 -303.22758)
			(xy 405.768413 -303.261672) (xy 405.72791 -303.289628) (xy 405.683448 -303.310726) (xy 405.636177 -303.324418)
			(xy 405.587322 -303.33035) (xy 405.538147 -303.328369) (xy 405.489928 -303.318525) (xy 405.443912 -303.301073)
			(xy 405.401291 -303.276466) (xy 405.36317 -303.245341) (xy 405.330535 -303.208504) (xy 405.304232 -303.166908)
			(xy 405.284941 -303.121632) (xy 405.273164 -303.073848) (xy 405.269204 -303.024794) (xy 404.930102 -303.024794)
			(xy 404.929607 -303.049401) (xy 404.921712 -303.097978) (xy 404.906128 -303.144659) (xy 404.883257 -303.188236)
			(xy 404.853692 -303.22758) (xy 404.818199 -303.261672) (xy 404.777696 -303.289628) (xy 404.733234 -303.310726)
			(xy 404.685963 -303.324418) (xy 404.637108 -303.33035) (xy 404.587933 -303.328369) (xy 404.539714 -303.318525)
			(xy 404.493698 -303.301073) (xy 404.451077 -303.276466) (xy 404.412956 -303.245341) (xy 404.380321 -303.208504)
			(xy 404.354018 -303.166908) (xy 404.334727 -303.121632) (xy 404.32295 -303.073848) (xy 404.31899 -303.024794)
			(xy 403.980142 -303.024794) (xy 403.979647 -303.049401) (xy 403.971752 -303.097978) (xy 403.956168 -303.144659)
			(xy 403.933297 -303.188236) (xy 403.903732 -303.22758) (xy 403.868239 -303.261672) (xy 403.827736 -303.289628)
			(xy 403.783274 -303.310726) (xy 403.736003 -303.324418) (xy 403.687148 -303.33035) (xy 403.637973 -303.328369)
			(xy 403.589754 -303.318525) (xy 403.543738 -303.301073) (xy 403.501117 -303.276466) (xy 403.462996 -303.245341)
			(xy 403.430361 -303.208504) (xy 403.404058 -303.166908) (xy 403.384767 -303.121632) (xy 403.37299 -303.073848)
			(xy 403.36903 -303.024794) (xy 403.030182 -303.024794) (xy 403.029687 -303.049401) (xy 403.021792 -303.097978)
			(xy 403.006208 -303.144659) (xy 402.983337 -303.188236) (xy 402.953772 -303.22758) (xy 402.918279 -303.261672)
			(xy 402.877776 -303.289628) (xy 402.833314 -303.310726) (xy 402.786043 -303.324418) (xy 402.737188 -303.33035)
			(xy 402.688013 -303.328369) (xy 402.639794 -303.318525) (xy 402.593778 -303.301073) (xy 402.551157 -303.276466)
			(xy 402.513036 -303.245341) (xy 402.480401 -303.208504) (xy 402.454098 -303.166908) (xy 402.434807 -303.121632)
			(xy 402.42303 -303.073848) (xy 402.41907 -303.024794) (xy 402.080222 -303.024794) (xy 402.079727 -303.049401)
			(xy 402.071832 -303.097978) (xy 402.056248 -303.144659) (xy 402.033377 -303.188236) (xy 402.003812 -303.22758)
			(xy 401.968319 -303.261672) (xy 401.927816 -303.289628) (xy 401.883354 -303.310726) (xy 401.836083 -303.324418)
			(xy 401.787228 -303.33035) (xy 401.738053 -303.328369) (xy 401.689834 -303.318525) (xy 401.643818 -303.301073)
			(xy 401.601197 -303.276466) (xy 401.563076 -303.245341) (xy 401.530441 -303.208504) (xy 401.504138 -303.166908)
			(xy 401.484847 -303.121632) (xy 401.47307 -303.073848) (xy 401.46911 -303.024794) (xy 401.130262 -303.024794)
			(xy 401.129767 -303.049401) (xy 401.121872 -303.097978) (xy 401.106288 -303.144659) (xy 401.083417 -303.188236)
			(xy 401.053852 -303.22758) (xy 401.018359 -303.261672) (xy 400.977856 -303.289628) (xy 400.933394 -303.310726)
			(xy 400.886123 -303.324418) (xy 400.837268 -303.33035) (xy 400.788093 -303.328369) (xy 400.739874 -303.318525)
			(xy 400.693858 -303.301073) (xy 400.651237 -303.276466) (xy 400.613116 -303.245341) (xy 400.580481 -303.208504)
			(xy 400.554178 -303.166908) (xy 400.534887 -303.121632) (xy 400.52311 -303.073848) (xy 400.51915 -303.024794)
			(xy 400.180302 -303.024794) (xy 400.179807 -303.049401) (xy 400.171912 -303.097978) (xy 400.156328 -303.144659)
			(xy 400.133457 -303.188236) (xy 400.103892 -303.22758) (xy 400.068399 -303.261672) (xy 400.027896 -303.289628)
			(xy 399.983434 -303.310726) (xy 399.936163 -303.324418) (xy 399.887308 -303.33035) (xy 399.838133 -303.328369)
			(xy 399.789914 -303.318525) (xy 399.743898 -303.301073) (xy 399.701277 -303.276466) (xy 399.663156 -303.245341)
			(xy 399.630521 -303.208504) (xy 399.604218 -303.166908) (xy 399.584927 -303.121632) (xy 399.57315 -303.073848)
			(xy 399.56919 -303.024794) (xy 399.230342 -303.024794) (xy 399.229847 -303.049401) (xy 399.221952 -303.097978)
			(xy 399.206368 -303.144659) (xy 399.183497 -303.188236) (xy 399.153932 -303.22758) (xy 399.118439 -303.261672)
			(xy 399.077936 -303.289628) (xy 399.033474 -303.310726) (xy 398.986203 -303.324418) (xy 398.937348 -303.33035)
			(xy 398.888173 -303.328369) (xy 398.839954 -303.318525) (xy 398.793938 -303.301073) (xy 398.751317 -303.276466)
			(xy 398.713196 -303.245341) (xy 398.680561 -303.208504) (xy 398.654258 -303.166908) (xy 398.634967 -303.121632)
			(xy 398.62319 -303.073848) (xy 398.61923 -303.024794) (xy 398.317212 -303.024794) (xy 398.317212 -303.499774)
			(xy 422.844226 -303.499774) (xy 422.848186 -303.45072) (xy 422.859963 -303.402936) (xy 422.879254 -303.35766)
			(xy 422.905557 -303.316064) (xy 422.938192 -303.279227) (xy 422.976313 -303.248102) (xy 423.018934 -303.223495)
			(xy 423.06495 -303.206043) (xy 423.113169 -303.196199) (xy 423.162344 -303.194218) (xy 423.211199 -303.20015)
			(xy 423.25847 -303.213842) (xy 423.302932 -303.23494) (xy 423.343435 -303.262896) (xy 423.378928 -303.296988)
			(xy 423.408493 -303.336332) (xy 423.431364 -303.379909) (xy 423.446948 -303.42659) (xy 423.454843 -303.475167)
			(xy 423.455172 -303.491533) (xy 423.794255 -303.491533) (xy 423.79962 -303.442177) (xy 423.8129 -303.39434)
			(xy 423.833744 -303.349281) (xy 423.861603 -303.308188) (xy 423.895743 -303.272143) (xy 423.935265 -303.242097)
			(xy 423.979128 -303.21884) (xy 424.026175 -303.202986) (xy 424.075167 -303.194953) (xy 424.09999 -303.194466)
			(xy 424.114173 -303.194644) (xy 424.142413 -303.197315) (xy 424.156378 -303.1998) (xy 424.170345 -303.201961)
			(xy 424.198479 -303.199387) (xy 424.224829 -303.1892) (xy 424.247378 -303.17218) (xy 424.264398 -303.149632)
			(xy 424.274586 -303.123282) (xy 424.277161 -303.095148) (xy 424.274996 -303.081182) (xy 424.272521 -303.067216)
			(xy 424.269848 -303.038976) (xy 424.269662 -303.024794) (xy 424.270184 -302.999973) (xy 424.278217 -302.950986)
			(xy 424.294068 -302.903943) (xy 424.317322 -302.860085) (xy 424.347365 -302.820567) (xy 424.383406 -302.786429)
			(xy 424.424495 -302.758573) (xy 424.469549 -302.73773) (xy 424.517382 -302.724452) (xy 424.566732 -302.719087)
			(xy 424.616301 -302.721777) (xy 424.664781 -302.73245) (xy 424.710896 -302.750827) (xy 424.753431 -302.776422)
			(xy 424.791264 -302.808562) (xy 424.823399 -302.846399) (xy 424.848989 -302.888936) (xy 424.86736 -302.935053)
			(xy 424.878028 -302.983535) (xy 424.880262 -303.024794) (xy 425.219126 -303.024794) (xy 425.223086 -302.97574)
			(xy 425.234863 -302.927956) (xy 425.254154 -302.88268) (xy 425.280457 -302.841084) (xy 425.313092 -302.804247)
			(xy 425.351213 -302.773122) (xy 425.393834 -302.748515) (xy 425.43985 -302.731063) (xy 425.488069 -302.721219)
			(xy 425.537244 -302.719238) (xy 425.586099 -302.72517) (xy 425.63337 -302.738862) (xy 425.677832 -302.75996)
			(xy 425.718335 -302.787916) (xy 425.753828 -302.822008) (xy 425.783393 -302.861352) (xy 425.806264 -302.904929)
			(xy 425.821848 -302.95161) (xy 425.829743 -303.000187) (xy 425.830238 -303.024794) (xy 425.830071 -303.033077)
			(xy 426.169191 -303.033077) (xy 426.171879 -302.98351) (xy 426.182551 -302.935031) (xy 426.200925 -302.888917)
			(xy 426.226517 -302.846384) (xy 426.258653 -302.80855) (xy 426.296487 -302.776415) (xy 426.339021 -302.750823)
			(xy 426.385135 -302.73245) (xy 426.433614 -302.721779) (xy 426.483181 -302.719091) (xy 426.532529 -302.724458)
			(xy 426.580359 -302.737738) (xy 426.625411 -302.75858) (xy 426.666498 -302.786437) (xy 426.702536 -302.820574)
			(xy 426.732577 -302.860091) (xy 426.755829 -302.903948) (xy 426.77168 -302.950989) (xy 426.779712 -302.999974)
			(xy 426.780198 -303.024794) (xy 426.780021 -303.038977) (xy 426.777349 -303.067217) (xy 426.774864 -303.081182)
			(xy 426.772578 -303.093628) (xy 426.779944 -303.11725) (xy 426.857414 -303.19472) (xy 426.881036 -303.202086)
			(xy 426.893482 -303.1998) (xy 426.907447 -303.197316) (xy 426.935687 -303.194649) (xy 426.94987 -303.194466)
			(xy 426.964053 -303.194647) (xy 426.992293 -303.197316) (xy 427.006258 -303.1998) (xy 427.018704 -303.202086)
			(xy 427.042326 -303.19472) (xy 427.119796 -303.11725) (xy 427.127162 -303.093628) (xy 427.124876 -303.081182)
			(xy 427.122401 -303.067216) (xy 427.119728 -303.038976) (xy 427.119542 -303.024794) (xy 427.119984 -302.999975)
			(xy 427.128016 -302.95099) (xy 427.143866 -302.90395) (xy 427.167117 -302.860093) (xy 427.197157 -302.820576)
			(xy 427.233194 -302.786439) (xy 427.274279 -302.758581) (xy 427.319329 -302.737737) (xy 427.367158 -302.724456)
			(xy 427.416506 -302.719087) (xy 427.466072 -302.721773) (xy 427.514551 -302.732441) (xy 427.560665 -302.750812)
			(xy 427.6032 -302.776401) (xy 427.641035 -302.808533) (xy 427.673174 -302.846364) (xy 427.698769 -302.888895)
			(xy 427.717146 -302.935007) (xy 427.727821 -302.983484) (xy 427.730065 -303.024794) (xy 428.069006 -303.024794)
			(xy 428.072966 -302.97574) (xy 428.084743 -302.927956) (xy 428.104034 -302.88268) (xy 428.130337 -302.841084)
			(xy 428.162972 -302.804247) (xy 428.201093 -302.773122) (xy 428.243714 -302.748515) (xy 428.28973 -302.731063)
			(xy 428.337949 -302.721219) (xy 428.387124 -302.719238) (xy 428.435979 -302.72517) (xy 428.48325 -302.738862)
			(xy 428.527712 -302.75996) (xy 428.568215 -302.787916) (xy 428.603708 -302.822008) (xy 428.633273 -302.861352)
			(xy 428.656144 -302.904929) (xy 428.671728 -302.95161) (xy 428.679623 -303.000187) (xy 428.680118 -303.024794)
			(xy 429.01922 -303.024794) (xy 429.02318 -302.97574) (xy 429.034957 -302.927956) (xy 429.054248 -302.88268)
			(xy 429.080551 -302.841084) (xy 429.113186 -302.804247) (xy 429.151307 -302.773122) (xy 429.193928 -302.748515)
			(xy 429.239944 -302.731063) (xy 429.288163 -302.721219) (xy 429.337338 -302.719238) (xy 429.386193 -302.72517)
			(xy 429.433464 -302.738862) (xy 429.477926 -302.75996) (xy 429.518429 -302.787916) (xy 429.553922 -302.822008)
			(xy 429.583487 -302.861352) (xy 429.606358 -302.904929) (xy 429.621942 -302.95161) (xy 429.629837 -303.000187)
			(xy 429.630332 -303.024794) (xy 429.96918 -303.024794) (xy 429.97314 -302.97574) (xy 429.984917 -302.927956)
			(xy 430.004208 -302.88268) (xy 430.030511 -302.841084) (xy 430.063146 -302.804247) (xy 430.101267 -302.773122)
			(xy 430.143888 -302.748515) (xy 430.189904 -302.731063) (xy 430.238123 -302.721219) (xy 430.287298 -302.719238)
			(xy 430.336153 -302.72517) (xy 430.383424 -302.738862) (xy 430.427886 -302.75996) (xy 430.468389 -302.787916)
			(xy 430.503882 -302.822008) (xy 430.533447 -302.861352) (xy 430.556318 -302.904929) (xy 430.571902 -302.95161)
			(xy 430.579797 -303.000187) (xy 430.580292 -303.024794) (xy 430.9039 -303.024794) (xy 430.90786 -302.97574)
			(xy 430.919637 -302.927956) (xy 430.938928 -302.88268) (xy 430.965231 -302.841084) (xy 430.997866 -302.804247)
			(xy 431.035987 -302.773122) (xy 431.078608 -302.748515) (xy 431.124624 -302.731063) (xy 431.172843 -302.721219)
			(xy 431.222018 -302.719238) (xy 431.270873 -302.72517) (xy 431.318144 -302.738862) (xy 431.362606 -302.75996)
			(xy 431.403109 -302.787916) (xy 431.438602 -302.822008) (xy 431.468167 -302.861352) (xy 431.491038 -302.904929)
			(xy 431.506622 -302.95161) (xy 431.514517 -303.000187) (xy 431.515012 -303.024794) (xy 431.514517 -303.049401)
			(xy 431.506622 -303.097978) (xy 431.491038 -303.144659) (xy 431.468167 -303.188236) (xy 431.438602 -303.22758)
			(xy 431.428387 -303.237392) (xy 434.411374 -303.237392) (xy 434.41186 -303.210141) (xy 434.419616 -303.156193)
			(xy 434.434971 -303.103898) (xy 434.457613 -303.054321) (xy 434.487079 -303.008471) (xy 434.52277 -302.96728)
			(xy 434.563961 -302.931589) (xy 434.609811 -302.902123) (xy 434.659388 -302.879481) (xy 434.711683 -302.864126)
			(xy 434.765631 -302.85637) (xy 434.820133 -302.85637) (xy 434.874081 -302.864126) (xy 434.926376 -302.879481)
			(xy 434.975953 -302.902123) (xy 435.021803 -302.931589) (xy 435.062994 -302.96728) (xy 435.098685 -303.008471)
			(xy 435.110481 -303.026826) (xy 436.919622 -303.026826) (xy 436.923693 -302.971204) (xy 436.935819 -302.916767)
			(xy 436.955742 -302.864676) (xy 436.983038 -302.816041) (xy 437.017124 -302.771898) (xy 437.057273 -302.733189)
			(xy 437.102631 -302.700738) (xy 437.152231 -302.675237) (xy 437.205015 -302.65723) (xy 437.259858 -302.6471)
			(xy 437.315592 -302.645063) (xy 437.371029 -302.651163) (xy 437.424986 -302.665269) (xy 437.476315 -302.687081)
			(xy 437.523921 -302.716135) (xy 437.566789 -302.75181) (xy 437.604006 -302.793347) (xy 437.634779 -302.83986)
			(xy 437.658451 -302.890357) (xy 437.674519 -302.943764) (xy 437.682639 -302.99894) (xy 437.683148 -303.026826)
			(xy 437.935622 -303.026826) (xy 437.939693 -302.971204) (xy 437.951819 -302.916767) (xy 437.971742 -302.864676)
			(xy 437.999038 -302.816041) (xy 438.033124 -302.771898) (xy 438.073273 -302.733189) (xy 438.118631 -302.700738)
			(xy 438.168231 -302.675237) (xy 438.221015 -302.65723) (xy 438.275858 -302.6471) (xy 438.331592 -302.645063)
			(xy 438.387029 -302.651163) (xy 438.440986 -302.665269) (xy 438.492315 -302.687081) (xy 438.539921 -302.716135)
			(xy 438.582789 -302.75181) (xy 438.620006 -302.793347) (xy 438.650779 -302.83986) (xy 438.674451 -302.890357)
			(xy 438.690519 -302.943764) (xy 438.698639 -302.99894) (xy 438.699148 -303.026826) (xy 438.951622 -303.026826)
			(xy 438.955693 -302.971204) (xy 438.967819 -302.916767) (xy 438.987742 -302.864676) (xy 439.015038 -302.816041)
			(xy 439.049124 -302.771898) (xy 439.089273 -302.733189) (xy 439.134631 -302.700738) (xy 439.184231 -302.675237)
			(xy 439.237015 -302.65723) (xy 439.291858 -302.6471) (xy 439.347592 -302.645063) (xy 439.403029 -302.651163)
			(xy 439.456986 -302.665269) (xy 439.508315 -302.687081) (xy 439.555921 -302.716135) (xy 439.598789 -302.75181)
			(xy 439.636006 -302.793347) (xy 439.666779 -302.83986) (xy 439.690451 -302.890357) (xy 439.706519 -302.943764)
			(xy 439.714639 -302.99894) (xy 439.715148 -303.026826) (xy 439.967622 -303.026826) (xy 439.971693 -302.971204)
			(xy 439.983819 -302.916767) (xy 440.003742 -302.864676) (xy 440.031038 -302.816041) (xy 440.065124 -302.771898)
			(xy 440.105273 -302.733189) (xy 440.150631 -302.700738) (xy 440.200231 -302.675237) (xy 440.253015 -302.65723)
			(xy 440.307858 -302.6471) (xy 440.363592 -302.645063) (xy 440.419029 -302.651163) (xy 440.472986 -302.665269)
			(xy 440.524315 -302.687081) (xy 440.571921 -302.716135) (xy 440.614789 -302.75181) (xy 440.652006 -302.793347)
			(xy 440.682779 -302.83986) (xy 440.706451 -302.890357) (xy 440.722519 -302.943764) (xy 440.730639 -302.99894)
			(xy 440.731148 -303.026826) (xy 440.983622 -303.026826) (xy 440.987693 -302.971204) (xy 440.999819 -302.916767)
			(xy 441.019742 -302.864676) (xy 441.047038 -302.816041) (xy 441.081124 -302.771898) (xy 441.121273 -302.733189)
			(xy 441.166631 -302.700738) (xy 441.216231 -302.675237) (xy 441.269015 -302.65723) (xy 441.323858 -302.6471)
			(xy 441.379592 -302.645063) (xy 441.435029 -302.651163) (xy 441.488986 -302.665269) (xy 441.540315 -302.687081)
			(xy 441.587921 -302.716135) (xy 441.630789 -302.75181) (xy 441.668006 -302.793347) (xy 441.698779 -302.83986)
			(xy 441.722451 -302.890357) (xy 441.738519 -302.943764) (xy 441.746639 -302.99894) (xy 441.747148 -303.026826)
			(xy 441.746639 -303.054712) (xy 441.738519 -303.109888) (xy 441.722451 -303.163295) (xy 441.698779 -303.213792)
			(xy 441.668006 -303.260305) (xy 441.630789 -303.301842) (xy 441.587921 -303.337517) (xy 441.540315 -303.366571)
			(xy 441.488986 -303.388383) (xy 441.435029 -303.402489) (xy 441.379592 -303.408589) (xy 441.323858 -303.406552)
			(xy 441.269015 -303.396422) (xy 441.216231 -303.378415) (xy 441.166631 -303.352914) (xy 441.121273 -303.320463)
			(xy 441.081124 -303.281754) (xy 441.047038 -303.237611) (xy 441.019742 -303.188976) (xy 440.999819 -303.136885)
			(xy 440.987693 -303.082448) (xy 440.983622 -303.026826) (xy 440.731148 -303.026826) (xy 440.730639 -303.054712)
			(xy 440.722519 -303.109888) (xy 440.706451 -303.163295) (xy 440.682779 -303.213792) (xy 440.652006 -303.260305)
			(xy 440.614789 -303.301842) (xy 440.571921 -303.337517) (xy 440.524315 -303.366571) (xy 440.472986 -303.388383)
			(xy 440.419029 -303.402489) (xy 440.363592 -303.408589) (xy 440.307858 -303.406552) (xy 440.253015 -303.396422)
			(xy 440.200231 -303.378415) (xy 440.150631 -303.352914) (xy 440.105273 -303.320463) (xy 440.065124 -303.281754)
			(xy 440.031038 -303.237611) (xy 440.003742 -303.188976) (xy 439.983819 -303.136885) (xy 439.971693 -303.082448)
			(xy 439.967622 -303.026826) (xy 439.715148 -303.026826) (xy 439.714639 -303.054712) (xy 439.706519 -303.109888)
			(xy 439.690451 -303.163295) (xy 439.666779 -303.213792) (xy 439.636006 -303.260305) (xy 439.598789 -303.301842)
			(xy 439.555921 -303.337517) (xy 439.508315 -303.366571) (xy 439.456986 -303.388383) (xy 439.403029 -303.402489)
			(xy 439.347592 -303.408589) (xy 439.291858 -303.406552) (xy 439.237015 -303.396422) (xy 439.184231 -303.378415)
			(xy 439.134631 -303.352914) (xy 439.089273 -303.320463) (xy 439.049124 -303.281754) (xy 439.015038 -303.237611)
			(xy 438.987742 -303.188976) (xy 438.967819 -303.136885) (xy 438.955693 -303.082448) (xy 438.951622 -303.026826)
			(xy 438.699148 -303.026826) (xy 438.698639 -303.054712) (xy 438.690519 -303.109888) (xy 438.674451 -303.163295)
			(xy 438.650779 -303.213792) (xy 438.620006 -303.260305) (xy 438.582789 -303.301842) (xy 438.539921 -303.337517)
			(xy 438.492315 -303.366571) (xy 438.440986 -303.388383) (xy 438.387029 -303.402489) (xy 438.331592 -303.408589)
			(xy 438.275858 -303.406552) (xy 438.221015 -303.396422) (xy 438.168231 -303.378415) (xy 438.118631 -303.352914)
			(xy 438.073273 -303.320463) (xy 438.033124 -303.281754) (xy 437.999038 -303.237611) (xy 437.971742 -303.188976)
			(xy 437.951819 -303.136885) (xy 437.939693 -303.082448) (xy 437.935622 -303.026826) (xy 437.683148 -303.026826)
			(xy 437.682639 -303.054712) (xy 437.674519 -303.109888) (xy 437.658451 -303.163295) (xy 437.634779 -303.213792)
			(xy 437.604006 -303.260305) (xy 437.566789 -303.301842) (xy 437.523921 -303.337517) (xy 437.476315 -303.366571)
			(xy 437.424986 -303.388383) (xy 437.371029 -303.402489) (xy 437.315592 -303.408589) (xy 437.259858 -303.406552)
			(xy 437.205015 -303.396422) (xy 437.152231 -303.378415) (xy 437.102631 -303.352914) (xy 437.057273 -303.320463)
			(xy 437.017124 -303.281754) (xy 436.983038 -303.237611) (xy 436.955742 -303.188976) (xy 436.935819 -303.136885)
			(xy 436.923693 -303.082448) (xy 436.919622 -303.026826) (xy 435.110481 -303.026826) (xy 435.128151 -303.054321)
			(xy 435.150793 -303.103898) (xy 435.166148 -303.156193) (xy 435.173904 -303.210141) (xy 435.17439 -303.237392)
			(xy 435.173917 -303.265054) (xy 435.165948 -303.3198) (xy 435.150161 -303.372823) (xy 435.126886 -303.423013)
			(xy 435.11216 -303.446434) (xy 435.106064 -303.455578) (xy 435.102762 -303.477168) (xy 435.128924 -303.57191)
			(xy 435.14264 -303.58842) (xy 435.152546 -303.593246) (xy 435.176365 -303.605269) (xy 435.220622 -303.635074)
			(xy 435.260295 -303.670753) (xy 435.294611 -303.711612) (xy 435.3229 -303.756852) (xy 435.34461 -303.805593)
			(xy 435.359318 -303.856883) (xy 435.366738 -303.909721) (xy 435.367176 -303.9364) (xy 435.36669 -303.963651)
			(xy 435.358934 -304.017599) (xy 435.343579 -304.069894) (xy 435.320937 -304.119471) (xy 435.291471 -304.165321)
			(xy 435.25578 -304.206512) (xy 435.214589 -304.242203) (xy 435.168739 -304.271669) (xy 435.119162 -304.294311)
			(xy 435.066867 -304.309666) (xy 435.012919 -304.317422) (xy 434.958417 -304.317422) (xy 434.904469 -304.309666)
			(xy 434.852174 -304.294311) (xy 434.802597 -304.271669) (xy 434.756747 -304.242203) (xy 434.715556 -304.206512)
			(xy 434.679865 -304.165321) (xy 434.650399 -304.119471) (xy 434.627757 -304.069894) (xy 434.612402 -304.017599)
			(xy 434.604646 -303.963651) (xy 434.60416 -303.9364) (xy 434.604621 -303.908738) (xy 434.612592 -303.85399)
			(xy 434.628383 -303.800967) (xy 434.651662 -303.750779) (xy 434.66639 -303.727358) (xy 434.672486 -303.718214)
			(xy 434.675788 -303.696624) (xy 434.649626 -303.601882) (xy 434.63591 -303.585372) (xy 434.626004 -303.580546)
			(xy 434.602193 -303.568507) (xy 434.557934 -303.538707) (xy 434.518259 -303.503031) (xy 434.483941 -303.462175)
			(xy 434.455651 -303.416936) (xy 434.43394 -303.368197) (xy 434.419231 -303.316908) (xy 434.411812 -303.26407)
			(xy 434.411374 -303.237392) (xy 431.428387 -303.237392) (xy 431.403109 -303.261672) (xy 431.362606 -303.289628)
			(xy 431.318144 -303.310726) (xy 431.270873 -303.324418) (xy 431.222018 -303.33035) (xy 431.172843 -303.328369)
			(xy 431.124624 -303.318525) (xy 431.078608 -303.301073) (xy 431.035987 -303.276466) (xy 430.997866 -303.245341)
			(xy 430.965231 -303.208504) (xy 430.938928 -303.166908) (xy 430.919637 -303.121632) (xy 430.90786 -303.073848)
			(xy 430.9039 -303.024794) (xy 430.580292 -303.024794) (xy 430.579797 -303.049401) (xy 430.571902 -303.097978)
			(xy 430.556318 -303.144659) (xy 430.533447 -303.188236) (xy 430.503882 -303.22758) (xy 430.468389 -303.261672)
			(xy 430.427886 -303.289628) (xy 430.383424 -303.310726) (xy 430.336153 -303.324418) (xy 430.287298 -303.33035)
			(xy 430.238123 -303.328369) (xy 430.189904 -303.318525) (xy 430.143888 -303.301073) (xy 430.101267 -303.276466)
			(xy 430.063146 -303.245341) (xy 430.030511 -303.208504) (xy 430.004208 -303.166908) (xy 429.984917 -303.121632)
			(xy 429.97314 -303.073848) (xy 429.96918 -303.024794) (xy 429.630332 -303.024794) (xy 429.629837 -303.049401)
			(xy 429.621942 -303.097978) (xy 429.606358 -303.144659) (xy 429.583487 -303.188236) (xy 429.553922 -303.22758)
			(xy 429.518429 -303.261672) (xy 429.477926 -303.289628) (xy 429.433464 -303.310726) (xy 429.386193 -303.324418)
			(xy 429.337338 -303.33035) (xy 429.288163 -303.328369) (xy 429.239944 -303.318525) (xy 429.193928 -303.301073)
			(xy 429.151307 -303.276466) (xy 429.113186 -303.245341) (xy 429.080551 -303.208504) (xy 429.054248 -303.166908)
			(xy 429.034957 -303.121632) (xy 429.02318 -303.073848) (xy 429.01922 -303.024794) (xy 428.680118 -303.024794)
			(xy 428.679623 -303.049401) (xy 428.671728 -303.097978) (xy 428.656144 -303.144659) (xy 428.633273 -303.188236)
			(xy 428.603708 -303.22758) (xy 428.568215 -303.261672) (xy 428.527712 -303.289628) (xy 428.48325 -303.310726)
			(xy 428.435979 -303.324418) (xy 428.387124 -303.33035) (xy 428.337949 -303.328369) (xy 428.28973 -303.318525)
			(xy 428.243714 -303.301073) (xy 428.201093 -303.276466) (xy 428.162972 -303.245341) (xy 428.130337 -303.208504)
			(xy 428.104034 -303.166908) (xy 428.084743 -303.121632) (xy 428.072966 -303.073848) (xy 428.069006 -303.024794)
			(xy 427.730065 -303.024794) (xy 427.730514 -303.03305) (xy 427.725152 -303.082398) (xy 427.711878 -303.130229)
			(xy 427.69104 -303.175283) (xy 427.663189 -303.216372) (xy 427.629057 -303.252414) (xy 427.589544 -303.282459)
			(xy 427.545691 -303.305717) (xy 427.498653 -303.321574) (xy 427.449669 -303.329612) (xy 427.42485 -303.330102)
			(xy 427.410667 -303.329919) (xy 427.382427 -303.327251) (xy 427.368462 -303.324768) (xy 427.356016 -303.322482)
			(xy 427.332394 -303.329848) (xy 427.254924 -303.407318) (xy 427.247558 -303.43094) (xy 427.249844 -303.443386)
			(xy 427.252314 -303.457353) (xy 427.25499 -303.485592) (xy 427.255178 -303.499774) (xy 427.254656 -303.525029)
			(xy 427.246343 -303.574851) (xy 427.229942 -303.622625) (xy 427.205901 -303.667048) (xy 427.174877 -303.706908)
			(xy 427.137715 -303.741118) (xy 427.095429 -303.768744) (xy 427.049173 -303.789034) (xy 427.000208 -303.801434)
			(xy 426.94987 -303.805605) (xy 426.899532 -303.801434) (xy 426.850567 -303.789034) (xy 426.804311 -303.768744)
			(xy 426.762025 -303.741118) (xy 426.724863 -303.706908) (xy 426.693839 -303.667048) (xy 426.669798 -303.622625)
			(xy 426.653397 -303.574851) (xy 426.645084 -303.525029) (xy 426.644562 -303.499774) (xy 426.644736 -303.485591)
			(xy 426.64741 -303.457351) (xy 426.649896 -303.443386) (xy 426.652182 -303.43094) (xy 426.644816 -303.407318)
			(xy 426.567346 -303.329848) (xy 426.543724 -303.322482) (xy 426.531278 -303.324768) (xy 426.517312 -303.327243)
			(xy 426.489072 -303.329916) (xy 426.47489 -303.330102) (xy 426.45007 -303.329611) (xy 426.401085 -303.321579)
			(xy 426.354044 -303.305728) (xy 426.310188 -303.282475) (xy 426.270671 -303.252433) (xy 426.236535 -303.216394)
			(xy 426.208678 -303.175308) (xy 426.187836 -303.130256) (xy 426.174557 -303.082425) (xy 426.169191 -303.033077)
			(xy 425.830071 -303.033077) (xy 425.829743 -303.049401) (xy 425.821848 -303.097978) (xy 425.806264 -303.144659)
			(xy 425.783393 -303.188236) (xy 425.753828 -303.22758) (xy 425.718335 -303.261672) (xy 425.677832 -303.289628)
			(xy 425.63337 -303.310726) (xy 425.586099 -303.324418) (xy 425.537244 -303.33035) (xy 425.488069 -303.328369)
			(xy 425.43985 -303.318525) (xy 425.393834 -303.301073) (xy 425.351213 -303.276466) (xy 425.313092 -303.245341)
			(xy 425.280457 -303.208504) (xy 425.254154 -303.166908) (xy 425.234863 -303.121632) (xy 425.223086 -303.073848)
			(xy 425.219126 -303.024794) (xy 424.880262 -303.024794) (xy 424.880712 -303.033104) (xy 424.875341 -303.082454)
			(xy 424.862057 -303.130285) (xy 424.84121 -303.175337) (xy 424.813348 -303.216422) (xy 424.779207 -303.252459)
			(xy 424.739685 -303.282497) (xy 424.695824 -303.305746) (xy 424.648779 -303.321592) (xy 424.599791 -303.329619)
			(xy 424.57497 -303.330102) (xy 424.560787 -303.32993) (xy 424.532547 -303.327255) (xy 424.518582 -303.324768)
			(xy 424.504617 -303.322603) (xy 424.476487 -303.325186) (xy 424.450141 -303.335378) (xy 424.427596 -303.352398)
			(xy 424.410576 -303.374944) (xy 424.400386 -303.40129) (xy 424.397803 -303.42942) (xy 424.399964 -303.443386)
			(xy 424.402434 -303.457353) (xy 424.40511 -303.485592) (xy 424.405298 -303.499774) (xy 424.40485 -303.524597)
			(xy 424.396822 -303.57359) (xy 424.380974 -303.620639) (xy 424.357723 -303.664504) (xy 424.327681 -303.70403)
			(xy 424.29164 -303.738175) (xy 424.250551 -303.766039) (xy 424.205494 -303.786888) (xy 424.157658 -303.800173)
			(xy 424.108303 -303.805544) (xy 424.058729 -303.80286) (xy 424.010243 -303.79219) (xy 423.964121 -303.773817)
			(xy 423.92158 -303.748224) (xy 423.883739 -303.716086) (xy 423.851597 -303.67825) (xy 423.825999 -303.635711)
			(xy 423.80762 -303.589592) (xy 423.796945 -303.541106) (xy 423.794255 -303.491533) (xy 423.455172 -303.491533)
			(xy 423.455338 -303.499774) (xy 423.454843 -303.524381) (xy 423.446948 -303.572958) (xy 423.431364 -303.619639)
			(xy 423.408493 -303.663216) (xy 423.378928 -303.70256) (xy 423.343435 -303.736652) (xy 423.302932 -303.764608)
			(xy 423.25847 -303.785706) (xy 423.211199 -303.799398) (xy 423.162344 -303.80533) (xy 423.113169 -303.803349)
			(xy 423.06495 -303.793505) (xy 423.018934 -303.776053) (xy 422.976313 -303.751446) (xy 422.938192 -303.720321)
			(xy 422.905557 -303.683484) (xy 422.879254 -303.641888) (xy 422.859963 -303.596612) (xy 422.848186 -303.548828)
			(xy 422.844226 -303.499774) (xy 398.317212 -303.499774) (xy 398.317212 -303.974754) (xy 398.61923 -303.974754)
			(xy 398.62319 -303.9257) (xy 398.634967 -303.877916) (xy 398.654258 -303.83264) (xy 398.680561 -303.791044)
			(xy 398.713196 -303.754207) (xy 398.751317 -303.723082) (xy 398.793938 -303.698475) (xy 398.839954 -303.681023)
			(xy 398.888173 -303.671179) (xy 398.937348 -303.669198) (xy 398.986203 -303.67513) (xy 399.033474 -303.688822)
			(xy 399.077936 -303.70992) (xy 399.118439 -303.737876) (xy 399.153932 -303.771968) (xy 399.183497 -303.811312)
			(xy 399.206368 -303.854889) (xy 399.221952 -303.90157) (xy 399.229847 -303.950147) (xy 399.230342 -303.974754)
			(xy 399.56919 -303.974754) (xy 399.57315 -303.9257) (xy 399.584927 -303.877916) (xy 399.604218 -303.83264)
			(xy 399.630521 -303.791044) (xy 399.663156 -303.754207) (xy 399.701277 -303.723082) (xy 399.743898 -303.698475)
			(xy 399.789914 -303.681023) (xy 399.838133 -303.671179) (xy 399.887308 -303.669198) (xy 399.936163 -303.67513)
			(xy 399.983434 -303.688822) (xy 400.027896 -303.70992) (xy 400.068399 -303.737876) (xy 400.103892 -303.771968)
			(xy 400.133457 -303.811312) (xy 400.156328 -303.854889) (xy 400.171912 -303.90157) (xy 400.179807 -303.950147)
			(xy 400.180302 -303.974754) (xy 400.51915 -303.974754) (xy 400.52311 -303.9257) (xy 400.534887 -303.877916)
			(xy 400.554178 -303.83264) (xy 400.580481 -303.791044) (xy 400.613116 -303.754207) (xy 400.651237 -303.723082)
			(xy 400.693858 -303.698475) (xy 400.739874 -303.681023) (xy 400.788093 -303.671179) (xy 400.837268 -303.669198)
			(xy 400.886123 -303.67513) (xy 400.933394 -303.688822) (xy 400.977856 -303.70992) (xy 401.018359 -303.737876)
			(xy 401.053852 -303.771968) (xy 401.083417 -303.811312) (xy 401.106288 -303.854889) (xy 401.121872 -303.90157)
			(xy 401.129767 -303.950147) (xy 401.130262 -303.974754) (xy 401.46911 -303.974754) (xy 401.47307 -303.9257)
			(xy 401.484847 -303.877916) (xy 401.504138 -303.83264) (xy 401.530441 -303.791044) (xy 401.563076 -303.754207)
			(xy 401.601197 -303.723082) (xy 401.643818 -303.698475) (xy 401.689834 -303.681023) (xy 401.738053 -303.671179)
			(xy 401.787228 -303.669198) (xy 401.836083 -303.67513) (xy 401.883354 -303.688822) (xy 401.927816 -303.70992)
			(xy 401.968319 -303.737876) (xy 402.003812 -303.771968) (xy 402.033377 -303.811312) (xy 402.056248 -303.854889)
			(xy 402.071832 -303.90157) (xy 402.079727 -303.950147) (xy 402.080222 -303.974754) (xy 402.41907 -303.974754)
			(xy 402.42303 -303.9257) (xy 402.434807 -303.877916) (xy 402.454098 -303.83264) (xy 402.480401 -303.791044)
			(xy 402.513036 -303.754207) (xy 402.551157 -303.723082) (xy 402.593778 -303.698475) (xy 402.639794 -303.681023)
			(xy 402.688013 -303.671179) (xy 402.737188 -303.669198) (xy 402.786043 -303.67513) (xy 402.833314 -303.688822)
			(xy 402.877776 -303.70992) (xy 402.918279 -303.737876) (xy 402.953772 -303.771968) (xy 402.983337 -303.811312)
			(xy 403.006208 -303.854889) (xy 403.021792 -303.90157) (xy 403.029687 -303.950147) (xy 403.030182 -303.974754)
			(xy 403.36903 -303.974754) (xy 403.37299 -303.9257) (xy 403.384767 -303.877916) (xy 403.404058 -303.83264)
			(xy 403.430361 -303.791044) (xy 403.462996 -303.754207) (xy 403.501117 -303.723082) (xy 403.543738 -303.698475)
			(xy 403.589754 -303.681023) (xy 403.637973 -303.671179) (xy 403.687148 -303.669198) (xy 403.736003 -303.67513)
			(xy 403.783274 -303.688822) (xy 403.827736 -303.70992) (xy 403.868239 -303.737876) (xy 403.903732 -303.771968)
			(xy 403.933297 -303.811312) (xy 403.956168 -303.854889) (xy 403.971752 -303.90157) (xy 403.979647 -303.950147)
			(xy 403.980142 -303.974754) (xy 404.31899 -303.974754) (xy 404.32295 -303.9257) (xy 404.334727 -303.877916)
			(xy 404.354018 -303.83264) (xy 404.380321 -303.791044) (xy 404.412956 -303.754207) (xy 404.451077 -303.723082)
			(xy 404.493698 -303.698475) (xy 404.539714 -303.681023) (xy 404.587933 -303.671179) (xy 404.637108 -303.669198)
			(xy 404.685963 -303.67513) (xy 404.733234 -303.688822) (xy 404.777696 -303.70992) (xy 404.818199 -303.737876)
			(xy 404.853692 -303.771968) (xy 404.883257 -303.811312) (xy 404.906128 -303.854889) (xy 404.921712 -303.90157)
			(xy 404.929607 -303.950147) (xy 404.930102 -303.974754) (xy 405.269204 -303.974754) (xy 405.273164 -303.9257)
			(xy 405.284941 -303.877916) (xy 405.304232 -303.83264) (xy 405.330535 -303.791044) (xy 405.36317 -303.754207)
			(xy 405.401291 -303.723082) (xy 405.443912 -303.698475) (xy 405.489928 -303.681023) (xy 405.538147 -303.671179)
			(xy 405.587322 -303.669198) (xy 405.636177 -303.67513) (xy 405.683448 -303.688822) (xy 405.72791 -303.70992)
			(xy 405.768413 -303.737876) (xy 405.803906 -303.771968) (xy 405.833471 -303.811312) (xy 405.856342 -303.854889)
			(xy 405.871926 -303.90157) (xy 405.879821 -303.950147) (xy 405.880316 -303.974754) (xy 406.219164 -303.974754)
			(xy 406.223124 -303.9257) (xy 406.234901 -303.877916) (xy 406.254192 -303.83264) (xy 406.280495 -303.791044)
			(xy 406.31313 -303.754207) (xy 406.351251 -303.723082) (xy 406.393872 -303.698475) (xy 406.439888 -303.681023)
			(xy 406.488107 -303.671179) (xy 406.537282 -303.669198) (xy 406.586137 -303.67513) (xy 406.633408 -303.688822)
			(xy 406.67787 -303.70992) (xy 406.718373 -303.737876) (xy 406.753866 -303.771968) (xy 406.783431 -303.811312)
			(xy 406.806302 -303.854889) (xy 406.821886 -303.90157) (xy 406.829781 -303.950147) (xy 406.830276 -303.974754)
			(xy 408.119084 -303.974754) (xy 408.123044 -303.9257) (xy 408.134821 -303.877916) (xy 408.154112 -303.83264)
			(xy 408.180415 -303.791044) (xy 408.21305 -303.754207) (xy 408.251171 -303.723082) (xy 408.293792 -303.698475)
			(xy 408.339808 -303.681023) (xy 408.388027 -303.671179) (xy 408.437202 -303.669198) (xy 408.486057 -303.67513)
			(xy 408.533328 -303.688822) (xy 408.57779 -303.70992) (xy 408.618293 -303.737876) (xy 408.653786 -303.771968)
			(xy 408.683351 -303.811312) (xy 408.706222 -303.854889) (xy 408.721806 -303.90157) (xy 408.729701 -303.950147)
			(xy 408.730196 -303.974754) (xy 409.069044 -303.974754) (xy 409.073004 -303.9257) (xy 409.084781 -303.877916)
			(xy 409.104072 -303.83264) (xy 409.130375 -303.791044) (xy 409.16301 -303.754207) (xy 409.201131 -303.723082)
			(xy 409.243752 -303.698475) (xy 409.289768 -303.681023) (xy 409.337987 -303.671179) (xy 409.387162 -303.669198)
			(xy 409.436017 -303.67513) (xy 409.483288 -303.688822) (xy 409.52775 -303.70992) (xy 409.568253 -303.737876)
			(xy 409.603746 -303.771968) (xy 409.633311 -303.811312) (xy 409.656182 -303.854889) (xy 409.671766 -303.90157)
			(xy 409.679661 -303.950147) (xy 409.680156 -303.974754) (xy 410.019004 -303.974754) (xy 410.022964 -303.9257)
			(xy 410.034741 -303.877916) (xy 410.054032 -303.83264) (xy 410.080335 -303.791044) (xy 410.11297 -303.754207)
			(xy 410.151091 -303.723082) (xy 410.193712 -303.698475) (xy 410.239728 -303.681023) (xy 410.287947 -303.671179)
			(xy 410.337122 -303.669198) (xy 410.385977 -303.67513) (xy 410.433248 -303.688822) (xy 410.47771 -303.70992)
			(xy 410.518213 -303.737876) (xy 410.553706 -303.771968) (xy 410.583271 -303.811312) (xy 410.606142 -303.854889)
			(xy 410.621726 -303.90157) (xy 410.629621 -303.950147) (xy 410.630116 -303.974754) (xy 410.969218 -303.974754)
			(xy 410.973178 -303.9257) (xy 410.984955 -303.877916) (xy 411.004246 -303.83264) (xy 411.030549 -303.791044)
			(xy 411.063184 -303.754207) (xy 411.101305 -303.723082) (xy 411.143926 -303.698475) (xy 411.189942 -303.681023)
			(xy 411.238161 -303.671179) (xy 411.287336 -303.669198) (xy 411.336191 -303.67513) (xy 411.383462 -303.688822)
			(xy 411.427924 -303.70992) (xy 411.468427 -303.737876) (xy 411.50392 -303.771968) (xy 411.533485 -303.811312)
			(xy 411.556356 -303.854889) (xy 411.57194 -303.90157) (xy 411.579835 -303.950147) (xy 411.58033 -303.974754)
			(xy 411.919178 -303.974754) (xy 411.923138 -303.9257) (xy 411.934915 -303.877916) (xy 411.954206 -303.83264)
			(xy 411.980509 -303.791044) (xy 412.013144 -303.754207) (xy 412.051265 -303.723082) (xy 412.093886 -303.698475)
			(xy 412.139902 -303.681023) (xy 412.188121 -303.671179) (xy 412.237296 -303.669198) (xy 412.286151 -303.67513)
			(xy 412.333422 -303.688822) (xy 412.377884 -303.70992) (xy 412.418387 -303.737876) (xy 412.45388 -303.771968)
			(xy 412.483445 -303.811312) (xy 412.506316 -303.854889) (xy 412.5219 -303.90157) (xy 412.529795 -303.950147)
			(xy 412.53029 -303.974754) (xy 412.869138 -303.974754) (xy 412.873098 -303.9257) (xy 412.884875 -303.877916)
			(xy 412.904166 -303.83264) (xy 412.930469 -303.791044) (xy 412.963104 -303.754207) (xy 413.001225 -303.723082)
			(xy 413.043846 -303.698475) (xy 413.089862 -303.681023) (xy 413.138081 -303.671179) (xy 413.187256 -303.669198)
			(xy 413.236111 -303.67513) (xy 413.283382 -303.688822) (xy 413.327844 -303.70992) (xy 413.368347 -303.737876)
			(xy 413.40384 -303.771968) (xy 413.433405 -303.811312) (xy 413.456276 -303.854889) (xy 413.47186 -303.90157)
			(xy 413.479755 -303.950147) (xy 413.48025 -303.974754) (xy 413.819098 -303.974754) (xy 413.823058 -303.9257)
			(xy 413.834835 -303.877916) (xy 413.854126 -303.83264) (xy 413.880429 -303.791044) (xy 413.913064 -303.754207)
			(xy 413.951185 -303.723082) (xy 413.993806 -303.698475) (xy 414.039822 -303.681023) (xy 414.088041 -303.671179)
			(xy 414.137216 -303.669198) (xy 414.186071 -303.67513) (xy 414.233342 -303.688822) (xy 414.277804 -303.70992)
			(xy 414.318307 -303.737876) (xy 414.3538 -303.771968) (xy 414.383365 -303.811312) (xy 414.406236 -303.854889)
			(xy 414.42182 -303.90157) (xy 414.429715 -303.950147) (xy 414.43021 -303.974754) (xy 414.769058 -303.974754)
			(xy 414.773018 -303.9257) (xy 414.784795 -303.877916) (xy 414.804086 -303.83264) (xy 414.830389 -303.791044)
			(xy 414.863024 -303.754207) (xy 414.901145 -303.723082) (xy 414.943766 -303.698475) (xy 414.989782 -303.681023)
			(xy 415.038001 -303.671179) (xy 415.087176 -303.669198) (xy 415.136031 -303.67513) (xy 415.183302 -303.688822)
			(xy 415.227764 -303.70992) (xy 415.268267 -303.737876) (xy 415.30376 -303.771968) (xy 415.333325 -303.811312)
			(xy 415.356196 -303.854889) (xy 415.37178 -303.90157) (xy 415.379675 -303.950147) (xy 415.38017 -303.974754)
			(xy 415.719018 -303.974754) (xy 415.722978 -303.9257) (xy 415.734755 -303.877916) (xy 415.754046 -303.83264)
			(xy 415.780349 -303.791044) (xy 415.812984 -303.754207) (xy 415.851105 -303.723082) (xy 415.893726 -303.698475)
			(xy 415.939742 -303.681023) (xy 415.987961 -303.671179) (xy 416.037136 -303.669198) (xy 416.085991 -303.67513)
			(xy 416.133262 -303.688822) (xy 416.177724 -303.70992) (xy 416.218227 -303.737876) (xy 416.25372 -303.771968)
			(xy 416.283285 -303.811312) (xy 416.306156 -303.854889) (xy 416.32174 -303.90157) (xy 416.329635 -303.950147)
			(xy 416.330033 -303.969928) (xy 416.674058 -303.969928) (xy 416.678018 -303.920874) (xy 416.689795 -303.87309)
			(xy 416.709086 -303.827814) (xy 416.735389 -303.786218) (xy 416.768024 -303.749381) (xy 416.806145 -303.718256)
			(xy 416.848766 -303.693649) (xy 416.894782 -303.676197) (xy 416.943001 -303.666353) (xy 416.992176 -303.664372)
			(xy 417.041031 -303.670304) (xy 417.088302 -303.683996) (xy 417.132764 -303.705094) (xy 417.173267 -303.73305)
			(xy 417.20876 -303.767142) (xy 417.238325 -303.806486) (xy 417.261196 -303.850063) (xy 417.27678 -303.896744)
			(xy 417.284675 -303.945321) (xy 417.28517 -303.969928) (xy 417.285073 -303.974754) (xy 417.619192 -303.974754)
			(xy 417.623152 -303.9257) (xy 417.634929 -303.877916) (xy 417.65422 -303.83264) (xy 417.680523 -303.791044)
			(xy 417.713158 -303.754207) (xy 417.751279 -303.723082) (xy 417.7939 -303.698475) (xy 417.839916 -303.681023)
			(xy 417.888135 -303.671179) (xy 417.93731 -303.669198) (xy 417.986165 -303.67513) (xy 418.033436 -303.688822)
			(xy 418.077898 -303.70992) (xy 418.118401 -303.737876) (xy 418.153894 -303.771968) (xy 418.183459 -303.811312)
			(xy 418.20633 -303.854889) (xy 418.221914 -303.90157) (xy 418.229809 -303.950147) (xy 418.230304 -303.974754)
			(xy 418.569152 -303.974754) (xy 418.573112 -303.9257) (xy 418.584889 -303.877916) (xy 418.60418 -303.83264)
			(xy 418.630483 -303.791044) (xy 418.663118 -303.754207) (xy 418.701239 -303.723082) (xy 418.74386 -303.698475)
			(xy 418.789876 -303.681023) (xy 418.838095 -303.671179) (xy 418.88727 -303.669198) (xy 418.936125 -303.67513)
			(xy 418.983396 -303.688822) (xy 419.027858 -303.70992) (xy 419.068361 -303.737876) (xy 419.103854 -303.771968)
			(xy 419.133419 -303.811312) (xy 419.15629 -303.854889) (xy 419.171874 -303.90157) (xy 419.179769 -303.950147)
			(xy 419.180264 -303.974754) (xy 419.519112 -303.974754) (xy 419.523072 -303.9257) (xy 419.534849 -303.877916)
			(xy 419.55414 -303.83264) (xy 419.580443 -303.791044) (xy 419.613078 -303.754207) (xy 419.651199 -303.723082)
			(xy 419.69382 -303.698475) (xy 419.739836 -303.681023) (xy 419.788055 -303.671179) (xy 419.83723 -303.669198)
			(xy 419.886085 -303.67513) (xy 419.933356 -303.688822) (xy 419.977818 -303.70992) (xy 420.018321 -303.737876)
			(xy 420.053814 -303.771968) (xy 420.083379 -303.811312) (xy 420.10625 -303.854889) (xy 420.121834 -303.90157)
			(xy 420.129729 -303.950147) (xy 420.130224 -303.974754) (xy 420.469072 -303.974754) (xy 420.473032 -303.9257)
			(xy 420.484809 -303.877916) (xy 420.5041 -303.83264) (xy 420.530403 -303.791044) (xy 420.563038 -303.754207)
			(xy 420.601159 -303.723082) (xy 420.64378 -303.698475) (xy 420.689796 -303.681023) (xy 420.738015 -303.671179)
			(xy 420.78719 -303.669198) (xy 420.836045 -303.67513) (xy 420.883316 -303.688822) (xy 420.927778 -303.70992)
			(xy 420.968281 -303.737876) (xy 421.003774 -303.771968) (xy 421.033339 -303.811312) (xy 421.05621 -303.854889)
			(xy 421.071794 -303.90157) (xy 421.079689 -303.950147) (xy 421.080184 -303.974754) (xy 421.419032 -303.974754)
			(xy 421.422992 -303.9257) (xy 421.434769 -303.877916) (xy 421.45406 -303.83264) (xy 421.480363 -303.791044)
			(xy 421.512998 -303.754207) (xy 421.551119 -303.723082) (xy 421.59374 -303.698475) (xy 421.639756 -303.681023)
			(xy 421.687975 -303.671179) (xy 421.73715 -303.669198) (xy 421.786005 -303.67513) (xy 421.833276 -303.688822)
			(xy 421.877738 -303.70992) (xy 421.918241 -303.737876) (xy 421.953734 -303.771968) (xy 421.983299 -303.811312)
			(xy 422.00617 -303.854889) (xy 422.021754 -303.90157) (xy 422.029649 -303.950147) (xy 422.030144 -303.974754)
			(xy 422.029649 -303.999361) (xy 422.021754 -304.047938) (xy 422.00617 -304.094619) (xy 421.983299 -304.138196)
			(xy 421.953734 -304.17754) (xy 421.918241 -304.211632) (xy 421.877738 -304.239588) (xy 421.833276 -304.260686)
			(xy 421.786005 -304.274378) (xy 421.73715 -304.28031) (xy 421.687975 -304.278329) (xy 421.639756 -304.268485)
			(xy 421.59374 -304.251033) (xy 421.551119 -304.226426) (xy 421.512998 -304.195301) (xy 421.480363 -304.158464)
			(xy 421.45406 -304.116868) (xy 421.434769 -304.071592) (xy 421.422992 -304.023808) (xy 421.419032 -303.974754)
			(xy 421.080184 -303.974754) (xy 421.079689 -303.999361) (xy 421.071794 -304.047938) (xy 421.05621 -304.094619)
			(xy 421.033339 -304.138196) (xy 421.003774 -304.17754) (xy 420.968281 -304.211632) (xy 420.927778 -304.239588)
			(xy 420.883316 -304.260686) (xy 420.836045 -304.274378) (xy 420.78719 -304.28031) (xy 420.738015 -304.278329)
			(xy 420.689796 -304.268485) (xy 420.64378 -304.251033) (xy 420.601159 -304.226426) (xy 420.563038 -304.195301)
			(xy 420.530403 -304.158464) (xy 420.5041 -304.116868) (xy 420.484809 -304.071592) (xy 420.473032 -304.023808)
			(xy 420.469072 -303.974754) (xy 420.130224 -303.974754) (xy 420.129729 -303.999361) (xy 420.121834 -304.047938)
			(xy 420.10625 -304.094619) (xy 420.083379 -304.138196) (xy 420.053814 -304.17754) (xy 420.018321 -304.211632)
			(xy 419.977818 -304.239588) (xy 419.933356 -304.260686) (xy 419.886085 -304.274378) (xy 419.83723 -304.28031)
			(xy 419.788055 -304.278329) (xy 419.739836 -304.268485) (xy 419.69382 -304.251033) (xy 419.651199 -304.226426)
			(xy 419.613078 -304.195301) (xy 419.580443 -304.158464) (xy 419.55414 -304.116868) (xy 419.534849 -304.071592)
			(xy 419.523072 -304.023808) (xy 419.519112 -303.974754) (xy 419.180264 -303.974754) (xy 419.179769 -303.999361)
			(xy 419.171874 -304.047938) (xy 419.15629 -304.094619) (xy 419.133419 -304.138196) (xy 419.103854 -304.17754)
			(xy 419.068361 -304.211632) (xy 419.027858 -304.239588) (xy 418.983396 -304.260686) (xy 418.936125 -304.274378)
			(xy 418.88727 -304.28031) (xy 418.838095 -304.278329) (xy 418.789876 -304.268485) (xy 418.74386 -304.251033)
			(xy 418.701239 -304.226426) (xy 418.663118 -304.195301) (xy 418.630483 -304.158464) (xy 418.60418 -304.116868)
			(xy 418.584889 -304.071592) (xy 418.573112 -304.023808) (xy 418.569152 -303.974754) (xy 418.230304 -303.974754)
			(xy 418.229809 -303.999361) (xy 418.221914 -304.047938) (xy 418.20633 -304.094619) (xy 418.183459 -304.138196)
			(xy 418.153894 -304.17754) (xy 418.118401 -304.211632) (xy 418.077898 -304.239588) (xy 418.033436 -304.260686)
			(xy 417.986165 -304.274378) (xy 417.93731 -304.28031) (xy 417.888135 -304.278329) (xy 417.839916 -304.268485)
			(xy 417.7939 -304.251033) (xy 417.751279 -304.226426) (xy 417.713158 -304.195301) (xy 417.680523 -304.158464)
			(xy 417.65422 -304.116868) (xy 417.634929 -304.071592) (xy 417.623152 -304.023808) (xy 417.619192 -303.974754)
			(xy 417.285073 -303.974754) (xy 417.284675 -303.994535) (xy 417.27678 -304.043112) (xy 417.261196 -304.089793)
			(xy 417.238325 -304.13337) (xy 417.20876 -304.172714) (xy 417.173267 -304.206806) (xy 417.132764 -304.234762)
			(xy 417.088302 -304.25586) (xy 417.041031 -304.269552) (xy 416.992176 -304.275484) (xy 416.943001 -304.273503)
			(xy 416.894782 -304.263659) (xy 416.848766 -304.246207) (xy 416.806145 -304.2216) (xy 416.768024 -304.190475)
			(xy 416.735389 -304.153638) (xy 416.709086 -304.112042) (xy 416.689795 -304.066766) (xy 416.678018 -304.018982)
			(xy 416.674058 -303.969928) (xy 416.330033 -303.969928) (xy 416.33013 -303.974754) (xy 416.329635 -303.999361)
			(xy 416.32174 -304.047938) (xy 416.306156 -304.094619) (xy 416.283285 -304.138196) (xy 416.25372 -304.17754)
			(xy 416.218227 -304.211632) (xy 416.177724 -304.239588) (xy 416.133262 -304.260686) (xy 416.085991 -304.274378)
			(xy 416.037136 -304.28031) (xy 415.987961 -304.278329) (xy 415.939742 -304.268485) (xy 415.893726 -304.251033)
			(xy 415.851105 -304.226426) (xy 415.812984 -304.195301) (xy 415.780349 -304.158464) (xy 415.754046 -304.116868)
			(xy 415.734755 -304.071592) (xy 415.722978 -304.023808) (xy 415.719018 -303.974754) (xy 415.38017 -303.974754)
			(xy 415.379675 -303.999361) (xy 415.37178 -304.047938) (xy 415.356196 -304.094619) (xy 415.333325 -304.138196)
			(xy 415.30376 -304.17754) (xy 415.268267 -304.211632) (xy 415.227764 -304.239588) (xy 415.183302 -304.260686)
			(xy 415.136031 -304.274378) (xy 415.087176 -304.28031) (xy 415.038001 -304.278329) (xy 414.989782 -304.268485)
			(xy 414.943766 -304.251033) (xy 414.901145 -304.226426) (xy 414.863024 -304.195301) (xy 414.830389 -304.158464)
			(xy 414.804086 -304.116868) (xy 414.784795 -304.071592) (xy 414.773018 -304.023808) (xy 414.769058 -303.974754)
			(xy 414.43021 -303.974754) (xy 414.429715 -303.999361) (xy 414.42182 -304.047938) (xy 414.406236 -304.094619)
			(xy 414.383365 -304.138196) (xy 414.3538 -304.17754) (xy 414.318307 -304.211632) (xy 414.277804 -304.239588)
			(xy 414.233342 -304.260686) (xy 414.186071 -304.274378) (xy 414.137216 -304.28031) (xy 414.088041 -304.278329)
			(xy 414.039822 -304.268485) (xy 413.993806 -304.251033) (xy 413.951185 -304.226426) (xy 413.913064 -304.195301)
			(xy 413.880429 -304.158464) (xy 413.854126 -304.116868) (xy 413.834835 -304.071592) (xy 413.823058 -304.023808)
			(xy 413.819098 -303.974754) (xy 413.48025 -303.974754) (xy 413.479755 -303.999361) (xy 413.47186 -304.047938)
			(xy 413.456276 -304.094619) (xy 413.433405 -304.138196) (xy 413.40384 -304.17754) (xy 413.368347 -304.211632)
			(xy 413.327844 -304.239588) (xy 413.283382 -304.260686) (xy 413.236111 -304.274378) (xy 413.187256 -304.28031)
			(xy 413.138081 -304.278329) (xy 413.089862 -304.268485) (xy 413.043846 -304.251033) (xy 413.001225 -304.226426)
			(xy 412.963104 -304.195301) (xy 412.930469 -304.158464) (xy 412.904166 -304.116868) (xy 412.884875 -304.071592)
			(xy 412.873098 -304.023808) (xy 412.869138 -303.974754) (xy 412.53029 -303.974754) (xy 412.529795 -303.999361)
			(xy 412.5219 -304.047938) (xy 412.506316 -304.094619) (xy 412.483445 -304.138196) (xy 412.45388 -304.17754)
			(xy 412.418387 -304.211632) (xy 412.377884 -304.239588) (xy 412.333422 -304.260686) (xy 412.286151 -304.274378)
			(xy 412.237296 -304.28031) (xy 412.188121 -304.278329) (xy 412.139902 -304.268485) (xy 412.093886 -304.251033)
			(xy 412.051265 -304.226426) (xy 412.013144 -304.195301) (xy 411.980509 -304.158464) (xy 411.954206 -304.116868)
			(xy 411.934915 -304.071592) (xy 411.923138 -304.023808) (xy 411.919178 -303.974754) (xy 411.58033 -303.974754)
			(xy 411.579835 -303.999361) (xy 411.57194 -304.047938) (xy 411.556356 -304.094619) (xy 411.533485 -304.138196)
			(xy 411.50392 -304.17754) (xy 411.468427 -304.211632) (xy 411.427924 -304.239588) (xy 411.383462 -304.260686)
			(xy 411.336191 -304.274378) (xy 411.287336 -304.28031) (xy 411.238161 -304.278329) (xy 411.189942 -304.268485)
			(xy 411.143926 -304.251033) (xy 411.101305 -304.226426) (xy 411.063184 -304.195301) (xy 411.030549 -304.158464)
			(xy 411.004246 -304.116868) (xy 410.984955 -304.071592) (xy 410.973178 -304.023808) (xy 410.969218 -303.974754)
			(xy 410.630116 -303.974754) (xy 410.629621 -303.999361) (xy 410.621726 -304.047938) (xy 410.606142 -304.094619)
			(xy 410.583271 -304.138196) (xy 410.553706 -304.17754) (xy 410.518213 -304.211632) (xy 410.47771 -304.239588)
			(xy 410.433248 -304.260686) (xy 410.385977 -304.274378) (xy 410.337122 -304.28031) (xy 410.287947 -304.278329)
			(xy 410.239728 -304.268485) (xy 410.193712 -304.251033) (xy 410.151091 -304.226426) (xy 410.11297 -304.195301)
			(xy 410.080335 -304.158464) (xy 410.054032 -304.116868) (xy 410.034741 -304.071592) (xy 410.022964 -304.023808)
			(xy 410.019004 -303.974754) (xy 409.680156 -303.974754) (xy 409.679661 -303.999361) (xy 409.671766 -304.047938)
			(xy 409.656182 -304.094619) (xy 409.633311 -304.138196) (xy 409.603746 -304.17754) (xy 409.568253 -304.211632)
			(xy 409.52775 -304.239588) (xy 409.483288 -304.260686) (xy 409.436017 -304.274378) (xy 409.387162 -304.28031)
			(xy 409.337987 -304.278329) (xy 409.289768 -304.268485) (xy 409.243752 -304.251033) (xy 409.201131 -304.226426)
			(xy 409.16301 -304.195301) (xy 409.130375 -304.158464) (xy 409.104072 -304.116868) (xy 409.084781 -304.071592)
			(xy 409.073004 -304.023808) (xy 409.069044 -303.974754) (xy 408.730196 -303.974754) (xy 408.729701 -303.999361)
			(xy 408.721806 -304.047938) (xy 408.706222 -304.094619) (xy 408.683351 -304.138196) (xy 408.653786 -304.17754)
			(xy 408.618293 -304.211632) (xy 408.57779 -304.239588) (xy 408.533328 -304.260686) (xy 408.486057 -304.274378)
			(xy 408.437202 -304.28031) (xy 408.388027 -304.278329) (xy 408.339808 -304.268485) (xy 408.293792 -304.251033)
			(xy 408.251171 -304.226426) (xy 408.21305 -304.195301) (xy 408.180415 -304.158464) (xy 408.154112 -304.116868)
			(xy 408.134821 -304.071592) (xy 408.123044 -304.023808) (xy 408.119084 -303.974754) (xy 406.830276 -303.974754)
			(xy 406.829781 -303.999361) (xy 406.821886 -304.047938) (xy 406.806302 -304.094619) (xy 406.783431 -304.138196)
			(xy 406.753866 -304.17754) (xy 406.718373 -304.211632) (xy 406.67787 -304.239588) (xy 406.633408 -304.260686)
			(xy 406.586137 -304.274378) (xy 406.537282 -304.28031) (xy 406.488107 -304.278329) (xy 406.439888 -304.268485)
			(xy 406.393872 -304.251033) (xy 406.351251 -304.226426) (xy 406.31313 -304.195301) (xy 406.280495 -304.158464)
			(xy 406.254192 -304.116868) (xy 406.234901 -304.071592) (xy 406.223124 -304.023808) (xy 406.219164 -303.974754)
			(xy 405.880316 -303.974754) (xy 405.879821 -303.999361) (xy 405.871926 -304.047938) (xy 405.856342 -304.094619)
			(xy 405.833471 -304.138196) (xy 405.803906 -304.17754) (xy 405.768413 -304.211632) (xy 405.72791 -304.239588)
			(xy 405.683448 -304.260686) (xy 405.636177 -304.274378) (xy 405.587322 -304.28031) (xy 405.538147 -304.278329)
			(xy 405.489928 -304.268485) (xy 405.443912 -304.251033) (xy 405.401291 -304.226426) (xy 405.36317 -304.195301)
			(xy 405.330535 -304.158464) (xy 405.304232 -304.116868) (xy 405.284941 -304.071592) (xy 405.273164 -304.023808)
			(xy 405.269204 -303.974754) (xy 404.930102 -303.974754) (xy 404.929607 -303.999361) (xy 404.921712 -304.047938)
			(xy 404.906128 -304.094619) (xy 404.883257 -304.138196) (xy 404.853692 -304.17754) (xy 404.818199 -304.211632)
			(xy 404.777696 -304.239588) (xy 404.733234 -304.260686) (xy 404.685963 -304.274378) (xy 404.637108 -304.28031)
			(xy 404.587933 -304.278329) (xy 404.539714 -304.268485) (xy 404.493698 -304.251033) (xy 404.451077 -304.226426)
			(xy 404.412956 -304.195301) (xy 404.380321 -304.158464) (xy 404.354018 -304.116868) (xy 404.334727 -304.071592)
			(xy 404.32295 -304.023808) (xy 404.31899 -303.974754) (xy 403.980142 -303.974754) (xy 403.979647 -303.999361)
			(xy 403.971752 -304.047938) (xy 403.956168 -304.094619) (xy 403.933297 -304.138196) (xy 403.903732 -304.17754)
			(xy 403.868239 -304.211632) (xy 403.827736 -304.239588) (xy 403.783274 -304.260686) (xy 403.736003 -304.274378)
			(xy 403.687148 -304.28031) (xy 403.637973 -304.278329) (xy 403.589754 -304.268485) (xy 403.543738 -304.251033)
			(xy 403.501117 -304.226426) (xy 403.462996 -304.195301) (xy 403.430361 -304.158464) (xy 403.404058 -304.116868)
			(xy 403.384767 -304.071592) (xy 403.37299 -304.023808) (xy 403.36903 -303.974754) (xy 403.030182 -303.974754)
			(xy 403.029687 -303.999361) (xy 403.021792 -304.047938) (xy 403.006208 -304.094619) (xy 402.983337 -304.138196)
			(xy 402.953772 -304.17754) (xy 402.918279 -304.211632) (xy 402.877776 -304.239588) (xy 402.833314 -304.260686)
			(xy 402.786043 -304.274378) (xy 402.737188 -304.28031) (xy 402.688013 -304.278329) (xy 402.639794 -304.268485)
			(xy 402.593778 -304.251033) (xy 402.551157 -304.226426) (xy 402.513036 -304.195301) (xy 402.480401 -304.158464)
			(xy 402.454098 -304.116868) (xy 402.434807 -304.071592) (xy 402.42303 -304.023808) (xy 402.41907 -303.974754)
			(xy 402.080222 -303.974754) (xy 402.079727 -303.999361) (xy 402.071832 -304.047938) (xy 402.056248 -304.094619)
			(xy 402.033377 -304.138196) (xy 402.003812 -304.17754) (xy 401.968319 -304.211632) (xy 401.927816 -304.239588)
			(xy 401.883354 -304.260686) (xy 401.836083 -304.274378) (xy 401.787228 -304.28031) (xy 401.738053 -304.278329)
			(xy 401.689834 -304.268485) (xy 401.643818 -304.251033) (xy 401.601197 -304.226426) (xy 401.563076 -304.195301)
			(xy 401.530441 -304.158464) (xy 401.504138 -304.116868) (xy 401.484847 -304.071592) (xy 401.47307 -304.023808)
			(xy 401.46911 -303.974754) (xy 401.130262 -303.974754) (xy 401.129767 -303.999361) (xy 401.121872 -304.047938)
			(xy 401.106288 -304.094619) (xy 401.083417 -304.138196) (xy 401.053852 -304.17754) (xy 401.018359 -304.211632)
			(xy 400.977856 -304.239588) (xy 400.933394 -304.260686) (xy 400.886123 -304.274378) (xy 400.837268 -304.28031)
			(xy 400.788093 -304.278329) (xy 400.739874 -304.268485) (xy 400.693858 -304.251033) (xy 400.651237 -304.226426)
			(xy 400.613116 -304.195301) (xy 400.580481 -304.158464) (xy 400.554178 -304.116868) (xy 400.534887 -304.071592)
			(xy 400.52311 -304.023808) (xy 400.51915 -303.974754) (xy 400.180302 -303.974754) (xy 400.179807 -303.999361)
			(xy 400.171912 -304.047938) (xy 400.156328 -304.094619) (xy 400.133457 -304.138196) (xy 400.103892 -304.17754)
			(xy 400.068399 -304.211632) (xy 400.027896 -304.239588) (xy 399.983434 -304.260686) (xy 399.936163 -304.274378)
			(xy 399.887308 -304.28031) (xy 399.838133 -304.278329) (xy 399.789914 -304.268485) (xy 399.743898 -304.251033)
			(xy 399.701277 -304.226426) (xy 399.663156 -304.195301) (xy 399.630521 -304.158464) (xy 399.604218 -304.116868)
			(xy 399.584927 -304.071592) (xy 399.57315 -304.023808) (xy 399.56919 -303.974754) (xy 399.230342 -303.974754)
			(xy 399.229847 -303.999361) (xy 399.221952 -304.047938) (xy 399.206368 -304.094619) (xy 399.183497 -304.138196)
			(xy 399.153932 -304.17754) (xy 399.118439 -304.211632) (xy 399.077936 -304.239588) (xy 399.033474 -304.260686)
			(xy 398.986203 -304.274378) (xy 398.937348 -304.28031) (xy 398.888173 -304.278329) (xy 398.839954 -304.268485)
			(xy 398.793938 -304.251033) (xy 398.751317 -304.226426) (xy 398.713196 -304.195301) (xy 398.680561 -304.158464)
			(xy 398.654258 -304.116868) (xy 398.634967 -304.071592) (xy 398.62319 -304.023808) (xy 398.61923 -303.974754)
			(xy 398.317212 -303.974754) (xy 398.317212 -304.475442) (xy 422.823382 -304.475442) (xy 422.823382 -304.424026)
			(xy 422.831425 -304.373244) (xy 422.847313 -304.324345) (xy 422.870656 -304.278533) (xy 422.900877 -304.236937)
			(xy 422.937233 -304.200581) (xy 422.978829 -304.17036) (xy 423.024641 -304.147017) (xy 423.07354 -304.131129)
			(xy 423.124322 -304.123086) (xy 423.175738 -304.123086) (xy 423.22652 -304.131129) (xy 423.275419 -304.147017)
			(xy 423.321231 -304.17036) (xy 423.362827 -304.200581) (xy 423.399183 -304.236937) (xy 423.429404 -304.278533)
			(xy 423.452747 -304.324345) (xy 423.468635 -304.373244) (xy 423.476678 -304.424026) (xy 423.477182 -304.449734)
			(xy 423.476678 -304.475442) (xy 423.773342 -304.475442) (xy 423.773342 -304.424026) (xy 423.781385 -304.373244)
			(xy 423.797273 -304.324345) (xy 423.820616 -304.278533) (xy 423.850837 -304.236937) (xy 423.887193 -304.200581)
			(xy 423.928789 -304.17036) (xy 423.974601 -304.147017) (xy 424.0235 -304.131129) (xy 424.074282 -304.123086)
			(xy 424.125698 -304.123086) (xy 424.17648 -304.131129) (xy 424.225379 -304.147017) (xy 424.271191 -304.17036)
			(xy 424.312787 -304.200581) (xy 424.349143 -304.236937) (xy 424.379364 -304.278533) (xy 424.402707 -304.324345)
			(xy 424.418595 -304.373244) (xy 424.426638 -304.424026) (xy 424.427142 -304.449734) (xy 424.744146 -304.449734)
			(xy 424.748106 -304.40068) (xy 424.759883 -304.352896) (xy 424.779174 -304.30762) (xy 424.805477 -304.266024)
			(xy 424.838112 -304.229187) (xy 424.876233 -304.198062) (xy 424.918854 -304.173455) (xy 424.96487 -304.156003)
			(xy 425.013089 -304.146159) (xy 425.062264 -304.144178) (xy 425.111119 -304.15011) (xy 425.15839 -304.163802)
			(xy 425.202852 -304.1849) (xy 425.243355 -304.212856) (xy 425.278848 -304.246948) (xy 425.308413 -304.286292)
			(xy 425.331284 -304.329869) (xy 425.346868 -304.37655) (xy 425.354763 -304.425127) (xy 425.355258 -304.449734)
			(xy 425.694106 -304.449734) (xy 425.698066 -304.40068) (xy 425.709843 -304.352896) (xy 425.729134 -304.30762)
			(xy 425.755437 -304.266024) (xy 425.788072 -304.229187) (xy 425.826193 -304.198062) (xy 425.868814 -304.173455)
			(xy 425.91483 -304.156003) (xy 425.963049 -304.146159) (xy 426.012224 -304.144178) (xy 426.061079 -304.15011)
			(xy 426.10835 -304.163802) (xy 426.152812 -304.1849) (xy 426.193315 -304.212856) (xy 426.228808 -304.246948)
			(xy 426.258373 -304.286292) (xy 426.281244 -304.329869) (xy 426.296828 -304.37655) (xy 426.304723 -304.425127)
			(xy 426.305218 -304.449734) (xy 426.644066 -304.449734) (xy 426.648026 -304.40068) (xy 426.659803 -304.352896)
			(xy 426.679094 -304.30762) (xy 426.705397 -304.266024) (xy 426.738032 -304.229187) (xy 426.776153 -304.198062)
			(xy 426.818774 -304.173455) (xy 426.86479 -304.156003) (xy 426.913009 -304.146159) (xy 426.962184 -304.144178)
			(xy 427.011039 -304.15011) (xy 427.05831 -304.163802) (xy 427.102772 -304.1849) (xy 427.143275 -304.212856)
			(xy 427.178768 -304.246948) (xy 427.208333 -304.286292) (xy 427.231204 -304.329869) (xy 427.246788 -304.37655)
			(xy 427.254683 -304.425127) (xy 427.255178 -304.449734) (xy 427.594026 -304.449734) (xy 427.597986 -304.40068)
			(xy 427.609763 -304.352896) (xy 427.629054 -304.30762) (xy 427.655357 -304.266024) (xy 427.687992 -304.229187)
			(xy 427.726113 -304.198062) (xy 427.768734 -304.173455) (xy 427.81475 -304.156003) (xy 427.862969 -304.146159)
			(xy 427.912144 -304.144178) (xy 427.960999 -304.15011) (xy 428.00827 -304.163802) (xy 428.052732 -304.1849)
			(xy 428.093235 -304.212856) (xy 428.128728 -304.246948) (xy 428.158293 -304.286292) (xy 428.181164 -304.329869)
			(xy 428.196748 -304.37655) (xy 428.204643 -304.425127) (xy 428.205138 -304.449734) (xy 428.543986 -304.449734)
			(xy 428.547946 -304.40068) (xy 428.559723 -304.352896) (xy 428.579014 -304.30762) (xy 428.605317 -304.266024)
			(xy 428.637952 -304.229187) (xy 428.676073 -304.198062) (xy 428.718694 -304.173455) (xy 428.76471 -304.156003)
			(xy 428.812929 -304.146159) (xy 428.862104 -304.144178) (xy 428.910959 -304.15011) (xy 428.95823 -304.163802)
			(xy 429.002692 -304.1849) (xy 429.043195 -304.212856) (xy 429.078688 -304.246948) (xy 429.108253 -304.286292)
			(xy 429.131124 -304.329869) (xy 429.146708 -304.37655) (xy 429.154603 -304.425127) (xy 429.155098 -304.449734)
			(xy 429.154603 -304.474341) (xy 429.154424 -304.475442) (xy 429.473356 -304.475442) (xy 429.473356 -304.424026)
			(xy 429.481399 -304.373244) (xy 429.497287 -304.324345) (xy 429.52063 -304.278533) (xy 429.550851 -304.236937)
			(xy 429.587207 -304.200581) (xy 429.628803 -304.17036) (xy 429.674615 -304.147017) (xy 429.723514 -304.131129)
			(xy 429.774296 -304.123086) (xy 429.825712 -304.123086) (xy 429.876494 -304.131129) (xy 429.925393 -304.147017)
			(xy 429.971205 -304.17036) (xy 430.012801 -304.200581) (xy 430.049157 -304.236937) (xy 430.079378 -304.278533)
			(xy 430.102721 -304.324345) (xy 430.118609 -304.373244) (xy 430.126652 -304.424026) (xy 430.127156 -304.449734)
			(xy 430.126652 -304.475442) (xy 430.423316 -304.475442) (xy 430.423316 -304.424026) (xy 430.431359 -304.373244)
			(xy 430.447247 -304.324345) (xy 430.47059 -304.278533) (xy 430.500811 -304.236937) (xy 430.537167 -304.200581)
			(xy 430.578763 -304.17036) (xy 430.624575 -304.147017) (xy 430.673474 -304.131129) (xy 430.724256 -304.123086)
			(xy 430.775672 -304.123086) (xy 430.826454 -304.131129) (xy 430.875353 -304.147017) (xy 430.921165 -304.17036)
			(xy 430.962761 -304.200581) (xy 430.999117 -304.236937) (xy 431.029338 -304.278533) (xy 431.052681 -304.324345)
			(xy 431.068569 -304.373244) (xy 431.076612 -304.424026) (xy 431.077116 -304.449734) (xy 431.394374 -304.449734)
			(xy 431.398334 -304.40068) (xy 431.410111 -304.352896) (xy 431.429402 -304.30762) (xy 431.455705 -304.266024)
			(xy 431.48834 -304.229187) (xy 431.526461 -304.198062) (xy 431.569082 -304.173455) (xy 431.615098 -304.156003)
			(xy 431.663317 -304.146159) (xy 431.712492 -304.144178) (xy 431.761347 -304.15011) (xy 431.808618 -304.163802)
			(xy 431.85308 -304.1849) (xy 431.893583 -304.212856) (xy 431.929076 -304.246948) (xy 431.958641 -304.286292)
			(xy 431.981512 -304.329869) (xy 431.997096 -304.37655) (xy 432.004991 -304.425127) (xy 432.005486 -304.449734)
			(xy 432.004991 -304.474341) (xy 431.997096 -304.522918) (xy 431.981512 -304.569599) (xy 431.958641 -304.613176)
			(xy 431.929076 -304.65252) (xy 431.893583 -304.686612) (xy 431.85308 -304.714568) (xy 431.808618 -304.735666)
			(xy 431.761347 -304.749358) (xy 431.712492 -304.75529) (xy 431.663317 -304.753309) (xy 431.615098 -304.743465)
			(xy 431.569082 -304.726013) (xy 431.526461 -304.701406) (xy 431.48834 -304.670281) (xy 431.455705 -304.633444)
			(xy 431.429402 -304.591848) (xy 431.410111 -304.546572) (xy 431.398334 -304.498788) (xy 431.394374 -304.449734)
			(xy 431.077116 -304.449734) (xy 431.076612 -304.475442) (xy 431.068569 -304.526224) (xy 431.052681 -304.575123)
			(xy 431.029338 -304.620935) (xy 430.999117 -304.662531) (xy 430.962761 -304.698887) (xy 430.921165 -304.729108)
			(xy 430.875353 -304.752451) (xy 430.826454 -304.768339) (xy 430.775672 -304.776382) (xy 430.724256 -304.776382)
			(xy 430.673474 -304.768339) (xy 430.624575 -304.752451) (xy 430.578763 -304.729108) (xy 430.537167 -304.698887)
			(xy 430.500811 -304.662531) (xy 430.47059 -304.620935) (xy 430.447247 -304.575123) (xy 430.431359 -304.526224)
			(xy 430.423316 -304.475442) (xy 430.126652 -304.475442) (xy 430.118609 -304.526224) (xy 430.102721 -304.575123)
			(xy 430.079378 -304.620935) (xy 430.049157 -304.662531) (xy 430.012801 -304.698887) (xy 429.971205 -304.729108)
			(xy 429.925393 -304.752451) (xy 429.876494 -304.768339) (xy 429.825712 -304.776382) (xy 429.774296 -304.776382)
			(xy 429.723514 -304.768339) (xy 429.674615 -304.752451) (xy 429.628803 -304.729108) (xy 429.587207 -304.698887)
			(xy 429.550851 -304.662531) (xy 429.52063 -304.620935) (xy 429.497287 -304.575123) (xy 429.481399 -304.526224)
			(xy 429.473356 -304.475442) (xy 429.154424 -304.475442) (xy 429.146708 -304.522918) (xy 429.131124 -304.569599)
			(xy 429.108253 -304.613176) (xy 429.078688 -304.65252) (xy 429.043195 -304.686612) (xy 429.002692 -304.714568)
			(xy 428.95823 -304.735666) (xy 428.910959 -304.749358) (xy 428.862104 -304.75529) (xy 428.812929 -304.753309)
			(xy 428.76471 -304.743465) (xy 428.718694 -304.726013) (xy 428.676073 -304.701406) (xy 428.637952 -304.670281)
			(xy 428.605317 -304.633444) (xy 428.579014 -304.591848) (xy 428.559723 -304.546572) (xy 428.547946 -304.498788)
			(xy 428.543986 -304.449734) (xy 428.205138 -304.449734) (xy 428.204643 -304.474341) (xy 428.196748 -304.522918)
			(xy 428.181164 -304.569599) (xy 428.158293 -304.613176) (xy 428.128728 -304.65252) (xy 428.093235 -304.686612)
			(xy 428.052732 -304.714568) (xy 428.00827 -304.735666) (xy 427.960999 -304.749358) (xy 427.912144 -304.75529)
			(xy 427.862969 -304.753309) (xy 427.81475 -304.743465) (xy 427.768734 -304.726013) (xy 427.726113 -304.701406)
			(xy 427.687992 -304.670281) (xy 427.655357 -304.633444) (xy 427.629054 -304.591848) (xy 427.609763 -304.546572)
			(xy 427.597986 -304.498788) (xy 427.594026 -304.449734) (xy 427.255178 -304.449734) (xy 427.254683 -304.474341)
			(xy 427.246788 -304.522918) (xy 427.231204 -304.569599) (xy 427.208333 -304.613176) (xy 427.178768 -304.65252)
			(xy 427.143275 -304.686612) (xy 427.102772 -304.714568) (xy 427.05831 -304.735666) (xy 427.011039 -304.749358)
			(xy 426.962184 -304.75529) (xy 426.913009 -304.753309) (xy 426.86479 -304.743465) (xy 426.818774 -304.726013)
			(xy 426.776153 -304.701406) (xy 426.738032 -304.670281) (xy 426.705397 -304.633444) (xy 426.679094 -304.591848)
			(xy 426.659803 -304.546572) (xy 426.648026 -304.498788) (xy 426.644066 -304.449734) (xy 426.305218 -304.449734)
			(xy 426.304723 -304.474341) (xy 426.296828 -304.522918) (xy 426.281244 -304.569599) (xy 426.258373 -304.613176)
			(xy 426.228808 -304.65252) (xy 426.193315 -304.686612) (xy 426.152812 -304.714568) (xy 426.10835 -304.735666)
			(xy 426.061079 -304.749358) (xy 426.012224 -304.75529) (xy 425.963049 -304.753309) (xy 425.91483 -304.743465)
			(xy 425.868814 -304.726013) (xy 425.826193 -304.701406) (xy 425.788072 -304.670281) (xy 425.755437 -304.633444)
			(xy 425.729134 -304.591848) (xy 425.709843 -304.546572) (xy 425.698066 -304.498788) (xy 425.694106 -304.449734)
			(xy 425.355258 -304.449734) (xy 425.354763 -304.474341) (xy 425.346868 -304.522918) (xy 425.331284 -304.569599)
			(xy 425.308413 -304.613176) (xy 425.278848 -304.65252) (xy 425.243355 -304.686612) (xy 425.202852 -304.714568)
			(xy 425.15839 -304.735666) (xy 425.111119 -304.749358) (xy 425.062264 -304.75529) (xy 425.013089 -304.753309)
			(xy 424.96487 -304.743465) (xy 424.918854 -304.726013) (xy 424.876233 -304.701406) (xy 424.838112 -304.670281)
			(xy 424.805477 -304.633444) (xy 424.779174 -304.591848) (xy 424.759883 -304.546572) (xy 424.748106 -304.498788)
			(xy 424.744146 -304.449734) (xy 424.427142 -304.449734) (xy 424.426638 -304.475442) (xy 424.418595 -304.526224)
			(xy 424.402707 -304.575123) (xy 424.379364 -304.620935) (xy 424.349143 -304.662531) (xy 424.312787 -304.698887)
			(xy 424.271191 -304.729108) (xy 424.225379 -304.752451) (xy 424.17648 -304.768339) (xy 424.125698 -304.776382)
			(xy 424.074282 -304.776382) (xy 424.0235 -304.768339) (xy 423.974601 -304.752451) (xy 423.928789 -304.729108)
			(xy 423.887193 -304.698887) (xy 423.850837 -304.662531) (xy 423.820616 -304.620935) (xy 423.797273 -304.575123)
			(xy 423.781385 -304.526224) (xy 423.773342 -304.475442) (xy 423.476678 -304.475442) (xy 423.468635 -304.526224)
			(xy 423.452747 -304.575123) (xy 423.429404 -304.620935) (xy 423.399183 -304.662531) (xy 423.362827 -304.698887)
			(xy 423.321231 -304.729108) (xy 423.275419 -304.752451) (xy 423.22652 -304.768339) (xy 423.175738 -304.776382)
			(xy 423.124322 -304.776382) (xy 423.07354 -304.768339) (xy 423.024641 -304.752451) (xy 422.978829 -304.729108)
			(xy 422.937233 -304.698887) (xy 422.900877 -304.662531) (xy 422.870656 -304.620935) (xy 422.847313 -304.575123)
			(xy 422.831425 -304.526224) (xy 422.823382 -304.475442) (xy 398.317212 -304.475442) (xy 398.317212 -304.924714)
			(xy 416.668978 -304.924714) (xy 416.672938 -304.87566) (xy 416.684715 -304.827876) (xy 416.704006 -304.7826)
			(xy 416.730309 -304.741004) (xy 416.762944 -304.704167) (xy 416.801065 -304.673042) (xy 416.843686 -304.648435)
			(xy 416.889702 -304.630983) (xy 416.937921 -304.621139) (xy 416.987096 -304.619158) (xy 417.035951 -304.62509)
			(xy 417.083222 -304.638782) (xy 417.127684 -304.65988) (xy 417.168187 -304.687836) (xy 417.20368 -304.721928)
			(xy 417.233245 -304.761272) (xy 417.256116 -304.804849) (xy 417.2717 -304.85153) (xy 417.279595 -304.900107)
			(xy 417.28009 -304.924714) (xy 417.619192 -304.924714) (xy 417.623152 -304.87566) (xy 417.634929 -304.827876)
			(xy 417.65422 -304.7826) (xy 417.680523 -304.741004) (xy 417.713158 -304.704167) (xy 417.751279 -304.673042)
			(xy 417.7939 -304.648435) (xy 417.839916 -304.630983) (xy 417.888135 -304.621139) (xy 417.93731 -304.619158)
			(xy 417.986165 -304.62509) (xy 418.033436 -304.638782) (xy 418.077898 -304.65988) (xy 418.118401 -304.687836)
			(xy 418.153894 -304.721928) (xy 418.183459 -304.761272) (xy 418.20633 -304.804849) (xy 418.221914 -304.85153)
			(xy 418.229809 -304.900107) (xy 418.230304 -304.924714) (xy 418.569152 -304.924714) (xy 418.573112 -304.87566)
			(xy 418.584889 -304.827876) (xy 418.60418 -304.7826) (xy 418.630483 -304.741004) (xy 418.663118 -304.704167)
			(xy 418.701239 -304.673042) (xy 418.74386 -304.648435) (xy 418.789876 -304.630983) (xy 418.838095 -304.621139)
			(xy 418.88727 -304.619158) (xy 418.936125 -304.62509) (xy 418.983396 -304.638782) (xy 419.027858 -304.65988)
			(xy 419.068361 -304.687836) (xy 419.103854 -304.721928) (xy 419.133419 -304.761272) (xy 419.15629 -304.804849)
			(xy 419.171874 -304.85153) (xy 419.179769 -304.900107) (xy 419.180264 -304.924714) (xy 419.519112 -304.924714)
			(xy 419.523072 -304.87566) (xy 419.534849 -304.827876) (xy 419.55414 -304.7826) (xy 419.580443 -304.741004)
			(xy 419.613078 -304.704167) (xy 419.651199 -304.673042) (xy 419.69382 -304.648435) (xy 419.739836 -304.630983)
			(xy 419.788055 -304.621139) (xy 419.83723 -304.619158) (xy 419.886085 -304.62509) (xy 419.933356 -304.638782)
			(xy 419.977818 -304.65988) (xy 420.018321 -304.687836) (xy 420.053814 -304.721928) (xy 420.083379 -304.761272)
			(xy 420.10625 -304.804849) (xy 420.121834 -304.85153) (xy 420.129729 -304.900107) (xy 420.130224 -304.924714)
			(xy 420.469072 -304.924714) (xy 420.473032 -304.87566) (xy 420.484809 -304.827876) (xy 420.5041 -304.7826)
			(xy 420.530403 -304.741004) (xy 420.563038 -304.704167) (xy 420.601159 -304.673042) (xy 420.64378 -304.648435)
			(xy 420.689796 -304.630983) (xy 420.738015 -304.621139) (xy 420.78719 -304.619158) (xy 420.836045 -304.62509)
			(xy 420.883316 -304.638782) (xy 420.927778 -304.65988) (xy 420.968281 -304.687836) (xy 421.003774 -304.721928)
			(xy 421.033339 -304.761272) (xy 421.05621 -304.804849) (xy 421.071794 -304.85153) (xy 421.079689 -304.900107)
			(xy 421.080184 -304.924714) (xy 421.419032 -304.924714) (xy 421.422992 -304.87566) (xy 421.434769 -304.827876)
			(xy 421.45406 -304.7826) (xy 421.480363 -304.741004) (xy 421.512998 -304.704167) (xy 421.551119 -304.673042)
			(xy 421.59374 -304.648435) (xy 421.639756 -304.630983) (xy 421.687975 -304.621139) (xy 421.73715 -304.619158)
			(xy 421.786005 -304.62509) (xy 421.833276 -304.638782) (xy 421.877738 -304.65988) (xy 421.918241 -304.687836)
			(xy 421.953734 -304.721928) (xy 421.983299 -304.761272) (xy 421.993156 -304.780052) (xy 436.149734 -304.780052)
			(xy 436.149734 -304.725548) (xy 436.15749 -304.671598) (xy 436.172844 -304.619302) (xy 436.195484 -304.569722)
			(xy 436.224949 -304.523869) (xy 436.26064 -304.482675) (xy 436.301829 -304.446979) (xy 436.347678 -304.417508)
			(xy 436.397255 -304.394862) (xy 436.449549 -304.3795) (xy 436.503498 -304.371737) (xy 436.53075 -304.371248)
			(xy 436.557895 -304.371688) (xy 436.61164 -304.37937) (xy 436.663751 -304.3946) (xy 436.713173 -304.417069)
			(xy 436.758908 -304.446324) (xy 436.800029 -304.481771) (xy 436.835704 -304.522695) (xy 436.865213 -304.568266)
			(xy 436.887956 -304.617563) (xy 436.903475 -304.669588) (xy 436.90794 -304.696368) (xy 436.910763 -304.711197)
			(xy 436.923798 -304.738405) (xy 436.944204 -304.760626) (xy 436.970207 -304.775926) (xy 436.999542 -304.782973)
			(xy 437.029656 -304.781154) (xy 437.05793 -304.770627) (xy 437.070246 -304.7619) (xy 437.090311 -304.747097)
			(xy 437.133526 -304.722227) (xy 437.179611 -304.703192) (xy 437.227781 -304.690318) (xy 437.277218 -304.683822)
			(xy 437.302148 -304.683414) (xy 437.329399 -304.683859) (xy 437.383344 -304.691622) (xy 437.435636 -304.706982)
			(xy 437.48521 -304.729627) (xy 437.531057 -304.759096) (xy 437.572244 -304.79479) (xy 437.607933 -304.835981)
			(xy 437.637396 -304.881832) (xy 437.660035 -304.931409) (xy 437.675389 -304.983703) (xy 437.683144 -305.037649)
			(xy 437.683144 -305.064922) (xy 437.935114 -305.064922) (xy 437.939185 -305.0093) (xy 437.951311 -304.954863)
			(xy 437.971234 -304.902772) (xy 437.99853 -304.854137) (xy 438.032616 -304.809994) (xy 438.072765 -304.771285)
			(xy 438.118123 -304.738834) (xy 438.167723 -304.713333) (xy 438.220507 -304.695326) (xy 438.27535 -304.685196)
			(xy 438.331084 -304.683159) (xy 438.386521 -304.689259) (xy 438.440478 -304.703365) (xy 438.491807 -304.725177)
			(xy 438.539413 -304.754231) (xy 438.582281 -304.789906) (xy 438.619498 -304.831443) (xy 438.650271 -304.877956)
			(xy 438.673943 -304.928453) (xy 438.690011 -304.98186) (xy 438.698131 -305.037036) (xy 438.69864 -305.064922)
			(xy 438.943494 -305.064922) (xy 438.947565 -305.0093) (xy 438.959691 -304.954863) (xy 438.979614 -304.902772)
			(xy 439.00691 -304.854137) (xy 439.040996 -304.809994) (xy 439.081145 -304.771285) (xy 439.126503 -304.738834)
			(xy 439.176103 -304.713333) (xy 439.228887 -304.695326) (xy 439.28373 -304.685196) (xy 439.339464 -304.683159)
			(xy 439.394901 -304.689259) (xy 439.448858 -304.703365) (xy 439.500187 -304.725177) (xy 439.547793 -304.754231)
			(xy 439.590661 -304.789906) (xy 439.627878 -304.831443) (xy 439.658651 -304.877956) (xy 439.682323 -304.928453)
			(xy 439.698391 -304.98186) (xy 439.706511 -305.037036) (xy 439.707001 -305.063906) (xy 439.96813 -305.063906)
			(xy 439.972201 -305.008284) (xy 439.984327 -304.953847) (xy 440.00425 -304.901756) (xy 440.031546 -304.853121)
			(xy 440.065632 -304.808978) (xy 440.105781 -304.770269) (xy 440.151139 -304.737818) (xy 440.200739 -304.712317)
			(xy 440.253523 -304.69431) (xy 440.308366 -304.68418) (xy 440.3641 -304.682143) (xy 440.419537 -304.688243)
			(xy 440.473494 -304.702349) (xy 440.524823 -304.724161) (xy 440.572429 -304.753215) (xy 440.615297 -304.78889)
			(xy 440.652514 -304.830427) (xy 440.683287 -304.87694) (xy 440.706959 -304.927437) (xy 440.723027 -304.980844)
			(xy 440.731147 -305.03602) (xy 440.731331 -305.046126) (xy 440.98413 -305.046126) (xy 440.988201 -304.990504)
			(xy 441.000327 -304.936067) (xy 441.02025 -304.883976) (xy 441.047546 -304.835341) (xy 441.081632 -304.791198)
			(xy 441.121781 -304.752489) (xy 441.167139 -304.720038) (xy 441.216739 -304.694537) (xy 441.269523 -304.67653)
			(xy 441.324366 -304.6664) (xy 441.3801 -304.664363) (xy 441.435537 -304.670463) (xy 441.489494 -304.684569)
			(xy 441.540823 -304.706381) (xy 441.588429 -304.735435) (xy 441.631297 -304.77111) (xy 441.668514 -304.812647)
			(xy 441.699287 -304.85916) (xy 441.722959 -304.909657) (xy 441.739027 -304.963064) (xy 441.747147 -305.01824)
			(xy 441.747656 -305.046126) (xy 441.747147 -305.074012) (xy 441.739027 -305.129188) (xy 441.722959 -305.182595)
			(xy 441.699287 -305.233092) (xy 441.668514 -305.279605) (xy 441.631297 -305.321142) (xy 441.588429 -305.356817)
			(xy 441.540823 -305.385871) (xy 441.489494 -305.407683) (xy 441.435537 -305.421789) (xy 441.3801 -305.427889)
			(xy 441.324366 -305.425852) (xy 441.269523 -305.415722) (xy 441.216739 -305.397715) (xy 441.167139 -305.372214)
			(xy 441.121781 -305.339763) (xy 441.081632 -305.301054) (xy 441.047546 -305.256911) (xy 441.02025 -305.208276)
			(xy 441.000327 -305.156185) (xy 440.988201 -305.101748) (xy 440.98413 -305.046126) (xy 440.731331 -305.046126)
			(xy 440.731656 -305.063906) (xy 440.731147 -305.091792) (xy 440.723027 -305.146968) (xy 440.706959 -305.200375)
			(xy 440.683287 -305.250872) (xy 440.652514 -305.297385) (xy 440.615297 -305.338922) (xy 440.572429 -305.374597)
			(xy 440.524823 -305.403651) (xy 440.473494 -305.425463) (xy 440.419537 -305.439569) (xy 440.3641 -305.445669)
			(xy 440.308366 -305.443632) (xy 440.253523 -305.433502) (xy 440.200739 -305.415495) (xy 440.151139 -305.389994)
			(xy 440.105781 -305.357543) (xy 440.065632 -305.318834) (xy 440.031546 -305.274691) (xy 440.00425 -305.226056)
			(xy 439.984327 -305.173965) (xy 439.972201 -305.119528) (xy 439.96813 -305.063906) (xy 439.707001 -305.063906)
			(xy 439.70702 -305.064922) (xy 439.706511 -305.092808) (xy 439.698391 -305.147984) (xy 439.682323 -305.201391)
			(xy 439.658651 -305.251888) (xy 439.627878 -305.298401) (xy 439.590661 -305.339938) (xy 439.547793 -305.375613)
			(xy 439.500187 -305.404667) (xy 439.448858 -305.426479) (xy 439.394901 -305.440585) (xy 439.339464 -305.446685)
			(xy 439.28373 -305.444648) (xy 439.228887 -305.434518) (xy 439.176103 -305.416511) (xy 439.126503 -305.39101)
			(xy 439.081145 -305.358559) (xy 439.040996 -305.31985) (xy 439.00691 -305.275707) (xy 438.979614 -305.227072)
			(xy 438.959691 -305.174981) (xy 438.947565 -305.120544) (xy 438.943494 -305.064922) (xy 438.69864 -305.064922)
			(xy 438.698131 -305.092808) (xy 438.690011 -305.147984) (xy 438.673943 -305.201391) (xy 438.650271 -305.251888)
			(xy 438.619498 -305.298401) (xy 438.582281 -305.339938) (xy 438.539413 -305.375613) (xy 438.491807 -305.404667)
			(xy 438.440478 -305.426479) (xy 438.386521 -305.440585) (xy 438.331084 -305.446685) (xy 438.27535 -305.444648)
			(xy 438.220507 -305.434518) (xy 438.167723 -305.416511) (xy 438.118123 -305.39101) (xy 438.072765 -305.358559)
			(xy 438.032616 -305.31985) (xy 437.99853 -305.275707) (xy 437.971234 -305.227072) (xy 437.951311 -305.174981)
			(xy 437.939185 -305.120544) (xy 437.935114 -305.064922) (xy 437.683144 -305.064922) (xy 437.683144 -305.092151)
			(xy 437.675389 -305.146097) (xy 437.660035 -305.198391) (xy 437.637396 -305.247968) (xy 437.607933 -305.293819)
			(xy 437.572244 -305.33501) (xy 437.531057 -305.370704) (xy 437.48521 -305.400173) (xy 437.435636 -305.422818)
			(xy 437.383344 -305.438178) (xy 437.329399 -305.445941) (xy 437.302148 -305.44643) (xy 437.275002 -305.44601)
			(xy 437.221256 -305.438328) (xy 437.169143 -305.423097) (xy 437.119719 -305.400625) (xy 437.073984 -305.371369)
			(xy 437.032863 -305.335919) (xy 436.997188 -305.294993) (xy 436.96768 -305.249419) (xy 436.944938 -305.200119)
			(xy 436.929421 -305.148091) (xy 436.924958 -305.12131) (xy 436.922149 -305.106479) (xy 436.909109 -305.079272)
			(xy 436.8887 -305.057053) (xy 436.862695 -305.041755) (xy 436.83336 -305.034708) (xy 436.803244 -305.036527)
			(xy 436.774969 -305.047052) (xy 436.762652 -305.055778) (xy 436.742596 -305.070592) (xy 436.699377 -305.095459)
			(xy 436.65329 -305.11449) (xy 436.605118 -305.127362) (xy 436.555681 -305.133857) (xy 436.53075 -305.134264)
			(xy 436.503498 -305.133863) (xy 436.449549 -305.1261) (xy 436.397255 -305.110738) (xy 436.347678 -305.088092)
			(xy 436.301829 -305.058621) (xy 436.26064 -305.022925) (xy 436.224949 -304.981731) (xy 436.195484 -304.935878)
			(xy 436.172844 -304.886298) (xy 436.15749 -304.834002) (xy 436.149734 -304.780052) (xy 421.993156 -304.780052)
			(xy 422.00617 -304.804849) (xy 422.021754 -304.85153) (xy 422.029649 -304.900107) (xy 422.030144 -304.924714)
			(xy 422.029649 -304.949321) (xy 422.021754 -304.997898) (xy 422.00617 -305.044579) (xy 421.983299 -305.088156)
			(xy 421.953734 -305.1275) (xy 421.918241 -305.161592) (xy 421.877738 -305.189548) (xy 421.833276 -305.210646)
			(xy 421.786005 -305.224338) (xy 421.73715 -305.23027) (xy 421.687975 -305.228289) (xy 421.639756 -305.218445)
			(xy 421.59374 -305.200993) (xy 421.551119 -305.176386) (xy 421.512998 -305.145261) (xy 421.480363 -305.108424)
			(xy 421.45406 -305.066828) (xy 421.434769 -305.021552) (xy 421.422992 -304.973768) (xy 421.419032 -304.924714)
			(xy 421.080184 -304.924714) (xy 421.079689 -304.949321) (xy 421.071794 -304.997898) (xy 421.05621 -305.044579)
			(xy 421.033339 -305.088156) (xy 421.003774 -305.1275) (xy 420.968281 -305.161592) (xy 420.927778 -305.189548)
			(xy 420.883316 -305.210646) (xy 420.836045 -305.224338) (xy 420.78719 -305.23027) (xy 420.738015 -305.228289)
			(xy 420.689796 -305.218445) (xy 420.64378 -305.200993) (xy 420.601159 -305.176386) (xy 420.563038 -305.145261)
			(xy 420.530403 -305.108424) (xy 420.5041 -305.066828) (xy 420.484809 -305.021552) (xy 420.473032 -304.973768)
			(xy 420.469072 -304.924714) (xy 420.130224 -304.924714) (xy 420.129729 -304.949321) (xy 420.121834 -304.997898)
			(xy 420.10625 -305.044579) (xy 420.083379 -305.088156) (xy 420.053814 -305.1275) (xy 420.018321 -305.161592)
			(xy 419.977818 -305.189548) (xy 419.933356 -305.210646) (xy 419.886085 -305.224338) (xy 419.83723 -305.23027)
			(xy 419.788055 -305.228289) (xy 419.739836 -305.218445) (xy 419.69382 -305.200993) (xy 419.651199 -305.176386)
			(xy 419.613078 -305.145261) (xy 419.580443 -305.108424) (xy 419.55414 -305.066828) (xy 419.534849 -305.021552)
			(xy 419.523072 -304.973768) (xy 419.519112 -304.924714) (xy 419.180264 -304.924714) (xy 419.179769 -304.949321)
			(xy 419.171874 -304.997898) (xy 419.15629 -305.044579) (xy 419.133419 -305.088156) (xy 419.103854 -305.1275)
			(xy 419.068361 -305.161592) (xy 419.027858 -305.189548) (xy 418.983396 -305.210646) (xy 418.936125 -305.224338)
			(xy 418.88727 -305.23027) (xy 418.838095 -305.228289) (xy 418.789876 -305.218445) (xy 418.74386 -305.200993)
			(xy 418.701239 -305.176386) (xy 418.663118 -305.145261) (xy 418.630483 -305.108424) (xy 418.60418 -305.066828)
			(xy 418.584889 -305.021552) (xy 418.573112 -304.973768) (xy 418.569152 -304.924714) (xy 418.230304 -304.924714)
			(xy 418.229809 -304.949321) (xy 418.221914 -304.997898) (xy 418.20633 -305.044579) (xy 418.183459 -305.088156)
			(xy 418.153894 -305.1275) (xy 418.118401 -305.161592) (xy 418.077898 -305.189548) (xy 418.033436 -305.210646)
			(xy 417.986165 -305.224338) (xy 417.93731 -305.23027) (xy 417.888135 -305.228289) (xy 417.839916 -305.218445)
			(xy 417.7939 -305.200993) (xy 417.751279 -305.176386) (xy 417.713158 -305.145261) (xy 417.680523 -305.108424)
			(xy 417.65422 -305.066828) (xy 417.634929 -305.021552) (xy 417.623152 -304.973768) (xy 417.619192 -304.924714)
			(xy 417.28009 -304.924714) (xy 417.279595 -304.949321) (xy 417.2717 -304.997898) (xy 417.256116 -305.044579)
			(xy 417.233245 -305.088156) (xy 417.20368 -305.1275) (xy 417.168187 -305.161592) (xy 417.127684 -305.189548)
			(xy 417.083222 -305.210646) (xy 417.035951 -305.224338) (xy 416.987096 -305.23027) (xy 416.937921 -305.228289)
			(xy 416.889702 -305.218445) (xy 416.843686 -305.200993) (xy 416.801065 -305.176386) (xy 416.762944 -305.145261)
			(xy 416.730309 -305.108424) (xy 416.704006 -305.066828) (xy 416.684715 -305.021552) (xy 416.672938 -304.973768)
			(xy 416.668978 -304.924714) (xy 398.317212 -304.924714) (xy 398.317212 -305.874928) (xy 398.61923 -305.874928)
			(xy 398.62319 -305.825874) (xy 398.634967 -305.77809) (xy 398.654258 -305.732814) (xy 398.680561 -305.691218)
			(xy 398.713196 -305.654381) (xy 398.751317 -305.623256) (xy 398.793938 -305.598649) (xy 398.839954 -305.581197)
			(xy 398.888173 -305.571353) (xy 398.937348 -305.569372) (xy 398.986203 -305.575304) (xy 399.033474 -305.588996)
			(xy 399.077936 -305.610094) (xy 399.118439 -305.63805) (xy 399.153932 -305.672142) (xy 399.183497 -305.711486)
			(xy 399.206368 -305.755063) (xy 399.221952 -305.801744) (xy 399.229847 -305.850321) (xy 399.230342 -305.874928)
			(xy 399.56919 -305.874928) (xy 399.57315 -305.825874) (xy 399.584927 -305.77809) (xy 399.604218 -305.732814)
			(xy 399.630521 -305.691218) (xy 399.663156 -305.654381) (xy 399.701277 -305.623256) (xy 399.743898 -305.598649)
			(xy 399.789914 -305.581197) (xy 399.838133 -305.571353) (xy 399.887308 -305.569372) (xy 399.936163 -305.575304)
			(xy 399.983434 -305.588996) (xy 400.027896 -305.610094) (xy 400.068399 -305.63805) (xy 400.103892 -305.672142)
			(xy 400.133457 -305.711486) (xy 400.156328 -305.755063) (xy 400.171912 -305.801744) (xy 400.179807 -305.850321)
			(xy 400.180302 -305.874928) (xy 400.51915 -305.874928) (xy 400.52311 -305.825874) (xy 400.534887 -305.77809)
			(xy 400.554178 -305.732814) (xy 400.580481 -305.691218) (xy 400.613116 -305.654381) (xy 400.651237 -305.623256)
			(xy 400.693858 -305.598649) (xy 400.739874 -305.581197) (xy 400.788093 -305.571353) (xy 400.837268 -305.569372)
			(xy 400.886123 -305.575304) (xy 400.933394 -305.588996) (xy 400.977856 -305.610094) (xy 401.018359 -305.63805)
			(xy 401.053852 -305.672142) (xy 401.083417 -305.711486) (xy 401.106288 -305.755063) (xy 401.121872 -305.801744)
			(xy 401.129767 -305.850321) (xy 401.130262 -305.874928) (xy 401.46911 -305.874928) (xy 401.47307 -305.825874)
			(xy 401.484847 -305.77809) (xy 401.504138 -305.732814) (xy 401.530441 -305.691218) (xy 401.563076 -305.654381)
			(xy 401.601197 -305.623256) (xy 401.643818 -305.598649) (xy 401.689834 -305.581197) (xy 401.738053 -305.571353)
			(xy 401.787228 -305.569372) (xy 401.836083 -305.575304) (xy 401.883354 -305.588996) (xy 401.927816 -305.610094)
			(xy 401.968319 -305.63805) (xy 402.003812 -305.672142) (xy 402.033377 -305.711486) (xy 402.056248 -305.755063)
			(xy 402.071832 -305.801744) (xy 402.079727 -305.850321) (xy 402.080222 -305.874928) (xy 402.41907 -305.874928)
			(xy 402.42303 -305.825874) (xy 402.434807 -305.77809) (xy 402.454098 -305.732814) (xy 402.480401 -305.691218)
			(xy 402.513036 -305.654381) (xy 402.551157 -305.623256) (xy 402.593778 -305.598649) (xy 402.639794 -305.581197)
			(xy 402.688013 -305.571353) (xy 402.737188 -305.569372) (xy 402.786043 -305.575304) (xy 402.833314 -305.588996)
			(xy 402.877776 -305.610094) (xy 402.918279 -305.63805) (xy 402.953772 -305.672142) (xy 402.983337 -305.711486)
			(xy 403.006208 -305.755063) (xy 403.021792 -305.801744) (xy 403.029687 -305.850321) (xy 403.030182 -305.874928)
			(xy 403.36903 -305.874928) (xy 403.37299 -305.825874) (xy 403.384767 -305.77809) (xy 403.404058 -305.732814)
			(xy 403.430361 -305.691218) (xy 403.462996 -305.654381) (xy 403.501117 -305.623256) (xy 403.543738 -305.598649)
			(xy 403.589754 -305.581197) (xy 403.637973 -305.571353) (xy 403.687148 -305.569372) (xy 403.736003 -305.575304)
			(xy 403.783274 -305.588996) (xy 403.827736 -305.610094) (xy 403.868239 -305.63805) (xy 403.903732 -305.672142)
			(xy 403.933297 -305.711486) (xy 403.956168 -305.755063) (xy 403.971752 -305.801744) (xy 403.979647 -305.850321)
			(xy 403.980142 -305.874928) (xy 404.31899 -305.874928) (xy 404.32295 -305.825874) (xy 404.334727 -305.77809)
			(xy 404.354018 -305.732814) (xy 404.380321 -305.691218) (xy 404.412956 -305.654381) (xy 404.451077 -305.623256)
			(xy 404.493698 -305.598649) (xy 404.539714 -305.581197) (xy 404.587933 -305.571353) (xy 404.637108 -305.569372)
			(xy 404.685963 -305.575304) (xy 404.733234 -305.588996) (xy 404.777696 -305.610094) (xy 404.818199 -305.63805)
			(xy 404.853692 -305.672142) (xy 404.883257 -305.711486) (xy 404.906128 -305.755063) (xy 404.921712 -305.801744)
			(xy 404.929607 -305.850321) (xy 404.930102 -305.874928) (xy 405.269204 -305.874928) (xy 405.273164 -305.825874)
			(xy 405.284941 -305.77809) (xy 405.304232 -305.732814) (xy 405.330535 -305.691218) (xy 405.36317 -305.654381)
			(xy 405.401291 -305.623256) (xy 405.443912 -305.598649) (xy 405.489928 -305.581197) (xy 405.538147 -305.571353)
			(xy 405.587322 -305.569372) (xy 405.636177 -305.575304) (xy 405.683448 -305.588996) (xy 405.72791 -305.610094)
			(xy 405.768413 -305.63805) (xy 405.803906 -305.672142) (xy 405.833471 -305.711486) (xy 405.856342 -305.755063)
			(xy 405.871926 -305.801744) (xy 405.879821 -305.850321) (xy 405.880316 -305.874928) (xy 406.219164 -305.874928)
			(xy 406.223124 -305.825874) (xy 406.234901 -305.77809) (xy 406.254192 -305.732814) (xy 406.280495 -305.691218)
			(xy 406.31313 -305.654381) (xy 406.351251 -305.623256) (xy 406.393872 -305.598649) (xy 406.439888 -305.581197)
			(xy 406.488107 -305.571353) (xy 406.537282 -305.569372) (xy 406.586137 -305.575304) (xy 406.633408 -305.588996)
			(xy 406.67787 -305.610094) (xy 406.718373 -305.63805) (xy 406.753866 -305.672142) (xy 406.783431 -305.711486)
			(xy 406.806302 -305.755063) (xy 406.821886 -305.801744) (xy 406.829781 -305.850321) (xy 406.830276 -305.874928)
			(xy 408.119084 -305.874928) (xy 408.123044 -305.825874) (xy 408.134821 -305.77809) (xy 408.154112 -305.732814)
			(xy 408.180415 -305.691218) (xy 408.21305 -305.654381) (xy 408.251171 -305.623256) (xy 408.293792 -305.598649)
			(xy 408.339808 -305.581197) (xy 408.388027 -305.571353) (xy 408.437202 -305.569372) (xy 408.486057 -305.575304)
			(xy 408.533328 -305.588996) (xy 408.57779 -305.610094) (xy 408.618293 -305.63805) (xy 408.653786 -305.672142)
			(xy 408.683351 -305.711486) (xy 408.706222 -305.755063) (xy 408.721806 -305.801744) (xy 408.729701 -305.850321)
			(xy 408.730196 -305.874928) (xy 409.069044 -305.874928) (xy 409.073004 -305.825874) (xy 409.084781 -305.77809)
			(xy 409.104072 -305.732814) (xy 409.130375 -305.691218) (xy 409.16301 -305.654381) (xy 409.201131 -305.623256)
			(xy 409.243752 -305.598649) (xy 409.289768 -305.581197) (xy 409.337987 -305.571353) (xy 409.387162 -305.569372)
			(xy 409.436017 -305.575304) (xy 409.483288 -305.588996) (xy 409.52775 -305.610094) (xy 409.568253 -305.63805)
			(xy 409.603746 -305.672142) (xy 409.633311 -305.711486) (xy 409.656182 -305.755063) (xy 409.671766 -305.801744)
			(xy 409.679661 -305.850321) (xy 409.680156 -305.874928) (xy 410.019004 -305.874928) (xy 410.022964 -305.825874)
			(xy 410.034741 -305.77809) (xy 410.054032 -305.732814) (xy 410.080335 -305.691218) (xy 410.11297 -305.654381)
			(xy 410.151091 -305.623256) (xy 410.193712 -305.598649) (xy 410.239728 -305.581197) (xy 410.287947 -305.571353)
			(xy 410.337122 -305.569372) (xy 410.385977 -305.575304) (xy 410.433248 -305.588996) (xy 410.47771 -305.610094)
			(xy 410.518213 -305.63805) (xy 410.553706 -305.672142) (xy 410.583271 -305.711486) (xy 410.606142 -305.755063)
			(xy 410.621726 -305.801744) (xy 410.629621 -305.850321) (xy 410.630116 -305.874928) (xy 410.969218 -305.874928)
			(xy 410.973178 -305.825874) (xy 410.984955 -305.77809) (xy 411.004246 -305.732814) (xy 411.030549 -305.691218)
			(xy 411.063184 -305.654381) (xy 411.101305 -305.623256) (xy 411.143926 -305.598649) (xy 411.189942 -305.581197)
			(xy 411.238161 -305.571353) (xy 411.287336 -305.569372) (xy 411.336191 -305.575304) (xy 411.383462 -305.588996)
			(xy 411.427924 -305.610094) (xy 411.468427 -305.63805) (xy 411.50392 -305.672142) (xy 411.533485 -305.711486)
			(xy 411.556356 -305.755063) (xy 411.57194 -305.801744) (xy 411.579835 -305.850321) (xy 411.58033 -305.874928)
			(xy 411.919178 -305.874928) (xy 411.923138 -305.825874) (xy 411.934915 -305.77809) (xy 411.954206 -305.732814)
			(xy 411.980509 -305.691218) (xy 412.013144 -305.654381) (xy 412.051265 -305.623256) (xy 412.093886 -305.598649)
			(xy 412.139902 -305.581197) (xy 412.188121 -305.571353) (xy 412.237296 -305.569372) (xy 412.286151 -305.575304)
			(xy 412.333422 -305.588996) (xy 412.377884 -305.610094) (xy 412.418387 -305.63805) (xy 412.45388 -305.672142)
			(xy 412.483445 -305.711486) (xy 412.506316 -305.755063) (xy 412.5219 -305.801744) (xy 412.529795 -305.850321)
			(xy 412.53029 -305.874928) (xy 412.869138 -305.874928) (xy 412.873098 -305.825874) (xy 412.884875 -305.77809)
			(xy 412.904166 -305.732814) (xy 412.930469 -305.691218) (xy 412.963104 -305.654381) (xy 413.001225 -305.623256)
			(xy 413.043846 -305.598649) (xy 413.089862 -305.581197) (xy 413.138081 -305.571353) (xy 413.187256 -305.569372)
			(xy 413.236111 -305.575304) (xy 413.283382 -305.588996) (xy 413.327844 -305.610094) (xy 413.368347 -305.63805)
			(xy 413.40384 -305.672142) (xy 413.433405 -305.711486) (xy 413.456276 -305.755063) (xy 413.47186 -305.801744)
			(xy 413.479755 -305.850321) (xy 413.48025 -305.874928) (xy 413.819098 -305.874928) (xy 413.823058 -305.825874)
			(xy 413.834835 -305.77809) (xy 413.854126 -305.732814) (xy 413.880429 -305.691218) (xy 413.913064 -305.654381)
			(xy 413.951185 -305.623256) (xy 413.993806 -305.598649) (xy 414.039822 -305.581197) (xy 414.088041 -305.571353)
			(xy 414.137216 -305.569372) (xy 414.186071 -305.575304) (xy 414.233342 -305.588996) (xy 414.277804 -305.610094)
			(xy 414.318307 -305.63805) (xy 414.3538 -305.672142) (xy 414.383365 -305.711486) (xy 414.406236 -305.755063)
			(xy 414.42182 -305.801744) (xy 414.429715 -305.850321) (xy 414.43021 -305.874928) (xy 414.769058 -305.874928)
			(xy 414.773018 -305.825874) (xy 414.784795 -305.77809) (xy 414.804086 -305.732814) (xy 414.830389 -305.691218)
			(xy 414.863024 -305.654381) (xy 414.901145 -305.623256) (xy 414.943766 -305.598649) (xy 414.989782 -305.581197)
			(xy 415.038001 -305.571353) (xy 415.087176 -305.569372) (xy 415.136031 -305.575304) (xy 415.183302 -305.588996)
			(xy 415.227764 -305.610094) (xy 415.268267 -305.63805) (xy 415.30376 -305.672142) (xy 415.333325 -305.711486)
			(xy 415.356196 -305.755063) (xy 415.37178 -305.801744) (xy 415.379675 -305.850321) (xy 415.38017 -305.874928)
			(xy 415.719018 -305.874928) (xy 415.722978 -305.825874) (xy 415.734755 -305.77809) (xy 415.754046 -305.732814)
			(xy 415.780349 -305.691218) (xy 415.812984 -305.654381) (xy 415.851105 -305.623256) (xy 415.893726 -305.598649)
			(xy 415.939742 -305.581197) (xy 415.987961 -305.571353) (xy 416.037136 -305.569372) (xy 416.085991 -305.575304)
			(xy 416.133262 -305.588996) (xy 416.177724 -305.610094) (xy 416.218227 -305.63805) (xy 416.25372 -305.672142)
			(xy 416.283285 -305.711486) (xy 416.306156 -305.755063) (xy 416.32174 -305.801744) (xy 416.329635 -305.850321)
			(xy 416.33013 -305.874928) (xy 416.668978 -305.874928) (xy 416.672938 -305.825874) (xy 416.684715 -305.77809)
			(xy 416.704006 -305.732814) (xy 416.730309 -305.691218) (xy 416.762944 -305.654381) (xy 416.801065 -305.623256)
			(xy 416.843686 -305.598649) (xy 416.889702 -305.581197) (xy 416.937921 -305.571353) (xy 416.987096 -305.569372)
			(xy 417.035951 -305.575304) (xy 417.083222 -305.588996) (xy 417.127684 -305.610094) (xy 417.168187 -305.63805)
			(xy 417.20368 -305.672142) (xy 417.233245 -305.711486) (xy 417.256116 -305.755063) (xy 417.2717 -305.801744)
			(xy 417.279595 -305.850321) (xy 417.28009 -305.874928) (xy 417.619192 -305.874928) (xy 417.623152 -305.825874)
			(xy 417.634929 -305.77809) (xy 417.65422 -305.732814) (xy 417.680523 -305.691218) (xy 417.713158 -305.654381)
			(xy 417.751279 -305.623256) (xy 417.7939 -305.598649) (xy 417.839916 -305.581197) (xy 417.888135 -305.571353)
			(xy 417.93731 -305.569372) (xy 417.986165 -305.575304) (xy 418.033436 -305.588996) (xy 418.077898 -305.610094)
			(xy 418.118401 -305.63805) (xy 418.153894 -305.672142) (xy 418.183459 -305.711486) (xy 418.20633 -305.755063)
			(xy 418.221914 -305.801744) (xy 418.229809 -305.850321) (xy 418.230304 -305.874928) (xy 418.569152 -305.874928)
			(xy 418.573112 -305.825874) (xy 418.584889 -305.77809) (xy 418.60418 -305.732814) (xy 418.630483 -305.691218)
			(xy 418.663118 -305.654381) (xy 418.701239 -305.623256) (xy 418.74386 -305.598649) (xy 418.789876 -305.581197)
			(xy 418.838095 -305.571353) (xy 418.88727 -305.569372) (xy 418.936125 -305.575304) (xy 418.983396 -305.588996)
			(xy 419.027858 -305.610094) (xy 419.068361 -305.63805) (xy 419.103854 -305.672142) (xy 419.133419 -305.711486)
			(xy 419.15629 -305.755063) (xy 419.171874 -305.801744) (xy 419.179769 -305.850321) (xy 419.180264 -305.874928)
			(xy 419.519112 -305.874928) (xy 419.523072 -305.825874) (xy 419.534849 -305.77809) (xy 419.55414 -305.732814)
			(xy 419.580443 -305.691218) (xy 419.613078 -305.654381) (xy 419.651199 -305.623256) (xy 419.69382 -305.598649)
			(xy 419.739836 -305.581197) (xy 419.788055 -305.571353) (xy 419.83723 -305.569372) (xy 419.886085 -305.575304)
			(xy 419.933356 -305.588996) (xy 419.977818 -305.610094) (xy 420.018321 -305.63805) (xy 420.053814 -305.672142)
			(xy 420.083379 -305.711486) (xy 420.10625 -305.755063) (xy 420.121834 -305.801744) (xy 420.129729 -305.850321)
			(xy 420.130224 -305.874928) (xy 420.469072 -305.874928) (xy 420.473032 -305.825874) (xy 420.484809 -305.77809)
			(xy 420.5041 -305.732814) (xy 420.530403 -305.691218) (xy 420.563038 -305.654381) (xy 420.601159 -305.623256)
			(xy 420.64378 -305.598649) (xy 420.689796 -305.581197) (xy 420.738015 -305.571353) (xy 420.78719 -305.569372)
			(xy 420.836045 -305.575304) (xy 420.883316 -305.588996) (xy 420.927778 -305.610094) (xy 420.968281 -305.63805)
			(xy 421.003774 -305.672142) (xy 421.033339 -305.711486) (xy 421.05621 -305.755063) (xy 421.071794 -305.801744)
			(xy 421.079689 -305.850321) (xy 421.080184 -305.874928) (xy 421.419032 -305.874928) (xy 421.422992 -305.825874)
			(xy 421.434769 -305.77809) (xy 421.45406 -305.732814) (xy 421.480363 -305.691218) (xy 421.512998 -305.654381)
			(xy 421.551119 -305.623256) (xy 421.59374 -305.598649) (xy 421.639756 -305.581197) (xy 421.687975 -305.571353)
			(xy 421.73715 -305.569372) (xy 421.786005 -305.575304) (xy 421.833276 -305.588996) (xy 421.877738 -305.610094)
			(xy 421.918241 -305.63805) (xy 421.953734 -305.672142) (xy 421.983299 -305.711486) (xy 422.00617 -305.755063)
			(xy 422.021754 -305.801744) (xy 422.029649 -305.850321) (xy 422.030143 -305.8749) (xy 422.368997 -305.8749)
			(xy 422.373168 -305.824567) (xy 422.385566 -305.775607) (xy 422.405854 -305.729355) (xy 422.433477 -305.687073)
			(xy 422.467684 -305.649915) (xy 422.507539 -305.618893) (xy 422.551958 -305.594855) (xy 422.599727 -305.578455)
			(xy 422.649543 -305.570142) (xy 422.674796 -305.56962) (xy 422.689043 -305.569789) (xy 422.717411 -305.572457)
			(xy 422.731438 -305.574954) (xy 422.74363 -305.57724) (xy 422.76776 -305.569874) (xy 422.844976 -305.492658)
			(xy 422.852342 -305.468782) (xy 422.850056 -305.456336) (xy 422.847575 -305.442371) (xy 422.844906 -305.414131)
			(xy 422.844722 -305.399948) (xy 422.845126 -305.375123) (xy 422.853151 -305.326125) (xy 422.868997 -305.279072)
			(xy 422.892247 -305.235202) (xy 422.922288 -305.195671) (xy 422.958329 -305.161521) (xy 422.99942 -305.133652)
			(xy 423.044478 -305.112798) (xy 423.092316 -305.099509) (xy 423.141675 -305.094134) (xy 423.191253 -305.096815)
			(xy 423.239743 -305.107482) (xy 423.28587 -305.125853) (xy 423.328416 -305.151445) (xy 423.366262 -305.183583)
			(xy 423.398409 -305.22142) (xy 423.424012 -305.26396) (xy 423.442395 -305.310082) (xy 423.453074 -305.35857)
			(xy 423.455322 -305.399948) (xy 423.794186 -305.399948) (xy 423.798146 -305.350894) (xy 423.809923 -305.30311)
			(xy 423.829214 -305.257834) (xy 423.855517 -305.216238) (xy 423.888152 -305.179401) (xy 423.926273 -305.148276)
			(xy 423.968894 -305.123669) (xy 424.01491 -305.106217) (xy 424.063129 -305.096373) (xy 424.112304 -305.094392)
			(xy 424.161159 -305.100324) (xy 424.20843 -305.114016) (xy 424.252892 -305.135114) (xy 424.293395 -305.16307)
			(xy 424.328888 -305.197162) (xy 424.358453 -305.236506) (xy 424.381324 -305.280083) (xy 424.396908 -305.326764)
			(xy 424.404803 -305.375341) (xy 424.405298 -305.399948) (xy 424.404803 -305.424555) (xy 424.404624 -305.425656)
			(xy 424.723302 -305.425656) (xy 424.723302 -305.37424) (xy 424.731345 -305.323458) (xy 424.747233 -305.274559)
			(xy 424.770576 -305.228747) (xy 424.800797 -305.187151) (xy 424.837153 -305.150795) (xy 424.878749 -305.120574)
			(xy 424.924561 -305.097231) (xy 424.97346 -305.081343) (xy 425.024242 -305.0733) (xy 425.075658 -305.0733)
			(xy 425.12644 -305.081343) (xy 425.175339 -305.097231) (xy 425.221151 -305.120574) (xy 425.262747 -305.150795)
			(xy 425.299103 -305.187151) (xy 425.329324 -305.228747) (xy 425.352667 -305.274559) (xy 425.368555 -305.323458)
			(xy 425.376598 -305.37424) (xy 425.377102 -305.399948) (xy 425.376598 -305.425656) (xy 425.673262 -305.425656)
			(xy 425.673262 -305.37424) (xy 425.681305 -305.323458) (xy 425.697193 -305.274559) (xy 425.720536 -305.228747)
			(xy 425.750757 -305.187151) (xy 425.787113 -305.150795) (xy 425.828709 -305.120574) (xy 425.874521 -305.097231)
			(xy 425.92342 -305.081343) (xy 425.974202 -305.0733) (xy 426.025618 -305.0733) (xy 426.0764 -305.081343)
			(xy 426.125299 -305.097231) (xy 426.171111 -305.120574) (xy 426.212707 -305.150795) (xy 426.249063 -305.187151)
			(xy 426.279284 -305.228747) (xy 426.302627 -305.274559) (xy 426.318515 -305.323458) (xy 426.326558 -305.37424)
			(xy 426.327062 -305.399948) (xy 426.644066 -305.399948) (xy 426.648026 -305.350894) (xy 426.659803 -305.30311)
			(xy 426.679094 -305.257834) (xy 426.705397 -305.216238) (xy 426.738032 -305.179401) (xy 426.776153 -305.148276)
			(xy 426.818774 -305.123669) (xy 426.86479 -305.106217) (xy 426.913009 -305.096373) (xy 426.962184 -305.094392)
			(xy 427.011039 -305.100324) (xy 427.05831 -305.114016) (xy 427.102772 -305.135114) (xy 427.143275 -305.16307)
			(xy 427.178768 -305.197162) (xy 427.208333 -305.236506) (xy 427.231204 -305.280083) (xy 427.246788 -305.326764)
			(xy 427.254683 -305.375341) (xy 427.255178 -305.399948) (xy 427.254683 -305.424555) (xy 427.254504 -305.425656)
			(xy 427.573182 -305.425656) (xy 427.573182 -305.37424) (xy 427.581225 -305.323458) (xy 427.597113 -305.274559)
			(xy 427.620456 -305.228747) (xy 427.650677 -305.187151) (xy 427.687033 -305.150795) (xy 427.728629 -305.120574)
			(xy 427.774441 -305.097231) (xy 427.82334 -305.081343) (xy 427.874122 -305.0733) (xy 427.925538 -305.0733)
			(xy 427.97632 -305.081343) (xy 428.025219 -305.097231) (xy 428.071031 -305.120574) (xy 428.112627 -305.150795)
			(xy 428.148983 -305.187151) (xy 428.179204 -305.228747) (xy 428.202547 -305.274559) (xy 428.218435 -305.323458)
			(xy 428.226478 -305.37424) (xy 428.226982 -305.399948) (xy 428.226478 -305.425656) (xy 428.523142 -305.425656)
			(xy 428.523142 -305.37424) (xy 428.531185 -305.323458) (xy 428.547073 -305.274559) (xy 428.570416 -305.228747)
			(xy 428.600637 -305.187151) (xy 428.636993 -305.150795) (xy 428.678589 -305.120574) (xy 428.724401 -305.097231)
			(xy 428.7733 -305.081343) (xy 428.824082 -305.0733) (xy 428.875498 -305.0733) (xy 428.92628 -305.081343)
			(xy 428.975179 -305.097231) (xy 429.020991 -305.120574) (xy 429.062587 -305.150795) (xy 429.098943 -305.187151)
			(xy 429.129164 -305.228747) (xy 429.152507 -305.274559) (xy 429.168395 -305.323458) (xy 429.176438 -305.37424)
			(xy 429.176942 -305.399948) (xy 429.4942 -305.399948) (xy 429.49816 -305.350894) (xy 429.509937 -305.30311)
			(xy 429.529228 -305.257834) (xy 429.555531 -305.216238) (xy 429.588166 -305.179401) (xy 429.626287 -305.148276)
			(xy 429.668908 -305.123669) (xy 429.714924 -305.106217) (xy 429.763143 -305.096373) (xy 429.812318 -305.094392)
			(xy 429.861173 -305.100324) (xy 429.908444 -305.114016) (xy 429.952906 -305.135114) (xy 429.993409 -305.16307)
			(xy 430.028902 -305.197162) (xy 430.058467 -305.236506) (xy 430.081338 -305.280083) (xy 430.096922 -305.326764)
			(xy 430.104817 -305.375341) (xy 430.105312 -305.399948) (xy 430.44416 -305.399948) (xy 430.44812 -305.350894)
			(xy 430.459897 -305.30311) (xy 430.479188 -305.257834) (xy 430.505491 -305.216238) (xy 430.538126 -305.179401)
			(xy 430.576247 -305.148276) (xy 430.618868 -305.123669) (xy 430.664884 -305.106217) (xy 430.713103 -305.096373)
			(xy 430.762278 -305.094392) (xy 430.811133 -305.100324) (xy 430.858404 -305.114016) (xy 430.902866 -305.135114)
			(xy 430.943369 -305.16307) (xy 430.978862 -305.197162) (xy 431.008427 -305.236506) (xy 431.031298 -305.280083)
			(xy 431.046882 -305.326764) (xy 431.054777 -305.375341) (xy 431.055272 -305.399948) (xy 431.054777 -305.424555)
			(xy 431.046882 -305.473132) (xy 431.031298 -305.519813) (xy 431.008427 -305.56339) (xy 430.978862 -305.602734)
			(xy 430.943369 -305.636826) (xy 430.902866 -305.664782) (xy 430.858404 -305.68588) (xy 430.811133 -305.699572)
			(xy 430.762278 -305.705504) (xy 430.713103 -305.703523) (xy 430.664884 -305.693679) (xy 430.618868 -305.676227)
			(xy 430.576247 -305.65162) (xy 430.538126 -305.620495) (xy 430.505491 -305.583658) (xy 430.479188 -305.542062)
			(xy 430.459897 -305.496786) (xy 430.44812 -305.449002) (xy 430.44416 -305.399948) (xy 430.105312 -305.399948)
			(xy 430.104817 -305.424555) (xy 430.096922 -305.473132) (xy 430.081338 -305.519813) (xy 430.058467 -305.56339)
			(xy 430.028902 -305.602734) (xy 429.993409 -305.636826) (xy 429.952906 -305.664782) (xy 429.908444 -305.68588)
			(xy 429.861173 -305.699572) (xy 429.812318 -305.705504) (xy 429.763143 -305.703523) (xy 429.714924 -305.693679)
			(xy 429.668908 -305.676227) (xy 429.626287 -305.65162) (xy 429.588166 -305.620495) (xy 429.555531 -305.583658)
			(xy 429.529228 -305.542062) (xy 429.509937 -305.496786) (xy 429.49816 -305.449002) (xy 429.4942 -305.399948)
			(xy 429.176942 -305.399948) (xy 429.176438 -305.425656) (xy 429.168395 -305.476438) (xy 429.152507 -305.525337)
			(xy 429.129164 -305.571149) (xy 429.098943 -305.612745) (xy 429.062587 -305.649101) (xy 429.020991 -305.679322)
			(xy 428.975179 -305.702665) (xy 428.92628 -305.718553) (xy 428.875498 -305.726596) (xy 428.824082 -305.726596)
			(xy 428.7733 -305.718553) (xy 428.724401 -305.702665) (xy 428.678589 -305.679322) (xy 428.636993 -305.649101)
			(xy 428.600637 -305.612745) (xy 428.570416 -305.571149) (xy 428.547073 -305.525337) (xy 428.531185 -305.476438)
			(xy 428.523142 -305.425656) (xy 428.226478 -305.425656) (xy 428.218435 -305.476438) (xy 428.202547 -305.525337)
			(xy 428.179204 -305.571149) (xy 428.148983 -305.612745) (xy 428.112627 -305.649101) (xy 428.071031 -305.679322)
			(xy 428.025219 -305.702665) (xy 427.97632 -305.718553) (xy 427.925538 -305.726596) (xy 427.874122 -305.726596)
			(xy 427.82334 -305.718553) (xy 427.774441 -305.702665) (xy 427.728629 -305.679322) (xy 427.687033 -305.649101)
			(xy 427.650677 -305.612745) (xy 427.620456 -305.571149) (xy 427.597113 -305.525337) (xy 427.581225 -305.476438)
			(xy 427.573182 -305.425656) (xy 427.254504 -305.425656) (xy 427.246788 -305.473132) (xy 427.231204 -305.519813)
			(xy 427.208333 -305.56339) (xy 427.178768 -305.602734) (xy 427.143275 -305.636826) (xy 427.102772 -305.664782)
			(xy 427.05831 -305.68588) (xy 427.011039 -305.699572) (xy 426.962184 -305.705504) (xy 426.913009 -305.703523)
			(xy 426.86479 -305.693679) (xy 426.818774 -305.676227) (xy 426.776153 -305.65162) (xy 426.738032 -305.620495)
			(xy 426.705397 -305.583658) (xy 426.679094 -305.542062) (xy 426.659803 -305.496786) (xy 426.648026 -305.449002)
			(xy 426.644066 -305.399948) (xy 426.327062 -305.399948) (xy 426.326558 -305.425656) (xy 426.318515 -305.476438)
			(xy 426.302627 -305.525337) (xy 426.279284 -305.571149) (xy 426.249063 -305.612745) (xy 426.212707 -305.649101)
			(xy 426.171111 -305.679322) (xy 426.125299 -305.702665) (xy 426.0764 -305.718553) (xy 426.025618 -305.726596)
			(xy 425.974202 -305.726596) (xy 425.92342 -305.718553) (xy 425.874521 -305.702665) (xy 425.828709 -305.679322)
			(xy 425.787113 -305.649101) (xy 425.750757 -305.612745) (xy 425.720536 -305.571149) (xy 425.697193 -305.525337)
			(xy 425.681305 -305.476438) (xy 425.673262 -305.425656) (xy 425.376598 -305.425656) (xy 425.368555 -305.476438)
			(xy 425.352667 -305.525337) (xy 425.329324 -305.571149) (xy 425.299103 -305.612745) (xy 425.262747 -305.649101)
			(xy 425.221151 -305.679322) (xy 425.175339 -305.702665) (xy 425.12644 -305.718553) (xy 425.075658 -305.726596)
			(xy 425.024242 -305.726596) (xy 424.97346 -305.718553) (xy 424.924561 -305.702665) (xy 424.878749 -305.679322)
			(xy 424.837153 -305.649101) (xy 424.800797 -305.612745) (xy 424.770576 -305.571149) (xy 424.747233 -305.525337)
			(xy 424.731345 -305.476438) (xy 424.723302 -305.425656) (xy 424.404624 -305.425656) (xy 424.396908 -305.473132)
			(xy 424.381324 -305.519813) (xy 424.358453 -305.56339) (xy 424.328888 -305.602734) (xy 424.293395 -305.636826)
			(xy 424.252892 -305.664782) (xy 424.20843 -305.68588) (xy 424.161159 -305.699572) (xy 424.112304 -305.705504)
			(xy 424.063129 -305.703523) (xy 424.01491 -305.693679) (xy 423.968894 -305.676227) (xy 423.926273 -305.65162)
			(xy 423.888152 -305.620495) (xy 423.855517 -305.583658) (xy 423.829214 -305.542062) (xy 423.809923 -305.496786)
			(xy 423.798146 -305.449002) (xy 423.794186 -305.399948) (xy 423.455322 -305.399948) (xy 423.455768 -305.408147)
			(xy 423.450406 -305.457507) (xy 423.437129 -305.505349) (xy 423.416286 -305.550412) (xy 423.388428 -305.59151)
			(xy 423.354287 -305.62756) (xy 423.314764 -305.657611) (xy 423.2709 -305.680872) (xy 423.22385 -305.696731)
			(xy 423.174855 -305.704768) (xy 423.15003 -305.705256) (xy 423.135783 -305.705098) (xy 423.107415 -305.702423)
			(xy 423.093388 -305.699922) (xy 423.081196 -305.697636) (xy 423.057066 -305.705002) (xy 422.97985 -305.782218)
			(xy 422.972484 -305.806094) (xy 422.97477 -305.81854) (xy 422.977248 -305.832506) (xy 422.979919 -305.860745)
			(xy 422.980104 -305.874928) (xy 422.980034 -305.884799) (xy 422.978761 -305.9045) (xy 422.977564 -305.914298)
			(xy 422.97604 -305.926236) (xy 422.983914 -305.949096) (xy 423.060368 -306.022502) (xy 423.083228 -306.029614)
			(xy 423.09542 -306.027582) (xy 423.108965 -306.025369) (xy 423.136307 -306.02295) (xy 423.15003 -306.022756)
			(xy 423.175711 -306.023338) (xy 423.226441 -306.031376) (xy 423.27529 -306.04725) (xy 423.321054 -306.070569)
			(xy 423.362608 -306.100759) (xy 423.398928 -306.137077) (xy 423.429121 -306.178629) (xy 423.452442 -306.224392)
			(xy 423.468319 -306.27324) (xy 423.476361 -306.323969) (xy 423.476369 -306.375332) (xy 423.476324 -306.375616)
			(xy 423.773342 -306.375616) (xy 423.773342 -306.3242) (xy 423.781385 -306.273418) (xy 423.797273 -306.224519)
			(xy 423.820616 -306.178707) (xy 423.850837 -306.137111) (xy 423.887193 -306.100755) (xy 423.928789 -306.070534)
			(xy 423.974601 -306.047191) (xy 424.0235 -306.031303) (xy 424.074282 -306.02326) (xy 424.125698 -306.02326)
			(xy 424.17648 -306.031303) (xy 424.225379 -306.047191) (xy 424.271191 -306.070534) (xy 424.312787 -306.100755)
			(xy 424.349143 -306.137111) (xy 424.379364 -306.178707) (xy 424.402707 -306.224519) (xy 424.418595 -306.273418)
			(xy 424.426638 -306.3242) (xy 424.427142 -306.349908) (xy 424.744146 -306.349908) (xy 424.748106 -306.300854)
			(xy 424.759883 -306.25307) (xy 424.779174 -306.207794) (xy 424.805477 -306.166198) (xy 424.838112 -306.129361)
			(xy 424.876233 -306.098236) (xy 424.918854 -306.073629) (xy 424.96487 -306.056177) (xy 425.013089 -306.046333)
			(xy 425.062264 -306.044352) (xy 425.111119 -306.050284) (xy 425.15839 -306.063976) (xy 425.202852 -306.085074)
			(xy 425.243355 -306.11303) (xy 425.278848 -306.147122) (xy 425.308413 -306.186466) (xy 425.331284 -306.230043)
			(xy 425.346868 -306.276724) (xy 425.354763 -306.325301) (xy 425.355258 -306.349908) (xy 425.694106 -306.349908)
			(xy 425.698066 -306.300854) (xy 425.709843 -306.25307) (xy 425.729134 -306.207794) (xy 425.755437 -306.166198)
			(xy 425.788072 -306.129361) (xy 425.826193 -306.098236) (xy 425.868814 -306.073629) (xy 425.91483 -306.056177)
			(xy 425.963049 -306.046333) (xy 426.012224 -306.044352) (xy 426.061079 -306.050284) (xy 426.10835 -306.063976)
			(xy 426.152812 -306.085074) (xy 426.193315 -306.11303) (xy 426.228808 -306.147122) (xy 426.258373 -306.186466)
			(xy 426.281244 -306.230043) (xy 426.296828 -306.276724) (xy 426.304723 -306.325301) (xy 426.305218 -306.349908)
			(xy 426.644066 -306.349908) (xy 426.648026 -306.300854) (xy 426.659803 -306.25307) (xy 426.679094 -306.207794)
			(xy 426.705397 -306.166198) (xy 426.738032 -306.129361) (xy 426.776153 -306.098236) (xy 426.818774 -306.073629)
			(xy 426.86479 -306.056177) (xy 426.913009 -306.046333) (xy 426.962184 -306.044352) (xy 427.011039 -306.050284)
			(xy 427.05831 -306.063976) (xy 427.102772 -306.085074) (xy 427.143275 -306.11303) (xy 427.178768 -306.147122)
			(xy 427.208333 -306.186466) (xy 427.231204 -306.230043) (xy 427.246788 -306.276724) (xy 427.254683 -306.325301)
			(xy 427.255178 -306.349908) (xy 427.594026 -306.349908) (xy 427.597986 -306.300854) (xy 427.609763 -306.25307)
			(xy 427.629054 -306.207794) (xy 427.655357 -306.166198) (xy 427.687992 -306.129361) (xy 427.726113 -306.098236)
			(xy 427.768734 -306.073629) (xy 427.81475 -306.056177) (xy 427.862969 -306.046333) (xy 427.912144 -306.044352)
			(xy 427.960999 -306.050284) (xy 428.00827 -306.063976) (xy 428.052732 -306.085074) (xy 428.093235 -306.11303)
			(xy 428.128728 -306.147122) (xy 428.158293 -306.186466) (xy 428.181164 -306.230043) (xy 428.196748 -306.276724)
			(xy 428.204643 -306.325301) (xy 428.205138 -306.349908) (xy 428.543986 -306.349908) (xy 428.547946 -306.300854)
			(xy 428.559723 -306.25307) (xy 428.579014 -306.207794) (xy 428.605317 -306.166198) (xy 428.637952 -306.129361)
			(xy 428.676073 -306.098236) (xy 428.718694 -306.073629) (xy 428.76471 -306.056177) (xy 428.812929 -306.046333)
			(xy 428.862104 -306.044352) (xy 428.910959 -306.050284) (xy 428.95823 -306.063976) (xy 429.002692 -306.085074)
			(xy 429.043195 -306.11303) (xy 429.078688 -306.147122) (xy 429.108253 -306.186466) (xy 429.131124 -306.230043)
			(xy 429.146708 -306.276724) (xy 429.154603 -306.325301) (xy 429.155098 -306.349908) (xy 429.154603 -306.374515)
			(xy 429.154424 -306.375616) (xy 429.473356 -306.375616) (xy 429.473356 -306.3242) (xy 429.481399 -306.273418)
			(xy 429.497287 -306.224519) (xy 429.52063 -306.178707) (xy 429.550851 -306.137111) (xy 429.587207 -306.100755)
			(xy 429.628803 -306.070534) (xy 429.674615 -306.047191) (xy 429.723514 -306.031303) (xy 429.774296 -306.02326)
			(xy 429.825712 -306.02326) (xy 429.876494 -306.031303) (xy 429.925393 -306.047191) (xy 429.971205 -306.070534)
			(xy 430.012801 -306.100755) (xy 430.049157 -306.137111) (xy 430.079378 -306.178707) (xy 430.102721 -306.224519)
			(xy 430.118609 -306.273418) (xy 430.126652 -306.3242) (xy 430.127156 -306.349908) (xy 430.126652 -306.375616)
			(xy 430.423316 -306.375616) (xy 430.423316 -306.3242) (xy 430.431359 -306.273418) (xy 430.447247 -306.224519)
			(xy 430.47059 -306.178707) (xy 430.500811 -306.137111) (xy 430.537167 -306.100755) (xy 430.578763 -306.070534)
			(xy 430.624575 -306.047191) (xy 430.673474 -306.031303) (xy 430.724256 -306.02326) (xy 430.775672 -306.02326)
			(xy 430.826454 -306.031303) (xy 430.875353 -306.047191) (xy 430.921165 -306.070534) (xy 430.962761 -306.100755)
			(xy 430.999117 -306.137111) (xy 431.029338 -306.178707) (xy 431.052681 -306.224519) (xy 431.068569 -306.273418)
			(xy 431.076612 -306.3242) (xy 431.077116 -306.349908) (xy 431.394374 -306.349908) (xy 431.398334 -306.300854)
			(xy 431.410111 -306.25307) (xy 431.429402 -306.207794) (xy 431.455705 -306.166198) (xy 431.48834 -306.129361)
			(xy 431.526461 -306.098236) (xy 431.569082 -306.073629) (xy 431.615098 -306.056177) (xy 431.663317 -306.046333)
			(xy 431.712492 -306.044352) (xy 431.761347 -306.050284) (xy 431.808618 -306.063976) (xy 431.85308 -306.085074)
			(xy 431.893583 -306.11303) (xy 431.929076 -306.147122) (xy 431.958641 -306.186466) (xy 431.981512 -306.230043)
			(xy 431.997096 -306.276724) (xy 432.004991 -306.325301) (xy 432.005486 -306.349908) (xy 432.004991 -306.374515)
			(xy 431.997096 -306.423092) (xy 431.981512 -306.469773) (xy 431.958641 -306.51335) (xy 431.929076 -306.552694)
			(xy 431.893583 -306.586786) (xy 431.85308 -306.614742) (xy 431.808618 -306.63584) (xy 431.761347 -306.649532)
			(xy 431.712492 -306.655464) (xy 431.663317 -306.653483) (xy 431.615098 -306.643639) (xy 431.569082 -306.626187)
			(xy 431.526461 -306.60158) (xy 431.48834 -306.570455) (xy 431.455705 -306.533618) (xy 431.429402 -306.492022)
			(xy 431.410111 -306.446746) (xy 431.398334 -306.398962) (xy 431.394374 -306.349908) (xy 431.077116 -306.349908)
			(xy 431.076612 -306.375616) (xy 431.068569 -306.426398) (xy 431.052681 -306.475297) (xy 431.029338 -306.521109)
			(xy 430.999117 -306.562705) (xy 430.962761 -306.599061) (xy 430.921165 -306.629282) (xy 430.875353 -306.652625)
			(xy 430.826454 -306.668513) (xy 430.775672 -306.676556) (xy 430.724256 -306.676556) (xy 430.673474 -306.668513)
			(xy 430.624575 -306.652625) (xy 430.578763 -306.629282) (xy 430.537167 -306.599061) (xy 430.500811 -306.562705)
			(xy 430.47059 -306.521109) (xy 430.447247 -306.475297) (xy 430.431359 -306.426398) (xy 430.423316 -306.375616)
			(xy 430.126652 -306.375616) (xy 430.118609 -306.426398) (xy 430.102721 -306.475297) (xy 430.079378 -306.521109)
			(xy 430.049157 -306.562705) (xy 430.012801 -306.599061) (xy 429.971205 -306.629282) (xy 429.925393 -306.652625)
			(xy 429.876494 -306.668513) (xy 429.825712 -306.676556) (xy 429.774296 -306.676556) (xy 429.723514 -306.668513)
			(xy 429.674615 -306.652625) (xy 429.628803 -306.629282) (xy 429.587207 -306.599061) (xy 429.550851 -306.562705)
			(xy 429.52063 -306.521109) (xy 429.497287 -306.475297) (xy 429.481399 -306.426398) (xy 429.473356 -306.375616)
			(xy 429.154424 -306.375616) (xy 429.146708 -306.423092) (xy 429.131124 -306.469773) (xy 429.108253 -306.51335)
			(xy 429.078688 -306.552694) (xy 429.043195 -306.586786) (xy 429.002692 -306.614742) (xy 428.95823 -306.63584)
			(xy 428.910959 -306.649532) (xy 428.862104 -306.655464) (xy 428.812929 -306.653483) (xy 428.76471 -306.643639)
			(xy 428.718694 -306.626187) (xy 428.676073 -306.60158) (xy 428.637952 -306.570455) (xy 428.605317 -306.533618)
			(xy 428.579014 -306.492022) (xy 428.559723 -306.446746) (xy 428.547946 -306.398962) (xy 428.543986 -306.349908)
			(xy 428.205138 -306.349908) (xy 428.204643 -306.374515) (xy 428.196748 -306.423092) (xy 428.181164 -306.469773)
			(xy 428.158293 -306.51335) (xy 428.128728 -306.552694) (xy 428.093235 -306.586786) (xy 428.052732 -306.614742)
			(xy 428.00827 -306.63584) (xy 427.960999 -306.649532) (xy 427.912144 -306.655464) (xy 427.862969 -306.653483)
			(xy 427.81475 -306.643639) (xy 427.768734 -306.626187) (xy 427.726113 -306.60158) (xy 427.687992 -306.570455)
			(xy 427.655357 -306.533618) (xy 427.629054 -306.492022) (xy 427.609763 -306.446746) (xy 427.597986 -306.398962)
			(xy 427.594026 -306.349908) (xy 427.255178 -306.349908) (xy 427.254683 -306.374515) (xy 427.246788 -306.423092)
			(xy 427.231204 -306.469773) (xy 427.208333 -306.51335) (xy 427.178768 -306.552694) (xy 427.143275 -306.586786)
			(xy 427.102772 -306.614742) (xy 427.05831 -306.63584) (xy 427.011039 -306.649532) (xy 426.962184 -306.655464)
			(xy 426.913009 -306.653483) (xy 426.86479 -306.643639) (xy 426.818774 -306.626187) (xy 426.776153 -306.60158)
			(xy 426.738032 -306.570455) (xy 426.705397 -306.533618) (xy 426.679094 -306.492022) (xy 426.659803 -306.446746)
			(xy 426.648026 -306.398962) (xy 426.644066 -306.349908) (xy 426.305218 -306.349908) (xy 426.304723 -306.374515)
			(xy 426.296828 -306.423092) (xy 426.281244 -306.469773) (xy 426.258373 -306.51335) (xy 426.228808 -306.552694)
			(xy 426.193315 -306.586786) (xy 426.152812 -306.614742) (xy 426.10835 -306.63584) (xy 426.061079 -306.649532)
			(xy 426.012224 -306.655464) (xy 425.963049 -306.653483) (xy 425.91483 -306.643639) (xy 425.868814 -306.626187)
			(xy 425.826193 -306.60158) (xy 425.788072 -306.570455) (xy 425.755437 -306.533618) (xy 425.729134 -306.492022)
			(xy 425.709843 -306.446746) (xy 425.698066 -306.398962) (xy 425.694106 -306.349908) (xy 425.355258 -306.349908)
			(xy 425.354763 -306.374515) (xy 425.346868 -306.423092) (xy 425.331284 -306.469773) (xy 425.308413 -306.51335)
			(xy 425.278848 -306.552694) (xy 425.243355 -306.586786) (xy 425.202852 -306.614742) (xy 425.15839 -306.63584)
			(xy 425.111119 -306.649532) (xy 425.062264 -306.655464) (xy 425.013089 -306.653483) (xy 424.96487 -306.643639)
			(xy 424.918854 -306.626187) (xy 424.876233 -306.60158) (xy 424.838112 -306.570455) (xy 424.805477 -306.533618)
			(xy 424.779174 -306.492022) (xy 424.759883 -306.446746) (xy 424.748106 -306.398962) (xy 424.744146 -306.349908)
			(xy 424.427142 -306.349908) (xy 424.426638 -306.375616) (xy 424.418595 -306.426398) (xy 424.402707 -306.475297)
			(xy 424.379364 -306.521109) (xy 424.349143 -306.562705) (xy 424.312787 -306.599061) (xy 424.271191 -306.629282)
			(xy 424.225379 -306.652625) (xy 424.17648 -306.668513) (xy 424.125698 -306.676556) (xy 424.074282 -306.676556)
			(xy 424.0235 -306.668513) (xy 423.974601 -306.652625) (xy 423.928789 -306.629282) (xy 423.887193 -306.599061)
			(xy 423.850837 -306.562705) (xy 423.820616 -306.521109) (xy 423.797273 -306.475297) (xy 423.781385 -306.426398)
			(xy 423.773342 -306.375616) (xy 423.476324 -306.375616) (xy 423.468343 -306.426064) (xy 423.45248 -306.474916)
			(xy 423.429172 -306.520686) (xy 423.398992 -306.562247) (xy 423.362683 -306.598576) (xy 423.321138 -306.628779)
			(xy 423.275381 -306.652112) (xy 423.226538 -306.668001) (xy 423.17581 -306.676055) (xy 423.124447 -306.676075)
			(xy 423.073713 -306.668061) (xy 423.024857 -306.652211) (xy 422.979081 -306.628914) (xy 422.937513 -306.598744)
			(xy 422.901175 -306.562443) (xy 422.870963 -306.520906) (xy 422.847618 -306.475155) (xy 422.831718 -306.426315)
			(xy 422.823652 -306.375589) (xy 422.823132 -306.349908) (xy 422.823281 -306.33619) (xy 422.825567 -306.308849)
			(xy 422.827704 -306.295298) (xy 422.829736 -306.28336) (xy 422.822624 -306.2605) (xy 422.748964 -306.184046)
			(xy 422.726358 -306.176172) (xy 422.714166 -306.177696) (xy 422.704367 -306.178883) (xy 422.684667 -306.180155)
			(xy 422.674796 -306.180236) (xy 422.649543 -306.179658) (xy 422.599727 -306.171345) (xy 422.551958 -306.154945)
			(xy 422.507539 -306.130907) (xy 422.467684 -306.099885) (xy 422.433477 -306.062727) (xy 422.405854 -306.020445)
			(xy 422.385566 -305.974193) (xy 422.373168 -305.925233) (xy 422.368997 -305.8749) (xy 422.030143 -305.8749)
			(xy 422.030144 -305.874928) (xy 422.029649 -305.899535) (xy 422.021754 -305.948112) (xy 422.00617 -305.994793)
			(xy 421.983299 -306.03837) (xy 421.953734 -306.077714) (xy 421.918241 -306.111806) (xy 421.877738 -306.139762)
			(xy 421.833276 -306.16086) (xy 421.786005 -306.174552) (xy 421.73715 -306.180484) (xy 421.687975 -306.178503)
			(xy 421.639756 -306.168659) (xy 421.59374 -306.151207) (xy 421.551119 -306.1266) (xy 421.512998 -306.095475)
			(xy 421.480363 -306.058638) (xy 421.45406 -306.017042) (xy 421.434769 -305.971766) (xy 421.422992 -305.923982)
			(xy 421.419032 -305.874928) (xy 421.080184 -305.874928) (xy 421.079689 -305.899535) (xy 421.071794 -305.948112)
			(xy 421.05621 -305.994793) (xy 421.033339 -306.03837) (xy 421.003774 -306.077714) (xy 420.968281 -306.111806)
			(xy 420.927778 -306.139762) (xy 420.883316 -306.16086) (xy 420.836045 -306.174552) (xy 420.78719 -306.180484)
			(xy 420.738015 -306.178503) (xy 420.689796 -306.168659) (xy 420.64378 -306.151207) (xy 420.601159 -306.1266)
			(xy 420.563038 -306.095475) (xy 420.530403 -306.058638) (xy 420.5041 -306.017042) (xy 420.484809 -305.971766)
			(xy 420.473032 -305.923982) (xy 420.469072 -305.874928) (xy 420.130224 -305.874928) (xy 420.129729 -305.899535)
			(xy 420.121834 -305.948112) (xy 420.10625 -305.994793) (xy 420.083379 -306.03837) (xy 420.053814 -306.077714)
			(xy 420.018321 -306.111806) (xy 419.977818 -306.139762) (xy 419.933356 -306.16086) (xy 419.886085 -306.174552)
			(xy 419.83723 -306.180484) (xy 419.788055 -306.178503) (xy 419.739836 -306.168659) (xy 419.69382 -306.151207)
			(xy 419.651199 -306.1266) (xy 419.613078 -306.095475) (xy 419.580443 -306.058638) (xy 419.55414 -306.017042)
			(xy 419.534849 -305.971766) (xy 419.523072 -305.923982) (xy 419.519112 -305.874928) (xy 419.180264 -305.874928)
			(xy 419.179769 -305.899535) (xy 419.171874 -305.948112) (xy 419.15629 -305.994793) (xy 419.133419 -306.03837)
			(xy 419.103854 -306.077714) (xy 419.068361 -306.111806) (xy 419.027858 -306.139762) (xy 418.983396 -306.16086)
			(xy 418.936125 -306.174552) (xy 418.88727 -306.180484) (xy 418.838095 -306.178503) (xy 418.789876 -306.168659)
			(xy 418.74386 -306.151207) (xy 418.701239 -306.1266) (xy 418.663118 -306.095475) (xy 418.630483 -306.058638)
			(xy 418.60418 -306.017042) (xy 418.584889 -305.971766) (xy 418.573112 -305.923982) (xy 418.569152 -305.874928)
			(xy 418.230304 -305.874928) (xy 418.229809 -305.899535) (xy 418.221914 -305.948112) (xy 418.20633 -305.994793)
			(xy 418.183459 -306.03837) (xy 418.153894 -306.077714) (xy 418.118401 -306.111806) (xy 418.077898 -306.139762)
			(xy 418.033436 -306.16086) (xy 417.986165 -306.174552) (xy 417.93731 -306.180484) (xy 417.888135 -306.178503)
			(xy 417.839916 -306.168659) (xy 417.7939 -306.151207) (xy 417.751279 -306.1266) (xy 417.713158 -306.095475)
			(xy 417.680523 -306.058638) (xy 417.65422 -306.017042) (xy 417.634929 -305.971766) (xy 417.623152 -305.923982)
			(xy 417.619192 -305.874928) (xy 417.28009 -305.874928) (xy 417.279595 -305.899535) (xy 417.2717 -305.948112)
			(xy 417.256116 -305.994793) (xy 417.233245 -306.03837) (xy 417.20368 -306.077714) (xy 417.168187 -306.111806)
			(xy 417.127684 -306.139762) (xy 417.083222 -306.16086) (xy 417.035951 -306.174552) (xy 416.987096 -306.180484)
			(xy 416.937921 -306.178503) (xy 416.889702 -306.168659) (xy 416.843686 -306.151207) (xy 416.801065 -306.1266)
			(xy 416.762944 -306.095475) (xy 416.730309 -306.058638) (xy 416.704006 -306.017042) (xy 416.684715 -305.971766)
			(xy 416.672938 -305.923982) (xy 416.668978 -305.874928) (xy 416.33013 -305.874928) (xy 416.329635 -305.899535)
			(xy 416.32174 -305.948112) (xy 416.306156 -305.994793) (xy 416.283285 -306.03837) (xy 416.25372 -306.077714)
			(xy 416.218227 -306.111806) (xy 416.177724 -306.139762) (xy 416.133262 -306.16086) (xy 416.085991 -306.174552)
			(xy 416.037136 -306.180484) (xy 415.987961 -306.178503) (xy 415.939742 -306.168659) (xy 415.893726 -306.151207)
			(xy 415.851105 -306.1266) (xy 415.812984 -306.095475) (xy 415.780349 -306.058638) (xy 415.754046 -306.017042)
			(xy 415.734755 -305.971766) (xy 415.722978 -305.923982) (xy 415.719018 -305.874928) (xy 415.38017 -305.874928)
			(xy 415.379675 -305.899535) (xy 415.37178 -305.948112) (xy 415.356196 -305.994793) (xy 415.333325 -306.03837)
			(xy 415.30376 -306.077714) (xy 415.268267 -306.111806) (xy 415.227764 -306.139762) (xy 415.183302 -306.16086)
			(xy 415.136031 -306.174552) (xy 415.087176 -306.180484) (xy 415.038001 -306.178503) (xy 414.989782 -306.168659)
			(xy 414.943766 -306.151207) (xy 414.901145 -306.1266) (xy 414.863024 -306.095475) (xy 414.830389 -306.058638)
			(xy 414.804086 -306.017042) (xy 414.784795 -305.971766) (xy 414.773018 -305.923982) (xy 414.769058 -305.874928)
			(xy 414.43021 -305.874928) (xy 414.429715 -305.899535) (xy 414.42182 -305.948112) (xy 414.406236 -305.994793)
			(xy 414.383365 -306.03837) (xy 414.3538 -306.077714) (xy 414.318307 -306.111806) (xy 414.277804 -306.139762)
			(xy 414.233342 -306.16086) (xy 414.186071 -306.174552) (xy 414.137216 -306.180484) (xy 414.088041 -306.178503)
			(xy 414.039822 -306.168659) (xy 413.993806 -306.151207) (xy 413.951185 -306.1266) (xy 413.913064 -306.095475)
			(xy 413.880429 -306.058638) (xy 413.854126 -306.017042) (xy 413.834835 -305.971766) (xy 413.823058 -305.923982)
			(xy 413.819098 -305.874928) (xy 413.48025 -305.874928) (xy 413.479755 -305.899535) (xy 413.47186 -305.948112)
			(xy 413.456276 -305.994793) (xy 413.433405 -306.03837) (xy 413.40384 -306.077714) (xy 413.368347 -306.111806)
			(xy 413.327844 -306.139762) (xy 413.283382 -306.16086) (xy 413.236111 -306.174552) (xy 413.187256 -306.180484)
			(xy 413.138081 -306.178503) (xy 413.089862 -306.168659) (xy 413.043846 -306.151207) (xy 413.001225 -306.1266)
			(xy 412.963104 -306.095475) (xy 412.930469 -306.058638) (xy 412.904166 -306.017042) (xy 412.884875 -305.971766)
			(xy 412.873098 -305.923982) (xy 412.869138 -305.874928) (xy 412.53029 -305.874928) (xy 412.529795 -305.899535)
			(xy 412.5219 -305.948112) (xy 412.506316 -305.994793) (xy 412.483445 -306.03837) (xy 412.45388 -306.077714)
			(xy 412.418387 -306.111806) (xy 412.377884 -306.139762) (xy 412.333422 -306.16086) (xy 412.286151 -306.174552)
			(xy 412.237296 -306.180484) (xy 412.188121 -306.178503) (xy 412.139902 -306.168659) (xy 412.093886 -306.151207)
			(xy 412.051265 -306.1266) (xy 412.013144 -306.095475) (xy 411.980509 -306.058638) (xy 411.954206 -306.017042)
			(xy 411.934915 -305.971766) (xy 411.923138 -305.923982) (xy 411.919178 -305.874928) (xy 411.58033 -305.874928)
			(xy 411.579835 -305.899535) (xy 411.57194 -305.948112) (xy 411.556356 -305.994793) (xy 411.533485 -306.03837)
			(xy 411.50392 -306.077714) (xy 411.468427 -306.111806) (xy 411.427924 -306.139762) (xy 411.383462 -306.16086)
			(xy 411.336191 -306.174552) (xy 411.287336 -306.180484) (xy 411.238161 -306.178503) (xy 411.189942 -306.168659)
			(xy 411.143926 -306.151207) (xy 411.101305 -306.1266) (xy 411.063184 -306.095475) (xy 411.030549 -306.058638)
			(xy 411.004246 -306.017042) (xy 410.984955 -305.971766) (xy 410.973178 -305.923982) (xy 410.969218 -305.874928)
			(xy 410.630116 -305.874928) (xy 410.629621 -305.899535) (xy 410.621726 -305.948112) (xy 410.606142 -305.994793)
			(xy 410.583271 -306.03837) (xy 410.553706 -306.077714) (xy 410.518213 -306.111806) (xy 410.47771 -306.139762)
			(xy 410.433248 -306.16086) (xy 410.385977 -306.174552) (xy 410.337122 -306.180484) (xy 410.287947 -306.178503)
			(xy 410.239728 -306.168659) (xy 410.193712 -306.151207) (xy 410.151091 -306.1266) (xy 410.11297 -306.095475)
			(xy 410.080335 -306.058638) (xy 410.054032 -306.017042) (xy 410.034741 -305.971766) (xy 410.022964 -305.923982)
			(xy 410.019004 -305.874928) (xy 409.680156 -305.874928) (xy 409.679661 -305.899535) (xy 409.671766 -305.948112)
			(xy 409.656182 -305.994793) (xy 409.633311 -306.03837) (xy 409.603746 -306.077714) (xy 409.568253 -306.111806)
			(xy 409.52775 -306.139762) (xy 409.483288 -306.16086) (xy 409.436017 -306.174552) (xy 409.387162 -306.180484)
			(xy 409.337987 -306.178503) (xy 409.289768 -306.168659) (xy 409.243752 -306.151207) (xy 409.201131 -306.1266)
			(xy 409.16301 -306.095475) (xy 409.130375 -306.058638) (xy 409.104072 -306.017042) (xy 409.084781 -305.971766)
			(xy 409.073004 -305.923982) (xy 409.069044 -305.874928) (xy 408.730196 -305.874928) (xy 408.729701 -305.899535)
			(xy 408.721806 -305.948112) (xy 408.706222 -305.994793) (xy 408.683351 -306.03837) (xy 408.653786 -306.077714)
			(xy 408.618293 -306.111806) (xy 408.57779 -306.139762) (xy 408.533328 -306.16086) (xy 408.486057 -306.174552)
			(xy 408.437202 -306.180484) (xy 408.388027 -306.178503) (xy 408.339808 -306.168659) (xy 408.293792 -306.151207)
			(xy 408.251171 -306.1266) (xy 408.21305 -306.095475) (xy 408.180415 -306.058638) (xy 408.154112 -306.017042)
			(xy 408.134821 -305.971766) (xy 408.123044 -305.923982) (xy 408.119084 -305.874928) (xy 406.830276 -305.874928)
			(xy 406.829781 -305.899535) (xy 406.821886 -305.948112) (xy 406.806302 -305.994793) (xy 406.783431 -306.03837)
			(xy 406.753866 -306.077714) (xy 406.718373 -306.111806) (xy 406.67787 -306.139762) (xy 406.633408 -306.16086)
			(xy 406.586137 -306.174552) (xy 406.537282 -306.180484) (xy 406.488107 -306.178503) (xy 406.439888 -306.168659)
			(xy 406.393872 -306.151207) (xy 406.351251 -306.1266) (xy 406.31313 -306.095475) (xy 406.280495 -306.058638)
			(xy 406.254192 -306.017042) (xy 406.234901 -305.971766) (xy 406.223124 -305.923982) (xy 406.219164 -305.874928)
			(xy 405.880316 -305.874928) (xy 405.879821 -305.899535) (xy 405.871926 -305.948112) (xy 405.856342 -305.994793)
			(xy 405.833471 -306.03837) (xy 405.803906 -306.077714) (xy 405.768413 -306.111806) (xy 405.72791 -306.139762)
			(xy 405.683448 -306.16086) (xy 405.636177 -306.174552) (xy 405.587322 -306.180484) (xy 405.538147 -306.178503)
			(xy 405.489928 -306.168659) (xy 405.443912 -306.151207) (xy 405.401291 -306.1266) (xy 405.36317 -306.095475)
			(xy 405.330535 -306.058638) (xy 405.304232 -306.017042) (xy 405.284941 -305.971766) (xy 405.273164 -305.923982)
			(xy 405.269204 -305.874928) (xy 404.930102 -305.874928) (xy 404.929607 -305.899535) (xy 404.921712 -305.948112)
			(xy 404.906128 -305.994793) (xy 404.883257 -306.03837) (xy 404.853692 -306.077714) (xy 404.818199 -306.111806)
			(xy 404.777696 -306.139762) (xy 404.733234 -306.16086) (xy 404.685963 -306.174552) (xy 404.637108 -306.180484)
			(xy 404.587933 -306.178503) (xy 404.539714 -306.168659) (xy 404.493698 -306.151207) (xy 404.451077 -306.1266)
			(xy 404.412956 -306.095475) (xy 404.380321 -306.058638) (xy 404.354018 -306.017042) (xy 404.334727 -305.971766)
			(xy 404.32295 -305.923982) (xy 404.31899 -305.874928) (xy 403.980142 -305.874928) (xy 403.979647 -305.899535)
			(xy 403.971752 -305.948112) (xy 403.956168 -305.994793) (xy 403.933297 -306.03837) (xy 403.903732 -306.077714)
			(xy 403.868239 -306.111806) (xy 403.827736 -306.139762) (xy 403.783274 -306.16086) (xy 403.736003 -306.174552)
			(xy 403.687148 -306.180484) (xy 403.637973 -306.178503) (xy 403.589754 -306.168659) (xy 403.543738 -306.151207)
			(xy 403.501117 -306.1266) (xy 403.462996 -306.095475) (xy 403.430361 -306.058638) (xy 403.404058 -306.017042)
			(xy 403.384767 -305.971766) (xy 403.37299 -305.923982) (xy 403.36903 -305.874928) (xy 403.030182 -305.874928)
			(xy 403.029687 -305.899535) (xy 403.021792 -305.948112) (xy 403.006208 -305.994793) (xy 402.983337 -306.03837)
			(xy 402.953772 -306.077714) (xy 402.918279 -306.111806) (xy 402.877776 -306.139762) (xy 402.833314 -306.16086)
			(xy 402.786043 -306.174552) (xy 402.737188 -306.180484) (xy 402.688013 -306.178503) (xy 402.639794 -306.168659)
			(xy 402.593778 -306.151207) (xy 402.551157 -306.1266) (xy 402.513036 -306.095475) (xy 402.480401 -306.058638)
			(xy 402.454098 -306.017042) (xy 402.434807 -305.971766) (xy 402.42303 -305.923982) (xy 402.41907 -305.874928)
			(xy 402.080222 -305.874928) (xy 402.079727 -305.899535) (xy 402.071832 -305.948112) (xy 402.056248 -305.994793)
			(xy 402.033377 -306.03837) (xy 402.003812 -306.077714) (xy 401.968319 -306.111806) (xy 401.927816 -306.139762)
			(xy 401.883354 -306.16086) (xy 401.836083 -306.174552) (xy 401.787228 -306.180484) (xy 401.738053 -306.178503)
			(xy 401.689834 -306.168659) (xy 401.643818 -306.151207) (xy 401.601197 -306.1266) (xy 401.563076 -306.095475)
			(xy 401.530441 -306.058638) (xy 401.504138 -306.017042) (xy 401.484847 -305.971766) (xy 401.47307 -305.923982)
			(xy 401.46911 -305.874928) (xy 401.130262 -305.874928) (xy 401.129767 -305.899535) (xy 401.121872 -305.948112)
			(xy 401.106288 -305.994793) (xy 401.083417 -306.03837) (xy 401.053852 -306.077714) (xy 401.018359 -306.111806)
			(xy 400.977856 -306.139762) (xy 400.933394 -306.16086) (xy 400.886123 -306.174552) (xy 400.837268 -306.180484)
			(xy 400.788093 -306.178503) (xy 400.739874 -306.168659) (xy 400.693858 -306.151207) (xy 400.651237 -306.1266)
			(xy 400.613116 -306.095475) (xy 400.580481 -306.058638) (xy 400.554178 -306.017042) (xy 400.534887 -305.971766)
			(xy 400.52311 -305.923982) (xy 400.51915 -305.874928) (xy 400.180302 -305.874928) (xy 400.179807 -305.899535)
			(xy 400.171912 -305.948112) (xy 400.156328 -305.994793) (xy 400.133457 -306.03837) (xy 400.103892 -306.077714)
			(xy 400.068399 -306.111806) (xy 400.027896 -306.139762) (xy 399.983434 -306.16086) (xy 399.936163 -306.174552)
			(xy 399.887308 -306.180484) (xy 399.838133 -306.178503) (xy 399.789914 -306.168659) (xy 399.743898 -306.151207)
			(xy 399.701277 -306.1266) (xy 399.663156 -306.095475) (xy 399.630521 -306.058638) (xy 399.604218 -306.017042)
			(xy 399.584927 -305.971766) (xy 399.57315 -305.923982) (xy 399.56919 -305.874928) (xy 399.230342 -305.874928)
			(xy 399.229847 -305.899535) (xy 399.221952 -305.948112) (xy 399.206368 -305.994793) (xy 399.183497 -306.03837)
			(xy 399.153932 -306.077714) (xy 399.118439 -306.111806) (xy 399.077936 -306.139762) (xy 399.033474 -306.16086)
			(xy 398.986203 -306.174552) (xy 398.937348 -306.180484) (xy 398.888173 -306.178503) (xy 398.839954 -306.168659)
			(xy 398.793938 -306.151207) (xy 398.751317 -306.1266) (xy 398.713196 -306.095475) (xy 398.680561 -306.058638)
			(xy 398.654258 -306.017042) (xy 398.634967 -305.971766) (xy 398.62319 -305.923982) (xy 398.61923 -305.874928)
			(xy 398.317212 -305.874928) (xy 398.317212 -306.824888) (xy 398.61923 -306.824888) (xy 398.62319 -306.775834)
			(xy 398.634967 -306.72805) (xy 398.654258 -306.682774) (xy 398.680561 -306.641178) (xy 398.713196 -306.604341)
			(xy 398.751317 -306.573216) (xy 398.793938 -306.548609) (xy 398.839954 -306.531157) (xy 398.888173 -306.521313)
			(xy 398.937348 -306.519332) (xy 398.986203 -306.525264) (xy 399.033474 -306.538956) (xy 399.077936 -306.560054)
			(xy 399.118439 -306.58801) (xy 399.153932 -306.622102) (xy 399.183497 -306.661446) (xy 399.206368 -306.705023)
			(xy 399.221952 -306.751704) (xy 399.229847 -306.800281) (xy 399.230342 -306.824888) (xy 399.56919 -306.824888)
			(xy 399.57315 -306.775834) (xy 399.584927 -306.72805) (xy 399.604218 -306.682774) (xy 399.630521 -306.641178)
			(xy 399.663156 -306.604341) (xy 399.701277 -306.573216) (xy 399.743898 -306.548609) (xy 399.789914 -306.531157)
			(xy 399.838133 -306.521313) (xy 399.887308 -306.519332) (xy 399.936163 -306.525264) (xy 399.983434 -306.538956)
			(xy 400.027896 -306.560054) (xy 400.068399 -306.58801) (xy 400.103892 -306.622102) (xy 400.133457 -306.661446)
			(xy 400.156328 -306.705023) (xy 400.171912 -306.751704) (xy 400.179807 -306.800281) (xy 400.180302 -306.824888)
			(xy 400.51915 -306.824888) (xy 400.52311 -306.775834) (xy 400.534887 -306.72805) (xy 400.554178 -306.682774)
			(xy 400.580481 -306.641178) (xy 400.613116 -306.604341) (xy 400.651237 -306.573216) (xy 400.693858 -306.548609)
			(xy 400.739874 -306.531157) (xy 400.788093 -306.521313) (xy 400.837268 -306.519332) (xy 400.886123 -306.525264)
			(xy 400.933394 -306.538956) (xy 400.977856 -306.560054) (xy 401.018359 -306.58801) (xy 401.053852 -306.622102)
			(xy 401.083417 -306.661446) (xy 401.106288 -306.705023) (xy 401.121872 -306.751704) (xy 401.129767 -306.800281)
			(xy 401.130262 -306.824888) (xy 401.46911 -306.824888) (xy 401.47307 -306.775834) (xy 401.484847 -306.72805)
			(xy 401.504138 -306.682774) (xy 401.530441 -306.641178) (xy 401.563076 -306.604341) (xy 401.601197 -306.573216)
			(xy 401.643818 -306.548609) (xy 401.689834 -306.531157) (xy 401.738053 -306.521313) (xy 401.787228 -306.519332)
			(xy 401.836083 -306.525264) (xy 401.883354 -306.538956) (xy 401.927816 -306.560054) (xy 401.968319 -306.58801)
			(xy 402.003812 -306.622102) (xy 402.033377 -306.661446) (xy 402.056248 -306.705023) (xy 402.071832 -306.751704)
			(xy 402.079727 -306.800281) (xy 402.080222 -306.824888) (xy 402.41907 -306.824888) (xy 402.42303 -306.775834)
			(xy 402.434807 -306.72805) (xy 402.454098 -306.682774) (xy 402.480401 -306.641178) (xy 402.513036 -306.604341)
			(xy 402.551157 -306.573216) (xy 402.593778 -306.548609) (xy 402.639794 -306.531157) (xy 402.688013 -306.521313)
			(xy 402.737188 -306.519332) (xy 402.786043 -306.525264) (xy 402.833314 -306.538956) (xy 402.877776 -306.560054)
			(xy 402.918279 -306.58801) (xy 402.953772 -306.622102) (xy 402.983337 -306.661446) (xy 403.006208 -306.705023)
			(xy 403.021792 -306.751704) (xy 403.029687 -306.800281) (xy 403.030182 -306.824888) (xy 403.36903 -306.824888)
			(xy 403.37299 -306.775834) (xy 403.384767 -306.72805) (xy 403.404058 -306.682774) (xy 403.430361 -306.641178)
			(xy 403.462996 -306.604341) (xy 403.501117 -306.573216) (xy 403.543738 -306.548609) (xy 403.589754 -306.531157)
			(xy 403.637973 -306.521313) (xy 403.687148 -306.519332) (xy 403.736003 -306.525264) (xy 403.783274 -306.538956)
			(xy 403.827736 -306.560054) (xy 403.868239 -306.58801) (xy 403.903732 -306.622102) (xy 403.933297 -306.661446)
			(xy 403.956168 -306.705023) (xy 403.971752 -306.751704) (xy 403.979647 -306.800281) (xy 403.980142 -306.824888)
			(xy 404.31899 -306.824888) (xy 404.32295 -306.775834) (xy 404.334727 -306.72805) (xy 404.354018 -306.682774)
			(xy 404.380321 -306.641178) (xy 404.412956 -306.604341) (xy 404.451077 -306.573216) (xy 404.493698 -306.548609)
			(xy 404.539714 -306.531157) (xy 404.587933 -306.521313) (xy 404.637108 -306.519332) (xy 404.685963 -306.525264)
			(xy 404.733234 -306.538956) (xy 404.777696 -306.560054) (xy 404.818199 -306.58801) (xy 404.853692 -306.622102)
			(xy 404.883257 -306.661446) (xy 404.906128 -306.705023) (xy 404.921712 -306.751704) (xy 404.929607 -306.800281)
			(xy 404.930102 -306.824888) (xy 405.269204 -306.824888) (xy 405.273164 -306.775834) (xy 405.284941 -306.72805)
			(xy 405.304232 -306.682774) (xy 405.330535 -306.641178) (xy 405.36317 -306.604341) (xy 405.401291 -306.573216)
			(xy 405.443912 -306.548609) (xy 405.489928 -306.531157) (xy 405.538147 -306.521313) (xy 405.587322 -306.519332)
			(xy 405.636177 -306.525264) (xy 405.683448 -306.538956) (xy 405.72791 -306.560054) (xy 405.768413 -306.58801)
			(xy 405.803906 -306.622102) (xy 405.833471 -306.661446) (xy 405.856342 -306.705023) (xy 405.871926 -306.751704)
			(xy 405.879821 -306.800281) (xy 405.880316 -306.824888) (xy 406.219164 -306.824888) (xy 406.223124 -306.775834)
			(xy 406.234901 -306.72805) (xy 406.254192 -306.682774) (xy 406.280495 -306.641178) (xy 406.31313 -306.604341)
			(xy 406.351251 -306.573216) (xy 406.393872 -306.548609) (xy 406.439888 -306.531157) (xy 406.488107 -306.521313)
			(xy 406.537282 -306.519332) (xy 406.586137 -306.525264) (xy 406.633408 -306.538956) (xy 406.67787 -306.560054)
			(xy 406.718373 -306.58801) (xy 406.753866 -306.622102) (xy 406.783431 -306.661446) (xy 406.806302 -306.705023)
			(xy 406.821886 -306.751704) (xy 406.829781 -306.800281) (xy 406.830276 -306.824888) (xy 408.119084 -306.824888)
			(xy 408.123044 -306.775834) (xy 408.134821 -306.72805) (xy 408.154112 -306.682774) (xy 408.180415 -306.641178)
			(xy 408.21305 -306.604341) (xy 408.251171 -306.573216) (xy 408.293792 -306.548609) (xy 408.339808 -306.531157)
			(xy 408.388027 -306.521313) (xy 408.437202 -306.519332) (xy 408.486057 -306.525264) (xy 408.533328 -306.538956)
			(xy 408.57779 -306.560054) (xy 408.618293 -306.58801) (xy 408.653786 -306.622102) (xy 408.683351 -306.661446)
			(xy 408.706222 -306.705023) (xy 408.721806 -306.751704) (xy 408.729701 -306.800281) (xy 408.730196 -306.824888)
			(xy 409.069044 -306.824888) (xy 409.073004 -306.775834) (xy 409.084781 -306.72805) (xy 409.104072 -306.682774)
			(xy 409.130375 -306.641178) (xy 409.16301 -306.604341) (xy 409.201131 -306.573216) (xy 409.243752 -306.548609)
			(xy 409.289768 -306.531157) (xy 409.337987 -306.521313) (xy 409.387162 -306.519332) (xy 409.436017 -306.525264)
			(xy 409.483288 -306.538956) (xy 409.52775 -306.560054) (xy 409.568253 -306.58801) (xy 409.603746 -306.622102)
			(xy 409.633311 -306.661446) (xy 409.656182 -306.705023) (xy 409.671766 -306.751704) (xy 409.679661 -306.800281)
			(xy 409.680156 -306.824888) (xy 410.019004 -306.824888) (xy 410.022964 -306.775834) (xy 410.034741 -306.72805)
			(xy 410.054032 -306.682774) (xy 410.080335 -306.641178) (xy 410.11297 -306.604341) (xy 410.151091 -306.573216)
			(xy 410.193712 -306.548609) (xy 410.239728 -306.531157) (xy 410.287947 -306.521313) (xy 410.337122 -306.519332)
			(xy 410.385977 -306.525264) (xy 410.433248 -306.538956) (xy 410.47771 -306.560054) (xy 410.518213 -306.58801)
			(xy 410.553706 -306.622102) (xy 410.583271 -306.661446) (xy 410.606142 -306.705023) (xy 410.621726 -306.751704)
			(xy 410.629621 -306.800281) (xy 410.630116 -306.824888) (xy 410.969218 -306.824888) (xy 410.973178 -306.775834)
			(xy 410.984955 -306.72805) (xy 411.004246 -306.682774) (xy 411.030549 -306.641178) (xy 411.063184 -306.604341)
			(xy 411.101305 -306.573216) (xy 411.143926 -306.548609) (xy 411.189942 -306.531157) (xy 411.238161 -306.521313)
			(xy 411.287336 -306.519332) (xy 411.336191 -306.525264) (xy 411.383462 -306.538956) (xy 411.427924 -306.560054)
			(xy 411.468427 -306.58801) (xy 411.50392 -306.622102) (xy 411.533485 -306.661446) (xy 411.556356 -306.705023)
			(xy 411.57194 -306.751704) (xy 411.579835 -306.800281) (xy 411.58033 -306.824888) (xy 411.919178 -306.824888)
			(xy 411.923138 -306.775834) (xy 411.934915 -306.72805) (xy 411.954206 -306.682774) (xy 411.980509 -306.641178)
			(xy 412.013144 -306.604341) (xy 412.051265 -306.573216) (xy 412.093886 -306.548609) (xy 412.139902 -306.531157)
			(xy 412.188121 -306.521313) (xy 412.237296 -306.519332) (xy 412.286151 -306.525264) (xy 412.333422 -306.538956)
			(xy 412.377884 -306.560054) (xy 412.418387 -306.58801) (xy 412.45388 -306.622102) (xy 412.483445 -306.661446)
			(xy 412.506316 -306.705023) (xy 412.5219 -306.751704) (xy 412.529795 -306.800281) (xy 412.53029 -306.824888)
			(xy 412.869138 -306.824888) (xy 412.873098 -306.775834) (xy 412.884875 -306.72805) (xy 412.904166 -306.682774)
			(xy 412.930469 -306.641178) (xy 412.963104 -306.604341) (xy 413.001225 -306.573216) (xy 413.043846 -306.548609)
			(xy 413.089862 -306.531157) (xy 413.138081 -306.521313) (xy 413.187256 -306.519332) (xy 413.236111 -306.525264)
			(xy 413.283382 -306.538956) (xy 413.327844 -306.560054) (xy 413.368347 -306.58801) (xy 413.40384 -306.622102)
			(xy 413.433405 -306.661446) (xy 413.456276 -306.705023) (xy 413.47186 -306.751704) (xy 413.479755 -306.800281)
			(xy 413.48025 -306.824888) (xy 413.819098 -306.824888) (xy 413.823058 -306.775834) (xy 413.834835 -306.72805)
			(xy 413.854126 -306.682774) (xy 413.880429 -306.641178) (xy 413.913064 -306.604341) (xy 413.951185 -306.573216)
			(xy 413.993806 -306.548609) (xy 414.039822 -306.531157) (xy 414.088041 -306.521313) (xy 414.137216 -306.519332)
			(xy 414.186071 -306.525264) (xy 414.233342 -306.538956) (xy 414.277804 -306.560054) (xy 414.318307 -306.58801)
			(xy 414.3538 -306.622102) (xy 414.383365 -306.661446) (xy 414.406236 -306.705023) (xy 414.42182 -306.751704)
			(xy 414.429715 -306.800281) (xy 414.43021 -306.824888) (xy 414.769058 -306.824888) (xy 414.773018 -306.775834)
			(xy 414.784795 -306.72805) (xy 414.804086 -306.682774) (xy 414.830389 -306.641178) (xy 414.863024 -306.604341)
			(xy 414.901145 -306.573216) (xy 414.943766 -306.548609) (xy 414.989782 -306.531157) (xy 415.038001 -306.521313)
			(xy 415.087176 -306.519332) (xy 415.136031 -306.525264) (xy 415.183302 -306.538956) (xy 415.227764 -306.560054)
			(xy 415.268267 -306.58801) (xy 415.30376 -306.622102) (xy 415.333325 -306.661446) (xy 415.356196 -306.705023)
			(xy 415.37178 -306.751704) (xy 415.379675 -306.800281) (xy 415.38017 -306.824888) (xy 415.719018 -306.824888)
			(xy 415.722978 -306.775834) (xy 415.734755 -306.72805) (xy 415.754046 -306.682774) (xy 415.780349 -306.641178)
			(xy 415.812984 -306.604341) (xy 415.851105 -306.573216) (xy 415.893726 -306.548609) (xy 415.939742 -306.531157)
			(xy 415.987961 -306.521313) (xy 416.037136 -306.519332) (xy 416.085991 -306.525264) (xy 416.133262 -306.538956)
			(xy 416.177724 -306.560054) (xy 416.218227 -306.58801) (xy 416.25372 -306.622102) (xy 416.283285 -306.661446)
			(xy 416.306156 -306.705023) (xy 416.32174 -306.751704) (xy 416.329635 -306.800281) (xy 416.33013 -306.824888)
			(xy 416.668978 -306.824888) (xy 416.672938 -306.775834) (xy 416.684715 -306.72805) (xy 416.704006 -306.682774)
			(xy 416.730309 -306.641178) (xy 416.762944 -306.604341) (xy 416.801065 -306.573216) (xy 416.843686 -306.548609)
			(xy 416.889702 -306.531157) (xy 416.937921 -306.521313) (xy 416.987096 -306.519332) (xy 417.035951 -306.525264)
			(xy 417.083222 -306.538956) (xy 417.127684 -306.560054) (xy 417.168187 -306.58801) (xy 417.20368 -306.622102)
			(xy 417.233245 -306.661446) (xy 417.256116 -306.705023) (xy 417.2717 -306.751704) (xy 417.279595 -306.800281)
			(xy 417.28009 -306.824888) (xy 417.619192 -306.824888) (xy 417.623152 -306.775834) (xy 417.634929 -306.72805)
			(xy 417.65422 -306.682774) (xy 417.680523 -306.641178) (xy 417.713158 -306.604341) (xy 417.751279 -306.573216)
			(xy 417.7939 -306.548609) (xy 417.839916 -306.531157) (xy 417.888135 -306.521313) (xy 417.93731 -306.519332)
			(xy 417.986165 -306.525264) (xy 418.033436 -306.538956) (xy 418.077898 -306.560054) (xy 418.118401 -306.58801)
			(xy 418.153894 -306.622102) (xy 418.183459 -306.661446) (xy 418.20633 -306.705023) (xy 418.221914 -306.751704)
			(xy 418.229809 -306.800281) (xy 418.230304 -306.824888) (xy 418.569152 -306.824888) (xy 418.573112 -306.775834)
			(xy 418.584889 -306.72805) (xy 418.60418 -306.682774) (xy 418.630483 -306.641178) (xy 418.663118 -306.604341)
			(xy 418.701239 -306.573216) (xy 418.74386 -306.548609) (xy 418.789876 -306.531157) (xy 418.838095 -306.521313)
			(xy 418.88727 -306.519332) (xy 418.936125 -306.525264) (xy 418.983396 -306.538956) (xy 419.027858 -306.560054)
			(xy 419.068361 -306.58801) (xy 419.103854 -306.622102) (xy 419.133419 -306.661446) (xy 419.15629 -306.705023)
			(xy 419.171874 -306.751704) (xy 419.179769 -306.800281) (xy 419.180264 -306.824888) (xy 419.519112 -306.824888)
			(xy 419.523072 -306.775834) (xy 419.534849 -306.72805) (xy 419.55414 -306.682774) (xy 419.580443 -306.641178)
			(xy 419.613078 -306.604341) (xy 419.651199 -306.573216) (xy 419.69382 -306.548609) (xy 419.739836 -306.531157)
			(xy 419.788055 -306.521313) (xy 419.83723 -306.519332) (xy 419.886085 -306.525264) (xy 419.933356 -306.538956)
			(xy 419.977818 -306.560054) (xy 420.018321 -306.58801) (xy 420.053814 -306.622102) (xy 420.083379 -306.661446)
			(xy 420.10625 -306.705023) (xy 420.121834 -306.751704) (xy 420.129729 -306.800281) (xy 420.130224 -306.824888)
			(xy 420.469072 -306.824888) (xy 420.473032 -306.775834) (xy 420.484809 -306.72805) (xy 420.5041 -306.682774)
			(xy 420.530403 -306.641178) (xy 420.563038 -306.604341) (xy 420.601159 -306.573216) (xy 420.64378 -306.548609)
			(xy 420.689796 -306.531157) (xy 420.738015 -306.521313) (xy 420.78719 -306.519332) (xy 420.836045 -306.525264)
			(xy 420.883316 -306.538956) (xy 420.927778 -306.560054) (xy 420.968281 -306.58801) (xy 421.003774 -306.622102)
			(xy 421.033339 -306.661446) (xy 421.05621 -306.705023) (xy 421.071794 -306.751704) (xy 421.079689 -306.800281)
			(xy 421.080184 -306.824888) (xy 421.419032 -306.824888) (xy 421.422992 -306.775834) (xy 421.434769 -306.72805)
			(xy 421.45406 -306.682774) (xy 421.480363 -306.641178) (xy 421.512998 -306.604341) (xy 421.551119 -306.573216)
			(xy 421.59374 -306.548609) (xy 421.639756 -306.531157) (xy 421.687975 -306.521313) (xy 421.73715 -306.519332)
			(xy 421.786005 -306.525264) (xy 421.833276 -306.538956) (xy 421.877738 -306.560054) (xy 421.918241 -306.58801)
			(xy 421.953734 -306.622102) (xy 421.983299 -306.661446) (xy 422.00617 -306.705023) (xy 422.021754 -306.751704)
			(xy 422.029649 -306.800281) (xy 422.030144 -306.824888) (xy 422.029649 -306.849495) (xy 422.021754 -306.898072)
			(xy 422.00617 -306.944753) (xy 421.983299 -306.98833) (xy 421.953734 -307.027674) (xy 421.918241 -307.061766)
			(xy 421.877738 -307.089722) (xy 421.833276 -307.11082) (xy 421.786005 -307.124512) (xy 421.73715 -307.130444)
			(xy 421.687975 -307.128463) (xy 421.639756 -307.118619) (xy 421.59374 -307.101167) (xy 421.551119 -307.07656)
			(xy 421.512998 -307.045435) (xy 421.480363 -307.008598) (xy 421.45406 -306.967002) (xy 421.434769 -306.921726)
			(xy 421.422992 -306.873942) (xy 421.419032 -306.824888) (xy 421.080184 -306.824888) (xy 421.079689 -306.849495)
			(xy 421.071794 -306.898072) (xy 421.05621 -306.944753) (xy 421.033339 -306.98833) (xy 421.003774 -307.027674)
			(xy 420.968281 -307.061766) (xy 420.927778 -307.089722) (xy 420.883316 -307.11082) (xy 420.836045 -307.124512)
			(xy 420.78719 -307.130444) (xy 420.738015 -307.128463) (xy 420.689796 -307.118619) (xy 420.64378 -307.101167)
			(xy 420.601159 -307.07656) (xy 420.563038 -307.045435) (xy 420.530403 -307.008598) (xy 420.5041 -306.967002)
			(xy 420.484809 -306.921726) (xy 420.473032 -306.873942) (xy 420.469072 -306.824888) (xy 420.130224 -306.824888)
			(xy 420.129729 -306.849495) (xy 420.121834 -306.898072) (xy 420.10625 -306.944753) (xy 420.083379 -306.98833)
			(xy 420.053814 -307.027674) (xy 420.018321 -307.061766) (xy 419.977818 -307.089722) (xy 419.933356 -307.11082)
			(xy 419.886085 -307.124512) (xy 419.83723 -307.130444) (xy 419.788055 -307.128463) (xy 419.739836 -307.118619)
			(xy 419.69382 -307.101167) (xy 419.651199 -307.07656) (xy 419.613078 -307.045435) (xy 419.580443 -307.008598)
			(xy 419.55414 -306.967002) (xy 419.534849 -306.921726) (xy 419.523072 -306.873942) (xy 419.519112 -306.824888)
			(xy 419.180264 -306.824888) (xy 419.179769 -306.849495) (xy 419.171874 -306.898072) (xy 419.15629 -306.944753)
			(xy 419.133419 -306.98833) (xy 419.103854 -307.027674) (xy 419.068361 -307.061766) (xy 419.027858 -307.089722)
			(xy 418.983396 -307.11082) (xy 418.936125 -307.124512) (xy 418.88727 -307.130444) (xy 418.838095 -307.128463)
			(xy 418.789876 -307.118619) (xy 418.74386 -307.101167) (xy 418.701239 -307.07656) (xy 418.663118 -307.045435)
			(xy 418.630483 -307.008598) (xy 418.60418 -306.967002) (xy 418.584889 -306.921726) (xy 418.573112 -306.873942)
			(xy 418.569152 -306.824888) (xy 418.230304 -306.824888) (xy 418.229809 -306.849495) (xy 418.221914 -306.898072)
			(xy 418.20633 -306.944753) (xy 418.183459 -306.98833) (xy 418.153894 -307.027674) (xy 418.118401 -307.061766)
			(xy 418.077898 -307.089722) (xy 418.033436 -307.11082) (xy 417.986165 -307.124512) (xy 417.93731 -307.130444)
			(xy 417.888135 -307.128463) (xy 417.839916 -307.118619) (xy 417.7939 -307.101167) (xy 417.751279 -307.07656)
			(xy 417.713158 -307.045435) (xy 417.680523 -307.008598) (xy 417.65422 -306.967002) (xy 417.634929 -306.921726)
			(xy 417.623152 -306.873942) (xy 417.619192 -306.824888) (xy 417.28009 -306.824888) (xy 417.279595 -306.849495)
			(xy 417.2717 -306.898072) (xy 417.256116 -306.944753) (xy 417.233245 -306.98833) (xy 417.20368 -307.027674)
			(xy 417.168187 -307.061766) (xy 417.127684 -307.089722) (xy 417.083222 -307.11082) (xy 417.035951 -307.124512)
			(xy 416.987096 -307.130444) (xy 416.937921 -307.128463) (xy 416.889702 -307.118619) (xy 416.843686 -307.101167)
			(xy 416.801065 -307.07656) (xy 416.762944 -307.045435) (xy 416.730309 -307.008598) (xy 416.704006 -306.967002)
			(xy 416.684715 -306.921726) (xy 416.672938 -306.873942) (xy 416.668978 -306.824888) (xy 416.33013 -306.824888)
			(xy 416.329635 -306.849495) (xy 416.32174 -306.898072) (xy 416.306156 -306.944753) (xy 416.283285 -306.98833)
			(xy 416.25372 -307.027674) (xy 416.218227 -307.061766) (xy 416.177724 -307.089722) (xy 416.133262 -307.11082)
			(xy 416.085991 -307.124512) (xy 416.037136 -307.130444) (xy 415.987961 -307.128463) (xy 415.939742 -307.118619)
			(xy 415.893726 -307.101167) (xy 415.851105 -307.07656) (xy 415.812984 -307.045435) (xy 415.780349 -307.008598)
			(xy 415.754046 -306.967002) (xy 415.734755 -306.921726) (xy 415.722978 -306.873942) (xy 415.719018 -306.824888)
			(xy 415.38017 -306.824888) (xy 415.379675 -306.849495) (xy 415.37178 -306.898072) (xy 415.356196 -306.944753)
			(xy 415.333325 -306.98833) (xy 415.30376 -307.027674) (xy 415.268267 -307.061766) (xy 415.227764 -307.089722)
			(xy 415.183302 -307.11082) (xy 415.136031 -307.124512) (xy 415.087176 -307.130444) (xy 415.038001 -307.128463)
			(xy 414.989782 -307.118619) (xy 414.943766 -307.101167) (xy 414.901145 -307.07656) (xy 414.863024 -307.045435)
			(xy 414.830389 -307.008598) (xy 414.804086 -306.967002) (xy 414.784795 -306.921726) (xy 414.773018 -306.873942)
			(xy 414.769058 -306.824888) (xy 414.43021 -306.824888) (xy 414.429715 -306.849495) (xy 414.42182 -306.898072)
			(xy 414.406236 -306.944753) (xy 414.383365 -306.98833) (xy 414.3538 -307.027674) (xy 414.318307 -307.061766)
			(xy 414.277804 -307.089722) (xy 414.233342 -307.11082) (xy 414.186071 -307.124512) (xy 414.137216 -307.130444)
			(xy 414.088041 -307.128463) (xy 414.039822 -307.118619) (xy 413.993806 -307.101167) (xy 413.951185 -307.07656)
			(xy 413.913064 -307.045435) (xy 413.880429 -307.008598) (xy 413.854126 -306.967002) (xy 413.834835 -306.921726)
			(xy 413.823058 -306.873942) (xy 413.819098 -306.824888) (xy 413.48025 -306.824888) (xy 413.479755 -306.849495)
			(xy 413.47186 -306.898072) (xy 413.456276 -306.944753) (xy 413.433405 -306.98833) (xy 413.40384 -307.027674)
			(xy 413.368347 -307.061766) (xy 413.327844 -307.089722) (xy 413.283382 -307.11082) (xy 413.236111 -307.124512)
			(xy 413.187256 -307.130444) (xy 413.138081 -307.128463) (xy 413.089862 -307.118619) (xy 413.043846 -307.101167)
			(xy 413.001225 -307.07656) (xy 412.963104 -307.045435) (xy 412.930469 -307.008598) (xy 412.904166 -306.967002)
			(xy 412.884875 -306.921726) (xy 412.873098 -306.873942) (xy 412.869138 -306.824888) (xy 412.53029 -306.824888)
			(xy 412.529795 -306.849495) (xy 412.5219 -306.898072) (xy 412.506316 -306.944753) (xy 412.483445 -306.98833)
			(xy 412.45388 -307.027674) (xy 412.418387 -307.061766) (xy 412.377884 -307.089722) (xy 412.333422 -307.11082)
			(xy 412.286151 -307.124512) (xy 412.237296 -307.130444) (xy 412.188121 -307.128463) (xy 412.139902 -307.118619)
			(xy 412.093886 -307.101167) (xy 412.051265 -307.07656) (xy 412.013144 -307.045435) (xy 411.980509 -307.008598)
			(xy 411.954206 -306.967002) (xy 411.934915 -306.921726) (xy 411.923138 -306.873942) (xy 411.919178 -306.824888)
			(xy 411.58033 -306.824888) (xy 411.579835 -306.849495) (xy 411.57194 -306.898072) (xy 411.556356 -306.944753)
			(xy 411.533485 -306.98833) (xy 411.50392 -307.027674) (xy 411.468427 -307.061766) (xy 411.427924 -307.089722)
			(xy 411.383462 -307.11082) (xy 411.336191 -307.124512) (xy 411.287336 -307.130444) (xy 411.238161 -307.128463)
			(xy 411.189942 -307.118619) (xy 411.143926 -307.101167) (xy 411.101305 -307.07656) (xy 411.063184 -307.045435)
			(xy 411.030549 -307.008598) (xy 411.004246 -306.967002) (xy 410.984955 -306.921726) (xy 410.973178 -306.873942)
			(xy 410.969218 -306.824888) (xy 410.630116 -306.824888) (xy 410.629621 -306.849495) (xy 410.621726 -306.898072)
			(xy 410.606142 -306.944753) (xy 410.583271 -306.98833) (xy 410.553706 -307.027674) (xy 410.518213 -307.061766)
			(xy 410.47771 -307.089722) (xy 410.433248 -307.11082) (xy 410.385977 -307.124512) (xy 410.337122 -307.130444)
			(xy 410.287947 -307.128463) (xy 410.239728 -307.118619) (xy 410.193712 -307.101167) (xy 410.151091 -307.07656)
			(xy 410.11297 -307.045435) (xy 410.080335 -307.008598) (xy 410.054032 -306.967002) (xy 410.034741 -306.921726)
			(xy 410.022964 -306.873942) (xy 410.019004 -306.824888) (xy 409.680156 -306.824888) (xy 409.679661 -306.849495)
			(xy 409.671766 -306.898072) (xy 409.656182 -306.944753) (xy 409.633311 -306.98833) (xy 409.603746 -307.027674)
			(xy 409.568253 -307.061766) (xy 409.52775 -307.089722) (xy 409.483288 -307.11082) (xy 409.436017 -307.124512)
			(xy 409.387162 -307.130444) (xy 409.337987 -307.128463) (xy 409.289768 -307.118619) (xy 409.243752 -307.101167)
			(xy 409.201131 -307.07656) (xy 409.16301 -307.045435) (xy 409.130375 -307.008598) (xy 409.104072 -306.967002)
			(xy 409.084781 -306.921726) (xy 409.073004 -306.873942) (xy 409.069044 -306.824888) (xy 408.730196 -306.824888)
			(xy 408.729701 -306.849495) (xy 408.721806 -306.898072) (xy 408.706222 -306.944753) (xy 408.683351 -306.98833)
			(xy 408.653786 -307.027674) (xy 408.618293 -307.061766) (xy 408.57779 -307.089722) (xy 408.533328 -307.11082)
			(xy 408.486057 -307.124512) (xy 408.437202 -307.130444) (xy 408.388027 -307.128463) (xy 408.339808 -307.118619)
			(xy 408.293792 -307.101167) (xy 408.251171 -307.07656) (xy 408.21305 -307.045435) (xy 408.180415 -307.008598)
			(xy 408.154112 -306.967002) (xy 408.134821 -306.921726) (xy 408.123044 -306.873942) (xy 408.119084 -306.824888)
			(xy 406.830276 -306.824888) (xy 406.829781 -306.849495) (xy 406.821886 -306.898072) (xy 406.806302 -306.944753)
			(xy 406.783431 -306.98833) (xy 406.753866 -307.027674) (xy 406.718373 -307.061766) (xy 406.67787 -307.089722)
			(xy 406.633408 -307.11082) (xy 406.586137 -307.124512) (xy 406.537282 -307.130444) (xy 406.488107 -307.128463)
			(xy 406.439888 -307.118619) (xy 406.393872 -307.101167) (xy 406.351251 -307.07656) (xy 406.31313 -307.045435)
			(xy 406.280495 -307.008598) (xy 406.254192 -306.967002) (xy 406.234901 -306.921726) (xy 406.223124 -306.873942)
			(xy 406.219164 -306.824888) (xy 405.880316 -306.824888) (xy 405.879821 -306.849495) (xy 405.871926 -306.898072)
			(xy 405.856342 -306.944753) (xy 405.833471 -306.98833) (xy 405.803906 -307.027674) (xy 405.768413 -307.061766)
			(xy 405.72791 -307.089722) (xy 405.683448 -307.11082) (xy 405.636177 -307.124512) (xy 405.587322 -307.130444)
			(xy 405.538147 -307.128463) (xy 405.489928 -307.118619) (xy 405.443912 -307.101167) (xy 405.401291 -307.07656)
			(xy 405.36317 -307.045435) (xy 405.330535 -307.008598) (xy 405.304232 -306.967002) (xy 405.284941 -306.921726)
			(xy 405.273164 -306.873942) (xy 405.269204 -306.824888) (xy 404.930102 -306.824888) (xy 404.929607 -306.849495)
			(xy 404.921712 -306.898072) (xy 404.906128 -306.944753) (xy 404.883257 -306.98833) (xy 404.853692 -307.027674)
			(xy 404.818199 -307.061766) (xy 404.777696 -307.089722) (xy 404.733234 -307.11082) (xy 404.685963 -307.124512)
			(xy 404.637108 -307.130444) (xy 404.587933 -307.128463) (xy 404.539714 -307.118619) (xy 404.493698 -307.101167)
			(xy 404.451077 -307.07656) (xy 404.412956 -307.045435) (xy 404.380321 -307.008598) (xy 404.354018 -306.967002)
			(xy 404.334727 -306.921726) (xy 404.32295 -306.873942) (xy 404.31899 -306.824888) (xy 403.980142 -306.824888)
			(xy 403.979647 -306.849495) (xy 403.971752 -306.898072) (xy 403.956168 -306.944753) (xy 403.933297 -306.98833)
			(xy 403.903732 -307.027674) (xy 403.868239 -307.061766) (xy 403.827736 -307.089722) (xy 403.783274 -307.11082)
			(xy 403.736003 -307.124512) (xy 403.687148 -307.130444) (xy 403.637973 -307.128463) (xy 403.589754 -307.118619)
			(xy 403.543738 -307.101167) (xy 403.501117 -307.07656) (xy 403.462996 -307.045435) (xy 403.430361 -307.008598)
			(xy 403.404058 -306.967002) (xy 403.384767 -306.921726) (xy 403.37299 -306.873942) (xy 403.36903 -306.824888)
			(xy 403.030182 -306.824888) (xy 403.029687 -306.849495) (xy 403.021792 -306.898072) (xy 403.006208 -306.944753)
			(xy 402.983337 -306.98833) (xy 402.953772 -307.027674) (xy 402.918279 -307.061766) (xy 402.877776 -307.089722)
			(xy 402.833314 -307.11082) (xy 402.786043 -307.124512) (xy 402.737188 -307.130444) (xy 402.688013 -307.128463)
			(xy 402.639794 -307.118619) (xy 402.593778 -307.101167) (xy 402.551157 -307.07656) (xy 402.513036 -307.045435)
			(xy 402.480401 -307.008598) (xy 402.454098 -306.967002) (xy 402.434807 -306.921726) (xy 402.42303 -306.873942)
			(xy 402.41907 -306.824888) (xy 402.080222 -306.824888) (xy 402.079727 -306.849495) (xy 402.071832 -306.898072)
			(xy 402.056248 -306.944753) (xy 402.033377 -306.98833) (xy 402.003812 -307.027674) (xy 401.968319 -307.061766)
			(xy 401.927816 -307.089722) (xy 401.883354 -307.11082) (xy 401.836083 -307.124512) (xy 401.787228 -307.130444)
			(xy 401.738053 -307.128463) (xy 401.689834 -307.118619) (xy 401.643818 -307.101167) (xy 401.601197 -307.07656)
			(xy 401.563076 -307.045435) (xy 401.530441 -307.008598) (xy 401.504138 -306.967002) (xy 401.484847 -306.921726)
			(xy 401.47307 -306.873942) (xy 401.46911 -306.824888) (xy 401.130262 -306.824888) (xy 401.129767 -306.849495)
			(xy 401.121872 -306.898072) (xy 401.106288 -306.944753) (xy 401.083417 -306.98833) (xy 401.053852 -307.027674)
			(xy 401.018359 -307.061766) (xy 400.977856 -307.089722) (xy 400.933394 -307.11082) (xy 400.886123 -307.124512)
			(xy 400.837268 -307.130444) (xy 400.788093 -307.128463) (xy 400.739874 -307.118619) (xy 400.693858 -307.101167)
			(xy 400.651237 -307.07656) (xy 400.613116 -307.045435) (xy 400.580481 -307.008598) (xy 400.554178 -306.967002)
			(xy 400.534887 -306.921726) (xy 400.52311 -306.873942) (xy 400.51915 -306.824888) (xy 400.180302 -306.824888)
			(xy 400.179807 -306.849495) (xy 400.171912 -306.898072) (xy 400.156328 -306.944753) (xy 400.133457 -306.98833)
			(xy 400.103892 -307.027674) (xy 400.068399 -307.061766) (xy 400.027896 -307.089722) (xy 399.983434 -307.11082)
			(xy 399.936163 -307.124512) (xy 399.887308 -307.130444) (xy 399.838133 -307.128463) (xy 399.789914 -307.118619)
			(xy 399.743898 -307.101167) (xy 399.701277 -307.07656) (xy 399.663156 -307.045435) (xy 399.630521 -307.008598)
			(xy 399.604218 -306.967002) (xy 399.584927 -306.921726) (xy 399.57315 -306.873942) (xy 399.56919 -306.824888)
			(xy 399.230342 -306.824888) (xy 399.229847 -306.849495) (xy 399.221952 -306.898072) (xy 399.206368 -306.944753)
			(xy 399.183497 -306.98833) (xy 399.153932 -307.027674) (xy 399.118439 -307.061766) (xy 399.077936 -307.089722)
			(xy 399.033474 -307.11082) (xy 398.986203 -307.124512) (xy 398.937348 -307.130444) (xy 398.888173 -307.128463)
			(xy 398.839954 -307.118619) (xy 398.793938 -307.101167) (xy 398.751317 -307.07656) (xy 398.713196 -307.045435)
			(xy 398.680561 -307.008598) (xy 398.654258 -306.967002) (xy 398.634967 -306.921726) (xy 398.62319 -306.873942)
			(xy 398.61923 -306.824888) (xy 398.317212 -306.824888) (xy 398.317212 -307.299868) (xy 422.844226 -307.299868)
			(xy 422.848186 -307.250814) (xy 422.859963 -307.20303) (xy 422.879254 -307.157754) (xy 422.905557 -307.116158)
			(xy 422.938192 -307.079321) (xy 422.976313 -307.048196) (xy 423.018934 -307.023589) (xy 423.06495 -307.006137)
			(xy 423.113169 -306.996293) (xy 423.162344 -306.994312) (xy 423.211199 -307.000244) (xy 423.25847 -307.013936)
			(xy 423.302932 -307.035034) (xy 423.343435 -307.06299) (xy 423.378928 -307.097082) (xy 423.408493 -307.136426)
			(xy 423.431364 -307.180003) (xy 423.446948 -307.226684) (xy 423.454843 -307.275261) (xy 423.455338 -307.299868)
			(xy 423.794186 -307.299868) (xy 423.798146 -307.250814) (xy 423.809923 -307.20303) (xy 423.829214 -307.157754)
			(xy 423.855517 -307.116158) (xy 423.888152 -307.079321) (xy 423.926273 -307.048196) (xy 423.968894 -307.023589)
			(xy 424.01491 -307.006137) (xy 424.063129 -306.996293) (xy 424.112304 -306.994312) (xy 424.161159 -307.000244)
			(xy 424.20843 -307.013936) (xy 424.252892 -307.035034) (xy 424.293395 -307.06299) (xy 424.328888 -307.097082)
			(xy 424.358453 -307.136426) (xy 424.381324 -307.180003) (xy 424.396908 -307.226684) (xy 424.404803 -307.275261)
			(xy 424.405298 -307.299868) (xy 424.404803 -307.324475) (xy 424.404624 -307.325576) (xy 424.723302 -307.325576)
			(xy 424.723302 -307.27416) (xy 424.731345 -307.223378) (xy 424.747233 -307.174479) (xy 424.770576 -307.128667)
			(xy 424.800797 -307.087071) (xy 424.837153 -307.050715) (xy 424.878749 -307.020494) (xy 424.924561 -306.997151)
			(xy 424.97346 -306.981263) (xy 425.024242 -306.97322) (xy 425.075658 -306.97322) (xy 425.12644 -306.981263)
			(xy 425.175339 -306.997151) (xy 425.221151 -307.020494) (xy 425.262747 -307.050715) (xy 425.299103 -307.087071)
			(xy 425.329324 -307.128667) (xy 425.352667 -307.174479) (xy 425.368555 -307.223378) (xy 425.376598 -307.27416)
			(xy 425.377102 -307.299868) (xy 425.376598 -307.325576) (xy 425.673262 -307.325576) (xy 425.673262 -307.27416)
			(xy 425.681305 -307.223378) (xy 425.697193 -307.174479) (xy 425.720536 -307.128667) (xy 425.750757 -307.087071)
			(xy 425.787113 -307.050715) (xy 425.828709 -307.020494) (xy 425.874521 -306.997151) (xy 425.92342 -306.981263)
			(xy 425.974202 -306.97322) (xy 426.025618 -306.97322) (xy 426.0764 -306.981263) (xy 426.125299 -306.997151)
			(xy 426.171111 -307.020494) (xy 426.212707 -307.050715) (xy 426.249063 -307.087071) (xy 426.279284 -307.128667)
			(xy 426.302627 -307.174479) (xy 426.318515 -307.223378) (xy 426.326558 -307.27416) (xy 426.327062 -307.299868)
			(xy 426.644066 -307.299868) (xy 426.648026 -307.250814) (xy 426.659803 -307.20303) (xy 426.679094 -307.157754)
			(xy 426.705397 -307.116158) (xy 426.738032 -307.079321) (xy 426.776153 -307.048196) (xy 426.818774 -307.023589)
			(xy 426.86479 -307.006137) (xy 426.913009 -306.996293) (xy 426.962184 -306.994312) (xy 427.011039 -307.000244)
			(xy 427.05831 -307.013936) (xy 427.102772 -307.035034) (xy 427.143275 -307.06299) (xy 427.178768 -307.097082)
			(xy 427.208333 -307.136426) (xy 427.231204 -307.180003) (xy 427.246788 -307.226684) (xy 427.254683 -307.275261)
			(xy 427.255178 -307.299868) (xy 427.254683 -307.324475) (xy 427.254504 -307.325576) (xy 427.573182 -307.325576)
			(xy 427.573182 -307.27416) (xy 427.581225 -307.223378) (xy 427.597113 -307.174479) (xy 427.620456 -307.128667)
			(xy 427.650677 -307.087071) (xy 427.687033 -307.050715) (xy 427.728629 -307.020494) (xy 427.774441 -306.997151)
			(xy 427.82334 -306.981263) (xy 427.874122 -306.97322) (xy 427.925538 -306.97322) (xy 427.97632 -306.981263)
			(xy 428.025219 -306.997151) (xy 428.071031 -307.020494) (xy 428.112627 -307.050715) (xy 428.148983 -307.087071)
			(xy 428.179204 -307.128667) (xy 428.202547 -307.174479) (xy 428.218435 -307.223378) (xy 428.226478 -307.27416)
			(xy 428.226982 -307.299868) (xy 428.226478 -307.325576) (xy 428.523142 -307.325576) (xy 428.523142 -307.27416)
			(xy 428.531185 -307.223378) (xy 428.547073 -307.174479) (xy 428.570416 -307.128667) (xy 428.600637 -307.087071)
			(xy 428.636993 -307.050715) (xy 428.678589 -307.020494) (xy 428.724401 -306.997151) (xy 428.7733 -306.981263)
			(xy 428.824082 -306.97322) (xy 428.875498 -306.97322) (xy 428.92628 -306.981263) (xy 428.975179 -306.997151)
			(xy 429.020991 -307.020494) (xy 429.062587 -307.050715) (xy 429.098943 -307.087071) (xy 429.129164 -307.128667)
			(xy 429.152507 -307.174479) (xy 429.168395 -307.223378) (xy 429.176438 -307.27416) (xy 429.176942 -307.299868)
			(xy 429.4942 -307.299868) (xy 429.49816 -307.250814) (xy 429.509937 -307.20303) (xy 429.529228 -307.157754)
			(xy 429.555531 -307.116158) (xy 429.588166 -307.079321) (xy 429.626287 -307.048196) (xy 429.668908 -307.023589)
			(xy 429.714924 -307.006137) (xy 429.763143 -306.996293) (xy 429.812318 -306.994312) (xy 429.861173 -307.000244)
			(xy 429.908444 -307.013936) (xy 429.952906 -307.035034) (xy 429.993409 -307.06299) (xy 430.028902 -307.097082)
			(xy 430.058467 -307.136426) (xy 430.081338 -307.180003) (xy 430.096922 -307.226684) (xy 430.104817 -307.275261)
			(xy 430.105312 -307.299868) (xy 430.44416 -307.299868) (xy 430.44812 -307.250814) (xy 430.459897 -307.20303)
			(xy 430.479188 -307.157754) (xy 430.505491 -307.116158) (xy 430.538126 -307.079321) (xy 430.576247 -307.048196)
			(xy 430.618868 -307.023589) (xy 430.664884 -307.006137) (xy 430.713103 -306.996293) (xy 430.762278 -306.994312)
			(xy 430.811133 -307.000244) (xy 430.858404 -307.013936) (xy 430.902866 -307.035034) (xy 430.943369 -307.06299)
			(xy 430.978862 -307.097082) (xy 431.008427 -307.136426) (xy 431.031298 -307.180003) (xy 431.046882 -307.226684)
			(xy 431.054777 -307.275261) (xy 431.055272 -307.299868) (xy 431.054777 -307.324475) (xy 431.053008 -307.33536)
			(xy 439.450128 -307.33536) (xy 439.457883 -307.281404) (xy 439.473239 -307.229101) (xy 439.495882 -307.179516)
			(xy 439.525351 -307.133658) (xy 439.561047 -307.092461) (xy 439.602242 -307.056763) (xy 439.648098 -307.027291)
			(xy 439.697682 -307.004646) (xy 439.749985 -306.989288) (xy 439.80394 -306.981529) (xy 439.858451 -306.981529)
			(xy 439.912406 -306.989286) (xy 439.964709 -307.004643) (xy 440.014293 -307.027287) (xy 440.06015 -307.056757)
			(xy 440.091847 -307.084222) (xy 441.014356 -307.084222) (xy 441.018427 -307.0286) (xy 441.030553 -306.974163)
			(xy 441.050476 -306.922072) (xy 441.077772 -306.873437) (xy 441.111858 -306.829294) (xy 441.152007 -306.790585)
			(xy 441.197365 -306.758134) (xy 441.246965 -306.732633) (xy 441.299749 -306.714626) (xy 441.354592 -306.704496)
			(xy 441.410326 -306.702459) (xy 441.465763 -306.708559) (xy 441.51972 -306.722665) (xy 441.571049 -306.744477)
			(xy 441.618655 -306.773531) (xy 441.661523 -306.809206) (xy 441.69874 -306.850743) (xy 441.729513 -306.897256)
			(xy 441.753185 -306.947753) (xy 441.769253 -307.00116) (xy 441.777373 -307.056336) (xy 441.777882 -307.084222)
			(xy 441.777373 -307.112108) (xy 441.769253 -307.167284) (xy 441.753185 -307.220691) (xy 441.729513 -307.271188)
			(xy 441.69874 -307.317701) (xy 441.661523 -307.359238) (xy 441.618655 -307.394913) (xy 441.571049 -307.423967)
			(xy 441.51972 -307.445779) (xy 441.465763 -307.459885) (xy 441.410326 -307.465985) (xy 441.354592 -307.463948)
			(xy 441.299749 -307.453818) (xy 441.246965 -307.435811) (xy 441.197365 -307.41031) (xy 441.152007 -307.377859)
			(xy 441.111858 -307.33915) (xy 441.077772 -307.295007) (xy 441.050476 -307.246372) (xy 441.030553 -307.194281)
			(xy 441.018427 -307.139844) (xy 441.014356 -307.084222) (xy 440.091847 -307.084222) (xy 440.101347 -307.092454)
			(xy 440.137043 -307.133651) (xy 440.166514 -307.179508) (xy 440.189158 -307.229092) (xy 440.204515 -307.281395)
			(xy 440.212271 -307.335351) (xy 440.212734 -307.362606) (xy 440.210956 -307.399182) (xy 440.20994 -307.410612)
			(xy 440.21756 -307.431694) (xy 440.289188 -307.503322) (xy 440.310524 -307.510942) (xy 440.321954 -307.509926)
			(xy 440.35853 -307.508148) (xy 440.38578 -307.50865) (xy 440.439725 -307.516409) (xy 440.492017 -307.531766)
			(xy 440.541591 -307.554407) (xy 440.587439 -307.583873) (xy 440.628628 -307.619562) (xy 440.664319 -307.66075)
			(xy 440.693786 -307.706597) (xy 440.716429 -307.75617) (xy 440.731788 -307.808461) (xy 440.739549 -307.862406)
			(xy 440.740038 -307.889656) (xy 440.739682 -307.912162) (xy 440.734339 -307.956856) (xy 440.72937 -307.97881)
			(xy 440.726322 -307.992018) (xy 440.733434 -308.017164) (xy 440.813698 -308.097428) (xy 440.838844 -308.10454)
			(xy 440.852052 -308.101492) (xy 440.874008 -308.096534) (xy 440.918701 -308.091184) (xy 440.941206 -308.090824)
			(xy 440.968456 -308.091284) (xy 441.022402 -308.099041) (xy 441.074695 -308.114396) (xy 441.12427 -308.137037)
			(xy 441.170118 -308.166502) (xy 441.211307 -308.202192) (xy 441.246997 -308.243381) (xy 441.276463 -308.28923)
			(xy 441.299104 -308.338805) (xy 441.314459 -308.391097) (xy 441.322216 -308.445043) (xy 441.322217 -308.499544)
			(xy 441.314462 -308.553489) (xy 441.299108 -308.605783) (xy 441.276469 -308.655359) (xy 441.247005 -308.701208)
			(xy 441.211317 -308.742398) (xy 441.170129 -308.77809) (xy 441.124282 -308.807557) (xy 441.074707 -308.830199)
			(xy 441.022415 -308.845556) (xy 440.96847 -308.853315) (xy 440.913969 -308.853318) (xy 440.860023 -308.845564)
			(xy 440.807729 -308.830213) (xy 440.758152 -308.807575) (xy 440.712302 -308.778113) (xy 440.671111 -308.742426)
			(xy 440.635418 -308.701239) (xy 440.605949 -308.655393) (xy 440.583305 -308.605819) (xy 440.567947 -308.553527)
			(xy 440.560186 -308.499582) (xy 440.559698 -308.472332) (xy 440.560053 -308.449826) (xy 440.565397 -308.405132)
			(xy 440.570366 -308.383178) (xy 440.573414 -308.36997) (xy 440.566302 -308.344824) (xy 440.486038 -308.26456)
			(xy 440.460892 -308.257448) (xy 440.447684 -308.260496) (xy 440.425731 -308.265464) (xy 440.381036 -308.270807)
			(xy 440.35853 -308.271164) (xy 440.331276 -308.270717) (xy 440.277322 -308.262963) (xy 440.225021 -308.247608)
			(xy 440.175438 -308.224966) (xy 440.129583 -308.195497) (xy 440.088389 -308.159801) (xy 440.052695 -308.118606)
			(xy 440.023227 -308.072749) (xy 440.000587 -308.023166) (xy 439.985234 -307.970864) (xy 439.977482 -307.91691)
			(xy 439.977022 -307.889656) (xy 439.9788 -307.85308) (xy 439.979816 -307.84165) (xy 439.972196 -307.820568)
			(xy 439.900568 -307.74894) (xy 439.879232 -307.74132) (xy 439.867802 -307.742336) (xy 439.831226 -307.744114)
			(xy 439.803971 -307.743673) (xy 439.750015 -307.735919) (xy 439.697711 -307.720565) (xy 439.648125 -307.697923)
			(xy 439.602267 -307.668455) (xy 439.561068 -307.632761) (xy 439.525369 -307.591567) (xy 439.495897 -307.545711)
			(xy 439.47325 -307.496128) (xy 439.45789 -307.443826) (xy 439.45013 -307.389871) (xy 439.450128 -307.33536)
			(xy 431.053008 -307.33536) (xy 431.046882 -307.373052) (xy 431.031298 -307.419733) (xy 431.008427 -307.46331)
			(xy 430.978862 -307.502654) (xy 430.943369 -307.536746) (xy 430.902866 -307.564702) (xy 430.858404 -307.5858)
			(xy 430.811133 -307.599492) (xy 430.762278 -307.605424) (xy 430.713103 -307.603443) (xy 430.664884 -307.593599)
			(xy 430.618868 -307.576147) (xy 430.576247 -307.55154) (xy 430.538126 -307.520415) (xy 430.505491 -307.483578)
			(xy 430.479188 -307.441982) (xy 430.459897 -307.396706) (xy 430.44812 -307.348922) (xy 430.44416 -307.299868)
			(xy 430.105312 -307.299868) (xy 430.104817 -307.324475) (xy 430.096922 -307.373052) (xy 430.081338 -307.419733)
			(xy 430.058467 -307.46331) (xy 430.028902 -307.502654) (xy 429.993409 -307.536746) (xy 429.952906 -307.564702)
			(xy 429.908444 -307.5858) (xy 429.861173 -307.599492) (xy 429.812318 -307.605424) (xy 429.763143 -307.603443)
			(xy 429.714924 -307.593599) (xy 429.668908 -307.576147) (xy 429.626287 -307.55154) (xy 429.588166 -307.520415)
			(xy 429.555531 -307.483578) (xy 429.529228 -307.441982) (xy 429.509937 -307.396706) (xy 429.49816 -307.348922)
			(xy 429.4942 -307.299868) (xy 429.176942 -307.299868) (xy 429.176438 -307.325576) (xy 429.168395 -307.376358)
			(xy 429.152507 -307.425257) (xy 429.129164 -307.471069) (xy 429.098943 -307.512665) (xy 429.062587 -307.549021)
			(xy 429.020991 -307.579242) (xy 428.975179 -307.602585) (xy 428.92628 -307.618473) (xy 428.875498 -307.626516)
			(xy 428.824082 -307.626516) (xy 428.7733 -307.618473) (xy 428.724401 -307.602585) (xy 428.678589 -307.579242)
			(xy 428.636993 -307.549021) (xy 428.600637 -307.512665) (xy 428.570416 -307.471069) (xy 428.547073 -307.425257)
			(xy 428.531185 -307.376358) (xy 428.523142 -307.325576) (xy 428.226478 -307.325576) (xy 428.218435 -307.376358)
			(xy 428.202547 -307.425257) (xy 428.179204 -307.471069) (xy 428.148983 -307.512665) (xy 428.112627 -307.549021)
			(xy 428.071031 -307.579242) (xy 428.025219 -307.602585) (xy 427.97632 -307.618473) (xy 427.925538 -307.626516)
			(xy 427.874122 -307.626516) (xy 427.82334 -307.618473) (xy 427.774441 -307.602585) (xy 427.728629 -307.579242)
			(xy 427.687033 -307.549021) (xy 427.650677 -307.512665) (xy 427.620456 -307.471069) (xy 427.597113 -307.425257)
			(xy 427.581225 -307.376358) (xy 427.573182 -307.325576) (xy 427.254504 -307.325576) (xy 427.246788 -307.373052)
			(xy 427.231204 -307.419733) (xy 427.208333 -307.46331) (xy 427.178768 -307.502654) (xy 427.143275 -307.536746)
			(xy 427.102772 -307.564702) (xy 427.05831 -307.5858) (xy 427.011039 -307.599492) (xy 426.962184 -307.605424)
			(xy 426.913009 -307.603443) (xy 426.86479 -307.593599) (xy 426.818774 -307.576147) (xy 426.776153 -307.55154)
			(xy 426.738032 -307.520415) (xy 426.705397 -307.483578) (xy 426.679094 -307.441982) (xy 426.659803 -307.396706)
			(xy 426.648026 -307.348922) (xy 426.644066 -307.299868) (xy 426.327062 -307.299868) (xy 426.326558 -307.325576)
			(xy 426.318515 -307.376358) (xy 426.302627 -307.425257) (xy 426.279284 -307.471069) (xy 426.249063 -307.512665)
			(xy 426.212707 -307.549021) (xy 426.171111 -307.579242) (xy 426.125299 -307.602585) (xy 426.0764 -307.618473)
			(xy 426.025618 -307.626516) (xy 425.974202 -307.626516) (xy 425.92342 -307.618473) (xy 425.874521 -307.602585)
			(xy 425.828709 -307.579242) (xy 425.787113 -307.549021) (xy 425.750757 -307.512665) (xy 425.720536 -307.471069)
			(xy 425.697193 -307.425257) (xy 425.681305 -307.376358) (xy 425.673262 -307.325576) (xy 425.376598 -307.325576)
			(xy 425.368555 -307.376358) (xy 425.352667 -307.425257) (xy 425.329324 -307.471069) (xy 425.299103 -307.512665)
			(xy 425.262747 -307.549021) (xy 425.221151 -307.579242) (xy 425.175339 -307.602585) (xy 425.12644 -307.618473)
			(xy 425.075658 -307.626516) (xy 425.024242 -307.626516) (xy 424.97346 -307.618473) (xy 424.924561 -307.602585)
			(xy 424.878749 -307.579242) (xy 424.837153 -307.549021) (xy 424.800797 -307.512665) (xy 424.770576 -307.471069)
			(xy 424.747233 -307.425257) (xy 424.731345 -307.376358) (xy 424.723302 -307.325576) (xy 424.404624 -307.325576)
			(xy 424.396908 -307.373052) (xy 424.381324 -307.419733) (xy 424.358453 -307.46331) (xy 424.328888 -307.502654)
			(xy 424.293395 -307.536746) (xy 424.252892 -307.564702) (xy 424.20843 -307.5858) (xy 424.161159 -307.599492)
			(xy 424.112304 -307.605424) (xy 424.063129 -307.603443) (xy 424.01491 -307.593599) (xy 423.968894 -307.576147)
			(xy 423.926273 -307.55154) (xy 423.888152 -307.520415) (xy 423.855517 -307.483578) (xy 423.829214 -307.441982)
			(xy 423.809923 -307.396706) (xy 423.798146 -307.348922) (xy 423.794186 -307.299868) (xy 423.455338 -307.299868)
			(xy 423.454843 -307.324475) (xy 423.446948 -307.373052) (xy 423.431364 -307.419733) (xy 423.408493 -307.46331)
			(xy 423.378928 -307.502654) (xy 423.343435 -307.536746) (xy 423.302932 -307.564702) (xy 423.25847 -307.5858)
			(xy 423.211199 -307.599492) (xy 423.162344 -307.605424) (xy 423.113169 -307.603443) (xy 423.06495 -307.593599)
			(xy 423.018934 -307.576147) (xy 422.976313 -307.55154) (xy 422.938192 -307.520415) (xy 422.905557 -307.483578)
			(xy 422.879254 -307.441982) (xy 422.859963 -307.396706) (xy 422.848186 -307.348922) (xy 422.844226 -307.299868)
			(xy 398.317212 -307.299868) (xy 398.317212 -307.774848) (xy 398.61923 -307.774848) (xy 398.62319 -307.725794)
			(xy 398.634967 -307.67801) (xy 398.654258 -307.632734) (xy 398.680561 -307.591138) (xy 398.713196 -307.554301)
			(xy 398.751317 -307.523176) (xy 398.793938 -307.498569) (xy 398.839954 -307.481117) (xy 398.888173 -307.471273)
			(xy 398.937348 -307.469292) (xy 398.986203 -307.475224) (xy 399.033474 -307.488916) (xy 399.077936 -307.510014)
			(xy 399.118439 -307.53797) (xy 399.153932 -307.572062) (xy 399.183497 -307.611406) (xy 399.206368 -307.654983)
			(xy 399.221952 -307.701664) (xy 399.229847 -307.750241) (xy 399.230342 -307.774848) (xy 399.56919 -307.774848)
			(xy 399.57315 -307.725794) (xy 399.584927 -307.67801) (xy 399.604218 -307.632734) (xy 399.630521 -307.591138)
			(xy 399.663156 -307.554301) (xy 399.701277 -307.523176) (xy 399.743898 -307.498569) (xy 399.789914 -307.481117)
			(xy 399.838133 -307.471273) (xy 399.887308 -307.469292) (xy 399.936163 -307.475224) (xy 399.983434 -307.488916)
			(xy 400.027896 -307.510014) (xy 400.068399 -307.53797) (xy 400.103892 -307.572062) (xy 400.133457 -307.611406)
			(xy 400.156328 -307.654983) (xy 400.171912 -307.701664) (xy 400.179807 -307.750241) (xy 400.180302 -307.774848)
			(xy 400.51915 -307.774848) (xy 400.52311 -307.725794) (xy 400.534887 -307.67801) (xy 400.554178 -307.632734)
			(xy 400.580481 -307.591138) (xy 400.613116 -307.554301) (xy 400.651237 -307.523176) (xy 400.693858 -307.498569)
			(xy 400.739874 -307.481117) (xy 400.788093 -307.471273) (xy 400.837268 -307.469292) (xy 400.886123 -307.475224)
			(xy 400.933394 -307.488916) (xy 400.977856 -307.510014) (xy 401.018359 -307.53797) (xy 401.053852 -307.572062)
			(xy 401.083417 -307.611406) (xy 401.106288 -307.654983) (xy 401.121872 -307.701664) (xy 401.129767 -307.750241)
			(xy 401.130262 -307.774848) (xy 401.46911 -307.774848) (xy 401.47307 -307.725794) (xy 401.484847 -307.67801)
			(xy 401.504138 -307.632734) (xy 401.530441 -307.591138) (xy 401.563076 -307.554301) (xy 401.601197 -307.523176)
			(xy 401.643818 -307.498569) (xy 401.689834 -307.481117) (xy 401.738053 -307.471273) (xy 401.787228 -307.469292)
			(xy 401.836083 -307.475224) (xy 401.883354 -307.488916) (xy 401.927816 -307.510014) (xy 401.968319 -307.53797)
			(xy 402.003812 -307.572062) (xy 402.033377 -307.611406) (xy 402.056248 -307.654983) (xy 402.071832 -307.701664)
			(xy 402.079727 -307.750241) (xy 402.080222 -307.774848) (xy 402.41907 -307.774848) (xy 402.42303 -307.725794)
			(xy 402.434807 -307.67801) (xy 402.454098 -307.632734) (xy 402.480401 -307.591138) (xy 402.513036 -307.554301)
			(xy 402.551157 -307.523176) (xy 402.593778 -307.498569) (xy 402.639794 -307.481117) (xy 402.688013 -307.471273)
			(xy 402.737188 -307.469292) (xy 402.786043 -307.475224) (xy 402.833314 -307.488916) (xy 402.877776 -307.510014)
			(xy 402.918279 -307.53797) (xy 402.953772 -307.572062) (xy 402.983337 -307.611406) (xy 403.006208 -307.654983)
			(xy 403.021792 -307.701664) (xy 403.029687 -307.750241) (xy 403.030182 -307.774848) (xy 403.36903 -307.774848)
			(xy 403.37299 -307.725794) (xy 403.384767 -307.67801) (xy 403.404058 -307.632734) (xy 403.430361 -307.591138)
			(xy 403.462996 -307.554301) (xy 403.501117 -307.523176) (xy 403.543738 -307.498569) (xy 403.589754 -307.481117)
			(xy 403.637973 -307.471273) (xy 403.687148 -307.469292) (xy 403.736003 -307.475224) (xy 403.783274 -307.488916)
			(xy 403.827736 -307.510014) (xy 403.868239 -307.53797) (xy 403.903732 -307.572062) (xy 403.933297 -307.611406)
			(xy 403.956168 -307.654983) (xy 403.971752 -307.701664) (xy 403.979647 -307.750241) (xy 403.980142 -307.774848)
			(xy 404.319244 -307.774848) (xy 404.323204 -307.725794) (xy 404.334981 -307.67801) (xy 404.354272 -307.632734)
			(xy 404.380575 -307.591138) (xy 404.41321 -307.554301) (xy 404.451331 -307.523176) (xy 404.493952 -307.498569)
			(xy 404.539968 -307.481117) (xy 404.588187 -307.471273) (xy 404.637362 -307.469292) (xy 404.686217 -307.475224)
			(xy 404.733488 -307.488916) (xy 404.77795 -307.510014) (xy 404.818453 -307.53797) (xy 404.853946 -307.572062)
			(xy 404.883511 -307.611406) (xy 404.906382 -307.654983) (xy 404.921966 -307.701664) (xy 404.929861 -307.750241)
			(xy 404.930356 -307.774848) (xy 405.269204 -307.774848) (xy 405.273164 -307.725794) (xy 405.284941 -307.67801)
			(xy 405.304232 -307.632734) (xy 405.330535 -307.591138) (xy 405.36317 -307.554301) (xy 405.401291 -307.523176)
			(xy 405.443912 -307.498569) (xy 405.489928 -307.481117) (xy 405.538147 -307.471273) (xy 405.587322 -307.469292)
			(xy 405.636177 -307.475224) (xy 405.683448 -307.488916) (xy 405.72791 -307.510014) (xy 405.768413 -307.53797)
			(xy 405.803906 -307.572062) (xy 405.833471 -307.611406) (xy 405.856342 -307.654983) (xy 405.871926 -307.701664)
			(xy 405.879821 -307.750241) (xy 405.880316 -307.774848) (xy 406.219164 -307.774848) (xy 406.223124 -307.725794)
			(xy 406.234901 -307.67801) (xy 406.254192 -307.632734) (xy 406.280495 -307.591138) (xy 406.31313 -307.554301)
			(xy 406.351251 -307.523176) (xy 406.393872 -307.498569) (xy 406.439888 -307.481117) (xy 406.488107 -307.471273)
			(xy 406.537282 -307.469292) (xy 406.586137 -307.475224) (xy 406.633408 -307.488916) (xy 406.67787 -307.510014)
			(xy 406.718373 -307.53797) (xy 406.753866 -307.572062) (xy 406.783431 -307.611406) (xy 406.806302 -307.654983)
			(xy 406.821886 -307.701664) (xy 406.829781 -307.750241) (xy 406.830276 -307.774848) (xy 408.119084 -307.774848)
			(xy 408.123044 -307.725794) (xy 408.134821 -307.67801) (xy 408.154112 -307.632734) (xy 408.180415 -307.591138)
			(xy 408.21305 -307.554301) (xy 408.251171 -307.523176) (xy 408.293792 -307.498569) (xy 408.339808 -307.481117)
			(xy 408.388027 -307.471273) (xy 408.437202 -307.469292) (xy 408.486057 -307.475224) (xy 408.533328 -307.488916)
			(xy 408.57779 -307.510014) (xy 408.618293 -307.53797) (xy 408.653786 -307.572062) (xy 408.683351 -307.611406)
			(xy 408.706222 -307.654983) (xy 408.721806 -307.701664) (xy 408.729701 -307.750241) (xy 408.730196 -307.774848)
			(xy 409.069044 -307.774848) (xy 409.073004 -307.725794) (xy 409.084781 -307.67801) (xy 409.104072 -307.632734)
			(xy 409.130375 -307.591138) (xy 409.16301 -307.554301) (xy 409.201131 -307.523176) (xy 409.243752 -307.498569)
			(xy 409.289768 -307.481117) (xy 409.337987 -307.471273) (xy 409.387162 -307.469292) (xy 409.436017 -307.475224)
			(xy 409.483288 -307.488916) (xy 409.52775 -307.510014) (xy 409.568253 -307.53797) (xy 409.603746 -307.572062)
			(xy 409.633311 -307.611406) (xy 409.656182 -307.654983) (xy 409.671766 -307.701664) (xy 409.679661 -307.750241)
			(xy 409.680156 -307.774848) (xy 410.019004 -307.774848) (xy 410.022964 -307.725794) (xy 410.034741 -307.67801)
			(xy 410.054032 -307.632734) (xy 410.080335 -307.591138) (xy 410.11297 -307.554301) (xy 410.151091 -307.523176)
			(xy 410.193712 -307.498569) (xy 410.239728 -307.481117) (xy 410.287947 -307.471273) (xy 410.337122 -307.469292)
			(xy 410.385977 -307.475224) (xy 410.433248 -307.488916) (xy 410.47771 -307.510014) (xy 410.518213 -307.53797)
			(xy 410.553706 -307.572062) (xy 410.583271 -307.611406) (xy 410.606142 -307.654983) (xy 410.621726 -307.701664)
			(xy 410.629621 -307.750241) (xy 410.630111 -307.774594) (xy 410.968964 -307.774594) (xy 410.972924 -307.72554)
			(xy 410.984701 -307.677756) (xy 411.003992 -307.63248) (xy 411.030295 -307.590884) (xy 411.06293 -307.554047)
			(xy 411.101051 -307.522922) (xy 411.143672 -307.498315) (xy 411.189688 -307.480863) (xy 411.237907 -307.471019)
			(xy 411.287082 -307.469038) (xy 411.335937 -307.47497) (xy 411.383208 -307.488662) (xy 411.42767 -307.50976)
			(xy 411.468173 -307.537716) (xy 411.503666 -307.571808) (xy 411.533231 -307.611152) (xy 411.556102 -307.654729)
			(xy 411.571686 -307.70141) (xy 411.579581 -307.749987) (xy 411.580076 -307.774594) (xy 411.919178 -307.774594)
			(xy 411.923138 -307.72554) (xy 411.934915 -307.677756) (xy 411.954206 -307.63248) (xy 411.980509 -307.590884)
			(xy 412.013144 -307.554047) (xy 412.051265 -307.522922) (xy 412.093886 -307.498315) (xy 412.139902 -307.480863)
			(xy 412.188121 -307.471019) (xy 412.237296 -307.469038) (xy 412.286151 -307.47497) (xy 412.333422 -307.488662)
			(xy 412.377884 -307.50976) (xy 412.418387 -307.537716) (xy 412.45388 -307.571808) (xy 412.483445 -307.611152)
			(xy 412.506316 -307.654729) (xy 412.5219 -307.70141) (xy 412.529795 -307.749987) (xy 412.53029 -307.774594)
			(xy 412.530285 -307.774848) (xy 412.869138 -307.774848) (xy 412.873098 -307.725794) (xy 412.884875 -307.67801)
			(xy 412.904166 -307.632734) (xy 412.930469 -307.591138) (xy 412.963104 -307.554301) (xy 413.001225 -307.523176)
			(xy 413.043846 -307.498569) (xy 413.089862 -307.481117) (xy 413.138081 -307.471273) (xy 413.187256 -307.469292)
			(xy 413.236111 -307.475224) (xy 413.283382 -307.488916) (xy 413.327844 -307.510014) (xy 413.368347 -307.53797)
			(xy 413.40384 -307.572062) (xy 413.433405 -307.611406) (xy 413.456276 -307.654983) (xy 413.47186 -307.701664)
			(xy 413.479755 -307.750241) (xy 413.48025 -307.774848) (xy 413.819098 -307.774848) (xy 413.823058 -307.725794)
			(xy 413.834835 -307.67801) (xy 413.854126 -307.632734) (xy 413.880429 -307.591138) (xy 413.913064 -307.554301)
			(xy 413.951185 -307.523176) (xy 413.993806 -307.498569) (xy 414.039822 -307.481117) (xy 414.088041 -307.471273)
			(xy 414.137216 -307.469292) (xy 414.186071 -307.475224) (xy 414.233342 -307.488916) (xy 414.277804 -307.510014)
			(xy 414.318307 -307.53797) (xy 414.3538 -307.572062) (xy 414.383365 -307.611406) (xy 414.406236 -307.654983)
			(xy 414.42182 -307.701664) (xy 414.429715 -307.750241) (xy 414.43021 -307.774848) (xy 414.769058 -307.774848)
			(xy 414.773018 -307.725794) (xy 414.784795 -307.67801) (xy 414.804086 -307.632734) (xy 414.830389 -307.591138)
			(xy 414.863024 -307.554301) (xy 414.901145 -307.523176) (xy 414.943766 -307.498569) (xy 414.989782 -307.481117)
			(xy 415.038001 -307.471273) (xy 415.087176 -307.469292) (xy 415.136031 -307.475224) (xy 415.183302 -307.488916)
			(xy 415.227764 -307.510014) (xy 415.268267 -307.53797) (xy 415.30376 -307.572062) (xy 415.333325 -307.611406)
			(xy 415.356196 -307.654983) (xy 415.37178 -307.701664) (xy 415.379675 -307.750241) (xy 415.38017 -307.774848)
			(xy 415.719018 -307.774848) (xy 415.722978 -307.725794) (xy 415.734755 -307.67801) (xy 415.754046 -307.632734)
			(xy 415.780349 -307.591138) (xy 415.812984 -307.554301) (xy 415.851105 -307.523176) (xy 415.893726 -307.498569)
			(xy 415.939742 -307.481117) (xy 415.987961 -307.471273) (xy 416.037136 -307.469292) (xy 416.085991 -307.475224)
			(xy 416.133262 -307.488916) (xy 416.177724 -307.510014) (xy 416.218227 -307.53797) (xy 416.25372 -307.572062)
			(xy 416.283285 -307.611406) (xy 416.306156 -307.654983) (xy 416.32174 -307.701664) (xy 416.329635 -307.750241)
			(xy 416.33013 -307.774848) (xy 416.668978 -307.774848) (xy 416.672938 -307.725794) (xy 416.684715 -307.67801)
			(xy 416.704006 -307.632734) (xy 416.730309 -307.591138) (xy 416.762944 -307.554301) (xy 416.801065 -307.523176)
			(xy 416.843686 -307.498569) (xy 416.889702 -307.481117) (xy 416.937921 -307.471273) (xy 416.987096 -307.469292)
			(xy 417.035951 -307.475224) (xy 417.083222 -307.488916) (xy 417.127684 -307.510014) (xy 417.168187 -307.53797)
			(xy 417.20368 -307.572062) (xy 417.233245 -307.611406) (xy 417.256116 -307.654983) (xy 417.2717 -307.701664)
			(xy 417.279595 -307.750241) (xy 417.28009 -307.774848) (xy 417.619192 -307.774848) (xy 417.623152 -307.725794)
			(xy 417.634929 -307.67801) (xy 417.65422 -307.632734) (xy 417.680523 -307.591138) (xy 417.713158 -307.554301)
			(xy 417.751279 -307.523176) (xy 417.7939 -307.498569) (xy 417.839916 -307.481117) (xy 417.888135 -307.471273)
			(xy 417.93731 -307.469292) (xy 417.986165 -307.475224) (xy 418.033436 -307.488916) (xy 418.077898 -307.510014)
			(xy 418.118401 -307.53797) (xy 418.153894 -307.572062) (xy 418.183459 -307.611406) (xy 418.20633 -307.654983)
			(xy 418.221914 -307.701664) (xy 418.229809 -307.750241) (xy 418.230304 -307.774848) (xy 418.569152 -307.774848)
			(xy 418.573112 -307.725794) (xy 418.584889 -307.67801) (xy 418.60418 -307.632734) (xy 418.630483 -307.591138)
			(xy 418.663118 -307.554301) (xy 418.701239 -307.523176) (xy 418.74386 -307.498569) (xy 418.789876 -307.481117)
			(xy 418.838095 -307.471273) (xy 418.88727 -307.469292) (xy 418.936125 -307.475224) (xy 418.983396 -307.488916)
			(xy 419.027858 -307.510014) (xy 419.068361 -307.53797) (xy 419.103854 -307.572062) (xy 419.133419 -307.611406)
			(xy 419.15629 -307.654983) (xy 419.171874 -307.701664) (xy 419.179769 -307.750241) (xy 419.180264 -307.774848)
			(xy 419.519112 -307.774848) (xy 419.523072 -307.725794) (xy 419.534849 -307.67801) (xy 419.55414 -307.632734)
			(xy 419.580443 -307.591138) (xy 419.613078 -307.554301) (xy 419.651199 -307.523176) (xy 419.69382 -307.498569)
			(xy 419.739836 -307.481117) (xy 419.788055 -307.471273) (xy 419.83723 -307.469292) (xy 419.886085 -307.475224)
			(xy 419.933356 -307.488916) (xy 419.977818 -307.510014) (xy 420.018321 -307.53797) (xy 420.053814 -307.572062)
			(xy 420.083379 -307.611406) (xy 420.10625 -307.654983) (xy 420.121834 -307.701664) (xy 420.129729 -307.750241)
			(xy 420.130224 -307.774848) (xy 420.469072 -307.774848) (xy 420.473032 -307.725794) (xy 420.484809 -307.67801)
			(xy 420.5041 -307.632734) (xy 420.530403 -307.591138) (xy 420.563038 -307.554301) (xy 420.601159 -307.523176)
			(xy 420.64378 -307.498569) (xy 420.689796 -307.481117) (xy 420.738015 -307.471273) (xy 420.78719 -307.469292)
			(xy 420.836045 -307.475224) (xy 420.883316 -307.488916) (xy 420.927778 -307.510014) (xy 420.968281 -307.53797)
			(xy 421.003774 -307.572062) (xy 421.033339 -307.611406) (xy 421.05621 -307.654983) (xy 421.071794 -307.701664)
			(xy 421.079689 -307.750241) (xy 421.080184 -307.774848) (xy 421.419032 -307.774848) (xy 421.422992 -307.725794)
			(xy 421.434769 -307.67801) (xy 421.45406 -307.632734) (xy 421.480363 -307.591138) (xy 421.512998 -307.554301)
			(xy 421.551119 -307.523176) (xy 421.59374 -307.498569) (xy 421.639756 -307.481117) (xy 421.687975 -307.471273)
			(xy 421.73715 -307.469292) (xy 421.786005 -307.475224) (xy 421.833276 -307.488916) (xy 421.877738 -307.510014)
			(xy 421.918241 -307.53797) (xy 421.953734 -307.572062) (xy 421.983299 -307.611406) (xy 422.00617 -307.654983)
			(xy 422.021754 -307.701664) (xy 422.029649 -307.750241) (xy 422.030144 -307.774848) (xy 422.029649 -307.799455)
			(xy 422.021754 -307.848032) (xy 422.00617 -307.894713) (xy 421.983299 -307.93829) (xy 421.953734 -307.977634)
			(xy 421.918241 -308.011726) (xy 421.877738 -308.039682) (xy 421.833276 -308.06078) (xy 421.786005 -308.074472)
			(xy 421.73715 -308.080404) (xy 421.687975 -308.078423) (xy 421.639756 -308.068579) (xy 421.59374 -308.051127)
			(xy 421.551119 -308.02652) (xy 421.512998 -307.995395) (xy 421.480363 -307.958558) (xy 421.45406 -307.916962)
			(xy 421.434769 -307.871686) (xy 421.422992 -307.823902) (xy 421.419032 -307.774848) (xy 421.080184 -307.774848)
			(xy 421.079689 -307.799455) (xy 421.071794 -307.848032) (xy 421.05621 -307.894713) (xy 421.033339 -307.93829)
			(xy 421.003774 -307.977634) (xy 420.968281 -308.011726) (xy 420.927778 -308.039682) (xy 420.883316 -308.06078)
			(xy 420.836045 -308.074472) (xy 420.78719 -308.080404) (xy 420.738015 -308.078423) (xy 420.689796 -308.068579)
			(xy 420.64378 -308.051127) (xy 420.601159 -308.02652) (xy 420.563038 -307.995395) (xy 420.530403 -307.958558)
			(xy 420.5041 -307.916962) (xy 420.484809 -307.871686) (xy 420.473032 -307.823902) (xy 420.469072 -307.774848)
			(xy 420.130224 -307.774848) (xy 420.129729 -307.799455) (xy 420.121834 -307.848032) (xy 420.10625 -307.894713)
			(xy 420.083379 -307.93829) (xy 420.053814 -307.977634) (xy 420.018321 -308.011726) (xy 419.977818 -308.039682)
			(xy 419.933356 -308.06078) (xy 419.886085 -308.074472) (xy 419.83723 -308.080404) (xy 419.788055 -308.078423)
			(xy 419.739836 -308.068579) (xy 419.69382 -308.051127) (xy 419.651199 -308.02652) (xy 419.613078 -307.995395)
			(xy 419.580443 -307.958558) (xy 419.55414 -307.916962) (xy 419.534849 -307.871686) (xy 419.523072 -307.823902)
			(xy 419.519112 -307.774848) (xy 419.180264 -307.774848) (xy 419.179769 -307.799455) (xy 419.171874 -307.848032)
			(xy 419.15629 -307.894713) (xy 419.133419 -307.93829) (xy 419.103854 -307.977634) (xy 419.068361 -308.011726)
			(xy 419.027858 -308.039682) (xy 418.983396 -308.06078) (xy 418.936125 -308.074472) (xy 418.88727 -308.080404)
			(xy 418.838095 -308.078423) (xy 418.789876 -308.068579) (xy 418.74386 -308.051127) (xy 418.701239 -308.02652)
			(xy 418.663118 -307.995395) (xy 418.630483 -307.958558) (xy 418.60418 -307.916962) (xy 418.584889 -307.871686)
			(xy 418.573112 -307.823902) (xy 418.569152 -307.774848) (xy 418.230304 -307.774848) (xy 418.229809 -307.799455)
			(xy 418.221914 -307.848032) (xy 418.20633 -307.894713) (xy 418.183459 -307.93829) (xy 418.153894 -307.977634)
			(xy 418.118401 -308.011726) (xy 418.077898 -308.039682) (xy 418.033436 -308.06078) (xy 417.986165 -308.074472)
			(xy 417.93731 -308.080404) (xy 417.888135 -308.078423) (xy 417.839916 -308.068579) (xy 417.7939 -308.051127)
			(xy 417.751279 -308.02652) (xy 417.713158 -307.995395) (xy 417.680523 -307.958558) (xy 417.65422 -307.916962)
			(xy 417.634929 -307.871686) (xy 417.623152 -307.823902) (xy 417.619192 -307.774848) (xy 417.28009 -307.774848)
			(xy 417.279595 -307.799455) (xy 417.2717 -307.848032) (xy 417.256116 -307.894713) (xy 417.233245 -307.93829)
			(xy 417.20368 -307.977634) (xy 417.168187 -308.011726) (xy 417.127684 -308.039682) (xy 417.083222 -308.06078)
			(xy 417.035951 -308.074472) (xy 416.987096 -308.080404) (xy 416.937921 -308.078423) (xy 416.889702 -308.068579)
			(xy 416.843686 -308.051127) (xy 416.801065 -308.02652) (xy 416.762944 -307.995395) (xy 416.730309 -307.958558)
			(xy 416.704006 -307.916962) (xy 416.684715 -307.871686) (xy 416.672938 -307.823902) (xy 416.668978 -307.774848)
			(xy 416.33013 -307.774848) (xy 416.329635 -307.799455) (xy 416.32174 -307.848032) (xy 416.306156 -307.894713)
			(xy 416.283285 -307.93829) (xy 416.25372 -307.977634) (xy 416.218227 -308.011726) (xy 416.177724 -308.039682)
			(xy 416.133262 -308.06078) (xy 416.085991 -308.074472) (xy 416.037136 -308.080404) (xy 415.987961 -308.078423)
			(xy 415.939742 -308.068579) (xy 415.893726 -308.051127) (xy 415.851105 -308.02652) (xy 415.812984 -307.995395)
			(xy 415.780349 -307.958558) (xy 415.754046 -307.916962) (xy 415.734755 -307.871686) (xy 415.722978 -307.823902)
			(xy 415.719018 -307.774848) (xy 415.38017 -307.774848) (xy 415.379675 -307.799455) (xy 415.37178 -307.848032)
			(xy 415.356196 -307.894713) (xy 415.333325 -307.93829) (xy 415.30376 -307.977634) (xy 415.268267 -308.011726)
			(xy 415.227764 -308.039682) (xy 415.183302 -308.06078) (xy 415.136031 -308.074472) (xy 415.087176 -308.080404)
			(xy 415.038001 -308.078423) (xy 414.989782 -308.068579) (xy 414.943766 -308.051127) (xy 414.901145 -308.02652)
			(xy 414.863024 -307.995395) (xy 414.830389 -307.958558) (xy 414.804086 -307.916962) (xy 414.784795 -307.871686)
			(xy 414.773018 -307.823902) (xy 414.769058 -307.774848) (xy 414.43021 -307.774848) (xy 414.429715 -307.799455)
			(xy 414.42182 -307.848032) (xy 414.406236 -307.894713) (xy 414.383365 -307.93829) (xy 414.3538 -307.977634)
			(xy 414.318307 -308.011726) (xy 414.277804 -308.039682) (xy 414.233342 -308.06078) (xy 414.186071 -308.074472)
			(xy 414.137216 -308.080404) (xy 414.088041 -308.078423) (xy 414.039822 -308.068579) (xy 413.993806 -308.051127)
			(xy 413.951185 -308.02652) (xy 413.913064 -307.995395) (xy 413.880429 -307.958558) (xy 413.854126 -307.916962)
			(xy 413.834835 -307.871686) (xy 413.823058 -307.823902) (xy 413.819098 -307.774848) (xy 413.48025 -307.774848)
			(xy 413.479755 -307.799455) (xy 413.47186 -307.848032) (xy 413.456276 -307.894713) (xy 413.433405 -307.93829)
			(xy 413.40384 -307.977634) (xy 413.368347 -308.011726) (xy 413.327844 -308.039682) (xy 413.283382 -308.06078)
			(xy 413.236111 -308.074472) (xy 413.187256 -308.080404) (xy 413.138081 -308.078423) (xy 413.089862 -308.068579)
			(xy 413.043846 -308.051127) (xy 413.001225 -308.02652) (xy 412.963104 -307.995395) (xy 412.930469 -307.958558)
			(xy 412.904166 -307.916962) (xy 412.884875 -307.871686) (xy 412.873098 -307.823902) (xy 412.869138 -307.774848)
			(xy 412.530285 -307.774848) (xy 412.529795 -307.799201) (xy 412.5219 -307.847778) (xy 412.506316 -307.894459)
			(xy 412.483445 -307.938036) (xy 412.45388 -307.97738) (xy 412.418387 -308.011472) (xy 412.377884 -308.039428)
			(xy 412.333422 -308.060526) (xy 412.286151 -308.074218) (xy 412.237296 -308.08015) (xy 412.188121 -308.078169)
			(xy 412.139902 -308.068325) (xy 412.093886 -308.050873) (xy 412.051265 -308.026266) (xy 412.013144 -307.995141)
			(xy 411.980509 -307.958304) (xy 411.954206 -307.916708) (xy 411.934915 -307.871432) (xy 411.923138 -307.823648)
			(xy 411.919178 -307.774594) (xy 411.580076 -307.774594) (xy 411.579581 -307.799201) (xy 411.571686 -307.847778)
			(xy 411.556102 -307.894459) (xy 411.533231 -307.938036) (xy 411.503666 -307.97738) (xy 411.468173 -308.011472)
			(xy 411.42767 -308.039428) (xy 411.383208 -308.060526) (xy 411.335937 -308.074218) (xy 411.287082 -308.08015)
			(xy 411.237907 -308.078169) (xy 411.189688 -308.068325) (xy 411.143672 -308.050873) (xy 411.101051 -308.026266)
			(xy 411.06293 -307.995141) (xy 411.030295 -307.958304) (xy 411.003992 -307.916708) (xy 410.984701 -307.871432)
			(xy 410.972924 -307.823648) (xy 410.968964 -307.774594) (xy 410.630111 -307.774594) (xy 410.630116 -307.774848)
			(xy 410.629621 -307.799455) (xy 410.621726 -307.848032) (xy 410.606142 -307.894713) (xy 410.583271 -307.93829)
			(xy 410.553706 -307.977634) (xy 410.518213 -308.011726) (xy 410.47771 -308.039682) (xy 410.433248 -308.06078)
			(xy 410.385977 -308.074472) (xy 410.337122 -308.080404) (xy 410.287947 -308.078423) (xy 410.239728 -308.068579)
			(xy 410.193712 -308.051127) (xy 410.151091 -308.02652) (xy 410.11297 -307.995395) (xy 410.080335 -307.958558)
			(xy 410.054032 -307.916962) (xy 410.034741 -307.871686) (xy 410.022964 -307.823902) (xy 410.019004 -307.774848)
			(xy 409.680156 -307.774848) (xy 409.679661 -307.799455) (xy 409.671766 -307.848032) (xy 409.656182 -307.894713)
			(xy 409.633311 -307.93829) (xy 409.603746 -307.977634) (xy 409.568253 -308.011726) (xy 409.52775 -308.039682)
			(xy 409.483288 -308.06078) (xy 409.436017 -308.074472) (xy 409.387162 -308.080404) (xy 409.337987 -308.078423)
			(xy 409.289768 -308.068579) (xy 409.243752 -308.051127) (xy 409.201131 -308.02652) (xy 409.16301 -307.995395)
			(xy 409.130375 -307.958558) (xy 409.104072 -307.916962) (xy 409.084781 -307.871686) (xy 409.073004 -307.823902)
			(xy 409.069044 -307.774848) (xy 408.730196 -307.774848) (xy 408.729701 -307.799455) (xy 408.721806 -307.848032)
			(xy 408.706222 -307.894713) (xy 408.683351 -307.93829) (xy 408.653786 -307.977634) (xy 408.618293 -308.011726)
			(xy 408.57779 -308.039682) (xy 408.533328 -308.06078) (xy 408.486057 -308.074472) (xy 408.437202 -308.080404)
			(xy 408.388027 -308.078423) (xy 408.339808 -308.068579) (xy 408.293792 -308.051127) (xy 408.251171 -308.02652)
			(xy 408.21305 -307.995395) (xy 408.180415 -307.958558) (xy 408.154112 -307.916962) (xy 408.134821 -307.871686)
			(xy 408.123044 -307.823902) (xy 408.119084 -307.774848) (xy 406.830276 -307.774848) (xy 406.829781 -307.799455)
			(xy 406.821886 -307.848032) (xy 406.806302 -307.894713) (xy 406.783431 -307.93829) (xy 406.753866 -307.977634)
			(xy 406.718373 -308.011726) (xy 406.67787 -308.039682) (xy 406.633408 -308.06078) (xy 406.586137 -308.074472)
			(xy 406.537282 -308.080404) (xy 406.488107 -308.078423) (xy 406.439888 -308.068579) (xy 406.393872 -308.051127)
			(xy 406.351251 -308.02652) (xy 406.31313 -307.995395) (xy 406.280495 -307.958558) (xy 406.254192 -307.916962)
			(xy 406.234901 -307.871686) (xy 406.223124 -307.823902) (xy 406.219164 -307.774848) (xy 405.880316 -307.774848)
			(xy 405.879821 -307.799455) (xy 405.871926 -307.848032) (xy 405.856342 -307.894713) (xy 405.833471 -307.93829)
			(xy 405.803906 -307.977634) (xy 405.768413 -308.011726) (xy 405.72791 -308.039682) (xy 405.683448 -308.06078)
			(xy 405.636177 -308.074472) (xy 405.587322 -308.080404) (xy 405.538147 -308.078423) (xy 405.489928 -308.068579)
			(xy 405.443912 -308.051127) (xy 405.401291 -308.02652) (xy 405.36317 -307.995395) (xy 405.330535 -307.958558)
			(xy 405.304232 -307.916962) (xy 405.284941 -307.871686) (xy 405.273164 -307.823902) (xy 405.269204 -307.774848)
			(xy 404.930356 -307.774848) (xy 404.929861 -307.799455) (xy 404.921966 -307.848032) (xy 404.906382 -307.894713)
			(xy 404.883511 -307.93829) (xy 404.853946 -307.977634) (xy 404.818453 -308.011726) (xy 404.77795 -308.039682)
			(xy 404.733488 -308.06078) (xy 404.686217 -308.074472) (xy 404.637362 -308.080404) (xy 404.588187 -308.078423)
			(xy 404.539968 -308.068579) (xy 404.493952 -308.051127) (xy 404.451331 -308.02652) (xy 404.41321 -307.995395)
			(xy 404.380575 -307.958558) (xy 404.354272 -307.916962) (xy 404.334981 -307.871686) (xy 404.323204 -307.823902)
			(xy 404.319244 -307.774848) (xy 403.980142 -307.774848) (xy 403.979647 -307.799455) (xy 403.971752 -307.848032)
			(xy 403.956168 -307.894713) (xy 403.933297 -307.93829) (xy 403.903732 -307.977634) (xy 403.868239 -308.011726)
			(xy 403.827736 -308.039682) (xy 403.783274 -308.06078) (xy 403.736003 -308.074472) (xy 403.687148 -308.080404)
			(xy 403.637973 -308.078423) (xy 403.589754 -308.068579) (xy 403.543738 -308.051127) (xy 403.501117 -308.02652)
			(xy 403.462996 -307.995395) (xy 403.430361 -307.958558) (xy 403.404058 -307.916962) (xy 403.384767 -307.871686)
			(xy 403.37299 -307.823902) (xy 403.36903 -307.774848) (xy 403.030182 -307.774848) (xy 403.029687 -307.799455)
			(xy 403.021792 -307.848032) (xy 403.006208 -307.894713) (xy 402.983337 -307.93829) (xy 402.953772 -307.977634)
			(xy 402.918279 -308.011726) (xy 402.877776 -308.039682) (xy 402.833314 -308.06078) (xy 402.786043 -308.074472)
			(xy 402.737188 -308.080404) (xy 402.688013 -308.078423) (xy 402.639794 -308.068579) (xy 402.593778 -308.051127)
			(xy 402.551157 -308.02652) (xy 402.513036 -307.995395) (xy 402.480401 -307.958558) (xy 402.454098 -307.916962)
			(xy 402.434807 -307.871686) (xy 402.42303 -307.823902) (xy 402.41907 -307.774848) (xy 402.080222 -307.774848)
			(xy 402.079727 -307.799455) (xy 402.071832 -307.848032) (xy 402.056248 -307.894713) (xy 402.033377 -307.93829)
			(xy 402.003812 -307.977634) (xy 401.968319 -308.011726) (xy 401.927816 -308.039682) (xy 401.883354 -308.06078)
			(xy 401.836083 -308.074472) (xy 401.787228 -308.080404) (xy 401.738053 -308.078423) (xy 401.689834 -308.068579)
			(xy 401.643818 -308.051127) (xy 401.601197 -308.02652) (xy 401.563076 -307.995395) (xy 401.530441 -307.958558)
			(xy 401.504138 -307.916962) (xy 401.484847 -307.871686) (xy 401.47307 -307.823902) (xy 401.46911 -307.774848)
			(xy 401.130262 -307.774848) (xy 401.129767 -307.799455) (xy 401.121872 -307.848032) (xy 401.106288 -307.894713)
			(xy 401.083417 -307.93829) (xy 401.053852 -307.977634) (xy 401.018359 -308.011726) (xy 400.977856 -308.039682)
			(xy 400.933394 -308.06078) (xy 400.886123 -308.074472) (xy 400.837268 -308.080404) (xy 400.788093 -308.078423)
			(xy 400.739874 -308.068579) (xy 400.693858 -308.051127) (xy 400.651237 -308.02652) (xy 400.613116 -307.995395)
			(xy 400.580481 -307.958558) (xy 400.554178 -307.916962) (xy 400.534887 -307.871686) (xy 400.52311 -307.823902)
			(xy 400.51915 -307.774848) (xy 400.180302 -307.774848) (xy 400.179807 -307.799455) (xy 400.171912 -307.848032)
			(xy 400.156328 -307.894713) (xy 400.133457 -307.93829) (xy 400.103892 -307.977634) (xy 400.068399 -308.011726)
			(xy 400.027896 -308.039682) (xy 399.983434 -308.06078) (xy 399.936163 -308.074472) (xy 399.887308 -308.080404)
			(xy 399.838133 -308.078423) (xy 399.789914 -308.068579) (xy 399.743898 -308.051127) (xy 399.701277 -308.02652)
			(xy 399.663156 -307.995395) (xy 399.630521 -307.958558) (xy 399.604218 -307.916962) (xy 399.584927 -307.871686)
			(xy 399.57315 -307.823902) (xy 399.56919 -307.774848) (xy 399.230342 -307.774848) (xy 399.229847 -307.799455)
			(xy 399.221952 -307.848032) (xy 399.206368 -307.894713) (xy 399.183497 -307.93829) (xy 399.153932 -307.977634)
			(xy 399.118439 -308.011726) (xy 399.077936 -308.039682) (xy 399.033474 -308.06078) (xy 398.986203 -308.074472)
			(xy 398.937348 -308.080404) (xy 398.888173 -308.078423) (xy 398.839954 -308.068579) (xy 398.793938 -308.051127)
			(xy 398.751317 -308.02652) (xy 398.713196 -307.995395) (xy 398.680561 -307.958558) (xy 398.654258 -307.916962)
			(xy 398.634967 -307.871686) (xy 398.62319 -307.823902) (xy 398.61923 -307.774848) (xy 398.317212 -307.774848)
			(xy 398.317212 -308.275536) (xy 422.823382 -308.275536) (xy 422.823382 -308.22412) (xy 422.831425 -308.173338)
			(xy 422.847313 -308.124439) (xy 422.870656 -308.078627) (xy 422.900877 -308.037031) (xy 422.937233 -308.000675)
			(xy 422.978829 -307.970454) (xy 423.024641 -307.947111) (xy 423.07354 -307.931223) (xy 423.124322 -307.92318)
			(xy 423.175738 -307.92318) (xy 423.22652 -307.931223) (xy 423.275419 -307.947111) (xy 423.321231 -307.970454)
			(xy 423.362827 -308.000675) (xy 423.399183 -308.037031) (xy 423.429404 -308.078627) (xy 423.452747 -308.124439)
			(xy 423.468635 -308.173338) (xy 423.476678 -308.22412) (xy 423.477182 -308.249828) (xy 423.476678 -308.275536)
			(xy 423.773342 -308.275536) (xy 423.773342 -308.22412) (xy 423.781385 -308.173338) (xy 423.797273 -308.124439)
			(xy 423.820616 -308.078627) (xy 423.850837 -308.037031) (xy 423.887193 -308.000675) (xy 423.928789 -307.970454)
			(xy 423.974601 -307.947111) (xy 424.0235 -307.931223) (xy 424.074282 -307.92318) (xy 424.125698 -307.92318)
			(xy 424.17648 -307.931223) (xy 424.225379 -307.947111) (xy 424.271191 -307.970454) (xy 424.312787 -308.000675)
			(xy 424.349143 -308.037031) (xy 424.379364 -308.078627) (xy 424.402707 -308.124439) (xy 424.418595 -308.173338)
			(xy 424.426638 -308.22412) (xy 424.427142 -308.249828) (xy 424.744146 -308.249828) (xy 424.748106 -308.200774)
			(xy 424.759883 -308.15299) (xy 424.779174 -308.107714) (xy 424.805477 -308.066118) (xy 424.838112 -308.029281)
			(xy 424.876233 -307.998156) (xy 424.918854 -307.973549) (xy 424.96487 -307.956097) (xy 425.013089 -307.946253)
			(xy 425.062264 -307.944272) (xy 425.111119 -307.950204) (xy 425.15839 -307.963896) (xy 425.202852 -307.984994)
			(xy 425.243355 -308.01295) (xy 425.278848 -308.047042) (xy 425.308413 -308.086386) (xy 425.331284 -308.129963)
			(xy 425.346868 -308.176644) (xy 425.354763 -308.225221) (xy 425.355258 -308.249828) (xy 425.694106 -308.249828)
			(xy 425.698066 -308.200774) (xy 425.709843 -308.15299) (xy 425.729134 -308.107714) (xy 425.755437 -308.066118)
			(xy 425.788072 -308.029281) (xy 425.826193 -307.998156) (xy 425.868814 -307.973549) (xy 425.91483 -307.956097)
			(xy 425.963049 -307.946253) (xy 426.012224 -307.944272) (xy 426.061079 -307.950204) (xy 426.10835 -307.963896)
			(xy 426.152812 -307.984994) (xy 426.193315 -308.01295) (xy 426.228808 -308.047042) (xy 426.258373 -308.086386)
			(xy 426.281244 -308.129963) (xy 426.296828 -308.176644) (xy 426.304723 -308.225221) (xy 426.305218 -308.249828)
			(xy 426.644066 -308.249828) (xy 426.648026 -308.200774) (xy 426.659803 -308.15299) (xy 426.679094 -308.107714)
			(xy 426.705397 -308.066118) (xy 426.738032 -308.029281) (xy 426.776153 -307.998156) (xy 426.818774 -307.973549)
			(xy 426.86479 -307.956097) (xy 426.913009 -307.946253) (xy 426.962184 -307.944272) (xy 427.011039 -307.950204)
			(xy 427.05831 -307.963896) (xy 427.102772 -307.984994) (xy 427.143275 -308.01295) (xy 427.178768 -308.047042)
			(xy 427.208333 -308.086386) (xy 427.231204 -308.129963) (xy 427.246788 -308.176644) (xy 427.254683 -308.225221)
			(xy 427.255178 -308.249828) (xy 427.594026 -308.249828) (xy 427.597986 -308.200774) (xy 427.609763 -308.15299)
			(xy 427.629054 -308.107714) (xy 427.655357 -308.066118) (xy 427.687992 -308.029281) (xy 427.726113 -307.998156)
			(xy 427.768734 -307.973549) (xy 427.81475 -307.956097) (xy 427.862969 -307.946253) (xy 427.912144 -307.944272)
			(xy 427.960999 -307.950204) (xy 428.00827 -307.963896) (xy 428.052732 -307.984994) (xy 428.093235 -308.01295)
			(xy 428.128728 -308.047042) (xy 428.158293 -308.086386) (xy 428.181164 -308.129963) (xy 428.196748 -308.176644)
			(xy 428.204643 -308.225221) (xy 428.205138 -308.249828) (xy 428.543986 -308.249828) (xy 428.547946 -308.200774)
			(xy 428.559723 -308.15299) (xy 428.579014 -308.107714) (xy 428.605317 -308.066118) (xy 428.637952 -308.029281)
			(xy 428.676073 -307.998156) (xy 428.718694 -307.973549) (xy 428.76471 -307.956097) (xy 428.812929 -307.946253)
			(xy 428.862104 -307.944272) (xy 428.910959 -307.950204) (xy 428.95823 -307.963896) (xy 429.002692 -307.984994)
			(xy 429.043195 -308.01295) (xy 429.078688 -308.047042) (xy 429.108253 -308.086386) (xy 429.131124 -308.129963)
			(xy 429.146708 -308.176644) (xy 429.154603 -308.225221) (xy 429.155098 -308.249828) (xy 429.154603 -308.274435)
			(xy 429.154424 -308.275536) (xy 429.473356 -308.275536) (xy 429.473356 -308.22412) (xy 429.481399 -308.173338)
			(xy 429.497287 -308.124439) (xy 429.52063 -308.078627) (xy 429.550851 -308.037031) (xy 429.587207 -308.000675)
			(xy 429.628803 -307.970454) (xy 429.674615 -307.947111) (xy 429.723514 -307.931223) (xy 429.774296 -307.92318)
			(xy 429.825712 -307.92318) (xy 429.876494 -307.931223) (xy 429.925393 -307.947111) (xy 429.971205 -307.970454)
			(xy 430.012801 -308.000675) (xy 430.049157 -308.037031) (xy 430.079378 -308.078627) (xy 430.102721 -308.124439)
			(xy 430.118609 -308.173338) (xy 430.126652 -308.22412) (xy 430.127156 -308.249828) (xy 430.126652 -308.275536)
			(xy 430.423316 -308.275536) (xy 430.423316 -308.22412) (xy 430.431359 -308.173338) (xy 430.447247 -308.124439)
			(xy 430.47059 -308.078627) (xy 430.500811 -308.037031) (xy 430.537167 -308.000675) (xy 430.578763 -307.970454)
			(xy 430.624575 -307.947111) (xy 430.673474 -307.931223) (xy 430.724256 -307.92318) (xy 430.775672 -307.92318)
			(xy 430.826454 -307.931223) (xy 430.875353 -307.947111) (xy 430.921165 -307.970454) (xy 430.962761 -308.000675)
			(xy 430.999117 -308.037031) (xy 431.029338 -308.078627) (xy 431.052681 -308.124439) (xy 431.068569 -308.173338)
			(xy 431.076612 -308.22412) (xy 431.077116 -308.249828) (xy 431.394374 -308.249828) (xy 431.398334 -308.200774)
			(xy 431.410111 -308.15299) (xy 431.429402 -308.107714) (xy 431.455705 -308.066118) (xy 431.48834 -308.029281)
			(xy 431.526461 -307.998156) (xy 431.569082 -307.973549) (xy 431.615098 -307.956097) (xy 431.663317 -307.946253)
			(xy 431.712492 -307.944272) (xy 431.761347 -307.950204) (xy 431.808618 -307.963896) (xy 431.85308 -307.984994)
			(xy 431.893583 -308.01295) (xy 431.929076 -308.047042) (xy 431.958641 -308.086386) (xy 431.981512 -308.129963)
			(xy 431.997096 -308.176644) (xy 432.004991 -308.225221) (xy 432.005486 -308.249828) (xy 432.004991 -308.274435)
			(xy 431.997096 -308.323012) (xy 431.981512 -308.369693) (xy 431.958641 -308.41327) (xy 431.929076 -308.452614)
			(xy 431.893583 -308.486706) (xy 431.85308 -308.514662) (xy 431.808618 -308.53576) (xy 431.761347 -308.549452)
			(xy 431.712492 -308.555384) (xy 431.663317 -308.553403) (xy 431.615098 -308.543559) (xy 431.569082 -308.526107)
			(xy 431.526461 -308.5015) (xy 431.48834 -308.470375) (xy 431.455705 -308.433538) (xy 431.429402 -308.391942)
			(xy 431.410111 -308.346666) (xy 431.398334 -308.298882) (xy 431.394374 -308.249828) (xy 431.077116 -308.249828)
			(xy 431.076612 -308.275536) (xy 431.068569 -308.326318) (xy 431.052681 -308.375217) (xy 431.029338 -308.421029)
			(xy 430.999117 -308.462625) (xy 430.962761 -308.498981) (xy 430.921165 -308.529202) (xy 430.875353 -308.552545)
			(xy 430.826454 -308.568433) (xy 430.775672 -308.576476) (xy 430.724256 -308.576476) (xy 430.673474 -308.568433)
			(xy 430.624575 -308.552545) (xy 430.578763 -308.529202) (xy 430.537167 -308.498981) (xy 430.500811 -308.462625)
			(xy 430.47059 -308.421029) (xy 430.447247 -308.375217) (xy 430.431359 -308.326318) (xy 430.423316 -308.275536)
			(xy 430.126652 -308.275536) (xy 430.118609 -308.326318) (xy 430.102721 -308.375217) (xy 430.079378 -308.421029)
			(xy 430.049157 -308.462625) (xy 430.012801 -308.498981) (xy 429.971205 -308.529202) (xy 429.925393 -308.552545)
			(xy 429.876494 -308.568433) (xy 429.825712 -308.576476) (xy 429.774296 -308.576476) (xy 429.723514 -308.568433)
			(xy 429.674615 -308.552545) (xy 429.628803 -308.529202) (xy 429.587207 -308.498981) (xy 429.550851 -308.462625)
			(xy 429.52063 -308.421029) (xy 429.497287 -308.375217) (xy 429.481399 -308.326318) (xy 429.473356 -308.275536)
			(xy 429.154424 -308.275536) (xy 429.146708 -308.323012) (xy 429.131124 -308.369693) (xy 429.108253 -308.41327)
			(xy 429.078688 -308.452614) (xy 429.043195 -308.486706) (xy 429.002692 -308.514662) (xy 428.95823 -308.53576)
			(xy 428.910959 -308.549452) (xy 428.862104 -308.555384) (xy 428.812929 -308.553403) (xy 428.76471 -308.543559)
			(xy 428.718694 -308.526107) (xy 428.676073 -308.5015) (xy 428.637952 -308.470375) (xy 428.605317 -308.433538)
			(xy 428.579014 -308.391942) (xy 428.559723 -308.346666) (xy 428.547946 -308.298882) (xy 428.543986 -308.249828)
			(xy 428.205138 -308.249828) (xy 428.204643 -308.274435) (xy 428.196748 -308.323012) (xy 428.181164 -308.369693)
			(xy 428.158293 -308.41327) (xy 428.128728 -308.452614) (xy 428.093235 -308.486706) (xy 428.052732 -308.514662)
			(xy 428.00827 -308.53576) (xy 427.960999 -308.549452) (xy 427.912144 -308.555384) (xy 427.862969 -308.553403)
			(xy 427.81475 -308.543559) (xy 427.768734 -308.526107) (xy 427.726113 -308.5015) (xy 427.687992 -308.470375)
			(xy 427.655357 -308.433538) (xy 427.629054 -308.391942) (xy 427.609763 -308.346666) (xy 427.597986 -308.298882)
			(xy 427.594026 -308.249828) (xy 427.255178 -308.249828) (xy 427.254683 -308.274435) (xy 427.246788 -308.323012)
			(xy 427.231204 -308.369693) (xy 427.208333 -308.41327) (xy 427.178768 -308.452614) (xy 427.143275 -308.486706)
			(xy 427.102772 -308.514662) (xy 427.05831 -308.53576) (xy 427.011039 -308.549452) (xy 426.962184 -308.555384)
			(xy 426.913009 -308.553403) (xy 426.86479 -308.543559) (xy 426.818774 -308.526107) (xy 426.776153 -308.5015)
			(xy 426.738032 -308.470375) (xy 426.705397 -308.433538) (xy 426.679094 -308.391942) (xy 426.659803 -308.346666)
			(xy 426.648026 -308.298882) (xy 426.644066 -308.249828) (xy 426.305218 -308.249828) (xy 426.304723 -308.274435)
			(xy 426.296828 -308.323012) (xy 426.281244 -308.369693) (xy 426.258373 -308.41327) (xy 426.228808 -308.452614)
			(xy 426.193315 -308.486706) (xy 426.152812 -308.514662) (xy 426.10835 -308.53576) (xy 426.061079 -308.549452)
			(xy 426.012224 -308.555384) (xy 425.963049 -308.553403) (xy 425.91483 -308.543559) (xy 425.868814 -308.526107)
			(xy 425.826193 -308.5015) (xy 425.788072 -308.470375) (xy 425.755437 -308.433538) (xy 425.729134 -308.391942)
			(xy 425.709843 -308.346666) (xy 425.698066 -308.298882) (xy 425.694106 -308.249828) (xy 425.355258 -308.249828)
			(xy 425.354763 -308.274435) (xy 425.346868 -308.323012) (xy 425.331284 -308.369693) (xy 425.308413 -308.41327)
			(xy 425.278848 -308.452614) (xy 425.243355 -308.486706) (xy 425.202852 -308.514662) (xy 425.15839 -308.53576)
			(xy 425.111119 -308.549452) (xy 425.062264 -308.555384) (xy 425.013089 -308.553403) (xy 424.96487 -308.543559)
			(xy 424.918854 -308.526107) (xy 424.876233 -308.5015) (xy 424.838112 -308.470375) (xy 424.805477 -308.433538)
			(xy 424.779174 -308.391942) (xy 424.759883 -308.346666) (xy 424.748106 -308.298882) (xy 424.744146 -308.249828)
			(xy 424.427142 -308.249828) (xy 424.426638 -308.275536) (xy 424.418595 -308.326318) (xy 424.402707 -308.375217)
			(xy 424.379364 -308.421029) (xy 424.349143 -308.462625) (xy 424.312787 -308.498981) (xy 424.271191 -308.529202)
			(xy 424.225379 -308.552545) (xy 424.17648 -308.568433) (xy 424.125698 -308.576476) (xy 424.074282 -308.576476)
			(xy 424.0235 -308.568433) (xy 423.974601 -308.552545) (xy 423.928789 -308.529202) (xy 423.887193 -308.498981)
			(xy 423.850837 -308.462625) (xy 423.820616 -308.421029) (xy 423.797273 -308.375217) (xy 423.781385 -308.326318)
			(xy 423.773342 -308.275536) (xy 423.476678 -308.275536) (xy 423.468635 -308.326318) (xy 423.452747 -308.375217)
			(xy 423.429404 -308.421029) (xy 423.399183 -308.462625) (xy 423.362827 -308.498981) (xy 423.321231 -308.529202)
			(xy 423.275419 -308.552545) (xy 423.22652 -308.568433) (xy 423.175738 -308.576476) (xy 423.124322 -308.576476)
			(xy 423.07354 -308.568433) (xy 423.024641 -308.552545) (xy 422.978829 -308.529202) (xy 422.937233 -308.498981)
			(xy 422.900877 -308.462625) (xy 422.870656 -308.421029) (xy 422.847313 -308.375217) (xy 422.831425 -308.326318)
			(xy 422.823382 -308.275536) (xy 398.317212 -308.275536) (xy 398.317212 -308.724808) (xy 398.61923 -308.724808)
			(xy 398.62319 -308.675754) (xy 398.634967 -308.62797) (xy 398.654258 -308.582694) (xy 398.680561 -308.541098)
			(xy 398.713196 -308.504261) (xy 398.751317 -308.473136) (xy 398.793938 -308.448529) (xy 398.839954 -308.431077)
			(xy 398.888173 -308.421233) (xy 398.937348 -308.419252) (xy 398.986203 -308.425184) (xy 399.033474 -308.438876)
			(xy 399.077936 -308.459974) (xy 399.118439 -308.48793) (xy 399.153932 -308.522022) (xy 399.183497 -308.561366)
			(xy 399.206368 -308.604943) (xy 399.221952 -308.651624) (xy 399.229847 -308.700201) (xy 399.230342 -308.724808)
			(xy 399.56919 -308.724808) (xy 399.57315 -308.675754) (xy 399.584927 -308.62797) (xy 399.604218 -308.582694)
			(xy 399.630521 -308.541098) (xy 399.663156 -308.504261) (xy 399.701277 -308.473136) (xy 399.743898 -308.448529)
			(xy 399.789914 -308.431077) (xy 399.838133 -308.421233) (xy 399.887308 -308.419252) (xy 399.936163 -308.425184)
			(xy 399.983434 -308.438876) (xy 400.027896 -308.459974) (xy 400.068399 -308.48793) (xy 400.103892 -308.522022)
			(xy 400.133457 -308.561366) (xy 400.156328 -308.604943) (xy 400.171912 -308.651624) (xy 400.179807 -308.700201)
			(xy 400.180302 -308.724808) (xy 400.51915 -308.724808) (xy 400.52311 -308.675754) (xy 400.534887 -308.62797)
			(xy 400.554178 -308.582694) (xy 400.580481 -308.541098) (xy 400.613116 -308.504261) (xy 400.651237 -308.473136)
			(xy 400.693858 -308.448529) (xy 400.739874 -308.431077) (xy 400.788093 -308.421233) (xy 400.837268 -308.419252)
			(xy 400.886123 -308.425184) (xy 400.933394 -308.438876) (xy 400.977856 -308.459974) (xy 401.018359 -308.48793)
			(xy 401.053852 -308.522022) (xy 401.083417 -308.561366) (xy 401.106288 -308.604943) (xy 401.121872 -308.651624)
			(xy 401.129767 -308.700201) (xy 401.130262 -308.724808) (xy 401.46911 -308.724808) (xy 401.47307 -308.675754)
			(xy 401.484847 -308.62797) (xy 401.504138 -308.582694) (xy 401.530441 -308.541098) (xy 401.563076 -308.504261)
			(xy 401.601197 -308.473136) (xy 401.643818 -308.448529) (xy 401.689834 -308.431077) (xy 401.738053 -308.421233)
			(xy 401.787228 -308.419252) (xy 401.836083 -308.425184) (xy 401.883354 -308.438876) (xy 401.927816 -308.459974)
			(xy 401.968319 -308.48793) (xy 402.003812 -308.522022) (xy 402.033377 -308.561366) (xy 402.056248 -308.604943)
			(xy 402.071832 -308.651624) (xy 402.079727 -308.700201) (xy 402.080222 -308.724808) (xy 402.41907 -308.724808)
			(xy 402.42303 -308.675754) (xy 402.434807 -308.62797) (xy 402.454098 -308.582694) (xy 402.480401 -308.541098)
			(xy 402.513036 -308.504261) (xy 402.551157 -308.473136) (xy 402.593778 -308.448529) (xy 402.639794 -308.431077)
			(xy 402.688013 -308.421233) (xy 402.737188 -308.419252) (xy 402.786043 -308.425184) (xy 402.833314 -308.438876)
			(xy 402.877776 -308.459974) (xy 402.918279 -308.48793) (xy 402.953772 -308.522022) (xy 402.983337 -308.561366)
			(xy 403.006208 -308.604943) (xy 403.021792 -308.651624) (xy 403.029687 -308.700201) (xy 403.030182 -308.724808)
			(xy 403.029687 -308.749415) (xy 403.021792 -308.797992) (xy 403.006208 -308.844673) (xy 402.983337 -308.88825)
			(xy 402.953772 -308.927594) (xy 402.918279 -308.961686) (xy 402.877776 -308.989642) (xy 402.833314 -309.01074)
			(xy 402.786043 -309.024432) (xy 402.737188 -309.030364) (xy 402.688013 -309.028383) (xy 402.639794 -309.018539)
			(xy 402.593778 -309.001087) (xy 402.551157 -308.97648) (xy 402.513036 -308.945355) (xy 402.480401 -308.908518)
			(xy 402.454098 -308.866922) (xy 402.434807 -308.821646) (xy 402.42303 -308.773862) (xy 402.41907 -308.724808)
			(xy 402.080222 -308.724808) (xy 402.079727 -308.749415) (xy 402.071832 -308.797992) (xy 402.056248 -308.844673)
			(xy 402.033377 -308.88825) (xy 402.003812 -308.927594) (xy 401.968319 -308.961686) (xy 401.927816 -308.989642)
			(xy 401.883354 -309.01074) (xy 401.836083 -309.024432) (xy 401.787228 -309.030364) (xy 401.738053 -309.028383)
			(xy 401.689834 -309.018539) (xy 401.643818 -309.001087) (xy 401.601197 -308.97648) (xy 401.563076 -308.945355)
			(xy 401.530441 -308.908518) (xy 401.504138 -308.866922) (xy 401.484847 -308.821646) (xy 401.47307 -308.773862)
			(xy 401.46911 -308.724808) (xy 401.130262 -308.724808) (xy 401.129767 -308.749415) (xy 401.121872 -308.797992)
			(xy 401.106288 -308.844673) (xy 401.083417 -308.88825) (xy 401.053852 -308.927594) (xy 401.018359 -308.961686)
			(xy 400.977856 -308.989642) (xy 400.933394 -309.01074) (xy 400.886123 -309.024432) (xy 400.837268 -309.030364)
			(xy 400.788093 -309.028383) (xy 400.739874 -309.018539) (xy 400.693858 -309.001087) (xy 400.651237 -308.97648)
			(xy 400.613116 -308.945355) (xy 400.580481 -308.908518) (xy 400.554178 -308.866922) (xy 400.534887 -308.821646)
			(xy 400.52311 -308.773862) (xy 400.51915 -308.724808) (xy 400.180302 -308.724808) (xy 400.179807 -308.749415)
			(xy 400.171912 -308.797992) (xy 400.156328 -308.844673) (xy 400.133457 -308.88825) (xy 400.103892 -308.927594)
			(xy 400.068399 -308.961686) (xy 400.027896 -308.989642) (xy 399.983434 -309.01074) (xy 399.936163 -309.024432)
			(xy 399.887308 -309.030364) (xy 399.838133 -309.028383) (xy 399.789914 -309.018539) (xy 399.743898 -309.001087)
			(xy 399.701277 -308.97648) (xy 399.663156 -308.945355) (xy 399.630521 -308.908518) (xy 399.604218 -308.866922)
			(xy 399.584927 -308.821646) (xy 399.57315 -308.773862) (xy 399.56919 -308.724808) (xy 399.230342 -308.724808)
			(xy 399.229847 -308.749415) (xy 399.221952 -308.797992) (xy 399.206368 -308.844673) (xy 399.183497 -308.88825)
			(xy 399.153932 -308.927594) (xy 399.118439 -308.961686) (xy 399.077936 -308.989642) (xy 399.033474 -309.01074)
			(xy 398.986203 -309.024432) (xy 398.937348 -309.030364) (xy 398.888173 -309.028383) (xy 398.839954 -309.018539)
			(xy 398.793938 -309.001087) (xy 398.751317 -308.97648) (xy 398.713196 -308.945355) (xy 398.680561 -308.908518)
			(xy 398.654258 -308.866922) (xy 398.634967 -308.821646) (xy 398.62319 -308.773862) (xy 398.61923 -308.724808)
			(xy 398.317212 -308.724808) (xy 398.317212 -309.74411) (xy 398.31777 -309.75456) (xy 398.326155 -309.77371)
			(xy 398.333468 -309.781194) (xy 398.395952 -309.83936) (xy 398.415764 -309.846218) (xy 398.426432 -309.845202)
			(xy 398.4498 -309.84444) (xy 398.473792 -309.844886) (xy 398.521184 -309.852393) (xy 398.566819 -309.867222)
			(xy 398.609572 -309.889009) (xy 398.648389 -309.917215) (xy 398.682316 -309.951147) (xy 398.710517 -309.989969)
			(xy 398.732296 -310.032725) (xy 398.747118 -310.078362) (xy 398.754618 -310.125756) (xy 398.755108 -310.149748)
			(xy 398.755062 -310.158785) (xy 398.754047 -310.176831) (xy 398.753076 -310.185816) (xy 398.751552 -310.197754)
			(xy 398.759426 -310.220106) (xy 398.83588 -310.293004) (xy 398.858486 -310.299862) (xy 398.870424 -310.298084)
			(xy 398.883912 -310.295953) (xy 398.911125 -310.293661) (xy 398.92478 -310.293512) (xy 398.938434 -310.293675)
			(xy 398.965646 -310.295965) (xy 398.979136 -310.298084) (xy 398.991328 -310.300116) (xy 399.013934 -310.293004)
			(xy 399.090388 -310.220106) (xy 399.098262 -310.198008) (xy 399.096738 -310.185816) (xy 399.095756 -310.176832)
			(xy 399.094739 -310.158786) (xy 399.094706 -310.149748) (xy 399.095228 -310.124493) (xy 399.103541 -310.074671)
			(xy 399.119942 -310.026897) (xy 399.143983 -309.982474) (xy 399.175007 -309.942614) (xy 399.212169 -309.908404)
			(xy 399.254455 -309.880778) (xy 399.300711 -309.860488) (xy 399.349676 -309.848088) (xy 399.400014 -309.843917)
			(xy 399.450352 -309.848088) (xy 399.499317 -309.860488) (xy 399.545573 -309.880778) (xy 399.587859 -309.908404)
			(xy 399.625021 -309.942614) (xy 399.656045 -309.982474) (xy 399.680086 -310.026897) (xy 399.696487 -310.074671)
			(xy 399.7048 -310.124493) (xy 399.705322 -310.149748) (xy 399.7052 -310.163862) (xy 399.702656 -310.191975)
			(xy 399.700242 -310.205882) (xy 399.697702 -310.218328) (xy 399.705068 -310.24195) (xy 399.782538 -310.31942)
			(xy 399.80616 -310.326532) (xy 399.818606 -310.324246) (xy 399.846614 -310.319623) (xy 399.903374 -310.319623)
			(xy 399.931382 -310.324246) (xy 399.943828 -310.326532) (xy 399.96745 -310.31942) (xy 400.04492 -310.24195)
			(xy 400.052286 -310.218328) (xy 400.049746 -310.205882) (xy 400.047347 -310.191973) (xy 400.044801 -310.163862)
			(xy 400.044666 -310.149748) (xy 400.045188 -310.124493) (xy 400.053501 -310.074671) (xy 400.069902 -310.026897)
			(xy 400.093943 -309.982474) (xy 400.124967 -309.942614) (xy 400.162129 -309.908404) (xy 400.204415 -309.880778)
			(xy 400.250671 -309.860488) (xy 400.299636 -309.848088) (xy 400.349974 -309.843917) (xy 400.400312 -309.848088)
			(xy 400.449277 -309.860488) (xy 400.495533 -309.880778) (xy 400.537819 -309.908404) (xy 400.574981 -309.942614)
			(xy 400.606005 -309.982474) (xy 400.630046 -310.026897) (xy 400.646447 -310.074671) (xy 400.65476 -310.124493)
			(xy 400.655282 -310.149748) (xy 400.655236 -310.158785) (xy 400.654221 -310.176831) (xy 400.65325 -310.185816)
			(xy 400.651726 -310.197754) (xy 400.6596 -310.220106) (xy 400.736054 -310.293004) (xy 400.75866 -310.299862)
			(xy 400.770598 -310.298084) (xy 400.784024 -310.295965) (xy 400.811109 -310.293673) (xy 400.8247 -310.293512)
			(xy 400.838354 -310.293675) (xy 400.865566 -310.295967) (xy 400.879056 -310.298084) (xy 400.891248 -310.300116)
			(xy 400.913854 -310.293004) (xy 400.990308 -310.220106) (xy 400.998182 -310.198008) (xy 400.996658 -310.185816)
			(xy 400.995676 -310.176832) (xy 400.994659 -310.158786) (xy 400.994626 -310.149748) (xy 400.995148 -310.124493)
			(xy 401.003461 -310.074671) (xy 401.019862 -310.026897) (xy 401.043903 -309.982474) (xy 401.074927 -309.942614)
			(xy 401.112089 -309.908404) (xy 401.154375 -309.880778) (xy 401.200631 -309.860488) (xy 401.249596 -309.848088)
			(xy 401.299934 -309.843917) (xy 401.350272 -309.848088) (xy 401.399237 -309.860488) (xy 401.445493 -309.880778)
			(xy 401.487779 -309.908404) (xy 401.524941 -309.942614) (xy 401.555965 -309.982474) (xy 401.580006 -310.026897)
			(xy 401.596407 -310.074671) (xy 401.60472 -310.124493) (xy 401.605242 -310.149748) (xy 401.60512 -310.163862)
			(xy 401.602576 -310.191975) (xy 401.600162 -310.205882) (xy 401.597622 -310.218328) (xy 401.604988 -310.24195)
			(xy 401.682458 -310.31942) (xy 401.70608 -310.326532) (xy 401.718526 -310.324246) (xy 401.746534 -310.319623)
			(xy 401.803294 -310.319623) (xy 401.831302 -310.324246) (xy 401.843748 -310.326532) (xy 401.86737 -310.31942)
			(xy 401.94484 -310.24195) (xy 401.952206 -310.218328) (xy 401.949666 -310.205882) (xy 401.947267 -310.191973)
			(xy 401.944721 -310.163862) (xy 401.944586 -310.149748) (xy 401.945108 -310.124493) (xy 401.953421 -310.074671)
			(xy 401.969822 -310.026897) (xy 401.993863 -309.982474) (xy 402.024887 -309.942614) (xy 402.062049 -309.908404)
			(xy 402.104335 -309.880778) (xy 402.150591 -309.860488) (xy 402.199556 -309.848088) (xy 402.249894 -309.843917)
			(xy 402.300232 -309.848088) (xy 402.349197 -309.860488) (xy 402.395453 -309.880778) (xy 402.437739 -309.908404)
			(xy 402.474901 -309.942614) (xy 402.505925 -309.982474) (xy 402.529966 -310.026897) (xy 402.546367 -310.074671)
			(xy 402.55468 -310.124493) (xy 402.555202 -310.149748) (xy 402.555156 -310.158785) (xy 402.554141 -310.176831)
			(xy 402.55317 -310.185816) (xy 402.551646 -310.197754) (xy 402.55952 -310.220106) (xy 402.635974 -310.293004)
			(xy 402.65858 -310.299862) (xy 402.670518 -310.298084) (xy 402.683944 -310.295966) (xy 402.711029 -310.293675)
			(xy 402.72462 -310.293512) (xy 402.738274 -310.293672) (xy 402.765487 -310.295958) (xy 402.778976 -310.298084)
			(xy 402.791168 -310.300116) (xy 402.813774 -310.293004) (xy 402.890228 -310.220106) (xy 402.898102 -310.198008)
			(xy 402.896578 -310.185816) (xy 402.895596 -310.176832) (xy 402.894579 -310.158786) (xy 402.894546 -310.149748)
			(xy 402.895068 -310.124493) (xy 402.903381 -310.074671) (xy 402.919782 -310.026897) (xy 402.943823 -309.982474)
			(xy 402.974847 -309.942614) (xy 403.012009 -309.908404) (xy 403.054295 -309.880778) (xy 403.100551 -309.860488)
			(xy 403.149516 -309.848088) (xy 403.199854 -309.843917) (xy 403.250192 -309.848088) (xy 403.299157 -309.860488)
			(xy 403.345413 -309.880778) (xy 403.387699 -309.908404) (xy 403.424861 -309.942614) (xy 403.455885 -309.982474)
			(xy 403.479926 -310.026897) (xy 403.496327 -310.074671) (xy 403.50464 -310.124493) (xy 403.505162 -310.149748)
			(xy 403.50504 -310.163862) (xy 403.502496 -310.191975) (xy 403.500082 -310.205882) (xy 403.497542 -310.218328)
			(xy 403.504908 -310.24195) (xy 403.582378 -310.31942) (xy 403.606 -310.326532) (xy 403.618446 -310.324246)
			(xy 403.646454 -310.319623) (xy 403.703214 -310.319623) (xy 403.731222 -310.324246) (xy 403.743668 -310.326532)
			(xy 403.76729 -310.31942) (xy 403.84476 -310.24195) (xy 403.852126 -310.218328) (xy 403.849586 -310.205882)
			(xy 403.847188 -310.191973) (xy 403.844642 -310.163862) (xy 403.844506 -310.149748) (xy 403.844949 -310.125753)
			(xy 403.852449 -310.078352) (xy 403.867274 -310.032709) (xy 403.889057 -309.989947) (xy 403.917262 -309.95112)
			(xy 403.951194 -309.917184) (xy 403.990018 -309.888975) (xy 404.032778 -309.867187) (xy 404.078419 -309.852357)
			(xy 404.125819 -309.844851) (xy 404.149814 -309.84444) (xy 404.163996 -309.844627) (xy 404.192235 -309.847301)
			(xy 404.206202 -309.849774) (xy 404.218648 -309.85206) (xy 404.24227 -309.844694) (xy 404.31974 -309.767224)
			(xy 404.327106 -309.743602) (xy 404.32482 -309.731156) (xy 404.322336 -309.717191) (xy 404.319667 -309.688951)
			(xy 404.319486 -309.674768) (xy 404.319669 -309.660585) (xy 404.322337 -309.632345) (xy 404.32482 -309.61838)
			(xy 404.327106 -309.605934) (xy 404.31974 -309.582312) (xy 404.24227 -309.504842) (xy 404.218648 -309.497476)
			(xy 404.206202 -309.499762) (xy 404.192237 -309.502248) (xy 404.163997 -309.504921) (xy 404.149814 -309.505096)
			(xy 404.12582 -309.504651) (xy 404.078424 -309.497146) (xy 404.032785 -309.482318) (xy 403.990028 -309.460534)
			(xy 403.951205 -309.432328) (xy 403.917273 -309.398396) (xy 403.889068 -309.359574) (xy 403.867282 -309.316817)
			(xy 403.852455 -309.271178) (xy 403.844949 -309.223782) (xy 403.844506 -309.199788) (xy 403.844693 -309.185606)
			(xy 403.847368 -309.157367) (xy 403.84984 -309.1434) (xy 403.852126 -309.130954) (xy 403.84476 -309.107332)
			(xy 403.76729 -309.029862) (xy 403.743668 -309.022496) (xy 403.731222 -309.024782) (xy 403.717257 -309.027269)
			(xy 403.689017 -309.029944) (xy 403.674834 -309.030116) (xy 403.650012 -309.029633) (xy 403.60102 -309.021606)
			(xy 403.553973 -309.00576) (xy 403.510109 -308.98251) (xy 403.470585 -308.95247) (xy 403.436441 -308.916432)
			(xy 403.408578 -308.875344) (xy 403.387729 -308.830289) (xy 403.374445 -308.782455) (xy 403.369074 -308.733102)
			(xy 403.371758 -308.68353) (xy 403.382427 -308.635046) (xy 403.4008 -308.588926) (xy 403.426393 -308.546387)
			(xy 403.45853 -308.508548) (xy 403.496366 -308.476408) (xy 403.538903 -308.450812) (xy 403.585021 -308.432435)
			(xy 403.633505 -308.421762) (xy 403.683076 -308.419073) (xy 403.73243 -308.42444) (xy 403.780265 -308.43772)
			(xy 403.825321 -308.458565) (xy 403.866411 -308.486425) (xy 403.902453 -308.520566) (xy 403.932496 -308.560087)
			(xy 403.955749 -308.603949) (xy 403.9716 -308.650995) (xy 403.979631 -308.699986) (xy 403.980142 -308.724808)
			(xy 403.979955 -308.73899) (xy 403.977281 -308.76723) (xy 403.974808 -308.781196) (xy 403.972522 -308.793642)
			(xy 403.979888 -308.817264) (xy 404.057358 -308.894734) (xy 404.08098 -308.9021) (xy 404.093426 -308.899814)
			(xy 404.107391 -308.897329) (xy 404.135631 -308.894659) (xy 404.149814 -308.89448) (xy 404.16406 -308.894656)
			(xy 404.192428 -308.897325) (xy 404.206456 -308.899814) (xy 404.218648 -308.9021) (xy 404.242778 -308.894734)
			(xy 404.319994 -308.817518) (xy 404.32736 -308.793642) (xy 404.325074 -308.781196) (xy 404.322588 -308.767231)
			(xy 404.319915 -308.738991) (xy 404.31974 -308.724808) (xy 404.320225 -308.699992) (xy 404.328253 -308.651013)
			(xy 404.344099 -308.603978) (xy 404.367346 -308.560126) (xy 404.39738 -308.520612) (xy 404.433412 -308.486478)
			(xy 404.474491 -308.458623) (xy 404.519535 -308.43778) (xy 404.567357 -308.424499) (xy 404.616698 -308.41913)
			(xy 404.666258 -308.421813) (xy 404.714731 -308.432479) (xy 404.76084 -308.450846) (xy 404.80337 -308.476431)
			(xy 404.841201 -308.508559) (xy 404.873336 -308.546384) (xy 404.898929 -308.588909) (xy 404.917304 -308.635015)
			(xy 404.927979 -308.683486) (xy 404.930224 -308.724808) (xy 406.219164 -308.724808) (xy 406.223124 -308.675754)
			(xy 406.234901 -308.62797) (xy 406.254192 -308.582694) (xy 406.280495 -308.541098) (xy 406.31313 -308.504261)
			(xy 406.351251 -308.473136) (xy 406.393872 -308.448529) (xy 406.439888 -308.431077) (xy 406.488107 -308.421233)
			(xy 406.537282 -308.419252) (xy 406.586137 -308.425184) (xy 406.633408 -308.438876) (xy 406.67787 -308.459974)
			(xy 406.718373 -308.48793) (xy 406.753866 -308.522022) (xy 406.783431 -308.561366) (xy 406.806302 -308.604943)
			(xy 406.821886 -308.651624) (xy 406.829781 -308.700201) (xy 406.830276 -308.724808) (xy 406.829781 -308.749415)
			(xy 406.821886 -308.797992) (xy 406.806302 -308.844673) (xy 406.783431 -308.88825) (xy 406.753866 -308.927594)
			(xy 406.718373 -308.961686) (xy 406.67787 -308.989642) (xy 406.633408 -309.01074) (xy 406.586137 -309.024432)
			(xy 406.537282 -309.030364) (xy 406.488107 -309.028383) (xy 406.439888 -309.018539) (xy 406.393872 -309.001087)
			(xy 406.351251 -308.97648) (xy 406.31313 -308.945355) (xy 406.280495 -308.908518) (xy 406.254192 -308.866922)
			(xy 406.234901 -308.821646) (xy 406.223124 -308.773862) (xy 406.219164 -308.724808) (xy 404.930224 -308.724808)
			(xy 404.930672 -308.733045) (xy 404.925311 -308.782388) (xy 404.912039 -308.830213) (xy 404.891205 -308.875261)
			(xy 404.863357 -308.916345) (xy 404.829229 -308.952382) (xy 404.789721 -308.982424) (xy 404.745874 -309.005679)
			(xy 404.698842 -309.021533) (xy 404.649864 -309.02957) (xy 404.625048 -309.030116) (xy 404.610802 -309.029938)
			(xy 404.582435 -309.027266) (xy 404.568406 -309.024782) (xy 404.556214 -309.022496) (xy 404.532084 -309.029862)
			(xy 404.454868 -309.107078) (xy 404.447502 -309.130954) (xy 404.449788 -309.1434) (xy 404.452274 -309.157365)
			(xy 404.454947 -309.185605) (xy 404.455122 -309.199788) (xy 404.454936 -309.21397) (xy 404.452264 -309.24221)
			(xy 404.449788 -309.256176) (xy 404.447502 -309.268622) (xy 404.454868 -309.292244) (xy 404.532338 -309.369714)
			(xy 404.55596 -309.37708) (xy 404.568406 -309.374794) (xy 404.582371 -309.372309) (xy 404.610611 -309.369636)
			(xy 404.624794 -309.36946) (xy 404.648786 -309.36993) (xy 404.696181 -309.377435) (xy 404.741818 -309.392262)
			(xy 404.784573 -309.414045) (xy 404.823396 -309.442247) (xy 404.857328 -309.476176) (xy 404.885536 -309.514994)
			(xy 404.907324 -309.557747) (xy 404.922156 -309.603382) (xy 404.929667 -309.650776) (xy 404.930102 -309.674768)
			(xy 404.929917 -309.688951) (xy 404.927246 -309.71719) (xy 404.924768 -309.731156) (xy 404.922482 -309.743602)
			(xy 404.929848 -309.767478) (xy 405.007064 -309.844694) (xy 405.031194 -309.85206) (xy 405.043386 -309.849774)
			(xy 405.057413 -309.847273) (xy 405.085781 -309.844598) (xy 405.100028 -309.84444) (xy 405.114211 -309.844623)
			(xy 405.142451 -309.84729) (xy 405.156416 -309.849774) (xy 405.168862 -309.85206) (xy 405.192484 -309.844694)
			(xy 405.269954 -309.767224) (xy 405.27732 -309.743602) (xy 405.275034 -309.731156) (xy 405.27255 -309.717191)
			(xy 405.269881 -309.688951) (xy 405.2697 -309.674768) (xy 405.270173 -309.650779) (xy 405.277683 -309.603391)
			(xy 405.292513 -309.557762) (xy 405.314299 -309.515014) (xy 405.342503 -309.476201) (xy 405.376431 -309.442277)
			(xy 405.415249 -309.414078) (xy 405.457999 -309.392298) (xy 405.50363 -309.377474) (xy 405.551019 -309.36997)
			(xy 405.575008 -309.36946) (xy 405.598949 -309.369927) (xy 405.646244 -309.377402) (xy 405.691792 -309.392169)
			(xy 405.734477 -309.413863) (xy 405.773253 -309.441955) (xy 405.807168 -309.475755) (xy 405.835392 -309.514435)
			(xy 405.857232 -309.557046) (xy 405.872153 -309.602543) (xy 405.879789 -309.649813) (xy 405.880316 -309.673752)
			(xy 405.880316 -309.678324) (xy 405.879554 -309.700676) (xy 405.878538 -309.715154) (xy 405.891238 -309.740046)
			(xy 405.94153 -309.771288) (xy 405.991822 -309.80253) (xy 406.020016 -309.802784) (xy 406.032462 -309.795672)
			(xy 406.047618 -309.786733) (xy 406.078486 -309.769837) (xy 406.094184 -309.76189) (xy 406.131014 -309.744364)
			(xy 406.14092 -309.740046) (xy 406.172416 -309.726838) (xy 406.179528 -309.724044) (xy 406.185878 -309.718964)
			(xy 406.188747 -309.716631) (xy 406.193849 -309.711277) (xy 406.196038 -309.708296) (xy 406.21077 -309.687468)
			(xy 406.214688 -309.681473) (xy 406.219342 -309.667936) (xy 406.219914 -309.660798) (xy 406.219914 -309.660544)
			(xy 406.220692 -309.646895) (xy 406.224383 -309.619803) (xy 406.22728 -309.606442) (xy 406.233246 -309.582644)
			(xy 406.251722 -309.537198) (xy 406.277217 -309.495284) (xy 406.309077 -309.457979) (xy 406.346485 -309.42624)
			(xy 406.367234 -309.413148) (xy 406.367488 -309.413148) (xy 406.37206 -309.410354) (xy 406.39266 -309.398984)
			(xy 406.436546 -309.382019) (xy 406.459436 -309.376572) (xy 406.49017 -309.371492) (xy 406.497536 -309.37073)
			(xy 406.49906 -309.37073) (xy 406.503124 -309.370222) (xy 406.505156 -309.370222) (xy 406.524968 -309.36946)
			(xy 406.550812 -309.370006) (xy 406.60176 -309.378714) (xy 406.650517 -309.395871) (xy 406.695692 -309.420987)
			(xy 406.735997 -309.453346) (xy 406.770283 -309.492025) (xy 406.797572 -309.535922) (xy 406.817085 -309.583784)
			(xy 406.828267 -309.634247) (xy 406.830022 -309.660036) (xy 406.830784 -309.67426) (xy 406.847802 -309.69966)
			(xy 406.84831 -309.700168) (xy 406.858724 -309.715154) (xy 406.870154 -309.724298) (xy 406.877266 -309.727092)
			(xy 406.92152 -309.745087) (xy 407.006566 -309.788613) (xy 407.086892 -309.840334) (xy 407.124662 -309.869586)
			(xy 407.133806 -309.875428) (xy 407.156366 -309.88696) (xy 407.197637 -309.916342) (xy 407.233494 -309.952132)
			(xy 407.262952 -309.99335) (xy 407.274522 -310.01589) (xy 407.280364 -310.025288) (xy 407.307049 -310.059719)
			(xy 407.354799 -310.132583) (xy 407.395784 -310.209456) (xy 407.429667 -310.289713) (xy 407.456174 -310.372699)
			(xy 407.475088 -310.457738) (xy 407.486256 -310.544136) (xy 407.48839 -310.587644) (xy 407.489152 -310.608218)
			(xy 407.518362 -310.636412)
		)
		(stroke
			(width 0)
			(type solid)
		)
		(fill yes)
		(layer "In13.Cu")
		(net "P1V25_SERDES_VDDPLL_PEX3")
	)
	(gr_poly
		(pts
			(xy 175.842676 -310.633872) (xy 175.850879 -310.631965) (xy 175.865526 -310.623673) (xy 175.871378 -310.617616)
			(xy 175.871632 -310.617362) (xy 175.883824 -310.603646) (xy 175.884078 -310.603392) (xy 175.91151 -310.574182)
			(xy 175.916082 -310.56961) (xy 175.922686 -310.55818) (xy 175.924464 -310.555132) (xy 175.929544 -310.543956)
			(xy 175.93056 -310.5404) (xy 175.934157 -310.528349) (xy 175.94306 -310.504825) (xy 175.94834 -310.49341)
			(xy 175.95239 -310.483761) (xy 175.953144 -310.462869) (xy 175.945513 -310.443407) (xy 175.93076 -310.428596)
			(xy 175.911327 -310.42089) (xy 175.890433 -310.421563) (xy 175.880776 -310.425592) (xy 175.860237 -310.434893)
			(xy 175.817104 -310.44802) (xy 175.772509 -310.454653) (xy 175.749966 -310.455056) (xy 175.724709 -310.454532)
			(xy 175.674883 -310.446213) (xy 175.627107 -310.429806) (xy 175.582682 -310.40576) (xy 175.54282 -310.374731)
			(xy 175.508609 -310.337564) (xy 175.480982 -310.295273) (xy 175.460692 -310.249012) (xy 175.448292 -310.200043)
			(xy 175.44412 -310.1497) (xy 175.448292 -310.099357) (xy 175.460692 -310.050388) (xy 175.480982 -310.004127)
			(xy 175.508609 -309.961836) (xy 175.54282 -309.924669) (xy 175.582682 -309.89364) (xy 175.627107 -309.869594)
			(xy 175.674883 -309.853187) (xy 175.724709 -309.844868) (xy 175.749966 -309.84444) (xy 175.764149 -309.844625)
			(xy 175.792389 -309.847295) (xy 175.806354 -309.849774) (xy 175.8188 -309.85206) (xy 175.842422 -309.844694)
			(xy 175.919892 -309.767224) (xy 175.927258 -309.743602) (xy 175.924972 -309.731156) (xy 175.922488 -309.717191)
			(xy 175.919818 -309.688951) (xy 175.919638 -309.674768) (xy 175.920087 -309.650778) (xy 175.927598 -309.603389)
			(xy 175.94243 -309.557758) (xy 175.964217 -309.51501) (xy 175.992424 -309.476197) (xy 176.026356 -309.442274)
			(xy 176.065177 -309.414077) (xy 176.107931 -309.3923) (xy 176.153565 -309.377479) (xy 176.200956 -309.36998)
			(xy 176.224946 -309.36946) (xy 176.239129 -309.369644) (xy 176.267369 -309.372312) (xy 176.281334 -309.374794)
			(xy 176.29378 -309.37708) (xy 176.317402 -309.369714) (xy 176.394872 -309.292244) (xy 176.402238 -309.268622)
			(xy 176.399952 -309.256176) (xy 176.397467 -309.242211) (xy 176.394796 -309.213971) (xy 176.394618 -309.199788)
			(xy 176.394805 -309.185606) (xy 176.39748 -309.157367) (xy 176.399952 -309.1434) (xy 176.402238 -309.130954)
			(xy 176.394872 -309.107332) (xy 176.317402 -309.029862) (xy 176.29378 -309.022496) (xy 176.281334 -309.024782)
			(xy 176.267369 -309.027265) (xy 176.239129 -309.029932) (xy 176.224946 -309.030116) (xy 176.200123 -309.029634)
			(xy 176.151131 -309.021609) (xy 176.104083 -309.005764) (xy 176.060218 -308.982516) (xy 176.020693 -308.952477)
			(xy 175.986547 -308.916439) (xy 175.958683 -308.875352) (xy 175.937832 -308.830298) (xy 175.924546 -308.782464)
			(xy 175.919174 -308.73311) (xy 175.921857 -308.683538) (xy 175.932525 -308.635053) (xy 175.950897 -308.588933)
			(xy 175.976489 -308.546392) (xy 176.008626 -308.508553) (xy 176.046461 -308.476411) (xy 176.088998 -308.450814)
			(xy 176.135117 -308.432436) (xy 176.1836 -308.421762) (xy 176.233172 -308.419073) (xy 176.282526 -308.424439)
			(xy 176.330362 -308.437719) (xy 176.375419 -308.458564) (xy 176.416509 -308.486424) (xy 176.452552 -308.520564)
			(xy 176.482595 -308.560086) (xy 176.505849 -308.603948) (xy 176.5217 -308.650995) (xy 176.529731 -308.699986)
			(xy 176.530254 -308.724808) (xy 176.530067 -308.73899) (xy 176.527393 -308.76723) (xy 176.52492 -308.781196)
			(xy 176.522634 -308.793642) (xy 176.53 -308.817264) (xy 176.60747 -308.894734) (xy 176.631092 -308.9021)
			(xy 176.643538 -308.899814) (xy 176.657503 -308.89733) (xy 176.685743 -308.89466) (xy 176.699926 -308.89448)
			(xy 176.714108 -308.894668) (xy 176.742347 -308.897343) (xy 176.756314 -308.899814) (xy 176.76876 -308.9021)
			(xy 176.792382 -308.894734) (xy 176.869852 -308.817264) (xy 176.877218 -308.793642) (xy 176.874932 -308.781196)
			(xy 176.872446 -308.767231) (xy 176.869773 -308.738991) (xy 176.869598 -308.724808) (xy 176.87012 -308.699553)
			(xy 176.878433 -308.649731) (xy 176.894834 -308.601957) (xy 176.918875 -308.557534) (xy 176.949899 -308.517674)
			(xy 176.987061 -308.483464) (xy 177.029347 -308.455838) (xy 177.075603 -308.435548) (xy 177.124568 -308.423148)
			(xy 177.174906 -308.418977) (xy 177.225244 -308.423148) (xy 177.274209 -308.435548) (xy 177.320465 -308.455838)
			(xy 177.362751 -308.483464) (xy 177.399913 -308.517674) (xy 177.430937 -308.557534) (xy 177.454978 -308.601957)
			(xy 177.471379 -308.649731) (xy 177.479692 -308.699553) (xy 177.480214 -308.724808) (xy 177.480027 -308.73899)
			(xy 177.477353 -308.76723) (xy 177.47488 -308.781196) (xy 177.472594 -308.793642) (xy 177.47996 -308.817264)
			(xy 177.55743 -308.894734) (xy 177.581052 -308.9021) (xy 177.593498 -308.899814) (xy 177.607463 -308.897328)
			(xy 177.635703 -308.894655) (xy 177.649886 -308.89448) (xy 177.664069 -308.894666) (xy 177.692308 -308.897338)
			(xy 177.706274 -308.899814) (xy 177.71872 -308.9021) (xy 177.742342 -308.894734) (xy 177.819812 -308.817264)
			(xy 177.827178 -308.793642) (xy 177.824892 -308.781196) (xy 177.822407 -308.767231) (xy 177.819734 -308.738991)
			(xy 177.819558 -308.724808) (xy 177.820043 -308.699984) (xy 177.828075 -308.650989) (xy 177.843927 -308.603939)
			(xy 177.867182 -308.560073) (xy 177.897228 -308.520548) (xy 177.933272 -308.486405) (xy 177.974366 -308.458543)
			(xy 178.019426 -308.437696) (xy 178.067265 -308.424414) (xy 178.116623 -308.419047) (xy 178.166199 -308.421736)
			(xy 178.214687 -308.43241) (xy 178.260808 -308.450789) (xy 178.303349 -308.476387) (xy 178.341188 -308.50853)
			(xy 178.373329 -308.546372) (xy 178.398923 -308.588915) (xy 178.417297 -308.635038) (xy 178.427968 -308.683527)
			(xy 178.430189 -308.724554) (xy 178.769022 -308.724554) (xy 178.772982 -308.6755) (xy 178.784759 -308.627716)
			(xy 178.80405 -308.58244) (xy 178.830353 -308.540844) (xy 178.862988 -308.504007) (xy 178.901109 -308.472882)
			(xy 178.94373 -308.448275) (xy 178.989746 -308.430823) (xy 179.037965 -308.420979) (xy 179.08714 -308.418998)
			(xy 179.135995 -308.42493) (xy 179.183266 -308.438622) (xy 179.227728 -308.45972) (xy 179.268231 -308.487676)
			(xy 179.303724 -308.521768) (xy 179.333289 -308.561112) (xy 179.35616 -308.604689) (xy 179.371744 -308.65137)
			(xy 179.379639 -308.699947) (xy 179.380134 -308.724554) (xy 179.380129 -308.724808) (xy 179.719236 -308.724808)
			(xy 179.723196 -308.675754) (xy 179.734973 -308.62797) (xy 179.754264 -308.582694) (xy 179.780567 -308.541098)
			(xy 179.813202 -308.504261) (xy 179.851323 -308.473136) (xy 179.893944 -308.448529) (xy 179.93996 -308.431077)
			(xy 179.988179 -308.421233) (xy 180.037354 -308.419252) (xy 180.086209 -308.425184) (xy 180.13348 -308.438876)
			(xy 180.177942 -308.459974) (xy 180.218445 -308.48793) (xy 180.253938 -308.522022) (xy 180.283503 -308.561366)
			(xy 180.306374 -308.604943) (xy 180.321958 -308.651624) (xy 180.329853 -308.700201) (xy 180.330348 -308.724808)
			(xy 180.669196 -308.724808) (xy 180.673156 -308.675754) (xy 180.684933 -308.62797) (xy 180.704224 -308.582694)
			(xy 180.730527 -308.541098) (xy 180.763162 -308.504261) (xy 180.801283 -308.473136) (xy 180.843904 -308.448529)
			(xy 180.88992 -308.431077) (xy 180.938139 -308.421233) (xy 180.987314 -308.419252) (xy 181.036169 -308.425184)
			(xy 181.08344 -308.438876) (xy 181.127902 -308.459974) (xy 181.168405 -308.48793) (xy 181.203898 -308.522022)
			(xy 181.233463 -308.561366) (xy 181.256334 -308.604943) (xy 181.271918 -308.651624) (xy 181.279813 -308.700201)
			(xy 181.280308 -308.724808) (xy 181.619156 -308.724808) (xy 181.623116 -308.675754) (xy 181.634893 -308.62797)
			(xy 181.654184 -308.582694) (xy 181.680487 -308.541098) (xy 181.713122 -308.504261) (xy 181.751243 -308.473136)
			(xy 181.793864 -308.448529) (xy 181.83988 -308.431077) (xy 181.888099 -308.421233) (xy 181.937274 -308.419252)
			(xy 181.986129 -308.425184) (xy 182.0334 -308.438876) (xy 182.077862 -308.459974) (xy 182.118365 -308.48793)
			(xy 182.153858 -308.522022) (xy 182.183423 -308.561366) (xy 182.206294 -308.604943) (xy 182.221878 -308.651624)
			(xy 182.229773 -308.700201) (xy 182.230268 -308.724808) (xy 182.569116 -308.724808) (xy 182.573076 -308.675754)
			(xy 182.584853 -308.62797) (xy 182.604144 -308.582694) (xy 182.630447 -308.541098) (xy 182.663082 -308.504261)
			(xy 182.701203 -308.473136) (xy 182.743824 -308.448529) (xy 182.78984 -308.431077) (xy 182.838059 -308.421233)
			(xy 182.887234 -308.419252) (xy 182.936089 -308.425184) (xy 182.98336 -308.438876) (xy 183.027822 -308.459974)
			(xy 183.068325 -308.48793) (xy 183.103818 -308.522022) (xy 183.133383 -308.561366) (xy 183.156254 -308.604943)
			(xy 183.171838 -308.651624) (xy 183.179733 -308.700201) (xy 183.180228 -308.724808) (xy 183.519076 -308.724808)
			(xy 183.523036 -308.675754) (xy 183.534813 -308.62797) (xy 183.554104 -308.582694) (xy 183.580407 -308.541098)
			(xy 183.613042 -308.504261) (xy 183.651163 -308.473136) (xy 183.693784 -308.448529) (xy 183.7398 -308.431077)
			(xy 183.788019 -308.421233) (xy 183.837194 -308.419252) (xy 183.886049 -308.425184) (xy 183.93332 -308.438876)
			(xy 183.977782 -308.459974) (xy 184.018285 -308.48793) (xy 184.053778 -308.522022) (xy 184.083343 -308.561366)
			(xy 184.106214 -308.604943) (xy 184.121798 -308.651624) (xy 184.129693 -308.700201) (xy 184.130188 -308.724808)
			(xy 184.46929 -308.724808) (xy 184.47325 -308.675754) (xy 184.485027 -308.62797) (xy 184.504318 -308.582694)
			(xy 184.530621 -308.541098) (xy 184.563256 -308.504261) (xy 184.601377 -308.473136) (xy 184.643998 -308.448529)
			(xy 184.690014 -308.431077) (xy 184.738233 -308.421233) (xy 184.787408 -308.419252) (xy 184.836263 -308.425184)
			(xy 184.883534 -308.438876) (xy 184.927996 -308.459974) (xy 184.968499 -308.48793) (xy 185.003992 -308.522022)
			(xy 185.033557 -308.561366) (xy 185.056428 -308.604943) (xy 185.072012 -308.651624) (xy 185.079907 -308.700201)
			(xy 185.080402 -308.724808) (xy 185.41925 -308.724808) (xy 185.42321 -308.675754) (xy 185.434987 -308.62797)
			(xy 185.454278 -308.582694) (xy 185.480581 -308.541098) (xy 185.513216 -308.504261) (xy 185.551337 -308.473136)
			(xy 185.593958 -308.448529) (xy 185.639974 -308.431077) (xy 185.688193 -308.421233) (xy 185.737368 -308.419252)
			(xy 185.786223 -308.425184) (xy 185.833494 -308.438876) (xy 185.877956 -308.459974) (xy 185.918459 -308.48793)
			(xy 185.953952 -308.522022) (xy 185.983517 -308.561366) (xy 186.006388 -308.604943) (xy 186.021972 -308.651624)
			(xy 186.029867 -308.700201) (xy 186.030362 -308.724808) (xy 186.36921 -308.724808) (xy 186.37317 -308.675754)
			(xy 186.384947 -308.62797) (xy 186.404238 -308.582694) (xy 186.430541 -308.541098) (xy 186.463176 -308.504261)
			(xy 186.501297 -308.473136) (xy 186.543918 -308.448529) (xy 186.589934 -308.431077) (xy 186.638153 -308.421233)
			(xy 186.687328 -308.419252) (xy 186.736183 -308.425184) (xy 186.783454 -308.438876) (xy 186.827916 -308.459974)
			(xy 186.868419 -308.48793) (xy 186.903912 -308.522022) (xy 186.933477 -308.561366) (xy 186.956348 -308.604943)
			(xy 186.971932 -308.651624) (xy 186.979827 -308.700201) (xy 186.980322 -308.724808) (xy 187.31917 -308.724808)
			(xy 187.32313 -308.675754) (xy 187.334907 -308.62797) (xy 187.354198 -308.582694) (xy 187.380501 -308.541098)
			(xy 187.413136 -308.504261) (xy 187.451257 -308.473136) (xy 187.493878 -308.448529) (xy 187.539894 -308.431077)
			(xy 187.588113 -308.421233) (xy 187.637288 -308.419252) (xy 187.686143 -308.425184) (xy 187.733414 -308.438876)
			(xy 187.777876 -308.459974) (xy 187.818379 -308.48793) (xy 187.853872 -308.522022) (xy 187.883437 -308.561366)
			(xy 187.906308 -308.604943) (xy 187.921892 -308.651624) (xy 187.929787 -308.700201) (xy 187.930282 -308.724808)
			(xy 188.26913 -308.724808) (xy 188.27309 -308.675754) (xy 188.284867 -308.62797) (xy 188.304158 -308.582694)
			(xy 188.330461 -308.541098) (xy 188.363096 -308.504261) (xy 188.401217 -308.473136) (xy 188.443838 -308.448529)
			(xy 188.489854 -308.431077) (xy 188.538073 -308.421233) (xy 188.587248 -308.419252) (xy 188.636103 -308.425184)
			(xy 188.683374 -308.438876) (xy 188.727836 -308.459974) (xy 188.768339 -308.48793) (xy 188.803832 -308.522022)
			(xy 188.833397 -308.561366) (xy 188.856268 -308.604943) (xy 188.871852 -308.651624) (xy 188.879747 -308.700201)
			(xy 188.880242 -308.724808) (xy 188.879747 -308.749415) (xy 188.871852 -308.797992) (xy 188.856268 -308.844673)
			(xy 188.833397 -308.88825) (xy 188.803832 -308.927594) (xy 188.768339 -308.961686) (xy 188.727836 -308.989642)
			(xy 188.683374 -309.01074) (xy 188.636103 -309.024432) (xy 188.587248 -309.030364) (xy 188.538073 -309.028383)
			(xy 188.489854 -309.018539) (xy 188.443838 -309.001087) (xy 188.401217 -308.97648) (xy 188.363096 -308.945355)
			(xy 188.330461 -308.908518) (xy 188.304158 -308.866922) (xy 188.284867 -308.821646) (xy 188.27309 -308.773862)
			(xy 188.26913 -308.724808) (xy 187.930282 -308.724808) (xy 187.929787 -308.749415) (xy 187.921892 -308.797992)
			(xy 187.906308 -308.844673) (xy 187.883437 -308.88825) (xy 187.853872 -308.927594) (xy 187.818379 -308.961686)
			(xy 187.777876 -308.989642) (xy 187.733414 -309.01074) (xy 187.686143 -309.024432) (xy 187.637288 -309.030364)
			(xy 187.588113 -309.028383) (xy 187.539894 -309.018539) (xy 187.493878 -309.001087) (xy 187.451257 -308.97648)
			(xy 187.413136 -308.945355) (xy 187.380501 -308.908518) (xy 187.354198 -308.866922) (xy 187.334907 -308.821646)
			(xy 187.32313 -308.773862) (xy 187.31917 -308.724808) (xy 186.980322 -308.724808) (xy 186.979827 -308.749415)
			(xy 186.971932 -308.797992) (xy 186.956348 -308.844673) (xy 186.933477 -308.88825) (xy 186.903912 -308.927594)
			(xy 186.868419 -308.961686) (xy 186.827916 -308.989642) (xy 186.783454 -309.01074) (xy 186.736183 -309.024432)
			(xy 186.687328 -309.030364) (xy 186.638153 -309.028383) (xy 186.589934 -309.018539) (xy 186.543918 -309.001087)
			(xy 186.501297 -308.97648) (xy 186.463176 -308.945355) (xy 186.430541 -308.908518) (xy 186.404238 -308.866922)
			(xy 186.384947 -308.821646) (xy 186.37317 -308.773862) (xy 186.36921 -308.724808) (xy 186.030362 -308.724808)
			(xy 186.029867 -308.749415) (xy 186.021972 -308.797992) (xy 186.006388 -308.844673) (xy 185.983517 -308.88825)
			(xy 185.953952 -308.927594) (xy 185.918459 -308.961686) (xy 185.877956 -308.989642) (xy 185.833494 -309.01074)
			(xy 185.786223 -309.024432) (xy 185.737368 -309.030364) (xy 185.688193 -309.028383) (xy 185.639974 -309.018539)
			(xy 185.593958 -309.001087) (xy 185.551337 -308.97648) (xy 185.513216 -308.945355) (xy 185.480581 -308.908518)
			(xy 185.454278 -308.866922) (xy 185.434987 -308.821646) (xy 185.42321 -308.773862) (xy 185.41925 -308.724808)
			(xy 185.080402 -308.724808) (xy 185.079907 -308.749415) (xy 185.072012 -308.797992) (xy 185.056428 -308.844673)
			(xy 185.033557 -308.88825) (xy 185.003992 -308.927594) (xy 184.968499 -308.961686) (xy 184.927996 -308.989642)
			(xy 184.883534 -309.01074) (xy 184.836263 -309.024432) (xy 184.787408 -309.030364) (xy 184.738233 -309.028383)
			(xy 184.690014 -309.018539) (xy 184.643998 -309.001087) (xy 184.601377 -308.97648) (xy 184.563256 -308.945355)
			(xy 184.530621 -308.908518) (xy 184.504318 -308.866922) (xy 184.485027 -308.821646) (xy 184.47325 -308.773862)
			(xy 184.46929 -308.724808) (xy 184.130188 -308.724808) (xy 184.129693 -308.749415) (xy 184.121798 -308.797992)
			(xy 184.106214 -308.844673) (xy 184.083343 -308.88825) (xy 184.053778 -308.927594) (xy 184.018285 -308.961686)
			(xy 183.977782 -308.989642) (xy 183.93332 -309.01074) (xy 183.886049 -309.024432) (xy 183.837194 -309.030364)
			(xy 183.788019 -309.028383) (xy 183.7398 -309.018539) (xy 183.693784 -309.001087) (xy 183.651163 -308.97648)
			(xy 183.613042 -308.945355) (xy 183.580407 -308.908518) (xy 183.554104 -308.866922) (xy 183.534813 -308.821646)
			(xy 183.523036 -308.773862) (xy 183.519076 -308.724808) (xy 183.180228 -308.724808) (xy 183.179733 -308.749415)
			(xy 183.171838 -308.797992) (xy 183.156254 -308.844673) (xy 183.133383 -308.88825) (xy 183.103818 -308.927594)
			(xy 183.068325 -308.961686) (xy 183.027822 -308.989642) (xy 182.98336 -309.01074) (xy 182.936089 -309.024432)
			(xy 182.887234 -309.030364) (xy 182.838059 -309.028383) (xy 182.78984 -309.018539) (xy 182.743824 -309.001087)
			(xy 182.701203 -308.97648) (xy 182.663082 -308.945355) (xy 182.630447 -308.908518) (xy 182.604144 -308.866922)
			(xy 182.584853 -308.821646) (xy 182.573076 -308.773862) (xy 182.569116 -308.724808) (xy 182.230268 -308.724808)
			(xy 182.229773 -308.749415) (xy 182.221878 -308.797992) (xy 182.206294 -308.844673) (xy 182.183423 -308.88825)
			(xy 182.153858 -308.927594) (xy 182.118365 -308.961686) (xy 182.077862 -308.989642) (xy 182.0334 -309.01074)
			(xy 181.986129 -309.024432) (xy 181.937274 -309.030364) (xy 181.888099 -309.028383) (xy 181.83988 -309.018539)
			(xy 181.793864 -309.001087) (xy 181.751243 -308.97648) (xy 181.713122 -308.945355) (xy 181.680487 -308.908518)
			(xy 181.654184 -308.866922) (xy 181.634893 -308.821646) (xy 181.623116 -308.773862) (xy 181.619156 -308.724808)
			(xy 181.280308 -308.724808) (xy 181.279813 -308.749415) (xy 181.271918 -308.797992) (xy 181.256334 -308.844673)
			(xy 181.233463 -308.88825) (xy 181.203898 -308.927594) (xy 181.168405 -308.961686) (xy 181.127902 -308.989642)
			(xy 181.08344 -309.01074) (xy 181.036169 -309.024432) (xy 180.987314 -309.030364) (xy 180.938139 -309.028383)
			(xy 180.88992 -309.018539) (xy 180.843904 -309.001087) (xy 180.801283 -308.97648) (xy 180.763162 -308.945355)
			(xy 180.730527 -308.908518) (xy 180.704224 -308.866922) (xy 180.684933 -308.821646) (xy 180.673156 -308.773862)
			(xy 180.669196 -308.724808) (xy 180.330348 -308.724808) (xy 180.329853 -308.749415) (xy 180.321958 -308.797992)
			(xy 180.306374 -308.844673) (xy 180.283503 -308.88825) (xy 180.253938 -308.927594) (xy 180.218445 -308.961686)
			(xy 180.177942 -308.989642) (xy 180.13348 -309.01074) (xy 180.086209 -309.024432) (xy 180.037354 -309.030364)
			(xy 179.988179 -309.028383) (xy 179.93996 -309.018539) (xy 179.893944 -309.001087) (xy 179.851323 -308.97648)
			(xy 179.813202 -308.945355) (xy 179.780567 -308.908518) (xy 179.754264 -308.866922) (xy 179.734973 -308.821646)
			(xy 179.723196 -308.773862) (xy 179.719236 -308.724808) (xy 179.380129 -308.724808) (xy 179.379639 -308.749161)
			(xy 179.371744 -308.797738) (xy 179.35616 -308.844419) (xy 179.333289 -308.887996) (xy 179.303724 -308.92734)
			(xy 179.268231 -308.961432) (xy 179.227728 -308.989388) (xy 179.183266 -309.010486) (xy 179.135995 -309.024178)
			(xy 179.08714 -309.03011) (xy 179.037965 -309.028129) (xy 178.989746 -309.018285) (xy 178.94373 -309.000833)
			(xy 178.901109 -308.976226) (xy 178.862988 -308.945101) (xy 178.830353 -308.908264) (xy 178.80405 -308.866668)
			(xy 178.784759 -308.821392) (xy 178.772982 -308.773608) (xy 178.769022 -308.724554) (xy 178.430189 -308.724554)
			(xy 178.430652 -308.733103) (xy 178.425281 -308.78246) (xy 178.411995 -308.830298) (xy 178.391145 -308.875356)
			(xy 178.363279 -308.916448) (xy 178.329132 -308.95249) (xy 178.289605 -308.982532) (xy 178.245737 -309.005784)
			(xy 178.198686 -309.021632) (xy 178.14969 -309.029659) (xy 178.124866 -309.030116) (xy 178.110683 -309.029933)
			(xy 178.082443 -309.027265) (xy 178.068478 -309.024782) (xy 178.056032 -309.022496) (xy 178.03241 -309.029862)
			(xy 177.95494 -309.107332) (xy 177.947574 -309.130954) (xy 177.94986 -309.1434) (xy 177.952346 -309.157365)
			(xy 177.955019 -309.185605) (xy 177.955194 -309.199788) (xy 177.955008 -309.21397) (xy 177.952335 -309.24221)
			(xy 177.94986 -309.256176) (xy 177.947574 -309.268622) (xy 177.95494 -309.292244) (xy 178.03241 -309.369714)
			(xy 178.056032 -309.37708) (xy 178.068478 -309.374794) (xy 178.082443 -309.372307) (xy 178.110683 -309.369632)
			(xy 178.124866 -309.36946) (xy 178.148862 -309.369904) (xy 178.196263 -309.377406) (xy 178.241908 -309.392231)
			(xy 178.284671 -309.414014) (xy 178.3235 -309.442219) (xy 178.357438 -309.47615) (xy 178.385651 -309.514973)
			(xy 178.407444 -309.557731) (xy 178.422279 -309.603372) (xy 178.429791 -309.650772) (xy 178.430174 -309.674768)
			(xy 178.429158 -309.700168) (xy 178.427888 -309.714392) (xy 178.440588 -309.739538) (xy 178.491134 -309.771288)
			(xy 178.491388 -309.771288) (xy 178.529996 -309.795164) (xy 178.536103 -309.798663) (xy 178.549632 -309.802522)
			(xy 178.556666 -309.802784) (xy 178.570382 -309.802784) (xy 178.582828 -309.795672) (xy 178.583336 -309.795418)
			(xy 178.60392 -309.783268) (xy 178.646103 -309.760777) (xy 178.667664 -309.75046) (xy 178.667918 -309.75046)
			(xy 178.678078 -309.745888) (xy 178.679094 -309.74538) (xy 178.722274 -309.727092) (xy 178.729132 -309.724298)
			(xy 178.740816 -309.715408) (xy 178.764946 -309.681118) (xy 178.769518 -309.66791) (xy 178.769772 -309.66029)
			(xy 178.771435 -309.635862) (xy 178.781565 -309.587963) (xy 178.799208 -309.542293) (xy 178.823911 -309.500023)
			(xy 178.855042 -309.462236) (xy 178.891803 -309.4299) (xy 178.933252 -309.403843) (xy 178.978327 -309.384733)
			(xy 179.025874 -309.373059) (xy 179.074674 -309.369121) (xy 179.123478 -309.373019) (xy 179.171034 -309.384654)
			(xy 179.216125 -309.403727) (xy 179.257596 -309.42975) (xy 179.294383 -309.462056) (xy 179.325545 -309.499817)
			(xy 179.350283 -309.542067) (xy 179.367963 -309.587722) (xy 179.378132 -309.635613) (xy 179.37988 -309.660036)
			(xy 179.380134 -309.667402) (xy 179.38242 -309.67426) (xy 179.384706 -309.681372) (xy 179.403248 -309.708042)
			(xy 179.407566 -309.714392) (xy 179.419504 -309.72379) (xy 179.427378 -309.726838) (xy 179.46361 -309.741533)
			(xy 179.533802 -309.775991) (xy 179.567586 -309.795672) (xy 179.575832 -309.80007) (xy 179.594242 -309.803203)
			(xy 179.612553 -309.79954) (xy 179.620672 -309.79491) (xy 179.638452 -309.783734) (xy 179.63896 -309.783734)
			(xy 179.70881 -309.739284) (xy 179.72151 -309.714392) (xy 179.720494 -309.700422) (xy 179.719732 -309.68061)
			(xy 179.719732 -309.673752) (xy 179.720333 -309.648552) (xy 179.728777 -309.59886) (xy 179.745269 -309.55123)
			(xy 179.769359 -309.506956) (xy 179.800395 -309.467239) (xy 179.837532 -309.43316) (xy 179.879762 -309.405643)
			(xy 179.925939 -309.385437) (xy 179.974807 -309.373089) (xy 180.02504 -309.368935) (xy 180.075273 -309.373089)
			(xy 180.124141 -309.385437) (xy 180.170318 -309.405643) (xy 180.212548 -309.43316) (xy 180.249685 -309.467239)
			(xy 180.280721 -309.506956) (xy 180.304811 -309.55123) (xy 180.321303 -309.59886) (xy 180.329747 -309.648552)
			(xy 180.330348 -309.673752) (xy 180.330348 -309.68061) (xy 180.329332 -309.69966) (xy 180.328062 -309.714138)
			(xy 180.340762 -309.739284) (xy 180.391308 -309.771034) (xy 180.429408 -309.79491) (xy 180.429916 -309.79491)
			(xy 180.441346 -309.802276) (xy 180.46827 -309.803292) (xy 180.484272 -309.79491) (xy 180.485796 -309.793894)
			(xy 180.504073 -309.783206) (xy 180.541424 -309.763259) (xy 180.560472 -309.754016) (xy 180.560726 -309.754016)
			(xy 180.57114 -309.74919) (xy 180.623718 -309.726076) (xy 180.623972 -309.726076) (xy 180.62448 -309.725822)
			(xy 180.631353 -309.722738) (xy 180.642979 -309.713169) (xy 180.64734 -309.707026) (xy 180.656992 -309.692548)
			(xy 180.660673 -309.686553) (xy 180.664934 -309.673152) (xy 180.665374 -309.666132) (xy 180.66648 -309.642247)
			(xy 180.675137 -309.595225) (xy 180.690921 -309.550093) (xy 180.713457 -309.507924) (xy 180.742209 -309.469723)
			(xy 180.776493 -309.436396) (xy 180.815494 -309.408738) (xy 180.858284 -309.387405) (xy 180.903845 -309.372906)
			(xy 180.951093 -309.365585) (xy 180.975 -309.365142) (xy 180.998901 -309.365592) (xy 181.046133 -309.372949)
			(xy 181.091676 -309.387472) (xy 181.134447 -309.408816) (xy 181.173434 -309.436477) (xy 181.20771 -309.469796)
			(xy 181.236462 -309.507984) (xy 181.259009 -309.550135) (xy 181.274814 -309.595248) (xy 181.283504 -309.642253)
			(xy 181.284626 -309.666132) (xy 181.284626 -309.666386) (xy 181.285134 -309.68061) (xy 181.297834 -309.700422)
			(xy 181.298342 -309.70093) (xy 181.302152 -309.706772) (xy 181.304365 -309.709963) (xy 181.309598 -309.715698)
			(xy 181.312566 -309.718202) (xy 181.318408 -309.723028) (xy 181.325774 -309.726076) (xy 181.360915 -309.740278)
			(xy 181.429066 -309.773465) (xy 181.461918 -309.79237) (xy 181.467506 -309.795672) (xy 181.48046 -309.799228)
			(xy 181.49443 -309.80126) (xy 181.495954 -309.80126) (xy 181.503133 -309.801007) (xy 181.516922 -309.796999)
			(xy 181.523132 -309.793386) (xy 181.538372 -309.783734) (xy 181.53888 -309.783734) (xy 181.597046 -309.74665)
			(xy 181.604001 -309.741793) (xy 181.614481 -309.728466) (xy 181.620054 -309.712454) (xy 181.620414 -309.703978)
			(xy 181.620414 -309.69966) (xy 181.62016 -309.697882) (xy 181.62016 -309.690262) (xy 181.619398 -309.675022)
			(xy 181.619398 -309.674514) (xy 181.61989 -309.650516) (xy 181.627438 -309.603117) (xy 181.642302 -309.557481)
			(xy 181.664118 -309.51473) (xy 181.69235 -309.475914) (xy 181.726302 -309.44199) (xy 181.76514 -309.41379)
			(xy 181.807909 -309.392008) (xy 181.853557 -309.37718) (xy 181.900962 -309.369671) (xy 181.92496 -309.369206)
			(xy 181.948976 -309.369649) (xy 181.996418 -309.377157) (xy 182.042101 -309.391994) (xy 182.0849 -309.413795)
			(xy 182.123762 -309.442023) (xy 182.15773 -309.475983) (xy 182.185967 -309.514838) (xy 182.207778 -309.557633)
			(xy 182.222626 -309.603312) (xy 182.230145 -309.650752) (xy 182.230522 -309.674768) (xy 182.229506 -309.700168)
			(xy 182.228236 -309.714392) (xy 182.240936 -309.739538) (xy 182.27675 -309.762144) (xy 182.277004 -309.762144)
			(xy 182.342028 -309.80253) (xy 182.370222 -309.802784) (xy 182.382668 -309.795418) (xy 182.419667 -309.77405)
			(xy 182.496742 -309.737168) (xy 182.536592 -309.721758) (xy 182.546067 -309.717697) (xy 182.560967 -309.703478)
			(xy 182.569101 -309.684556) (xy 182.569612 -309.67426) (xy 182.570173 -309.649032) (xy 182.578552 -309.599275)
			(xy 182.594999 -309.551574) (xy 182.619064 -309.507225) (xy 182.650094 -309.467437) (xy 182.687244 -309.433292)
			(xy 182.729502 -309.405721) (xy 182.775718 -309.385473) (xy 182.824635 -309.373099) (xy 182.87492 -309.368937)
			(xy 182.925205 -309.373099) (xy 182.974122 -309.385473) (xy 183.020338 -309.405721) (xy 183.062596 -309.433292)
			(xy 183.099746 -309.467437) (xy 183.130776 -309.507225) (xy 183.154841 -309.551574) (xy 183.171288 -309.599275)
			(xy 183.179667 -309.649032) (xy 183.180228 -309.67426) (xy 183.180704 -309.684565) (xy 183.188824 -309.703506)
			(xy 183.203761 -309.717704) (xy 183.213248 -309.721758) (xy 183.252076 -309.736732) (xy 183.32724 -309.772468)
			(xy 183.363362 -309.793132) (xy 183.369712 -309.796942) (xy 183.382158 -309.800244) (xy 183.392379 -309.802362)
			(xy 183.412968 -309.799068) (xy 183.422036 -309.793894) (xy 183.496458 -309.747412) (xy 183.505534 -309.741118)
			(xy 183.517651 -309.72268) (xy 183.519826 -309.711852) (xy 183.520334 -309.708042) (xy 183.520334 -309.701184)
			(xy 183.52008 -309.699406) (xy 183.519318 -309.675276) (xy 183.519318 -309.674768) (xy 183.51984 -309.649492)
			(xy 183.528161 -309.599628) (xy 183.544575 -309.551815) (xy 183.568635 -309.507355) (xy 183.599686 -309.467462)
			(xy 183.636878 -309.433224) (xy 183.679199 -309.405574) (xy 183.725494 -309.385267) (xy 183.7745 -309.372857)
			(xy 183.82488 -309.368683) (xy 183.87526 -309.372857) (xy 183.924266 -309.385267) (xy 183.970561 -309.405574)
			(xy 184.012882 -309.433224) (xy 184.050074 -309.467462) (xy 184.081125 -309.507355) (xy 184.105185 -309.551815)
			(xy 184.121599 -309.599628) (xy 184.12992 -309.649492) (xy 184.130442 -309.674768) (xy 184.129426 -309.700168)
			(xy 184.128156 -309.714392) (xy 184.140856 -309.739538) (xy 184.17667 -309.762144) (xy 184.176924 -309.762144)
			(xy 184.241948 -309.80253) (xy 184.270142 -309.802784) (xy 184.282588 -309.795672) (xy 184.319635 -309.774217)
			(xy 184.39684 -309.737207) (xy 184.436766 -309.721758) (xy 184.446231 -309.717688) (xy 184.461109 -309.703464)
			(xy 184.46923 -309.68455) (xy 184.469786 -309.67426) (xy 184.470297 -309.650296) (xy 184.47787 -309.60297)
			(xy 184.492745 -309.557407) (xy 184.514557 -309.514729) (xy 184.54277 -309.475984) (xy 184.57669 -309.442122)
			(xy 184.615485 -309.413977) (xy 184.658201 -309.39224) (xy 184.703789 -309.377445) (xy 184.75113 -309.369954)
			(xy 184.775094 -309.36946) (xy 184.799074 -309.369929) (xy 184.846444 -309.377426) (xy 184.892059 -309.392237)
			(xy 184.934797 -309.413998) (xy 184.973608 -309.442173) (xy 185.007537 -309.476069) (xy 185.035749 -309.514853)
			(xy 185.057551 -309.557571) (xy 185.072405 -309.603172) (xy 185.079948 -309.650535) (xy 185.080402 -309.674514)
			(xy 185.080402 -309.690516) (xy 185.098182 -309.71617) (xy 185.113422 -309.722012) (xy 185.15184 -309.736859)
			(xy 185.226237 -309.772214) (xy 185.262012 -309.792624) (xy 185.2676 -309.795926) (xy 185.281316 -309.799736)
			(xy 185.291674 -309.802075) (xy 185.312667 -309.799044) (xy 185.321956 -309.793894) (xy 185.409078 -309.739792)
			(xy 185.421778 -309.714646) (xy 185.420508 -309.700168) (xy 185.419492 -309.67553) (xy 185.419492 -309.674768)
			(xy 185.420014 -309.649492) (xy 185.428335 -309.599628) (xy 185.444749 -309.551815) (xy 185.468809 -309.507355)
			(xy 185.49986 -309.467462) (xy 185.537052 -309.433224) (xy 185.579373 -309.405574) (xy 185.625668 -309.385267)
			(xy 185.674674 -309.372857) (xy 185.725054 -309.368683) (xy 185.775434 -309.372857) (xy 185.82444 -309.385267)
			(xy 185.870735 -309.405574) (xy 185.913056 -309.433224) (xy 185.950248 -309.467462) (xy 185.981299 -309.507355)
			(xy 186.005359 -309.551815) (xy 186.021773 -309.599628) (xy 186.030094 -309.649492) (xy 186.030616 -309.674768)
			(xy 186.0296 -309.700168) (xy 186.02833 -309.714392) (xy 186.04103 -309.739538) (xy 186.076844 -309.762144)
			(xy 186.077098 -309.762144) (xy 186.142122 -309.80253) (xy 186.170316 -309.802784) (xy 186.182762 -309.795418)
			(xy 186.21976 -309.77405) (xy 186.296836 -309.737167) (xy 186.336686 -309.721758) (xy 186.346162 -309.717697)
			(xy 186.361064 -309.703479) (xy 186.369199 -309.684557) (xy 186.369706 -309.67426) (xy 186.370267 -309.649032)
			(xy 186.378646 -309.599275) (xy 186.395093 -309.551574) (xy 186.419158 -309.507225) (xy 186.450188 -309.467437)
			(xy 186.487338 -309.433292) (xy 186.529596 -309.405721) (xy 186.575812 -309.385473) (xy 186.624729 -309.373099)
			(xy 186.675014 -309.368937) (xy 186.725299 -309.373099) (xy 186.774216 -309.385473) (xy 186.820432 -309.405721)
			(xy 186.86269 -309.433292) (xy 186.89984 -309.467437) (xy 186.93087 -309.507225) (xy 186.954935 -309.551574)
			(xy 186.971382 -309.599275) (xy 186.979761 -309.649032) (xy 186.980322 -309.67426) (xy 186.980798 -309.684565)
			(xy 186.988917 -309.703507) (xy 187.003854 -309.717706) (xy 187.013342 -309.721758) (xy 187.05217 -309.736732)
			(xy 187.127334 -309.772467) (xy 187.163456 -309.793132) (xy 187.169806 -309.796942) (xy 187.182252 -309.800244)
			(xy 187.192473 -309.802363) (xy 187.213064 -309.799071) (xy 187.22213 -309.793894) (xy 187.296552 -309.747412)
			(xy 187.305628 -309.741118) (xy 187.317748 -309.722681) (xy 187.31992 -309.711852) (xy 187.320428 -309.708042)
			(xy 187.320428 -309.701184) (xy 187.320174 -309.699406) (xy 187.319412 -309.675276) (xy 187.319412 -309.674768)
			(xy 187.319934 -309.649492) (xy 187.328255 -309.599628) (xy 187.344669 -309.551815) (xy 187.368729 -309.507355)
			(xy 187.39978 -309.467462) (xy 187.436972 -309.433224) (xy 187.479293 -309.405574) (xy 187.525588 -309.385267)
			(xy 187.574594 -309.372857) (xy 187.624974 -309.368683) (xy 187.675354 -309.372857) (xy 187.72436 -309.385267)
			(xy 187.770655 -309.405574) (xy 187.812976 -309.433224) (xy 187.850168 -309.467462) (xy 187.881219 -309.507355)
			(xy 187.905279 -309.551815) (xy 187.921693 -309.599628) (xy 187.930014 -309.649492) (xy 187.930536 -309.674768)
			(xy 187.92952 -309.700168) (xy 187.92825 -309.714392) (xy 187.94095 -309.739538) (xy 187.976764 -309.762144)
			(xy 187.977018 -309.762144) (xy 188.042042 -309.80253) (xy 188.070236 -309.802784) (xy 188.082682 -309.795418)
			(xy 188.119681 -309.774051) (xy 188.196757 -309.737169) (xy 188.236606 -309.721758) (xy 188.246079 -309.717695)
			(xy 188.260975 -309.703475) (xy 188.269106 -309.684555) (xy 188.269626 -309.67426) (xy 188.270187 -309.649032)
			(xy 188.278566 -309.599275) (xy 188.295013 -309.551574) (xy 188.319078 -309.507225) (xy 188.350108 -309.467437)
			(xy 188.387258 -309.433292) (xy 188.429516 -309.405721) (xy 188.475732 -309.385473) (xy 188.524649 -309.373099)
			(xy 188.574934 -309.368937) (xy 188.625219 -309.373099) (xy 188.674136 -309.385473) (xy 188.720352 -309.405721)
			(xy 188.76261 -309.433292) (xy 188.79976 -309.467437) (xy 188.83079 -309.507225) (xy 188.854855 -309.551574)
			(xy 188.871302 -309.599275) (xy 188.879681 -309.649032) (xy 188.880242 -309.67426) (xy 188.880718 -309.684564)
			(xy 188.888839 -309.703503) (xy 188.903778 -309.717697) (xy 188.913262 -309.721758) (xy 188.95209 -309.736733)
			(xy 189.027253 -309.772469) (xy 189.063376 -309.793132) (xy 189.069726 -309.796942) (xy 189.082172 -309.800244)
			(xy 189.092393 -309.802359) (xy 189.112979 -309.79906) (xy 189.12205 -309.793894) (xy 189.196472 -309.747412)
			(xy 189.205546 -309.741116) (xy 189.21766 -309.722679) (xy 189.21984 -309.711852) (xy 189.220348 -309.708042)
			(xy 189.220348 -309.701184) (xy 189.220094 -309.699406) (xy 189.219332 -309.675276) (xy 189.219332 -309.674768)
			(xy 189.219805 -309.650758) (xy 189.227322 -309.603331) (xy 189.242164 -309.557663) (xy 189.263967 -309.514878)
			(xy 189.292195 -309.476031) (xy 189.326151 -309.442078) (xy 189.365001 -309.413854) (xy 189.407787 -309.392054)
			(xy 189.453456 -309.377215) (xy 189.500884 -309.369703) (xy 189.524894 -309.369206) (xy 189.539076 -309.369393)
			(xy 189.567315 -309.372068) (xy 189.581282 -309.37454) (xy 189.593728 -309.376826) (xy 189.61735 -309.36946)
			(xy 189.69482 -309.29199) (xy 189.702186 -309.268622) (xy 189.699646 -309.255922) (xy 189.69725 -309.242013)
			(xy 189.694709 -309.213901) (xy 189.694566 -309.199788) (xy 189.695053 -309.174965) (xy 189.703087 -309.125973)
			(xy 189.718941 -309.078926) (xy 189.742198 -309.035064) (xy 189.772244 -308.995542) (xy 189.808289 -308.961402)
			(xy 189.849382 -308.933543) (xy 189.894441 -308.912699) (xy 189.942279 -308.89942) (xy 189.991634 -308.894055)
			(xy 190.041208 -308.896745) (xy 190.089693 -308.907421) (xy 190.135812 -308.925799) (xy 190.17835 -308.951397)
			(xy 190.216187 -308.98354) (xy 190.248325 -309.021381) (xy 190.273918 -309.063922) (xy 190.292291 -309.110044)
			(xy 190.30296 -309.15853) (xy 190.305194 -309.199788) (xy 190.644284 -309.199788) (xy 190.648244 -309.150734)
			(xy 190.660021 -309.10295) (xy 190.679312 -309.057674) (xy 190.705615 -309.016078) (xy 190.73825 -308.979241)
			(xy 190.776371 -308.948116) (xy 190.818992 -308.923509) (xy 190.865008 -308.906057) (xy 190.913227 -308.896213)
			(xy 190.962402 -308.894232) (xy 191.011257 -308.900164) (xy 191.058528 -308.913856) (xy 191.10299 -308.934954)
			(xy 191.143493 -308.96291) (xy 191.178986 -308.997002) (xy 191.208551 -309.036346) (xy 191.231422 -309.079923)
			(xy 191.247006 -309.126604) (xy 191.254901 -309.175181) (xy 191.255396 -309.199788) (xy 191.594244 -309.199788)
			(xy 191.598204 -309.150734) (xy 191.609981 -309.10295) (xy 191.629272 -309.057674) (xy 191.655575 -309.016078)
			(xy 191.68821 -308.979241) (xy 191.726331 -308.948116) (xy 191.768952 -308.923509) (xy 191.814968 -308.906057)
			(xy 191.863187 -308.896213) (xy 191.912362 -308.894232) (xy 191.961217 -308.900164) (xy 192.008488 -308.913856)
			(xy 192.05295 -308.934954) (xy 192.093453 -308.96291) (xy 192.128946 -308.997002) (xy 192.158511 -309.036346)
			(xy 192.181382 -309.079923) (xy 192.196966 -309.126604) (xy 192.204861 -309.175181) (xy 192.205356 -309.199788)
			(xy 192.204861 -309.224395) (xy 192.204682 -309.225496) (xy 192.52336 -309.225496) (xy 192.52336 -309.17408)
			(xy 192.531403 -309.123298) (xy 192.547291 -309.074399) (xy 192.570634 -309.028587) (xy 192.600855 -308.986991)
			(xy 192.637211 -308.950635) (xy 192.678807 -308.920414) (xy 192.724619 -308.897071) (xy 192.773518 -308.881183)
			(xy 192.8243 -308.87314) (xy 192.875716 -308.87314) (xy 192.926498 -308.881183) (xy 192.975397 -308.897071)
			(xy 193.021209 -308.920414) (xy 193.062805 -308.950635) (xy 193.099161 -308.986991) (xy 193.129382 -309.028587)
			(xy 193.152725 -309.074399) (xy 193.168613 -309.123298) (xy 193.176656 -309.17408) (xy 193.17716 -309.199788)
			(xy 193.176656 -309.225496) (xy 193.47332 -309.225496) (xy 193.47332 -309.17408) (xy 193.481363 -309.123298)
			(xy 193.497251 -309.074399) (xy 193.520594 -309.028587) (xy 193.550815 -308.986991) (xy 193.587171 -308.950635)
			(xy 193.628767 -308.920414) (xy 193.674579 -308.897071) (xy 193.723478 -308.881183) (xy 193.77426 -308.87314)
			(xy 193.825676 -308.87314) (xy 193.876458 -308.881183) (xy 193.925357 -308.897071) (xy 193.971169 -308.920414)
			(xy 194.012765 -308.950635) (xy 194.049121 -308.986991) (xy 194.079342 -309.028587) (xy 194.102685 -309.074399)
			(xy 194.118573 -309.123298) (xy 194.126616 -309.17408) (xy 194.12712 -309.199788) (xy 194.444124 -309.199788)
			(xy 194.448084 -309.150734) (xy 194.459861 -309.10295) (xy 194.479152 -309.057674) (xy 194.505455 -309.016078)
			(xy 194.53809 -308.979241) (xy 194.576211 -308.948116) (xy 194.618832 -308.923509) (xy 194.664848 -308.906057)
			(xy 194.713067 -308.896213) (xy 194.762242 -308.894232) (xy 194.811097 -308.900164) (xy 194.858368 -308.913856)
			(xy 194.90283 -308.934954) (xy 194.943333 -308.96291) (xy 194.978826 -308.997002) (xy 195.008391 -309.036346)
			(xy 195.031262 -309.079923) (xy 195.046846 -309.126604) (xy 195.054741 -309.175181) (xy 195.055236 -309.199788)
			(xy 195.054741 -309.224395) (xy 195.054562 -309.225496) (xy 195.37324 -309.225496) (xy 195.37324 -309.17408)
			(xy 195.381283 -309.123298) (xy 195.397171 -309.074399) (xy 195.420514 -309.028587) (xy 195.450735 -308.986991)
			(xy 195.487091 -308.950635) (xy 195.528687 -308.920414) (xy 195.574499 -308.897071) (xy 195.623398 -308.881183)
			(xy 195.67418 -308.87314) (xy 195.725596 -308.87314) (xy 195.776378 -308.881183) (xy 195.825277 -308.897071)
			(xy 195.871089 -308.920414) (xy 195.912685 -308.950635) (xy 195.949041 -308.986991) (xy 195.979262 -309.028587)
			(xy 196.002605 -309.074399) (xy 196.018493 -309.123298) (xy 196.026536 -309.17408) (xy 196.02704 -309.199788)
			(xy 196.026536 -309.225496) (xy 196.3232 -309.225496) (xy 196.3232 -309.17408) (xy 196.331243 -309.123298)
			(xy 196.347131 -309.074399) (xy 196.370474 -309.028587) (xy 196.400695 -308.986991) (xy 196.437051 -308.950635)
			(xy 196.478647 -308.920414) (xy 196.524459 -308.897071) (xy 196.573358 -308.881183) (xy 196.62414 -308.87314)
			(xy 196.675556 -308.87314) (xy 196.726338 -308.881183) (xy 196.775237 -308.897071) (xy 196.821049 -308.920414)
			(xy 196.862645 -308.950635) (xy 196.899001 -308.986991) (xy 196.929222 -309.028587) (xy 196.952565 -309.074399)
			(xy 196.968453 -309.123298) (xy 196.976496 -309.17408) (xy 196.977 -309.199788) (xy 197.294258 -309.199788)
			(xy 197.298218 -309.150734) (xy 197.309995 -309.10295) (xy 197.329286 -309.057674) (xy 197.355589 -309.016078)
			(xy 197.388224 -308.979241) (xy 197.426345 -308.948116) (xy 197.468966 -308.923509) (xy 197.514982 -308.906057)
			(xy 197.563201 -308.896213) (xy 197.612376 -308.894232) (xy 197.661231 -308.900164) (xy 197.708502 -308.913856)
			(xy 197.752964 -308.934954) (xy 197.793467 -308.96291) (xy 197.82896 -308.997002) (xy 197.858525 -309.036346)
			(xy 197.881396 -309.079923) (xy 197.89698 -309.126604) (xy 197.904875 -309.175181) (xy 197.90537 -309.199788)
			(xy 198.244218 -309.199788) (xy 198.248178 -309.150734) (xy 198.259955 -309.10295) (xy 198.279246 -309.057674)
			(xy 198.305549 -309.016078) (xy 198.338184 -308.979241) (xy 198.376305 -308.948116) (xy 198.418926 -308.923509)
			(xy 198.464942 -308.906057) (xy 198.513161 -308.896213) (xy 198.562336 -308.894232) (xy 198.611191 -308.900164)
			(xy 198.658462 -308.913856) (xy 198.702924 -308.934954) (xy 198.743427 -308.96291) (xy 198.77892 -308.997002)
			(xy 198.808485 -309.036346) (xy 198.831356 -309.079923) (xy 198.84694 -309.126604) (xy 198.854835 -309.175181)
			(xy 198.85533 -309.199788) (xy 198.854835 -309.224395) (xy 198.84694 -309.272972) (xy 198.831356 -309.319653)
			(xy 198.808485 -309.36323) (xy 198.800515 -309.373836) (xy 204.602097 -309.373836) (xy 204.602099 -309.319337)
			(xy 204.609857 -309.265393) (xy 204.625213 -309.213102) (xy 204.647854 -309.163529) (xy 204.67732 -309.117682)
			(xy 204.71301 -309.076496) (xy 204.754198 -309.040808) (xy 204.800047 -309.011344) (xy 204.849621 -308.988706)
			(xy 204.901913 -308.973353) (xy 204.955857 -308.965598) (xy 205.010356 -308.965599) (xy 205.0643 -308.973356)
			(xy 205.116591 -308.98871) (xy 205.166165 -309.011351) (xy 205.212012 -309.040816) (xy 205.253199 -309.076505)
			(xy 205.288888 -309.117693) (xy 205.318352 -309.163541) (xy 205.340992 -309.213115) (xy 205.356346 -309.265406)
			(xy 205.364102 -309.319351) (xy 205.364588 -309.3466) (xy 205.36408 -309.365904) (xy 205.363572 -309.376826)
			(xy 205.371192 -309.396638) (xy 205.44028 -309.465472) (xy 205.460346 -309.473092) (xy 205.471268 -309.47233)
			(xy 205.492858 -309.471822) (xy 205.520114 -309.47221) (xy 205.574072 -309.479962) (xy 205.626378 -309.495314)
			(xy 205.675966 -309.517954) (xy 205.721828 -309.547421) (xy 205.763029 -309.583114) (xy 205.798731 -309.624308)
			(xy 205.828208 -309.670163) (xy 205.837505 -309.690516) (xy 209.57743 -309.690516) (xy 209.581501 -309.634894)
			(xy 209.593627 -309.580457) (xy 209.61355 -309.528366) (xy 209.640846 -309.479731) (xy 209.674932 -309.435588)
			(xy 209.715081 -309.396879) (xy 209.760439 -309.364428) (xy 209.810039 -309.338927) (xy 209.862823 -309.32092)
			(xy 209.917666 -309.31079) (xy 209.9734 -309.308753) (xy 210.028837 -309.314853) (xy 210.082794 -309.328959)
			(xy 210.134123 -309.350771) (xy 210.181729 -309.379825) (xy 210.224597 -309.4155) (xy 210.261814 -309.457037)
			(xy 210.292587 -309.50355) (xy 210.316259 -309.554047) (xy 210.332327 -309.607454) (xy 210.340447 -309.66263)
			(xy 210.340956 -309.690516) (xy 210.340447 -309.718402) (xy 210.332327 -309.773578) (xy 210.316259 -309.826985)
			(xy 210.292587 -309.877482) (xy 210.261814 -309.923995) (xy 210.224597 -309.965532) (xy 210.181729 -310.001207)
			(xy 210.134123 -310.030261) (xy 210.082794 -310.052073) (xy 210.028837 -310.066179) (xy 209.9734 -310.072279)
			(xy 209.917666 -310.070242) (xy 209.862823 -310.060112) (xy 209.810039 -310.042105) (xy 209.760439 -310.016604)
			(xy 209.715081 -309.984153) (xy 209.674932 -309.945444) (xy 209.640846 -309.901301) (xy 209.61355 -309.852666)
			(xy 209.593627 -309.800575) (xy 209.581501 -309.746138) (xy 209.57743 -309.690516) (xy 205.837505 -309.690516)
			(xy 205.850858 -309.719747) (xy 205.866221 -309.772049) (xy 205.873984 -309.826006) (xy 205.87399 -309.880518)
			(xy 205.866237 -309.934476) (xy 205.850884 -309.986782) (xy 205.828244 -310.03637) (xy 205.798777 -310.082231)
			(xy 205.763083 -310.123432) (xy 205.721889 -310.159134) (xy 205.676033 -310.18861) (xy 205.626449 -310.211259)
			(xy 205.574147 -310.226622) (xy 205.52019 -310.234385) (xy 205.465678 -310.234389) (xy 205.41172 -310.226636)
			(xy 205.359415 -310.211283) (xy 205.309827 -310.188642) (xy 205.263966 -310.159175) (xy 205.222765 -310.12348)
			(xy 205.187064 -310.082286) (xy 205.157589 -310.03643) (xy 205.134939 -309.986845) (xy 205.119577 -309.934543)
			(xy 205.111815 -309.880586) (xy 205.11135 -309.85333) (xy 205.111858 -309.834026) (xy 205.112366 -309.823104)
			(xy 205.104746 -309.803292) (xy 205.035658 -309.734458) (xy 205.015592 -309.726838) (xy 205.00467 -309.7276)
			(xy 204.98308 -309.728108) (xy 204.955831 -309.7276) (xy 204.901887 -309.719842) (xy 204.849596 -309.704485)
			(xy 204.800023 -309.681843) (xy 204.754177 -309.652376) (xy 204.712991 -309.616685) (xy 204.677304 -309.575496)
			(xy 204.647841 -309.529648) (xy 204.625203 -309.480073) (xy 204.609851 -309.427781) (xy 204.602097 -309.373836)
			(xy 198.800515 -309.373836) (xy 198.77892 -309.402574) (xy 198.743427 -309.436666) (xy 198.702924 -309.464622)
			(xy 198.658462 -309.48572) (xy 198.611191 -309.499412) (xy 198.562336 -309.505344) (xy 198.513161 -309.503363)
			(xy 198.464942 -309.493519) (xy 198.418926 -309.476067) (xy 198.376305 -309.45146) (xy 198.338184 -309.420335)
			(xy 198.305549 -309.383498) (xy 198.279246 -309.341902) (xy 198.259955 -309.296626) (xy 198.248178 -309.248842)
			(xy 198.244218 -309.199788) (xy 197.90537 -309.199788) (xy 197.904875 -309.224395) (xy 197.89698 -309.272972)
			(xy 197.881396 -309.319653) (xy 197.858525 -309.36323) (xy 197.82896 -309.402574) (xy 197.793467 -309.436666)
			(xy 197.752964 -309.464622) (xy 197.708502 -309.48572) (xy 197.661231 -309.499412) (xy 197.612376 -309.505344)
			(xy 197.563201 -309.503363) (xy 197.514982 -309.493519) (xy 197.468966 -309.476067) (xy 197.426345 -309.45146)
			(xy 197.388224 -309.420335) (xy 197.355589 -309.383498) (xy 197.329286 -309.341902) (xy 197.309995 -309.296626)
			(xy 197.298218 -309.248842) (xy 197.294258 -309.199788) (xy 196.977 -309.199788) (xy 196.976496 -309.225496)
			(xy 196.968453 -309.276278) (xy 196.952565 -309.325177) (xy 196.929222 -309.370989) (xy 196.899001 -309.412585)
			(xy 196.862645 -309.448941) (xy 196.821049 -309.479162) (xy 196.775237 -309.502505) (xy 196.726338 -309.518393)
			(xy 196.675556 -309.526436) (xy 196.62414 -309.526436) (xy 196.573358 -309.518393) (xy 196.524459 -309.502505)
			(xy 196.478647 -309.479162) (xy 196.437051 -309.448941) (xy 196.400695 -309.412585) (xy 196.370474 -309.370989)
			(xy 196.347131 -309.325177) (xy 196.331243 -309.276278) (xy 196.3232 -309.225496) (xy 196.026536 -309.225496)
			(xy 196.018493 -309.276278) (xy 196.002605 -309.325177) (xy 195.979262 -309.370989) (xy 195.949041 -309.412585)
			(xy 195.912685 -309.448941) (xy 195.871089 -309.479162) (xy 195.825277 -309.502505) (xy 195.776378 -309.518393)
			(xy 195.725596 -309.526436) (xy 195.67418 -309.526436) (xy 195.623398 -309.518393) (xy 195.574499 -309.502505)
			(xy 195.528687 -309.479162) (xy 195.487091 -309.448941) (xy 195.450735 -309.412585) (xy 195.420514 -309.370989)
			(xy 195.397171 -309.325177) (xy 195.381283 -309.276278) (xy 195.37324 -309.225496) (xy 195.054562 -309.225496)
			(xy 195.046846 -309.272972) (xy 195.031262 -309.319653) (xy 195.008391 -309.36323) (xy 194.978826 -309.402574)
			(xy 194.943333 -309.436666) (xy 194.90283 -309.464622) (xy 194.858368 -309.48572) (xy 194.811097 -309.499412)
			(xy 194.762242 -309.505344) (xy 194.713067 -309.503363) (xy 194.664848 -309.493519) (xy 194.618832 -309.476067)
			(xy 194.576211 -309.45146) (xy 194.53809 -309.420335) (xy 194.505455 -309.383498) (xy 194.479152 -309.341902)
			(xy 194.459861 -309.296626) (xy 194.448084 -309.248842) (xy 194.444124 -309.199788) (xy 194.12712 -309.199788)
			(xy 194.126616 -309.225496) (xy 194.118573 -309.276278) (xy 194.102685 -309.325177) (xy 194.079342 -309.370989)
			(xy 194.049121 -309.412585) (xy 194.012765 -309.448941) (xy 193.971169 -309.479162) (xy 193.925357 -309.502505)
			(xy 193.876458 -309.518393) (xy 193.825676 -309.526436) (xy 193.77426 -309.526436) (xy 193.723478 -309.518393)
			(xy 193.674579 -309.502505) (xy 193.628767 -309.479162) (xy 193.587171 -309.448941) (xy 193.550815 -309.412585)
			(xy 193.520594 -309.370989) (xy 193.497251 -309.325177) (xy 193.481363 -309.276278) (xy 193.47332 -309.225496)
			(xy 193.176656 -309.225496) (xy 193.168613 -309.276278) (xy 193.152725 -309.325177) (xy 193.129382 -309.370989)
			(xy 193.099161 -309.412585) (xy 193.062805 -309.448941) (xy 193.021209 -309.479162) (xy 192.975397 -309.502505)
			(xy 192.926498 -309.518393) (xy 192.875716 -309.526436) (xy 192.8243 -309.526436) (xy 192.773518 -309.518393)
			(xy 192.724619 -309.502505) (xy 192.678807 -309.479162) (xy 192.637211 -309.448941) (xy 192.600855 -309.412585)
			(xy 192.570634 -309.370989) (xy 192.547291 -309.325177) (xy 192.531403 -309.276278) (xy 192.52336 -309.225496)
			(xy 192.204682 -309.225496) (xy 192.196966 -309.272972) (xy 192.181382 -309.319653) (xy 192.158511 -309.36323)
			(xy 192.128946 -309.402574) (xy 192.093453 -309.436666) (xy 192.05295 -309.464622) (xy 192.008488 -309.48572)
			(xy 191.961217 -309.499412) (xy 191.912362 -309.505344) (xy 191.863187 -309.503363) (xy 191.814968 -309.493519)
			(xy 191.768952 -309.476067) (xy 191.726331 -309.45146) (xy 191.68821 -309.420335) (xy 191.655575 -309.383498)
			(xy 191.629272 -309.341902) (xy 191.609981 -309.296626) (xy 191.598204 -309.248842) (xy 191.594244 -309.199788)
			(xy 191.255396 -309.199788) (xy 191.254901 -309.224395) (xy 191.247006 -309.272972) (xy 191.231422 -309.319653)
			(xy 191.208551 -309.36323) (xy 191.178986 -309.402574) (xy 191.143493 -309.436666) (xy 191.10299 -309.464622)
			(xy 191.058528 -309.48572) (xy 191.011257 -309.499412) (xy 190.962402 -309.505344) (xy 190.913227 -309.503363)
			(xy 190.865008 -309.493519) (xy 190.818992 -309.476067) (xy 190.776371 -309.45146) (xy 190.73825 -309.420335)
			(xy 190.705615 -309.383498) (xy 190.679312 -309.341902) (xy 190.660021 -309.296626) (xy 190.648244 -309.248842)
			(xy 190.644284 -309.199788) (xy 190.305194 -309.199788) (xy 190.305644 -309.208104) (xy 190.300273 -309.257459)
			(xy 190.286988 -309.305295) (xy 190.266138 -309.350351) (xy 190.238274 -309.391441) (xy 190.20413 -309.427481)
			(xy 190.164604 -309.457523) (xy 190.120739 -309.480774) (xy 190.07369 -309.496622) (xy 190.024697 -309.50465)
			(xy 189.999874 -309.505096) (xy 189.98576 -309.504975) (xy 189.957646 -309.502432) (xy 189.94374 -309.500016)
			(xy 189.93104 -309.497476) (xy 189.907672 -309.504842) (xy 189.830202 -309.582312) (xy 189.822836 -309.605934)
			(xy 189.825122 -309.61838) (xy 189.827604 -309.632345) (xy 189.830274 -309.660585) (xy 189.830456 -309.674768)
			(xy 189.83027 -309.68895) (xy 189.827597 -309.71719) (xy 189.825122 -309.731156) (xy 189.822836 -309.743602)
			(xy 189.830202 -309.767224) (xy 189.907672 -309.844694) (xy 189.93104 -309.85206) (xy 189.94374 -309.84952)
			(xy 189.957649 -309.847122) (xy 189.985761 -309.844578) (xy 189.999874 -309.84444) (xy 190.023867 -309.844884)
			(xy 190.071263 -309.852388) (xy 190.116901 -309.867215) (xy 190.159657 -309.889) (xy 190.198479 -309.917206)
			(xy 190.232409 -309.951138) (xy 190.260612 -309.989962) (xy 190.282393 -310.032719) (xy 190.297217 -310.078358)
			(xy 190.304717 -310.125755) (xy 190.305182 -310.149748) (xy 190.305136 -310.158785) (xy 190.304121 -310.176831)
			(xy 190.30315 -310.185816) (xy 190.301626 -310.197754) (xy 190.3095 -310.220106) (xy 190.385954 -310.293004)
			(xy 190.40856 -310.299862) (xy 190.420752 -310.29783) (xy 190.441834 -310.295036) (xy 190.447168 -310.295036)
			(xy 190.451994 -310.294274) (xy 190.471403 -310.293167) (xy 190.510238 -310.294953) (xy 190.529464 -310.29783)
			(xy 190.541402 -310.299862) (xy 190.564008 -310.293004) (xy 190.640462 -310.220106) (xy 190.648336 -310.197754)
			(xy 190.646812 -310.185816) (xy 190.64583 -310.176832) (xy 190.644814 -310.158786) (xy 190.64478 -310.149748)
			(xy 190.645302 -310.124493) (xy 190.653615 -310.074671) (xy 190.670016 -310.026897) (xy 190.694057 -309.982474)
			(xy 190.725081 -309.942614) (xy 190.762243 -309.908404) (xy 190.804529 -309.880778) (xy 190.850785 -309.860488)
			(xy 190.89975 -309.848088) (xy 190.950088 -309.843917) (xy 191.000426 -309.848088) (xy 191.049391 -309.860488)
			(xy 191.095647 -309.880778) (xy 191.137933 -309.908404) (xy 191.175095 -309.942614) (xy 191.206119 -309.982474)
			(xy 191.23016 -310.026897) (xy 191.246561 -310.074671) (xy 191.254874 -310.124493) (xy 191.255396 -310.149748)
			(xy 191.255274 -310.163862) (xy 191.252729 -310.191975) (xy 191.250316 -310.205882) (xy 191.247776 -310.218328)
			(xy 191.255142 -310.24195) (xy 191.332612 -310.31942) (xy 191.356234 -310.326532) (xy 191.36868 -310.324246)
			(xy 191.396688 -310.319623) (xy 191.453448 -310.319623) (xy 191.481456 -310.324246) (xy 191.493902 -310.326532)
			(xy 191.517524 -310.31942) (xy 191.594994 -310.24195) (xy 191.60236 -310.218328) (xy 191.59982 -310.205882)
			(xy 191.597421 -310.191973) (xy 191.594875 -310.163862) (xy 191.59474 -310.149748) (xy 191.595262 -310.124493)
			(xy 191.603575 -310.074671) (xy 191.619976 -310.026897) (xy 191.644017 -309.982474) (xy 191.675041 -309.942614)
			(xy 191.712203 -309.908404) (xy 191.754489 -309.880778) (xy 191.800745 -309.860488) (xy 191.84971 -309.848088)
			(xy 191.900048 -309.843917) (xy 191.950386 -309.848088) (xy 191.999351 -309.860488) (xy 192.045607 -309.880778)
			(xy 192.087893 -309.908404) (xy 192.125055 -309.942614) (xy 192.156079 -309.982474) (xy 192.18012 -310.026897)
			(xy 192.196521 -310.074671) (xy 192.204834 -310.124493) (xy 192.205356 -310.149748) (xy 192.205315 -310.158722)
			(xy 192.204298 -310.176641) (xy 192.203324 -310.185562) (xy 192.2018 -310.197754) (xy 192.209928 -310.220106)
			(xy 192.286128 -310.293004) (xy 192.308734 -310.299862) (xy 192.320672 -310.29783) (xy 192.341754 -310.295036)
			(xy 192.347088 -310.295036) (xy 192.351914 -310.294274) (xy 192.371323 -310.293169) (xy 192.410157 -310.294956)
			(xy 192.429384 -310.29783) (xy 192.441322 -310.299862) (xy 192.463928 -310.293004) (xy 192.540382 -310.220106)
			(xy 192.548256 -310.197754) (xy 192.546732 -310.185816) (xy 192.54575 -310.176832) (xy 192.544734 -310.158786)
			(xy 192.5447 -310.149748) (xy 192.545222 -310.124493) (xy 192.553535 -310.074671) (xy 192.569936 -310.026897)
			(xy 192.593977 -309.982474) (xy 192.625001 -309.942614) (xy 192.662163 -309.908404) (xy 192.704449 -309.880778)
			(xy 192.750705 -309.860488) (xy 192.79967 -309.848088) (xy 192.850008 -309.843917) (xy 192.900346 -309.848088)
			(xy 192.949311 -309.860488) (xy 192.995567 -309.880778) (xy 193.037853 -309.908404) (xy 193.075015 -309.942614)
			(xy 193.106039 -309.982474) (xy 193.13008 -310.026897) (xy 193.146481 -310.074671) (xy 193.154794 -310.124493)
			(xy 193.155316 -310.149748) (xy 193.155194 -310.163862) (xy 193.15265 -310.191975) (xy 193.150236 -310.205882)
			(xy 193.147696 -310.218328) (xy 193.155062 -310.24195) (xy 193.232532 -310.31942) (xy 193.256154 -310.326532)
			(xy 193.2686 -310.324246) (xy 193.296608 -310.319623) (xy 193.353368 -310.319623) (xy 193.381376 -310.324246)
			(xy 193.393822 -310.326532) (xy 193.417444 -310.31942) (xy 193.494914 -310.24195) (xy 193.50228 -310.218328)
			(xy 193.49974 -310.205882) (xy 193.497341 -310.191973) (xy 193.494795 -310.163862) (xy 193.49466 -310.149748)
			(xy 193.495182 -310.124493) (xy 193.503495 -310.074671) (xy 193.519896 -310.026897) (xy 193.543937 -309.982474)
			(xy 193.574961 -309.942614) (xy 193.612123 -309.908404) (xy 193.654409 -309.880778) (xy 193.700665 -309.860488)
			(xy 193.74963 -309.848088) (xy 193.799968 -309.843917) (xy 193.850306 -309.848088) (xy 193.899271 -309.860488)
			(xy 193.945527 -309.880778) (xy 193.987813 -309.908404) (xy 194.024975 -309.942614) (xy 194.055999 -309.982474)
			(xy 194.08004 -310.026897) (xy 194.096441 -310.074671) (xy 194.104754 -310.124493) (xy 194.105276 -310.149748)
			(xy 194.105235 -310.158722) (xy 194.104219 -310.176641) (xy 194.103244 -310.185562) (xy 194.10172 -310.197754)
			(xy 194.109848 -310.220106) (xy 194.186048 -310.293004) (xy 194.208654 -310.299862) (xy 194.220592 -310.29783)
			(xy 194.241674 -310.295036) (xy 194.247008 -310.295036) (xy 194.251834 -310.294274) (xy 194.271243 -310.293164)
			(xy 194.310079 -310.294942) (xy 194.329304 -310.29783) (xy 194.341242 -310.299862) (xy 194.363848 -310.293004)
			(xy 194.440302 -310.220106) (xy 194.448176 -310.197754) (xy 194.446652 -310.185816) (xy 194.44567 -310.176832)
			(xy 194.444653 -310.158786) (xy 194.44462 -310.149748) (xy 194.445142 -310.124493) (xy 194.453455 -310.074671)
			(xy 194.469856 -310.026897) (xy 194.493897 -309.982474) (xy 194.524921 -309.942614) (xy 194.562083 -309.908404)
			(xy 194.604369 -309.880778) (xy 194.650625 -309.860488) (xy 194.69959 -309.848088) (xy 194.749928 -309.843917)
			(xy 194.800266 -309.848088) (xy 194.849231 -309.860488) (xy 194.895487 -309.880778) (xy 194.937773 -309.908404)
			(xy 194.974935 -309.942614) (xy 195.005959 -309.982474) (xy 195.03 -310.026897) (xy 195.046401 -310.074671)
			(xy 195.054714 -310.124493) (xy 195.055236 -310.149748) (xy 195.055114 -310.163862) (xy 195.05257 -310.191975)
			(xy 195.050156 -310.205882) (xy 195.047616 -310.218328) (xy 195.054982 -310.24195) (xy 195.132452 -310.31942)
			(xy 195.156074 -310.326532) (xy 195.16852 -310.324246) (xy 195.196528 -310.319623) (xy 195.253288 -310.319623)
			(xy 195.281296 -310.324246) (xy 195.293742 -310.326532) (xy 195.317364 -310.31942) (xy 195.394834 -310.24195)
			(xy 195.4022 -310.218328) (xy 195.39966 -310.205882) (xy 195.397261 -310.191973) (xy 195.394715 -310.163862)
			(xy 195.39458 -310.149748) (xy 195.395102 -310.124493) (xy 195.403415 -310.074671) (xy 195.419816 -310.026897)
			(xy 195.443857 -309.982474) (xy 195.474881 -309.942614) (xy 195.512043 -309.908404) (xy 195.554329 -309.880778)
			(xy 195.600585 -309.860488) (xy 195.64955 -309.848088) (xy 195.699888 -309.843917) (xy 195.750226 -309.848088)
			(xy 195.799191 -309.860488) (xy 195.845447 -309.880778) (xy 195.887733 -309.908404) (xy 195.924895 -309.942614)
			(xy 195.955919 -309.982474) (xy 195.97996 -310.026897) (xy 195.996361 -310.074671) (xy 196.004674 -310.124493)
			(xy 196.005196 -310.149748) (xy 196.005155 -310.158722) (xy 196.004139 -310.176641) (xy 196.003164 -310.185562)
			(xy 196.00164 -310.197754) (xy 196.009768 -310.220106) (xy 196.085968 -310.293004) (xy 196.108574 -310.299862)
			(xy 196.120512 -310.29783) (xy 196.141594 -310.295036) (xy 196.146928 -310.295036) (xy 196.151754 -310.294274)
			(xy 196.171163 -310.293165) (xy 196.209999 -310.294946) (xy 196.229224 -310.29783) (xy 196.241162 -310.299862)
			(xy 196.263768 -310.293004) (xy 196.340222 -310.220106) (xy 196.348096 -310.197754) (xy 196.346572 -310.185816)
			(xy 196.34559 -310.176832) (xy 196.344573 -310.158786) (xy 196.34454 -310.149748) (xy 196.345062 -310.124493)
			(xy 196.353375 -310.074671) (xy 196.369776 -310.026897) (xy 196.393817 -309.982474) (xy 196.424841 -309.942614)
			(xy 196.462003 -309.908404) (xy 196.504289 -309.880778) (xy 196.550545 -309.860488) (xy 196.59951 -309.848088)
			(xy 196.649848 -309.843917) (xy 196.700186 -309.848088) (xy 196.749151 -309.860488) (xy 196.795407 -309.880778)
			(xy 196.837693 -309.908404) (xy 196.874855 -309.942614) (xy 196.905879 -309.982474) (xy 196.92992 -310.026897)
			(xy 196.946321 -310.074671) (xy 196.954634 -310.124493) (xy 196.955156 -310.149748) (xy 196.955034 -310.163862)
			(xy 196.95249 -310.191975) (xy 196.950076 -310.205882) (xy 196.947536 -310.218328) (xy 196.954902 -310.24195)
			(xy 197.032372 -310.31942) (xy 197.055994 -310.326786) (xy 197.068694 -310.324246) (xy 197.092432 -310.320288)
			(xy 197.140538 -310.319008) (xy 197.164452 -310.321706) (xy 197.17639 -310.32323) (xy 197.198996 -310.315102)
			(xy 197.272402 -310.238902) (xy 197.279514 -310.216042) (xy 197.277482 -310.204104) (xy 197.275398 -310.190613)
			(xy 197.273232 -310.163399) (xy 197.273164 -310.149748) (xy 197.273668 -310.12406) (xy 197.281705 -310.073317)
			(xy 197.297581 -310.024456) (xy 197.320905 -309.97868) (xy 197.351102 -309.937116) (xy 197.38743 -309.900788)
			(xy 197.428994 -309.870591) (xy 197.47477 -309.847267) (xy 197.523631 -309.831391) (xy 197.574374 -309.823354)
			(xy 197.62575 -309.823354) (xy 197.676493 -309.831391) (xy 197.725354 -309.847267) (xy 197.77113 -309.870591)
			(xy 197.812694 -309.900788) (xy 197.849022 -309.937116) (xy 197.879219 -309.97868) (xy 197.902543 -310.024456)
			(xy 197.918419 -310.073317) (xy 197.926456 -310.12406) (xy 197.92696 -310.149748) (xy 197.92683 -310.163467)
			(xy 197.924539 -310.190808) (xy 197.922388 -310.204358) (xy 197.920356 -310.21655) (xy 197.927468 -310.23941)
			(xy 198.000874 -310.315864) (xy 198.023734 -310.323738) (xy 198.035672 -310.322214) (xy 198.055295 -310.319976)
			(xy 198.094789 -310.319976) (xy 198.114412 -310.322214) (xy 198.12635 -310.323738) (xy 198.14921 -310.315864)
			(xy 198.222616 -310.23941) (xy 198.229728 -310.21655) (xy 198.227696 -310.204358) (xy 198.225557 -310.190807)
			(xy 198.223266 -310.163466) (xy 198.223124 -310.149748) (xy 198.223628 -310.12406) (xy 198.231665 -310.073317)
			(xy 198.247541 -310.024456) (xy 198.270865 -309.97868) (xy 198.301062 -309.937116) (xy 198.33739 -309.900788)
			(xy 198.378954 -309.870591) (xy 198.42473 -309.847267) (xy 198.473591 -309.831391) (xy 198.524334 -309.823354)
			(xy 198.57571 -309.823354) (xy 198.626453 -309.831391) (xy 198.675314 -309.847267) (xy 198.72109 -309.870591)
			(xy 198.762654 -309.900788) (xy 198.798982 -309.937116) (xy 198.829179 -309.97868) (xy 198.852503 -310.024456)
			(xy 198.868379 -310.073317) (xy 198.876416 -310.12406) (xy 198.87692 -310.149748) (xy 198.87679 -310.163467)
			(xy 198.874499 -310.190808) (xy 198.872348 -310.204358) (xy 198.870316 -310.21655) (xy 198.877428 -310.23941)
			(xy 198.950834 -310.315864) (xy 198.973694 -310.323738) (xy 198.985632 -310.322214) (xy 199.009618 -310.31958)
			(xy 199.057851 -310.320987) (xy 199.081644 -310.325008) (xy 199.093836 -310.327294) (xy 199.117966 -310.319928)
			(xy 199.195182 -310.242712) (xy 199.202548 -310.218582) (xy 199.200262 -310.20639) (xy 199.197762 -310.192363)
			(xy 199.19509 -310.163995) (xy 199.194928 -310.149748) (xy 199.19541 -310.12493) (xy 199.203432 -310.075946)
			(xy 199.219274 -310.028906) (xy 199.242518 -309.985048) (xy 199.27255 -309.945528) (xy 199.308581 -309.911388)
			(xy 199.34966 -309.883527) (xy 199.394706 -309.862678) (xy 199.442531 -309.849392) (xy 199.491875 -309.844018)
			(xy 199.541439 -309.846698) (xy 199.589916 -309.857362) (xy 199.63603 -309.875728) (xy 199.678565 -309.901312)
			(xy 199.7164 -309.933441) (xy 199.748539 -309.971267) (xy 199.774135 -310.013795) (xy 199.792513 -310.059903)
			(xy 199.80319 -310.108378) (xy 199.805884 -310.157941) (xy 199.800524 -310.207287) (xy 199.787251 -310.255116)
			(xy 199.766415 -310.300167) (xy 199.738565 -310.341254) (xy 199.704434 -310.377294) (xy 199.664923 -310.407337)
			(xy 199.621072 -310.430593) (xy 199.574036 -310.446447) (xy 199.525054 -310.454483) (xy 199.500236 -310.455056)
			(xy 199.486053 -310.454871) (xy 199.457813 -310.452201) (xy 199.443848 -310.449722) (xy 199.431402 -310.447436)
			(xy 199.407272 -310.454802) (xy 199.33031 -310.532018) (xy 199.32269 -310.556148) (xy 199.32523 -310.56834)
			(xy 199.328532 -310.5912) (xy 199.328532 -310.591454) (xy 199.329994 -310.600631) (xy 199.33855 -310.61711)
			(xy 199.352426 -310.629448) (xy 199.369793 -310.636017) (xy 199.379078 -310.636412) (xy 205.903322 -310.636412)
			(xy 205.913633 -310.635944) (xy 205.932592 -310.627835) (xy 205.946812 -310.612902) (xy 205.95082 -310.603392)
			(xy 205.952598 -310.598312) (xy 205.95336 -310.595518) (xy 205.960288 -310.568941) (xy 205.980726 -310.517965)
			(xy 206.00825 -310.470438) (xy 206.042294 -310.427342) (xy 206.082157 -310.389562) (xy 206.127016 -310.357877)
			(xy 206.17595 -310.33294) (xy 206.227949 -310.315263) (xy 206.254858 -310.309768) (xy 206.280934 -310.305366)
			(xy 206.33376 -310.302946) (xy 206.386414 -310.307839) (xy 206.437889 -310.319952) (xy 206.4872 -310.339054)
			(xy 206.533403 -310.364777) (xy 206.575614 -310.396631) (xy 206.613025 -310.434006) (xy 206.64492 -310.476186)
			(xy 206.670689 -310.522364) (xy 206.689838 -310.571657) (xy 206.69631 -310.597296) (xy 206.700374 -310.614568)
			(xy 206.727806 -310.636412) (xy 213.59368 -310.636412) (xy 213.602435 -310.636094) (xy 213.618935 -310.630246)
			(xy 213.625938 -310.624982) (xy 213.648798 -310.606186) (xy 213.657942 -310.590692) (xy 213.659466 -310.581802)
			(xy 213.674309 -310.50189) (xy 213.710695 -310.343459) (xy 213.754647 -310.186959) (xy 213.806063 -310.03275)
			(xy 213.864824 -309.881187) (xy 213.930795 -309.732621) (xy 214.003824 -309.587393) (xy 214.083743 -309.445841)
			(xy 214.170366 -309.308289) (xy 214.263494 -309.175055) (xy 214.362912 -309.046446) (xy 214.468392 -308.92276)
			(xy 214.579688 -308.804281) (xy 214.696546 -308.691284) (xy 214.818694 -308.584028) (xy 214.945852 -308.482761)
			(xy 215.077726 -308.387716) (xy 215.214012 -308.299114) (xy 215.354394 -308.217158) (xy 215.498551 -308.142037)
			(xy 215.646148 -308.073925) (xy 215.796845 -308.012979) (xy 215.950295 -307.959339) (xy 216.106144 -307.91313)
			(xy 216.264032 -307.874457) (xy 216.423595 -307.843411) (xy 216.584464 -307.820062) (xy 216.746269 -307.804465)
			(xy 216.908636 -307.796655) (xy 216.989914 -307.796184) (xy 217.070683 -307.796659) (xy 217.232036 -307.804364)
			(xy 217.392837 -307.81976) (xy 217.552721 -307.842813) (xy 217.711322 -307.873468) (xy 217.86828 -307.911658)
			(xy 218.023237 -307.957295) (xy 218.175839 -308.010274) (xy 218.325739 -308.070476) (xy 218.472595 -308.137762)
			(xy 218.616073 -308.21198) (xy 218.755845 -308.292961) (xy 218.891594 -308.380519) (xy 219.023009 -308.474456)
			(xy 219.086684 -308.524148) (xy 219.101924 -308.53634) (xy 219.140278 -308.534054) (xy 223.86798 -303.806352)
			(xy 223.87538 -303.799512) (xy 223.893979 -303.791799) (xy 223.904048 -303.791366) (xy 226.84486 -303.791366)
			(xy 226.854735 -303.7909) (xy 226.873029 -303.783453) (xy 226.88042 -303.776888) (xy 226.880674 -303.776634)
			(xy 227.799392 -302.857916) (xy 227.806226 -302.850513) (xy 227.813931 -302.831915) (xy 227.814378 -302.821848)
			(xy 227.814378 -291.289994) (xy 227.811584 -291.277802) (xy 227.809298 -291.267134) (xy 227.796852 -291.25037)
			(xy 227.713032 -291.202364) (xy 227.707212 -291.199253) (xy 227.69448 -291.195793) (xy 227.687886 -291.195506)
			(xy 227.673408 -291.195506) (xy 227.661724 -291.202364) (xy 227.6602 -291.203126) (xy 227.650548 -291.20846)
			(xy 227.622518 -291.222895) (xy 227.562895 -291.243376) (xy 227.500713 -291.253766) (xy 227.469192 -291.254434)
			(xy 227.46335 -291.254434) (xy 227.436359 -291.253573) (xy 227.383015 -291.24518) (xy 227.331387 -291.229349)
			(xy 227.282508 -291.206396) (xy 227.237355 -291.176778) (xy 227.196829 -291.141089) (xy 227.161741 -291.100042)
			(xy 227.132793 -291.054456) (xy 227.110562 -291.005244) (xy 227.095494 -290.953389) (xy 227.087889 -290.899926)
			(xy 227.08743 -290.872926) (xy 227.087892 -290.845673) (xy 227.095646 -290.791721) (xy 227.111 -290.739422)
			(xy 227.133641 -290.689841) (xy 227.163109 -290.643988) (xy 227.198804 -290.602795) (xy 227.239997 -290.567102)
			(xy 227.285852 -290.537636) (xy 227.335434 -290.514996) (xy 227.387733 -290.499643) (xy 227.441685 -290.491891)
			(xy 227.468938 -290.491418) (xy 227.469192 -290.491418) (xy 227.494425 -290.491828) (xy 227.544452 -290.498477)
			(xy 227.593169 -290.511648) (xy 227.639732 -290.53111) (xy 227.661724 -290.543488) (xy 227.673662 -290.5506)
			(xy 227.700586 -290.5506) (xy 227.783136 -290.503356) (xy 227.793804 -290.495228) (xy 227.799392 -290.48964)
			(xy 227.80623 -290.482239) (xy 227.813944 -290.46364) (xy 227.814378 -290.453572) (xy 227.814378 -288.808414)
			(xy 227.810568 -288.799016) (xy 227.801249 -288.775674) (xy 227.788134 -288.727156) (xy 227.781512 -288.677334)
			(xy 227.781104 -288.652204) (xy 227.781522 -288.627075) (xy 227.788152 -288.577256) (xy 227.801257 -288.528736)
			(xy 227.810568 -288.505392) (xy 227.814378 -288.495994) (xy 227.814378 -288.117026) (xy 227.81395 -288.107344)
			(xy 227.806796 -288.089349) (xy 227.793521 -288.07525) (xy 227.784914 -288.070798) (xy 227.687632 -288.026094)
			(xy 227.658422 -288.029904) (xy 227.646992 -288.039556) (xy 227.626209 -288.056641) (xy 227.580747 -288.085409)
			(xy 227.531691 -288.107498) (xy 227.480016 -288.12247) (xy 227.42675 -288.130028) (xy 227.39985 -288.130488)
			(xy 227.369724 -288.129923) (xy 227.310222 -288.120457) (xy 227.252947 -288.101754) (xy 227.199326 -288.074278)
			(xy 227.150692 -288.038713) (xy 227.129086 -288.017712) (xy 227.125471 -288.014275) (xy 227.117156 -288.008766)
			(xy 227.112576 -288.00679) (xy 227.103178 -288.002726) (xy 227.020882 -288.002726) (xy 227.015849 -288.002864)
			(xy 227.005993 -288.004907) (xy 227.001324 -288.00679) (xy 226.991672 -288.010854) (xy 226.973565 -288.029395)
			(xy 226.933212 -288.061912) (xy 226.888832 -288.088671) (xy 226.84124 -288.109182) (xy 226.79131 -288.123066)
			(xy 226.739962 -288.13007) (xy 226.71405 -288.130488) (xy 226.686803 -288.129998) (xy 226.632863 -288.122236)
			(xy 226.580577 -288.106878) (xy 226.531009 -288.084235) (xy 226.485167 -288.054769) (xy 226.443985 -288.019079)
			(xy 226.408301 -287.977893) (xy 226.378841 -287.932047) (xy 226.356205 -287.882476) (xy 226.340853 -287.830188)
			(xy 226.333098 -287.776248) (xy 226.333098 -287.721752) (xy 226.340853 -287.667812) (xy 226.356205 -287.615524)
			(xy 226.378841 -287.565953) (xy 226.408301 -287.520107) (xy 226.443985 -287.478921) (xy 226.485167 -287.443231)
			(xy 226.531009 -287.413765) (xy 226.580577 -287.391122) (xy 226.632863 -287.375764) (xy 226.686803 -287.368002)
			(xy 226.71405 -287.367472) (xy 226.744175 -287.368037) (xy 226.803677 -287.377504) (xy 226.860949 -287.39621)
			(xy 226.914568 -287.423689) (xy 226.963198 -287.459258) (xy 226.984814 -287.480248) (xy 226.991926 -287.48736)
			(xy 227.010722 -287.495234) (xy 227.103178 -287.495234) (xy 227.121974 -287.48736) (xy 227.129086 -287.480248)
			(xy 227.150712 -287.459271) (xy 227.199347 -287.423717) (xy 227.252964 -287.396247) (xy 227.310232 -287.377542)
			(xy 227.369728 -287.368068) (xy 227.39985 -287.367472) (xy 227.426748 -287.367937) (xy 227.48001 -287.375505)
			(xy 227.53168 -287.390484) (xy 227.580731 -287.412576) (xy 227.626191 -287.441343) (xy 227.646992 -287.458404)
			(xy 227.658422 -287.468056) (xy 227.687632 -287.47212) (xy 227.755704 -287.440624) (xy 227.784406 -287.42767)
			(xy 227.79482 -287.421066) (xy 227.800064 -287.416633) (xy 227.80817 -287.405556) (xy 227.810822 -287.399222)
			(xy 227.814378 -287.390078) (xy 227.814378 -282.151074) (xy 227.806758 -282.132278) (xy 227.799392 -282.125166)
			(xy 226.235514 -280.561288) (xy 226.229282 -280.554625) (xy 226.221603 -280.53809) (xy 226.220528 -280.52903)
			(xy 226.219766 -280.51887) (xy 226.212146 -280.502614) (xy 226.205288 -280.49601) (xy 226.192588 -280.483564)
			(xy 226.19208 -280.483056) (xy 226.15144 -280.442416) (xy 226.151186 -280.442162) (xy 226.149916 -280.440892)
			(xy 226.149154 -280.439876) (xy 226.145598 -280.43632) (xy 226.141788 -280.427176) (xy 226.139921 -280.422436)
			(xy 226.13788 -280.412456) (xy 226.137724 -280.407364) (xy 226.137724 -278.592026) (xy 226.125278 -278.56815)
			(xy 226.118928 -278.558752) (xy 226.10699 -278.544782) (xy 226.102418 -278.541226) (xy 226.078679 -278.523106)
			(xy 226.036606 -278.480728) (xy 226.001645 -278.432314) (xy 225.97465 -278.379047) (xy 225.95628 -278.322225)
			(xy 225.946984 -278.263237) (xy 225.946462 -278.233378) (xy 225.947012 -278.203902) (xy 225.956084 -278.145651)
			(xy 225.974007 -278.089488) (xy 226.000355 -278.036751) (xy 226.034502 -277.988694) (xy 226.054666 -277.967186)
			(xy 226.05873 -277.963122) (xy 226.064572 -277.953216) (xy 226.06635 -277.947628) (xy 226.068056 -277.942017)
			(xy 226.069088 -277.930336) (xy 226.068382 -277.924514) (xy 226.05492 -277.832566) (xy 226.041712 -277.813516)
			(xy 226.031298 -277.807674) (xy 226.004569 -277.792036) (xy 225.956113 -277.753481) (xy 225.91452 -277.707606)
			(xy 225.897186 -277.681944) (xy 225.891852 -277.673562) (xy 225.87585 -277.662386) (xy 225.79711 -277.643844)
			(xy 225.792279 -277.642866) (xy 225.782428 -277.642616) (xy 225.777552 -277.643336) (xy 225.767138 -277.64486)
			(xy 225.758756 -277.650194) (xy 225.736251 -277.663397) (xy 225.688401 -277.684203) (xy 225.638162 -277.698292)
			(xy 225.586471 -277.705402) (xy 225.560382 -277.70582) (xy 225.533131 -277.705333) (xy 225.479183 -277.697574)
			(xy 225.426889 -277.682217) (xy 225.377313 -277.659574) (xy 225.331463 -277.630106) (xy 225.290274 -277.594414)
			(xy 225.254583 -277.553223) (xy 225.225117 -277.507372) (xy 225.202477 -277.457794) (xy 225.187122 -277.405499)
			(xy 225.179366 -277.351551) (xy 225.179366 -277.297049) (xy 225.187122 -277.243101) (xy 225.202477 -277.190806)
			(xy 225.225117 -277.141228) (xy 225.254583 -277.095377) (xy 225.290274 -277.054186) (xy 225.331463 -277.018494)
			(xy 225.377313 -276.989026) (xy 225.426889 -276.966383) (xy 225.479183 -276.951026) (xy 225.533131 -276.943267)
			(xy 225.560382 -276.942804) (xy 225.587617 -276.943284) (xy 225.641537 -276.951013) (xy 225.693813 -276.966317)
			(xy 225.743388 -276.988887) (xy 225.789257 -277.018264) (xy 225.830493 -277.053855) (xy 225.866259 -277.094938)
			(xy 225.881438 -277.117556) (xy 225.887026 -277.125938) (xy 225.902774 -277.137114) (xy 225.980752 -277.155402)
			(xy 225.984883 -277.156275) (xy 225.993311 -277.156793) (xy 225.997516 -277.156418) (xy 226.009708 -277.155148)
			(xy 226.019614 -277.149052) (xy 226.042119 -277.135849) (xy 226.089969 -277.115042) (xy 226.140208 -277.100951)
			(xy 226.191899 -277.093838) (xy 226.217988 -277.093426) (xy 226.220528 -277.093426) (xy 226.247194 -277.094073)
			(xy 226.299963 -277.101854) (xy 226.325684 -277.10892) (xy 226.33452 -277.111164) (xy 226.352695 -277.109932)
			(xy 226.369287 -277.102411) (xy 226.375976 -277.09622) (xy 227.813362 -275.658834) (xy 227.816241 -275.655829)
			(xy 227.821085 -275.649061) (xy 227.823014 -275.645372) (xy 227.823268 -275.645118) (xy 227.825644 -275.639839)
			(xy 227.828208 -275.628553) (xy 227.828348 -275.622766) (xy 227.828348 -275.3487) (xy 227.82852 -275.342692)
			(xy 227.831352 -275.331013) (xy 227.833936 -275.325586) (xy 227.842064 -275.309584) (xy 227.842064 -275.29917)
			(xy 227.842826 -275.291042) (xy 227.842826 -274.173188) (xy 227.842166 -274.161112) (xy 227.831171 -274.139611)
			(xy 227.821744 -274.13204) (xy 227.799523 -274.115386) (xy 227.759684 -274.076705) (xy 227.725873 -274.032657)
			(xy 227.698805 -273.984172) (xy 227.679053 -273.932275) (xy 227.667033 -273.878063) (xy 227.663 -273.822681)
			(xy 227.667039 -273.7673) (xy 227.679064 -273.713089) (xy 227.698821 -273.661194) (xy 227.725894 -273.612712)
			(xy 227.759709 -273.568667) (xy 227.799552 -273.52999) (xy 227.821744 -273.513296) (xy 227.831135 -273.505688)
			(xy 227.842151 -273.484214) (xy 227.842826 -273.472148) (xy 227.842826 -272.439892) (xy 227.843251 -272.429823)
			(xy 227.850971 -272.411223) (xy 227.857812 -272.403824) (xy 228.838506 -271.42313) (xy 228.841388 -271.420126)
			(xy 228.846236 -271.41336) (xy 228.848158 -271.409668) (xy 228.848412 -271.409414) (xy 228.850785 -271.404135)
			(xy 228.853346 -271.392849) (xy 228.853492 -271.387062) (xy 228.853492 -261.246112) (xy 228.852909 -261.233781)
			(xy 228.841468 -261.211935) (xy 228.831648 -261.204456) (xy 228.80828 -261.1882) (xy 228.807772 -261.1882)
			(xy 228.751384 -261.149338) (xy 228.726238 -261.146544) (xy 228.7143 -261.15137) (xy 228.69153 -261.160123)
			(xy 228.644328 -261.172439) (xy 228.595943 -261.178651) (xy 228.571552 -261.179056) (xy 228.571298 -261.179056)
			(xy 228.544043 -261.17857) (xy 228.490089 -261.170812) (xy 228.437788 -261.155455) (xy 228.388205 -261.132811)
			(xy 228.342349 -261.103341) (xy 228.301154 -261.067645) (xy 228.265458 -261.026449) (xy 228.235988 -260.980593)
			(xy 228.213344 -260.93101) (xy 228.197987 -260.878709) (xy 228.19023 -260.824755) (xy 228.19023 -260.770245)
			(xy 228.197987 -260.716291) (xy 228.213344 -260.66399) (xy 228.235988 -260.614407) (xy 228.265458 -260.568551)
			(xy 228.301154 -260.527355) (xy 228.342349 -260.491659) (xy 228.388205 -260.462189) (xy 228.437788 -260.439545)
			(xy 228.490089 -260.424188) (xy 228.544043 -260.41643) (xy 228.571298 -260.41604) (xy 228.59569 -260.416426)
			(xy 228.644078 -260.422637) (xy 228.69128 -260.434959) (xy 228.714046 -260.443726) (xy 228.725984 -260.448552)
			(xy 228.750876 -260.445758) (xy 228.808026 -260.406896) (xy 228.83114 -260.391402) (xy 228.83747 -260.386788)
			(xy 228.847167 -260.374498) (xy 228.85019 -260.367272) (xy 228.853492 -260.358382) (xy 228.853492 -260.343396)
			(xy 228.852905 -260.331067) (xy 228.84146 -260.309227) (xy 228.831648 -260.30174) (xy 228.80828 -260.285484)
			(xy 228.807772 -260.285484) (xy 228.751384 -260.246622) (xy 228.726238 -260.243828) (xy 228.7143 -260.248654)
			(xy 228.69153 -260.257408) (xy 228.644328 -260.269724) (xy 228.595943 -260.275936) (xy 228.571552 -260.27634)
			(xy 228.571298 -260.27634) (xy 228.544045 -260.275854) (xy 228.490093 -260.268097) (xy 228.437794 -260.25274)
			(xy 228.388213 -260.230097) (xy 228.342359 -260.200628) (xy 228.301165 -260.164934) (xy 228.265471 -260.12374)
			(xy 228.236002 -260.077886) (xy 228.213359 -260.028305) (xy 228.198003 -259.976006) (xy 228.190246 -259.922053)
			(xy 228.190246 -259.867547) (xy 228.198003 -259.813594) (xy 228.213359 -259.761295) (xy 228.236002 -259.711714)
			(xy 228.265471 -259.66586) (xy 228.301165 -259.624666) (xy 228.342359 -259.588972) (xy 228.388213 -259.559503)
			(xy 228.437794 -259.53686) (xy 228.490093 -259.521503) (xy 228.544045 -259.513746) (xy 228.571298 -259.513324)
			(xy 228.59569 -259.51371) (xy 228.644078 -259.519921) (xy 228.691281 -259.532243) (xy 228.714046 -259.54101)
			(xy 228.725984 -259.545836) (xy 228.750876 -259.543042) (xy 228.808026 -259.50418) (xy 228.83114 -259.488686)
			(xy 228.837469 -259.484072) (xy 228.847162 -259.47178) (xy 228.85019 -259.464556) (xy 228.853492 -259.455666)
			(xy 228.853492 -259.002784) (xy 228.84638 -258.985004) (xy 228.839776 -258.978146) (xy 228.837744 -258.975606)
			(xy 228.32822 -258.466082) (xy 228.320821 -258.459239) (xy 228.302222 -258.451521) (xy 228.292152 -258.451096)
			(xy 223.645984 -258.451096) (xy 223.637381 -258.451445) (xy 223.621147 -258.457151) (xy 223.607699 -258.467887)
			(xy 223.602804 -258.474972) (xy 223.549972 -258.559046) (xy 223.548702 -258.584954) (xy 223.554544 -258.596892)
			(xy 223.566503 -258.622887) (xy 223.583373 -258.677563) (xy 223.591899 -258.734144) (xy 223.59239 -258.762754)
			(xy 223.591904 -258.790005) (xy 223.584148 -258.843953) (xy 223.568793 -258.896248) (xy 223.546151 -258.945825)
			(xy 223.516685 -258.991675) (xy 223.480994 -259.032866) (xy 223.439803 -259.068557) (xy 223.393953 -259.098023)
			(xy 223.344376 -259.120665) (xy 223.292081 -259.13602) (xy 223.238133 -259.143776) (xy 223.183631 -259.143776)
			(xy 223.129683 -259.13602) (xy 223.077388 -259.120665) (xy 223.027811 -259.098023) (xy 222.981961 -259.068557)
			(xy 222.94077 -259.032866) (xy 222.905079 -258.991675) (xy 222.875613 -258.945825) (xy 222.852971 -258.896248)
			(xy 222.837616 -258.843953) (xy 222.82986 -258.790005) (xy 222.829374 -258.762754) (xy 222.829861 -258.734142)
			(xy 222.838365 -258.677556) (xy 222.855236 -258.622877) (xy 222.86722 -258.596892) (xy 222.873062 -258.584954)
			(xy 222.871792 -258.559046) (xy 222.81896 -258.474972) (xy 222.814126 -258.467827) (xy 222.800677 -258.457044)
			(xy 222.784401 -258.451364) (xy 222.77578 -258.451096) (xy 222.102934 -258.451096) (xy 222.093779 -258.451536)
			(xy 222.076661 -258.458051) (xy 222.062893 -258.47013) (xy 222.05823 -258.47802) (xy 222.009462 -258.569968)
			(xy 222.010986 -258.597654) (xy 222.01886 -258.609592) (xy 222.03428 -258.63335) (xy 222.058682 -258.68446)
			(xy 222.075253 -258.738619) (xy 222.083627 -258.794633) (xy 222.084138 -258.822952) (xy 222.083652 -258.850203)
			(xy 222.075896 -258.904151) (xy 222.060541 -258.956446) (xy 222.037899 -259.006023) (xy 222.008433 -259.051873)
			(xy 221.972742 -259.093064) (xy 221.931551 -259.128755) (xy 221.885701 -259.158221) (xy 221.836124 -259.180863)
			(xy 221.783829 -259.196218) (xy 221.729881 -259.203974) (xy 221.675379 -259.203974) (xy 221.621431 -259.196218)
			(xy 221.569136 -259.180863) (xy 221.519559 -259.158221) (xy 221.473709 -259.128755) (xy 221.432518 -259.093064)
			(xy 221.396827 -259.051873) (xy 221.367361 -259.006023) (xy 221.344719 -258.956446) (xy 221.329364 -258.904151)
			(xy 221.321608 -258.850203) (xy 221.321122 -258.822952) (xy 221.321642 -258.794635) (xy 221.330025 -258.738624)
			(xy 221.346598 -258.684469) (xy 221.370998 -258.63336) (xy 221.3864 -258.609592) (xy 221.394274 -258.597654)
			(xy 221.395798 -258.569968) (xy 221.34703 -258.47802) (xy 221.342403 -258.470088) (xy 221.328657 -258.457936)
			(xy 221.3115 -258.451434) (xy 221.302326 -258.451096) (xy 220.629226 -258.451096) (xy 220.620619 -258.451439)
			(xy 220.604375 -258.457135) (xy 220.590916 -258.467867) (xy 220.586046 -258.474972) (xy 220.533214 -258.559046)
			(xy 220.531944 -258.584954) (xy 220.537786 -258.596892) (xy 220.549747 -258.622887) (xy 220.566619 -258.677563)
			(xy 220.575147 -258.734144) (xy 220.575632 -258.762754) (xy 220.575146 -258.790005) (xy 220.56739 -258.843953)
			(xy 220.552035 -258.896248) (xy 220.529393 -258.945825) (xy 220.499927 -258.991675) (xy 220.464236 -259.032866)
			(xy 220.423045 -259.068557) (xy 220.377195 -259.098023) (xy 220.327618 -259.120665) (xy 220.275323 -259.13602)
			(xy 220.221375 -259.143776) (xy 220.166873 -259.143776) (xy 220.112925 -259.13602) (xy 220.06063 -259.120665)
			(xy 220.011053 -259.098023) (xy 219.965203 -259.068557) (xy 219.924012 -259.032866) (xy 219.888321 -258.991675)
			(xy 219.858855 -258.945825) (xy 219.836213 -258.896248) (xy 219.820858 -258.843953) (xy 219.813102 -258.790005)
			(xy 219.812616 -258.762754) (xy 219.813103 -258.734143) (xy 219.821608 -258.677556) (xy 219.83848 -258.622878)
			(xy 219.850462 -258.596892) (xy 219.856304 -258.584954) (xy 219.855034 -258.559046) (xy 219.802202 -258.474972)
			(xy 219.797365 -258.467834) (xy 219.783914 -258.457066) (xy 219.767639 -258.451405) (xy 219.759022 -258.451096)
			(xy 219.119196 -258.451096) (xy 219.110209 -258.45144) (xy 219.093344 -258.457649) (xy 219.079685 -258.469328)
			(xy 219.075 -258.477004) (xy 219.024708 -258.566158) (xy 219.024962 -258.593336) (xy 219.032328 -258.605274)
			(xy 219.045403 -258.627723) (xy 219.066025 -258.675404) (xy 219.079989 -258.725442) (xy 219.087037 -258.776911)
			(xy 219.087446 -258.802886) (xy 219.08696 -258.830137) (xy 219.079204 -258.884085) (xy 219.063849 -258.93638)
			(xy 219.041207 -258.985957) (xy 219.011741 -259.031807) (xy 218.97605 -259.072998) (xy 218.934859 -259.108689)
			(xy 218.889009 -259.138155) (xy 218.839432 -259.160797) (xy 218.787137 -259.176152) (xy 218.733189 -259.183908)
			(xy 218.678687 -259.183908) (xy 218.624739 -259.176152) (xy 218.572444 -259.160797) (xy 218.522867 -259.138155)
			(xy 218.477017 -259.108689) (xy 218.435826 -259.072998) (xy 218.400135 -259.031807) (xy 218.370669 -258.985957)
			(xy 218.348027 -258.93638) (xy 218.332672 -258.884085) (xy 218.324916 -258.830137) (xy 218.32443 -258.802886)
			(xy 218.326208 -258.766818) (xy 218.327732 -258.750816) (xy 218.31173 -258.722876) (xy 218.210638 -258.675378)
			(xy 218.20103 -258.67141) (xy 218.180272 -258.67073) (xy 218.160934 -258.678302) (xy 218.153234 -258.685284)
			(xy 217.624406 -259.214112) (xy 217.617012 -259.220969) (xy 217.598413 -259.228719) (xy 217.588338 -259.229098)
			(xy 215.783922 -259.229098) (xy 215.774337 -259.22951) (xy 215.7565 -259.236535) (xy 215.742459 -259.249587)
			(xy 215.737948 -259.258054) (xy 215.73053 -259.273802) (xy 219.062806 -259.273802) (xy 219.066877 -259.21818)
			(xy 219.079003 -259.163743) (xy 219.098926 -259.111652) (xy 219.126222 -259.063017) (xy 219.160308 -259.018874)
			(xy 219.200457 -258.980165) (xy 219.245815 -258.947714) (xy 219.295415 -258.922213) (xy 219.348199 -258.904206)
			(xy 219.403042 -258.894076) (xy 219.458776 -258.892039) (xy 219.514213 -258.898139) (xy 219.56817 -258.912245)
			(xy 219.619499 -258.934057) (xy 219.667105 -258.963111) (xy 219.709973 -258.998786) (xy 219.74719 -259.040323)
			(xy 219.777963 -259.086836) (xy 219.801635 -259.137333) (xy 219.817703 -259.19074) (xy 219.825823 -259.245916)
			(xy 219.826332 -259.273802) (xy 219.825823 -259.301688) (xy 219.817703 -259.356864) (xy 219.801635 -259.410271)
			(xy 219.777963 -259.460768) (xy 219.74719 -259.507281) (xy 219.709973 -259.548818) (xy 219.667105 -259.584493)
			(xy 219.619499 -259.613547) (xy 219.56817 -259.635359) (xy 219.514213 -259.649465) (xy 219.458776 -259.655565)
			(xy 219.403042 -259.653528) (xy 219.348199 -259.643398) (xy 219.295415 -259.625391) (xy 219.245815 -259.59989)
			(xy 219.200457 -259.567439) (xy 219.160308 -259.52873) (xy 219.126222 -259.484587) (xy 219.098926 -259.435952)
			(xy 219.079003 -259.383861) (xy 219.066877 -259.329424) (xy 219.062806 -259.273802) (xy 215.73053 -259.273802)
			(xy 215.692482 -259.354574) (xy 215.695784 -259.38353) (xy 215.705182 -259.39496) (xy 215.721396 -259.415469)
			(xy 215.748652 -259.460084) (xy 215.769559 -259.508004) (xy 215.783725 -259.55833) (xy 215.790885 -259.610119)
			(xy 215.791288 -259.63626) (xy 215.790802 -259.663511) (xy 215.783046 -259.717459) (xy 215.767691 -259.769754)
			(xy 215.745049 -259.819331) (xy 215.715583 -259.865181) (xy 215.679892 -259.906372) (xy 215.661808 -259.922041)
			(xy 218.284257 -259.922041) (xy 218.284258 -259.867535) (xy 218.292017 -259.813584) (xy 218.307375 -259.761286)
			(xy 218.33002 -259.711706) (xy 218.35949 -259.665853) (xy 218.395186 -259.624662) (xy 218.436381 -259.58897)
			(xy 218.482236 -259.559504) (xy 218.531818 -259.536863) (xy 218.584117 -259.52151) (xy 218.638069 -259.513756)
			(xy 218.692575 -259.513759) (xy 218.746526 -259.521519) (xy 218.798824 -259.536879) (xy 218.848403 -259.559525)
			(xy 218.894255 -259.588996) (xy 218.935445 -259.624693) (xy 218.971136 -259.665889) (xy 219.000601 -259.711745)
			(xy 219.02324 -259.761327) (xy 219.038592 -259.813627) (xy 219.046345 -259.867579) (xy 219.046806 -259.894832)
			(xy 219.80728 -259.894832) (xy 219.811351 -259.83921) (xy 219.823477 -259.784773) (xy 219.8434 -259.732682)
			(xy 219.870696 -259.684047) (xy 219.904782 -259.639904) (xy 219.944931 -259.601195) (xy 219.990289 -259.568744)
			(xy 220.039889 -259.543243) (xy 220.092673 -259.525236) (xy 220.147516 -259.515106) (xy 220.20325 -259.513069)
			(xy 220.258687 -259.519169) (xy 220.312644 -259.533275) (xy 220.363973 -259.555087) (xy 220.411579 -259.584141)
			(xy 220.454447 -259.619816) (xy 220.491664 -259.661353) (xy 220.522437 -259.707866) (xy 220.546109 -259.758363)
			(xy 220.562177 -259.81177) (xy 220.570297 -259.866946) (xy 220.570806 -259.894832) (xy 220.570297 -259.922718)
			(xy 220.562177 -259.977894) (xy 220.546109 -260.031301) (xy 220.522437 -260.081798) (xy 220.491664 -260.128311)
			(xy 220.454447 -260.169848) (xy 220.411579 -260.205523) (xy 220.363973 -260.234577) (xy 220.312644 -260.256389)
			(xy 220.258687 -260.270495) (xy 220.20325 -260.276595) (xy 220.147516 -260.274558) (xy 220.092673 -260.264428)
			(xy 220.039889 -260.246421) (xy 219.990289 -260.22092) (xy 219.944931 -260.188469) (xy 219.904782 -260.14976)
			(xy 219.870696 -260.105617) (xy 219.8434 -260.056982) (xy 219.823477 -260.004891) (xy 219.811351 -259.950454)
			(xy 219.80728 -259.894832) (xy 219.046806 -259.894832) (xy 219.046298 -259.91312) (xy 219.04579 -259.92709)
			(xy 219.058236 -259.95122) (xy 219.156534 -260.013196) (xy 219.183712 -260.014212) (xy 219.195904 -260.007608)
			(xy 219.223904 -259.99323) (xy 219.283452 -259.972857) (xy 219.345537 -259.962531) (xy 219.377006 -259.961888)
			(xy 219.404257 -259.962382) (xy 219.458203 -259.970139) (xy 219.510497 -259.985495) (xy 219.560073 -260.008136)
			(xy 219.605922 -260.037602) (xy 219.647111 -260.073293) (xy 219.682801 -260.114483) (xy 219.712267 -260.160333)
			(xy 219.734907 -260.209909) (xy 219.750262 -260.262203) (xy 219.758018 -260.316149) (xy 219.758018 -260.370651)
			(xy 219.750262 -260.424597) (xy 219.734907 -260.476891) (xy 219.712267 -260.526467) (xy 219.682801 -260.572317)
			(xy 219.647111 -260.613507) (xy 219.605922 -260.649198) (xy 219.560073 -260.678664) (xy 219.510497 -260.701305)
			(xy 219.458203 -260.716661) (xy 219.404257 -260.724418) (xy 219.377006 -260.724904) (xy 219.345537 -260.724274)
			(xy 219.283452 -260.713942) (xy 219.223906 -260.693558) (xy 219.195904 -260.679184) (xy 219.183712 -260.67258)
			(xy 219.156026 -260.673596) (xy 219.057728 -260.73608) (xy 219.045282 -260.760718) (xy 219.046044 -260.774688)
			(xy 219.046806 -260.797548) (xy 219.046271 -260.824748) (xy 219.808326 -260.824748) (xy 219.808326 -260.770252)
			(xy 219.816082 -260.716312) (xy 219.831435 -260.664024) (xy 219.854073 -260.614453) (xy 219.883535 -260.568608)
			(xy 219.919222 -260.527423) (xy 219.960407 -260.491736) (xy 220.006251 -260.462274) (xy 220.055822 -260.439635)
			(xy 220.10811 -260.424282) (xy 220.16205 -260.416526) (xy 220.189298 -260.41604) (xy 220.218233 -260.416577)
			(xy 220.275439 -260.425323) (xy 220.330667 -260.442613) (xy 220.382647 -260.468052) (xy 220.406722 -260.484112)
			(xy 220.416374 -260.490716) (xy 220.43898 -260.494272) (xy 220.53804 -260.4643) (xy 220.554804 -260.448806)
			(xy 220.559122 -260.43763) (xy 220.569672 -260.412025) (xy 220.597175 -260.363958) (xy 220.63134 -260.320373)
			(xy 220.671447 -260.282186) (xy 220.716655 -260.2502) (xy 220.766013 -260.225087) (xy 220.818483 -260.207375)
			(xy 220.845634 -260.201918) (xy 220.857572 -260.199886) (xy 220.87713 -260.1849) (xy 220.923104 -260.088634)
			(xy 220.922342 -260.06425) (xy 220.9165 -260.053582) (xy 220.901891 -260.02538) (xy 220.881173 -259.965344)
			(xy 220.870658 -259.902711) (xy 220.870018 -259.870956) (xy 220.870504 -259.843705) (xy 220.87826 -259.789757)
			(xy 220.893615 -259.737462) (xy 220.916257 -259.687885) (xy 220.945723 -259.642035) (xy 220.981414 -259.600844)
			(xy 221.022605 -259.565153) (xy 221.068455 -259.535687) (xy 221.118032 -259.513045) (xy 221.170327 -259.49769)
			(xy 221.224275 -259.489934) (xy 221.278777 -259.489934) (xy 221.332725 -259.49769) (xy 221.38502 -259.513045)
			(xy 221.434597 -259.535687) (xy 221.480447 -259.565153) (xy 221.521638 -259.600844) (xy 221.557329 -259.642035)
			(xy 221.586795 -259.687885) (xy 221.609437 -259.737462) (xy 221.624792 -259.789757) (xy 221.632548 -259.843705)
			(xy 221.633034 -259.870956) (xy 221.63257 -259.897484) (xy 221.629126 -259.922049) (xy 222.09431 -259.922049)
			(xy 222.09431 -259.867551) (xy 222.102066 -259.813608) (xy 222.11742 -259.761318) (xy 222.140059 -259.711745)
			(xy 222.169522 -259.665899) (xy 222.205211 -259.624712) (xy 222.246397 -259.589024) (xy 222.292243 -259.55956)
			(xy 222.341816 -259.53692) (xy 222.394106 -259.521566) (xy 222.448049 -259.51381) (xy 222.475298 -259.513324)
			(xy 222.502454 -259.513832) (xy 222.55622 -259.521514) (xy 222.608354 -259.536736) (xy 222.657806 -259.559192)
			(xy 222.703577 -259.588429) (xy 222.724472 -259.60578) (xy 222.734124 -259.614162) (xy 222.758508 -259.61975)
			(xy 222.864172 -259.591302) (xy 222.882714 -259.57403) (xy 222.886778 -259.562092) (xy 222.895716 -259.53738)
			(xy 222.919477 -259.490508) (xy 222.949448 -259.447341) (xy 222.985061 -259.408698) (xy 223.025643 -259.37531)
			(xy 223.070423 -259.347809) (xy 223.118556 -259.326717) (xy 223.169128 -259.312432) (xy 223.221182 -259.305226)
			(xy 223.247458 -259.30479) (xy 223.276335 -259.305319) (xy 223.333429 -259.314026) (xy 223.388561 -259.331233)
			(xy 223.440472 -259.356546) (xy 223.487979 -259.389389) (xy 223.529997 -259.429013) (xy 223.565569 -259.474513)
			(xy 223.593882 -259.524851) (xy 223.604582 -259.551678) (xy 223.6089 -259.563362) (xy 223.626426 -259.579618)
			(xy 223.729296 -259.608066) (xy 223.752918 -259.60324) (xy 223.76257 -259.59562) (xy 223.782847 -259.580074)
			(xy 223.826799 -259.554018) (xy 223.873834 -259.534057) (xy 223.923112 -259.520548) (xy 223.97375 -259.513733)
			(xy 223.999298 -259.513324) (xy 224.026553 -259.513723) (xy 224.080509 -259.52148) (xy 224.127427 -259.535256)
			(xy 224.434045 -259.535256) (xy 224.434045 -259.480744) (xy 224.441803 -259.426788) (xy 224.457162 -259.374485)
			(xy 224.479809 -259.3249) (xy 224.509282 -259.279044) (xy 224.544981 -259.237849) (xy 224.586181 -259.202154)
			(xy 224.632041 -259.172687) (xy 224.681628 -259.150046) (xy 224.733933 -259.134694) (xy 224.78789 -259.126942)
			(xy 224.815146 -259.126482) (xy 224.843547 -259.127031) (xy 224.899723 -259.135445) (xy 224.95403 -259.152096)
			(xy 225.005267 -259.176616) (xy 225.052303 -259.208462) (xy 225.094096 -259.24693) (xy 225.129724 -259.291169)
			(xy 225.158398 -259.340203) (xy 225.179485 -259.392946) (xy 225.192518 -259.448233) (xy 225.195384 -259.476494)
			(xy 225.1964 -259.489448) (xy 225.21037 -259.510784) (xy 225.307398 -259.56387) (xy 225.332798 -259.56387)
			(xy 225.344228 -259.558028) (xy 225.367276 -259.546235) (xy 225.415828 -259.528259) (xy 225.441002 -259.522214)
			(xy 225.454972 -259.519166) (xy 225.4758 -259.499354) (xy 225.505772 -259.384038) (xy 225.497644 -259.35686)
			(xy 225.486722 -259.347208) (xy 225.467038 -259.329023) (xy 225.43244 -259.288097) (xy 225.403909 -259.242734)
			(xy 225.382005 -259.193825) (xy 225.36716 -259.142332) (xy 225.359665 -259.089269) (xy 225.359214 -259.062474)
			(xy 225.3597 -259.035223) (xy 225.367456 -258.981275) (xy 225.382811 -258.92898) (xy 225.405453 -258.879403)
			(xy 225.434919 -258.833553) (xy 225.47061 -258.792362) (xy 225.511801 -258.756671) (xy 225.557651 -258.727205)
			(xy 225.607228 -258.704563) (xy 225.659523 -258.689208) (xy 225.713471 -258.681452) (xy 225.767973 -258.681452)
			(xy 225.821921 -258.689208) (xy 225.874216 -258.704563) (xy 225.923793 -258.727205) (xy 225.969643 -258.756671)
			(xy 226.010834 -258.792362) (xy 226.046525 -258.833553) (xy 226.075991 -258.879403) (xy 226.098633 -258.92898)
			(xy 226.113988 -258.981275) (xy 226.121744 -259.035223) (xy 226.12223 -259.062474) (xy 226.121754 -259.08635)
			(xy 226.47783 -259.08635) (xy 226.478316 -259.059099) (xy 226.486072 -259.005151) (xy 226.501427 -258.952856)
			(xy 226.524069 -258.903279) (xy 226.553535 -258.857429) (xy 226.589226 -258.816238) (xy 226.630417 -258.780547)
			(xy 226.676267 -258.751081) (xy 226.725844 -258.728439) (xy 226.778139 -258.713084) (xy 226.832087 -258.705328)
			(xy 226.886589 -258.705328) (xy 226.940537 -258.713084) (xy 226.992832 -258.728439) (xy 227.042409 -258.751081)
			(xy 227.088259 -258.780547) (xy 227.12945 -258.816238) (xy 227.165141 -258.857429) (xy 227.194607 -258.903279)
			(xy 227.217249 -258.952856) (xy 227.232604 -259.005151) (xy 227.240261 -259.05841) (xy 227.6381 -259.05841)
			(xy 227.642171 -259.002788) (xy 227.654297 -258.948351) (xy 227.67422 -258.89626) (xy 227.701516 -258.847625)
			(xy 227.735602 -258.803482) (xy 227.775751 -258.764773) (xy 227.821109 -258.732322) (xy 227.870709 -258.706821)
			(xy 227.923493 -258.688814) (xy 227.978336 -258.678684) (xy 228.03407 -258.676647) (xy 228.089507 -258.682747)
			(xy 228.143464 -258.696853) (xy 228.194793 -258.718665) (xy 228.242399 -258.747719) (xy 228.285267 -258.783394)
			(xy 228.322484 -258.824931) (xy 228.353257 -258.871444) (xy 228.376929 -258.921941) (xy 228.392997 -258.975348)
			(xy 228.401117 -259.030524) (xy 228.401626 -259.05841) (xy 228.401117 -259.086296) (xy 228.392997 -259.141472)
			(xy 228.376929 -259.194879) (xy 228.353257 -259.245376) (xy 228.322484 -259.291889) (xy 228.285267 -259.333426)
			(xy 228.242399 -259.369101) (xy 228.194793 -259.398155) (xy 228.143464 -259.419967) (xy 228.089507 -259.434073)
			(xy 228.03407 -259.440173) (xy 227.978336 -259.438136) (xy 227.923493 -259.428006) (xy 227.870709 -259.409999)
			(xy 227.821109 -259.384498) (xy 227.775751 -259.352047) (xy 227.735602 -259.313338) (xy 227.701516 -259.269195)
			(xy 227.67422 -259.22056) (xy 227.654297 -259.168469) (xy 227.642171 -259.114032) (xy 227.6381 -259.05841)
			(xy 227.240261 -259.05841) (xy 227.24036 -259.059099) (xy 227.240846 -259.08635) (xy 227.240446 -259.111959)
			(xy 227.233581 -259.162717) (xy 227.219995 -259.212101) (xy 227.199931 -259.259227) (xy 227.173749 -259.303249)
			(xy 227.14192 -259.343378) (xy 227.123752 -259.361432) (xy 227.113279 -259.372223) (xy 227.098618 -259.398462)
			(xy 227.092232 -259.427832) (xy 227.094676 -259.45779) (xy 227.105738 -259.485737) (xy 227.124458 -259.509252)
			(xy 227.149215 -259.526296) (xy 227.163376 -259.531358) (xy 227.188707 -259.539976) (xy 227.236898 -259.563222)
			(xy 227.281369 -259.592973) (xy 227.321249 -259.628643) (xy 227.355755 -259.669535) (xy 227.38421 -259.714845)
			(xy 227.406057 -259.763687) (xy 227.420868 -259.815101) (xy 227.428351 -259.86808) (xy 227.428806 -259.894832)
			(xy 227.42832 -259.922083) (xy 227.420564 -259.976031) (xy 227.405209 -260.028326) (xy 227.382567 -260.077903)
			(xy 227.353101 -260.123753) (xy 227.31741 -260.164944) (xy 227.276219 -260.200635) (xy 227.230369 -260.230101)
			(xy 227.180792 -260.252743) (xy 227.128497 -260.268098) (xy 227.074549 -260.275854) (xy 227.020047 -260.275854)
			(xy 226.966099 -260.268098) (xy 226.913804 -260.252743) (xy 226.864227 -260.230101) (xy 226.818377 -260.200635)
			(xy 226.777186 -260.164944) (xy 226.741495 -260.123753) (xy 226.712029 -260.077903) (xy 226.689387 -260.028326)
			(xy 226.674032 -259.976031) (xy 226.666276 -259.922083) (xy 226.66579 -259.894832) (xy 226.666234 -259.869224)
			(xy 226.673088 -259.818468) (xy 226.686665 -259.769084) (xy 226.706721 -259.721958) (xy 226.732895 -259.677935)
			(xy 226.764719 -259.637805) (xy 226.782884 -259.61975) (xy 226.793403 -259.608997) (xy 226.808076 -259.582749)
			(xy 226.814466 -259.553366) (xy 226.812018 -259.523395) (xy 226.800945 -259.495437) (xy 226.782207 -259.471919)
			(xy 226.75743 -259.454879) (xy 226.74326 -259.449824) (xy 226.71791 -259.44126) (xy 226.669719 -259.418004)
			(xy 226.625249 -259.388245) (xy 226.585372 -259.352567) (xy 226.550869 -259.311669) (xy 226.522416 -259.266352)
			(xy 226.500572 -259.217506) (xy 226.485764 -259.166087) (xy 226.478284 -259.113104) (xy 226.47783 -259.08635)
			(xy 226.121754 -259.08635) (xy 226.121658 -259.091178) (xy 226.113087 -259.147942) (xy 226.096104 -259.202781)
			(xy 226.071094 -259.254454) (xy 226.038621 -259.301795) (xy 225.99942 -259.343733) (xy 225.954375 -259.379322)
			(xy 225.904504 -259.407758) (xy 225.850935 -259.428397) (xy 225.823018 -259.435092) (xy 225.809048 -259.43814)
			(xy 225.78822 -259.457952) (xy 225.758248 -259.573268) (xy 225.766376 -259.600446) (xy 225.777298 -259.610098)
			(xy 225.796989 -259.628276) (xy 225.831586 -259.669203) (xy 225.860115 -259.714568) (xy 225.882018 -259.763479)
			(xy 225.896862 -259.814973) (xy 225.904355 -259.868037) (xy 225.904806 -259.894832) (xy 225.904352 -259.922084)
			(xy 225.896591 -259.976033) (xy 225.881232 -260.028329) (xy 225.858587 -260.077906) (xy 225.829117 -260.123756)
			(xy 225.793422 -260.164946) (xy 225.752229 -260.200637) (xy 225.706376 -260.230103) (xy 225.656797 -260.252744)
			(xy 225.6045 -260.268098) (xy 225.55055 -260.275854) (xy 225.523298 -260.27634) (xy 225.494895 -260.275822)
			(xy 225.438714 -260.267411) (xy 225.384402 -260.250762) (xy 225.33316 -260.226242) (xy 225.286121 -260.194393)
			(xy 225.244326 -260.155921) (xy 225.208699 -260.111675) (xy 225.180027 -260.062635) (xy 225.158946 -260.009885)
			(xy 225.145921 -259.954592) (xy 225.14306 -259.926328) (xy 225.142044 -259.913374) (xy 225.128074 -259.892038)
			(xy 225.031046 -259.838952) (xy 225.005646 -259.838952) (xy 224.994216 -259.844794) (xy 224.966493 -259.85888)
			(xy 224.907593 -259.878807) (xy 224.846236 -259.888892) (xy 224.815146 -259.889498) (xy 224.78789 -259.889058)
			(xy 224.733933 -259.881306) (xy 224.681628 -259.865954) (xy 224.632041 -259.843313) (xy 224.586181 -259.813846)
			(xy 224.544981 -259.778151) (xy 224.509282 -259.736956) (xy 224.479809 -259.6911) (xy 224.457162 -259.641515)
			(xy 224.441803 -259.589212) (xy 224.434045 -259.535256) (xy 224.127427 -259.535256) (xy 224.132812 -259.536837)
			(xy 224.182396 -259.559482) (xy 224.228253 -259.588952) (xy 224.26945 -259.624649) (xy 224.305147 -259.665845)
			(xy 224.334617 -259.711702) (xy 224.357262 -259.761287) (xy 224.372619 -259.813589) (xy 224.380377 -259.867545)
			(xy 224.380377 -259.922055) (xy 224.372619 -259.976011) (xy 224.357262 -260.028313) (xy 224.334617 -260.077898)
			(xy 224.305147 -260.123755) (xy 224.26945 -260.164951) (xy 224.228253 -260.200648) (xy 224.182396 -260.230118)
			(xy 224.132812 -260.252763) (xy 224.080509 -260.26812) (xy 224.026553 -260.275877) (xy 223.999298 -260.27634)
			(xy 223.970424 -260.275743) (xy 223.913333 -260.267045) (xy 223.858204 -260.249848) (xy 223.806294 -260.224544)
			(xy 223.758788 -260.19171) (xy 223.716768 -260.152096) (xy 223.681194 -260.106605) (xy 223.652877 -260.056275)
			(xy 223.642174 -260.029452) (xy 223.637856 -260.017768) (xy 223.62033 -260.001512) (xy 223.51746 -259.973064)
			(xy 223.493838 -259.97789) (xy 223.484186 -259.98551) (xy 223.463883 -260.001021) (xy 223.419939 -260.027085)
			(xy 223.372911 -260.047053) (xy 223.323639 -260.06057) (xy 223.273004 -260.067393) (xy 223.247458 -260.067806)
			(xy 223.2203 -260.06734) (xy 223.166532 -260.059651) (xy 223.114396 -260.04442) (xy 223.064945 -260.021954)
			(xy 223.019177 -259.992707) (xy 222.998284 -259.97535) (xy 222.988632 -259.966968) (xy 222.964248 -259.96138)
			(xy 222.858584 -259.989828) (xy 222.840042 -260.0071) (xy 222.835978 -260.019038) (xy 222.827009 -260.043738)
			(xy 222.803249 -260.090607) (xy 222.773281 -260.133771) (xy 222.737671 -260.172413) (xy 222.697093 -260.205801)
			(xy 222.652317 -260.233303) (xy 222.60419 -260.254399) (xy 222.553622 -260.268688) (xy 222.501572 -260.275901)
			(xy 222.475298 -260.27634) (xy 222.448049 -260.27579) (xy 222.394106 -260.268034) (xy 222.341816 -260.25268)
			(xy 222.292243 -260.23004) (xy 222.246397 -260.200576) (xy 222.205211 -260.164888) (xy 222.169522 -260.123701)
			(xy 222.140059 -260.077855) (xy 222.11742 -260.028282) (xy 222.102066 -259.975992) (xy 222.09431 -259.922049)
			(xy 221.629126 -259.922049) (xy 221.625203 -259.950027) (xy 221.610633 -260.001044) (xy 221.58914 -260.049552)
			(xy 221.561137 -260.094617) (xy 221.527166 -260.135372) (xy 221.487879 -260.171031) (xy 221.444034 -260.200907)
			(xy 221.396474 -260.224425) (xy 221.346117 -260.241133) (xy 221.320106 -260.246368) (xy 221.308168 -260.2484)
			(xy 221.28861 -260.263386) (xy 221.242636 -260.359652) (xy 221.243398 -260.384036) (xy 221.24924 -260.394704)
			(xy 221.259371 -260.413967) (xy 221.27567 -260.454325) (xy 221.281752 -260.475222) (xy 221.285562 -260.48843)
			(xy 221.304104 -260.506972) (xy 221.41434 -260.537452) (xy 221.439994 -260.530848) (xy 221.4499 -260.521704)
			(xy 221.471308 -260.501997) (xy 221.519006 -260.468673) (xy 221.571206 -260.442969) (xy 221.6267 -260.425479)
			(xy 221.684206 -260.416609) (xy 221.713298 -260.41604) (xy 221.740554 -260.416407) (xy 221.794512 -260.424165)
			(xy 221.846817 -260.439522) (xy 221.896404 -260.462168) (xy 221.942263 -260.491639) (xy 221.983461 -260.527337)
			(xy 222.019159 -260.568535) (xy 222.048631 -260.614394) (xy 222.071277 -260.663981) (xy 222.086635 -260.716286)
			(xy 222.094393 -260.770244) (xy 222.094393 -260.797548) (xy 222.85528 -260.797548) (xy 222.859351 -260.741926)
			(xy 222.871477 -260.687489) (xy 222.8914 -260.635398) (xy 222.918696 -260.586763) (xy 222.952782 -260.54262)
			(xy 222.992931 -260.503911) (xy 223.038289 -260.47146) (xy 223.087889 -260.445959) (xy 223.140673 -260.427952)
			(xy 223.195516 -260.417822) (xy 223.25125 -260.415785) (xy 223.306687 -260.421885) (xy 223.360644 -260.435991)
			(xy 223.411973 -260.457803) (xy 223.459579 -260.486857) (xy 223.502447 -260.522532) (xy 223.539664 -260.564069)
			(xy 223.570437 -260.610582) (xy 223.594109 -260.661079) (xy 223.610177 -260.714486) (xy 223.618297 -260.769662)
			(xy 223.618806 -260.797548) (xy 224.37928 -260.797548) (xy 224.383351 -260.741926) (xy 224.395477 -260.687489)
			(xy 224.4154 -260.635398) (xy 224.442696 -260.586763) (xy 224.476782 -260.54262) (xy 224.516931 -260.503911)
			(xy 224.562289 -260.47146) (xy 224.611889 -260.445959) (xy 224.664673 -260.427952) (xy 224.719516 -260.417822)
			(xy 224.77525 -260.415785) (xy 224.830687 -260.421885) (xy 224.884644 -260.435991) (xy 224.935973 -260.457803)
			(xy 224.983579 -260.486857) (xy 225.026447 -260.522532) (xy 225.063664 -260.564069) (xy 225.094437 -260.610582)
			(xy 225.118109 -260.661079) (xy 225.134177 -260.714486) (xy 225.142297 -260.769662) (xy 225.142806 -260.797548)
			(xy 225.90328 -260.797548) (xy 225.907351 -260.741926) (xy 225.919477 -260.687489) (xy 225.9394 -260.635398)
			(xy 225.966696 -260.586763) (xy 226.000782 -260.54262) (xy 226.040931 -260.503911) (xy 226.086289 -260.47146)
			(xy 226.135889 -260.445959) (xy 226.188673 -260.427952) (xy 226.243516 -260.417822) (xy 226.29925 -260.415785)
			(xy 226.354687 -260.421885) (xy 226.408644 -260.435991) (xy 226.459973 -260.457803) (xy 226.507579 -260.486857)
			(xy 226.550447 -260.522532) (xy 226.587664 -260.564069) (xy 226.618437 -260.610582) (xy 226.642109 -260.661079)
			(xy 226.658177 -260.714486) (xy 226.666297 -260.769662) (xy 226.666806 -260.797548) (xy 226.666297 -260.825434)
			(xy 226.662065 -260.85419) (xy 227.048058 -260.85419) (xy 227.052129 -260.798568) (xy 227.064255 -260.744131)
			(xy 227.084178 -260.69204) (xy 227.111474 -260.643405) (xy 227.14556 -260.599262) (xy 227.185709 -260.560553)
			(xy 227.231067 -260.528102) (xy 227.280667 -260.502601) (xy 227.333451 -260.484594) (xy 227.388294 -260.474464)
			(xy 227.444028 -260.472427) (xy 227.499465 -260.478527) (xy 227.553422 -260.492633) (xy 227.604751 -260.514445)
			(xy 227.652357 -260.543499) (xy 227.695225 -260.579174) (xy 227.732442 -260.620711) (xy 227.763215 -260.667224)
			(xy 227.786887 -260.717721) (xy 227.802955 -260.771128) (xy 227.811075 -260.826304) (xy 227.811584 -260.85419)
			(xy 227.811075 -260.882076) (xy 227.802955 -260.937252) (xy 227.786887 -260.990659) (xy 227.763215 -261.041156)
			(xy 227.732442 -261.087669) (xy 227.695225 -261.129206) (xy 227.652357 -261.164881) (xy 227.604751 -261.193935)
			(xy 227.553422 -261.215747) (xy 227.499465 -261.229853) (xy 227.444028 -261.235953) (xy 227.388294 -261.233916)
			(xy 227.333451 -261.223786) (xy 227.280667 -261.205779) (xy 227.231067 -261.180278) (xy 227.185709 -261.147827)
			(xy 227.14556 -261.109118) (xy 227.111474 -261.064975) (xy 227.084178 -261.01634) (xy 227.064255 -260.964249)
			(xy 227.052129 -260.909812) (xy 227.048058 -260.85419) (xy 226.662065 -260.85419) (xy 226.658177 -260.88061)
			(xy 226.642109 -260.934017) (xy 226.618437 -260.984514) (xy 226.587664 -261.031027) (xy 226.550447 -261.072564)
			(xy 226.507579 -261.108239) (xy 226.459973 -261.137293) (xy 226.408644 -261.159105) (xy 226.354687 -261.173211)
			(xy 226.29925 -261.179311) (xy 226.243516 -261.177274) (xy 226.188673 -261.167144) (xy 226.135889 -261.149137)
			(xy 226.086289 -261.123636) (xy 226.040931 -261.091185) (xy 226.000782 -261.052476) (xy 225.966696 -261.008333)
			(xy 225.9394 -260.959698) (xy 225.919477 -260.907607) (xy 225.907351 -260.85317) (xy 225.90328 -260.797548)
			(xy 225.142806 -260.797548) (xy 225.142297 -260.825434) (xy 225.134177 -260.88061) (xy 225.118109 -260.934017)
			(xy 225.094437 -260.984514) (xy 225.063664 -261.031027) (xy 225.026447 -261.072564) (xy 224.983579 -261.108239)
			(xy 224.935973 -261.137293) (xy 224.884644 -261.159105) (xy 224.830687 -261.173211) (xy 224.77525 -261.179311)
			(xy 224.719516 -261.177274) (xy 224.664673 -261.167144) (xy 224.611889 -261.149137) (xy 224.562289 -261.123636)
			(xy 224.516931 -261.091185) (xy 224.476782 -261.052476) (xy 224.442696 -261.008333) (xy 224.4154 -260.959698)
			(xy 224.395477 -260.907607) (xy 224.383351 -260.85317) (xy 224.37928 -260.797548) (xy 223.618806 -260.797548)
			(xy 223.618297 -260.825434) (xy 223.610177 -260.88061) (xy 223.594109 -260.934017) (xy 223.570437 -260.984514)
			(xy 223.539664 -261.031027) (xy 223.502447 -261.072564) (xy 223.459579 -261.108239) (xy 223.411973 -261.137293)
			(xy 223.360644 -261.159105) (xy 223.306687 -261.173211) (xy 223.25125 -261.179311) (xy 223.195516 -261.177274)
			(xy 223.140673 -261.167144) (xy 223.087889 -261.149137) (xy 223.038289 -261.123636) (xy 222.992931 -261.091185)
			(xy 222.952782 -261.052476) (xy 222.918696 -261.008333) (xy 222.8914 -260.959698) (xy 222.871477 -260.907607)
			(xy 222.859351 -260.85317) (xy 222.85528 -260.797548) (xy 222.094393 -260.797548) (xy 222.094393 -260.824756)
			(xy 222.086635 -260.878714) (xy 222.071277 -260.931019) (xy 222.048631 -260.980606) (xy 222.019159 -261.026465)
			(xy 221.983461 -261.067663) (xy 221.942263 -261.103361) (xy 221.896404 -261.132832) (xy 221.846817 -261.155478)
			(xy 221.794512 -261.170835) (xy 221.740554 -261.178593) (xy 221.713298 -261.179056) (xy 221.685738 -261.178577)
			(xy 221.631194 -261.170631) (xy 221.57836 -261.15492) (xy 221.528337 -261.13177) (xy 221.482166 -261.101664)
			(xy 221.440807 -261.065227) (xy 221.405121 -261.023218) (xy 221.375851 -260.976512) (xy 221.353606 -260.92608)
			(xy 221.34576 -260.899656) (xy 221.34195 -260.886448) (xy 221.323408 -260.867906) (xy 221.213172 -260.837426)
			(xy 221.187518 -260.84403) (xy 221.177612 -260.853174) (xy 221.156211 -260.872888) (xy 221.10851 -260.906208)
			(xy 221.056308 -260.93191) (xy 221.000812 -260.949398) (xy 220.943307 -260.958268) (xy 220.914214 -260.958838)
			(xy 220.885279 -260.958299) (xy 220.828072 -260.949555) (xy 220.772845 -260.932264) (xy 220.720865 -260.906826)
			(xy 220.69679 -260.890766) (xy 220.687138 -260.884162) (xy 220.664532 -260.880606) (xy 220.565472 -260.910578)
			(xy 220.548708 -260.926072) (xy 220.54439 -260.937248) (xy 220.533428 -260.963594) (xy 220.504841 -261.012979)
			(xy 220.469222 -261.057558) (xy 220.427364 -261.096339) (xy 220.3802 -261.128457) (xy 220.328781 -261.153198)
			(xy 220.274252 -261.17001) (xy 220.217829 -261.178518) (xy 220.189298 -261.179056) (xy 220.16205 -261.178474)
			(xy 220.10811 -261.170718) (xy 220.055822 -261.155365) (xy 220.006251 -261.132726) (xy 219.960407 -261.103264)
			(xy 219.919222 -261.067577) (xy 219.883535 -261.026392) (xy 219.854073 -260.980547) (xy 219.831435 -260.930976)
			(xy 219.816082 -260.878688) (xy 219.808326 -260.824748) (xy 219.046271 -260.824748) (xy 219.04627 -260.824795)
			(xy 219.038509 -260.878733) (xy 219.02315 -260.931018) (xy 219.000506 -260.980585) (xy 218.97104 -261.026425)
			(xy 218.935349 -261.067605) (xy 218.894162 -261.103287) (xy 218.848316 -261.132744) (xy 218.798744 -261.155377)
			(xy 218.746456 -261.170725) (xy 218.692516 -261.178476) (xy 218.638022 -261.178472) (xy 218.584083 -261.170712)
			(xy 218.531797 -261.155355) (xy 218.482229 -261.132714) (xy 218.436388 -261.10325) (xy 218.395206 -261.067561)
			(xy 218.359523 -261.026375) (xy 218.330064 -260.98053) (xy 218.307428 -260.930959) (xy 218.292078 -260.878672)
			(xy 218.284325 -260.824732) (xy 218.284327 -260.770238) (xy 218.292084 -260.716299) (xy 218.307439 -260.664013)
			(xy 218.330078 -260.614444) (xy 218.35954 -260.568601) (xy 218.395227 -260.527418) (xy 218.436412 -260.491733)
			(xy 218.482255 -260.462272) (xy 218.531825 -260.439634) (xy 218.584112 -260.424282) (xy 218.638051 -260.416526)
			(xy 218.665298 -260.41604) (xy 218.696767 -260.416675) (xy 218.758851 -260.427006) (xy 218.818397 -260.447388)
			(xy 218.8464 -260.46176) (xy 218.858592 -260.468364) (xy 218.886278 -260.467348) (xy 218.984576 -260.404864)
			(xy 218.997022 -260.380226) (xy 218.99626 -260.366256) (xy 218.995498 -260.343396) (xy 218.996006 -260.325108)
			(xy 218.996514 -260.311138) (xy 218.984068 -260.287008) (xy 218.88577 -260.225032) (xy 218.858592 -260.224016)
			(xy 218.8464 -260.23062) (xy 218.818397 -260.244991) (xy 218.75885 -260.265368) (xy 218.696766 -260.275696)
			(xy 218.665298 -260.27634) (xy 218.638045 -260.275842) (xy 218.584093 -260.268085) (xy 218.531795 -260.252728)
			(xy 218.482215 -260.230085) (xy 218.436361 -260.200616) (xy 218.395169 -260.164921) (xy 218.359476 -260.123727)
			(xy 218.330008 -260.077873) (xy 218.307367 -260.028292) (xy 218.292012 -259.975993) (xy 218.284257 -259.922041)
			(xy 215.661808 -259.922041) (xy 215.638701 -259.942063) (xy 215.592851 -259.971529) (xy 215.543274 -259.994171)
			(xy 215.490979 -260.009526) (xy 215.437031 -260.017282) (xy 215.382529 -260.017282) (xy 215.328581 -260.009526)
			(xy 215.276286 -259.994171) (xy 215.226709 -259.971529) (xy 215.180859 -259.942063) (xy 215.139668 -259.906372)
			(xy 215.103977 -259.865181) (xy 215.074511 -259.819331) (xy 215.051869 -259.769754) (xy 215.036514 -259.717459)
			(xy 215.028758 -259.663511) (xy 215.028272 -259.63626) (xy 215.0287 -259.610119) (xy 215.03584 -259.558327)
			(xy 215.049994 -259.507997) (xy 215.070896 -259.460076) (xy 215.098154 -259.415462) (xy 215.114378 -259.39496)
			(xy 215.123776 -259.38353) (xy 215.127078 -259.354574) (xy 215.081612 -259.258054) (xy 215.077133 -259.249561)
			(xy 215.063102 -259.236473) (xy 215.045233 -259.229487) (xy 215.035638 -259.229098) (xy 209.813906 -259.229098)
			(xy 209.803835 -259.228676) (xy 209.78523 -259.220963) (xy 209.777838 -259.214112) (xy 208.847436 -258.28371)
			(xy 208.840088 -258.276909) (xy 208.821625 -258.269198) (xy 208.811622 -258.268724) (xy 170.488102 -258.268724)
			(xy 170.478115 -258.269262) (xy 170.459684 -258.276977) (xy 170.452288 -258.28371) (xy 168.066647 -260.669351)
			(xy 200.037678 -260.669351) (xy 200.037678 -260.614849) (xy 200.045434 -260.560901) (xy 200.060789 -260.508606)
			(xy 200.083431 -260.459029) (xy 200.112897 -260.413179) (xy 200.148588 -260.371988) (xy 200.189779 -260.336297)
			(xy 200.235629 -260.306831) (xy 200.285206 -260.284189) (xy 200.337501 -260.268834) (xy 200.391449 -260.261078)
			(xy 200.4187 -260.260592) (xy 200.444345 -260.260996) (xy 200.495172 -260.267883) (xy 200.544617 -260.281519)
			(xy 200.591789 -260.301658) (xy 200.614026 -260.31444) (xy 200.622916 -260.31952) (xy 200.643236 -260.322568)
			(xy 200.73366 -260.298184) (xy 200.749662 -260.285484) (xy 200.754742 -260.27634) (xy 200.769319 -260.25127)
			(xy 200.804849 -260.205441) (xy 200.846905 -260.165516) (xy 200.894518 -260.132414) (xy 200.946592 -260.106899)
			(xy 201.001927 -260.089557) (xy 201.059249 -260.080789) (xy 201.088244 -260.080252) (xy 201.11549 -260.080821)
			(xy 201.169428 -260.088582) (xy 201.221711 -260.103939) (xy 201.271278 -260.126581) (xy 201.317118 -260.156045)
			(xy 201.358299 -260.191733) (xy 201.393982 -260.232917) (xy 201.423441 -260.278761) (xy 201.446076 -260.32833)
			(xy 201.461427 -260.380615) (xy 201.469182 -260.434554) (xy 201.469182 -260.46176) (xy 201.708256 -260.46176)
			(xy 201.712327 -260.406138) (xy 201.724453 -260.351701) (xy 201.744376 -260.29961) (xy 201.771672 -260.250975)
			(xy 201.805758 -260.206832) (xy 201.845907 -260.168123) (xy 201.891265 -260.135672) (xy 201.940865 -260.110171)
			(xy 201.993649 -260.092164) (xy 202.048492 -260.082034) (xy 202.104226 -260.079997) (xy 202.159663 -260.086097)
			(xy 202.21362 -260.100203) (xy 202.264949 -260.122015) (xy 202.312555 -260.151069) (xy 202.355423 -260.186744)
			(xy 202.39264 -260.228281) (xy 202.423413 -260.274794) (xy 202.447085 -260.325291) (xy 202.463153 -260.378698)
			(xy 202.471273 -260.433874) (xy 202.471782 -260.46176) (xy 202.724256 -260.46176) (xy 202.728327 -260.406138)
			(xy 202.740453 -260.351701) (xy 202.760376 -260.29961) (xy 202.787672 -260.250975) (xy 202.821758 -260.206832)
			(xy 202.861907 -260.168123) (xy 202.907265 -260.135672) (xy 202.956865 -260.110171) (xy 203.009649 -260.092164)
			(xy 203.064492 -260.082034) (xy 203.120226 -260.079997) (xy 203.175663 -260.086097) (xy 203.22962 -260.100203)
			(xy 203.280949 -260.122015) (xy 203.328555 -260.151069) (xy 203.371423 -260.186744) (xy 203.40864 -260.228281)
			(xy 203.439413 -260.274794) (xy 203.463085 -260.325291) (xy 203.479153 -260.378698) (xy 203.487273 -260.433874)
			(xy 203.487782 -260.46176) (xy 203.750924 -260.46176) (xy 203.754995 -260.406138) (xy 203.767121 -260.351701)
			(xy 203.787044 -260.29961) (xy 203.81434 -260.250975) (xy 203.848426 -260.206832) (xy 203.888575 -260.168123)
			(xy 203.933933 -260.135672) (xy 203.983533 -260.110171) (xy 204.036317 -260.092164) (xy 204.09116 -260.082034)
			(xy 204.146894 -260.079997) (xy 204.202331 -260.086097) (xy 204.256288 -260.100203) (xy 204.307617 -260.122015)
			(xy 204.355223 -260.151069) (xy 204.398091 -260.186744) (xy 204.435308 -260.228281) (xy 204.466081 -260.274794)
			(xy 204.489753 -260.325291) (xy 204.505821 -260.378698) (xy 204.513941 -260.433874) (xy 204.51445 -260.46176)
			(xy 204.513941 -260.489646) (xy 204.505821 -260.544822) (xy 204.489753 -260.598229) (xy 204.466081 -260.648726)
			(xy 204.435308 -260.695239) (xy 204.398091 -260.736776) (xy 204.355223 -260.772451) (xy 204.307617 -260.801505)
			(xy 204.256288 -260.823317) (xy 204.202331 -260.837423) (xy 204.146894 -260.843523) (xy 204.09116 -260.841486)
			(xy 204.036317 -260.831356) (xy 203.983533 -260.813349) (xy 203.933933 -260.787848) (xy 203.888575 -260.755397)
			(xy 203.848426 -260.716688) (xy 203.81434 -260.672545) (xy 203.787044 -260.62391) (xy 203.767121 -260.571819)
			(xy 203.754995 -260.517382) (xy 203.750924 -260.46176) (xy 203.487782 -260.46176) (xy 203.487273 -260.489646)
			(xy 203.479153 -260.544822) (xy 203.463085 -260.598229) (xy 203.439413 -260.648726) (xy 203.40864 -260.695239)
			(xy 203.371423 -260.736776) (xy 203.328555 -260.772451) (xy 203.280949 -260.801505) (xy 203.22962 -260.823317)
			(xy 203.175663 -260.837423) (xy 203.120226 -260.843523) (xy 203.064492 -260.841486) (xy 203.009649 -260.831356)
			(xy 202.956865 -260.813349) (xy 202.907265 -260.787848) (xy 202.861907 -260.755397) (xy 202.821758 -260.716688)
			(xy 202.787672 -260.672545) (xy 202.760376 -260.62391) (xy 202.740453 -260.571819) (xy 202.728327 -260.517382)
			(xy 202.724256 -260.46176) (xy 202.471782 -260.46176) (xy 202.471273 -260.489646) (xy 202.463153 -260.544822)
			(xy 202.447085 -260.598229) (xy 202.423413 -260.648726) (xy 202.39264 -260.695239) (xy 202.355423 -260.736776)
			(xy 202.312555 -260.772451) (xy 202.264949 -260.801505) (xy 202.21362 -260.823317) (xy 202.159663 -260.837423)
			(xy 202.104226 -260.843523) (xy 202.048492 -260.841486) (xy 201.993649 -260.831356) (xy 201.940865 -260.813349)
			(xy 201.891265 -260.787848) (xy 201.845907 -260.755397) (xy 201.805758 -260.716688) (xy 201.771672 -260.672545)
			(xy 201.744376 -260.62391) (xy 201.724453 -260.571819) (xy 201.712327 -260.517382) (xy 201.708256 -260.46176)
			(xy 201.469182 -260.46176) (xy 201.469182 -260.489046) (xy 201.461427 -260.542985) (xy 201.446076 -260.59527)
			(xy 201.423441 -260.644839) (xy 201.393982 -260.690683) (xy 201.358299 -260.731867) (xy 201.317118 -260.767555)
			(xy 201.271278 -260.797019) (xy 201.221711 -260.819661) (xy 201.169428 -260.835018) (xy 201.11549 -260.842779)
			(xy 201.088244 -260.843268) (xy 201.062599 -260.84285) (xy 201.011773 -260.835968) (xy 200.962327 -260.822336)
			(xy 200.915155 -260.8022) (xy 200.892918 -260.78942) (xy 200.884028 -260.78434) (xy 200.863708 -260.781292)
			(xy 200.773284 -260.805676) (xy 200.757282 -260.818376) (xy 200.752202 -260.82752) (xy 200.737649 -260.852605)
			(xy 200.702117 -260.898437) (xy 200.660058 -260.938363) (xy 200.612441 -260.971464) (xy 200.560362 -260.996976)
			(xy 200.505022 -261.014313) (xy 200.447696 -261.023075) (xy 200.4187 -261.023608) (xy 200.391449 -261.023122)
			(xy 200.337501 -261.015366) (xy 200.285206 -261.000011) (xy 200.235629 -260.977369) (xy 200.189779 -260.947903)
			(xy 200.148588 -260.912212) (xy 200.112897 -260.871021) (xy 200.083431 -260.825171) (xy 200.060789 -260.775594)
			(xy 200.045434 -260.723299) (xy 200.037678 -260.669351) (xy 168.066647 -260.669351) (xy 165.283642 -263.452356)
			(xy 165.283134 -263.459468) (xy 165.283134 -269.312136) (xy 165.283679 -269.32212) (xy 165.291405 -269.340539)
			(xy 165.29812 -269.34795) (xy 165.303708 -269.353538) (xy 165.303708 -270.89989) (xy 200.998589 -270.89989)
			(xy 201.002595 -270.704835) (xy 201.014605 -270.510109) (xy 201.0346 -270.31604) (xy 201.062545 -270.122956)
			(xy 201.098394 -269.931181) (xy 201.142086 -269.741041) (xy 201.193547 -269.552854) (xy 201.252691 -269.366939)
			(xy 201.319418 -269.183608) (xy 201.393615 -269.003172) (xy 201.475157 -268.825934) (xy 201.563908 -268.652193)
			(xy 201.659716 -268.482242) (xy 201.762421 -268.316368) (xy 201.871849 -268.15485) (xy 201.987816 -267.997961)
			(xy 202.110127 -267.845966) (xy 202.238574 -267.69912) (xy 202.372942 -267.557671) (xy 202.513004 -267.421858)
			(xy 202.658523 -267.291909) (xy 202.809255 -267.168045) (xy 202.964945 -267.050473) (xy 203.125331 -266.939393)
			(xy 203.290142 -266.83499) (xy 203.4591 -266.737442) (xy 203.631921 -266.646913) (xy 203.808313 -266.563555)
			(xy 203.987978 -266.487509) (xy 204.170613 -266.418904) (xy 204.355912 -266.357854) (xy 204.54356 -266.304464)
			(xy 204.733242 -266.258822) (xy 204.924639 -266.221006) (xy 205.117426 -266.19108) (xy 205.311279 -266.169094)
			(xy 205.505872 -266.155085) (xy 205.700875 -266.149077) (xy 205.895961 -266.15108) (xy 206.0908 -266.161091)
			(xy 206.285064 -266.179092) (xy 206.478425 -266.205054) (xy 206.670558 -266.238932) (xy 206.861137 -266.280669)
			(xy 207.049842 -266.330196) (xy 207.236355 -266.387428) (xy 207.420361 -266.452269) (xy 207.601549 -266.52461)
			(xy 207.779615 -266.604328) (xy 207.954258 -266.69129) (xy 208.125184 -266.785349) (xy 208.292103 -266.886345)
			(xy 208.454736 -266.99411) (xy 208.612807 -267.10846) (xy 208.76605 -267.229203) (xy 208.914207 -267.356137)
			(xy 209.057028 -267.489045) (xy 209.194272 -267.627705) (xy 209.325708 -267.771883) (xy 209.451113 -267.921336)
			(xy 209.570277 -268.07581) (xy 209.682998 -268.235047) (xy 209.789087 -268.398778) (xy 209.888365 -268.566725)
			(xy 209.980663 -268.738608) (xy 210.065828 -268.914134) (xy 210.143714 -269.093009) (xy 210.214191 -269.274931)
			(xy 210.277139 -269.459593) (xy 210.332454 -269.646683) (xy 210.38004 -269.835887) (xy 210.419819 -270.026884)
			(xy 210.451723 -270.219354) (xy 210.475698 -270.412972) (xy 210.491704 -270.60741) (xy 210.499713 -270.802342)
			(xy 210.500214 -270.89989) (xy 210.499713 -270.997438) (xy 210.491704 -271.19237) (xy 210.475698 -271.386808)
			(xy 210.451723 -271.580426) (xy 210.419819 -271.772896) (xy 210.38004 -271.963893) (xy 210.332454 -272.153097)
			(xy 210.277139 -272.340187) (xy 210.214191 -272.524849) (xy 210.143714 -272.706771) (xy 210.065828 -272.885646)
			(xy 209.980663 -273.061172) (xy 209.888365 -273.233055) (xy 209.789087 -273.401002) (xy 209.682998 -273.564733)
			(xy 209.570277 -273.72397) (xy 209.451113 -273.878444) (xy 209.325708 -274.027897) (xy 209.194272 -274.172075)
			(xy 209.057028 -274.310735) (xy 208.914207 -274.443643) (xy 208.76605 -274.570577) (xy 208.687239 -274.632674)
			(xy 226.694998 -274.632674) (xy 226.699069 -274.577052) (xy 226.711195 -274.522615) (xy 226.731118 -274.470524)
			(xy 226.758414 -274.421889) (xy 226.7925 -274.377746) (xy 226.832649 -274.339037) (xy 226.878007 -274.306586)
			(xy 226.927607 -274.281085) (xy 226.980391 -274.263078) (xy 227.035234 -274.252948) (xy 227.090968 -274.250911)
			(xy 227.146405 -274.257011) (xy 227.200362 -274.271117) (xy 227.251691 -274.292929) (xy 227.299297 -274.321983)
			(xy 227.342165 -274.357658) (xy 227.379382 -274.399195) (xy 227.410155 -274.445708) (xy 227.433827 -274.496205)
			(xy 227.449895 -274.549612) (xy 227.458015 -274.604788) (xy 227.458524 -274.632674) (xy 227.458015 -274.66056)
			(xy 227.449895 -274.715736) (xy 227.433827 -274.769143) (xy 227.410155 -274.81964) (xy 227.379382 -274.866153)
			(xy 227.342165 -274.90769) (xy 227.299297 -274.943365) (xy 227.251691 -274.972419) (xy 227.200362 -274.994231)
			(xy 227.146405 -275.008337) (xy 227.090968 -275.014437) (xy 227.035234 -275.0124) (xy 226.980391 -275.00227)
			(xy 226.927607 -274.984263) (xy 226.878007 -274.958762) (xy 226.832649 -274.926311) (xy 226.7925 -274.887602)
			(xy 226.758414 -274.843459) (xy 226.731118 -274.794824) (xy 226.711195 -274.742733) (xy 226.699069 -274.688296)
			(xy 226.694998 -274.632674) (xy 208.687239 -274.632674) (xy 208.612807 -274.69132) (xy 208.454736 -274.80567)
			(xy 208.292103 -274.913435) (xy 208.125184 -275.014431) (xy 207.954258 -275.10849) (xy 207.779615 -275.195452)
			(xy 207.601549 -275.27517) (xy 207.420361 -275.347511) (xy 207.236355 -275.412352) (xy 207.049842 -275.469584)
			(xy 206.861137 -275.519111) (xy 206.670558 -275.560848) (xy 206.478425 -275.594726) (xy 206.285064 -275.620688)
			(xy 206.0908 -275.638689) (xy 205.895961 -275.6487) (xy 205.700875 -275.650703) (xy 205.505872 -275.644695)
			(xy 205.311279 -275.630686) (xy 205.117426 -275.6087) (xy 204.924639 -275.578774) (xy 204.733242 -275.540958)
			(xy 204.54356 -275.495316) (xy 204.355912 -275.441926) (xy 204.170613 -275.380876) (xy 203.987978 -275.312271)
			(xy 203.808313 -275.236225) (xy 203.631921 -275.152867) (xy 203.4591 -275.062338) (xy 203.290142 -274.96479)
			(xy 203.125331 -274.860387) (xy 202.964945 -274.749307) (xy 202.809255 -274.631735) (xy 202.658523 -274.507871)
			(xy 202.513004 -274.377922) (xy 202.372942 -274.242109) (xy 202.238574 -274.10066) (xy 202.110127 -273.953814)
			(xy 201.987816 -273.801819) (xy 201.871849 -273.64493) (xy 201.762421 -273.483412) (xy 201.659716 -273.317538)
			(xy 201.563908 -273.147587) (xy 201.475157 -272.973846) (xy 201.393615 -272.796608) (xy 201.319418 -272.616172)
			(xy 201.252691 -272.432841) (xy 201.193547 -272.246926) (xy 201.142086 -272.058739) (xy 201.098394 -271.868599)
			(xy 201.062545 -271.676824) (xy 201.0346 -271.48374) (xy 201.014605 -271.289671) (xy 201.002595 -271.094945)
			(xy 200.998589 -270.89989) (xy 165.303708 -270.89989) (xy 165.303708 -272.14957) (xy 165.9438 -272.14957)
			(xy 165.94776 -272.100516) (xy 165.959537 -272.052732) (xy 165.978828 -272.007456) (xy 166.005131 -271.96586)
			(xy 166.037766 -271.929023) (xy 166.075887 -271.897898) (xy 166.118508 -271.873291) (xy 166.164524 -271.855839)
			(xy 166.212743 -271.845995) (xy 166.261918 -271.844014) (xy 166.310773 -271.849946) (xy 166.358044 -271.863638)
			(xy 166.402506 -271.884736) (xy 166.443009 -271.912692) (xy 166.478502 -271.946784) (xy 166.508067 -271.986128)
			(xy 166.530938 -272.029705) (xy 166.546522 -272.076386) (xy 166.554417 -272.124963) (xy 166.554912 -272.14957)
			(xy 167.843974 -272.14957) (xy 167.847934 -272.100516) (xy 167.859711 -272.052732) (xy 167.879002 -272.007456)
			(xy 167.905305 -271.96586) (xy 167.93794 -271.929023) (xy 167.976061 -271.897898) (xy 168.018682 -271.873291)
			(xy 168.064698 -271.855839) (xy 168.112917 -271.845995) (xy 168.162092 -271.844014) (xy 168.210947 -271.849946)
			(xy 168.258218 -271.863638) (xy 168.30268 -271.884736) (xy 168.343183 -271.912692) (xy 168.378676 -271.946784)
			(xy 168.408241 -271.986128) (xy 168.431112 -272.029705) (xy 168.446696 -272.076386) (xy 168.454591 -272.124963)
			(xy 168.455086 -272.14957) (xy 169.743894 -272.14957) (xy 169.747854 -272.100516) (xy 169.759631 -272.052732)
			(xy 169.778922 -272.007456) (xy 169.805225 -271.96586) (xy 169.83786 -271.929023) (xy 169.875981 -271.897898)
			(xy 169.918602 -271.873291) (xy 169.964618 -271.855839) (xy 170.012837 -271.845995) (xy 170.062012 -271.844014)
			(xy 170.110867 -271.849946) (xy 170.158138 -271.863638) (xy 170.2026 -271.884736) (xy 170.243103 -271.912692)
			(xy 170.278596 -271.946784) (xy 170.308161 -271.986128) (xy 170.331032 -272.029705) (xy 170.346616 -272.076386)
			(xy 170.354511 -272.124963) (xy 170.355006 -272.14957) (xy 171.643814 -272.14957) (xy 171.647774 -272.100516)
			(xy 171.659551 -272.052732) (xy 171.678842 -272.007456) (xy 171.705145 -271.96586) (xy 171.73778 -271.929023)
			(xy 171.775901 -271.897898) (xy 171.818522 -271.873291) (xy 171.864538 -271.855839) (xy 171.912757 -271.845995)
			(xy 171.961932 -271.844014) (xy 172.010787 -271.849946) (xy 172.058058 -271.863638) (xy 172.10252 -271.884736)
			(xy 172.143023 -271.912692) (xy 172.178516 -271.946784) (xy 172.208081 -271.986128) (xy 172.230952 -272.029705)
			(xy 172.246536 -272.076386) (xy 172.254431 -272.124963) (xy 172.254926 -272.14957) (xy 173.543988 -272.14957)
			(xy 173.547948 -272.100516) (xy 173.559725 -272.052732) (xy 173.579016 -272.007456) (xy 173.605319 -271.96586)
			(xy 173.637954 -271.929023) (xy 173.676075 -271.897898) (xy 173.718696 -271.873291) (xy 173.764712 -271.855839)
			(xy 173.812931 -271.845995) (xy 173.862106 -271.844014) (xy 173.910961 -271.849946) (xy 173.958232 -271.863638)
			(xy 174.002694 -271.884736) (xy 174.043197 -271.912692) (xy 174.07869 -271.946784) (xy 174.108255 -271.986128)
			(xy 174.131126 -272.029705) (xy 174.14671 -272.076386) (xy 174.154605 -272.124963) (xy 174.155095 -272.149316)
			(xy 175.443908 -272.149316) (xy 175.447868 -272.100262) (xy 175.459645 -272.052478) (xy 175.478936 -272.007202)
			(xy 175.505239 -271.965606) (xy 175.537874 -271.928769) (xy 175.575995 -271.897644) (xy 175.618616 -271.873037)
			(xy 175.664632 -271.855585) (xy 175.712851 -271.845741) (xy 175.762026 -271.84376) (xy 175.810881 -271.849692)
			(xy 175.858152 -271.863384) (xy 175.902614 -271.884482) (xy 175.943117 -271.912438) (xy 175.97861 -271.94653)
			(xy 176.008175 -271.985874) (xy 176.031046 -272.029451) (xy 176.04663 -272.076132) (xy 176.054525 -272.124709)
			(xy 176.05502 -272.149316) (xy 176.055015 -272.14957) (xy 177.343828 -272.14957) (xy 177.347788 -272.100516)
			(xy 177.359565 -272.052732) (xy 177.378856 -272.007456) (xy 177.405159 -271.96586) (xy 177.437794 -271.929023)
			(xy 177.475915 -271.897898) (xy 177.518536 -271.873291) (xy 177.564552 -271.855839) (xy 177.612771 -271.845995)
			(xy 177.661946 -271.844014) (xy 177.710801 -271.849946) (xy 177.758072 -271.863638) (xy 177.802534 -271.884736)
			(xy 177.843037 -271.912692) (xy 177.87853 -271.946784) (xy 177.908095 -271.986128) (xy 177.930966 -272.029705)
			(xy 177.94655 -272.076386) (xy 177.954445 -272.124963) (xy 177.95494 -272.14957) (xy 179.244002 -272.14957)
			(xy 179.247962 -272.100516) (xy 179.259739 -272.052732) (xy 179.27903 -272.007456) (xy 179.305333 -271.96586)
			(xy 179.337968 -271.929023) (xy 179.376089 -271.897898) (xy 179.41871 -271.873291) (xy 179.464726 -271.855839)
			(xy 179.512945 -271.845995) (xy 179.56212 -271.844014) (xy 179.610975 -271.849946) (xy 179.658246 -271.863638)
			(xy 179.702708 -271.884736) (xy 179.743211 -271.912692) (xy 179.778704 -271.946784) (xy 179.808269 -271.986128)
			(xy 179.83114 -272.029705) (xy 179.846724 -272.076386) (xy 179.854619 -272.124963) (xy 179.855114 -272.14957)
			(xy 181.143922 -272.14957) (xy 181.147882 -272.100516) (xy 181.159659 -272.052732) (xy 181.17895 -272.007456)
			(xy 181.205253 -271.96586) (xy 181.237888 -271.929023) (xy 181.276009 -271.897898) (xy 181.31863 -271.873291)
			(xy 181.364646 -271.855839) (xy 181.412865 -271.845995) (xy 181.46204 -271.844014) (xy 181.510895 -271.849946)
			(xy 181.558166 -271.863638) (xy 181.602628 -271.884736) (xy 181.643131 -271.912692) (xy 181.678624 -271.946784)
			(xy 181.708189 -271.986128) (xy 181.73106 -272.029705) (xy 181.746644 -272.076386) (xy 181.754539 -272.124963)
			(xy 181.755034 -272.14957) (xy 183.043842 -272.14957) (xy 183.047802 -272.100516) (xy 183.059579 -272.052732)
			(xy 183.07887 -272.007456) (xy 183.105173 -271.96586) (xy 183.137808 -271.929023) (xy 183.175929 -271.897898)
			(xy 183.21855 -271.873291) (xy 183.264566 -271.855839) (xy 183.312785 -271.845995) (xy 183.36196 -271.844014)
			(xy 183.410815 -271.849946) (xy 183.458086 -271.863638) (xy 183.502548 -271.884736) (xy 183.543051 -271.912692)
			(xy 183.578544 -271.946784) (xy 183.608109 -271.986128) (xy 183.63098 -272.029705) (xy 183.646564 -272.076386)
			(xy 183.654459 -272.124963) (xy 183.654954 -272.14957) (xy 184.944016 -272.14957) (xy 184.947976 -272.100516)
			(xy 184.959753 -272.052732) (xy 184.979044 -272.007456) (xy 185.005347 -271.96586) (xy 185.037982 -271.929023)
			(xy 185.076103 -271.897898) (xy 185.118724 -271.873291) (xy 185.16474 -271.855839) (xy 185.212959 -271.845995)
			(xy 185.262134 -271.844014) (xy 185.310989 -271.849946) (xy 185.35826 -271.863638) (xy 185.402722 -271.884736)
			(xy 185.443225 -271.912692) (xy 185.478718 -271.946784) (xy 185.508283 -271.986128) (xy 185.531154 -272.029705)
			(xy 185.546738 -272.076386) (xy 185.554633 -272.124963) (xy 185.555128 -272.14957) (xy 186.843936 -272.14957)
			(xy 186.847896 -272.100516) (xy 186.859673 -272.052732) (xy 186.878964 -272.007456) (xy 186.905267 -271.96586)
			(xy 186.937902 -271.929023) (xy 186.976023 -271.897898) (xy 187.018644 -271.873291) (xy 187.06466 -271.855839)
			(xy 187.112879 -271.845995) (xy 187.162054 -271.844014) (xy 187.210909 -271.849946) (xy 187.25818 -271.863638)
			(xy 187.302642 -271.884736) (xy 187.343145 -271.912692) (xy 187.378638 -271.946784) (xy 187.408203 -271.986128)
			(xy 187.431074 -272.029705) (xy 187.446658 -272.076386) (xy 187.454553 -272.124963) (xy 187.455048 -272.14957)
			(xy 188.743856 -272.14957) (xy 188.747816 -272.100516) (xy 188.759593 -272.052732) (xy 188.778884 -272.007456)
			(xy 188.805187 -271.96586) (xy 188.837822 -271.929023) (xy 188.875943 -271.897898) (xy 188.918564 -271.873291)
			(xy 188.96458 -271.855839) (xy 189.012799 -271.845995) (xy 189.061974 -271.844014) (xy 189.110829 -271.849946)
			(xy 189.1581 -271.863638) (xy 189.202562 -271.884736) (xy 189.243065 -271.912692) (xy 189.278558 -271.946784)
			(xy 189.308123 -271.986128) (xy 189.330994 -272.029705) (xy 189.346578 -272.076386) (xy 189.354473 -272.124963)
			(xy 189.354968 -272.14957) (xy 190.64403 -272.14957) (xy 190.64799 -272.100516) (xy 190.659767 -272.052732)
			(xy 190.679058 -272.007456) (xy 190.705361 -271.96586) (xy 190.737996 -271.929023) (xy 190.776117 -271.897898)
			(xy 190.818738 -271.873291) (xy 190.864754 -271.855839) (xy 190.912973 -271.845995) (xy 190.962148 -271.844014)
			(xy 191.011003 -271.849946) (xy 191.058274 -271.863638) (xy 191.102736 -271.884736) (xy 191.143239 -271.912692)
			(xy 191.178732 -271.946784) (xy 191.208297 -271.986128) (xy 191.231168 -272.029705) (xy 191.246752 -272.076386)
			(xy 191.254647 -272.124963) (xy 191.255142 -272.14957) (xy 192.544204 -272.14957) (xy 192.548164 -272.100516)
			(xy 192.559941 -272.052732) (xy 192.579232 -272.007456) (xy 192.605535 -271.96586) (xy 192.63817 -271.929023)
			(xy 192.676291 -271.897898) (xy 192.718912 -271.873291) (xy 192.764928 -271.855839) (xy 192.813147 -271.845995)
			(xy 192.862322 -271.844014) (xy 192.911177 -271.849946) (xy 192.958448 -271.863638) (xy 193.00291 -271.884736)
			(xy 193.043413 -271.912692) (xy 193.078906 -271.946784) (xy 193.108471 -271.986128) (xy 193.131342 -272.029705)
			(xy 193.146926 -272.076386) (xy 193.154821 -272.124963) (xy 193.155316 -272.14957) (xy 194.444124 -272.14957)
			(xy 194.448084 -272.100516) (xy 194.459861 -272.052732) (xy 194.479152 -272.007456) (xy 194.505455 -271.96586)
			(xy 194.53809 -271.929023) (xy 194.576211 -271.897898) (xy 194.618832 -271.873291) (xy 194.664848 -271.855839)
			(xy 194.713067 -271.845995) (xy 194.762242 -271.844014) (xy 194.811097 -271.849946) (xy 194.858368 -271.863638)
			(xy 194.90283 -271.884736) (xy 194.943333 -271.912692) (xy 194.978826 -271.946784) (xy 195.008391 -271.986128)
			(xy 195.031262 -272.029705) (xy 195.046846 -272.076386) (xy 195.054741 -272.124963) (xy 195.055236 -272.14957)
			(xy 196.344044 -272.14957) (xy 196.348004 -272.100516) (xy 196.359781 -272.052732) (xy 196.379072 -272.007456)
			(xy 196.405375 -271.96586) (xy 196.43801 -271.929023) (xy 196.476131 -271.897898) (xy 196.518752 -271.873291)
			(xy 196.564768 -271.855839) (xy 196.612987 -271.845995) (xy 196.662162 -271.844014) (xy 196.711017 -271.849946)
			(xy 196.758288 -271.863638) (xy 196.80275 -271.884736) (xy 196.843253 -271.912692) (xy 196.878746 -271.946784)
			(xy 196.908311 -271.986128) (xy 196.931182 -272.029705) (xy 196.946766 -272.076386) (xy 196.954661 -272.124963)
			(xy 196.955156 -272.14957) (xy 196.954661 -272.174177) (xy 196.946766 -272.222754) (xy 196.931182 -272.269435)
			(xy 196.908311 -272.313012) (xy 196.878746 -272.352356) (xy 196.843253 -272.386448) (xy 196.80275 -272.414404)
			(xy 196.758288 -272.435502) (xy 196.711017 -272.449194) (xy 196.662162 -272.455126) (xy 196.612987 -272.453145)
			(xy 196.564768 -272.443301) (xy 196.518752 -272.425849) (xy 196.476131 -272.401242) (xy 196.43801 -272.370117)
			(xy 196.405375 -272.33328) (xy 196.379072 -272.291684) (xy 196.359781 -272.246408) (xy 196.348004 -272.198624)
			(xy 196.344044 -272.14957) (xy 195.055236 -272.14957) (xy 195.054741 -272.174177) (xy 195.046846 -272.222754)
			(xy 195.031262 -272.269435) (xy 195.008391 -272.313012) (xy 194.978826 -272.352356) (xy 194.943333 -272.386448)
			(xy 194.90283 -272.414404) (xy 194.858368 -272.435502) (xy 194.811097 -272.449194) (xy 194.762242 -272.455126)
			(xy 194.713067 -272.453145) (xy 194.664848 -272.443301) (xy 194.618832 -272.425849) (xy 194.576211 -272.401242)
			(xy 194.53809 -272.370117) (xy 194.505455 -272.33328) (xy 194.479152 -272.291684) (xy 194.459861 -272.246408)
			(xy 194.448084 -272.198624) (xy 194.444124 -272.14957) (xy 193.155316 -272.14957) (xy 193.154821 -272.174177)
			(xy 193.146926 -272.222754) (xy 193.131342 -272.269435) (xy 193.108471 -272.313012) (xy 193.078906 -272.352356)
			(xy 193.043413 -272.386448) (xy 193.00291 -272.414404) (xy 192.958448 -272.435502) (xy 192.911177 -272.449194)
			(xy 192.862322 -272.455126) (xy 192.813147 -272.453145) (xy 192.764928 -272.443301) (xy 192.718912 -272.425849)
			(xy 192.676291 -272.401242) (xy 192.63817 -272.370117) (xy 192.605535 -272.33328) (xy 192.579232 -272.291684)
			(xy 192.559941 -272.246408) (xy 192.548164 -272.198624) (xy 192.544204 -272.14957) (xy 191.255142 -272.14957)
			(xy 191.254647 -272.174177) (xy 191.246752 -272.222754) (xy 191.231168 -272.269435) (xy 191.208297 -272.313012)
			(xy 191.178732 -272.352356) (xy 191.143239 -272.386448) (xy 191.102736 -272.414404) (xy 191.058274 -272.435502)
			(xy 191.011003 -272.449194) (xy 190.962148 -272.455126) (xy 190.912973 -272.453145) (xy 190.864754 -272.443301)
			(xy 190.818738 -272.425849) (xy 190.776117 -272.401242) (xy 190.737996 -272.370117) (xy 190.705361 -272.33328)
			(xy 190.679058 -272.291684) (xy 190.659767 -272.246408) (xy 190.64799 -272.198624) (xy 190.64403 -272.14957)
			(xy 189.354968 -272.14957) (xy 189.354473 -272.174177) (xy 189.346578 -272.222754) (xy 189.330994 -272.269435)
			(xy 189.308123 -272.313012) (xy 189.278558 -272.352356) (xy 189.243065 -272.386448) (xy 189.202562 -272.414404)
			(xy 189.1581 -272.435502) (xy 189.110829 -272.449194) (xy 189.061974 -272.455126) (xy 189.012799 -272.453145)
			(xy 188.96458 -272.443301) (xy 188.918564 -272.425849) (xy 188.875943 -272.401242) (xy 188.837822 -272.370117)
			(xy 188.805187 -272.33328) (xy 188.778884 -272.291684) (xy 188.759593 -272.246408) (xy 188.747816 -272.198624)
			(xy 188.743856 -272.14957) (xy 187.455048 -272.14957) (xy 187.454553 -272.174177) (xy 187.446658 -272.222754)
			(xy 187.431074 -272.269435) (xy 187.408203 -272.313012) (xy 187.378638 -272.352356) (xy 187.343145 -272.386448)
			(xy 187.302642 -272.414404) (xy 187.25818 -272.435502) (xy 187.210909 -272.449194) (xy 187.162054 -272.455126)
			(xy 187.112879 -272.453145) (xy 187.06466 -272.443301) (xy 187.018644 -272.425849) (xy 186.976023 -272.401242)
			(xy 186.937902 -272.370117) (xy 186.905267 -272.33328) (xy 186.878964 -272.291684) (xy 186.859673 -272.246408)
			(xy 186.847896 -272.198624) (xy 186.843936 -272.14957) (xy 185.555128 -272.14957) (xy 185.554633 -272.174177)
			(xy 185.546738 -272.222754) (xy 185.531154 -272.269435) (xy 185.508283 -272.313012) (xy 185.478718 -272.352356)
			(xy 185.443225 -272.386448) (xy 185.402722 -272.414404) (xy 185.35826 -272.435502) (xy 185.310989 -272.449194)
			(xy 185.262134 -272.455126) (xy 185.212959 -272.453145) (xy 185.16474 -272.443301) (xy 185.118724 -272.425849)
			(xy 185.076103 -272.401242) (xy 185.037982 -272.370117) (xy 185.005347 -272.33328) (xy 184.979044 -272.291684)
			(xy 184.959753 -272.246408) (xy 184.947976 -272.198624) (xy 184.944016 -272.14957) (xy 183.654954 -272.14957)
			(xy 183.654459 -272.174177) (xy 183.646564 -272.222754) (xy 183.63098 -272.269435) (xy 183.608109 -272.313012)
			(xy 183.578544 -272.352356) (xy 183.543051 -272.386448) (xy 183.502548 -272.414404) (xy 183.458086 -272.435502)
			(xy 183.410815 -272.449194) (xy 183.36196 -272.455126) (xy 183.312785 -272.453145) (xy 183.264566 -272.443301)
			(xy 183.21855 -272.425849) (xy 183.175929 -272.401242) (xy 183.137808 -272.370117) (xy 183.105173 -272.33328)
			(xy 183.07887 -272.291684) (xy 183.059579 -272.246408) (xy 183.047802 -272.198624) (xy 183.043842 -272.14957)
			(xy 181.755034 -272.14957) (xy 181.754539 -272.174177) (xy 181.746644 -272.222754) (xy 181.73106 -272.269435)
			(xy 181.708189 -272.313012) (xy 181.678624 -272.352356) (xy 181.643131 -272.386448) (xy 181.602628 -272.414404)
			(xy 181.558166 -272.435502) (xy 181.510895 -272.449194) (xy 181.46204 -272.455126) (xy 181.412865 -272.453145)
			(xy 181.364646 -272.443301) (xy 181.31863 -272.425849) (xy 181.276009 -272.401242) (xy 181.237888 -272.370117)
			(xy 181.205253 -272.33328) (xy 181.17895 -272.291684) (xy 181.159659 -272.246408) (xy 181.147882 -272.198624)
			(xy 181.143922 -272.14957) (xy 179.855114 -272.14957) (xy 179.854619 -272.174177) (xy 179.846724 -272.222754)
			(xy 179.83114 -272.269435) (xy 179.808269 -272.313012) (xy 179.778704 -272.352356) (xy 179.743211 -272.386448)
			(xy 179.702708 -272.414404) (xy 179.658246 -272.435502) (xy 179.610975 -272.449194) (xy 179.56212 -272.455126)
			(xy 179.512945 -272.453145) (xy 179.464726 -272.443301) (xy 179.41871 -272.425849) (xy 179.376089 -272.401242)
			(xy 179.337968 -272.370117) (xy 179.305333 -272.33328) (xy 179.27903 -272.291684) (xy 179.259739 -272.246408)
			(xy 179.247962 -272.198624) (xy 179.244002 -272.14957) (xy 177.95494 -272.14957) (xy 177.954445 -272.174177)
			(xy 177.94655 -272.222754) (xy 177.930966 -272.269435) (xy 177.908095 -272.313012) (xy 177.87853 -272.352356)
			(xy 177.843037 -272.386448) (xy 177.802534 -272.414404) (xy 177.758072 -272.435502) (xy 177.710801 -272.449194)
			(xy 177.661946 -272.455126) (xy 177.612771 -272.453145) (xy 177.564552 -272.443301) (xy 177.518536 -272.425849)
			(xy 177.475915 -272.401242) (xy 177.437794 -272.370117) (xy 177.405159 -272.33328) (xy 177.378856 -272.291684)
			(xy 177.359565 -272.246408) (xy 177.347788 -272.198624) (xy 177.343828 -272.14957) (xy 176.055015 -272.14957)
			(xy 176.054525 -272.173923) (xy 176.04663 -272.2225) (xy 176.031046 -272.269181) (xy 176.008175 -272.312758)
			(xy 175.97861 -272.352102) (xy 175.943117 -272.386194) (xy 175.902614 -272.41415) (xy 175.858152 -272.435248)
			(xy 175.810881 -272.44894) (xy 175.762026 -272.454872) (xy 175.712851 -272.452891) (xy 175.664632 -272.443047)
			(xy 175.618616 -272.425595) (xy 175.575995 -272.400988) (xy 175.537874 -272.369863) (xy 175.505239 -272.333026)
			(xy 175.478936 -272.29143) (xy 175.459645 -272.246154) (xy 175.447868 -272.19837) (xy 175.443908 -272.149316)
			(xy 174.155095 -272.149316) (xy 174.1551 -272.14957) (xy 174.154605 -272.174177) (xy 174.14671 -272.222754)
			(xy 174.131126 -272.269435) (xy 174.108255 -272.313012) (xy 174.07869 -272.352356) (xy 174.043197 -272.386448)
			(xy 174.002694 -272.414404) (xy 173.958232 -272.435502) (xy 173.910961 -272.449194) (xy 173.862106 -272.455126)
			(xy 173.812931 -272.453145) (xy 173.764712 -272.443301) (xy 173.718696 -272.425849) (xy 173.676075 -272.401242)
			(xy 173.637954 -272.370117) (xy 173.605319 -272.33328) (xy 173.579016 -272.291684) (xy 173.559725 -272.246408)
			(xy 173.547948 -272.198624) (xy 173.543988 -272.14957) (xy 172.254926 -272.14957) (xy 172.254431 -272.174177)
			(xy 172.246536 -272.222754) (xy 172.230952 -272.269435) (xy 172.208081 -272.313012) (xy 172.178516 -272.352356)
			(xy 172.143023 -272.386448) (xy 172.10252 -272.414404) (xy 172.058058 -272.435502) (xy 172.010787 -272.449194)
			(xy 171.961932 -272.455126) (xy 171.912757 -272.453145) (xy 171.864538 -272.443301) (xy 171.818522 -272.425849)
			(xy 171.775901 -272.401242) (xy 171.73778 -272.370117) (xy 171.705145 -272.33328) (xy 171.678842 -272.291684)
			(xy 171.659551 -272.246408) (xy 171.647774 -272.198624) (xy 171.643814 -272.14957) (xy 170.355006 -272.14957)
			(xy 170.354511 -272.174177) (xy 170.346616 -272.222754) (xy 170.331032 -272.269435) (xy 170.308161 -272.313012)
			(xy 170.278596 -272.352356) (xy 170.243103 -272.386448) (xy 170.2026 -272.414404) (xy 170.158138 -272.435502)
			(xy 170.110867 -272.449194) (xy 170.062012 -272.455126) (xy 170.012837 -272.453145) (xy 169.964618 -272.443301)
			(xy 169.918602 -272.425849) (xy 169.875981 -272.401242) (xy 169.83786 -272.370117) (xy 169.805225 -272.33328)
			(xy 169.778922 -272.291684) (xy 169.759631 -272.246408) (xy 169.747854 -272.198624) (xy 169.743894 -272.14957)
			(xy 168.455086 -272.14957) (xy 168.454591 -272.174177) (xy 168.446696 -272.222754) (xy 168.431112 -272.269435)
			(xy 168.408241 -272.313012) (xy 168.378676 -272.352356) (xy 168.343183 -272.386448) (xy 168.30268 -272.414404)
			(xy 168.258218 -272.435502) (xy 168.210947 -272.449194) (xy 168.162092 -272.455126) (xy 168.112917 -272.453145)
			(xy 168.064698 -272.443301) (xy 168.018682 -272.425849) (xy 167.976061 -272.401242) (xy 167.93794 -272.370117)
			(xy 167.905305 -272.33328) (xy 167.879002 -272.291684) (xy 167.859711 -272.246408) (xy 167.847934 -272.198624)
			(xy 167.843974 -272.14957) (xy 166.554912 -272.14957) (xy 166.554417 -272.174177) (xy 166.546522 -272.222754)
			(xy 166.530938 -272.269435) (xy 166.508067 -272.313012) (xy 166.478502 -272.352356) (xy 166.443009 -272.386448)
			(xy 166.402506 -272.414404) (xy 166.358044 -272.435502) (xy 166.310773 -272.449194) (xy 166.261918 -272.455126)
			(xy 166.212743 -272.453145) (xy 166.164524 -272.443301) (xy 166.118508 -272.425849) (xy 166.075887 -272.401242)
			(xy 166.037766 -272.370117) (xy 166.005131 -272.33328) (xy 165.978828 -272.291684) (xy 165.959537 -272.246408)
			(xy 165.94776 -272.198624) (xy 165.9438 -272.14957) (xy 165.303708 -272.14957) (xy 165.303708 -272.76679)
			(xy 165.327838 -272.795238) (xy 165.346634 -272.798032) (xy 165.370337 -272.802159) (xy 165.416139 -272.816887)
			(xy 165.459065 -272.838614) (xy 165.498052 -272.866804) (xy 165.532137 -272.900759) (xy 165.560476 -272.939638)
			(xy 165.582367 -272.982481) (xy 165.597269 -273.028226) (xy 165.604814 -273.075742) (xy 165.604815 -273.123853)
			(xy 165.604555 -273.125492) (xy 165.92321 -273.125492) (xy 165.92321 -273.074076) (xy 165.931253 -273.023294)
			(xy 165.947141 -272.974395) (xy 165.970484 -272.928583) (xy 166.000705 -272.886987) (xy 166.037061 -272.850631)
			(xy 166.078657 -272.82041) (xy 166.124469 -272.797067) (xy 166.173368 -272.781179) (xy 166.22415 -272.773136)
			(xy 166.275566 -272.773136) (xy 166.326348 -272.781179) (xy 166.375247 -272.797067) (xy 166.421059 -272.82041)
			(xy 166.462655 -272.850631) (xy 166.499011 -272.886987) (xy 166.529232 -272.928583) (xy 166.552575 -272.974395)
			(xy 166.568463 -273.023294) (xy 166.576506 -273.074076) (xy 166.57701 -273.099784) (xy 166.894268 -273.099784)
			(xy 166.898228 -273.05073) (xy 166.910005 -273.002946) (xy 166.929296 -272.95767) (xy 166.955599 -272.916074)
			(xy 166.988234 -272.879237) (xy 167.026355 -272.848112) (xy 167.068976 -272.823505) (xy 167.114992 -272.806053)
			(xy 167.163211 -272.796209) (xy 167.212386 -272.794228) (xy 167.261241 -272.80016) (xy 167.308512 -272.813852)
			(xy 167.352974 -272.83495) (xy 167.393477 -272.862906) (xy 167.42897 -272.896998) (xy 167.458535 -272.936342)
			(xy 167.481406 -272.979919) (xy 167.49699 -273.0266) (xy 167.504885 -273.075177) (xy 167.50538 -273.099784)
			(xy 167.504885 -273.124391) (xy 167.504706 -273.125492) (xy 167.823384 -273.125492) (xy 167.823384 -273.074076)
			(xy 167.831427 -273.023294) (xy 167.847315 -272.974395) (xy 167.870658 -272.928583) (xy 167.900879 -272.886987)
			(xy 167.937235 -272.850631) (xy 167.978831 -272.82041) (xy 168.024643 -272.797067) (xy 168.073542 -272.781179)
			(xy 168.124324 -272.773136) (xy 168.17574 -272.773136) (xy 168.226522 -272.781179) (xy 168.275421 -272.797067)
			(xy 168.321233 -272.82041) (xy 168.362829 -272.850631) (xy 168.399185 -272.886987) (xy 168.429406 -272.928583)
			(xy 168.452749 -272.974395) (xy 168.468637 -273.023294) (xy 168.47668 -273.074076) (xy 168.477184 -273.099784)
			(xy 168.794188 -273.099784) (xy 168.798148 -273.05073) (xy 168.809925 -273.002946) (xy 168.829216 -272.95767)
			(xy 168.855519 -272.916074) (xy 168.888154 -272.879237) (xy 168.926275 -272.848112) (xy 168.968896 -272.823505)
			(xy 169.014912 -272.806053) (xy 169.063131 -272.796209) (xy 169.112306 -272.794228) (xy 169.161161 -272.80016)
			(xy 169.208432 -272.813852) (xy 169.252894 -272.83495) (xy 169.293397 -272.862906) (xy 169.32889 -272.896998)
			(xy 169.358455 -272.936342) (xy 169.381326 -272.979919) (xy 169.39691 -273.0266) (xy 169.404805 -273.075177)
			(xy 169.4053 -273.099784) (xy 169.404805 -273.124391) (xy 169.404626 -273.125492) (xy 169.723304 -273.125492)
			(xy 169.723304 -273.074076) (xy 169.731347 -273.023294) (xy 169.747235 -272.974395) (xy 169.770578 -272.928583)
			(xy 169.800799 -272.886987) (xy 169.837155 -272.850631) (xy 169.878751 -272.82041) (xy 169.924563 -272.797067)
			(xy 169.973462 -272.781179) (xy 170.024244 -272.773136) (xy 170.07566 -272.773136) (xy 170.126442 -272.781179)
			(xy 170.175341 -272.797067) (xy 170.221153 -272.82041) (xy 170.262749 -272.850631) (xy 170.299105 -272.886987)
			(xy 170.329326 -272.928583) (xy 170.352669 -272.974395) (xy 170.368557 -273.023294) (xy 170.3766 -273.074076)
			(xy 170.377104 -273.099784) (xy 170.694108 -273.099784) (xy 170.698068 -273.05073) (xy 170.709845 -273.002946)
			(xy 170.729136 -272.95767) (xy 170.755439 -272.916074) (xy 170.788074 -272.879237) (xy 170.826195 -272.848112)
			(xy 170.868816 -272.823505) (xy 170.914832 -272.806053) (xy 170.963051 -272.796209) (xy 171.012226 -272.794228)
			(xy 171.061081 -272.80016) (xy 171.108352 -272.813852) (xy 171.152814 -272.83495) (xy 171.193317 -272.862906)
			(xy 171.22881 -272.896998) (xy 171.258375 -272.936342) (xy 171.281246 -272.979919) (xy 171.29683 -273.0266)
			(xy 171.304725 -273.075177) (xy 171.30522 -273.099784) (xy 171.304725 -273.124391) (xy 171.304546 -273.125492)
			(xy 171.623224 -273.125492) (xy 171.623224 -273.074076) (xy 171.631267 -273.023294) (xy 171.647155 -272.974395)
			(xy 171.670498 -272.928583) (xy 171.700719 -272.886987) (xy 171.737075 -272.850631) (xy 171.778671 -272.82041)
			(xy 171.824483 -272.797067) (xy 171.873382 -272.781179) (xy 171.924164 -272.773136) (xy 171.97558 -272.773136)
			(xy 172.026362 -272.781179) (xy 172.075261 -272.797067) (xy 172.121073 -272.82041) (xy 172.162669 -272.850631)
			(xy 172.199025 -272.886987) (xy 172.229246 -272.928583) (xy 172.252589 -272.974395) (xy 172.268477 -273.023294)
			(xy 172.27652 -273.074076) (xy 172.277024 -273.099784) (xy 172.594282 -273.099784) (xy 172.598242 -273.05073)
			(xy 172.610019 -273.002946) (xy 172.62931 -272.95767) (xy 172.655613 -272.916074) (xy 172.688248 -272.879237)
			(xy 172.726369 -272.848112) (xy 172.76899 -272.823505) (xy 172.815006 -272.806053) (xy 172.863225 -272.796209)
			(xy 172.9124 -272.794228) (xy 172.961255 -272.80016) (xy 173.008526 -272.813852) (xy 173.052988 -272.83495)
			(xy 173.093491 -272.862906) (xy 173.128984 -272.896998) (xy 173.158549 -272.936342) (xy 173.18142 -272.979919)
			(xy 173.197004 -273.0266) (xy 173.204899 -273.075177) (xy 173.205394 -273.099784) (xy 173.204899 -273.124391)
			(xy 173.20472 -273.125492) (xy 173.523398 -273.125492) (xy 173.523398 -273.074076) (xy 173.531441 -273.023294)
			(xy 173.547329 -272.974395) (xy 173.570672 -272.928583) (xy 173.600893 -272.886987) (xy 173.637249 -272.850631)
			(xy 173.678845 -272.82041) (xy 173.724657 -272.797067) (xy 173.773556 -272.781179) (xy 173.824338 -272.773136)
			(xy 173.875754 -272.773136) (xy 173.926536 -272.781179) (xy 173.975435 -272.797067) (xy 174.021247 -272.82041)
			(xy 174.062843 -272.850631) (xy 174.099199 -272.886987) (xy 174.12942 -272.928583) (xy 174.152763 -272.974395)
			(xy 174.168651 -273.023294) (xy 174.176694 -273.074076) (xy 174.177198 -273.099784) (xy 174.494202 -273.099784)
			(xy 174.498162 -273.05073) (xy 174.509939 -273.002946) (xy 174.52923 -272.95767) (xy 174.555533 -272.916074)
			(xy 174.588168 -272.879237) (xy 174.626289 -272.848112) (xy 174.66891 -272.823505) (xy 174.714926 -272.806053)
			(xy 174.763145 -272.796209) (xy 174.81232 -272.794228) (xy 174.861175 -272.80016) (xy 174.908446 -272.813852)
			(xy 174.952908 -272.83495) (xy 174.993411 -272.862906) (xy 175.028904 -272.896998) (xy 175.058469 -272.936342)
			(xy 175.08134 -272.979919) (xy 175.096924 -273.0266) (xy 175.104819 -273.075177) (xy 175.105314 -273.099784)
			(xy 175.104819 -273.124391) (xy 175.104681 -273.125238) (xy 175.423064 -273.125238) (xy 175.423064 -273.073822)
			(xy 175.431107 -273.02304) (xy 175.446995 -272.974141) (xy 175.470338 -272.928329) (xy 175.500559 -272.886733)
			(xy 175.536915 -272.850377) (xy 175.578511 -272.820156) (xy 175.624323 -272.796813) (xy 175.673222 -272.780925)
			(xy 175.724004 -272.772882) (xy 175.77542 -272.772882) (xy 175.826202 -272.780925) (xy 175.875101 -272.796813)
			(xy 175.920913 -272.820156) (xy 175.962509 -272.850377) (xy 175.998865 -272.886733) (xy 176.029086 -272.928329)
			(xy 176.052429 -272.974141) (xy 176.068317 -273.02304) (xy 176.07636 -273.073822) (xy 176.076864 -273.09953)
			(xy 176.076859 -273.099784) (xy 176.394122 -273.099784) (xy 176.398082 -273.05073) (xy 176.409859 -273.002946)
			(xy 176.42915 -272.95767) (xy 176.455453 -272.916074) (xy 176.488088 -272.879237) (xy 176.526209 -272.848112)
			(xy 176.56883 -272.823505) (xy 176.614846 -272.806053) (xy 176.663065 -272.796209) (xy 176.71224 -272.794228)
			(xy 176.761095 -272.80016) (xy 176.808366 -272.813852) (xy 176.852828 -272.83495) (xy 176.893331 -272.862906)
			(xy 176.928824 -272.896998) (xy 176.958389 -272.936342) (xy 176.98126 -272.979919) (xy 176.996844 -273.0266)
			(xy 177.004739 -273.075177) (xy 177.005234 -273.099784) (xy 177.004739 -273.124391) (xy 177.00456 -273.125492)
			(xy 177.322984 -273.125492) (xy 177.322984 -273.074076) (xy 177.331027 -273.023294) (xy 177.346915 -272.974395)
			(xy 177.370258 -272.928583) (xy 177.400479 -272.886987) (xy 177.436835 -272.850631) (xy 177.478431 -272.82041)
			(xy 177.524243 -272.797067) (xy 177.573142 -272.781179) (xy 177.623924 -272.773136) (xy 177.67534 -272.773136)
			(xy 177.726122 -272.781179) (xy 177.775021 -272.797067) (xy 177.820833 -272.82041) (xy 177.862429 -272.850631)
			(xy 177.898785 -272.886987) (xy 177.929006 -272.928583) (xy 177.952349 -272.974395) (xy 177.968237 -273.023294)
			(xy 177.97628 -273.074076) (xy 177.976784 -273.099784) (xy 178.294042 -273.099784) (xy 178.298002 -273.05073)
			(xy 178.309779 -273.002946) (xy 178.32907 -272.95767) (xy 178.355373 -272.916074) (xy 178.388008 -272.879237)
			(xy 178.426129 -272.848112) (xy 178.46875 -272.823505) (xy 178.514766 -272.806053) (xy 178.562985 -272.796209)
			(xy 178.61216 -272.794228) (xy 178.661015 -272.80016) (xy 178.708286 -272.813852) (xy 178.752748 -272.83495)
			(xy 178.793251 -272.862906) (xy 178.828744 -272.896998) (xy 178.858309 -272.936342) (xy 178.88118 -272.979919)
			(xy 178.896764 -273.0266) (xy 178.904659 -273.075177) (xy 178.905154 -273.099784) (xy 178.904659 -273.124391)
			(xy 178.90448 -273.125492) (xy 179.223158 -273.125492) (xy 179.223158 -273.074076) (xy 179.231201 -273.023294)
			(xy 179.247089 -272.974395) (xy 179.270432 -272.928583) (xy 179.300653 -272.886987) (xy 179.337009 -272.850631)
			(xy 179.378605 -272.82041) (xy 179.424417 -272.797067) (xy 179.473316 -272.781179) (xy 179.524098 -272.773136)
			(xy 179.575514 -272.773136) (xy 179.626296 -272.781179) (xy 179.675195 -272.797067) (xy 179.721007 -272.82041)
			(xy 179.762603 -272.850631) (xy 179.798959 -272.886987) (xy 179.82918 -272.928583) (xy 179.852523 -272.974395)
			(xy 179.868411 -273.023294) (xy 179.876454 -273.074076) (xy 179.876958 -273.099784) (xy 180.194216 -273.099784)
			(xy 180.198176 -273.05073) (xy 180.209953 -273.002946) (xy 180.229244 -272.95767) (xy 180.255547 -272.916074)
			(xy 180.288182 -272.879237) (xy 180.326303 -272.848112) (xy 180.368924 -272.823505) (xy 180.41494 -272.806053)
			(xy 180.463159 -272.796209) (xy 180.512334 -272.794228) (xy 180.561189 -272.80016) (xy 180.60846 -272.813852)
			(xy 180.652922 -272.83495) (xy 180.693425 -272.862906) (xy 180.728918 -272.896998) (xy 180.758483 -272.936342)
			(xy 180.781354 -272.979919) (xy 180.796938 -273.0266) (xy 180.804833 -273.075177) (xy 180.805328 -273.099784)
			(xy 180.804833 -273.124391) (xy 180.804654 -273.125492) (xy 181.123078 -273.125492) (xy 181.123078 -273.074076)
			(xy 181.131121 -273.023294) (xy 181.147009 -272.974395) (xy 181.170352 -272.928583) (xy 181.200573 -272.886987)
			(xy 181.236929 -272.850631) (xy 181.278525 -272.82041) (xy 181.324337 -272.797067) (xy 181.373236 -272.781179)
			(xy 181.424018 -272.773136) (xy 181.475434 -272.773136) (xy 181.526216 -272.781179) (xy 181.575115 -272.797067)
			(xy 181.620927 -272.82041) (xy 181.662523 -272.850631) (xy 181.698879 -272.886987) (xy 181.7291 -272.928583)
			(xy 181.752443 -272.974395) (xy 181.768331 -273.023294) (xy 181.776374 -273.074076) (xy 181.776878 -273.099784)
			(xy 182.094136 -273.099784) (xy 182.098096 -273.05073) (xy 182.109873 -273.002946) (xy 182.129164 -272.95767)
			(xy 182.155467 -272.916074) (xy 182.188102 -272.879237) (xy 182.226223 -272.848112) (xy 182.268844 -272.823505)
			(xy 182.31486 -272.806053) (xy 182.363079 -272.796209) (xy 182.412254 -272.794228) (xy 182.461109 -272.80016)
			(xy 182.50838 -272.813852) (xy 182.552842 -272.83495) (xy 182.593345 -272.862906) (xy 182.628838 -272.896998)
			(xy 182.658403 -272.936342) (xy 182.681274 -272.979919) (xy 182.696858 -273.0266) (xy 182.704753 -273.075177)
			(xy 182.705248 -273.099784) (xy 182.704753 -273.124391) (xy 182.704574 -273.125492) (xy 183.022998 -273.125492)
			(xy 183.022998 -273.074076) (xy 183.031041 -273.023294) (xy 183.046929 -272.974395) (xy 183.070272 -272.928583)
			(xy 183.100493 -272.886987) (xy 183.136849 -272.850631) (xy 183.178445 -272.82041) (xy 183.224257 -272.797067)
			(xy 183.273156 -272.781179) (xy 183.323938 -272.773136) (xy 183.375354 -272.773136) (xy 183.426136 -272.781179)
			(xy 183.475035 -272.797067) (xy 183.520847 -272.82041) (xy 183.562443 -272.850631) (xy 183.598799 -272.886987)
			(xy 183.62902 -272.928583) (xy 183.652363 -272.974395) (xy 183.668251 -273.023294) (xy 183.676294 -273.074076)
			(xy 183.676798 -273.099784) (xy 183.994056 -273.099784) (xy 183.998016 -273.05073) (xy 184.009793 -273.002946)
			(xy 184.029084 -272.95767) (xy 184.055387 -272.916074) (xy 184.088022 -272.879237) (xy 184.126143 -272.848112)
			(xy 184.168764 -272.823505) (xy 184.21478 -272.806053) (xy 184.262999 -272.796209) (xy 184.312174 -272.794228)
			(xy 184.361029 -272.80016) (xy 184.4083 -272.813852) (xy 184.452762 -272.83495) (xy 184.493265 -272.862906)
			(xy 184.528758 -272.896998) (xy 184.558323 -272.936342) (xy 184.581194 -272.979919) (xy 184.596778 -273.0266)
			(xy 184.604673 -273.075177) (xy 184.605168 -273.099784) (xy 184.604673 -273.124391) (xy 184.604494 -273.125492)
			(xy 184.923172 -273.125492) (xy 184.923172 -273.074076) (xy 184.931215 -273.023294) (xy 184.947103 -272.974395)
			(xy 184.970446 -272.928583) (xy 185.000667 -272.886987) (xy 185.037023 -272.850631) (xy 185.078619 -272.82041)
			(xy 185.124431 -272.797067) (xy 185.17333 -272.781179) (xy 185.224112 -272.773136) (xy 185.275528 -272.773136)
			(xy 185.32631 -272.781179) (xy 185.375209 -272.797067) (xy 185.421021 -272.82041) (xy 185.462617 -272.850631)
			(xy 185.498973 -272.886987) (xy 185.529194 -272.928583) (xy 185.552537 -272.974395) (xy 185.568425 -273.023294)
			(xy 185.576468 -273.074076) (xy 185.576972 -273.099784) (xy 185.89423 -273.099784) (xy 185.89819 -273.05073)
			(xy 185.909967 -273.002946) (xy 185.929258 -272.95767) (xy 185.955561 -272.916074) (xy 185.988196 -272.879237)
			(xy 186.026317 -272.848112) (xy 186.068938 -272.823505) (xy 186.114954 -272.806053) (xy 186.163173 -272.796209)
			(xy 186.212348 -272.794228) (xy 186.261203 -272.80016) (xy 186.308474 -272.813852) (xy 186.352936 -272.83495)
			(xy 186.393439 -272.862906) (xy 186.428932 -272.896998) (xy 186.458497 -272.936342) (xy 186.481368 -272.979919)
			(xy 186.496952 -273.0266) (xy 186.504847 -273.075177) (xy 186.505342 -273.099784) (xy 186.504847 -273.124391)
			(xy 186.504668 -273.125492) (xy 186.823092 -273.125492) (xy 186.823092 -273.074076) (xy 186.831135 -273.023294)
			(xy 186.847023 -272.974395) (xy 186.870366 -272.928583) (xy 186.900587 -272.886987) (xy 186.936943 -272.850631)
			(xy 186.978539 -272.82041) (xy 187.024351 -272.797067) (xy 187.07325 -272.781179) (xy 187.124032 -272.773136)
			(xy 187.175448 -272.773136) (xy 187.22623 -272.781179) (xy 187.275129 -272.797067) (xy 187.320941 -272.82041)
			(xy 187.362537 -272.850631) (xy 187.398893 -272.886987) (xy 187.429114 -272.928583) (xy 187.452457 -272.974395)
			(xy 187.468345 -273.023294) (xy 187.476388 -273.074076) (xy 187.476892 -273.099784) (xy 187.79415 -273.099784)
			(xy 187.79811 -273.05073) (xy 187.809887 -273.002946) (xy 187.829178 -272.95767) (xy 187.855481 -272.916074)
			(xy 187.888116 -272.879237) (xy 187.926237 -272.848112) (xy 187.968858 -272.823505) (xy 188.014874 -272.806053)
			(xy 188.063093 -272.796209) (xy 188.112268 -272.794228) (xy 188.161123 -272.80016) (xy 188.208394 -272.813852)
			(xy 188.252856 -272.83495) (xy 188.293359 -272.862906) (xy 188.328852 -272.896998) (xy 188.358417 -272.936342)
			(xy 188.381288 -272.979919) (xy 188.396872 -273.0266) (xy 188.404767 -273.075177) (xy 188.405262 -273.099784)
			(xy 188.404767 -273.124391) (xy 188.404588 -273.125492) (xy 188.723012 -273.125492) (xy 188.723012 -273.074076)
			(xy 188.731055 -273.023294) (xy 188.746943 -272.974395) (xy 188.770286 -272.928583) (xy 188.800507 -272.886987)
			(xy 188.836863 -272.850631) (xy 188.878459 -272.82041) (xy 188.924271 -272.797067) (xy 188.97317 -272.781179)
			(xy 189.023952 -272.773136) (xy 189.075368 -272.773136) (xy 189.12615 -272.781179) (xy 189.175049 -272.797067)
			(xy 189.220861 -272.82041) (xy 189.262457 -272.850631) (xy 189.298813 -272.886987) (xy 189.329034 -272.928583)
			(xy 189.352377 -272.974395) (xy 189.368265 -273.023294) (xy 189.376308 -273.074076) (xy 189.376812 -273.099784)
			(xy 189.69407 -273.099784) (xy 189.69803 -273.05073) (xy 189.709807 -273.002946) (xy 189.729098 -272.95767)
			(xy 189.755401 -272.916074) (xy 189.788036 -272.879237) (xy 189.826157 -272.848112) (xy 189.868778 -272.823505)
			(xy 189.914794 -272.806053) (xy 189.963013 -272.796209) (xy 190.012188 -272.794228) (xy 190.061043 -272.80016)
			(xy 190.108314 -272.813852) (xy 190.152776 -272.83495) (xy 190.193279 -272.862906) (xy 190.228772 -272.896998)
			(xy 190.258337 -272.936342) (xy 190.281208 -272.979919) (xy 190.296792 -273.0266) (xy 190.304687 -273.075177)
			(xy 190.305182 -273.099784) (xy 190.304687 -273.124391) (xy 190.304508 -273.125492) (xy 190.623186 -273.125492)
			(xy 190.623186 -273.074076) (xy 190.631229 -273.023294) (xy 190.647117 -272.974395) (xy 190.67046 -272.928583)
			(xy 190.700681 -272.886987) (xy 190.737037 -272.850631) (xy 190.778633 -272.82041) (xy 190.824445 -272.797067)
			(xy 190.873344 -272.781179) (xy 190.924126 -272.773136) (xy 190.975542 -272.773136) (xy 191.026324 -272.781179)
			(xy 191.075223 -272.797067) (xy 191.121035 -272.82041) (xy 191.162631 -272.850631) (xy 191.198987 -272.886987)
			(xy 191.229208 -272.928583) (xy 191.252551 -272.974395) (xy 191.268439 -273.023294) (xy 191.276482 -273.074076)
			(xy 191.276986 -273.099784) (xy 191.594244 -273.099784) (xy 191.598204 -273.05073) (xy 191.609981 -273.002946)
			(xy 191.629272 -272.95767) (xy 191.655575 -272.916074) (xy 191.68821 -272.879237) (xy 191.726331 -272.848112)
			(xy 191.768952 -272.823505) (xy 191.814968 -272.806053) (xy 191.863187 -272.796209) (xy 191.912362 -272.794228)
			(xy 191.961217 -272.80016) (xy 192.008488 -272.813852) (xy 192.05295 -272.83495) (xy 192.093453 -272.862906)
			(xy 192.128946 -272.896998) (xy 192.158511 -272.936342) (xy 192.181382 -272.979919) (xy 192.196966 -273.0266)
			(xy 192.204861 -273.075177) (xy 192.205356 -273.099784) (xy 192.204861 -273.124391) (xy 192.204682 -273.125492)
			(xy 192.523106 -273.125492) (xy 192.523106 -273.074076) (xy 192.531149 -273.023294) (xy 192.547037 -272.974395)
			(xy 192.57038 -272.928583) (xy 192.600601 -272.886987) (xy 192.636957 -272.850631) (xy 192.678553 -272.82041)
			(xy 192.724365 -272.797067) (xy 192.773264 -272.781179) (xy 192.824046 -272.773136) (xy 192.875462 -272.773136)
			(xy 192.926244 -272.781179) (xy 192.975143 -272.797067) (xy 193.020955 -272.82041) (xy 193.062551 -272.850631)
			(xy 193.098907 -272.886987) (xy 193.129128 -272.928583) (xy 193.152471 -272.974395) (xy 193.168359 -273.023294)
			(xy 193.176402 -273.074076) (xy 193.176906 -273.099784) (xy 193.494418 -273.099784) (xy 193.498378 -273.05073)
			(xy 193.510155 -273.002946) (xy 193.529446 -272.95767) (xy 193.555749 -272.916074) (xy 193.588384 -272.879237)
			(xy 193.626505 -272.848112) (xy 193.669126 -272.823505) (xy 193.715142 -272.806053) (xy 193.763361 -272.796209)
			(xy 193.812536 -272.794228) (xy 193.861391 -272.80016) (xy 193.908662 -272.813852) (xy 193.953124 -272.83495)
			(xy 193.993627 -272.862906) (xy 194.02912 -272.896998) (xy 194.058685 -272.936342) (xy 194.081556 -272.979919)
			(xy 194.09714 -273.0266) (xy 194.105035 -273.075177) (xy 194.10553 -273.099784) (xy 194.105035 -273.124391)
			(xy 194.104856 -273.125492) (xy 194.423026 -273.125492) (xy 194.423026 -273.074076) (xy 194.431069 -273.023294)
			(xy 194.446957 -272.974395) (xy 194.4703 -272.928583) (xy 194.500521 -272.886987) (xy 194.536877 -272.850631)
			(xy 194.578473 -272.82041) (xy 194.624285 -272.797067) (xy 194.673184 -272.781179) (xy 194.723966 -272.773136)
			(xy 194.775382 -272.773136) (xy 194.826164 -272.781179) (xy 194.875063 -272.797067) (xy 194.920875 -272.82041)
			(xy 194.962471 -272.850631) (xy 194.998827 -272.886987) (xy 195.029048 -272.928583) (xy 195.052391 -272.974395)
			(xy 195.068279 -273.023294) (xy 195.076322 -273.074076) (xy 195.076826 -273.099784) (xy 195.394338 -273.099784)
			(xy 195.398298 -273.05073) (xy 195.410075 -273.002946) (xy 195.429366 -272.95767) (xy 195.455669 -272.916074)
			(xy 195.488304 -272.879237) (xy 195.526425 -272.848112) (xy 195.569046 -272.823505) (xy 195.615062 -272.806053)
			(xy 195.663281 -272.796209) (xy 195.712456 -272.794228) (xy 195.761311 -272.80016) (xy 195.808582 -272.813852)
			(xy 195.853044 -272.83495) (xy 195.893547 -272.862906) (xy 195.92904 -272.896998) (xy 195.958605 -272.936342)
			(xy 195.981476 -272.979919) (xy 195.99706 -273.0266) (xy 196.004955 -273.075177) (xy 196.00545 -273.099784)
			(xy 196.004955 -273.124391) (xy 196.004776 -273.125492) (xy 196.322946 -273.125492) (xy 196.322946 -273.074076)
			(xy 196.330989 -273.023294) (xy 196.346877 -272.974395) (xy 196.37022 -272.928583) (xy 196.400441 -272.886987)
			(xy 196.436797 -272.850631) (xy 196.478393 -272.82041) (xy 196.524205 -272.797067) (xy 196.573104 -272.781179)
			(xy 196.623886 -272.773136) (xy 196.675302 -272.773136) (xy 196.726084 -272.781179) (xy 196.774983 -272.797067)
			(xy 196.820795 -272.82041) (xy 196.862391 -272.850631) (xy 196.898747 -272.886987) (xy 196.928968 -272.928583)
			(xy 196.952311 -272.974395) (xy 196.968199 -273.023294) (xy 196.976242 -273.074076) (xy 196.976746 -273.099784)
			(xy 197.294258 -273.099784) (xy 197.298218 -273.05073) (xy 197.309995 -273.002946) (xy 197.329286 -272.95767)
			(xy 197.355589 -272.916074) (xy 197.388224 -272.879237) (xy 197.426345 -272.848112) (xy 197.468966 -272.823505)
			(xy 197.514982 -272.806053) (xy 197.563201 -272.796209) (xy 197.612376 -272.794228) (xy 197.661231 -272.80016)
			(xy 197.708502 -272.813852) (xy 197.752964 -272.83495) (xy 197.793467 -272.862906) (xy 197.82896 -272.896998)
			(xy 197.858525 -272.936342) (xy 197.881396 -272.979919) (xy 197.89698 -273.0266) (xy 197.904875 -273.075177)
			(xy 197.90537 -273.099784) (xy 197.904875 -273.124391) (xy 197.89698 -273.172968) (xy 197.881396 -273.219649)
			(xy 197.858525 -273.263226) (xy 197.82896 -273.30257) (xy 197.793467 -273.336662) (xy 197.752964 -273.364618)
			(xy 197.708502 -273.385716) (xy 197.661231 -273.399408) (xy 197.612376 -273.40534) (xy 197.563201 -273.403359)
			(xy 197.514982 -273.393515) (xy 197.468966 -273.376063) (xy 197.426345 -273.351456) (xy 197.388224 -273.320331)
			(xy 197.355589 -273.283494) (xy 197.329286 -273.241898) (xy 197.309995 -273.196622) (xy 197.298218 -273.148838)
			(xy 197.294258 -273.099784) (xy 196.976746 -273.099784) (xy 196.976242 -273.125492) (xy 196.968199 -273.176274)
			(xy 196.952311 -273.225173) (xy 196.928968 -273.270985) (xy 196.898747 -273.312581) (xy 196.862391 -273.348937)
			(xy 196.820795 -273.379158) (xy 196.774983 -273.402501) (xy 196.726084 -273.418389) (xy 196.675302 -273.426432)
			(xy 196.623886 -273.426432) (xy 196.573104 -273.418389) (xy 196.524205 -273.402501) (xy 196.478393 -273.379158)
			(xy 196.436797 -273.348937) (xy 196.400441 -273.312581) (xy 196.37022 -273.270985) (xy 196.346877 -273.225173)
			(xy 196.330989 -273.176274) (xy 196.322946 -273.125492) (xy 196.004776 -273.125492) (xy 195.99706 -273.172968)
			(xy 195.981476 -273.219649) (xy 195.958605 -273.263226) (xy 195.92904 -273.30257) (xy 195.893547 -273.336662)
			(xy 195.853044 -273.364618) (xy 195.808582 -273.385716) (xy 195.761311 -273.399408) (xy 195.712456 -273.40534)
			(xy 195.663281 -273.403359) (xy 195.615062 -273.393515) (xy 195.569046 -273.376063) (xy 195.526425 -273.351456)
			(xy 195.488304 -273.320331) (xy 195.455669 -273.283494) (xy 195.429366 -273.241898) (xy 195.410075 -273.196622)
			(xy 195.398298 -273.148838) (xy 195.394338 -273.099784) (xy 195.076826 -273.099784) (xy 195.076322 -273.125492)
			(xy 195.068279 -273.176274) (xy 195.052391 -273.225173) (xy 195.029048 -273.270985) (xy 194.998827 -273.312581)
			(xy 194.962471 -273.348937) (xy 194.920875 -273.379158) (xy 194.875063 -273.402501) (xy 194.826164 -273.418389)
			(xy 194.775382 -273.426432) (xy 194.723966 -273.426432) (xy 194.673184 -273.418389) (xy 194.624285 -273.402501)
			(xy 194.578473 -273.379158) (xy 194.536877 -273.348937) (xy 194.500521 -273.312581) (xy 194.4703 -273.270985)
			(xy 194.446957 -273.225173) (xy 194.431069 -273.176274) (xy 194.423026 -273.125492) (xy 194.104856 -273.125492)
			(xy 194.09714 -273.172968) (xy 194.081556 -273.219649) (xy 194.058685 -273.263226) (xy 194.02912 -273.30257)
			(xy 193.993627 -273.336662) (xy 193.953124 -273.364618) (xy 193.908662 -273.385716) (xy 193.861391 -273.399408)
			(xy 193.812536 -273.40534) (xy 193.763361 -273.403359) (xy 193.715142 -273.393515) (xy 193.669126 -273.376063)
			(xy 193.626505 -273.351456) (xy 193.588384 -273.320331) (xy 193.555749 -273.283494) (xy 193.529446 -273.241898)
			(xy 193.510155 -273.196622) (xy 193.498378 -273.148838) (xy 193.494418 -273.099784) (xy 193.176906 -273.099784)
			(xy 193.176402 -273.125492) (xy 193.168359 -273.176274) (xy 193.152471 -273.225173) (xy 193.129128 -273.270985)
			(xy 193.098907 -273.312581) (xy 193.062551 -273.348937) (xy 193.020955 -273.379158) (xy 192.975143 -273.402501)
			(xy 192.926244 -273.418389) (xy 192.875462 -273.426432) (xy 192.824046 -273.426432) (xy 192.773264 -273.418389)
			(xy 192.724365 -273.402501) (xy 192.678553 -273.379158) (xy 192.636957 -273.348937) (xy 192.600601 -273.312581)
			(xy 192.57038 -273.270985) (xy 192.547037 -273.225173) (xy 192.531149 -273.176274) (xy 192.523106 -273.125492)
			(xy 192.204682 -273.125492) (xy 192.196966 -273.172968) (xy 192.181382 -273.219649) (xy 192.158511 -273.263226)
			(xy 192.128946 -273.30257) (xy 192.093453 -273.336662) (xy 192.05295 -273.364618) (xy 192.008488 -273.385716)
			(xy 191.961217 -273.399408) (xy 191.912362 -273.40534) (xy 191.863187 -273.403359) (xy 191.814968 -273.393515)
			(xy 191.768952 -273.376063) (xy 191.726331 -273.351456) (xy 191.68821 -273.320331) (xy 191.655575 -273.283494)
			(xy 191.629272 -273.241898) (xy 191.609981 -273.196622) (xy 191.598204 -273.148838) (xy 191.594244 -273.099784)
			(xy 191.276986 -273.099784) (xy 191.276482 -273.125492) (xy 191.268439 -273.176274) (xy 191.252551 -273.225173)
			(xy 191.229208 -273.270985) (xy 191.198987 -273.312581) (xy 191.162631 -273.348937) (xy 191.121035 -273.379158)
			(xy 191.075223 -273.402501) (xy 191.026324 -273.418389) (xy 190.975542 -273.426432) (xy 190.924126 -273.426432)
			(xy 190.873344 -273.418389) (xy 190.824445 -273.402501) (xy 190.778633 -273.379158) (xy 190.737037 -273.348937)
			(xy 190.700681 -273.312581) (xy 190.67046 -273.270985) (xy 190.647117 -273.225173) (xy 190.631229 -273.176274)
			(xy 190.623186 -273.125492) (xy 190.304508 -273.125492) (xy 190.296792 -273.172968) (xy 190.281208 -273.219649)
			(xy 190.258337 -273.263226) (xy 190.228772 -273.30257) (xy 190.193279 -273.336662) (xy 190.152776 -273.364618)
			(xy 190.108314 -273.385716) (xy 190.061043 -273.399408) (xy 190.012188 -273.40534) (xy 189.963013 -273.403359)
			(xy 189.914794 -273.393515) (xy 189.868778 -273.376063) (xy 189.826157 -273.351456) (xy 189.788036 -273.320331)
			(xy 189.755401 -273.283494) (xy 189.729098 -273.241898) (xy 189.709807 -273.196622) (xy 189.69803 -273.148838)
			(xy 189.69407 -273.099784) (xy 189.376812 -273.099784) (xy 189.376308 -273.125492) (xy 189.368265 -273.176274)
			(xy 189.352377 -273.225173) (xy 189.329034 -273.270985) (xy 189.298813 -273.312581) (xy 189.262457 -273.348937)
			(xy 189.220861 -273.379158) (xy 189.175049 -273.402501) (xy 189.12615 -273.418389) (xy 189.075368 -273.426432)
			(xy 189.023952 -273.426432) (xy 188.97317 -273.418389) (xy 188.924271 -273.402501) (xy 188.878459 -273.379158)
			(xy 188.836863 -273.348937) (xy 188.800507 -273.312581) (xy 188.770286 -273.270985) (xy 188.746943 -273.225173)
			(xy 188.731055 -273.176274) (xy 188.723012 -273.125492) (xy 188.404588 -273.125492) (xy 188.396872 -273.172968)
			(xy 188.381288 -273.219649) (xy 188.358417 -273.263226) (xy 188.328852 -273.30257) (xy 188.293359 -273.336662)
			(xy 188.252856 -273.364618) (xy 188.208394 -273.385716) (xy 188.161123 -273.399408) (xy 188.112268 -273.40534)
			(xy 188.063093 -273.403359) (xy 188.014874 -273.393515) (xy 187.968858 -273.376063) (xy 187.926237 -273.351456)
			(xy 187.888116 -273.320331) (xy 187.855481 -273.283494) (xy 187.829178 -273.241898) (xy 187.809887 -273.196622)
			(xy 187.79811 -273.148838) (xy 187.79415 -273.099784) (xy 187.476892 -273.099784) (xy 187.476388 -273.125492)
			(xy 187.468345 -273.176274) (xy 187.452457 -273.225173) (xy 187.429114 -273.270985) (xy 187.398893 -273.312581)
			(xy 187.362537 -273.348937) (xy 187.320941 -273.379158) (xy 187.275129 -273.402501) (xy 187.22623 -273.418389)
			(xy 187.175448 -273.426432) (xy 187.124032 -273.426432) (xy 187.07325 -273.418389) (xy 187.024351 -273.402501)
			(xy 186.978539 -273.379158) (xy 186.936943 -273.348937) (xy 186.900587 -273.312581) (xy 186.870366 -273.270985)
			(xy 186.847023 -273.225173) (xy 186.831135 -273.176274) (xy 186.823092 -273.125492) (xy 186.504668 -273.125492)
			(xy 186.496952 -273.172968) (xy 186.481368 -273.219649) (xy 186.458497 -273.263226) (xy 186.428932 -273.30257)
			(xy 186.393439 -273.336662) (xy 186.352936 -273.364618) (xy 186.308474 -273.385716) (xy 186.261203 -273.399408)
			(xy 186.212348 -273.40534) (xy 186.163173 -273.403359) (xy 186.114954 -273.393515) (xy 186.068938 -273.376063)
			(xy 186.026317 -273.351456) (xy 185.988196 -273.320331) (xy 185.955561 -273.283494) (xy 185.929258 -273.241898)
			(xy 185.909967 -273.196622) (xy 185.89819 -273.148838) (xy 185.89423 -273.099784) (xy 185.576972 -273.099784)
			(xy 185.576468 -273.125492) (xy 185.568425 -273.176274) (xy 185.552537 -273.225173) (xy 185.529194 -273.270985)
			(xy 185.498973 -273.312581) (xy 185.462617 -273.348937) (xy 185.421021 -273.379158) (xy 185.375209 -273.402501)
			(xy 185.32631 -273.418389) (xy 185.275528 -273.426432) (xy 185.224112 -273.426432) (xy 185.17333 -273.418389)
			(xy 185.124431 -273.402501) (xy 185.078619 -273.379158) (xy 185.037023 -273.348937) (xy 185.000667 -273.312581)
			(xy 184.970446 -273.270985) (xy 184.947103 -273.225173) (xy 184.931215 -273.176274) (xy 184.923172 -273.125492)
			(xy 184.604494 -273.125492) (xy 184.596778 -273.172968) (xy 184.581194 -273.219649) (xy 184.558323 -273.263226)
			(xy 184.528758 -273.30257) (xy 184.493265 -273.336662) (xy 184.452762 -273.364618) (xy 184.4083 -273.385716)
			(xy 184.361029 -273.399408) (xy 184.312174 -273.40534) (xy 184.262999 -273.403359) (xy 184.21478 -273.393515)
			(xy 184.168764 -273.376063) (xy 184.126143 -273.351456) (xy 184.088022 -273.320331) (xy 184.055387 -273.283494)
			(xy 184.029084 -273.241898) (xy 184.009793 -273.196622) (xy 183.998016 -273.148838) (xy 183.994056 -273.099784)
			(xy 183.676798 -273.099784) (xy 183.676294 -273.125492) (xy 183.668251 -273.176274) (xy 183.652363 -273.225173)
			(xy 183.62902 -273.270985) (xy 183.598799 -273.312581) (xy 183.562443 -273.348937) (xy 183.520847 -273.379158)
			(xy 183.475035 -273.402501) (xy 183.426136 -273.418389) (xy 183.375354 -273.426432) (xy 183.323938 -273.426432)
			(xy 183.273156 -273.418389) (xy 183.224257 -273.402501) (xy 183.178445 -273.379158) (xy 183.136849 -273.348937)
			(xy 183.100493 -273.312581) (xy 183.070272 -273.270985) (xy 183.046929 -273.225173) (xy 183.031041 -273.176274)
			(xy 183.022998 -273.125492) (xy 182.704574 -273.125492) (xy 182.696858 -273.172968) (xy 182.681274 -273.219649)
			(xy 182.658403 -273.263226) (xy 182.628838 -273.30257) (xy 182.593345 -273.336662) (xy 182.552842 -273.364618)
			(xy 182.50838 -273.385716) (xy 182.461109 -273.399408) (xy 182.412254 -273.40534) (xy 182.363079 -273.403359)
			(xy 182.31486 -273.393515) (xy 182.268844 -273.376063) (xy 182.226223 -273.351456) (xy 182.188102 -273.320331)
			(xy 182.155467 -273.283494) (xy 182.129164 -273.241898) (xy 182.109873 -273.196622) (xy 182.098096 -273.148838)
			(xy 182.094136 -273.099784) (xy 181.776878 -273.099784) (xy 181.776374 -273.125492) (xy 181.768331 -273.176274)
			(xy 181.752443 -273.225173) (xy 181.7291 -273.270985) (xy 181.698879 -273.312581) (xy 181.662523 -273.348937)
			(xy 181.620927 -273.379158) (xy 181.575115 -273.402501) (xy 181.526216 -273.418389) (xy 181.475434 -273.426432)
			(xy 181.424018 -273.426432) (xy 181.373236 -273.418389) (xy 181.324337 -273.402501) (xy 181.278525 -273.379158)
			(xy 181.236929 -273.348937) (xy 181.200573 -273.312581) (xy 181.170352 -273.270985) (xy 181.147009 -273.225173)
			(xy 181.131121 -273.176274) (xy 181.123078 -273.125492) (xy 180.804654 -273.125492) (xy 180.796938 -273.172968)
			(xy 180.781354 -273.219649) (xy 180.758483 -273.263226) (xy 180.728918 -273.30257) (xy 180.693425 -273.336662)
			(xy 180.652922 -273.364618) (xy 180.60846 -273.385716) (xy 180.561189 -273.399408) (xy 180.512334 -273.40534)
			(xy 180.463159 -273.403359) (xy 180.41494 -273.393515) (xy 180.368924 -273.376063) (xy 180.326303 -273.351456)
			(xy 180.288182 -273.320331) (xy 180.255547 -273.283494) (xy 180.229244 -273.241898) (xy 180.209953 -273.196622)
			(xy 180.198176 -273.148838) (xy 180.194216 -273.099784) (xy 179.876958 -273.099784) (xy 179.876454 -273.125492)
			(xy 179.868411 -273.176274) (xy 179.852523 -273.225173) (xy 179.82918 -273.270985) (xy 179.798959 -273.312581)
			(xy 179.762603 -273.348937) (xy 179.721007 -273.379158) (xy 179.675195 -273.402501) (xy 179.626296 -273.418389)
			(xy 179.575514 -273.426432) (xy 179.524098 -273.426432) (xy 179.473316 -273.418389) (xy 179.424417 -273.402501)
			(xy 179.378605 -273.379158) (xy 179.337009 -273.348937) (xy 179.300653 -273.312581) (xy 179.270432 -273.270985)
			(xy 179.247089 -273.225173) (xy 179.231201 -273.176274) (xy 179.223158 -273.125492) (xy 178.90448 -273.125492)
			(xy 178.896764 -273.172968) (xy 178.88118 -273.219649) (xy 178.858309 -273.263226) (xy 178.828744 -273.30257)
			(xy 178.793251 -273.336662) (xy 178.752748 -273.364618) (xy 178.708286 -273.385716) (xy 178.661015 -273.399408)
			(xy 178.61216 -273.40534) (xy 178.562985 -273.403359) (xy 178.514766 -273.393515) (xy 178.46875 -273.376063)
			(xy 178.426129 -273.351456) (xy 178.388008 -273.320331) (xy 178.355373 -273.283494) (xy 178.32907 -273.241898)
			(xy 178.309779 -273.196622) (xy 178.298002 -273.148838) (xy 178.294042 -273.099784) (xy 177.976784 -273.099784)
			(xy 177.97628 -273.125492) (xy 177.968237 -273.176274) (xy 177.952349 -273.225173) (xy 177.929006 -273.270985)
			(xy 177.898785 -273.312581) (xy 177.862429 -273.348937) (xy 177.820833 -273.379158) (xy 177.775021 -273.402501)
			(xy 177.726122 -273.418389) (xy 177.67534 -273.426432) (xy 177.623924 -273.426432) (xy 177.573142 -273.418389)
			(xy 177.524243 -273.402501) (xy 177.478431 -273.379158) (xy 177.436835 -273.348937) (xy 177.400479 -273.312581)
			(xy 177.370258 -273.270985) (xy 177.346915 -273.225173) (xy 177.331027 -273.176274) (xy 177.322984 -273.125492)
			(xy 177.00456 -273.125492) (xy 176.996844 -273.172968) (xy 176.98126 -273.219649) (xy 176.958389 -273.263226)
			(xy 176.928824 -273.30257) (xy 176.893331 -273.336662) (xy 176.852828 -273.364618) (xy 176.808366 -273.385716)
			(xy 176.761095 -273.399408) (xy 176.71224 -273.40534) (xy 176.663065 -273.403359) (xy 176.614846 -273.393515)
			(xy 176.56883 -273.376063) (xy 176.526209 -273.351456) (xy 176.488088 -273.320331) (xy 176.455453 -273.283494)
			(xy 176.42915 -273.241898) (xy 176.409859 -273.196622) (xy 176.398082 -273.148838) (xy 176.394122 -273.099784)
			(xy 176.076859 -273.099784) (xy 176.07636 -273.125238) (xy 176.068317 -273.17602) (xy 176.052429 -273.224919)
			(xy 176.029086 -273.270731) (xy 175.998865 -273.312327) (xy 175.962509 -273.348683) (xy 175.920913 -273.378904)
			(xy 175.875101 -273.402247) (xy 175.826202 -273.418135) (xy 175.77542 -273.426178) (xy 175.724004 -273.426178)
			(xy 175.673222 -273.418135) (xy 175.624323 -273.402247) (xy 175.578511 -273.378904) (xy 175.536915 -273.348683)
			(xy 175.500559 -273.312327) (xy 175.470338 -273.270731) (xy 175.446995 -273.224919) (xy 175.431107 -273.17602)
			(xy 175.423064 -273.125238) (xy 175.104681 -273.125238) (xy 175.096924 -273.172968) (xy 175.08134 -273.219649)
			(xy 175.058469 -273.263226) (xy 175.028904 -273.30257) (xy 174.993411 -273.336662) (xy 174.952908 -273.364618)
			(xy 174.908446 -273.385716) (xy 174.861175 -273.399408) (xy 174.81232 -273.40534) (xy 174.763145 -273.403359)
			(xy 174.714926 -273.393515) (xy 174.66891 -273.376063) (xy 174.626289 -273.351456) (xy 174.588168 -273.320331)
			(xy 174.555533 -273.283494) (xy 174.52923 -273.241898) (xy 174.509939 -273.196622) (xy 174.498162 -273.148838)
			(xy 174.494202 -273.099784) (xy 174.177198 -273.099784) (xy 174.176694 -273.125492) (xy 174.168651 -273.176274)
			(xy 174.152763 -273.225173) (xy 174.12942 -273.270985) (xy 174.099199 -273.312581) (xy 174.062843 -273.348937)
			(xy 174.021247 -273.379158) (xy 173.975435 -273.402501) (xy 173.926536 -273.418389) (xy 173.875754 -273.426432)
			(xy 173.824338 -273.426432) (xy 173.773556 -273.418389) (xy 173.724657 -273.402501) (xy 173.678845 -273.379158)
			(xy 173.637249 -273.348937) (xy 173.600893 -273.312581) (xy 173.570672 -273.270985) (xy 173.547329 -273.225173)
			(xy 173.531441 -273.176274) (xy 173.523398 -273.125492) (xy 173.20472 -273.125492) (xy 173.197004 -273.172968)
			(xy 173.18142 -273.219649) (xy 173.158549 -273.263226) (xy 173.128984 -273.30257) (xy 173.093491 -273.336662)
			(xy 173.052988 -273.364618) (xy 173.008526 -273.385716) (xy 172.961255 -273.399408) (xy 172.9124 -273.40534)
			(xy 172.863225 -273.403359) (xy 172.815006 -273.393515) (xy 172.76899 -273.376063) (xy 172.726369 -273.351456)
			(xy 172.688248 -273.320331) (xy 172.655613 -273.283494) (xy 172.62931 -273.241898) (xy 172.610019 -273.196622)
			(xy 172.598242 -273.148838) (xy 172.594282 -273.099784) (xy 172.277024 -273.099784) (xy 172.27652 -273.125492)
			(xy 172.268477 -273.176274) (xy 172.252589 -273.225173) (xy 172.229246 -273.270985) (xy 172.199025 -273.312581)
			(xy 172.162669 -273.348937) (xy 172.121073 -273.379158) (xy 172.075261 -273.402501) (xy 172.026362 -273.418389)
			(xy 171.97558 -273.426432) (xy 171.924164 -273.426432) (xy 171.873382 -273.418389) (xy 171.824483 -273.402501)
			(xy 171.778671 -273.379158) (xy 171.737075 -273.348937) (xy 171.700719 -273.312581) (xy 171.670498 -273.270985)
			(xy 171.647155 -273.225173) (xy 171.631267 -273.176274) (xy 171.623224 -273.125492) (xy 171.304546 -273.125492)
			(xy 171.29683 -273.172968) (xy 171.281246 -273.219649) (xy 171.258375 -273.263226) (xy 171.22881 -273.30257)
			(xy 171.193317 -273.336662) (xy 171.152814 -273.364618) (xy 171.108352 -273.385716) (xy 171.061081 -273.399408)
			(xy 171.012226 -273.40534) (xy 170.963051 -273.403359) (xy 170.914832 -273.393515) (xy 170.868816 -273.376063)
			(xy 170.826195 -273.351456) (xy 170.788074 -273.320331) (xy 170.755439 -273.283494) (xy 170.729136 -273.241898)
			(xy 170.709845 -273.196622) (xy 170.698068 -273.148838) (xy 170.694108 -273.099784) (xy 170.377104 -273.099784)
			(xy 170.3766 -273.125492) (xy 170.368557 -273.176274) (xy 170.352669 -273.225173) (xy 170.329326 -273.270985)
			(xy 170.299105 -273.312581) (xy 170.262749 -273.348937) (xy 170.221153 -273.379158) (xy 170.175341 -273.402501)
			(xy 170.126442 -273.418389) (xy 170.07566 -273.426432) (xy 170.024244 -273.426432) (xy 169.973462 -273.418389)
			(xy 169.924563 -273.402501) (xy 169.878751 -273.379158) (xy 169.837155 -273.348937) (xy 169.800799 -273.312581)
			(xy 169.770578 -273.270985) (xy 169.747235 -273.225173) (xy 169.731347 -273.176274) (xy 169.723304 -273.125492)
			(xy 169.404626 -273.125492) (xy 169.39691 -273.172968) (xy 169.381326 -273.219649) (xy 169.358455 -273.263226)
			(xy 169.32889 -273.30257) (xy 169.293397 -273.336662) (xy 169.252894 -273.364618) (xy 169.208432 -273.385716)
			(xy 169.161161 -273.399408) (xy 169.112306 -273.40534) (xy 169.063131 -273.403359) (xy 169.014912 -273.393515)
			(xy 168.968896 -273.376063) (xy 168.926275 -273.351456) (xy 168.888154 -273.320331) (xy 168.855519 -273.283494)
			(xy 168.829216 -273.241898) (xy 168.809925 -273.196622) (xy 168.798148 -273.148838) (xy 168.794188 -273.099784)
			(xy 168.477184 -273.099784) (xy 168.47668 -273.125492) (xy 168.468637 -273.176274) (xy 168.452749 -273.225173)
			(xy 168.429406 -273.270985) (xy 168.399185 -273.312581) (xy 168.362829 -273.348937) (xy 168.321233 -273.379158)
			(xy 168.275421 -273.402501) (xy 168.226522 -273.418389) (xy 168.17574 -273.426432) (xy 168.124324 -273.426432)
			(xy 168.073542 -273.418389) (xy 168.024643 -273.402501) (xy 167.978831 -273.379158) (xy 167.937235 -273.348937)
			(xy 167.900879 -273.312581) (xy 167.870658 -273.270985) (xy 167.847315 -273.225173) (xy 167.831427 -273.176274)
			(xy 167.823384 -273.125492) (xy 167.504706 -273.125492) (xy 167.49699 -273.172968) (xy 167.481406 -273.219649)
			(xy 167.458535 -273.263226) (xy 167.42897 -273.30257) (xy 167.393477 -273.336662) (xy 167.352974 -273.364618)
			(xy 167.308512 -273.385716) (xy 167.261241 -273.399408) (xy 167.212386 -273.40534) (xy 167.163211 -273.403359)
			(xy 167.114992 -273.393515) (xy 167.068976 -273.376063) (xy 167.026355 -273.351456) (xy 166.988234 -273.320331)
			(xy 166.955599 -273.283494) (xy 166.929296 -273.241898) (xy 166.910005 -273.196622) (xy 166.898228 -273.148838)
			(xy 166.894268 -273.099784) (xy 166.57701 -273.099784) (xy 166.576506 -273.125492) (xy 166.568463 -273.176274)
			(xy 166.552575 -273.225173) (xy 166.529232 -273.270985) (xy 166.499011 -273.312581) (xy 166.462655 -273.348937)
			(xy 166.421059 -273.379158) (xy 166.375247 -273.402501) (xy 166.326348 -273.418389) (xy 166.275566 -273.426432)
			(xy 166.22415 -273.426432) (xy 166.173368 -273.418389) (xy 166.124469 -273.402501) (xy 166.078657 -273.379158)
			(xy 166.037061 -273.348937) (xy 166.000705 -273.312581) (xy 165.970484 -273.270985) (xy 165.947141 -273.225173)
			(xy 165.931253 -273.176274) (xy 165.92321 -273.125492) (xy 165.604555 -273.125492) (xy 165.597271 -273.171369)
			(xy 165.582369 -273.217115) (xy 165.560478 -273.259957) (xy 165.53214 -273.298838) (xy 165.498056 -273.332793)
			(xy 165.459069 -273.360983) (xy 165.416144 -273.382711) (xy 165.370342 -273.39744) (xy 165.346634 -273.401536)
			(xy 165.327838 -273.40433) (xy 165.303708 -273.432778) (xy 165.303708 -273.71675) (xy 165.327838 -273.745198)
			(xy 165.346634 -273.747992) (xy 165.370333 -273.752119) (xy 165.416125 -273.766845) (xy 165.459042 -273.78857)
			(xy 165.498021 -273.816755) (xy 165.532098 -273.850704) (xy 165.56043 -273.889577) (xy 165.582316 -273.932412)
			(xy 165.597214 -273.978149) (xy 165.604756 -274.025656) (xy 165.604755 -274.073758) (xy 165.604486 -274.075452)
			(xy 165.92321 -274.075452) (xy 165.92321 -274.024036) (xy 165.931253 -273.973254) (xy 165.947141 -273.924355)
			(xy 165.970484 -273.878543) (xy 166.000705 -273.836947) (xy 166.037061 -273.800591) (xy 166.078657 -273.77037)
			(xy 166.124469 -273.747027) (xy 166.173368 -273.731139) (xy 166.22415 -273.723096) (xy 166.275566 -273.723096)
			(xy 166.326348 -273.731139) (xy 166.375247 -273.747027) (xy 166.421059 -273.77037) (xy 166.462655 -273.800591)
			(xy 166.499011 -273.836947) (xy 166.529232 -273.878543) (xy 166.552575 -273.924355) (xy 166.568463 -273.973254)
			(xy 166.576506 -274.024036) (xy 166.57701 -274.049744) (xy 166.894268 -274.049744) (xy 166.898228 -274.00069)
			(xy 166.910005 -273.952906) (xy 166.929296 -273.90763) (xy 166.955599 -273.866034) (xy 166.988234 -273.829197)
			(xy 167.026355 -273.798072) (xy 167.068976 -273.773465) (xy 167.114992 -273.756013) (xy 167.163211 -273.746169)
			(xy 167.212386 -273.744188) (xy 167.261241 -273.75012) (xy 167.308512 -273.763812) (xy 167.352974 -273.78491)
			(xy 167.393477 -273.812866) (xy 167.42897 -273.846958) (xy 167.458535 -273.886302) (xy 167.481406 -273.929879)
			(xy 167.49699 -273.97656) (xy 167.504885 -274.025137) (xy 167.50538 -274.049744) (xy 167.504885 -274.074351)
			(xy 167.504706 -274.075452) (xy 167.823384 -274.075452) (xy 167.823384 -274.024036) (xy 167.831427 -273.973254)
			(xy 167.847315 -273.924355) (xy 167.870658 -273.878543) (xy 167.900879 -273.836947) (xy 167.937235 -273.800591)
			(xy 167.978831 -273.77037) (xy 168.024643 -273.747027) (xy 168.073542 -273.731139) (xy 168.124324 -273.723096)
			(xy 168.17574 -273.723096) (xy 168.226522 -273.731139) (xy 168.275421 -273.747027) (xy 168.321233 -273.77037)
			(xy 168.362829 -273.800591) (xy 168.399185 -273.836947) (xy 168.429406 -273.878543) (xy 168.452749 -273.924355)
			(xy 168.468637 -273.973254) (xy 168.47668 -274.024036) (xy 168.477184 -274.049744) (xy 168.794188 -274.049744)
			(xy 168.798148 -274.00069) (xy 168.809925 -273.952906) (xy 168.829216 -273.90763) (xy 168.855519 -273.866034)
			(xy 168.888154 -273.829197) (xy 168.926275 -273.798072) (xy 168.968896 -273.773465) (xy 169.014912 -273.756013)
			(xy 169.063131 -273.746169) (xy 169.112306 -273.744188) (xy 169.161161 -273.75012) (xy 169.208432 -273.763812)
			(xy 169.252894 -273.78491) (xy 169.293397 -273.812866) (xy 169.32889 -273.846958) (xy 169.358455 -273.886302)
			(xy 169.381326 -273.929879) (xy 169.39691 -273.97656) (xy 169.404805 -274.025137) (xy 169.4053 -274.049744)
			(xy 169.404805 -274.074351) (xy 169.404626 -274.075452) (xy 169.723304 -274.075452) (xy 169.723304 -274.024036)
			(xy 169.731347 -273.973254) (xy 169.747235 -273.924355) (xy 169.770578 -273.878543) (xy 169.800799 -273.836947)
			(xy 169.837155 -273.800591) (xy 169.878751 -273.77037) (xy 169.924563 -273.747027) (xy 169.973462 -273.731139)
			(xy 170.024244 -273.723096) (xy 170.07566 -273.723096) (xy 170.126442 -273.731139) (xy 170.175341 -273.747027)
			(xy 170.221153 -273.77037) (xy 170.262749 -273.800591) (xy 170.299105 -273.836947) (xy 170.329326 -273.878543)
			(xy 170.352669 -273.924355) (xy 170.368557 -273.973254) (xy 170.3766 -274.024036) (xy 170.377104 -274.049744)
			(xy 170.694108 -274.049744) (xy 170.698068 -274.00069) (xy 170.709845 -273.952906) (xy 170.729136 -273.90763)
			(xy 170.755439 -273.866034) (xy 170.788074 -273.829197) (xy 170.826195 -273.798072) (xy 170.868816 -273.773465)
			(xy 170.914832 -273.756013) (xy 170.963051 -273.746169) (xy 171.012226 -273.744188) (xy 171.061081 -273.75012)
			(xy 171.108352 -273.763812) (xy 171.152814 -273.78491) (xy 171.193317 -273.812866) (xy 171.22881 -273.846958)
			(xy 171.258375 -273.886302) (xy 171.281246 -273.929879) (xy 171.29683 -273.97656) (xy 171.304725 -274.025137)
			(xy 171.30522 -274.049744) (xy 171.304725 -274.074351) (xy 171.304546 -274.075452) (xy 171.623224 -274.075452)
			(xy 171.623224 -274.024036) (xy 171.631267 -273.973254) (xy 171.647155 -273.924355) (xy 171.670498 -273.878543)
			(xy 171.700719 -273.836947) (xy 171.737075 -273.800591) (xy 171.778671 -273.77037) (xy 171.824483 -273.747027)
			(xy 171.873382 -273.731139) (xy 171.924164 -273.723096) (xy 171.97558 -273.723096) (xy 172.026362 -273.731139)
			(xy 172.075261 -273.747027) (xy 172.121073 -273.77037) (xy 172.162669 -273.800591) (xy 172.199025 -273.836947)
			(xy 172.229246 -273.878543) (xy 172.252589 -273.924355) (xy 172.268477 -273.973254) (xy 172.27652 -274.024036)
			(xy 172.277024 -274.049744) (xy 172.594282 -274.049744) (xy 172.598242 -274.00069) (xy 172.610019 -273.952906)
			(xy 172.62931 -273.90763) (xy 172.655613 -273.866034) (xy 172.688248 -273.829197) (xy 172.726369 -273.798072)
			(xy 172.76899 -273.773465) (xy 172.815006 -273.756013) (xy 172.863225 -273.746169) (xy 172.9124 -273.744188)
			(xy 172.961255 -273.75012) (xy 173.008526 -273.763812) (xy 173.052988 -273.78491) (xy 173.093491 -273.812866)
			(xy 173.128984 -273.846958) (xy 173.158549 -273.886302) (xy 173.18142 -273.929879) (xy 173.197004 -273.97656)
			(xy 173.204899 -274.025137) (xy 173.205394 -274.049744) (xy 173.204899 -274.074351) (xy 173.20472 -274.075452)
			(xy 173.523398 -274.075452) (xy 173.523398 -274.024036) (xy 173.531441 -273.973254) (xy 173.547329 -273.924355)
			(xy 173.570672 -273.878543) (xy 173.600893 -273.836947) (xy 173.637249 -273.800591) (xy 173.678845 -273.77037)
			(xy 173.724657 -273.747027) (xy 173.773556 -273.731139) (xy 173.824338 -273.723096) (xy 173.875754 -273.723096)
			(xy 173.926536 -273.731139) (xy 173.975435 -273.747027) (xy 174.021247 -273.77037) (xy 174.062843 -273.800591)
			(xy 174.099199 -273.836947) (xy 174.12942 -273.878543) (xy 174.152763 -273.924355) (xy 174.168651 -273.973254)
			(xy 174.176694 -274.024036) (xy 174.177198 -274.049744) (xy 174.494202 -274.049744) (xy 174.498162 -274.00069)
			(xy 174.509939 -273.952906) (xy 174.52923 -273.90763) (xy 174.555533 -273.866034) (xy 174.588168 -273.829197)
			(xy 174.626289 -273.798072) (xy 174.66891 -273.773465) (xy 174.714926 -273.756013) (xy 174.763145 -273.746169)
			(xy 174.81232 -273.744188) (xy 174.861175 -273.75012) (xy 174.908446 -273.763812) (xy 174.952908 -273.78491)
			(xy 174.993411 -273.812866) (xy 175.028904 -273.846958) (xy 175.058469 -273.886302) (xy 175.08134 -273.929879)
			(xy 175.096924 -273.97656) (xy 175.104819 -274.025137) (xy 175.105314 -274.049744) (xy 175.104819 -274.074351)
			(xy 175.104681 -274.075198) (xy 175.423064 -274.075198) (xy 175.423064 -274.023782) (xy 175.431107 -273.973)
			(xy 175.446995 -273.924101) (xy 175.470338 -273.878289) (xy 175.500559 -273.836693) (xy 175.536915 -273.800337)
			(xy 175.578511 -273.770116) (xy 175.624323 -273.746773) (xy 175.673222 -273.730885) (xy 175.724004 -273.722842)
			(xy 175.77542 -273.722842) (xy 175.826202 -273.730885) (xy 175.875101 -273.746773) (xy 175.920913 -273.770116)
			(xy 175.962509 -273.800337) (xy 175.998865 -273.836693) (xy 176.029086 -273.878289) (xy 176.052429 -273.924101)
			(xy 176.068317 -273.973) (xy 176.07636 -274.023782) (xy 176.076864 -274.04949) (xy 176.076859 -274.049744)
			(xy 176.394122 -274.049744) (xy 176.398082 -274.00069) (xy 176.409859 -273.952906) (xy 176.42915 -273.90763)
			(xy 176.455453 -273.866034) (xy 176.488088 -273.829197) (xy 176.526209 -273.798072) (xy 176.56883 -273.773465)
			(xy 176.614846 -273.756013) (xy 176.663065 -273.746169) (xy 176.71224 -273.744188) (xy 176.761095 -273.75012)
			(xy 176.808366 -273.763812) (xy 176.852828 -273.78491) (xy 176.893331 -273.812866) (xy 176.928824 -273.846958)
			(xy 176.958389 -273.886302) (xy 176.98126 -273.929879) (xy 176.996844 -273.97656) (xy 177.004739 -274.025137)
			(xy 177.005234 -274.049744) (xy 177.004739 -274.074351) (xy 177.00456 -274.075452) (xy 177.322984 -274.075452)
			(xy 177.322984 -274.024036) (xy 177.331027 -273.973254) (xy 177.346915 -273.924355) (xy 177.370258 -273.878543)
			(xy 177.400479 -273.836947) (xy 177.436835 -273.800591) (xy 177.478431 -273.77037) (xy 177.524243 -273.747027)
			(xy 177.573142 -273.731139) (xy 177.623924 -273.723096) (xy 177.67534 -273.723096) (xy 177.726122 -273.731139)
			(xy 177.775021 -273.747027) (xy 177.820833 -273.77037) (xy 177.862429 -273.800591) (xy 177.898785 -273.836947)
			(xy 177.929006 -273.878543) (xy 177.952349 -273.924355) (xy 177.968237 -273.973254) (xy 177.97628 -274.024036)
			(xy 177.976784 -274.049744) (xy 178.294042 -274.049744) (xy 178.298002 -274.00069) (xy 178.309779 -273.952906)
			(xy 178.32907 -273.90763) (xy 178.355373 -273.866034) (xy 178.388008 -273.829197) (xy 178.426129 -273.798072)
			(xy 178.46875 -273.773465) (xy 178.514766 -273.756013) (xy 178.562985 -273.746169) (xy 178.61216 -273.744188)
			(xy 178.661015 -273.75012) (xy 178.708286 -273.763812) (xy 178.752748 -273.78491) (xy 178.793251 -273.812866)
			(xy 178.828744 -273.846958) (xy 178.858309 -273.886302) (xy 178.88118 -273.929879) (xy 178.896764 -273.97656)
			(xy 178.904659 -274.025137) (xy 178.905154 -274.049744) (xy 178.904659 -274.074351) (xy 178.90448 -274.075452)
			(xy 179.223158 -274.075452) (xy 179.223158 -274.024036) (xy 179.231201 -273.973254) (xy 179.247089 -273.924355)
			(xy 179.270432 -273.878543) (xy 179.300653 -273.836947) (xy 179.337009 -273.800591) (xy 179.378605 -273.77037)
			(xy 179.424417 -273.747027) (xy 179.473316 -273.731139) (xy 179.524098 -273.723096) (xy 179.575514 -273.723096)
			(xy 179.626296 -273.731139) (xy 179.675195 -273.747027) (xy 179.721007 -273.77037) (xy 179.762603 -273.800591)
			(xy 179.798959 -273.836947) (xy 179.82918 -273.878543) (xy 179.852523 -273.924355) (xy 179.868411 -273.973254)
			(xy 179.876454 -274.024036) (xy 179.876958 -274.049744) (xy 180.194216 -274.049744) (xy 180.198176 -274.00069)
			(xy 180.209953 -273.952906) (xy 180.229244 -273.90763) (xy 180.255547 -273.866034) (xy 180.288182 -273.829197)
			(xy 180.326303 -273.798072) (xy 180.368924 -273.773465) (xy 180.41494 -273.756013) (xy 180.463159 -273.746169)
			(xy 180.512334 -273.744188) (xy 180.561189 -273.75012) (xy 180.60846 -273.763812) (xy 180.652922 -273.78491)
			(xy 180.693425 -273.812866) (xy 180.728918 -273.846958) (xy 180.758483 -273.886302) (xy 180.781354 -273.929879)
			(xy 180.796938 -273.97656) (xy 180.804833 -274.025137) (xy 180.805328 -274.049744) (xy 180.804833 -274.074351)
			(xy 180.804654 -274.075452) (xy 181.123078 -274.075452) (xy 181.123078 -274.024036) (xy 181.131121 -273.973254)
			(xy 181.147009 -273.924355) (xy 181.170352 -273.878543) (xy 181.200573 -273.836947) (xy 181.236929 -273.800591)
			(xy 181.278525 -273.77037) (xy 181.324337 -273.747027) (xy 181.373236 -273.731139) (xy 181.424018 -273.723096)
			(xy 181.475434 -273.723096) (xy 181.526216 -273.731139) (xy 181.575115 -273.747027) (xy 181.620927 -273.77037)
			(xy 181.662523 -273.800591) (xy 181.698879 -273.836947) (xy 181.7291 -273.878543) (xy 181.752443 -273.924355)
			(xy 181.768331 -273.973254) (xy 181.776374 -274.024036) (xy 181.776878 -274.049744) (xy 182.094136 -274.049744)
			(xy 182.098096 -274.00069) (xy 182.109873 -273.952906) (xy 182.129164 -273.90763) (xy 182.155467 -273.866034)
			(xy 182.188102 -273.829197) (xy 182.226223 -273.798072) (xy 182.268844 -273.773465) (xy 182.31486 -273.756013)
			(xy 182.363079 -273.746169) (xy 182.412254 -273.744188) (xy 182.461109 -273.75012) (xy 182.50838 -273.763812)
			(xy 182.552842 -273.78491) (xy 182.593345 -273.812866) (xy 182.628838 -273.846958) (xy 182.658403 -273.886302)
			(xy 182.681274 -273.929879) (xy 182.696858 -273.97656) (xy 182.704753 -274.025137) (xy 182.705248 -274.049744)
			(xy 182.704753 -274.074351) (xy 182.704574 -274.075452) (xy 183.022998 -274.075452) (xy 183.022998 -274.024036)
			(xy 183.031041 -273.973254) (xy 183.046929 -273.924355) (xy 183.070272 -273.878543) (xy 183.100493 -273.836947)
			(xy 183.136849 -273.800591) (xy 183.178445 -273.77037) (xy 183.224257 -273.747027) (xy 183.273156 -273.731139)
			(xy 183.323938 -273.723096) (xy 183.375354 -273.723096) (xy 183.426136 -273.731139) (xy 183.475035 -273.747027)
			(xy 183.520847 -273.77037) (xy 183.562443 -273.800591) (xy 183.598799 -273.836947) (xy 183.62902 -273.878543)
			(xy 183.652363 -273.924355) (xy 183.668251 -273.973254) (xy 183.676294 -274.024036) (xy 183.676798 -274.049744)
			(xy 183.994056 -274.049744) (xy 183.998016 -274.00069) (xy 184.009793 -273.952906) (xy 184.029084 -273.90763)
			(xy 184.055387 -273.866034) (xy 184.088022 -273.829197) (xy 184.126143 -273.798072) (xy 184.168764 -273.773465)
			(xy 184.21478 -273.756013) (xy 184.262999 -273.746169) (xy 184.312174 -273.744188) (xy 184.361029 -273.75012)
			(xy 184.4083 -273.763812) (xy 184.452762 -273.78491) (xy 184.493265 -273.812866) (xy 184.528758 -273.846958)
			(xy 184.558323 -273.886302) (xy 184.581194 -273.929879) (xy 184.596778 -273.97656) (xy 184.604673 -274.025137)
			(xy 184.605168 -274.049744) (xy 184.604673 -274.074351) (xy 184.604494 -274.075452) (xy 184.923172 -274.075452)
			(xy 184.923172 -274.024036) (xy 184.931215 -273.973254) (xy 184.947103 -273.924355) (xy 184.970446 -273.878543)
			(xy 185.000667 -273.836947) (xy 185.037023 -273.800591) (xy 185.078619 -273.77037) (xy 185.124431 -273.747027)
			(xy 185.17333 -273.731139) (xy 185.224112 -273.723096) (xy 185.275528 -273.723096) (xy 185.32631 -273.731139)
			(xy 185.375209 -273.747027) (xy 185.421021 -273.77037) (xy 185.462617 -273.800591) (xy 185.498973 -273.836947)
			(xy 185.529194 -273.878543) (xy 185.552537 -273.924355) (xy 185.568425 -273.973254) (xy 185.576468 -274.024036)
			(xy 185.576972 -274.049744) (xy 185.89423 -274.049744) (xy 185.89819 -274.00069) (xy 185.909967 -273.952906)
			(xy 185.929258 -273.90763) (xy 185.955561 -273.866034) (xy 185.988196 -273.829197) (xy 186.026317 -273.798072)
			(xy 186.068938 -273.773465) (xy 186.114954 -273.756013) (xy 186.163173 -273.746169) (xy 186.212348 -273.744188)
			(xy 186.261203 -273.75012) (xy 186.308474 -273.763812) (xy 186.352936 -273.78491) (xy 186.393439 -273.812866)
			(xy 186.428932 -273.846958) (xy 186.458497 -273.886302) (xy 186.481368 -273.929879) (xy 186.496952 -273.97656)
			(xy 186.504847 -274.025137) (xy 186.505342 -274.049744) (xy 186.504847 -274.074351) (xy 186.504668 -274.075452)
			(xy 186.823092 -274.075452) (xy 186.823092 -274.024036) (xy 186.831135 -273.973254) (xy 186.847023 -273.924355)
			(xy 186.870366 -273.878543) (xy 186.900587 -273.836947) (xy 186.936943 -273.800591) (xy 186.978539 -273.77037)
			(xy 187.024351 -273.747027) (xy 187.07325 -273.731139) (xy 187.124032 -273.723096) (xy 187.175448 -273.723096)
			(xy 187.22623 -273.731139) (xy 187.275129 -273.747027) (xy 187.320941 -273.77037) (xy 187.362537 -273.800591)
			(xy 187.398893 -273.836947) (xy 187.429114 -273.878543) (xy 187.452457 -273.924355) (xy 187.468345 -273.973254)
			(xy 187.476388 -274.024036) (xy 187.476892 -274.049744) (xy 187.79415 -274.049744) (xy 187.79811 -274.00069)
			(xy 187.809887 -273.952906) (xy 187.829178 -273.90763) (xy 187.855481 -273.866034) (xy 187.888116 -273.829197)
			(xy 187.926237 -273.798072) (xy 187.968858 -273.773465) (xy 188.014874 -273.756013) (xy 188.063093 -273.746169)
			(xy 188.112268 -273.744188) (xy 188.161123 -273.75012) (xy 188.208394 -273.763812) (xy 188.252856 -273.78491)
			(xy 188.293359 -273.812866) (xy 188.328852 -273.846958) (xy 188.358417 -273.886302) (xy 188.381288 -273.929879)
			(xy 188.396872 -273.97656) (xy 188.404767 -274.025137) (xy 188.405262 -274.049744) (xy 188.404767 -274.074351)
			(xy 188.404588 -274.075452) (xy 188.723012 -274.075452) (xy 188.723012 -274.024036) (xy 188.731055 -273.973254)
			(xy 188.746943 -273.924355) (xy 188.770286 -273.878543) (xy 188.800507 -273.836947) (xy 188.836863 -273.800591)
			(xy 188.878459 -273.77037) (xy 188.924271 -273.747027) (xy 188.97317 -273.731139) (xy 189.023952 -273.723096)
			(xy 189.075368 -273.723096) (xy 189.12615 -273.731139) (xy 189.175049 -273.747027) (xy 189.220861 -273.77037)
			(xy 189.262457 -273.800591) (xy 189.298813 -273.836947) (xy 189.329034 -273.878543) (xy 189.352377 -273.924355)
			(xy 189.368265 -273.973254) (xy 189.376308 -274.024036) (xy 189.376812 -274.049744) (xy 189.69407 -274.049744)
			(xy 189.69803 -274.00069) (xy 189.709807 -273.952906) (xy 189.729098 -273.90763) (xy 189.755401 -273.866034)
			(xy 189.788036 -273.829197) (xy 189.826157 -273.798072) (xy 189.868778 -273.773465) (xy 189.914794 -273.756013)
			(xy 189.963013 -273.746169) (xy 190.012188 -273.744188) (xy 190.061043 -273.75012) (xy 190.108314 -273.763812)
			(xy 190.152776 -273.78491) (xy 190.193279 -273.812866) (xy 190.228772 -273.846958) (xy 190.258337 -273.886302)
			(xy 190.281208 -273.929879) (xy 190.296792 -273.97656) (xy 190.304687 -274.025137) (xy 190.305182 -274.049744)
			(xy 190.304687 -274.074351) (xy 190.304508 -274.075452) (xy 190.623186 -274.075452) (xy 190.623186 -274.024036)
			(xy 190.631229 -273.973254) (xy 190.647117 -273.924355) (xy 190.67046 -273.878543) (xy 190.700681 -273.836947)
			(xy 190.737037 -273.800591) (xy 190.778633 -273.77037) (xy 190.824445 -273.747027) (xy 190.873344 -273.731139)
			(xy 190.924126 -273.723096) (xy 190.975542 -273.723096) (xy 191.026324 -273.731139) (xy 191.075223 -273.747027)
			(xy 191.121035 -273.77037) (xy 191.162631 -273.800591) (xy 191.198987 -273.836947) (xy 191.229208 -273.878543)
			(xy 191.252551 -273.924355) (xy 191.268439 -273.973254) (xy 191.276482 -274.024036) (xy 191.276986 -274.049744)
			(xy 191.594498 -274.049744) (xy 191.598458 -274.00069) (xy 191.610235 -273.952906) (xy 191.629526 -273.90763)
			(xy 191.655829 -273.866034) (xy 191.688464 -273.829197) (xy 191.726585 -273.798072) (xy 191.769206 -273.773465)
			(xy 191.815222 -273.756013) (xy 191.863441 -273.746169) (xy 191.912616 -273.744188) (xy 191.961471 -273.75012)
			(xy 192.008742 -273.763812) (xy 192.053204 -273.78491) (xy 192.093707 -273.812866) (xy 192.1292 -273.846958)
			(xy 192.158765 -273.886302) (xy 192.181636 -273.929879) (xy 192.19722 -273.97656) (xy 192.205115 -274.025137)
			(xy 192.20561 -274.049744) (xy 192.205115 -274.074351) (xy 192.204936 -274.075452) (xy 192.523106 -274.075452)
			(xy 192.523106 -274.024036) (xy 192.531149 -273.973254) (xy 192.547037 -273.924355) (xy 192.57038 -273.878543)
			(xy 192.600601 -273.836947) (xy 192.636957 -273.800591) (xy 192.678553 -273.77037) (xy 192.724365 -273.747027)
			(xy 192.773264 -273.731139) (xy 192.824046 -273.723096) (xy 192.875462 -273.723096) (xy 192.926244 -273.731139)
			(xy 192.975143 -273.747027) (xy 193.020955 -273.77037) (xy 193.062551 -273.800591) (xy 193.098907 -273.836947)
			(xy 193.129128 -273.878543) (xy 193.152471 -273.924355) (xy 193.168359 -273.973254) (xy 193.176402 -274.024036)
			(xy 193.176906 -274.049744) (xy 193.494418 -274.049744) (xy 193.498378 -274.00069) (xy 193.510155 -273.952906)
			(xy 193.529446 -273.90763) (xy 193.555749 -273.866034) (xy 193.588384 -273.829197) (xy 193.626505 -273.798072)
			(xy 193.669126 -273.773465) (xy 193.715142 -273.756013) (xy 193.763361 -273.746169) (xy 193.812536 -273.744188)
			(xy 193.861391 -273.75012) (xy 193.908662 -273.763812) (xy 193.953124 -273.78491) (xy 193.993627 -273.812866)
			(xy 194.02912 -273.846958) (xy 194.058685 -273.886302) (xy 194.081556 -273.929879) (xy 194.09714 -273.97656)
			(xy 194.105035 -274.025137) (xy 194.10553 -274.049744) (xy 194.105035 -274.074351) (xy 194.104856 -274.075452)
			(xy 194.423026 -274.075452) (xy 194.423026 -274.024036) (xy 194.431069 -273.973254) (xy 194.446957 -273.924355)
			(xy 194.4703 -273.878543) (xy 194.500521 -273.836947) (xy 194.536877 -273.800591) (xy 194.578473 -273.77037)
			(xy 194.624285 -273.747027) (xy 194.673184 -273.731139) (xy 194.723966 -273.723096) (xy 194.775382 -273.723096)
			(xy 194.826164 -273.731139) (xy 194.875063 -273.747027) (xy 194.920875 -273.77037) (xy 194.962471 -273.800591)
			(xy 194.998827 -273.836947) (xy 195.029048 -273.878543) (xy 195.052391 -273.924355) (xy 195.068279 -273.973254)
			(xy 195.076322 -274.024036) (xy 195.076826 -274.049744) (xy 195.394338 -274.049744) (xy 195.398298 -274.00069)
			(xy 195.410075 -273.952906) (xy 195.429366 -273.90763) (xy 195.455669 -273.866034) (xy 195.488304 -273.829197)
			(xy 195.526425 -273.798072) (xy 195.569046 -273.773465) (xy 195.615062 -273.756013) (xy 195.663281 -273.746169)
			(xy 195.712456 -273.744188) (xy 195.761311 -273.75012) (xy 195.808582 -273.763812) (xy 195.853044 -273.78491)
			(xy 195.893547 -273.812866) (xy 195.92904 -273.846958) (xy 195.958605 -273.886302) (xy 195.981476 -273.929879)
			(xy 195.99706 -273.97656) (xy 196.004955 -274.025137) (xy 196.00545 -274.049744) (xy 196.004955 -274.074351)
			(xy 196.004776 -274.075452) (xy 196.322946 -274.075452) (xy 196.322946 -274.024036) (xy 196.330989 -273.973254)
			(xy 196.346877 -273.924355) (xy 196.37022 -273.878543) (xy 196.400441 -273.836947) (xy 196.436797 -273.800591)
			(xy 196.478393 -273.77037) (xy 196.524205 -273.747027) (xy 196.573104 -273.731139) (xy 196.623886 -273.723096)
			(xy 196.675302 -273.723096) (xy 196.726084 -273.731139) (xy 196.774983 -273.747027) (xy 196.820795 -273.77037)
			(xy 196.862391 -273.800591) (xy 196.898747 -273.836947) (xy 196.928968 -273.878543) (xy 196.952311 -273.924355)
			(xy 196.968199 -273.973254) (xy 196.976242 -274.024036) (xy 196.976746 -274.049744) (xy 197.294258 -274.049744)
			(xy 197.298218 -274.00069) (xy 197.309995 -273.952906) (xy 197.329286 -273.90763) (xy 197.355589 -273.866034)
			(xy 197.388224 -273.829197) (xy 197.426345 -273.798072) (xy 197.468966 -273.773465) (xy 197.514982 -273.756013)
			(xy 197.563201 -273.746169) (xy 197.612376 -273.744188) (xy 197.661231 -273.75012) (xy 197.708502 -273.763812)
			(xy 197.752964 -273.78491) (xy 197.793467 -273.812866) (xy 197.82896 -273.846958) (xy 197.858525 -273.886302)
			(xy 197.881396 -273.929879) (xy 197.89698 -273.97656) (xy 197.904875 -274.025137) (xy 197.90537 -274.049744)
			(xy 198.244218 -274.049744) (xy 198.248178 -274.00069) (xy 198.259955 -273.952906) (xy 198.279246 -273.90763)
			(xy 198.305549 -273.866034) (xy 198.338184 -273.829197) (xy 198.376305 -273.798072) (xy 198.418926 -273.773465)
			(xy 198.464942 -273.756013) (xy 198.513161 -273.746169) (xy 198.562336 -273.744188) (xy 198.611191 -273.75012)
			(xy 198.658462 -273.763812) (xy 198.702924 -273.78491) (xy 198.743427 -273.812866) (xy 198.77892 -273.846958)
			(xy 198.808485 -273.886302) (xy 198.831356 -273.929879) (xy 198.84694 -273.97656) (xy 198.854835 -274.025137)
			(xy 198.85533 -274.049744) (xy 198.854835 -274.074351) (xy 198.84694 -274.122928) (xy 198.831356 -274.169609)
			(xy 198.808485 -274.213186) (xy 198.77892 -274.25253) (xy 198.743427 -274.286622) (xy 198.702924 -274.314578)
			(xy 198.658462 -274.335676) (xy 198.611191 -274.349368) (xy 198.562336 -274.3553) (xy 198.513161 -274.353319)
			(xy 198.464942 -274.343475) (xy 198.418926 -274.326023) (xy 198.376305 -274.301416) (xy 198.338184 -274.270291)
			(xy 198.305549 -274.233454) (xy 198.279246 -274.191858) (xy 198.259955 -274.146582) (xy 198.248178 -274.098798)
			(xy 198.244218 -274.049744) (xy 197.90537 -274.049744) (xy 197.904875 -274.074351) (xy 197.89698 -274.122928)
			(xy 197.881396 -274.169609) (xy 197.858525 -274.213186) (xy 197.82896 -274.25253) (xy 197.793467 -274.286622)
			(xy 197.752964 -274.314578) (xy 197.708502 -274.335676) (xy 197.661231 -274.349368) (xy 197.612376 -274.3553)
			(xy 197.563201 -274.353319) (xy 197.514982 -274.343475) (xy 197.468966 -274.326023) (xy 197.426345 -274.301416)
			(xy 197.388224 -274.270291) (xy 197.355589 -274.233454) (xy 197.329286 -274.191858) (xy 197.309995 -274.146582)
			(xy 197.298218 -274.098798) (xy 197.294258 -274.049744) (xy 196.976746 -274.049744) (xy 196.976242 -274.075452)
			(xy 196.968199 -274.126234) (xy 196.952311 -274.175133) (xy 196.928968 -274.220945) (xy 196.898747 -274.262541)
			(xy 196.862391 -274.298897) (xy 196.820795 -274.329118) (xy 196.774983 -274.352461) (xy 196.726084 -274.368349)
			(xy 196.675302 -274.376392) (xy 196.623886 -274.376392) (xy 196.573104 -274.368349) (xy 196.524205 -274.352461)
			(xy 196.478393 -274.329118) (xy 196.436797 -274.298897) (xy 196.400441 -274.262541) (xy 196.37022 -274.220945)
			(xy 196.346877 -274.175133) (xy 196.330989 -274.126234) (xy 196.322946 -274.075452) (xy 196.004776 -274.075452)
			(xy 195.99706 -274.122928) (xy 195.981476 -274.169609) (xy 195.958605 -274.213186) (xy 195.92904 -274.25253)
			(xy 195.893547 -274.286622) (xy 195.853044 -274.314578) (xy 195.808582 -274.335676) (xy 195.761311 -274.349368)
			(xy 195.712456 -274.3553) (xy 195.663281 -274.353319) (xy 195.615062 -274.343475) (xy 195.569046 -274.326023)
			(xy 195.526425 -274.301416) (xy 195.488304 -274.270291) (xy 195.455669 -274.233454) (xy 195.429366 -274.191858)
			(xy 195.410075 -274.146582) (xy 195.398298 -274.098798) (xy 195.394338 -274.049744) (xy 195.076826 -274.049744)
			(xy 195.076322 -274.075452) (xy 195.068279 -274.126234) (xy 195.052391 -274.175133) (xy 195.029048 -274.220945)
			(xy 194.998827 -274.262541) (xy 194.962471 -274.298897) (xy 194.920875 -274.329118) (xy 194.875063 -274.352461)
			(xy 194.826164 -274.368349) (xy 194.775382 -274.376392) (xy 194.723966 -274.376392) (xy 194.673184 -274.368349)
			(xy 194.624285 -274.352461) (xy 194.578473 -274.329118) (xy 194.536877 -274.298897) (xy 194.500521 -274.262541)
			(xy 194.4703 -274.220945) (xy 194.446957 -274.175133) (xy 194.431069 -274.126234) (xy 194.423026 -274.075452)
			(xy 194.104856 -274.075452) (xy 194.09714 -274.122928) (xy 194.081556 -274.169609) (xy 194.058685 -274.213186)
			(xy 194.02912 -274.25253) (xy 193.993627 -274.286622) (xy 193.953124 -274.314578) (xy 193.908662 -274.335676)
			(xy 193.861391 -274.349368) (xy 193.812536 -274.3553) (xy 193.763361 -274.353319) (xy 193.715142 -274.343475)
			(xy 193.669126 -274.326023) (xy 193.626505 -274.301416) (xy 193.588384 -274.270291) (xy 193.555749 -274.233454)
			(xy 193.529446 -274.191858) (xy 193.510155 -274.146582) (xy 193.498378 -274.098798) (xy 193.494418 -274.049744)
			(xy 193.176906 -274.049744) (xy 193.176402 -274.075452) (xy 193.168359 -274.126234) (xy 193.152471 -274.175133)
			(xy 193.129128 -274.220945) (xy 193.098907 -274.262541) (xy 193.062551 -274.298897) (xy 193.020955 -274.329118)
			(xy 192.975143 -274.352461) (xy 192.926244 -274.368349) (xy 192.875462 -274.376392) (xy 192.824046 -274.376392)
			(xy 192.773264 -274.368349) (xy 192.724365 -274.352461) (xy 192.678553 -274.329118) (xy 192.636957 -274.298897)
			(xy 192.600601 -274.262541) (xy 192.57038 -274.220945) (xy 192.547037 -274.175133) (xy 192.531149 -274.126234)
			(xy 192.523106 -274.075452) (xy 192.204936 -274.075452) (xy 192.19722 -274.122928) (xy 192.181636 -274.169609)
			(xy 192.158765 -274.213186) (xy 192.1292 -274.25253) (xy 192.093707 -274.286622) (xy 192.053204 -274.314578)
			(xy 192.008742 -274.335676) (xy 191.961471 -274.349368) (xy 191.912616 -274.3553) (xy 191.863441 -274.353319)
			(xy 191.815222 -274.343475) (xy 191.769206 -274.326023) (xy 191.726585 -274.301416) (xy 191.688464 -274.270291)
			(xy 191.655829 -274.233454) (xy 191.629526 -274.191858) (xy 191.610235 -274.146582) (xy 191.598458 -274.098798)
			(xy 191.594498 -274.049744) (xy 191.276986 -274.049744) (xy 191.276482 -274.075452) (xy 191.268439 -274.126234)
			(xy 191.252551 -274.175133) (xy 191.229208 -274.220945) (xy 191.198987 -274.262541) (xy 191.162631 -274.298897)
			(xy 191.121035 -274.329118) (xy 191.075223 -274.352461) (xy 191.026324 -274.368349) (xy 190.975542 -274.376392)
			(xy 190.924126 -274.376392) (xy 190.873344 -274.368349) (xy 190.824445 -274.352461) (xy 190.778633 -274.329118)
			(xy 190.737037 -274.298897) (xy 190.700681 -274.262541) (xy 190.67046 -274.220945) (xy 190.647117 -274.175133)
			(xy 190.631229 -274.126234) (xy 190.623186 -274.075452) (xy 190.304508 -274.075452) (xy 190.296792 -274.122928)
			(xy 190.281208 -274.169609) (xy 190.258337 -274.213186) (xy 190.228772 -274.25253) (xy 190.193279 -274.286622)
			(xy 190.152776 -274.314578) (xy 190.108314 -274.335676) (xy 190.061043 -274.349368) (xy 190.012188 -274.3553)
			(xy 189.963013 -274.353319) (xy 189.914794 -274.343475) (xy 189.868778 -274.326023) (xy 189.826157 -274.301416)
			(xy 189.788036 -274.270291) (xy 189.755401 -274.233454) (xy 189.729098 -274.191858) (xy 189.709807 -274.146582)
			(xy 189.69803 -274.098798) (xy 189.69407 -274.049744) (xy 189.376812 -274.049744) (xy 189.376308 -274.075452)
			(xy 189.368265 -274.126234) (xy 189.352377 -274.175133) (xy 189.329034 -274.220945) (xy 189.298813 -274.262541)
			(xy 189.262457 -274.298897) (xy 189.220861 -274.329118) (xy 189.175049 -274.352461) (xy 189.12615 -274.368349)
			(xy 189.075368 -274.376392) (xy 189.023952 -274.376392) (xy 188.97317 -274.368349) (xy 188.924271 -274.352461)
			(xy 188.878459 -274.329118) (xy 188.836863 -274.298897) (xy 188.800507 -274.262541) (xy 188.770286 -274.220945)
			(xy 188.746943 -274.175133) (xy 188.731055 -274.126234) (xy 188.723012 -274.075452) (xy 188.404588 -274.075452)
			(xy 188.396872 -274.122928) (xy 188.381288 -274.169609) (xy 188.358417 -274.213186) (xy 188.328852 -274.25253)
			(xy 188.293359 -274.286622) (xy 188.252856 -274.314578) (xy 188.208394 -274.335676) (xy 188.161123 -274.349368)
			(xy 188.112268 -274.3553) (xy 188.063093 -274.353319) (xy 188.014874 -274.343475) (xy 187.968858 -274.326023)
			(xy 187.926237 -274.301416) (xy 187.888116 -274.270291) (xy 187.855481 -274.233454) (xy 187.829178 -274.191858)
			(xy 187.809887 -274.146582) (xy 187.79811 -274.098798) (xy 187.79415 -274.049744) (xy 187.476892 -274.049744)
			(xy 187.476388 -274.075452) (xy 187.468345 -274.126234) (xy 187.452457 -274.175133) (xy 187.429114 -274.220945)
			(xy 187.398893 -274.262541) (xy 187.362537 -274.298897) (xy 187.320941 -274.329118) (xy 187.275129 -274.352461)
			(xy 187.22623 -274.368349) (xy 187.175448 -274.376392) (xy 187.124032 -274.376392) (xy 187.07325 -274.368349)
			(xy 187.024351 -274.352461) (xy 186.978539 -274.329118) (xy 186.936943 -274.298897) (xy 186.900587 -274.262541)
			(xy 186.870366 -274.220945) (xy 186.847023 -274.175133) (xy 186.831135 -274.126234) (xy 186.823092 -274.075452)
			(xy 186.504668 -274.075452) (xy 186.496952 -274.122928) (xy 186.481368 -274.169609) (xy 186.458497 -274.213186)
			(xy 186.428932 -274.25253) (xy 186.393439 -274.286622) (xy 186.352936 -274.314578) (xy 186.308474 -274.335676)
			(xy 186.261203 -274.349368) (xy 186.212348 -274.3553) (xy 186.163173 -274.353319) (xy 186.114954 -274.343475)
			(xy 186.068938 -274.326023) (xy 186.026317 -274.301416) (xy 185.988196 -274.270291) (xy 185.955561 -274.233454)
			(xy 185.929258 -274.191858) (xy 185.909967 -274.146582) (xy 185.89819 -274.098798) (xy 185.89423 -274.049744)
			(xy 185.576972 -274.049744) (xy 185.576468 -274.075452) (xy 185.568425 -274.126234) (xy 185.552537 -274.175133)
			(xy 185.529194 -274.220945) (xy 185.498973 -274.262541) (xy 185.462617 -274.298897) (xy 185.421021 -274.329118)
			(xy 185.375209 -274.352461) (xy 185.32631 -274.368349) (xy 185.275528 -274.376392) (xy 185.224112 -274.376392)
			(xy 185.17333 -274.368349) (xy 185.124431 -274.352461) (xy 185.078619 -274.329118) (xy 185.037023 -274.298897)
			(xy 185.000667 -274.262541) (xy 184.970446 -274.220945) (xy 184.947103 -274.175133) (xy 184.931215 -274.126234)
			(xy 184.923172 -274.075452) (xy 184.604494 -274.075452) (xy 184.596778 -274.122928) (xy 184.581194 -274.169609)
			(xy 184.558323 -274.213186) (xy 184.528758 -274.25253) (xy 184.493265 -274.286622) (xy 184.452762 -274.314578)
			(xy 184.4083 -274.335676) (xy 184.361029 -274.349368) (xy 184.312174 -274.3553) (xy 184.262999 -274.353319)
			(xy 184.21478 -274.343475) (xy 184.168764 -274.326023) (xy 184.126143 -274.301416) (xy 184.088022 -274.270291)
			(xy 184.055387 -274.233454) (xy 184.029084 -274.191858) (xy 184.009793 -274.146582) (xy 183.998016 -274.098798)
			(xy 183.994056 -274.049744) (xy 183.676798 -274.049744) (xy 183.676294 -274.075452) (xy 183.668251 -274.126234)
			(xy 183.652363 -274.175133) (xy 183.62902 -274.220945) (xy 183.598799 -274.262541) (xy 183.562443 -274.298897)
			(xy 183.520847 -274.329118) (xy 183.475035 -274.352461) (xy 183.426136 -274.368349) (xy 183.375354 -274.376392)
			(xy 183.323938 -274.376392) (xy 183.273156 -274.368349) (xy 183.224257 -274.352461) (xy 183.178445 -274.329118)
			(xy 183.136849 -274.298897) (xy 183.100493 -274.262541) (xy 183.070272 -274.220945) (xy 183.046929 -274.175133)
			(xy 183.031041 -274.126234) (xy 183.022998 -274.075452) (xy 182.704574 -274.075452) (xy 182.696858 -274.122928)
			(xy 182.681274 -274.169609) (xy 182.658403 -274.213186) (xy 182.628838 -274.25253) (xy 182.593345 -274.286622)
			(xy 182.552842 -274.314578) (xy 182.50838 -274.335676) (xy 182.461109 -274.349368) (xy 182.412254 -274.3553)
			(xy 182.363079 -274.353319) (xy 182.31486 -274.343475) (xy 182.268844 -274.326023) (xy 182.226223 -274.301416)
			(xy 182.188102 -274.270291) (xy 182.155467 -274.233454) (xy 182.129164 -274.191858) (xy 182.109873 -274.146582)
			(xy 182.098096 -274.098798) (xy 182.094136 -274.049744) (xy 181.776878 -274.049744) (xy 181.776374 -274.075452)
			(xy 181.768331 -274.126234) (xy 181.752443 -274.175133) (xy 181.7291 -274.220945) (xy 181.698879 -274.262541)
			(xy 181.662523 -274.298897) (xy 181.620927 -274.329118) (xy 181.575115 -274.352461) (xy 181.526216 -274.368349)
			(xy 181.475434 -274.376392) (xy 181.424018 -274.376392) (xy 181.373236 -274.368349) (xy 181.324337 -274.352461)
			(xy 181.278525 -274.329118) (xy 181.236929 -274.298897) (xy 181.200573 -274.262541) (xy 181.170352 -274.220945)
			(xy 181.147009 -274.175133) (xy 181.131121 -274.126234) (xy 181.123078 -274.075452) (xy 180.804654 -274.075452)
			(xy 180.796938 -274.122928) (xy 180.781354 -274.169609) (xy 180.758483 -274.213186) (xy 180.728918 -274.25253)
			(xy 180.693425 -274.286622) (xy 180.652922 -274.314578) (xy 180.60846 -274.335676) (xy 180.561189 -274.349368)
			(xy 180.512334 -274.3553) (xy 180.463159 -274.353319) (xy 180.41494 -274.343475) (xy 180.368924 -274.326023)
			(xy 180.326303 -274.301416) (xy 180.288182 -274.270291) (xy 180.255547 -274.233454) (xy 180.229244 -274.191858)
			(xy 180.209953 -274.146582) (xy 180.198176 -274.098798) (xy 180.194216 -274.049744) (xy 179.876958 -274.049744)
			(xy 179.876454 -274.075452) (xy 179.868411 -274.126234) (xy 179.852523 -274.175133) (xy 179.82918 -274.220945)
			(xy 179.798959 -274.262541) (xy 179.762603 -274.298897) (xy 179.721007 -274.329118) (xy 179.675195 -274.352461)
			(xy 179.626296 -274.368349) (xy 179.575514 -274.376392) (xy 179.524098 -274.376392) (xy 179.473316 -274.368349)
			(xy 179.424417 -274.352461) (xy 179.378605 -274.329118) (xy 179.337009 -274.298897) (xy 179.300653 -274.262541)
			(xy 179.270432 -274.220945) (xy 179.247089 -274.175133) (xy 179.231201 -274.126234) (xy 179.223158 -274.075452)
			(xy 178.90448 -274.075452) (xy 178.896764 -274.122928) (xy 178.88118 -274.169609) (xy 178.858309 -274.213186)
			(xy 178.828744 -274.25253) (xy 178.793251 -274.286622) (xy 178.752748 -274.314578) (xy 178.708286 -274.335676)
			(xy 178.661015 -274.349368) (xy 178.61216 -274.3553) (xy 178.562985 -274.353319) (xy 178.514766 -274.343475)
			(xy 178.46875 -274.326023) (xy 178.426129 -274.301416) (xy 178.388008 -274.270291) (xy 178.355373 -274.233454)
			(xy 178.32907 -274.191858) (xy 178.309779 -274.146582) (xy 178.298002 -274.098798) (xy 178.294042 -274.049744)
			(xy 177.976784 -274.049744) (xy 177.97628 -274.075452) (xy 177.968237 -274.126234) (xy 177.952349 -274.175133)
			(xy 177.929006 -274.220945) (xy 177.898785 -274.262541) (xy 177.862429 -274.298897) (xy 177.820833 -274.329118)
			(xy 177.775021 -274.352461) (xy 177.726122 -274.368349) (xy 177.67534 -274.376392) (xy 177.623924 -274.376392)
			(xy 177.573142 -274.368349) (xy 177.524243 -274.352461) (xy 177.478431 -274.329118) (xy 177.436835 -274.298897)
			(xy 177.400479 -274.262541) (xy 177.370258 -274.220945) (xy 177.346915 -274.175133) (xy 177.331027 -274.126234)
			(xy 177.322984 -274.075452) (xy 177.00456 -274.075452) (xy 176.996844 -274.122928) (xy 176.98126 -274.169609)
			(xy 176.958389 -274.213186) (xy 176.928824 -274.25253) (xy 176.893331 -274.286622) (xy 176.852828 -274.314578)
			(xy 176.808366 -274.335676) (xy 176.761095 -274.349368) (xy 176.71224 -274.3553) (xy 176.663065 -274.353319)
			(xy 176.614846 -274.343475) (xy 176.56883 -274.326023) (xy 176.526209 -274.301416) (xy 176.488088 -274.270291)
			(xy 176.455453 -274.233454) (xy 176.42915 -274.191858) (xy 176.409859 -274.146582) (xy 176.398082 -274.098798)
			(xy 176.394122 -274.049744) (xy 176.076859 -274.049744) (xy 176.07636 -274.075198) (xy 176.068317 -274.12598)
			(xy 176.052429 -274.174879) (xy 176.029086 -274.220691) (xy 175.998865 -274.262287) (xy 175.962509 -274.298643)
			(xy 175.920913 -274.328864) (xy 175.875101 -274.352207) (xy 175.826202 -274.368095) (xy 175.77542 -274.376138)
			(xy 175.724004 -274.376138) (xy 175.673222 -274.368095) (xy 175.624323 -274.352207) (xy 175.578511 -274.328864)
			(xy 175.536915 -274.298643) (xy 175.500559 -274.262287) (xy 175.470338 -274.220691) (xy 175.446995 -274.174879)
			(xy 175.431107 -274.12598) (xy 175.423064 -274.075198) (xy 175.104681 -274.075198) (xy 175.096924 -274.122928)
			(xy 175.08134 -274.169609) (xy 175.058469 -274.213186) (xy 175.028904 -274.25253) (xy 174.993411 -274.286622)
			(xy 174.952908 -274.314578) (xy 174.908446 -274.335676) (xy 174.861175 -274.349368) (xy 174.81232 -274.3553)
			(xy 174.763145 -274.353319) (xy 174.714926 -274.343475) (xy 174.66891 -274.326023) (xy 174.626289 -274.301416)
			(xy 174.588168 -274.270291) (xy 174.555533 -274.233454) (xy 174.52923 -274.191858) (xy 174.509939 -274.146582)
			(xy 174.498162 -274.098798) (xy 174.494202 -274.049744) (xy 174.177198 -274.049744) (xy 174.176694 -274.075452)
			(xy 174.168651 -274.126234) (xy 174.152763 -274.175133) (xy 174.12942 -274.220945) (xy 174.099199 -274.262541)
			(xy 174.062843 -274.298897) (xy 174.021247 -274.329118) (xy 173.975435 -274.352461) (xy 173.926536 -274.368349)
			(xy 173.875754 -274.376392) (xy 173.824338 -274.376392) (xy 173.773556 -274.368349) (xy 173.724657 -274.352461)
			(xy 173.678845 -274.329118) (xy 173.637249 -274.298897) (xy 173.600893 -274.262541) (xy 173.570672 -274.220945)
			(xy 173.547329 -274.175133) (xy 173.531441 -274.126234) (xy 173.523398 -274.075452) (xy 173.20472 -274.075452)
			(xy 173.197004 -274.122928) (xy 173.18142 -274.169609) (xy 173.158549 -274.213186) (xy 173.128984 -274.25253)
			(xy 173.093491 -274.286622) (xy 173.052988 -274.314578) (xy 173.008526 -274.335676) (xy 172.961255 -274.349368)
			(xy 172.9124 -274.3553) (xy 172.863225 -274.353319) (xy 172.815006 -274.343475) (xy 172.76899 -274.326023)
			(xy 172.726369 -274.301416) (xy 172.688248 -274.270291) (xy 172.655613 -274.233454) (xy 172.62931 -274.191858)
			(xy 172.610019 -274.146582) (xy 172.598242 -274.098798) (xy 172.594282 -274.049744) (xy 172.277024 -274.049744)
			(xy 172.27652 -274.075452) (xy 172.268477 -274.126234) (xy 172.252589 -274.175133) (xy 172.229246 -274.220945)
			(xy 172.199025 -274.262541) (xy 172.162669 -274.298897) (xy 172.121073 -274.329118) (xy 172.075261 -274.352461)
			(xy 172.026362 -274.368349) (xy 171.97558 -274.376392) (xy 171.924164 -274.376392) (xy 171.873382 -274.368349)
			(xy 171.824483 -274.352461) (xy 171.778671 -274.329118) (xy 171.737075 -274.298897) (xy 171.700719 -274.262541)
			(xy 171.670498 -274.220945) (xy 171.647155 -274.175133) (xy 171.631267 -274.126234) (xy 171.623224 -274.075452)
			(xy 171.304546 -274.075452) (xy 171.29683 -274.122928) (xy 171.281246 -274.169609) (xy 171.258375 -274.213186)
			(xy 171.22881 -274.25253) (xy 171.193317 -274.286622) (xy 171.152814 -274.314578) (xy 171.108352 -274.335676)
			(xy 171.061081 -274.349368) (xy 171.012226 -274.3553) (xy 170.963051 -274.353319) (xy 170.914832 -274.343475)
			(xy 170.868816 -274.326023) (xy 170.826195 -274.301416) (xy 170.788074 -274.270291) (xy 170.755439 -274.233454)
			(xy 170.729136 -274.191858) (xy 170.709845 -274.146582) (xy 170.698068 -274.098798) (xy 170.694108 -274.049744)
			(xy 170.377104 -274.049744) (xy 170.3766 -274.075452) (xy 170.368557 -274.126234) (xy 170.352669 -274.175133)
			(xy 170.329326 -274.220945) (xy 170.299105 -274.262541) (xy 170.262749 -274.298897) (xy 170.221153 -274.329118)
			(xy 170.175341 -274.352461) (xy 170.126442 -274.368349) (xy 170.07566 -274.376392) (xy 170.024244 -274.376392)
			(xy 169.973462 -274.368349) (xy 169.924563 -274.352461) (xy 169.878751 -274.329118) (xy 169.837155 -274.298897)
			(xy 169.800799 -274.262541) (xy 169.770578 -274.220945) (xy 169.747235 -274.175133) (xy 169.731347 -274.126234)
			(xy 169.723304 -274.075452) (xy 169.404626 -274.075452) (xy 169.39691 -274.122928) (xy 169.381326 -274.169609)
			(xy 169.358455 -274.213186) (xy 169.32889 -274.25253) (xy 169.293397 -274.286622) (xy 169.252894 -274.314578)
			(xy 169.208432 -274.335676) (xy 169.161161 -274.349368) (xy 169.112306 -274.3553) (xy 169.063131 -274.353319)
			(xy 169.014912 -274.343475) (xy 168.968896 -274.326023) (xy 168.926275 -274.301416) (xy 168.888154 -274.270291)
			(xy 168.855519 -274.233454) (xy 168.829216 -274.191858) (xy 168.809925 -274.146582) (xy 168.798148 -274.098798)
			(xy 168.794188 -274.049744) (xy 168.477184 -274.049744) (xy 168.47668 -274.075452) (xy 168.468637 -274.126234)
			(xy 168.452749 -274.175133) (xy 168.429406 -274.220945) (xy 168.399185 -274.262541) (xy 168.362829 -274.298897)
			(xy 168.321233 -274.329118) (xy 168.275421 -274.352461) (xy 168.226522 -274.368349) (xy 168.17574 -274.376392)
			(xy 168.124324 -274.376392) (xy 168.073542 -274.368349) (xy 168.024643 -274.352461) (xy 167.978831 -274.329118)
			(xy 167.937235 -274.298897) (xy 167.900879 -274.262541) (xy 167.870658 -274.220945) (xy 167.847315 -274.175133)
			(xy 167.831427 -274.126234) (xy 167.823384 -274.075452) (xy 167.504706 -274.075452) (xy 167.49699 -274.122928)
			(xy 167.481406 -274.169609) (xy 167.458535 -274.213186) (xy 167.42897 -274.25253) (xy 167.393477 -274.286622)
			(xy 167.352974 -274.314578) (xy 167.308512 -274.335676) (xy 167.261241 -274.349368) (xy 167.212386 -274.3553)
			(xy 167.163211 -274.353319) (xy 167.114992 -274.343475) (xy 167.068976 -274.326023) (xy 167.026355 -274.301416)
			(xy 166.988234 -274.270291) (xy 166.955599 -274.233454) (xy 166.929296 -274.191858) (xy 166.910005 -274.146582)
			(xy 166.898228 -274.098798) (xy 166.894268 -274.049744) (xy 166.57701 -274.049744) (xy 166.576506 -274.075452)
			(xy 166.568463 -274.126234) (xy 166.552575 -274.175133) (xy 166.529232 -274.220945) (xy 166.499011 -274.262541)
			(xy 166.462655 -274.298897) (xy 166.421059 -274.329118) (xy 166.375247 -274.352461) (xy 166.326348 -274.368349)
			(xy 166.275566 -274.376392) (xy 166.22415 -274.376392) (xy 166.173368 -274.368349) (xy 166.124469 -274.352461)
			(xy 166.078657 -274.329118) (xy 166.037061 -274.298897) (xy 166.000705 -274.262541) (xy 165.970484 -274.220945)
			(xy 165.947141 -274.175133) (xy 165.931253 -274.126234) (xy 165.92321 -274.075452) (xy 165.604486 -274.075452)
			(xy 165.597211 -274.121264) (xy 165.582311 -274.167001) (xy 165.560423 -274.209834) (xy 165.532089 -274.248706)
			(xy 165.498011 -274.282654) (xy 165.45903 -274.310837) (xy 165.416113 -274.33256) (xy 165.370319 -274.347284)
			(xy 165.346634 -274.351496) (xy 165.327838 -274.35429) (xy 165.303708 -274.382738) (xy 165.303708 -274.64512)
			(xy 165.328092 -274.673568) (xy 165.347142 -274.676362) (xy 165.372705 -274.680617) (xy 165.422146 -274.696137)
			(xy 165.468522 -274.719259) (xy 165.510672 -274.749403) (xy 165.547542 -274.785816) (xy 165.57821 -274.827586)
			(xy 165.601909 -274.873669) (xy 165.618046 -274.922912) (xy 165.626217 -274.974084) (xy 165.626217 -274.999958)
			(xy 165.944054 -274.999958) (xy 165.948014 -274.950904) (xy 165.959791 -274.90312) (xy 165.979082 -274.857844)
			(xy 166.005385 -274.816248) (xy 166.03802 -274.779411) (xy 166.076141 -274.748286) (xy 166.118762 -274.723679)
			(xy 166.164778 -274.706227) (xy 166.212997 -274.696383) (xy 166.262172 -274.694402) (xy 166.311027 -274.700334)
			(xy 166.358298 -274.714026) (xy 166.40276 -274.735124) (xy 166.443263 -274.76308) (xy 166.478756 -274.797172)
			(xy 166.508321 -274.836516) (xy 166.531192 -274.880093) (xy 166.546776 -274.926774) (xy 166.554671 -274.975351)
			(xy 166.555166 -274.999958) (xy 166.554671 -275.024565) (xy 166.554492 -275.025666) (xy 166.873424 -275.025666)
			(xy 166.873424 -274.97425) (xy 166.881467 -274.923468) (xy 166.897355 -274.874569) (xy 166.920698 -274.828757)
			(xy 166.950919 -274.787161) (xy 166.987275 -274.750805) (xy 167.028871 -274.720584) (xy 167.074683 -274.697241)
			(xy 167.123582 -274.681353) (xy 167.174364 -274.67331) (xy 167.22578 -274.67331) (xy 167.276562 -274.681353)
			(xy 167.325461 -274.697241) (xy 167.371273 -274.720584) (xy 167.412869 -274.750805) (xy 167.449225 -274.787161)
			(xy 167.479446 -274.828757) (xy 167.502789 -274.874569) (xy 167.518677 -274.923468) (xy 167.52672 -274.97425)
			(xy 167.527224 -274.999958) (xy 167.844228 -274.999958) (xy 167.848188 -274.950904) (xy 167.859965 -274.90312)
			(xy 167.879256 -274.857844) (xy 167.905559 -274.816248) (xy 167.938194 -274.779411) (xy 167.976315 -274.748286)
			(xy 168.018936 -274.723679) (xy 168.064952 -274.706227) (xy 168.113171 -274.696383) (xy 168.162346 -274.694402)
			(xy 168.211201 -274.700334) (xy 168.258472 -274.714026) (xy 168.302934 -274.735124) (xy 168.343437 -274.76308)
			(xy 168.37893 -274.797172) (xy 168.408495 -274.836516) (xy 168.431366 -274.880093) (xy 168.44695 -274.926774)
			(xy 168.454845 -274.975351) (xy 168.45534 -274.999958) (xy 168.454845 -275.024565) (xy 168.454666 -275.025666)
			(xy 168.773344 -275.025666) (xy 168.773344 -274.97425) (xy 168.781387 -274.923468) (xy 168.797275 -274.874569)
			(xy 168.820618 -274.828757) (xy 168.850839 -274.787161) (xy 168.887195 -274.750805) (xy 168.928791 -274.720584)
			(xy 168.974603 -274.697241) (xy 169.023502 -274.681353) (xy 169.074284 -274.67331) (xy 169.1257 -274.67331)
			(xy 169.176482 -274.681353) (xy 169.225381 -274.697241) (xy 169.271193 -274.720584) (xy 169.312789 -274.750805)
			(xy 169.349145 -274.787161) (xy 169.379366 -274.828757) (xy 169.402709 -274.874569) (xy 169.418597 -274.923468)
			(xy 169.42664 -274.97425) (xy 169.427144 -274.999958) (xy 169.744148 -274.999958) (xy 169.748108 -274.950904)
			(xy 169.759885 -274.90312) (xy 169.779176 -274.857844) (xy 169.805479 -274.816248) (xy 169.838114 -274.779411)
			(xy 169.876235 -274.748286) (xy 169.918856 -274.723679) (xy 169.964872 -274.706227) (xy 170.013091 -274.696383)
			(xy 170.062266 -274.694402) (xy 170.111121 -274.700334) (xy 170.158392 -274.714026) (xy 170.202854 -274.735124)
			(xy 170.243357 -274.76308) (xy 170.27885 -274.797172) (xy 170.308415 -274.836516) (xy 170.331286 -274.880093)
			(xy 170.34687 -274.926774) (xy 170.354765 -274.975351) (xy 170.35526 -274.999958) (xy 170.354765 -275.024565)
			(xy 170.354586 -275.025666) (xy 170.673264 -275.025666) (xy 170.673264 -274.97425) (xy 170.681307 -274.923468)
			(xy 170.697195 -274.874569) (xy 170.720538 -274.828757) (xy 170.750759 -274.787161) (xy 170.787115 -274.750805)
			(xy 170.828711 -274.720584) (xy 170.874523 -274.697241) (xy 170.923422 -274.681353) (xy 170.974204 -274.67331)
			(xy 171.02562 -274.67331) (xy 171.076402 -274.681353) (xy 171.125301 -274.697241) (xy 171.171113 -274.720584)
			(xy 171.212709 -274.750805) (xy 171.249065 -274.787161) (xy 171.279286 -274.828757) (xy 171.302629 -274.874569)
			(xy 171.318517 -274.923468) (xy 171.32656 -274.97425) (xy 171.327064 -274.999958) (xy 171.644068 -274.999958)
			(xy 171.648028 -274.950904) (xy 171.659805 -274.90312) (xy 171.679096 -274.857844) (xy 171.705399 -274.816248)
			(xy 171.738034 -274.779411) (xy 171.776155 -274.748286) (xy 171.818776 -274.723679) (xy 171.864792 -274.706227)
			(xy 171.913011 -274.696383) (xy 171.962186 -274.694402) (xy 172.011041 -274.700334) (xy 172.058312 -274.714026)
			(xy 172.102774 -274.735124) (xy 172.143277 -274.76308) (xy 172.17877 -274.797172) (xy 172.208335 -274.836516)
			(xy 172.231206 -274.880093) (xy 172.24679 -274.926774) (xy 172.254685 -274.975351) (xy 172.25518 -274.999958)
			(xy 172.254685 -275.024565) (xy 172.254506 -275.025666) (xy 172.573438 -275.025666) (xy 172.573438 -274.97425)
			(xy 172.581481 -274.923468) (xy 172.597369 -274.874569) (xy 172.620712 -274.828757) (xy 172.650933 -274.787161)
			(xy 172.687289 -274.750805) (xy 172.728885 -274.720584) (xy 172.774697 -274.697241) (xy 172.823596 -274.681353)
			(xy 172.874378 -274.67331) (xy 172.925794 -274.67331) (xy 172.976576 -274.681353) (xy 173.025475 -274.697241)
			(xy 173.071287 -274.720584) (xy 173.112883 -274.750805) (xy 173.149239 -274.787161) (xy 173.17946 -274.828757)
			(xy 173.202803 -274.874569) (xy 173.218691 -274.923468) (xy 173.226734 -274.97425) (xy 173.227238 -274.999958)
			(xy 173.544242 -274.999958) (xy 173.548202 -274.950904) (xy 173.559979 -274.90312) (xy 173.57927 -274.857844)
			(xy 173.605573 -274.816248) (xy 173.638208 -274.779411) (xy 173.676329 -274.748286) (xy 173.71895 -274.723679)
			(xy 173.764966 -274.706227) (xy 173.813185 -274.696383) (xy 173.86236 -274.694402) (xy 173.911215 -274.700334)
			(xy 173.958486 -274.714026) (xy 174.002948 -274.735124) (xy 174.043451 -274.76308) (xy 174.078944 -274.797172)
			(xy 174.108509 -274.836516) (xy 174.13138 -274.880093) (xy 174.146964 -274.926774) (xy 174.154859 -274.975351)
			(xy 174.155354 -274.999958) (xy 174.154859 -275.024565) (xy 174.15468 -275.025666) (xy 174.473358 -275.025666)
			(xy 174.473358 -274.97425) (xy 174.481401 -274.923468) (xy 174.497289 -274.874569) (xy 174.520632 -274.828757)
			(xy 174.550853 -274.787161) (xy 174.587209 -274.750805) (xy 174.628805 -274.720584) (xy 174.674617 -274.697241)
			(xy 174.723516 -274.681353) (xy 174.774298 -274.67331) (xy 174.825714 -274.67331) (xy 174.876496 -274.681353)
			(xy 174.925395 -274.697241) (xy 174.971207 -274.720584) (xy 175.012803 -274.750805) (xy 175.049159 -274.787161)
			(xy 175.07938 -274.828757) (xy 175.102723 -274.874569) (xy 175.118611 -274.923468) (xy 175.126654 -274.97425)
			(xy 175.127158 -274.999958) (xy 175.444162 -274.999958) (xy 175.448122 -274.950904) (xy 175.459899 -274.90312)
			(xy 175.47919 -274.857844) (xy 175.505493 -274.816248) (xy 175.538128 -274.779411) (xy 175.576249 -274.748286)
			(xy 175.61887 -274.723679) (xy 175.664886 -274.706227) (xy 175.713105 -274.696383) (xy 175.76228 -274.694402)
			(xy 175.811135 -274.700334) (xy 175.858406 -274.714026) (xy 175.902868 -274.735124) (xy 175.943371 -274.76308)
			(xy 175.978864 -274.797172) (xy 176.008429 -274.836516) (xy 176.0313 -274.880093) (xy 176.046884 -274.926774)
			(xy 176.054779 -274.975351) (xy 176.055274 -274.999958) (xy 176.054779 -275.024565) (xy 176.054641 -275.025412)
			(xy 176.373024 -275.025412) (xy 176.373024 -274.973996) (xy 176.381067 -274.923214) (xy 176.396955 -274.874315)
			(xy 176.420298 -274.828503) (xy 176.450519 -274.786907) (xy 176.486875 -274.750551) (xy 176.528471 -274.72033)
			(xy 176.574283 -274.696987) (xy 176.623182 -274.681099) (xy 176.673964 -274.673056) (xy 176.72538 -274.673056)
			(xy 176.776162 -274.681099) (xy 176.825061 -274.696987) (xy 176.870873 -274.72033) (xy 176.912469 -274.750551)
			(xy 176.948825 -274.786907) (xy 176.979046 -274.828503) (xy 177.002389 -274.874315) (xy 177.018277 -274.923214)
			(xy 177.02632 -274.973996) (xy 177.026824 -274.999704) (xy 177.026819 -274.999958) (xy 177.344082 -274.999958)
			(xy 177.348042 -274.950904) (xy 177.359819 -274.90312) (xy 177.37911 -274.857844) (xy 177.405413 -274.816248)
			(xy 177.438048 -274.779411) (xy 177.476169 -274.748286) (xy 177.51879 -274.723679) (xy 177.564806 -274.706227)
			(xy 177.613025 -274.696383) (xy 177.6622 -274.694402) (xy 177.711055 -274.700334) (xy 177.758326 -274.714026)
			(xy 177.802788 -274.735124) (xy 177.843291 -274.76308) (xy 177.878784 -274.797172) (xy 177.908349 -274.836516)
			(xy 177.93122 -274.880093) (xy 177.946804 -274.926774) (xy 177.954699 -274.975351) (xy 177.955194 -274.999958)
			(xy 177.954699 -275.024565) (xy 177.95452 -275.025666) (xy 178.272944 -275.025666) (xy 178.272944 -274.97425)
			(xy 178.280987 -274.923468) (xy 178.296875 -274.874569) (xy 178.320218 -274.828757) (xy 178.350439 -274.787161)
			(xy 178.386795 -274.750805) (xy 178.428391 -274.720584) (xy 178.474203 -274.697241) (xy 178.523102 -274.681353)
			(xy 178.573884 -274.67331) (xy 178.6253 -274.67331) (xy 178.676082 -274.681353) (xy 178.724981 -274.697241)
			(xy 178.770793 -274.720584) (xy 178.812389 -274.750805) (xy 178.848745 -274.787161) (xy 178.878966 -274.828757)
			(xy 178.902309 -274.874569) (xy 178.918197 -274.923468) (xy 178.92624 -274.97425) (xy 178.926744 -274.999958)
			(xy 179.244256 -274.999958) (xy 179.248216 -274.950904) (xy 179.259993 -274.90312) (xy 179.279284 -274.857844)
			(xy 179.305587 -274.816248) (xy 179.338222 -274.779411) (xy 179.376343 -274.748286) (xy 179.418964 -274.723679)
			(xy 179.46498 -274.706227) (xy 179.513199 -274.696383) (xy 179.562374 -274.694402) (xy 179.611229 -274.700334)
			(xy 179.6585 -274.714026) (xy 179.702962 -274.735124) (xy 179.743465 -274.76308) (xy 179.778958 -274.797172)
			(xy 179.808523 -274.836516) (xy 179.831394 -274.880093) (xy 179.846978 -274.926774) (xy 179.854873 -274.975351)
			(xy 179.855368 -274.999958) (xy 179.854873 -275.024565) (xy 179.854735 -275.025412) (xy 180.173118 -275.025412)
			(xy 180.173118 -274.973996) (xy 180.181161 -274.923214) (xy 180.197049 -274.874315) (xy 180.220392 -274.828503)
			(xy 180.250613 -274.786907) (xy 180.286969 -274.750551) (xy 180.328565 -274.72033) (xy 180.374377 -274.696987)
			(xy 180.423276 -274.681099) (xy 180.474058 -274.673056) (xy 180.525474 -274.673056) (xy 180.576256 -274.681099)
			(xy 180.625155 -274.696987) (xy 180.670967 -274.72033) (xy 180.712563 -274.750551) (xy 180.748919 -274.786907)
			(xy 180.77914 -274.828503) (xy 180.802483 -274.874315) (xy 180.818371 -274.923214) (xy 180.826414 -274.973996)
			(xy 180.826918 -274.999704) (xy 180.826913 -274.999958) (xy 181.144176 -274.999958) (xy 181.148136 -274.950904)
			(xy 181.159913 -274.90312) (xy 181.179204 -274.857844) (xy 181.205507 -274.816248) (xy 181.238142 -274.779411)
			(xy 181.276263 -274.748286) (xy 181.318884 -274.723679) (xy 181.3649 -274.706227) (xy 181.413119 -274.696383)
			(xy 181.462294 -274.694402) (xy 181.511149 -274.700334) (xy 181.55842 -274.714026) (xy 181.602882 -274.735124)
			(xy 181.643385 -274.76308) (xy 181.678878 -274.797172) (xy 181.708443 -274.836516) (xy 181.731314 -274.880093)
			(xy 181.746898 -274.926774) (xy 181.754793 -274.975351) (xy 181.755288 -274.999958) (xy 181.754793 -275.024565)
			(xy 181.754614 -275.025666) (xy 182.073038 -275.025666) (xy 182.073038 -274.97425) (xy 182.081081 -274.923468)
			(xy 182.096969 -274.874569) (xy 182.120312 -274.828757) (xy 182.150533 -274.787161) (xy 182.186889 -274.750805)
			(xy 182.228485 -274.720584) (xy 182.274297 -274.697241) (xy 182.323196 -274.681353) (xy 182.373978 -274.67331)
			(xy 182.425394 -274.67331) (xy 182.476176 -274.681353) (xy 182.525075 -274.697241) (xy 182.570887 -274.720584)
			(xy 182.612483 -274.750805) (xy 182.648839 -274.787161) (xy 182.67906 -274.828757) (xy 182.702403 -274.874569)
			(xy 182.718291 -274.923468) (xy 182.726334 -274.97425) (xy 182.726838 -274.999958) (xy 183.044096 -274.999958)
			(xy 183.048056 -274.950904) (xy 183.059833 -274.90312) (xy 183.079124 -274.857844) (xy 183.105427 -274.816248)
			(xy 183.138062 -274.779411) (xy 183.176183 -274.748286) (xy 183.218804 -274.723679) (xy 183.26482 -274.706227)
			(xy 183.313039 -274.696383) (xy 183.362214 -274.694402) (xy 183.411069 -274.700334) (xy 183.45834 -274.714026)
			(xy 183.502802 -274.735124) (xy 183.543305 -274.76308) (xy 183.578798 -274.797172) (xy 183.608363 -274.836516)
			(xy 183.631234 -274.880093) (xy 183.646818 -274.926774) (xy 183.654713 -274.975351) (xy 183.655208 -274.999958)
			(xy 183.654713 -275.024565) (xy 183.654575 -275.025412) (xy 183.972958 -275.025412) (xy 183.972958 -274.973996)
			(xy 183.981001 -274.923214) (xy 183.996889 -274.874315) (xy 184.020232 -274.828503) (xy 184.050453 -274.786907)
			(xy 184.086809 -274.750551) (xy 184.128405 -274.72033) (xy 184.174217 -274.696987) (xy 184.223116 -274.681099)
			(xy 184.273898 -274.673056) (xy 184.325314 -274.673056) (xy 184.376096 -274.681099) (xy 184.424995 -274.696987)
			(xy 184.470807 -274.72033) (xy 184.512403 -274.750551) (xy 184.548759 -274.786907) (xy 184.57898 -274.828503)
			(xy 184.602323 -274.874315) (xy 184.618211 -274.923214) (xy 184.626254 -274.973996) (xy 184.626758 -274.999704)
			(xy 184.626753 -274.999958) (xy 184.94427 -274.999958) (xy 184.94823 -274.950904) (xy 184.960007 -274.90312)
			(xy 184.979298 -274.857844) (xy 185.005601 -274.816248) (xy 185.038236 -274.779411) (xy 185.076357 -274.748286)
			(xy 185.118978 -274.723679) (xy 185.164994 -274.706227) (xy 185.213213 -274.696383) (xy 185.262388 -274.694402)
			(xy 185.311243 -274.700334) (xy 185.358514 -274.714026) (xy 185.402976 -274.735124) (xy 185.443479 -274.76308)
			(xy 185.478972 -274.797172) (xy 185.508537 -274.836516) (xy 185.531408 -274.880093) (xy 185.546992 -274.926774)
			(xy 185.554887 -274.975351) (xy 185.555382 -274.999958) (xy 185.554887 -275.024565) (xy 185.554708 -275.025666)
			(xy 185.872878 -275.025666) (xy 185.872878 -274.97425) (xy 185.880921 -274.923468) (xy 185.896809 -274.874569)
			(xy 185.920152 -274.828757) (xy 185.950373 -274.787161) (xy 185.986729 -274.750805) (xy 186.028325 -274.720584)
			(xy 186.074137 -274.697241) (xy 186.123036 -274.681353) (xy 186.173818 -274.67331) (xy 186.225234 -274.67331)
			(xy 186.276016 -274.681353) (xy 186.324915 -274.697241) (xy 186.370727 -274.720584) (xy 186.412323 -274.750805)
			(xy 186.448679 -274.787161) (xy 186.4789 -274.828757) (xy 186.502243 -274.874569) (xy 186.518131 -274.923468)
			(xy 186.526174 -274.97425) (xy 186.526678 -274.999958) (xy 186.84419 -274.999958) (xy 186.84815 -274.950904)
			(xy 186.859927 -274.90312) (xy 186.879218 -274.857844) (xy 186.905521 -274.816248) (xy 186.938156 -274.779411)
			(xy 186.976277 -274.748286) (xy 187.018898 -274.723679) (xy 187.064914 -274.706227) (xy 187.113133 -274.696383)
			(xy 187.162308 -274.694402) (xy 187.211163 -274.700334) (xy 187.258434 -274.714026) (xy 187.302896 -274.735124)
			(xy 187.343399 -274.76308) (xy 187.378892 -274.797172) (xy 187.408457 -274.836516) (xy 187.431328 -274.880093)
			(xy 187.446912 -274.926774) (xy 187.454807 -274.975351) (xy 187.455302 -274.999958) (xy 187.454807 -275.024565)
			(xy 187.454669 -275.025412) (xy 187.773052 -275.025412) (xy 187.773052 -274.973996) (xy 187.781095 -274.923214)
			(xy 187.796983 -274.874315) (xy 187.820326 -274.828503) (xy 187.850547 -274.786907) (xy 187.886903 -274.750551)
			(xy 187.928499 -274.72033) (xy 187.974311 -274.696987) (xy 188.02321 -274.681099) (xy 188.073992 -274.673056)
			(xy 188.125408 -274.673056) (xy 188.17619 -274.681099) (xy 188.225089 -274.696987) (xy 188.270901 -274.72033)
			(xy 188.312497 -274.750551) (xy 188.348853 -274.786907) (xy 188.379074 -274.828503) (xy 188.402417 -274.874315)
			(xy 188.418305 -274.923214) (xy 188.426348 -274.973996) (xy 188.426852 -274.999704) (xy 188.426847 -274.999958)
			(xy 188.74411 -274.999958) (xy 188.74807 -274.950904) (xy 188.759847 -274.90312) (xy 188.779138 -274.857844)
			(xy 188.805441 -274.816248) (xy 188.838076 -274.779411) (xy 188.876197 -274.748286) (xy 188.918818 -274.723679)
			(xy 188.964834 -274.706227) (xy 189.013053 -274.696383) (xy 189.062228 -274.694402) (xy 189.111083 -274.700334)
			(xy 189.158354 -274.714026) (xy 189.202816 -274.735124) (xy 189.243319 -274.76308) (xy 189.278812 -274.797172)
			(xy 189.308377 -274.836516) (xy 189.331248 -274.880093) (xy 189.346832 -274.926774) (xy 189.354727 -274.975351)
			(xy 189.355222 -274.999958) (xy 189.354727 -275.024565) (xy 189.354548 -275.025666) (xy 189.672972 -275.025666)
			(xy 189.672972 -274.97425) (xy 189.681015 -274.923468) (xy 189.696903 -274.874569) (xy 189.720246 -274.828757)
			(xy 189.750467 -274.787161) (xy 189.786823 -274.750805) (xy 189.828419 -274.720584) (xy 189.874231 -274.697241)
			(xy 189.92313 -274.681353) (xy 189.973912 -274.67331) (xy 190.025328 -274.67331) (xy 190.07611 -274.681353)
			(xy 190.125009 -274.697241) (xy 190.170821 -274.720584) (xy 190.212417 -274.750805) (xy 190.248773 -274.787161)
			(xy 190.278994 -274.828757) (xy 190.302337 -274.874569) (xy 190.318225 -274.923468) (xy 190.326268 -274.97425)
			(xy 190.326772 -274.999958) (xy 190.64403 -274.999958) (xy 190.64799 -274.950904) (xy 190.659767 -274.90312)
			(xy 190.679058 -274.857844) (xy 190.705361 -274.816248) (xy 190.737996 -274.779411) (xy 190.776117 -274.748286)
			(xy 190.818738 -274.723679) (xy 190.864754 -274.706227) (xy 190.912973 -274.696383) (xy 190.962148 -274.694402)
			(xy 191.011003 -274.700334) (xy 191.058274 -274.714026) (xy 191.102736 -274.735124) (xy 191.143239 -274.76308)
			(xy 191.178732 -274.797172) (xy 191.208297 -274.836516) (xy 191.231168 -274.880093) (xy 191.246752 -274.926774)
			(xy 191.254647 -274.975351) (xy 191.255142 -274.999958) (xy 191.254647 -275.024565) (xy 191.254509 -275.025412)
			(xy 191.573146 -275.025412) (xy 191.573146 -274.973996) (xy 191.581189 -274.923214) (xy 191.597077 -274.874315)
			(xy 191.62042 -274.828503) (xy 191.650641 -274.786907) (xy 191.686997 -274.750551) (xy 191.728593 -274.72033)
			(xy 191.774405 -274.696987) (xy 191.823304 -274.681099) (xy 191.874086 -274.673056) (xy 191.925502 -274.673056)
			(xy 191.976284 -274.681099) (xy 192.025183 -274.696987) (xy 192.070995 -274.72033) (xy 192.112591 -274.750551)
			(xy 192.148947 -274.786907) (xy 192.179168 -274.828503) (xy 192.202511 -274.874315) (xy 192.218399 -274.923214)
			(xy 192.226442 -274.973996) (xy 192.226946 -274.999704) (xy 192.226941 -274.999958) (xy 192.54395 -274.999958)
			(xy 192.54791 -274.950904) (xy 192.559687 -274.90312) (xy 192.578978 -274.857844) (xy 192.605281 -274.816248)
			(xy 192.637916 -274.779411) (xy 192.676037 -274.748286) (xy 192.718658 -274.723679) (xy 192.764674 -274.706227)
			(xy 192.812893 -274.696383) (xy 192.862068 -274.694402) (xy 192.910923 -274.700334) (xy 192.958194 -274.714026)
			(xy 193.002656 -274.735124) (xy 193.043159 -274.76308) (xy 193.078652 -274.797172) (xy 193.108217 -274.836516)
			(xy 193.131088 -274.880093) (xy 193.146672 -274.926774) (xy 193.154567 -274.975351) (xy 193.155062 -274.999958)
			(xy 193.154567 -275.024565) (xy 193.154388 -275.025666) (xy 193.473066 -275.025666) (xy 193.473066 -274.97425)
			(xy 193.481109 -274.923468) (xy 193.496997 -274.874569) (xy 193.52034 -274.828757) (xy 193.550561 -274.787161)
			(xy 193.586917 -274.750805) (xy 193.628513 -274.720584) (xy 193.674325 -274.697241) (xy 193.723224 -274.681353)
			(xy 193.774006 -274.67331) (xy 193.825422 -274.67331) (xy 193.876204 -274.681353) (xy 193.925103 -274.697241)
			(xy 193.970915 -274.720584) (xy 194.012511 -274.750805) (xy 194.048867 -274.787161) (xy 194.079088 -274.828757)
			(xy 194.102431 -274.874569) (xy 194.118319 -274.923468) (xy 194.126362 -274.97425) (xy 194.126866 -274.999958)
			(xy 194.44387 -274.999958) (xy 194.44783 -274.950904) (xy 194.459607 -274.90312) (xy 194.478898 -274.857844)
			(xy 194.505201 -274.816248) (xy 194.537836 -274.779411) (xy 194.575957 -274.748286) (xy 194.618578 -274.723679)
			(xy 194.664594 -274.706227) (xy 194.712813 -274.696383) (xy 194.761988 -274.694402) (xy 194.810843 -274.700334)
			(xy 194.858114 -274.714026) (xy 194.902576 -274.735124) (xy 194.943079 -274.76308) (xy 194.978572 -274.797172)
			(xy 195.008137 -274.836516) (xy 195.031008 -274.880093) (xy 195.046592 -274.926774) (xy 195.054487 -274.975351)
			(xy 195.054982 -274.999958) (xy 195.054487 -275.024565) (xy 195.054308 -275.025666) (xy 195.372986 -275.025666)
			(xy 195.372986 -274.97425) (xy 195.381029 -274.923468) (xy 195.396917 -274.874569) (xy 195.42026 -274.828757)
			(xy 195.450481 -274.787161) (xy 195.486837 -274.750805) (xy 195.528433 -274.720584) (xy 195.574245 -274.697241)
			(xy 195.623144 -274.681353) (xy 195.673926 -274.67331) (xy 195.725342 -274.67331) (xy 195.776124 -274.681353)
			(xy 195.825023 -274.697241) (xy 195.870835 -274.720584) (xy 195.912431 -274.750805) (xy 195.948787 -274.787161)
			(xy 195.979008 -274.828757) (xy 196.002351 -274.874569) (xy 196.018239 -274.923468) (xy 196.026282 -274.97425)
			(xy 196.026786 -274.999958) (xy 196.344044 -274.999958) (xy 196.348004 -274.950904) (xy 196.359781 -274.90312)
			(xy 196.379072 -274.857844) (xy 196.405375 -274.816248) (xy 196.43801 -274.779411) (xy 196.476131 -274.748286)
			(xy 196.518752 -274.723679) (xy 196.564768 -274.706227) (xy 196.612987 -274.696383) (xy 196.662162 -274.694402)
			(xy 196.711017 -274.700334) (xy 196.758288 -274.714026) (xy 196.80275 -274.735124) (xy 196.843253 -274.76308)
			(xy 196.878746 -274.797172) (xy 196.908311 -274.836516) (xy 196.931182 -274.880093) (xy 196.946766 -274.926774)
			(xy 196.954661 -274.975351) (xy 196.955156 -274.999958) (xy 196.954661 -275.024565) (xy 196.954523 -275.025412)
			(xy 197.273414 -275.025412) (xy 197.273414 -274.973996) (xy 197.281457 -274.923214) (xy 197.297345 -274.874315)
			(xy 197.320688 -274.828503) (xy 197.350909 -274.786907) (xy 197.387265 -274.750551) (xy 197.428861 -274.72033)
			(xy 197.474673 -274.696987) (xy 197.523572 -274.681099) (xy 197.574354 -274.673056) (xy 197.62577 -274.673056)
			(xy 197.676552 -274.681099) (xy 197.725451 -274.696987) (xy 197.771263 -274.72033) (xy 197.812859 -274.750551)
			(xy 197.849215 -274.786907) (xy 197.879436 -274.828503) (xy 197.902779 -274.874315) (xy 197.918667 -274.923214)
			(xy 197.92671 -274.973996) (xy 197.927214 -274.999704) (xy 197.92671 -275.025412) (xy 198.223374 -275.025412)
			(xy 198.223374 -274.973996) (xy 198.231417 -274.923214) (xy 198.247305 -274.874315) (xy 198.270648 -274.828503)
			(xy 198.300869 -274.786907) (xy 198.337225 -274.750551) (xy 198.378821 -274.72033) (xy 198.424633 -274.696987)
			(xy 198.473532 -274.681099) (xy 198.524314 -274.673056) (xy 198.57573 -274.673056) (xy 198.626512 -274.681099)
			(xy 198.675411 -274.696987) (xy 198.721223 -274.72033) (xy 198.762819 -274.750551) (xy 198.799175 -274.786907)
			(xy 198.829396 -274.828503) (xy 198.852739 -274.874315) (xy 198.868627 -274.923214) (xy 198.87667 -274.973996)
			(xy 198.877174 -274.999704) (xy 198.877169 -274.999958) (xy 199.194432 -274.999958) (xy 199.198392 -274.950904)
			(xy 199.210169 -274.90312) (xy 199.22946 -274.857844) (xy 199.255763 -274.816248) (xy 199.288398 -274.779411)
			(xy 199.326519 -274.748286) (xy 199.36914 -274.723679) (xy 199.415156 -274.706227) (xy 199.463375 -274.696383)
			(xy 199.51255 -274.694402) (xy 199.561405 -274.700334) (xy 199.608676 -274.714026) (xy 199.653138 -274.735124)
			(xy 199.693641 -274.76308) (xy 199.729134 -274.797172) (xy 199.758699 -274.836516) (xy 199.78157 -274.880093)
			(xy 199.797154 -274.926774) (xy 199.805049 -274.975351) (xy 199.805544 -274.999958) (xy 199.805049 -275.024565)
			(xy 199.797154 -275.073142) (xy 199.78157 -275.119823) (xy 199.758699 -275.1634) (xy 199.729134 -275.202744)
			(xy 199.693641 -275.236836) (xy 199.653138 -275.264792) (xy 199.608676 -275.28589) (xy 199.561405 -275.299582)
			(xy 199.51255 -275.305514) (xy 199.463375 -275.303533) (xy 199.415156 -275.293689) (xy 199.36914 -275.276237)
			(xy 199.326519 -275.25163) (xy 199.288398 -275.220505) (xy 199.255763 -275.183668) (xy 199.22946 -275.142072)
			(xy 199.210169 -275.096796) (xy 199.198392 -275.049012) (xy 199.194432 -274.999958) (xy 198.877169 -274.999958)
			(xy 198.87667 -275.025412) (xy 198.868627 -275.076194) (xy 198.852739 -275.125093) (xy 198.829396 -275.170905)
			(xy 198.799175 -275.212501) (xy 198.762819 -275.248857) (xy 198.721223 -275.279078) (xy 198.675411 -275.302421)
			(xy 198.626512 -275.318309) (xy 198.57573 -275.326352) (xy 198.524314 -275.326352) (xy 198.473532 -275.318309)
			(xy 198.424633 -275.302421) (xy 198.378821 -275.279078) (xy 198.337225 -275.248857) (xy 198.300869 -275.212501)
			(xy 198.270648 -275.170905) (xy 198.247305 -275.125093) (xy 198.231417 -275.076194) (xy 198.223374 -275.025412)
			(xy 197.92671 -275.025412) (xy 197.918667 -275.076194) (xy 197.902779 -275.125093) (xy 197.879436 -275.170905)
			(xy 197.849215 -275.212501) (xy 197.812859 -275.248857) (xy 197.771263 -275.279078) (xy 197.725451 -275.302421)
			(xy 197.676552 -275.318309) (xy 197.62577 -275.326352) (xy 197.574354 -275.326352) (xy 197.523572 -275.318309)
			(xy 197.474673 -275.302421) (xy 197.428861 -275.279078) (xy 197.387265 -275.248857) (xy 197.350909 -275.212501)
			(xy 197.320688 -275.170905) (xy 197.297345 -275.125093) (xy 197.281457 -275.076194) (xy 197.273414 -275.025412)
			(xy 196.954523 -275.025412) (xy 196.946766 -275.073142) (xy 196.931182 -275.119823) (xy 196.908311 -275.1634)
			(xy 196.878746 -275.202744) (xy 196.843253 -275.236836) (xy 196.80275 -275.264792) (xy 196.758288 -275.28589)
			(xy 196.711017 -275.299582) (xy 196.662162 -275.305514) (xy 196.612987 -275.303533) (xy 196.564768 -275.293689)
			(xy 196.518752 -275.276237) (xy 196.476131 -275.25163) (xy 196.43801 -275.220505) (xy 196.405375 -275.183668)
			(xy 196.379072 -275.142072) (xy 196.359781 -275.096796) (xy 196.348004 -275.049012) (xy 196.344044 -274.999958)
			(xy 196.026786 -274.999958) (xy 196.026282 -275.025666) (xy 196.018239 -275.076448) (xy 196.002351 -275.125347)
			(xy 195.979008 -275.171159) (xy 195.948787 -275.212755) (xy 195.912431 -275.249111) (xy 195.870835 -275.279332)
			(xy 195.825023 -275.302675) (xy 195.776124 -275.318563) (xy 195.725342 -275.326606) (xy 195.673926 -275.326606)
			(xy 195.623144 -275.318563) (xy 195.574245 -275.302675) (xy 195.528433 -275.279332) (xy 195.486837 -275.249111)
			(xy 195.450481 -275.212755) (xy 195.42026 -275.171159) (xy 195.396917 -275.125347) (xy 195.381029 -275.076448)
			(xy 195.372986 -275.025666) (xy 195.054308 -275.025666) (xy 195.046592 -275.073142) (xy 195.031008 -275.119823)
			(xy 195.008137 -275.1634) (xy 194.978572 -275.202744) (xy 194.943079 -275.236836) (xy 194.902576 -275.264792)
			(xy 194.858114 -275.28589) (xy 194.810843 -275.299582) (xy 194.761988 -275.305514) (xy 194.712813 -275.303533)
			(xy 194.664594 -275.293689) (xy 194.618578 -275.276237) (xy 194.575957 -275.25163) (xy 194.537836 -275.220505)
			(xy 194.505201 -275.183668) (xy 194.478898 -275.142072) (xy 194.459607 -275.096796) (xy 194.44783 -275.049012)
			(xy 194.44387 -274.999958) (xy 194.126866 -274.999958) (xy 194.126362 -275.025666) (xy 194.118319 -275.076448)
			(xy 194.102431 -275.125347) (xy 194.079088 -275.171159) (xy 194.048867 -275.212755) (xy 194.012511 -275.249111)
			(xy 193.970915 -275.279332) (xy 193.925103 -275.302675) (xy 193.876204 -275.318563) (xy 193.825422 -275.326606)
			(xy 193.774006 -275.326606) (xy 193.723224 -275.318563) (xy 193.674325 -275.302675) (xy 193.628513 -275.279332)
			(xy 193.586917 -275.249111) (xy 193.550561 -275.212755) (xy 193.52034 -275.171159) (xy 193.496997 -275.125347)
			(xy 193.481109 -275.076448) (xy 193.473066 -275.025666) (xy 193.154388 -275.025666) (xy 193.146672 -275.073142)
			(xy 193.131088 -275.119823) (xy 193.108217 -275.1634) (xy 193.078652 -275.202744) (xy 193.043159 -275.236836)
			(xy 193.002656 -275.264792) (xy 192.958194 -275.28589) (xy 192.910923 -275.299582) (xy 192.862068 -275.305514)
			(xy 192.812893 -275.303533) (xy 192.764674 -275.293689) (xy 192.718658 -275.276237) (xy 192.676037 -275.25163)
			(xy 192.637916 -275.220505) (xy 192.605281 -275.183668) (xy 192.578978 -275.142072) (xy 192.559687 -275.096796)
			(xy 192.54791 -275.049012) (xy 192.54395 -274.999958) (xy 192.226941 -274.999958) (xy 192.226442 -275.025412)
			(xy 192.218399 -275.076194) (xy 192.202511 -275.125093) (xy 192.179168 -275.170905) (xy 192.148947 -275.212501)
			(xy 192.112591 -275.248857) (xy 192.070995 -275.279078) (xy 192.025183 -275.302421) (xy 191.976284 -275.318309)
			(xy 191.925502 -275.326352) (xy 191.874086 -275.326352) (xy 191.823304 -275.318309) (xy 191.774405 -275.302421)
			(xy 191.728593 -275.279078) (xy 191.686997 -275.248857) (xy 191.650641 -275.212501) (xy 191.62042 -275.170905)
			(xy 191.597077 -275.125093) (xy 191.581189 -275.076194) (xy 191.573146 -275.025412) (xy 191.254509 -275.025412)
			(xy 191.246752 -275.073142) (xy 191.231168 -275.119823) (xy 191.208297 -275.1634) (xy 191.178732 -275.202744)
			(xy 191.143239 -275.236836) (xy 191.102736 -275.264792) (xy 191.058274 -275.28589) (xy 191.011003 -275.299582)
			(xy 190.962148 -275.305514) (xy 190.912973 -275.303533) (xy 190.864754 -275.293689) (xy 190.818738 -275.276237)
			(xy 190.776117 -275.25163) (xy 190.737996 -275.220505) (xy 190.705361 -275.183668) (xy 190.679058 -275.142072)
			(xy 190.659767 -275.096796) (xy 190.64799 -275.049012) (xy 190.64403 -274.999958) (xy 190.326772 -274.999958)
			(xy 190.326268 -275.025666) (xy 190.318225 -275.076448) (xy 190.302337 -275.125347) (xy 190.278994 -275.171159)
			(xy 190.248773 -275.212755) (xy 190.212417 -275.249111) (xy 190.170821 -275.279332) (xy 190.125009 -275.302675)
			(xy 190.07611 -275.318563) (xy 190.025328 -275.326606) (xy 189.973912 -275.326606) (xy 189.92313 -275.318563)
			(xy 189.874231 -275.302675) (xy 189.828419 -275.279332) (xy 189.786823 -275.249111) (xy 189.750467 -275.212755)
			(xy 189.720246 -275.171159) (xy 189.696903 -275.125347) (xy 189.681015 -275.076448) (xy 189.672972 -275.025666)
			(xy 189.354548 -275.025666) (xy 189.346832 -275.073142) (xy 189.331248 -275.119823) (xy 189.308377 -275.1634)
			(xy 189.278812 -275.202744) (xy 189.243319 -275.236836) (xy 189.202816 -275.264792) (xy 189.158354 -275.28589)
			(xy 189.111083 -275.299582) (xy 189.062228 -275.305514) (xy 189.013053 -275.303533) (xy 188.964834 -275.293689)
			(xy 188.918818 -275.276237) (xy 188.876197 -275.25163) (xy 188.838076 -275.220505) (xy 188.805441 -275.183668)
			(xy 188.779138 -275.142072) (xy 188.759847 -275.096796) (xy 188.74807 -275.049012) (xy 188.74411 -274.999958)
			(xy 188.426847 -274.999958) (xy 188.426348 -275.025412) (xy 188.418305 -275.076194) (xy 188.402417 -275.125093)
			(xy 188.379074 -275.170905) (xy 188.348853 -275.212501) (xy 188.312497 -275.248857) (xy 188.270901 -275.279078)
			(xy 188.225089 -275.302421) (xy 188.17619 -275.318309) (xy 188.125408 -275.326352) (xy 188.073992 -275.326352)
			(xy 188.02321 -275.318309) (xy 187.974311 -275.302421) (xy 187.928499 -275.279078) (xy 187.886903 -275.248857)
			(xy 187.850547 -275.212501) (xy 187.820326 -275.170905) (xy 187.796983 -275.125093) (xy 187.781095 -275.076194)
			(xy 187.773052 -275.025412) (xy 187.454669 -275.025412) (xy 187.446912 -275.073142) (xy 187.431328 -275.119823)
			(xy 187.408457 -275.1634) (xy 187.378892 -275.202744) (xy 187.343399 -275.236836) (xy 187.302896 -275.264792)
			(xy 187.258434 -275.28589) (xy 187.211163 -275.299582) (xy 187.162308 -275.305514) (xy 187.113133 -275.303533)
			(xy 187.064914 -275.293689) (xy 187.018898 -275.276237) (xy 186.976277 -275.25163) (xy 186.938156 -275.220505)
			(xy 186.905521 -275.183668) (xy 186.879218 -275.142072) (xy 186.859927 -275.096796) (xy 186.84815 -275.049012)
			(xy 186.84419 -274.999958) (xy 186.526678 -274.999958) (xy 186.526174 -275.025666) (xy 186.518131 -275.076448)
			(xy 186.502243 -275.125347) (xy 186.4789 -275.171159) (xy 186.448679 -275.212755) (xy 186.412323 -275.249111)
			(xy 186.370727 -275.279332) (xy 186.324915 -275.302675) (xy 186.276016 -275.318563) (xy 186.225234 -275.326606)
			(xy 186.173818 -275.326606) (xy 186.123036 -275.318563) (xy 186.074137 -275.302675) (xy 186.028325 -275.279332)
			(xy 185.986729 -275.249111) (xy 185.950373 -275.212755) (xy 185.920152 -275.171159) (xy 185.896809 -275.125347)
			(xy 185.880921 -275.076448) (xy 185.872878 -275.025666) (xy 185.554708 -275.025666) (xy 185.546992 -275.073142)
			(xy 185.531408 -275.119823) (xy 185.508537 -275.1634) (xy 185.478972 -275.202744) (xy 185.443479 -275.236836)
			(xy 185.402976 -275.264792) (xy 185.358514 -275.28589) (xy 185.311243 -275.299582) (xy 185.262388 -275.305514)
			(xy 185.213213 -275.303533) (xy 185.164994 -275.293689) (xy 185.118978 -275.276237) (xy 185.076357 -275.25163)
			(xy 185.038236 -275.220505) (xy 185.005601 -275.183668) (xy 184.979298 -275.142072) (xy 184.960007 -275.096796)
			(xy 184.94823 -275.049012) (xy 184.94427 -274.999958) (xy 184.626753 -274.999958) (xy 184.626254 -275.025412)
			(xy 184.618211 -275.076194) (xy 184.602323 -275.125093) (xy 184.57898 -275.170905) (xy 184.548759 -275.212501)
			(xy 184.512403 -275.248857) (xy 184.470807 -275.279078) (xy 184.424995 -275.302421) (xy 184.376096 -275.318309)
			(xy 184.325314 -275.326352) (xy 184.273898 -275.326352) (xy 184.223116 -275.318309) (xy 184.174217 -275.302421)
			(xy 184.128405 -275.279078) (xy 184.086809 -275.248857) (xy 184.050453 -275.212501) (xy 184.020232 -275.170905)
			(xy 183.996889 -275.125093) (xy 183.981001 -275.076194) (xy 183.972958 -275.025412) (xy 183.654575 -275.025412)
			(xy 183.646818 -275.073142) (xy 183.631234 -275.119823) (xy 183.608363 -275.1634) (xy 183.578798 -275.202744)
			(xy 183.543305 -275.236836) (xy 183.502802 -275.264792) (xy 183.45834 -275.28589) (xy 183.411069 -275.299582)
			(xy 183.362214 -275.305514) (xy 183.313039 -275.303533) (xy 183.26482 -275.293689) (xy 183.218804 -275.276237)
			(xy 183.176183 -275.25163) (xy 183.138062 -275.220505) (xy 183.105427 -275.183668) (xy 183.079124 -275.142072)
			(xy 183.059833 -275.096796) (xy 183.048056 -275.049012) (xy 183.044096 -274.999958) (xy 182.726838 -274.999958)
			(xy 182.726334 -275.025666) (xy 182.718291 -275.076448) (xy 182.702403 -275.125347) (xy 182.67906 -275.171159)
			(xy 182.648839 -275.212755) (xy 182.612483 -275.249111) (xy 182.570887 -275.279332) (xy 182.525075 -275.302675)
			(xy 182.476176 -275.318563) (xy 182.425394 -275.326606) (xy 182.373978 -275.326606) (xy 182.323196 -275.318563)
			(xy 182.274297 -275.302675) (xy 182.228485 -275.279332) (xy 182.186889 -275.249111) (xy 182.150533 -275.212755)
			(xy 182.120312 -275.171159) (xy 182.096969 -275.125347) (xy 182.081081 -275.076448) (xy 182.073038 -275.025666)
			(xy 181.754614 -275.025666) (xy 181.746898 -275.073142) (xy 181.731314 -275.119823) (xy 181.708443 -275.1634)
			(xy 181.678878 -275.202744) (xy 181.643385 -275.236836) (xy 181.602882 -275.264792) (xy 181.55842 -275.28589)
			(xy 181.511149 -275.299582) (xy 181.462294 -275.305514) (xy 181.413119 -275.303533) (xy 181.3649 -275.293689)
			(xy 181.318884 -275.276237) (xy 181.276263 -275.25163) (xy 181.238142 -275.220505) (xy 181.205507 -275.183668)
			(xy 181.179204 -275.142072) (xy 181.159913 -275.096796) (xy 181.148136 -275.049012) (xy 181.144176 -274.999958)
			(xy 180.826913 -274.999958) (xy 180.826414 -275.025412) (xy 180.818371 -275.076194) (xy 180.802483 -275.125093)
			(xy 180.77914 -275.170905) (xy 180.748919 -275.212501) (xy 180.712563 -275.248857) (xy 180.670967 -275.279078)
			(xy 180.625155 -275.302421) (xy 180.576256 -275.318309) (xy 180.525474 -275.326352) (xy 180.474058 -275.326352)
			(xy 180.423276 -275.318309) (xy 180.374377 -275.302421) (xy 180.328565 -275.279078) (xy 180.286969 -275.248857)
			(xy 180.250613 -275.212501) (xy 180.220392 -275.170905) (xy 180.197049 -275.125093) (xy 180.181161 -275.076194)
			(xy 180.173118 -275.025412) (xy 179.854735 -275.025412) (xy 179.846978 -275.073142) (xy 179.831394 -275.119823)
			(xy 179.808523 -275.1634) (xy 179.778958 -275.202744) (xy 179.743465 -275.236836) (xy 179.702962 -275.264792)
			(xy 179.6585 -275.28589) (xy 179.611229 -275.299582) (xy 179.562374 -275.305514) (xy 179.513199 -275.303533)
			(xy 179.46498 -275.293689) (xy 179.418964 -275.276237) (xy 179.376343 -275.25163) (xy 179.338222 -275.220505)
			(xy 179.305587 -275.183668) (xy 179.279284 -275.142072) (xy 179.259993 -275.096796) (xy 179.248216 -275.049012)
			(xy 179.244256 -274.999958) (xy 178.926744 -274.999958) (xy 178.92624 -275.025666) (xy 178.918197 -275.076448)
			(xy 178.902309 -275.125347) (xy 178.878966 -275.171159) (xy 178.848745 -275.212755) (xy 178.812389 -275.249111)
			(xy 178.770793 -275.279332) (xy 178.724981 -275.302675) (xy 178.676082 -275.318563) (xy 178.6253 -275.326606)
			(xy 178.573884 -275.326606) (xy 178.523102 -275.318563) (xy 178.474203 -275.302675) (xy 178.428391 -275.279332)
			(xy 178.386795 -275.249111) (xy 178.350439 -275.212755) (xy 178.320218 -275.171159) (xy 178.296875 -275.125347)
			(xy 178.280987 -275.076448) (xy 178.272944 -275.025666) (xy 177.95452 -275.025666) (xy 177.946804 -275.073142)
			(xy 177.93122 -275.119823) (xy 177.908349 -275.1634) (xy 177.878784 -275.202744) (xy 177.843291 -275.236836)
			(xy 177.802788 -275.264792) (xy 177.758326 -275.28589) (xy 177.711055 -275.299582) (xy 177.6622 -275.305514)
			(xy 177.613025 -275.303533) (xy 177.564806 -275.293689) (xy 177.51879 -275.276237) (xy 177.476169 -275.25163)
			(xy 177.438048 -275.220505) (xy 177.405413 -275.183668) (xy 177.37911 -275.142072) (xy 177.359819 -275.096796)
			(xy 177.348042 -275.049012) (xy 177.344082 -274.999958) (xy 177.026819 -274.999958) (xy 177.02632 -275.025412)
			(xy 177.018277 -275.076194) (xy 177.002389 -275.125093) (xy 176.979046 -275.170905) (xy 176.948825 -275.212501)
			(xy 176.912469 -275.248857) (xy 176.870873 -275.279078) (xy 176.825061 -275.302421) (xy 176.776162 -275.318309)
			(xy 176.72538 -275.326352) (xy 176.673964 -275.326352) (xy 176.623182 -275.318309) (xy 176.574283 -275.302421)
			(xy 176.528471 -275.279078) (xy 176.486875 -275.248857) (xy 176.450519 -275.212501) (xy 176.420298 -275.170905)
			(xy 176.396955 -275.125093) (xy 176.381067 -275.076194) (xy 176.373024 -275.025412) (xy 176.054641 -275.025412)
			(xy 176.046884 -275.073142) (xy 176.0313 -275.119823) (xy 176.008429 -275.1634) (xy 175.978864 -275.202744)
			(xy 175.943371 -275.236836) (xy 175.902868 -275.264792) (xy 175.858406 -275.28589) (xy 175.811135 -275.299582)
			(xy 175.76228 -275.305514) (xy 175.713105 -275.303533) (xy 175.664886 -275.293689) (xy 175.61887 -275.276237)
			(xy 175.576249 -275.25163) (xy 175.538128 -275.220505) (xy 175.505493 -275.183668) (xy 175.47919 -275.142072)
			(xy 175.459899 -275.096796) (xy 175.448122 -275.049012) (xy 175.444162 -274.999958) (xy 175.127158 -274.999958)
			(xy 175.126654 -275.025666) (xy 175.118611 -275.076448) (xy 175.102723 -275.125347) (xy 175.07938 -275.171159)
			(xy 175.049159 -275.212755) (xy 175.012803 -275.249111) (xy 174.971207 -275.279332) (xy 174.925395 -275.302675)
			(xy 174.876496 -275.318563) (xy 174.825714 -275.326606) (xy 174.774298 -275.326606) (xy 174.723516 -275.318563)
			(xy 174.674617 -275.302675) (xy 174.628805 -275.279332) (xy 174.587209 -275.249111) (xy 174.550853 -275.212755)
			(xy 174.520632 -275.171159) (xy 174.497289 -275.125347) (xy 174.481401 -275.076448) (xy 174.473358 -275.025666)
			(xy 174.15468 -275.025666) (xy 174.146964 -275.073142) (xy 174.13138 -275.119823) (xy 174.108509 -275.1634)
			(xy 174.078944 -275.202744) (xy 174.043451 -275.236836) (xy 174.002948 -275.264792) (xy 173.958486 -275.28589)
			(xy 173.911215 -275.299582) (xy 173.86236 -275.305514) (xy 173.813185 -275.303533) (xy 173.764966 -275.293689)
			(xy 173.71895 -275.276237) (xy 173.676329 -275.25163) (xy 173.638208 -275.220505) (xy 173.605573 -275.183668)
			(xy 173.57927 -275.142072) (xy 173.559979 -275.096796) (xy 173.548202 -275.049012) (xy 173.544242 -274.999958)
			(xy 173.227238 -274.999958) (xy 173.226734 -275.025666) (xy 173.218691 -275.076448) (xy 173.202803 -275.125347)
			(xy 173.17946 -275.171159) (xy 173.149239 -275.212755) (xy 173.112883 -275.249111) (xy 173.071287 -275.279332)
			(xy 173.025475 -275.302675) (xy 172.976576 -275.318563) (xy 172.925794 -275.326606) (xy 172.874378 -275.326606)
			(xy 172.823596 -275.318563) (xy 172.774697 -275.302675) (xy 172.728885 -275.279332) (xy 172.687289 -275.249111)
			(xy 172.650933 -275.212755) (xy 172.620712 -275.171159) (xy 172.597369 -275.125347) (xy 172.581481 -275.076448)
			(xy 172.573438 -275.025666) (xy 172.254506 -275.025666) (xy 172.24679 -275.073142) (xy 172.231206 -275.119823)
			(xy 172.208335 -275.1634) (xy 172.17877 -275.202744) (xy 172.143277 -275.236836) (xy 172.102774 -275.264792)
			(xy 172.058312 -275.28589) (xy 172.011041 -275.299582) (xy 171.962186 -275.305514) (xy 171.913011 -275.303533)
			(xy 171.864792 -275.293689) (xy 171.818776 -275.276237) (xy 171.776155 -275.25163) (xy 171.738034 -275.220505)
			(xy 171.705399 -275.183668) (xy 171.679096 -275.142072) (xy 171.659805 -275.096796) (xy 171.648028 -275.049012)
			(xy 171.644068 -274.999958) (xy 171.327064 -274.999958) (xy 171.32656 -275.025666) (xy 171.318517 -275.076448)
			(xy 171.302629 -275.125347) (xy 171.279286 -275.171159) (xy 171.249065 -275.212755) (xy 171.212709 -275.249111)
			(xy 171.171113 -275.279332) (xy 171.125301 -275.302675) (xy 171.076402 -275.318563) (xy 171.02562 -275.326606)
			(xy 170.974204 -275.326606) (xy 170.923422 -275.318563) (xy 170.874523 -275.302675) (xy 170.828711 -275.279332)
			(xy 170.787115 -275.249111) (xy 170.750759 -275.212755) (xy 170.720538 -275.171159) (xy 170.697195 -275.125347)
			(xy 170.681307 -275.076448) (xy 170.673264 -275.025666) (xy 170.354586 -275.025666) (xy 170.34687 -275.073142)
			(xy 170.331286 -275.119823) (xy 170.308415 -275.1634) (xy 170.27885 -275.202744) (xy 170.243357 -275.236836)
			(xy 170.202854 -275.264792) (xy 170.158392 -275.28589) (xy 170.111121 -275.299582) (xy 170.062266 -275.305514)
			(xy 170.013091 -275.303533) (xy 169.964872 -275.293689) (xy 169.918856 -275.276237) (xy 169.876235 -275.25163)
			(xy 169.838114 -275.220505) (xy 169.805479 -275.183668) (xy 169.779176 -275.142072) (xy 169.759885 -275.096796)
			(xy 169.748108 -275.049012) (xy 169.744148 -274.999958) (xy 169.427144 -274.999958) (xy 169.42664 -275.025666)
			(xy 169.418597 -275.076448) (xy 169.402709 -275.125347) (xy 169.379366 -275.171159) (xy 169.349145 -275.212755)
			(xy 169.312789 -275.249111) (xy 169.271193 -275.279332) (xy 169.225381 -275.302675) (xy 169.176482 -275.318563)
			(xy 169.1257 -275.326606) (xy 169.074284 -275.326606) (xy 169.023502 -275.318563) (xy 168.974603 -275.302675)
			(xy 168.928791 -275.279332) (xy 168.887195 -275.249111) (xy 168.850839 -275.212755) (xy 168.820618 -275.171159)
			(xy 168.797275 -275.125347) (xy 168.781387 -275.076448) (xy 168.773344 -275.025666) (xy 168.454666 -275.025666)
			(xy 168.44695 -275.073142) (xy 168.431366 -275.119823) (xy 168.408495 -275.1634) (xy 168.37893 -275.202744)
			(xy 168.343437 -275.236836) (xy 168.302934 -275.264792) (xy 168.258472 -275.28589) (xy 168.211201 -275.299582)
			(xy 168.162346 -275.305514) (xy 168.113171 -275.303533) (xy 168.064952 -275.293689) (xy 168.018936 -275.276237)
			(xy 167.976315 -275.25163) (xy 167.938194 -275.220505) (xy 167.905559 -275.183668) (xy 167.879256 -275.142072)
			(xy 167.859965 -275.096796) (xy 167.848188 -275.049012) (xy 167.844228 -274.999958) (xy 167.527224 -274.999958)
			(xy 167.52672 -275.025666) (xy 167.518677 -275.076448) (xy 167.502789 -275.125347) (xy 167.479446 -275.171159)
			(xy 167.449225 -275.212755) (xy 167.412869 -275.249111) (xy 167.371273 -275.279332) (xy 167.325461 -275.302675)
			(xy 167.276562 -275.318563) (xy 167.22578 -275.326606) (xy 167.174364 -275.326606) (xy 167.123582 -275.318563)
			(xy 167.074683 -275.302675) (xy 167.028871 -275.279332) (xy 166.987275 -275.249111) (xy 166.950919 -275.212755)
			(xy 166.920698 -275.171159) (xy 166.897355 -275.125347) (xy 166.881467 -275.076448) (xy 166.873424 -275.025666)
			(xy 166.554492 -275.025666) (xy 166.546776 -275.073142) (xy 166.531192 -275.119823) (xy 166.508321 -275.1634)
			(xy 166.478756 -275.202744) (xy 166.443263 -275.236836) (xy 166.40276 -275.264792) (xy 166.358298 -275.28589)
			(xy 166.311027 -275.299582) (xy 166.262172 -275.305514) (xy 166.212997 -275.303533) (xy 166.164778 -275.293689)
			(xy 166.118762 -275.276237) (xy 166.076141 -275.25163) (xy 166.03802 -275.220505) (xy 166.005385 -275.183668)
			(xy 165.979082 -275.142072) (xy 165.959791 -275.096796) (xy 165.948014 -275.049012) (xy 165.944054 -274.999958)
			(xy 165.626217 -274.999958) (xy 165.626218 -275.025904) (xy 165.618049 -275.077076) (xy 165.601914 -275.12632)
			(xy 165.578216 -275.172404) (xy 165.54755 -275.214175) (xy 165.510681 -275.250589) (xy 165.468532 -275.280735)
			(xy 165.422157 -275.303858) (xy 165.372717 -275.319381) (xy 165.347142 -275.323554) (xy 165.328092 -275.326348)
			(xy 165.303708 -275.354796) (xy 165.303708 -275.59508) (xy 165.328092 -275.623528) (xy 165.347142 -275.626322)
			(xy 165.3727 -275.630576) (xy 165.422132 -275.646096) (xy 165.468498 -275.669214) (xy 165.51064 -275.699354)
			(xy 165.547503 -275.735761) (xy 165.578164 -275.777525) (xy 165.601857 -275.8236) (xy 165.61799 -275.872835)
			(xy 165.626158 -275.923997) (xy 165.626158 -275.949918) (xy 165.944054 -275.949918) (xy 165.948014 -275.900864)
			(xy 165.959791 -275.85308) (xy 165.979082 -275.807804) (xy 166.005385 -275.766208) (xy 166.03802 -275.729371)
			(xy 166.076141 -275.698246) (xy 166.118762 -275.673639) (xy 166.164778 -275.656187) (xy 166.212997 -275.646343)
			(xy 166.262172 -275.644362) (xy 166.311027 -275.650294) (xy 166.358298 -275.663986) (xy 166.40276 -275.685084)
			(xy 166.443263 -275.71304) (xy 166.478756 -275.747132) (xy 166.508321 -275.786476) (xy 166.531192 -275.830053)
			(xy 166.546776 -275.876734) (xy 166.554671 -275.925311) (xy 166.555166 -275.949918) (xy 166.554671 -275.974525)
			(xy 166.554492 -275.975626) (xy 166.873424 -275.975626) (xy 166.873424 -275.92421) (xy 166.881467 -275.873428)
			(xy 166.897355 -275.824529) (xy 166.920698 -275.778717) (xy 166.950919 -275.737121) (xy 166.987275 -275.700765)
			(xy 167.028871 -275.670544) (xy 167.074683 -275.647201) (xy 167.123582 -275.631313) (xy 167.174364 -275.62327)
			(xy 167.22578 -275.62327) (xy 167.276562 -275.631313) (xy 167.325461 -275.647201) (xy 167.371273 -275.670544)
			(xy 167.412869 -275.700765) (xy 167.449225 -275.737121) (xy 167.479446 -275.778717) (xy 167.502789 -275.824529)
			(xy 167.518677 -275.873428) (xy 167.52672 -275.92421) (xy 167.527224 -275.949918) (xy 167.844228 -275.949918)
			(xy 167.848188 -275.900864) (xy 167.859965 -275.85308) (xy 167.879256 -275.807804) (xy 167.905559 -275.766208)
			(xy 167.938194 -275.729371) (xy 167.976315 -275.698246) (xy 168.018936 -275.673639) (xy 168.064952 -275.656187)
			(xy 168.113171 -275.646343) (xy 168.162346 -275.644362) (xy 168.211201 -275.650294) (xy 168.258472 -275.663986)
			(xy 168.302934 -275.685084) (xy 168.343437 -275.71304) (xy 168.37893 -275.747132) (xy 168.408495 -275.786476)
			(xy 168.431366 -275.830053) (xy 168.44695 -275.876734) (xy 168.454845 -275.925311) (xy 168.45534 -275.949918)
			(xy 168.454845 -275.974525) (xy 168.454666 -275.975626) (xy 168.773344 -275.975626) (xy 168.773344 -275.92421)
			(xy 168.781387 -275.873428) (xy 168.797275 -275.824529) (xy 168.820618 -275.778717) (xy 168.850839 -275.737121)
			(xy 168.887195 -275.700765) (xy 168.928791 -275.670544) (xy 168.974603 -275.647201) (xy 169.023502 -275.631313)
			(xy 169.074284 -275.62327) (xy 169.1257 -275.62327) (xy 169.176482 -275.631313) (xy 169.225381 -275.647201)
			(xy 169.271193 -275.670544) (xy 169.312789 -275.700765) (xy 169.349145 -275.737121) (xy 169.379366 -275.778717)
			(xy 169.402709 -275.824529) (xy 169.418597 -275.873428) (xy 169.42664 -275.92421) (xy 169.427144 -275.949918)
			(xy 169.744148 -275.949918) (xy 169.748108 -275.900864) (xy 169.759885 -275.85308) (xy 169.779176 -275.807804)
			(xy 169.805479 -275.766208) (xy 169.838114 -275.729371) (xy 169.876235 -275.698246) (xy 169.918856 -275.673639)
			(xy 169.964872 -275.656187) (xy 170.013091 -275.646343) (xy 170.062266 -275.644362) (xy 170.111121 -275.650294)
			(xy 170.158392 -275.663986) (xy 170.202854 -275.685084) (xy 170.243357 -275.71304) (xy 170.27885 -275.747132)
			(xy 170.308415 -275.786476) (xy 170.331286 -275.830053) (xy 170.34687 -275.876734) (xy 170.354765 -275.925311)
			(xy 170.35526 -275.949918) (xy 170.354765 -275.974525) (xy 170.354586 -275.975626) (xy 170.673264 -275.975626)
			(xy 170.673264 -275.92421) (xy 170.681307 -275.873428) (xy 170.697195 -275.824529) (xy 170.720538 -275.778717)
			(xy 170.750759 -275.737121) (xy 170.787115 -275.700765) (xy 170.828711 -275.670544) (xy 170.874523 -275.647201)
			(xy 170.923422 -275.631313) (xy 170.974204 -275.62327) (xy 171.02562 -275.62327) (xy 171.076402 -275.631313)
			(xy 171.125301 -275.647201) (xy 171.171113 -275.670544) (xy 171.212709 -275.700765) (xy 171.249065 -275.737121)
			(xy 171.279286 -275.778717) (xy 171.302629 -275.824529) (xy 171.318517 -275.873428) (xy 171.32656 -275.92421)
			(xy 171.327064 -275.949918) (xy 171.644068 -275.949918) (xy 171.648028 -275.900864) (xy 171.659805 -275.85308)
			(xy 171.679096 -275.807804) (xy 171.705399 -275.766208) (xy 171.738034 -275.729371) (xy 171.776155 -275.698246)
			(xy 171.818776 -275.673639) (xy 171.864792 -275.656187) (xy 171.913011 -275.646343) (xy 171.962186 -275.644362)
			(xy 172.011041 -275.650294) (xy 172.058312 -275.663986) (xy 172.102774 -275.685084) (xy 172.143277 -275.71304)
			(xy 172.17877 -275.747132) (xy 172.208335 -275.786476) (xy 172.231206 -275.830053) (xy 172.24679 -275.876734)
			(xy 172.254685 -275.925311) (xy 172.25518 -275.949918) (xy 172.254685 -275.974525) (xy 172.254506 -275.975626)
			(xy 172.573438 -275.975626) (xy 172.573438 -275.92421) (xy 172.581481 -275.873428) (xy 172.597369 -275.824529)
			(xy 172.620712 -275.778717) (xy 172.650933 -275.737121) (xy 172.687289 -275.700765) (xy 172.728885 -275.670544)
			(xy 172.774697 -275.647201) (xy 172.823596 -275.631313) (xy 172.874378 -275.62327) (xy 172.925794 -275.62327)
			(xy 172.976576 -275.631313) (xy 173.025475 -275.647201) (xy 173.071287 -275.670544) (xy 173.112883 -275.700765)
			(xy 173.149239 -275.737121) (xy 173.17946 -275.778717) (xy 173.202803 -275.824529) (xy 173.218691 -275.873428)
			(xy 173.226734 -275.92421) (xy 173.227238 -275.949918) (xy 173.544242 -275.949918) (xy 173.548202 -275.900864)
			(xy 173.559979 -275.85308) (xy 173.57927 -275.807804) (xy 173.605573 -275.766208) (xy 173.638208 -275.729371)
			(xy 173.676329 -275.698246) (xy 173.71895 -275.673639) (xy 173.764966 -275.656187) (xy 173.813185 -275.646343)
			(xy 173.86236 -275.644362) (xy 173.911215 -275.650294) (xy 173.958486 -275.663986) (xy 174.002948 -275.685084)
			(xy 174.043451 -275.71304) (xy 174.078944 -275.747132) (xy 174.108509 -275.786476) (xy 174.13138 -275.830053)
			(xy 174.146964 -275.876734) (xy 174.154859 -275.925311) (xy 174.155354 -275.949918) (xy 174.154859 -275.974525)
			(xy 174.15468 -275.975626) (xy 174.473358 -275.975626) (xy 174.473358 -275.92421) (xy 174.481401 -275.873428)
			(xy 174.497289 -275.824529) (xy 174.520632 -275.778717) (xy 174.550853 -275.737121) (xy 174.587209 -275.700765)
			(xy 174.628805 -275.670544) (xy 174.674617 -275.647201) (xy 174.723516 -275.631313) (xy 174.774298 -275.62327)
			(xy 174.825714 -275.62327) (xy 174.876496 -275.631313) (xy 174.925395 -275.647201) (xy 174.971207 -275.670544)
			(xy 175.012803 -275.700765) (xy 175.049159 -275.737121) (xy 175.07938 -275.778717) (xy 175.102723 -275.824529)
			(xy 175.118611 -275.873428) (xy 175.126654 -275.92421) (xy 175.127158 -275.949918) (xy 175.444162 -275.949918)
			(xy 175.448122 -275.900864) (xy 175.459899 -275.85308) (xy 175.47919 -275.807804) (xy 175.505493 -275.766208)
			(xy 175.538128 -275.729371) (xy 175.576249 -275.698246) (xy 175.61887 -275.673639) (xy 175.664886 -275.656187)
			(xy 175.713105 -275.646343) (xy 175.76228 -275.644362) (xy 175.811135 -275.650294) (xy 175.858406 -275.663986)
			(xy 175.902868 -275.685084) (xy 175.943371 -275.71304) (xy 175.978864 -275.747132) (xy 176.008429 -275.786476)
			(xy 176.0313 -275.830053) (xy 176.046884 -275.876734) (xy 176.054779 -275.925311) (xy 176.055274 -275.949918)
			(xy 176.054779 -275.974525) (xy 176.054641 -275.975372) (xy 176.373024 -275.975372) (xy 176.373024 -275.923956)
			(xy 176.381067 -275.873174) (xy 176.396955 -275.824275) (xy 176.420298 -275.778463) (xy 176.450519 -275.736867)
			(xy 176.486875 -275.700511) (xy 176.528471 -275.67029) (xy 176.574283 -275.646947) (xy 176.623182 -275.631059)
			(xy 176.673964 -275.623016) (xy 176.72538 -275.623016) (xy 176.776162 -275.631059) (xy 176.825061 -275.646947)
			(xy 176.870873 -275.67029) (xy 176.912469 -275.700511) (xy 176.948825 -275.736867) (xy 176.979046 -275.778463)
			(xy 177.002389 -275.824275) (xy 177.018277 -275.873174) (xy 177.02632 -275.923956) (xy 177.026824 -275.949664)
			(xy 177.026819 -275.949918) (xy 177.344082 -275.949918) (xy 177.348042 -275.900864) (xy 177.359819 -275.85308)
			(xy 177.37911 -275.807804) (xy 177.405413 -275.766208) (xy 177.438048 -275.729371) (xy 177.476169 -275.698246)
			(xy 177.51879 -275.673639) (xy 177.564806 -275.656187) (xy 177.613025 -275.646343) (xy 177.6622 -275.644362)
			(xy 177.711055 -275.650294) (xy 177.758326 -275.663986) (xy 177.802788 -275.685084) (xy 177.843291 -275.71304)
			(xy 177.878784 -275.747132) (xy 177.908349 -275.786476) (xy 177.93122 -275.830053) (xy 177.946804 -275.876734)
			(xy 177.954699 -275.925311) (xy 177.955194 -275.949918) (xy 177.954699 -275.974525) (xy 177.95452 -275.975626)
			(xy 178.272944 -275.975626) (xy 178.272944 -275.92421) (xy 178.280987 -275.873428) (xy 178.296875 -275.824529)
			(xy 178.320218 -275.778717) (xy 178.350439 -275.737121) (xy 178.386795 -275.700765) (xy 178.428391 -275.670544)
			(xy 178.474203 -275.647201) (xy 178.523102 -275.631313) (xy 178.573884 -275.62327) (xy 178.6253 -275.62327)
			(xy 178.676082 -275.631313) (xy 178.724981 -275.647201) (xy 178.770793 -275.670544) (xy 178.812389 -275.700765)
			(xy 178.848745 -275.737121) (xy 178.878966 -275.778717) (xy 178.902309 -275.824529) (xy 178.918197 -275.873428)
			(xy 178.92624 -275.92421) (xy 178.926744 -275.949918) (xy 179.244256 -275.949918) (xy 179.248216 -275.900864)
			(xy 179.259993 -275.85308) (xy 179.279284 -275.807804) (xy 179.305587 -275.766208) (xy 179.338222 -275.729371)
			(xy 179.376343 -275.698246) (xy 179.418964 -275.673639) (xy 179.46498 -275.656187) (xy 179.513199 -275.646343)
			(xy 179.562374 -275.644362) (xy 179.611229 -275.650294) (xy 179.6585 -275.663986) (xy 179.702962 -275.685084)
			(xy 179.743465 -275.71304) (xy 179.778958 -275.747132) (xy 179.808523 -275.786476) (xy 179.831394 -275.830053)
			(xy 179.846978 -275.876734) (xy 179.854873 -275.925311) (xy 179.855368 -275.949918) (xy 179.854873 -275.974525)
			(xy 179.854735 -275.975372) (xy 180.173118 -275.975372) (xy 180.173118 -275.923956) (xy 180.181161 -275.873174)
			(xy 180.197049 -275.824275) (xy 180.220392 -275.778463) (xy 180.250613 -275.736867) (xy 180.286969 -275.700511)
			(xy 180.328565 -275.67029) (xy 180.374377 -275.646947) (xy 180.423276 -275.631059) (xy 180.474058 -275.623016)
			(xy 180.525474 -275.623016) (xy 180.576256 -275.631059) (xy 180.625155 -275.646947) (xy 180.670967 -275.67029)
			(xy 180.712563 -275.700511) (xy 180.748919 -275.736867) (xy 180.77914 -275.778463) (xy 180.802483 -275.824275)
			(xy 180.818371 -275.873174) (xy 180.826414 -275.923956) (xy 180.826918 -275.949664) (xy 180.826913 -275.949918)
			(xy 181.144176 -275.949918) (xy 181.148136 -275.900864) (xy 181.159913 -275.85308) (xy 181.179204 -275.807804)
			(xy 181.205507 -275.766208) (xy 181.238142 -275.729371) (xy 181.276263 -275.698246) (xy 181.318884 -275.673639)
			(xy 181.3649 -275.656187) (xy 181.413119 -275.646343) (xy 181.462294 -275.644362) (xy 181.511149 -275.650294)
			(xy 181.55842 -275.663986) (xy 181.602882 -275.685084) (xy 181.643385 -275.71304) (xy 181.678878 -275.747132)
			(xy 181.708443 -275.786476) (xy 181.731314 -275.830053) (xy 181.746898 -275.876734) (xy 181.754793 -275.925311)
			(xy 181.755288 -275.949918) (xy 181.754793 -275.974525) (xy 181.754614 -275.975626) (xy 182.073038 -275.975626)
			(xy 182.073038 -275.92421) (xy 182.081081 -275.873428) (xy 182.096969 -275.824529) (xy 182.120312 -275.778717)
			(xy 182.150533 -275.737121) (xy 182.186889 -275.700765) (xy 182.228485 -275.670544) (xy 182.274297 -275.647201)
			(xy 182.323196 -275.631313) (xy 182.373978 -275.62327) (xy 182.425394 -275.62327) (xy 182.476176 -275.631313)
			(xy 182.525075 -275.647201) (xy 182.570887 -275.670544) (xy 182.612483 -275.700765) (xy 182.648839 -275.737121)
			(xy 182.67906 -275.778717) (xy 182.702403 -275.824529) (xy 182.718291 -275.873428) (xy 182.726334 -275.92421)
			(xy 182.726838 -275.949918) (xy 183.044096 -275.949918) (xy 183.048056 -275.900864) (xy 183.059833 -275.85308)
			(xy 183.079124 -275.807804) (xy 183.105427 -275.766208) (xy 183.138062 -275.729371) (xy 183.176183 -275.698246)
			(xy 183.218804 -275.673639) (xy 183.26482 -275.656187) (xy 183.313039 -275.646343) (xy 183.362214 -275.644362)
			(xy 183.411069 -275.650294) (xy 183.45834 -275.663986) (xy 183.502802 -275.685084) (xy 183.543305 -275.71304)
			(xy 183.578798 -275.747132) (xy 183.608363 -275.786476) (xy 183.631234 -275.830053) (xy 183.646818 -275.876734)
			(xy 183.654713 -275.925311) (xy 183.655208 -275.949918) (xy 183.654713 -275.974525) (xy 183.654575 -275.975372)
			(xy 183.972958 -275.975372) (xy 183.972958 -275.923956) (xy 183.981001 -275.873174) (xy 183.996889 -275.824275)
			(xy 184.020232 -275.778463) (xy 184.050453 -275.736867) (xy 184.086809 -275.700511) (xy 184.128405 -275.67029)
			(xy 184.174217 -275.646947) (xy 184.223116 -275.631059) (xy 184.273898 -275.623016) (xy 184.325314 -275.623016)
			(xy 184.376096 -275.631059) (xy 184.424995 -275.646947) (xy 184.470807 -275.67029) (xy 184.512403 -275.700511)
			(xy 184.548759 -275.736867) (xy 184.57898 -275.778463) (xy 184.602323 -275.824275) (xy 184.618211 -275.873174)
			(xy 184.626254 -275.923956) (xy 184.626758 -275.949664) (xy 184.626753 -275.949918) (xy 184.94427 -275.949918)
			(xy 184.94823 -275.900864) (xy 184.960007 -275.85308) (xy 184.979298 -275.807804) (xy 185.005601 -275.766208)
			(xy 185.038236 -275.729371) (xy 185.076357 -275.698246) (xy 185.118978 -275.673639) (xy 185.164994 -275.656187)
			(xy 185.213213 -275.646343) (xy 185.262388 -275.644362) (xy 185.311243 -275.650294) (xy 185.358514 -275.663986)
			(xy 185.402976 -275.685084) (xy 185.443479 -275.71304) (xy 185.478972 -275.747132) (xy 185.508537 -275.786476)
			(xy 185.531408 -275.830053) (xy 185.546992 -275.876734) (xy 185.554887 -275.925311) (xy 185.555382 -275.949918)
			(xy 185.554887 -275.974525) (xy 185.554708 -275.975626) (xy 185.872878 -275.975626) (xy 185.872878 -275.92421)
			(xy 185.880921 -275.873428) (xy 185.896809 -275.824529) (xy 185.920152 -275.778717) (xy 185.950373 -275.737121)
			(xy 185.986729 -275.700765) (xy 186.028325 -275.670544) (xy 186.074137 -275.647201) (xy 186.123036 -275.631313)
			(xy 186.173818 -275.62327) (xy 186.225234 -275.62327) (xy 186.276016 -275.631313) (xy 186.324915 -275.647201)
			(xy 186.370727 -275.670544) (xy 186.412323 -275.700765) (xy 186.448679 -275.737121) (xy 186.4789 -275.778717)
			(xy 186.502243 -275.824529) (xy 186.518131 -275.873428) (xy 186.526174 -275.92421) (xy 186.526678 -275.949918)
			(xy 186.84419 -275.949918) (xy 186.84815 -275.900864) (xy 186.859927 -275.85308) (xy 186.879218 -275.807804)
			(xy 186.905521 -275.766208) (xy 186.938156 -275.729371) (xy 186.976277 -275.698246) (xy 187.018898 -275.673639)
			(xy 187.064914 -275.656187) (xy 187.113133 -275.646343) (xy 187.162308 -275.644362) (xy 187.211163 -275.650294)
			(xy 187.258434 -275.663986) (xy 187.302896 -275.685084) (xy 187.343399 -275.71304) (xy 187.378892 -275.747132)
			(xy 187.408457 -275.786476) (xy 187.431328 -275.830053) (xy 187.446912 -275.876734) (xy 187.454807 -275.925311)
			(xy 187.455302 -275.949918) (xy 187.454807 -275.974525) (xy 187.454669 -275.975372) (xy 187.773052 -275.975372)
			(xy 187.773052 -275.923956) (xy 187.781095 -275.873174) (xy 187.796983 -275.824275) (xy 187.820326 -275.778463)
			(xy 187.850547 -275.736867) (xy 187.886903 -275.700511) (xy 187.928499 -275.67029) (xy 187.974311 -275.646947)
			(xy 188.02321 -275.631059) (xy 188.073992 -275.623016) (xy 188.125408 -275.623016) (xy 188.17619 -275.631059)
			(xy 188.225089 -275.646947) (xy 188.270901 -275.67029) (xy 188.312497 -275.700511) (xy 188.348853 -275.736867)
			(xy 188.379074 -275.778463) (xy 188.402417 -275.824275) (xy 188.418305 -275.873174) (xy 188.426348 -275.923956)
			(xy 188.426852 -275.949664) (xy 188.426847 -275.949918) (xy 188.74411 -275.949918) (xy 188.74807 -275.900864)
			(xy 188.759847 -275.85308) (xy 188.779138 -275.807804) (xy 188.805441 -275.766208) (xy 188.838076 -275.729371)
			(xy 188.876197 -275.698246) (xy 188.918818 -275.673639) (xy 188.964834 -275.656187) (xy 189.013053 -275.646343)
			(xy 189.062228 -275.644362) (xy 189.111083 -275.650294) (xy 189.158354 -275.663986) (xy 189.202816 -275.685084)
			(xy 189.243319 -275.71304) (xy 189.278812 -275.747132) (xy 189.308377 -275.786476) (xy 189.331248 -275.830053)
			(xy 189.346832 -275.876734) (xy 189.354727 -275.925311) (xy 189.355222 -275.949918) (xy 189.354727 -275.974525)
			(xy 189.354548 -275.975626) (xy 189.672972 -275.975626) (xy 189.672972 -275.92421) (xy 189.681015 -275.873428)
			(xy 189.696903 -275.824529) (xy 189.720246 -275.778717) (xy 189.750467 -275.737121) (xy 189.786823 -275.700765)
			(xy 189.828419 -275.670544) (xy 189.874231 -275.647201) (xy 189.92313 -275.631313) (xy 189.973912 -275.62327)
			(xy 190.025328 -275.62327) (xy 190.07611 -275.631313) (xy 190.125009 -275.647201) (xy 190.170821 -275.670544)
			(xy 190.212417 -275.700765) (xy 190.248773 -275.737121) (xy 190.278994 -275.778717) (xy 190.302337 -275.824529)
			(xy 190.318225 -275.873428) (xy 190.326268 -275.92421) (xy 190.326772 -275.949918) (xy 190.644284 -275.949918)
			(xy 190.648244 -275.900864) (xy 190.660021 -275.85308) (xy 190.679312 -275.807804) (xy 190.705615 -275.766208)
			(xy 190.73825 -275.729371) (xy 190.776371 -275.698246) (xy 190.818992 -275.673639) (xy 190.865008 -275.656187)
			(xy 190.913227 -275.646343) (xy 190.962402 -275.644362) (xy 191.011257 -275.650294) (xy 191.058528 -275.663986)
			(xy 191.10299 -275.685084) (xy 191.143493 -275.71304) (xy 191.178986 -275.747132) (xy 191.208551 -275.786476)
			(xy 191.231422 -275.830053) (xy 191.247006 -275.876734) (xy 191.254901 -275.925311) (xy 191.255396 -275.949918)
			(xy 191.254901 -275.974525) (xy 191.254763 -275.975372) (xy 191.573146 -275.975372) (xy 191.573146 -275.923956)
			(xy 191.581189 -275.873174) (xy 191.597077 -275.824275) (xy 191.62042 -275.778463) (xy 191.650641 -275.736867)
			(xy 191.686997 -275.700511) (xy 191.728593 -275.67029) (xy 191.774405 -275.646947) (xy 191.823304 -275.631059)
			(xy 191.874086 -275.623016) (xy 191.925502 -275.623016) (xy 191.976284 -275.631059) (xy 192.025183 -275.646947)
			(xy 192.070995 -275.67029) (xy 192.112591 -275.700511) (xy 192.148947 -275.736867) (xy 192.179168 -275.778463)
			(xy 192.202511 -275.824275) (xy 192.218399 -275.873174) (xy 192.226442 -275.923956) (xy 192.226946 -275.949664)
			(xy 192.226941 -275.949918) (xy 192.544204 -275.949918) (xy 192.548164 -275.900864) (xy 192.559941 -275.85308)
			(xy 192.579232 -275.807804) (xy 192.605535 -275.766208) (xy 192.63817 -275.729371) (xy 192.676291 -275.698246)
			(xy 192.718912 -275.673639) (xy 192.764928 -275.656187) (xy 192.813147 -275.646343) (xy 192.862322 -275.644362)
			(xy 192.911177 -275.650294) (xy 192.958448 -275.663986) (xy 193.00291 -275.685084) (xy 193.043413 -275.71304)
			(xy 193.078906 -275.747132) (xy 193.108471 -275.786476) (xy 193.131342 -275.830053) (xy 193.146926 -275.876734)
			(xy 193.154821 -275.925311) (xy 193.155316 -275.949918) (xy 193.154821 -275.974525) (xy 193.154642 -275.975626)
			(xy 193.473066 -275.975626) (xy 193.473066 -275.92421) (xy 193.481109 -275.873428) (xy 193.496997 -275.824529)
			(xy 193.52034 -275.778717) (xy 193.550561 -275.737121) (xy 193.586917 -275.700765) (xy 193.628513 -275.670544)
			(xy 193.674325 -275.647201) (xy 193.723224 -275.631313) (xy 193.774006 -275.62327) (xy 193.825422 -275.62327)
			(xy 193.876204 -275.631313) (xy 193.925103 -275.647201) (xy 193.970915 -275.670544) (xy 194.012511 -275.700765)
			(xy 194.048867 -275.737121) (xy 194.079088 -275.778717) (xy 194.102431 -275.824529) (xy 194.118319 -275.873428)
			(xy 194.126362 -275.92421) (xy 194.126866 -275.949918) (xy 194.444124 -275.949918) (xy 194.448084 -275.900864)
			(xy 194.459861 -275.85308) (xy 194.479152 -275.807804) (xy 194.505455 -275.766208) (xy 194.53809 -275.729371)
			(xy 194.576211 -275.698246) (xy 194.618832 -275.673639) (xy 194.664848 -275.656187) (xy 194.713067 -275.646343)
			(xy 194.762242 -275.644362) (xy 194.811097 -275.650294) (xy 194.858368 -275.663986) (xy 194.90283 -275.685084)
			(xy 194.943333 -275.71304) (xy 194.978826 -275.747132) (xy 195.008391 -275.786476) (xy 195.031262 -275.830053)
			(xy 195.046846 -275.876734) (xy 195.054741 -275.925311) (xy 195.055236 -275.949918) (xy 195.054741 -275.974525)
			(xy 195.054562 -275.975626) (xy 195.372986 -275.975626) (xy 195.372986 -275.92421) (xy 195.381029 -275.873428)
			(xy 195.396917 -275.824529) (xy 195.42026 -275.778717) (xy 195.450481 -275.737121) (xy 195.486837 -275.700765)
			(xy 195.528433 -275.670544) (xy 195.574245 -275.647201) (xy 195.623144 -275.631313) (xy 195.673926 -275.62327)
			(xy 195.725342 -275.62327) (xy 195.776124 -275.631313) (xy 195.825023 -275.647201) (xy 195.870835 -275.670544)
			(xy 195.912431 -275.700765) (xy 195.948787 -275.737121) (xy 195.979008 -275.778717) (xy 196.002351 -275.824529)
			(xy 196.018239 -275.873428) (xy 196.026282 -275.92421) (xy 196.026786 -275.949918) (xy 196.344298 -275.949918)
			(xy 196.348258 -275.900864) (xy 196.360035 -275.85308) (xy 196.379326 -275.807804) (xy 196.405629 -275.766208)
			(xy 196.438264 -275.729371) (xy 196.476385 -275.698246) (xy 196.519006 -275.673639) (xy 196.565022 -275.656187)
			(xy 196.613241 -275.646343) (xy 196.662416 -275.644362) (xy 196.711271 -275.650294) (xy 196.758542 -275.663986)
			(xy 196.803004 -275.685084) (xy 196.843507 -275.71304) (xy 196.879 -275.747132) (xy 196.908565 -275.786476)
			(xy 196.931436 -275.830053) (xy 196.94702 -275.876734) (xy 196.954915 -275.925311) (xy 196.95541 -275.949918)
			(xy 197.294258 -275.949918) (xy 197.298218 -275.900864) (xy 197.309995 -275.85308) (xy 197.329286 -275.807804)
			(xy 197.355589 -275.766208) (xy 197.388224 -275.729371) (xy 197.426345 -275.698246) (xy 197.468966 -275.673639)
			(xy 197.514982 -275.656187) (xy 197.563201 -275.646343) (xy 197.612376 -275.644362) (xy 197.661231 -275.650294)
			(xy 197.708502 -275.663986) (xy 197.752964 -275.685084) (xy 197.793467 -275.71304) (xy 197.82896 -275.747132)
			(xy 197.858525 -275.786476) (xy 197.881396 -275.830053) (xy 197.89698 -275.876734) (xy 197.904875 -275.925311)
			(xy 197.90537 -275.949918) (xy 198.244218 -275.949918) (xy 198.248178 -275.900864) (xy 198.259955 -275.85308)
			(xy 198.279246 -275.807804) (xy 198.305549 -275.766208) (xy 198.338184 -275.729371) (xy 198.376305 -275.698246)
			(xy 198.418926 -275.673639) (xy 198.464942 -275.656187) (xy 198.513161 -275.646343) (xy 198.562336 -275.644362)
			(xy 198.611191 -275.650294) (xy 198.658462 -275.663986) (xy 198.702924 -275.685084) (xy 198.743427 -275.71304)
			(xy 198.77892 -275.747132) (xy 198.808485 -275.786476) (xy 198.831356 -275.830053) (xy 198.84694 -275.876734)
			(xy 198.854835 -275.925311) (xy 198.85533 -275.949918) (xy 198.854835 -275.974525) (xy 198.84694 -276.023102)
			(xy 198.831356 -276.069783) (xy 198.808485 -276.11336) (xy 198.77892 -276.152704) (xy 198.743427 -276.186796)
			(xy 198.702924 -276.214752) (xy 198.658462 -276.23585) (xy 198.611191 -276.249542) (xy 198.562336 -276.255474)
			(xy 198.513161 -276.253493) (xy 198.464942 -276.243649) (xy 198.418926 -276.226197) (xy 198.376305 -276.20159)
			(xy 198.338184 -276.170465) (xy 198.305549 -276.133628) (xy 198.279246 -276.092032) (xy 198.259955 -276.046756)
			(xy 198.248178 -275.998972) (xy 198.244218 -275.949918) (xy 197.90537 -275.949918) (xy 197.904875 -275.974525)
			(xy 197.89698 -276.023102) (xy 197.881396 -276.069783) (xy 197.858525 -276.11336) (xy 197.82896 -276.152704)
			(xy 197.793467 -276.186796) (xy 197.752964 -276.214752) (xy 197.708502 -276.23585) (xy 197.661231 -276.249542)
			(xy 197.612376 -276.255474) (xy 197.563201 -276.253493) (xy 197.514982 -276.243649) (xy 197.468966 -276.226197)
			(xy 197.426345 -276.20159) (xy 197.388224 -276.170465) (xy 197.355589 -276.133628) (xy 197.329286 -276.092032)
			(xy 197.309995 -276.046756) (xy 197.298218 -275.998972) (xy 197.294258 -275.949918) (xy 196.95541 -275.949918)
			(xy 196.954915 -275.974525) (xy 196.94702 -276.023102) (xy 196.931436 -276.069783) (xy 196.908565 -276.11336)
			(xy 196.879 -276.152704) (xy 196.843507 -276.186796) (xy 196.803004 -276.214752) (xy 196.758542 -276.23585)
			(xy 196.711271 -276.249542) (xy 196.662416 -276.255474) (xy 196.613241 -276.253493) (xy 196.565022 -276.243649)
			(xy 196.519006 -276.226197) (xy 196.476385 -276.20159) (xy 196.438264 -276.170465) (xy 196.405629 -276.133628)
			(xy 196.379326 -276.092032) (xy 196.360035 -276.046756) (xy 196.348258 -275.998972) (xy 196.344298 -275.949918)
			(xy 196.026786 -275.949918) (xy 196.026282 -275.975626) (xy 196.018239 -276.026408) (xy 196.002351 -276.075307)
			(xy 195.979008 -276.121119) (xy 195.948787 -276.162715) (xy 195.912431 -276.199071) (xy 195.870835 -276.229292)
			(xy 195.825023 -276.252635) (xy 195.776124 -276.268523) (xy 195.725342 -276.276566) (xy 195.673926 -276.276566)
			(xy 195.623144 -276.268523) (xy 195.574245 -276.252635) (xy 195.528433 -276.229292) (xy 195.486837 -276.199071)
			(xy 195.450481 -276.162715) (xy 195.42026 -276.121119) (xy 195.396917 -276.075307) (xy 195.381029 -276.026408)
			(xy 195.372986 -275.975626) (xy 195.054562 -275.975626) (xy 195.046846 -276.023102) (xy 195.031262 -276.069783)
			(xy 195.008391 -276.11336) (xy 194.978826 -276.152704) (xy 194.943333 -276.186796) (xy 194.90283 -276.214752)
			(xy 194.858368 -276.23585) (xy 194.811097 -276.249542) (xy 194.762242 -276.255474) (xy 194.713067 -276.253493)
			(xy 194.664848 -276.243649) (xy 194.618832 -276.226197) (xy 194.576211 -276.20159) (xy 194.53809 -276.170465)
			(xy 194.505455 -276.133628) (xy 194.479152 -276.092032) (xy 194.459861 -276.046756) (xy 194.448084 -275.998972)
			(xy 194.444124 -275.949918) (xy 194.126866 -275.949918) (xy 194.126362 -275.975626) (xy 194.118319 -276.026408)
			(xy 194.102431 -276.075307) (xy 194.079088 -276.121119) (xy 194.048867 -276.162715) (xy 194.012511 -276.199071)
			(xy 193.970915 -276.229292) (xy 193.925103 -276.252635) (xy 193.876204 -276.268523) (xy 193.825422 -276.276566)
			(xy 193.774006 -276.276566) (xy 193.723224 -276.268523) (xy 193.674325 -276.252635) (xy 193.628513 -276.229292)
			(xy 193.586917 -276.199071) (xy 193.550561 -276.162715) (xy 193.52034 -276.121119) (xy 193.496997 -276.075307)
			(xy 193.481109 -276.026408) (xy 193.473066 -275.975626) (xy 193.154642 -275.975626) (xy 193.146926 -276.023102)
			(xy 193.131342 -276.069783) (xy 193.108471 -276.11336) (xy 193.078906 -276.152704) (xy 193.043413 -276.186796)
			(xy 193.00291 -276.214752) (xy 192.958448 -276.23585) (xy 192.911177 -276.249542) (xy 192.862322 -276.255474)
			(xy 192.813147 -276.253493) (xy 192.764928 -276.243649) (xy 192.718912 -276.226197) (xy 192.676291 -276.20159)
			(xy 192.63817 -276.170465) (xy 192.605535 -276.133628) (xy 192.579232 -276.092032) (xy 192.559941 -276.046756)
			(xy 192.548164 -275.998972) (xy 192.544204 -275.949918) (xy 192.226941 -275.949918) (xy 192.226442 -275.975372)
			(xy 192.218399 -276.026154) (xy 192.202511 -276.075053) (xy 192.179168 -276.120865) (xy 192.148947 -276.162461)
			(xy 192.112591 -276.198817) (xy 192.070995 -276.229038) (xy 192.025183 -276.252381) (xy 191.976284 -276.268269)
			(xy 191.925502 -276.276312) (xy 191.874086 -276.276312) (xy 191.823304 -276.268269) (xy 191.774405 -276.252381)
			(xy 191.728593 -276.229038) (xy 191.686997 -276.198817) (xy 191.650641 -276.162461) (xy 191.62042 -276.120865)
			(xy 191.597077 -276.075053) (xy 191.581189 -276.026154) (xy 191.573146 -275.975372) (xy 191.254763 -275.975372)
			(xy 191.247006 -276.023102) (xy 191.231422 -276.069783) (xy 191.208551 -276.11336) (xy 191.178986 -276.152704)
			(xy 191.143493 -276.186796) (xy 191.10299 -276.214752) (xy 191.058528 -276.23585) (xy 191.011257 -276.249542)
			(xy 190.962402 -276.255474) (xy 190.913227 -276.253493) (xy 190.865008 -276.243649) (xy 190.818992 -276.226197)
			(xy 190.776371 -276.20159) (xy 190.73825 -276.170465) (xy 190.705615 -276.133628) (xy 190.679312 -276.092032)
			(xy 190.660021 -276.046756) (xy 190.648244 -275.998972) (xy 190.644284 -275.949918) (xy 190.326772 -275.949918)
			(xy 190.326268 -275.975626) (xy 190.318225 -276.026408) (xy 190.302337 -276.075307) (xy 190.278994 -276.121119)
			(xy 190.248773 -276.162715) (xy 190.212417 -276.199071) (xy 190.170821 -276.229292) (xy 190.125009 -276.252635)
			(xy 190.07611 -276.268523) (xy 190.025328 -276.276566) (xy 189.973912 -276.276566) (xy 189.92313 -276.268523)
			(xy 189.874231 -276.252635) (xy 189.828419 -276.229292) (xy 189.786823 -276.199071) (xy 189.750467 -276.162715)
			(xy 189.720246 -276.121119) (xy 189.696903 -276.075307) (xy 189.681015 -276.026408) (xy 189.672972 -275.975626)
			(xy 189.354548 -275.975626) (xy 189.346832 -276.023102) (xy 189.331248 -276.069783) (xy 189.308377 -276.11336)
			(xy 189.278812 -276.152704) (xy 189.243319 -276.186796) (xy 189.202816 -276.214752) (xy 189.158354 -276.23585)
			(xy 189.111083 -276.249542) (xy 189.062228 -276.255474) (xy 189.013053 -276.253493) (xy 188.964834 -276.243649)
			(xy 188.918818 -276.226197) (xy 188.876197 -276.20159) (xy 188.838076 -276.170465) (xy 188.805441 -276.133628)
			(xy 188.779138 -276.092032) (xy 188.759847 -276.046756) (xy 188.74807 -275.998972) (xy 188.74411 -275.949918)
			(xy 188.426847 -275.949918) (xy 188.426348 -275.975372) (xy 188.418305 -276.026154) (xy 188.402417 -276.075053)
			(xy 188.379074 -276.120865) (xy 188.348853 -276.162461) (xy 188.312497 -276.198817) (xy 188.270901 -276.229038)
			(xy 188.225089 -276.252381) (xy 188.17619 -276.268269) (xy 188.125408 -276.276312) (xy 188.073992 -276.276312)
			(xy 188.02321 -276.268269) (xy 187.974311 -276.252381) (xy 187.928499 -276.229038) (xy 187.886903 -276.198817)
			(xy 187.850547 -276.162461) (xy 187.820326 -276.120865) (xy 187.796983 -276.075053) (xy 187.781095 -276.026154)
			(xy 187.773052 -275.975372) (xy 187.454669 -275.975372) (xy 187.446912 -276.023102) (xy 187.431328 -276.069783)
			(xy 187.408457 -276.11336) (xy 187.378892 -276.152704) (xy 187.343399 -276.186796) (xy 187.302896 -276.214752)
			(xy 187.258434 -276.23585) (xy 187.211163 -276.249542) (xy 187.162308 -276.255474) (xy 187.113133 -276.253493)
			(xy 187.064914 -276.243649) (xy 187.018898 -276.226197) (xy 186.976277 -276.20159) (xy 186.938156 -276.170465)
			(xy 186.905521 -276.133628) (xy 186.879218 -276.092032) (xy 186.859927 -276.046756) (xy 186.84815 -275.998972)
			(xy 186.84419 -275.949918) (xy 186.526678 -275.949918) (xy 186.526174 -275.975626) (xy 186.518131 -276.026408)
			(xy 186.502243 -276.075307) (xy 186.4789 -276.121119) (xy 186.448679 -276.162715) (xy 186.412323 -276.199071)
			(xy 186.370727 -276.229292) (xy 186.324915 -276.252635) (xy 186.276016 -276.268523) (xy 186.225234 -276.276566)
			(xy 186.173818 -276.276566) (xy 186.123036 -276.268523) (xy 186.074137 -276.252635) (xy 186.028325 -276.229292)
			(xy 185.986729 -276.199071) (xy 185.950373 -276.162715) (xy 185.920152 -276.121119) (xy 185.896809 -276.075307)
			(xy 185.880921 -276.026408) (xy 185.872878 -275.975626) (xy 185.554708 -275.975626) (xy 185.546992 -276.023102)
			(xy 185.531408 -276.069783) (xy 185.508537 -276.11336) (xy 185.478972 -276.152704) (xy 185.443479 -276.186796)
			(xy 185.402976 -276.214752) (xy 185.358514 -276.23585) (xy 185.311243 -276.249542) (xy 185.262388 -276.255474)
			(xy 185.213213 -276.253493) (xy 185.164994 -276.243649) (xy 185.118978 -276.226197) (xy 185.076357 -276.20159)
			(xy 185.038236 -276.170465) (xy 185.005601 -276.133628) (xy 184.979298 -276.092032) (xy 184.960007 -276.046756)
			(xy 184.94823 -275.998972) (xy 184.94427 -275.949918) (xy 184.626753 -275.949918) (xy 184.626254 -275.975372)
			(xy 184.618211 -276.026154) (xy 184.602323 -276.075053) (xy 184.57898 -276.120865) (xy 184.548759 -276.162461)
			(xy 184.512403 -276.198817) (xy 184.470807 -276.229038) (xy 184.424995 -276.252381) (xy 184.376096 -276.268269)
			(xy 184.325314 -276.276312) (xy 184.273898 -276.276312) (xy 184.223116 -276.268269) (xy 184.174217 -276.252381)
			(xy 184.128405 -276.229038) (xy 184.086809 -276.198817) (xy 184.050453 -276.162461) (xy 184.020232 -276.120865)
			(xy 183.996889 -276.075053) (xy 183.981001 -276.026154) (xy 183.972958 -275.975372) (xy 183.654575 -275.975372)
			(xy 183.646818 -276.023102) (xy 183.631234 -276.069783) (xy 183.608363 -276.11336) (xy 183.578798 -276.152704)
			(xy 183.543305 -276.186796) (xy 183.502802 -276.214752) (xy 183.45834 -276.23585) (xy 183.411069 -276.249542)
			(xy 183.362214 -276.255474) (xy 183.313039 -276.253493) (xy 183.26482 -276.243649) (xy 183.218804 -276.226197)
			(xy 183.176183 -276.20159) (xy 183.138062 -276.170465) (xy 183.105427 -276.133628) (xy 183.079124 -276.092032)
			(xy 183.059833 -276.046756) (xy 183.048056 -275.998972) (xy 183.044096 -275.949918) (xy 182.726838 -275.949918)
			(xy 182.726334 -275.975626) (xy 182.718291 -276.026408) (xy 182.702403 -276.075307) (xy 182.67906 -276.121119)
			(xy 182.648839 -276.162715) (xy 182.612483 -276.199071) (xy 182.570887 -276.229292) (xy 182.525075 -276.252635)
			(xy 182.476176 -276.268523) (xy 182.425394 -276.276566) (xy 182.373978 -276.276566) (xy 182.323196 -276.268523)
			(xy 182.274297 -276.252635) (xy 182.228485 -276.229292) (xy 182.186889 -276.199071) (xy 182.150533 -276.162715)
			(xy 182.120312 -276.121119) (xy 182.096969 -276.075307) (xy 182.081081 -276.026408) (xy 182.073038 -275.975626)
			(xy 181.754614 -275.975626) (xy 181.746898 -276.023102) (xy 181.731314 -276.069783) (xy 181.708443 -276.11336)
			(xy 181.678878 -276.152704) (xy 181.643385 -276.186796) (xy 181.602882 -276.214752) (xy 181.55842 -276.23585)
			(xy 181.511149 -276.249542) (xy 181.462294 -276.255474) (xy 181.413119 -276.253493) (xy 181.3649 -276.243649)
			(xy 181.318884 -276.226197) (xy 181.276263 -276.20159) (xy 181.238142 -276.170465) (xy 181.205507 -276.133628)
			(xy 181.179204 -276.092032) (xy 181.159913 -276.046756) (xy 181.148136 -275.998972) (xy 181.144176 -275.949918)
			(xy 180.826913 -275.949918) (xy 180.826414 -275.975372) (xy 180.818371 -276.026154) (xy 180.802483 -276.075053)
			(xy 180.77914 -276.120865) (xy 180.748919 -276.162461) (xy 180.712563 -276.198817) (xy 180.670967 -276.229038)
			(xy 180.625155 -276.252381) (xy 180.576256 -276.268269) (xy 180.525474 -276.276312) (xy 180.474058 -276.276312)
			(xy 180.423276 -276.268269) (xy 180.374377 -276.252381) (xy 180.328565 -276.229038) (xy 180.286969 -276.198817)
			(xy 180.250613 -276.162461) (xy 180.220392 -276.120865) (xy 180.197049 -276.075053) (xy 180.181161 -276.026154)
			(xy 180.173118 -275.975372) (xy 179.854735 -275.975372) (xy 179.846978 -276.023102) (xy 179.831394 -276.069783)
			(xy 179.808523 -276.11336) (xy 179.778958 -276.152704) (xy 179.743465 -276.186796) (xy 179.702962 -276.214752)
			(xy 179.6585 -276.23585) (xy 179.611229 -276.249542) (xy 179.562374 -276.255474) (xy 179.513199 -276.253493)
			(xy 179.46498 -276.243649) (xy 179.418964 -276.226197) (xy 179.376343 -276.20159) (xy 179.338222 -276.170465)
			(xy 179.305587 -276.133628) (xy 179.279284 -276.092032) (xy 179.259993 -276.046756) (xy 179.248216 -275.998972)
			(xy 179.244256 -275.949918) (xy 178.926744 -275.949918) (xy 178.92624 -275.975626) (xy 178.918197 -276.026408)
			(xy 178.902309 -276.075307) (xy 178.878966 -276.121119) (xy 178.848745 -276.162715) (xy 178.812389 -276.199071)
			(xy 178.770793 -276.229292) (xy 178.724981 -276.252635) (xy 178.676082 -276.268523) (xy 178.6253 -276.276566)
			(xy 178.573884 -276.276566) (xy 178.523102 -276.268523) (xy 178.474203 -276.252635) (xy 178.428391 -276.229292)
			(xy 178.386795 -276.199071) (xy 178.350439 -276.162715) (xy 178.320218 -276.121119) (xy 178.296875 -276.075307)
			(xy 178.280987 -276.026408) (xy 178.272944 -275.975626) (xy 177.95452 -275.975626) (xy 177.946804 -276.023102)
			(xy 177.93122 -276.069783) (xy 177.908349 -276.11336) (xy 177.878784 -276.152704) (xy 177.843291 -276.186796)
			(xy 177.802788 -276.214752) (xy 177.758326 -276.23585) (xy 177.711055 -276.249542) (xy 177.6622 -276.255474)
			(xy 177.613025 -276.253493) (xy 177.564806 -276.243649) (xy 177.51879 -276.226197) (xy 177.476169 -276.20159)
			(xy 177.438048 -276.170465) (xy 177.405413 -276.133628) (xy 177.37911 -276.092032) (xy 177.359819 -276.046756)
			(xy 177.348042 -275.998972) (xy 177.344082 -275.949918) (xy 177.026819 -275.949918) (xy 177.02632 -275.975372)
			(xy 177.018277 -276.026154) (xy 177.002389 -276.075053) (xy 176.979046 -276.120865) (xy 176.948825 -276.162461)
			(xy 176.912469 -276.198817) (xy 176.870873 -276.229038) (xy 176.825061 -276.252381) (xy 176.776162 -276.268269)
			(xy 176.72538 -276.276312) (xy 176.673964 -276.276312) (xy 176.623182 -276.268269) (xy 176.574283 -276.252381)
			(xy 176.528471 -276.229038) (xy 176.486875 -276.198817) (xy 176.450519 -276.162461) (xy 176.420298 -276.120865)
			(xy 176.396955 -276.075053) (xy 176.381067 -276.026154) (xy 176.373024 -275.975372) (xy 176.054641 -275.975372)
			(xy 176.046884 -276.023102) (xy 176.0313 -276.069783) (xy 176.008429 -276.11336) (xy 175.978864 -276.152704)
			(xy 175.943371 -276.186796) (xy 175.902868 -276.214752) (xy 175.858406 -276.23585) (xy 175.811135 -276.249542)
			(xy 175.76228 -276.255474) (xy 175.713105 -276.253493) (xy 175.664886 -276.243649) (xy 175.61887 -276.226197)
			(xy 175.576249 -276.20159) (xy 175.538128 -276.170465) (xy 175.505493 -276.133628) (xy 175.47919 -276.092032)
			(xy 175.459899 -276.046756) (xy 175.448122 -275.998972) (xy 175.444162 -275.949918) (xy 175.127158 -275.949918)
			(xy 175.126654 -275.975626) (xy 175.118611 -276.026408) (xy 175.102723 -276.075307) (xy 175.07938 -276.121119)
			(xy 175.049159 -276.162715) (xy 175.012803 -276.199071) (xy 174.971207 -276.229292) (xy 174.925395 -276.252635)
			(xy 174.876496 -276.268523) (xy 174.825714 -276.276566) (xy 174.774298 -276.276566) (xy 174.723516 -276.268523)
			(xy 174.674617 -276.252635) (xy 174.628805 -276.229292) (xy 174.587209 -276.199071) (xy 174.550853 -276.162715)
			(xy 174.520632 -276.121119) (xy 174.497289 -276.075307) (xy 174.481401 -276.026408) (xy 174.473358 -275.975626)
			(xy 174.15468 -275.975626) (xy 174.146964 -276.023102) (xy 174.13138 -276.069783) (xy 174.108509 -276.11336)
			(xy 174.078944 -276.152704) (xy 174.043451 -276.186796) (xy 174.002948 -276.214752) (xy 173.958486 -276.23585)
			(xy 173.911215 -276.249542) (xy 173.86236 -276.255474) (xy 173.813185 -276.253493) (xy 173.764966 -276.243649)
			(xy 173.71895 -276.226197) (xy 173.676329 -276.20159) (xy 173.638208 -276.170465) (xy 173.605573 -276.133628)
			(xy 173.57927 -276.092032) (xy 173.559979 -276.046756) (xy 173.548202 -275.998972) (xy 173.544242 -275.949918)
			(xy 173.227238 -275.949918) (xy 173.226734 -275.975626) (xy 173.218691 -276.026408) (xy 173.202803 -276.075307)
			(xy 173.17946 -276.121119) (xy 173.149239 -276.162715) (xy 173.112883 -276.199071) (xy 173.071287 -276.229292)
			(xy 173.025475 -276.252635) (xy 172.976576 -276.268523) (xy 172.925794 -276.276566) (xy 172.874378 -276.276566)
			(xy 172.823596 -276.268523) (xy 172.774697 -276.252635) (xy 172.728885 -276.229292) (xy 172.687289 -276.199071)
			(xy 172.650933 -276.162715) (xy 172.620712 -276.121119) (xy 172.597369 -276.075307) (xy 172.581481 -276.026408)
			(xy 172.573438 -275.975626) (xy 172.254506 -275.975626) (xy 172.24679 -276.023102) (xy 172.231206 -276.069783)
			(xy 172.208335 -276.11336) (xy 172.17877 -276.152704) (xy 172.143277 -276.186796) (xy 172.102774 -276.214752)
			(xy 172.058312 -276.23585) (xy 172.011041 -276.249542) (xy 171.962186 -276.255474) (xy 171.913011 -276.253493)
			(xy 171.864792 -276.243649) (xy 171.818776 -276.226197) (xy 171.776155 -276.20159) (xy 171.738034 -276.170465)
			(xy 171.705399 -276.133628) (xy 171.679096 -276.092032) (xy 171.659805 -276.046756) (xy 171.648028 -275.998972)
			(xy 171.644068 -275.949918) (xy 171.327064 -275.949918) (xy 171.32656 -275.975626) (xy 171.318517 -276.026408)
			(xy 171.302629 -276.075307) (xy 171.279286 -276.121119) (xy 171.249065 -276.162715) (xy 171.212709 -276.199071)
			(xy 171.171113 -276.229292) (xy 171.125301 -276.252635) (xy 171.076402 -276.268523) (xy 171.02562 -276.276566)
			(xy 170.974204 -276.276566) (xy 170.923422 -276.268523) (xy 170.874523 -276.252635) (xy 170.828711 -276.229292)
			(xy 170.787115 -276.199071) (xy 170.750759 -276.162715) (xy 170.720538 -276.121119) (xy 170.697195 -276.075307)
			(xy 170.681307 -276.026408) (xy 170.673264 -275.975626) (xy 170.354586 -275.975626) (xy 170.34687 -276.023102)
			(xy 170.331286 -276.069783) (xy 170.308415 -276.11336) (xy 170.27885 -276.152704) (xy 170.243357 -276.186796)
			(xy 170.202854 -276.214752) (xy 170.158392 -276.23585) (xy 170.111121 -276.249542) (xy 170.062266 -276.255474)
			(xy 170.013091 -276.253493) (xy 169.964872 -276.243649) (xy 169.918856 -276.226197) (xy 169.876235 -276.20159)
			(xy 169.838114 -276.170465) (xy 169.805479 -276.133628) (xy 169.779176 -276.092032) (xy 169.759885 -276.046756)
			(xy 169.748108 -275.998972) (xy 169.744148 -275.949918) (xy 169.427144 -275.949918) (xy 169.42664 -275.975626)
			(xy 169.418597 -276.026408) (xy 169.402709 -276.075307) (xy 169.379366 -276.121119) (xy 169.349145 -276.162715)
			(xy 169.312789 -276.199071) (xy 169.271193 -276.229292) (xy 169.225381 -276.252635) (xy 169.176482 -276.268523)
			(xy 169.1257 -276.276566) (xy 169.074284 -276.276566) (xy 169.023502 -276.268523) (xy 168.974603 -276.252635)
			(xy 168.928791 -276.229292) (xy 168.887195 -276.199071) (xy 168.850839 -276.162715) (xy 168.820618 -276.121119)
			(xy 168.797275 -276.075307) (xy 168.781387 -276.026408) (xy 168.773344 -275.975626) (xy 168.454666 -275.975626)
			(xy 168.44695 -276.023102) (xy 168.431366 -276.069783) (xy 168.408495 -276.11336) (xy 168.37893 -276.152704)
			(xy 168.343437 -276.186796) (xy 168.302934 -276.214752) (xy 168.258472 -276.23585) (xy 168.211201 -276.249542)
			(xy 168.162346 -276.255474) (xy 168.113171 -276.253493) (xy 168.064952 -276.243649) (xy 168.018936 -276.226197)
			(xy 167.976315 -276.20159) (xy 167.938194 -276.170465) (xy 167.905559 -276.133628) (xy 167.879256 -276.092032)
			(xy 167.859965 -276.046756) (xy 167.848188 -275.998972) (xy 167.844228 -275.949918) (xy 167.527224 -275.949918)
			(xy 167.52672 -275.975626) (xy 167.518677 -276.026408) (xy 167.502789 -276.075307) (xy 167.479446 -276.121119)
			(xy 167.449225 -276.162715) (xy 167.412869 -276.199071) (xy 167.371273 -276.229292) (xy 167.325461 -276.252635)
			(xy 167.276562 -276.268523) (xy 167.22578 -276.276566) (xy 167.174364 -276.276566) (xy 167.123582 -276.268523)
			(xy 167.074683 -276.252635) (xy 167.028871 -276.229292) (xy 166.987275 -276.199071) (xy 166.950919 -276.162715)
			(xy 166.920698 -276.121119) (xy 166.897355 -276.075307) (xy 166.881467 -276.026408) (xy 166.873424 -275.975626)
			(xy 166.554492 -275.975626) (xy 166.546776 -276.023102) (xy 166.531192 -276.069783) (xy 166.508321 -276.11336)
			(xy 166.478756 -276.152704) (xy 166.443263 -276.186796) (xy 166.40276 -276.214752) (xy 166.358298 -276.23585)
			(xy 166.311027 -276.249542) (xy 166.262172 -276.255474) (xy 166.212997 -276.253493) (xy 166.164778 -276.243649)
			(xy 166.118762 -276.226197) (xy 166.076141 -276.20159) (xy 166.03802 -276.170465) (xy 166.005385 -276.133628)
			(xy 165.979082 -276.092032) (xy 165.959791 -276.046756) (xy 165.948014 -275.998972) (xy 165.944054 -275.949918)
			(xy 165.626158 -275.949918) (xy 165.626158 -275.975808) (xy 165.617989 -276.02697) (xy 165.601855 -276.076205)
			(xy 165.578161 -276.12228) (xy 165.547499 -276.164043) (xy 165.510636 -276.200449) (xy 165.468494 -276.230589)
			(xy 165.422127 -276.253706) (xy 165.372695 -276.269225) (xy 165.347142 -276.273514) (xy 165.328092 -276.276308)
			(xy 165.303708 -276.304756) (xy 165.303708 -276.369018) (xy 225.13493 -276.369018) (xy 225.139001 -276.313396)
			(xy 225.151127 -276.258959) (xy 225.17105 -276.206868) (xy 225.198346 -276.158233) (xy 225.232432 -276.11409)
			(xy 225.272581 -276.075381) (xy 225.317939 -276.04293) (xy 225.367539 -276.017429) (xy 225.420323 -275.999422)
			(xy 225.475166 -275.989292) (xy 225.5309 -275.987255) (xy 225.586337 -275.993355) (xy 225.640294 -276.007461)
			(xy 225.691623 -276.029273) (xy 225.739229 -276.058327) (xy 225.782097 -276.094002) (xy 225.819314 -276.135539)
			(xy 225.850087 -276.182052) (xy 225.873759 -276.232549) (xy 225.889827 -276.285956) (xy 225.897947 -276.341132)
			(xy 225.898456 -276.369018) (xy 225.897947 -276.396904) (xy 225.889827 -276.45208) (xy 225.873759 -276.505487)
			(xy 225.850087 -276.555984) (xy 225.819314 -276.602497) (xy 225.782097 -276.644034) (xy 225.739229 -276.679709)
			(xy 225.691623 -276.708763) (xy 225.640294 -276.730575) (xy 225.586337 -276.744681) (xy 225.5309 -276.750781)
			(xy 225.475166 -276.748744) (xy 225.420323 -276.738614) (xy 225.367539 -276.720607) (xy 225.317939 -276.695106)
			(xy 225.272581 -276.662655) (xy 225.232432 -276.623946) (xy 225.198346 -276.579803) (xy 225.17105 -276.531168)
			(xy 225.151127 -276.479077) (xy 225.139001 -276.42464) (xy 225.13493 -276.369018) (xy 165.303708 -276.369018)
			(xy 165.303708 -276.566884) (xy 165.327838 -276.595332) (xy 165.346634 -276.598126) (xy 165.370338 -276.602253)
			(xy 165.41614 -276.616981) (xy 165.459067 -276.638709) (xy 165.498055 -276.666899) (xy 165.532141 -276.700854)
			(xy 165.56048 -276.739734) (xy 165.582372 -276.782578) (xy 165.597275 -276.828324) (xy 165.60482 -276.875841)
			(xy 165.60482 -276.899878) (xy 165.944054 -276.899878) (xy 165.948014 -276.850824) (xy 165.959791 -276.80304)
			(xy 165.979082 -276.757764) (xy 166.005385 -276.716168) (xy 166.03802 -276.679331) (xy 166.076141 -276.648206)
			(xy 166.118762 -276.623599) (xy 166.164778 -276.606147) (xy 166.212997 -276.596303) (xy 166.262172 -276.594322)
			(xy 166.311027 -276.600254) (xy 166.358298 -276.613946) (xy 166.40276 -276.635044) (xy 166.443263 -276.663)
			(xy 166.478756 -276.697092) (xy 166.508321 -276.736436) (xy 166.531192 -276.780013) (xy 166.546776 -276.826694)
			(xy 166.554671 -276.875271) (xy 166.555166 -276.899878) (xy 166.894268 -276.899878) (xy 166.898228 -276.850824)
			(xy 166.910005 -276.80304) (xy 166.929296 -276.757764) (xy 166.955599 -276.716168) (xy 166.988234 -276.679331)
			(xy 167.026355 -276.648206) (xy 167.068976 -276.623599) (xy 167.114992 -276.606147) (xy 167.163211 -276.596303)
			(xy 167.212386 -276.594322) (xy 167.261241 -276.600254) (xy 167.308512 -276.613946) (xy 167.352974 -276.635044)
			(xy 167.393477 -276.663) (xy 167.42897 -276.697092) (xy 167.458535 -276.736436) (xy 167.481406 -276.780013)
			(xy 167.49699 -276.826694) (xy 167.504885 -276.875271) (xy 167.50538 -276.899878) (xy 167.844228 -276.899878)
			(xy 167.848188 -276.850824) (xy 167.859965 -276.80304) (xy 167.879256 -276.757764) (xy 167.905559 -276.716168)
			(xy 167.938194 -276.679331) (xy 167.976315 -276.648206) (xy 168.018936 -276.623599) (xy 168.064952 -276.606147)
			(xy 168.113171 -276.596303) (xy 168.162346 -276.594322) (xy 168.211201 -276.600254) (xy 168.258472 -276.613946)
			(xy 168.302934 -276.635044) (xy 168.343437 -276.663) (xy 168.37893 -276.697092) (xy 168.408495 -276.736436)
			(xy 168.431366 -276.780013) (xy 168.44695 -276.826694) (xy 168.454845 -276.875271) (xy 168.45534 -276.899878)
			(xy 168.794188 -276.899878) (xy 168.798148 -276.850824) (xy 168.809925 -276.80304) (xy 168.829216 -276.757764)
			(xy 168.855519 -276.716168) (xy 168.888154 -276.679331) (xy 168.926275 -276.648206) (xy 168.968896 -276.623599)
			(xy 169.014912 -276.606147) (xy 169.063131 -276.596303) (xy 169.112306 -276.594322) (xy 169.161161 -276.600254)
			(xy 169.208432 -276.613946) (xy 169.252894 -276.635044) (xy 169.293397 -276.663) (xy 169.32889 -276.697092)
			(xy 169.358455 -276.736436) (xy 169.381326 -276.780013) (xy 169.39691 -276.826694) (xy 169.404805 -276.875271)
			(xy 169.4053 -276.899878) (xy 169.744148 -276.899878) (xy 169.748108 -276.850824) (xy 169.759885 -276.80304)
			(xy 169.779176 -276.757764) (xy 169.805479 -276.716168) (xy 169.838114 -276.679331) (xy 169.876235 -276.648206)
			(xy 169.918856 -276.623599) (xy 169.964872 -276.606147) (xy 170.013091 -276.596303) (xy 170.062266 -276.594322)
			(xy 170.111121 -276.600254) (xy 170.158392 -276.613946) (xy 170.202854 -276.635044) (xy 170.243357 -276.663)
			(xy 170.27885 -276.697092) (xy 170.308415 -276.736436) (xy 170.331286 -276.780013) (xy 170.34687 -276.826694)
			(xy 170.354765 -276.875271) (xy 170.35526 -276.899878) (xy 170.694108 -276.899878) (xy 170.698068 -276.850824)
			(xy 170.709845 -276.80304) (xy 170.729136 -276.757764) (xy 170.755439 -276.716168) (xy 170.788074 -276.679331)
			(xy 170.826195 -276.648206) (xy 170.868816 -276.623599) (xy 170.914832 -276.606147) (xy 170.963051 -276.596303)
			(xy 171.012226 -276.594322) (xy 171.061081 -276.600254) (xy 171.108352 -276.613946) (xy 171.152814 -276.635044)
			(xy 171.193317 -276.663) (xy 171.22881 -276.697092) (xy 171.258375 -276.736436) (xy 171.281246 -276.780013)
			(xy 171.29683 -276.826694) (xy 171.304725 -276.875271) (xy 171.30522 -276.899878) (xy 171.644068 -276.899878)
			(xy 171.648028 -276.850824) (xy 171.659805 -276.80304) (xy 171.679096 -276.757764) (xy 171.705399 -276.716168)
			(xy 171.738034 -276.679331) (xy 171.776155 -276.648206) (xy 171.818776 -276.623599) (xy 171.864792 -276.606147)
			(xy 171.913011 -276.596303) (xy 171.962186 -276.594322) (xy 172.011041 -276.600254) (xy 172.058312 -276.613946)
			(xy 172.102774 -276.635044) (xy 172.143277 -276.663) (xy 172.17877 -276.697092) (xy 172.208335 -276.736436)
			(xy 172.231206 -276.780013) (xy 172.24679 -276.826694) (xy 172.254685 -276.875271) (xy 172.25518 -276.899878)
			(xy 172.594282 -276.899878) (xy 172.598242 -276.850824) (xy 172.610019 -276.80304) (xy 172.62931 -276.757764)
			(xy 172.655613 -276.716168) (xy 172.688248 -276.679331) (xy 172.726369 -276.648206) (xy 172.76899 -276.623599)
			(xy 172.815006 -276.606147) (xy 172.863225 -276.596303) (xy 172.9124 -276.594322) (xy 172.961255 -276.600254)
			(xy 173.008526 -276.613946) (xy 173.052988 -276.635044) (xy 173.093491 -276.663) (xy 173.128984 -276.697092)
			(xy 173.158549 -276.736436) (xy 173.18142 -276.780013) (xy 173.197004 -276.826694) (xy 173.204899 -276.875271)
			(xy 173.205394 -276.899878) (xy 173.544242 -276.899878) (xy 173.548202 -276.850824) (xy 173.559979 -276.80304)
			(xy 173.57927 -276.757764) (xy 173.605573 -276.716168) (xy 173.638208 -276.679331) (xy 173.676329 -276.648206)
			(xy 173.71895 -276.623599) (xy 173.764966 -276.606147) (xy 173.813185 -276.596303) (xy 173.86236 -276.594322)
			(xy 173.911215 -276.600254) (xy 173.958486 -276.613946) (xy 174.002948 -276.635044) (xy 174.043451 -276.663)
			(xy 174.078944 -276.697092) (xy 174.108509 -276.736436) (xy 174.13138 -276.780013) (xy 174.146964 -276.826694)
			(xy 174.154859 -276.875271) (xy 174.155354 -276.899878) (xy 174.494202 -276.899878) (xy 174.498162 -276.850824)
			(xy 174.509939 -276.80304) (xy 174.52923 -276.757764) (xy 174.555533 -276.716168) (xy 174.588168 -276.679331)
			(xy 174.626289 -276.648206) (xy 174.66891 -276.623599) (xy 174.714926 -276.606147) (xy 174.763145 -276.596303)
			(xy 174.81232 -276.594322) (xy 174.861175 -276.600254) (xy 174.908446 -276.613946) (xy 174.952908 -276.635044)
			(xy 174.993411 -276.663) (xy 175.028904 -276.697092) (xy 175.058469 -276.736436) (xy 175.08134 -276.780013)
			(xy 175.096924 -276.826694) (xy 175.104819 -276.875271) (xy 175.105314 -276.899878) (xy 175.444162 -276.899878)
			(xy 175.448122 -276.850824) (xy 175.459899 -276.80304) (xy 175.47919 -276.757764) (xy 175.505493 -276.716168)
			(xy 175.538128 -276.679331) (xy 175.576249 -276.648206) (xy 175.61887 -276.623599) (xy 175.664886 -276.606147)
			(xy 175.713105 -276.596303) (xy 175.76228 -276.594322) (xy 175.811135 -276.600254) (xy 175.858406 -276.613946)
			(xy 175.902868 -276.635044) (xy 175.943371 -276.663) (xy 175.978864 -276.697092) (xy 176.008429 -276.736436)
			(xy 176.0313 -276.780013) (xy 176.046884 -276.826694) (xy 176.054779 -276.875271) (xy 176.055274 -276.899878)
			(xy 176.394122 -276.899878) (xy 176.398082 -276.850824) (xy 176.409859 -276.80304) (xy 176.42915 -276.757764)
			(xy 176.455453 -276.716168) (xy 176.488088 -276.679331) (xy 176.526209 -276.648206) (xy 176.56883 -276.623599)
			(xy 176.614846 -276.606147) (xy 176.663065 -276.596303) (xy 176.71224 -276.594322) (xy 176.761095 -276.600254)
			(xy 176.808366 -276.613946) (xy 176.852828 -276.635044) (xy 176.893331 -276.663) (xy 176.928824 -276.697092)
			(xy 176.958389 -276.736436) (xy 176.98126 -276.780013) (xy 176.996844 -276.826694) (xy 177.004739 -276.875271)
			(xy 177.005234 -276.899878) (xy 177.344082 -276.899878) (xy 177.348042 -276.850824) (xy 177.359819 -276.80304)
			(xy 177.37911 -276.757764) (xy 177.405413 -276.716168) (xy 177.438048 -276.679331) (xy 177.476169 -276.648206)
			(xy 177.51879 -276.623599) (xy 177.564806 -276.606147) (xy 177.613025 -276.596303) (xy 177.6622 -276.594322)
			(xy 177.711055 -276.600254) (xy 177.758326 -276.613946) (xy 177.802788 -276.635044) (xy 177.843291 -276.663)
			(xy 177.878784 -276.697092) (xy 177.908349 -276.736436) (xy 177.93122 -276.780013) (xy 177.946804 -276.826694)
			(xy 177.954699 -276.875271) (xy 177.955194 -276.899878) (xy 178.294042 -276.899878) (xy 178.298002 -276.850824)
			(xy 178.309779 -276.80304) (xy 178.32907 -276.757764) (xy 178.355373 -276.716168) (xy 178.388008 -276.679331)
			(xy 178.426129 -276.648206) (xy 178.46875 -276.623599) (xy 178.514766 -276.606147) (xy 178.562985 -276.596303)
			(xy 178.61216 -276.594322) (xy 178.661015 -276.600254) (xy 178.708286 -276.613946) (xy 178.752748 -276.635044)
			(xy 178.793251 -276.663) (xy 178.828744 -276.697092) (xy 178.858309 -276.736436) (xy 178.88118 -276.780013)
			(xy 178.896764 -276.826694) (xy 178.904659 -276.875271) (xy 178.905154 -276.899878) (xy 179.244256 -276.899878)
			(xy 179.248216 -276.850824) (xy 179.259993 -276.80304) (xy 179.279284 -276.757764) (xy 179.305587 -276.716168)
			(xy 179.338222 -276.679331) (xy 179.376343 -276.648206) (xy 179.418964 -276.623599) (xy 179.46498 -276.606147)
			(xy 179.513199 -276.596303) (xy 179.562374 -276.594322) (xy 179.611229 -276.600254) (xy 179.6585 -276.613946)
			(xy 179.702962 -276.635044) (xy 179.743465 -276.663) (xy 179.778958 -276.697092) (xy 179.808523 -276.736436)
			(xy 179.831394 -276.780013) (xy 179.846978 -276.826694) (xy 179.854873 -276.875271) (xy 179.855368 -276.899878)
			(xy 180.194216 -276.899878) (xy 180.198176 -276.850824) (xy 180.209953 -276.80304) (xy 180.229244 -276.757764)
			(xy 180.255547 -276.716168) (xy 180.288182 -276.679331) (xy 180.326303 -276.648206) (xy 180.368924 -276.623599)
			(xy 180.41494 -276.606147) (xy 180.463159 -276.596303) (xy 180.512334 -276.594322) (xy 180.561189 -276.600254)
			(xy 180.60846 -276.613946) (xy 180.652922 -276.635044) (xy 180.693425 -276.663) (xy 180.728918 -276.697092)
			(xy 180.758483 -276.736436) (xy 180.781354 -276.780013) (xy 180.796938 -276.826694) (xy 180.804833 -276.875271)
			(xy 180.805328 -276.899878) (xy 181.144176 -276.899878) (xy 181.148136 -276.850824) (xy 181.159913 -276.80304)
			(xy 181.179204 -276.757764) (xy 181.205507 -276.716168) (xy 181.238142 -276.679331) (xy 181.276263 -276.648206)
			(xy 181.318884 -276.623599) (xy 181.3649 -276.606147) (xy 181.413119 -276.596303) (xy 181.462294 -276.594322)
			(xy 181.511149 -276.600254) (xy 181.55842 -276.613946) (xy 181.602882 -276.635044) (xy 181.643385 -276.663)
			(xy 181.678878 -276.697092) (xy 181.708443 -276.736436) (xy 181.731314 -276.780013) (xy 181.746898 -276.826694)
			(xy 181.754793 -276.875271) (xy 181.755288 -276.899878) (xy 182.094136 -276.899878) (xy 182.098096 -276.850824)
			(xy 182.109873 -276.80304) (xy 182.129164 -276.757764) (xy 182.155467 -276.716168) (xy 182.188102 -276.679331)
			(xy 182.226223 -276.648206) (xy 182.268844 -276.623599) (xy 182.31486 -276.606147) (xy 182.363079 -276.596303)
			(xy 182.412254 -276.594322) (xy 182.461109 -276.600254) (xy 182.50838 -276.613946) (xy 182.552842 -276.635044)
			(xy 182.593345 -276.663) (xy 182.628838 -276.697092) (xy 182.658403 -276.736436) (xy 182.681274 -276.780013)
			(xy 182.696858 -276.826694) (xy 182.704753 -276.875271) (xy 182.705248 -276.899878) (xy 183.044096 -276.899878)
			(xy 183.048056 -276.850824) (xy 183.059833 -276.80304) (xy 183.079124 -276.757764) (xy 183.105427 -276.716168)
			(xy 183.138062 -276.679331) (xy 183.176183 -276.648206) (xy 183.218804 -276.623599) (xy 183.26482 -276.606147)
			(xy 183.313039 -276.596303) (xy 183.362214 -276.594322) (xy 183.411069 -276.600254) (xy 183.45834 -276.613946)
			(xy 183.502802 -276.635044) (xy 183.543305 -276.663) (xy 183.578798 -276.697092) (xy 183.608363 -276.736436)
			(xy 183.631234 -276.780013) (xy 183.646818 -276.826694) (xy 183.654713 -276.875271) (xy 183.655208 -276.899878)
			(xy 183.994056 -276.899878) (xy 183.998016 -276.850824) (xy 184.009793 -276.80304) (xy 184.029084 -276.757764)
			(xy 184.055387 -276.716168) (xy 184.088022 -276.679331) (xy 184.126143 -276.648206) (xy 184.168764 -276.623599)
			(xy 184.21478 -276.606147) (xy 184.262999 -276.596303) (xy 184.312174 -276.594322) (xy 184.361029 -276.600254)
			(xy 184.4083 -276.613946) (xy 184.452762 -276.635044) (xy 184.493265 -276.663) (xy 184.528758 -276.697092)
			(xy 184.558323 -276.736436) (xy 184.581194 -276.780013) (xy 184.596778 -276.826694) (xy 184.604673 -276.875271)
			(xy 184.605168 -276.899878) (xy 184.94427 -276.899878) (xy 184.94823 -276.850824) (xy 184.960007 -276.80304)
			(xy 184.979298 -276.757764) (xy 185.005601 -276.716168) (xy 185.038236 -276.679331) (xy 185.076357 -276.648206)
			(xy 185.118978 -276.623599) (xy 185.164994 -276.606147) (xy 185.213213 -276.596303) (xy 185.262388 -276.594322)
			(xy 185.311243 -276.600254) (xy 185.358514 -276.613946) (xy 185.402976 -276.635044) (xy 185.443479 -276.663)
			(xy 185.478972 -276.697092) (xy 185.508537 -276.736436) (xy 185.531408 -276.780013) (xy 185.546992 -276.826694)
			(xy 185.554887 -276.875271) (xy 185.555382 -276.899878) (xy 185.89423 -276.899878) (xy 185.89819 -276.850824)
			(xy 185.909967 -276.80304) (xy 185.929258 -276.757764) (xy 185.955561 -276.716168) (xy 185.988196 -276.679331)
			(xy 186.026317 -276.648206) (xy 186.068938 -276.623599) (xy 186.114954 -276.606147) (xy 186.163173 -276.596303)
			(xy 186.212348 -276.594322) (xy 186.261203 -276.600254) (xy 186.308474 -276.613946) (xy 186.352936 -276.635044)
			(xy 186.393439 -276.663) (xy 186.428932 -276.697092) (xy 186.458497 -276.736436) (xy 186.481368 -276.780013)
			(xy 186.496952 -276.826694) (xy 186.504847 -276.875271) (xy 186.505342 -276.899878) (xy 186.84419 -276.899878)
			(xy 186.84815 -276.850824) (xy 186.859927 -276.80304) (xy 186.879218 -276.757764) (xy 186.905521 -276.716168)
			(xy 186.938156 -276.679331) (xy 186.976277 -276.648206) (xy 187.018898 -276.623599) (xy 187.064914 -276.606147)
			(xy 187.113133 -276.596303) (xy 187.162308 -276.594322) (xy 187.211163 -276.600254) (xy 187.258434 -276.613946)
			(xy 187.302896 -276.635044) (xy 187.343399 -276.663) (xy 187.378892 -276.697092) (xy 187.408457 -276.736436)
			(xy 187.431328 -276.780013) (xy 187.446912 -276.826694) (xy 187.454807 -276.875271) (xy 187.455302 -276.899878)
			(xy 187.79415 -276.899878) (xy 187.79811 -276.850824) (xy 187.809887 -276.80304) (xy 187.829178 -276.757764)
			(xy 187.855481 -276.716168) (xy 187.888116 -276.679331) (xy 187.926237 -276.648206) (xy 187.968858 -276.623599)
			(xy 188.014874 -276.606147) (xy 188.063093 -276.596303) (xy 188.112268 -276.594322) (xy 188.161123 -276.600254)
			(xy 188.208394 -276.613946) (xy 188.252856 -276.635044) (xy 188.293359 -276.663) (xy 188.328852 -276.697092)
			(xy 188.358417 -276.736436) (xy 188.381288 -276.780013) (xy 188.396872 -276.826694) (xy 188.404767 -276.875271)
			(xy 188.405262 -276.899878) (xy 188.74411 -276.899878) (xy 188.74807 -276.850824) (xy 188.759847 -276.80304)
			(xy 188.779138 -276.757764) (xy 188.805441 -276.716168) (xy 188.838076 -276.679331) (xy 188.876197 -276.648206)
			(xy 188.918818 -276.623599) (xy 188.964834 -276.606147) (xy 189.013053 -276.596303) (xy 189.062228 -276.594322)
			(xy 189.111083 -276.600254) (xy 189.158354 -276.613946) (xy 189.202816 -276.635044) (xy 189.243319 -276.663)
			(xy 189.278812 -276.697092) (xy 189.308377 -276.736436) (xy 189.331248 -276.780013) (xy 189.346832 -276.826694)
			(xy 189.354727 -276.875271) (xy 189.355222 -276.899878) (xy 189.693816 -276.899878) (xy 189.697776 -276.850824)
			(xy 189.709553 -276.80304) (xy 189.728844 -276.757764) (xy 189.755147 -276.716168) (xy 189.787782 -276.679331)
			(xy 189.825903 -276.648206) (xy 189.868524 -276.623599) (xy 189.91454 -276.606147) (xy 189.962759 -276.596303)
			(xy 190.011934 -276.594322) (xy 190.060789 -276.600254) (xy 190.10806 -276.613946) (xy 190.152522 -276.635044)
			(xy 190.193025 -276.663) (xy 190.228518 -276.697092) (xy 190.258083 -276.736436) (xy 190.280954 -276.780013)
			(xy 190.296538 -276.826694) (xy 190.304433 -276.875271) (xy 190.304928 -276.899878) (xy 190.64403 -276.899878)
			(xy 190.64799 -276.850824) (xy 190.659767 -276.80304) (xy 190.679058 -276.757764) (xy 190.705361 -276.716168)
			(xy 190.737996 -276.679331) (xy 190.776117 -276.648206) (xy 190.818738 -276.623599) (xy 190.864754 -276.606147)
			(xy 190.912973 -276.596303) (xy 190.962148 -276.594322) (xy 191.011003 -276.600254) (xy 191.058274 -276.613946)
			(xy 191.102736 -276.635044) (xy 191.143239 -276.663) (xy 191.178732 -276.697092) (xy 191.208297 -276.736436)
			(xy 191.231168 -276.780013) (xy 191.246752 -276.826694) (xy 191.254647 -276.875271) (xy 191.255142 -276.899878)
			(xy 191.59399 -276.899878) (xy 191.59795 -276.850824) (xy 191.609727 -276.80304) (xy 191.629018 -276.757764)
			(xy 191.655321 -276.716168) (xy 191.687956 -276.679331) (xy 191.726077 -276.648206) (xy 191.768698 -276.623599)
			(xy 191.814714 -276.606147) (xy 191.862933 -276.596303) (xy 191.912108 -276.594322) (xy 191.960963 -276.600254)
			(xy 192.008234 -276.613946) (xy 192.052696 -276.635044) (xy 192.093199 -276.663) (xy 192.128692 -276.697092)
			(xy 192.158257 -276.736436) (xy 192.181128 -276.780013) (xy 192.196712 -276.826694) (xy 192.204607 -276.875271)
			(xy 192.205102 -276.899878) (xy 192.54395 -276.899878) (xy 192.54791 -276.850824) (xy 192.559687 -276.80304)
			(xy 192.578978 -276.757764) (xy 192.605281 -276.716168) (xy 192.637916 -276.679331) (xy 192.676037 -276.648206)
			(xy 192.718658 -276.623599) (xy 192.764674 -276.606147) (xy 192.812893 -276.596303) (xy 192.862068 -276.594322)
			(xy 192.910923 -276.600254) (xy 192.958194 -276.613946) (xy 193.002656 -276.635044) (xy 193.043159 -276.663)
			(xy 193.078652 -276.697092) (xy 193.108217 -276.736436) (xy 193.131088 -276.780013) (xy 193.146672 -276.826694)
			(xy 193.154567 -276.875271) (xy 193.155062 -276.899878) (xy 193.49391 -276.899878) (xy 193.49787 -276.850824)
			(xy 193.509647 -276.80304) (xy 193.528938 -276.757764) (xy 193.555241 -276.716168) (xy 193.587876 -276.679331)
			(xy 193.625997 -276.648206) (xy 193.668618 -276.623599) (xy 193.714634 -276.606147) (xy 193.762853 -276.596303)
			(xy 193.812028 -276.594322) (xy 193.860883 -276.600254) (xy 193.908154 -276.613946) (xy 193.952616 -276.635044)
			(xy 193.993119 -276.663) (xy 194.028612 -276.697092) (xy 194.058177 -276.736436) (xy 194.081048 -276.780013)
			(xy 194.096632 -276.826694) (xy 194.104527 -276.875271) (xy 194.105022 -276.899878) (xy 194.44387 -276.899878)
			(xy 194.44783 -276.850824) (xy 194.459607 -276.80304) (xy 194.478898 -276.757764) (xy 194.505201 -276.716168)
			(xy 194.537836 -276.679331) (xy 194.575957 -276.648206) (xy 194.618578 -276.623599) (xy 194.664594 -276.606147)
			(xy 194.712813 -276.596303) (xy 194.761988 -276.594322) (xy 194.810843 -276.600254) (xy 194.858114 -276.613946)
			(xy 194.902576 -276.635044) (xy 194.943079 -276.663) (xy 194.978572 -276.697092) (xy 195.008137 -276.736436)
			(xy 195.031008 -276.780013) (xy 195.046592 -276.826694) (xy 195.054487 -276.875271) (xy 195.054982 -276.899878)
			(xy 195.39383 -276.899878) (xy 195.39779 -276.850824) (xy 195.409567 -276.80304) (xy 195.428858 -276.757764)
			(xy 195.455161 -276.716168) (xy 195.487796 -276.679331) (xy 195.525917 -276.648206) (xy 195.568538 -276.623599)
			(xy 195.614554 -276.606147) (xy 195.662773 -276.596303) (xy 195.711948 -276.594322) (xy 195.760803 -276.600254)
			(xy 195.808074 -276.613946) (xy 195.852536 -276.635044) (xy 195.893039 -276.663) (xy 195.928532 -276.697092)
			(xy 195.958097 -276.736436) (xy 195.980968 -276.780013) (xy 195.996552 -276.826694) (xy 196.004447 -276.875271)
			(xy 196.004942 -276.899878) (xy 196.344044 -276.899878) (xy 196.348004 -276.850824) (xy 196.359781 -276.80304)
			(xy 196.379072 -276.757764) (xy 196.405375 -276.716168) (xy 196.43801 -276.679331) (xy 196.476131 -276.648206)
			(xy 196.518752 -276.623599) (xy 196.564768 -276.606147) (xy 196.612987 -276.596303) (xy 196.662162 -276.594322)
			(xy 196.711017 -276.600254) (xy 196.758288 -276.613946) (xy 196.80275 -276.635044) (xy 196.843253 -276.663)
			(xy 196.878746 -276.697092) (xy 196.908311 -276.736436) (xy 196.931182 -276.780013) (xy 196.946766 -276.826694)
			(xy 196.954661 -276.875271) (xy 196.955156 -276.899878) (xy 196.954661 -276.924485) (xy 196.954482 -276.925586)
			(xy 197.273414 -276.925586) (xy 197.273414 -276.87417) (xy 197.281457 -276.823388) (xy 197.297345 -276.774489)
			(xy 197.320688 -276.728677) (xy 197.350909 -276.687081) (xy 197.387265 -276.650725) (xy 197.428861 -276.620504)
			(xy 197.474673 -276.597161) (xy 197.523572 -276.581273) (xy 197.574354 -276.57323) (xy 197.62577 -276.57323)
			(xy 197.676552 -276.581273) (xy 197.725451 -276.597161) (xy 197.771263 -276.620504) (xy 197.812859 -276.650725)
			(xy 197.849215 -276.687081) (xy 197.879436 -276.728677) (xy 197.902779 -276.774489) (xy 197.918667 -276.823388)
			(xy 197.92671 -276.87417) (xy 197.927214 -276.899878) (xy 197.92671 -276.925586) (xy 198.223374 -276.925586)
			(xy 198.223374 -276.87417) (xy 198.231417 -276.823388) (xy 198.247305 -276.774489) (xy 198.270648 -276.728677)
			(xy 198.300869 -276.687081) (xy 198.337225 -276.650725) (xy 198.378821 -276.620504) (xy 198.424633 -276.597161)
			(xy 198.473532 -276.581273) (xy 198.524314 -276.57323) (xy 198.57573 -276.57323) (xy 198.626512 -276.581273)
			(xy 198.675411 -276.597161) (xy 198.721223 -276.620504) (xy 198.762819 -276.650725) (xy 198.799175 -276.687081)
			(xy 198.829396 -276.728677) (xy 198.852739 -276.774489) (xy 198.868627 -276.823388) (xy 198.87667 -276.87417)
			(xy 198.877174 -276.899878) (xy 198.877169 -276.900132) (xy 199.194432 -276.900132) (xy 199.198392 -276.851078)
			(xy 199.210169 -276.803294) (xy 199.22946 -276.758018) (xy 199.255763 -276.716422) (xy 199.288398 -276.679585)
			(xy 199.326519 -276.64846) (xy 199.36914 -276.623853) (xy 199.415156 -276.606401) (xy 199.463375 -276.596557)
			(xy 199.51255 -276.594576) (xy 199.561405 -276.600508) (xy 199.608676 -276.6142) (xy 199.653138 -276.635298)
			(xy 199.693641 -276.663254) (xy 199.729134 -276.697346) (xy 199.758699 -276.73669) (xy 199.78157 -276.780267)
			(xy 199.797154 -276.826948) (xy 199.805049 -276.875525) (xy 199.805544 -276.900132) (xy 199.805049 -276.924739)
			(xy 199.797154 -276.973316) (xy 199.78157 -277.019997) (xy 199.758699 -277.063574) (xy 199.729134 -277.102918)
			(xy 199.698293 -277.132542) (xy 215.516966 -277.132542) (xy 215.521037 -277.07692) (xy 215.533163 -277.022483)
			(xy 215.553086 -276.970392) (xy 215.580382 -276.921757) (xy 215.614468 -276.877614) (xy 215.654617 -276.838905)
			(xy 215.699975 -276.806454) (xy 215.749575 -276.780953) (xy 215.802359 -276.762946) (xy 215.857202 -276.752816)
			(xy 215.912936 -276.750779) (xy 215.968373 -276.756879) (xy 216.02233 -276.770985) (xy 216.073659 -276.792797)
			(xy 216.121265 -276.821851) (xy 216.164133 -276.857526) (xy 216.20135 -276.899063) (xy 216.232123 -276.945576)
			(xy 216.255795 -276.996073) (xy 216.271863 -277.04948) (xy 216.279983 -277.104656) (xy 216.280492 -277.132542)
			(xy 216.279983 -277.160428) (xy 216.271863 -277.215604) (xy 216.255795 -277.269011) (xy 216.232123 -277.319508)
			(xy 216.20135 -277.366021) (xy 216.164133 -277.407558) (xy 216.121265 -277.443233) (xy 216.073659 -277.472287)
			(xy 216.02233 -277.494099) (xy 215.968373 -277.508205) (xy 215.912936 -277.514305) (xy 215.857202 -277.512268)
			(xy 215.802359 -277.502138) (xy 215.749575 -277.484131) (xy 215.699975 -277.45863) (xy 215.654617 -277.426179)
			(xy 215.614468 -277.38747) (xy 215.580382 -277.343327) (xy 215.553086 -277.294692) (xy 215.533163 -277.242601)
			(xy 215.521037 -277.188164) (xy 215.516966 -277.132542) (xy 199.698293 -277.132542) (xy 199.693641 -277.13701)
			(xy 199.653138 -277.164966) (xy 199.608676 -277.186064) (xy 199.561405 -277.199756) (xy 199.51255 -277.205688)
			(xy 199.463375 -277.203707) (xy 199.415156 -277.193863) (xy 199.36914 -277.176411) (xy 199.326519 -277.151804)
			(xy 199.288398 -277.120679) (xy 199.255763 -277.083842) (xy 199.22946 -277.042246) (xy 199.210169 -276.99697)
			(xy 199.198392 -276.949186) (xy 199.194432 -276.900132) (xy 198.877169 -276.900132) (xy 198.87667 -276.925586)
			(xy 198.868627 -276.976368) (xy 198.852739 -277.025267) (xy 198.829396 -277.071079) (xy 198.799175 -277.112675)
			(xy 198.762819 -277.149031) (xy 198.721223 -277.179252) (xy 198.675411 -277.202595) (xy 198.626512 -277.218483)
			(xy 198.57573 -277.226526) (xy 198.524314 -277.226526) (xy 198.473532 -277.218483) (xy 198.424633 -277.202595)
			(xy 198.378821 -277.179252) (xy 198.337225 -277.149031) (xy 198.300869 -277.112675) (xy 198.270648 -277.071079)
			(xy 198.247305 -277.025267) (xy 198.231417 -276.976368) (xy 198.223374 -276.925586) (xy 197.92671 -276.925586)
			(xy 197.918667 -276.976368) (xy 197.902779 -277.025267) (xy 197.879436 -277.071079) (xy 197.849215 -277.112675)
			(xy 197.812859 -277.149031) (xy 197.771263 -277.179252) (xy 197.725451 -277.202595) (xy 197.676552 -277.218483)
			(xy 197.62577 -277.226526) (xy 197.574354 -277.226526) (xy 197.523572 -277.218483) (xy 197.474673 -277.202595)
			(xy 197.428861 -277.179252) (xy 197.387265 -277.149031) (xy 197.350909 -277.112675) (xy 197.320688 -277.071079)
			(xy 197.297345 -277.025267) (xy 197.281457 -276.976368) (xy 197.273414 -276.925586) (xy 196.954482 -276.925586)
			(xy 196.946766 -276.973062) (xy 196.931182 -277.019743) (xy 196.908311 -277.06332) (xy 196.878746 -277.102664)
			(xy 196.843253 -277.136756) (xy 196.80275 -277.164712) (xy 196.758288 -277.18581) (xy 196.711017 -277.199502)
			(xy 196.662162 -277.205434) (xy 196.612987 -277.203453) (xy 196.564768 -277.193609) (xy 196.518752 -277.176157)
			(xy 196.476131 -277.15155) (xy 196.43801 -277.120425) (xy 196.405375 -277.083588) (xy 196.379072 -277.041992)
			(xy 196.359781 -276.996716) (xy 196.348004 -276.948932) (xy 196.344044 -276.899878) (xy 196.004942 -276.899878)
			(xy 196.004447 -276.924485) (xy 195.996552 -276.973062) (xy 195.980968 -277.019743) (xy 195.958097 -277.06332)
			(xy 195.928532 -277.102664) (xy 195.893039 -277.136756) (xy 195.852536 -277.164712) (xy 195.808074 -277.18581)
			(xy 195.760803 -277.199502) (xy 195.711948 -277.205434) (xy 195.662773 -277.203453) (xy 195.614554 -277.193609)
			(xy 195.568538 -277.176157) (xy 195.525917 -277.15155) (xy 195.487796 -277.120425) (xy 195.455161 -277.083588)
			(xy 195.428858 -277.041992) (xy 195.409567 -276.996716) (xy 195.39779 -276.948932) (xy 195.39383 -276.899878)
			(xy 195.054982 -276.899878) (xy 195.054487 -276.924485) (xy 195.046592 -276.973062) (xy 195.031008 -277.019743)
			(xy 195.008137 -277.06332) (xy 194.978572 -277.102664) (xy 194.943079 -277.136756) (xy 194.902576 -277.164712)
			(xy 194.858114 -277.18581) (xy 194.810843 -277.199502) (xy 194.761988 -277.205434) (xy 194.712813 -277.203453)
			(xy 194.664594 -277.193609) (xy 194.618578 -277.176157) (xy 194.575957 -277.15155) (xy 194.537836 -277.120425)
			(xy 194.505201 -277.083588) (xy 194.478898 -277.041992) (xy 194.459607 -276.996716) (xy 194.44783 -276.948932)
			(xy 194.44387 -276.899878) (xy 194.105022 -276.899878) (xy 194.104527 -276.924485) (xy 194.096632 -276.973062)
			(xy 194.081048 -277.019743) (xy 194.058177 -277.06332) (xy 194.028612 -277.102664) (xy 193.993119 -277.136756)
			(xy 193.952616 -277.164712) (xy 193.908154 -277.18581) (xy 193.860883 -277.199502) (xy 193.812028 -277.205434)
			(xy 193.762853 -277.203453) (xy 193.714634 -277.193609) (xy 193.668618 -277.176157) (xy 193.625997 -277.15155)
			(xy 193.587876 -277.120425) (xy 193.555241 -277.083588) (xy 193.528938 -277.041992) (xy 193.509647 -276.996716)
			(xy 193.49787 -276.948932) (xy 193.49391 -276.899878) (xy 193.155062 -276.899878) (xy 193.154567 -276.924485)
			(xy 193.146672 -276.973062) (xy 193.131088 -277.019743) (xy 193.108217 -277.06332) (xy 193.078652 -277.102664)
			(xy 193.043159 -277.136756) (xy 193.002656 -277.164712) (xy 192.958194 -277.18581) (xy 192.910923 -277.199502)
			(xy 192.862068 -277.205434) (xy 192.812893 -277.203453) (xy 192.764674 -277.193609) (xy 192.718658 -277.176157)
			(xy 192.676037 -277.15155) (xy 192.637916 -277.120425) (xy 192.605281 -277.083588) (xy 192.578978 -277.041992)
			(xy 192.559687 -276.996716) (xy 192.54791 -276.948932) (xy 192.54395 -276.899878) (xy 192.205102 -276.899878)
			(xy 192.204607 -276.924485) (xy 192.196712 -276.973062) (xy 192.181128 -277.019743) (xy 192.158257 -277.06332)
			(xy 192.128692 -277.102664) (xy 192.093199 -277.136756) (xy 192.052696 -277.164712) (xy 192.008234 -277.18581)
			(xy 191.960963 -277.199502) (xy 191.912108 -277.205434) (xy 191.862933 -277.203453) (xy 191.814714 -277.193609)
			(xy 191.768698 -277.176157) (xy 191.726077 -277.15155) (xy 191.687956 -277.120425) (xy 191.655321 -277.083588)
			(xy 191.629018 -277.041992) (xy 191.609727 -276.996716) (xy 191.59795 -276.948932) (xy 191.59399 -276.899878)
			(xy 191.255142 -276.899878) (xy 191.254647 -276.924485) (xy 191.246752 -276.973062) (xy 191.231168 -277.019743)
			(xy 191.208297 -277.06332) (xy 191.178732 -277.102664) (xy 191.143239 -277.136756) (xy 191.102736 -277.164712)
			(xy 191.058274 -277.18581) (xy 191.011003 -277.199502) (xy 190.962148 -277.205434) (xy 190.912973 -277.203453)
			(xy 190.864754 -277.193609) (xy 190.818738 -277.176157) (xy 190.776117 -277.15155) (xy 190.737996 -277.120425)
			(xy 190.705361 -277.083588) (xy 190.679058 -277.041992) (xy 190.659767 -276.996716) (xy 190.64799 -276.948932)
			(xy 190.64403 -276.899878) (xy 190.304928 -276.899878) (xy 190.304433 -276.924485) (xy 190.296538 -276.973062)
			(xy 190.280954 -277.019743) (xy 190.258083 -277.06332) (xy 190.228518 -277.102664) (xy 190.193025 -277.136756)
			(xy 190.152522 -277.164712) (xy 190.10806 -277.18581) (xy 190.060789 -277.199502) (xy 190.011934 -277.205434)
			(xy 189.962759 -277.203453) (xy 189.91454 -277.193609) (xy 189.868524 -277.176157) (xy 189.825903 -277.15155)
			(xy 189.787782 -277.120425) (xy 189.755147 -277.083588) (xy 189.728844 -277.041992) (xy 189.709553 -276.996716)
			(xy 189.697776 -276.948932) (xy 189.693816 -276.899878) (xy 189.355222 -276.899878) (xy 189.354727 -276.924485)
			(xy 189.346832 -276.973062) (xy 189.331248 -277.019743) (xy 189.308377 -277.06332) (xy 189.278812 -277.102664)
			(xy 189.243319 -277.136756) (xy 189.202816 -277.164712) (xy 189.158354 -277.18581) (xy 189.111083 -277.199502)
			(xy 189.062228 -277.205434) (xy 189.013053 -277.203453) (xy 188.964834 -277.193609) (xy 188.918818 -277.176157)
			(xy 188.876197 -277.15155) (xy 188.838076 -277.120425) (xy 188.805441 -277.083588) (xy 188.779138 -277.041992)
			(xy 188.759847 -276.996716) (xy 188.74807 -276.948932) (xy 188.74411 -276.899878) (xy 188.405262 -276.899878)
			(xy 188.404767 -276.924485) (xy 188.396872 -276.973062) (xy 188.381288 -277.019743) (xy 188.358417 -277.06332)
			(xy 188.328852 -277.102664) (xy 188.293359 -277.136756) (xy 188.252856 -277.164712) (xy 188.208394 -277.18581)
			(xy 188.161123 -277.199502) (xy 188.112268 -277.205434) (xy 188.063093 -277.203453) (xy 188.014874 -277.193609)
			(xy 187.968858 -277.176157) (xy 187.926237 -277.15155) (xy 187.888116 -277.120425) (xy 187.855481 -277.083588)
			(xy 187.829178 -277.041992) (xy 187.809887 -276.996716) (xy 187.79811 -276.948932) (xy 187.79415 -276.899878)
			(xy 187.455302 -276.899878) (xy 187.454807 -276.924485) (xy 187.446912 -276.973062) (xy 187.431328 -277.019743)
			(xy 187.408457 -277.06332) (xy 187.378892 -277.102664) (xy 187.343399 -277.136756) (xy 187.302896 -277.164712)
			(xy 187.258434 -277.18581) (xy 187.211163 -277.199502) (xy 187.162308 -277.205434) (xy 187.113133 -277.203453)
			(xy 187.064914 -277.193609) (xy 187.018898 -277.176157) (xy 186.976277 -277.15155) (xy 186.938156 -277.120425)
			(xy 186.905521 -277.083588) (xy 186.879218 -277.041992) (xy 186.859927 -276.996716) (xy 186.84815 -276.948932)
			(xy 186.84419 -276.899878) (xy 186.505342 -276.899878) (xy 186.504847 -276.924485) (xy 186.496952 -276.973062)
			(xy 186.481368 -277.019743) (xy 186.458497 -277.06332) (xy 186.428932 -277.102664) (xy 186.393439 -277.136756)
			(xy 186.352936 -277.164712) (xy 186.308474 -277.18581) (xy 186.261203 -277.199502) (xy 186.212348 -277.205434)
			(xy 186.163173 -277.203453) (xy 186.114954 -277.193609) (xy 186.068938 -277.176157) (xy 186.026317 -277.15155)
			(xy 185.988196 -277.120425) (xy 185.955561 -277.083588) (xy 185.929258 -277.041992) (xy 185.909967 -276.996716)
			(xy 185.89819 -276.948932) (xy 185.89423 -276.899878) (xy 185.555382 -276.899878) (xy 185.554887 -276.924485)
			(xy 185.546992 -276.973062) (xy 185.531408 -277.019743) (xy 185.508537 -277.06332) (xy 185.478972 -277.102664)
			(xy 185.443479 -277.136756) (xy 185.402976 -277.164712) (xy 185.358514 -277.18581) (xy 185.311243 -277.199502)
			(xy 185.262388 -277.205434) (xy 185.213213 -277.203453) (xy 185.164994 -277.193609) (xy 185.118978 -277.176157)
			(xy 185.076357 -277.15155) (xy 185.038236 -277.120425) (xy 185.005601 -277.083588) (xy 184.979298 -277.041992)
			(xy 184.960007 -276.996716) (xy 184.94823 -276.948932) (xy 184.94427 -276.899878) (xy 184.605168 -276.899878)
			(xy 184.604673 -276.924485) (xy 184.596778 -276.973062) (xy 184.581194 -277.019743) (xy 184.558323 -277.06332)
			(xy 184.528758 -277.102664) (xy 184.493265 -277.136756) (xy 184.452762 -277.164712) (xy 184.4083 -277.18581)
			(xy 184.361029 -277.199502) (xy 184.312174 -277.205434) (xy 184.262999 -277.203453) (xy 184.21478 -277.193609)
			(xy 184.168764 -277.176157) (xy 184.126143 -277.15155) (xy 184.088022 -277.120425) (xy 184.055387 -277.083588)
			(xy 184.029084 -277.041992) (xy 184.009793 -276.996716) (xy 183.998016 -276.948932) (xy 183.994056 -276.899878)
			(xy 183.655208 -276.899878) (xy 183.654713 -276.924485) (xy 183.646818 -276.973062) (xy 183.631234 -277.019743)
			(xy 183.608363 -277.06332) (xy 183.578798 -277.102664) (xy 183.543305 -277.136756) (xy 183.502802 -277.164712)
			(xy 183.45834 -277.18581) (xy 183.411069 -277.199502) (xy 183.362214 -277.205434) (xy 183.313039 -277.203453)
			(xy 183.26482 -277.193609) (xy 183.218804 -277.176157) (xy 183.176183 -277.15155) (xy 183.138062 -277.120425)
			(xy 183.105427 -277.083588) (xy 183.079124 -277.041992) (xy 183.059833 -276.996716) (xy 183.048056 -276.948932)
			(xy 183.044096 -276.899878) (xy 182.705248 -276.899878) (xy 182.704753 -276.924485) (xy 182.696858 -276.973062)
			(xy 182.681274 -277.019743) (xy 182.658403 -277.06332) (xy 182.628838 -277.102664) (xy 182.593345 -277.136756)
			(xy 182.552842 -277.164712) (xy 182.50838 -277.18581) (xy 182.461109 -277.199502) (xy 182.412254 -277.205434)
			(xy 182.363079 -277.203453) (xy 182.31486 -277.193609) (xy 182.268844 -277.176157) (xy 182.226223 -277.15155)
			(xy 182.188102 -277.120425) (xy 182.155467 -277.083588) (xy 182.129164 -277.041992) (xy 182.109873 -276.996716)
			(xy 182.098096 -276.948932) (xy 182.094136 -276.899878) (xy 181.755288 -276.899878) (xy 181.754793 -276.924485)
			(xy 181.746898 -276.973062) (xy 181.731314 -277.019743) (xy 181.708443 -277.06332) (xy 181.678878 -277.102664)
			(xy 181.643385 -277.136756) (xy 181.602882 -277.164712) (xy 181.55842 -277.18581) (xy 181.511149 -277.199502)
			(xy 181.462294 -277.205434) (xy 181.413119 -277.203453) (xy 181.3649 -277.193609) (xy 181.318884 -277.176157)
			(xy 181.276263 -277.15155) (xy 181.238142 -277.120425) (xy 181.205507 -277.083588) (xy 181.179204 -277.041992)
			(xy 181.159913 -276.996716) (xy 181.148136 -276.948932) (xy 181.144176 -276.899878) (xy 180.805328 -276.899878)
			(xy 180.804833 -276.924485) (xy 180.796938 -276.973062) (xy 180.781354 -277.019743) (xy 180.758483 -277.06332)
			(xy 180.728918 -277.102664) (xy 180.693425 -277.136756) (xy 180.652922 -277.164712) (xy 180.60846 -277.18581)
			(xy 180.561189 -277.199502) (xy 180.512334 -277.205434) (xy 180.463159 -277.203453) (xy 180.41494 -277.193609)
			(xy 180.368924 -277.176157) (xy 180.326303 -277.15155) (xy 180.288182 -277.120425) (xy 180.255547 -277.083588)
			(xy 180.229244 -277.041992) (xy 180.209953 -276.996716) (xy 180.198176 -276.948932) (xy 180.194216 -276.899878)
			(xy 179.855368 -276.899878) (xy 179.854873 -276.924485) (xy 179.846978 -276.973062) (xy 179.831394 -277.019743)
			(xy 179.808523 -277.06332) (xy 179.778958 -277.102664) (xy 179.743465 -277.136756) (xy 179.702962 -277.164712)
			(xy 179.6585 -277.18581) (xy 179.611229 -277.199502) (xy 179.562374 -277.205434) (xy 179.513199 -277.203453)
			(xy 179.46498 -277.193609) (xy 179.418964 -277.176157) (xy 179.376343 -277.15155) (xy 179.338222 -277.120425)
			(xy 179.305587 -277.083588) (xy 179.279284 -277.041992) (xy 179.259993 -276.996716) (xy 179.248216 -276.948932)
			(xy 179.244256 -276.899878) (xy 178.905154 -276.899878) (xy 178.904659 -276.924485) (xy 178.896764 -276.973062)
			(xy 178.88118 -277.019743) (xy 178.858309 -277.06332) (xy 178.828744 -277.102664) (xy 178.793251 -277.136756)
			(xy 178.752748 -277.164712) (xy 178.708286 -277.18581) (xy 178.661015 -277.199502) (xy 178.61216 -277.205434)
			(xy 178.562985 -277.203453) (xy 178.514766 -277.193609) (xy 178.46875 -277.176157) (xy 178.426129 -277.15155)
			(xy 178.388008 -277.120425) (xy 178.355373 -277.083588) (xy 178.32907 -277.041992) (xy 178.309779 -276.996716)
			(xy 178.298002 -276.948932) (xy 178.294042 -276.899878) (xy 177.955194 -276.899878) (xy 177.954699 -276.924485)
			(xy 177.946804 -276.973062) (xy 177.93122 -277.019743) (xy 177.908349 -277.06332) (xy 177.878784 -277.102664)
			(xy 177.843291 -277.136756) (xy 177.802788 -277.164712) (xy 177.758326 -277.18581) (xy 177.711055 -277.199502)
			(xy 177.6622 -277.205434) (xy 177.613025 -277.203453) (xy 177.564806 -277.193609) (xy 177.51879 -277.176157)
			(xy 177.476169 -277.15155) (xy 177.438048 -277.120425) (xy 177.405413 -277.083588) (xy 177.37911 -277.041992)
			(xy 177.359819 -276.996716) (xy 177.348042 -276.948932) (xy 177.344082 -276.899878) (xy 177.005234 -276.899878)
			(xy 177.004739 -276.924485) (xy 176.996844 -276.973062) (xy 176.98126 -277.019743) (xy 176.958389 -277.06332)
			(xy 176.928824 -277.102664) (xy 176.893331 -277.136756) (xy 176.852828 -277.164712) (xy 176.808366 -277.18581)
			(xy 176.761095 -277.199502) (xy 176.71224 -277.205434) (xy 176.663065 -277.203453) (xy 176.614846 -277.193609)
			(xy 176.56883 -277.176157) (xy 176.526209 -277.15155) (xy 176.488088 -277.120425) (xy 176.455453 -277.083588)
			(xy 176.42915 -277.041992) (xy 176.409859 -276.996716) (xy 176.398082 -276.948932) (xy 176.394122 -276.899878)
			(xy 176.055274 -276.899878) (xy 176.054779 -276.924485) (xy 176.046884 -276.973062) (xy 176.0313 -277.019743)
			(xy 176.008429 -277.06332) (xy 175.978864 -277.102664) (xy 175.943371 -277.136756) (xy 175.902868 -277.164712)
			(xy 175.858406 -277.18581) (xy 175.811135 -277.199502) (xy 175.76228 -277.205434) (xy 175.713105 -277.203453)
			(xy 175.664886 -277.193609) (xy 175.61887 -277.176157) (xy 175.576249 -277.15155) (xy 175.538128 -277.120425)
			(xy 175.505493 -277.083588) (xy 175.47919 -277.041992) (xy 175.459899 -276.996716) (xy 175.448122 -276.948932)
			(xy 175.444162 -276.899878) (xy 175.105314 -276.899878) (xy 175.104819 -276.924485) (xy 175.096924 -276.973062)
			(xy 175.08134 -277.019743) (xy 175.058469 -277.06332) (xy 175.028904 -277.102664) (xy 174.993411 -277.136756)
			(xy 174.952908 -277.164712) (xy 174.908446 -277.18581) (xy 174.861175 -277.199502) (xy 174.81232 -277.205434)
			(xy 174.763145 -277.203453) (xy 174.714926 -277.193609) (xy 174.66891 -277.176157) (xy 174.626289 -277.15155)
			(xy 174.588168 -277.120425) (xy 174.555533 -277.083588) (xy 174.52923 -277.041992) (xy 174.509939 -276.996716)
			(xy 174.498162 -276.948932) (xy 174.494202 -276.899878) (xy 174.155354 -276.899878) (xy 174.154859 -276.924485)
			(xy 174.146964 -276.973062) (xy 174.13138 -277.019743) (xy 174.108509 -277.06332) (xy 174.078944 -277.102664)
			(xy 174.043451 -277.136756) (xy 174.002948 -277.164712) (xy 173.958486 -277.18581) (xy 173.911215 -277.199502)
			(xy 173.86236 -277.205434) (xy 173.813185 -277.203453) (xy 173.764966 -277.193609) (xy 173.71895 -277.176157)
			(xy 173.676329 -277.15155) (xy 173.638208 -277.120425) (xy 173.605573 -277.083588) (xy 173.57927 -277.041992)
			(xy 173.559979 -276.996716) (xy 173.548202 -276.948932) (xy 173.544242 -276.899878) (xy 173.205394 -276.899878)
			(xy 173.204899 -276.924485) (xy 173.197004 -276.973062) (xy 173.18142 -277.019743) (xy 173.158549 -277.06332)
			(xy 173.128984 -277.102664) (xy 173.093491 -277.136756) (xy 173.052988 -277.164712) (xy 173.008526 -277.18581)
			(xy 172.961255 -277.199502) (xy 172.9124 -277.205434) (xy 172.863225 -277.203453) (xy 172.815006 -277.193609)
			(xy 172.76899 -277.176157) (xy 172.726369 -277.15155) (xy 172.688248 -277.120425) (xy 172.655613 -277.083588)
			(xy 172.62931 -277.041992) (xy 172.610019 -276.996716) (xy 172.598242 -276.948932) (xy 172.594282 -276.899878)
			(xy 172.25518 -276.899878) (xy 172.254685 -276.924485) (xy 172.24679 -276.973062) (xy 172.231206 -277.019743)
			(xy 172.208335 -277.06332) (xy 172.17877 -277.102664) (xy 172.143277 -277.136756) (xy 172.102774 -277.164712)
			(xy 172.058312 -277.18581) (xy 172.011041 -277.199502) (xy 171.962186 -277.205434) (xy 171.913011 -277.203453)
			(xy 171.864792 -277.193609) (xy 171.818776 -277.176157) (xy 171.776155 -277.15155) (xy 171.738034 -277.120425)
			(xy 171.705399 -277.083588) (xy 171.679096 -277.041992) (xy 171.659805 -276.996716) (xy 171.648028 -276.948932)
			(xy 171.644068 -276.899878) (xy 171.30522 -276.899878) (xy 171.304725 -276.924485) (xy 171.29683 -276.973062)
			(xy 171.281246 -277.019743) (xy 171.258375 -277.06332) (xy 171.22881 -277.102664) (xy 171.193317 -277.136756)
			(xy 171.152814 -277.164712) (xy 171.108352 -277.18581) (xy 171.061081 -277.199502) (xy 171.012226 -277.205434)
			(xy 170.963051 -277.203453) (xy 170.914832 -277.193609) (xy 170.868816 -277.176157) (xy 170.826195 -277.15155)
			(xy 170.788074 -277.120425) (xy 170.755439 -277.083588) (xy 170.729136 -277.041992) (xy 170.709845 -276.996716)
			(xy 170.698068 -276.948932) (xy 170.694108 -276.899878) (xy 170.35526 -276.899878) (xy 170.354765 -276.924485)
			(xy 170.34687 -276.973062) (xy 170.331286 -277.019743) (xy 170.308415 -277.06332) (xy 170.27885 -277.102664)
			(xy 170.243357 -277.136756) (xy 170.202854 -277.164712) (xy 170.158392 -277.18581) (xy 170.111121 -277.199502)
			(xy 170.062266 -277.205434) (xy 170.013091 -277.203453) (xy 169.964872 -277.193609) (xy 169.918856 -277.176157)
			(xy 169.876235 -277.15155) (xy 169.838114 -277.120425) (xy 169.805479 -277.083588) (xy 169.779176 -277.041992)
			(xy 169.759885 -276.996716) (xy 169.748108 -276.948932) (xy 169.744148 -276.899878) (xy 169.4053 -276.899878)
			(xy 169.404805 -276.924485) (xy 169.39691 -276.973062) (xy 169.381326 -277.019743) (xy 169.358455 -277.06332)
			(xy 169.32889 -277.102664) (xy 169.293397 -277.136756) (xy 169.252894 -277.164712) (xy 169.208432 -277.18581)
			(xy 169.161161 -277.199502) (xy 169.112306 -277.205434) (xy 169.063131 -277.203453) (xy 169.014912 -277.193609)
			(xy 168.968896 -277.176157) (xy 168.926275 -277.15155) (xy 168.888154 -277.120425) (xy 168.855519 -277.083588)
			(xy 168.829216 -277.041992) (xy 168.809925 -276.996716) (xy 168.798148 -276.948932) (xy 168.794188 -276.899878)
			(xy 168.45534 -276.899878) (xy 168.454845 -276.924485) (xy 168.44695 -276.973062) (xy 168.431366 -277.019743)
			(xy 168.408495 -277.06332) (xy 168.37893 -277.102664) (xy 168.343437 -277.136756) (xy 168.302934 -277.164712)
			(xy 168.258472 -277.18581) (xy 168.211201 -277.199502) (xy 168.162346 -277.205434) (xy 168.113171 -277.203453)
			(xy 168.064952 -277.193609) (xy 168.018936 -277.176157) (xy 167.976315 -277.15155) (xy 167.938194 -277.120425)
			(xy 167.905559 -277.083588) (xy 167.879256 -277.041992) (xy 167.859965 -276.996716) (xy 167.848188 -276.948932)
			(xy 167.844228 -276.899878) (xy 167.50538 -276.899878) (xy 167.504885 -276.924485) (xy 167.49699 -276.973062)
			(xy 167.481406 -277.019743) (xy 167.458535 -277.06332) (xy 167.42897 -277.102664) (xy 167.393477 -277.136756)
			(xy 167.352974 -277.164712) (xy 167.308512 -277.18581) (xy 167.261241 -277.199502) (xy 167.212386 -277.205434)
			(xy 167.163211 -277.203453) (xy 167.114992 -277.193609) (xy 167.068976 -277.176157) (xy 167.026355 -277.15155)
			(xy 166.988234 -277.120425) (xy 166.955599 -277.083588) (xy 166.929296 -277.041992) (xy 166.910005 -276.996716)
			(xy 166.898228 -276.948932) (xy 166.894268 -276.899878) (xy 166.555166 -276.899878) (xy 166.554671 -276.924485)
			(xy 166.546776 -276.973062) (xy 166.531192 -277.019743) (xy 166.508321 -277.06332) (xy 166.478756 -277.102664)
			(xy 166.443263 -277.136756) (xy 166.40276 -277.164712) (xy 166.358298 -277.18581) (xy 166.311027 -277.199502)
			(xy 166.262172 -277.205434) (xy 166.212997 -277.203453) (xy 166.164778 -277.193609) (xy 166.118762 -277.176157)
			(xy 166.076141 -277.15155) (xy 166.03802 -277.120425) (xy 166.005385 -277.083588) (xy 165.979082 -277.041992)
			(xy 165.959791 -276.996716) (xy 165.948014 -276.948932) (xy 165.944054 -276.899878) (xy 165.60482 -276.899878)
			(xy 165.604821 -276.923953) (xy 165.597277 -276.97147) (xy 165.582375 -277.017216) (xy 165.560484 -277.06006)
			(xy 165.532145 -277.098941) (xy 165.498061 -277.132897) (xy 165.459073 -277.161088) (xy 165.416147 -277.182817)
			(xy 165.370344 -277.197545) (xy 165.346634 -277.20163) (xy 165.327838 -277.204424) (xy 165.303708 -277.232872)
			(xy 165.303708 -277.516844) (xy 165.327838 -277.545292) (xy 165.346634 -277.548086) (xy 165.370333 -277.552213)
			(xy 165.416126 -277.566939) (xy 165.459044 -277.588664) (xy 165.498024 -277.61685) (xy 165.532102 -277.6508)
			(xy 165.560435 -277.689673) (xy 165.582321 -277.732509) (xy 165.59722 -277.778246) (xy 165.604762 -277.825754)
			(xy 165.604761 -277.873857) (xy 165.604493 -277.875546) (xy 165.92321 -277.875546) (xy 165.92321 -277.82413)
			(xy 165.931253 -277.773348) (xy 165.947141 -277.724449) (xy 165.970484 -277.678637) (xy 166.000705 -277.637041)
			(xy 166.037061 -277.600685) (xy 166.078657 -277.570464) (xy 166.124469 -277.547121) (xy 166.173368 -277.531233)
			(xy 166.22415 -277.52319) (xy 166.275566 -277.52319) (xy 166.326348 -277.531233) (xy 166.375247 -277.547121)
			(xy 166.421059 -277.570464) (xy 166.462655 -277.600685) (xy 166.499011 -277.637041) (xy 166.529232 -277.678637)
			(xy 166.552575 -277.724449) (xy 166.568463 -277.773348) (xy 166.576506 -277.82413) (xy 166.57701 -277.849838)
			(xy 166.894268 -277.849838) (xy 166.898228 -277.800784) (xy 166.910005 -277.753) (xy 166.929296 -277.707724)
			(xy 166.955599 -277.666128) (xy 166.988234 -277.629291) (xy 167.026355 -277.598166) (xy 167.068976 -277.573559)
			(xy 167.114992 -277.556107) (xy 167.163211 -277.546263) (xy 167.212386 -277.544282) (xy 167.261241 -277.550214)
			(xy 167.308512 -277.563906) (xy 167.352974 -277.585004) (xy 167.393477 -277.61296) (xy 167.42897 -277.647052)
			(xy 167.458535 -277.686396) (xy 167.481406 -277.729973) (xy 167.49699 -277.776654) (xy 167.504885 -277.825231)
			(xy 167.50538 -277.849838) (xy 167.504885 -277.874445) (xy 167.504706 -277.875546) (xy 167.823384 -277.875546)
			(xy 167.823384 -277.82413) (xy 167.831427 -277.773348) (xy 167.847315 -277.724449) (xy 167.870658 -277.678637)
			(xy 167.900879 -277.637041) (xy 167.937235 -277.600685) (xy 167.978831 -277.570464) (xy 168.024643 -277.547121)
			(xy 168.073542 -277.531233) (xy 168.124324 -277.52319) (xy 168.17574 -277.52319) (xy 168.226522 -277.531233)
			(xy 168.275421 -277.547121) (xy 168.321233 -277.570464) (xy 168.362829 -277.600685) (xy 168.399185 -277.637041)
			(xy 168.429406 -277.678637) (xy 168.452749 -277.724449) (xy 168.468637 -277.773348) (xy 168.47668 -277.82413)
			(xy 168.477184 -277.849838) (xy 168.794188 -277.849838) (xy 168.798148 -277.800784) (xy 168.809925 -277.753)
			(xy 168.829216 -277.707724) (xy 168.855519 -277.666128) (xy 168.888154 -277.629291) (xy 168.926275 -277.598166)
			(xy 168.968896 -277.573559) (xy 169.014912 -277.556107) (xy 169.063131 -277.546263) (xy 169.112306 -277.544282)
			(xy 169.161161 -277.550214) (xy 169.208432 -277.563906) (xy 169.252894 -277.585004) (xy 169.293397 -277.61296)
			(xy 169.32889 -277.647052) (xy 169.358455 -277.686396) (xy 169.381326 -277.729973) (xy 169.39691 -277.776654)
			(xy 169.404805 -277.825231) (xy 169.4053 -277.849838) (xy 169.404805 -277.874445) (xy 169.404626 -277.875546)
			(xy 169.723304 -277.875546) (xy 169.723304 -277.82413) (xy 169.731347 -277.773348) (xy 169.747235 -277.724449)
			(xy 169.770578 -277.678637) (xy 169.800799 -277.637041) (xy 169.837155 -277.600685) (xy 169.878751 -277.570464)
			(xy 169.924563 -277.547121) (xy 169.973462 -277.531233) (xy 170.024244 -277.52319) (xy 170.07566 -277.52319)
			(xy 170.126442 -277.531233) (xy 170.175341 -277.547121) (xy 170.221153 -277.570464) (xy 170.262749 -277.600685)
			(xy 170.299105 -277.637041) (xy 170.329326 -277.678637) (xy 170.352669 -277.724449) (xy 170.368557 -277.773348)
			(xy 170.3766 -277.82413) (xy 170.377104 -277.849838) (xy 170.694108 -277.849838) (xy 170.698068 -277.800784)
			(xy 170.709845 -277.753) (xy 170.729136 -277.707724) (xy 170.755439 -277.666128) (xy 170.788074 -277.629291)
			(xy 170.826195 -277.598166) (xy 170.868816 -277.573559) (xy 170.914832 -277.556107) (xy 170.963051 -277.546263)
			(xy 171.012226 -277.544282) (xy 171.061081 -277.550214) (xy 171.108352 -277.563906) (xy 171.152814 -277.585004)
			(xy 171.193317 -277.61296) (xy 171.22881 -277.647052) (xy 171.258375 -277.686396) (xy 171.281246 -277.729973)
			(xy 171.29683 -277.776654) (xy 171.304725 -277.825231) (xy 171.30522 -277.849838) (xy 171.304725 -277.874445)
			(xy 171.304546 -277.875546) (xy 171.623224 -277.875546) (xy 171.623224 -277.82413) (xy 171.631267 -277.773348)
			(xy 171.647155 -277.724449) (xy 171.670498 -277.678637) (xy 171.700719 -277.637041) (xy 171.737075 -277.600685)
			(xy 171.778671 -277.570464) (xy 171.824483 -277.547121) (xy 171.873382 -277.531233) (xy 171.924164 -277.52319)
			(xy 171.97558 -277.52319) (xy 172.026362 -277.531233) (xy 172.075261 -277.547121) (xy 172.121073 -277.570464)
			(xy 172.162669 -277.600685) (xy 172.199025 -277.637041) (xy 172.229246 -277.678637) (xy 172.252589 -277.724449)
			(xy 172.268477 -277.773348) (xy 172.27652 -277.82413) (xy 172.277024 -277.849838) (xy 172.594282 -277.849838)
			(xy 172.598242 -277.800784) (xy 172.610019 -277.753) (xy 172.62931 -277.707724) (xy 172.655613 -277.666128)
			(xy 172.688248 -277.629291) (xy 172.726369 -277.598166) (xy 172.76899 -277.573559) (xy 172.815006 -277.556107)
			(xy 172.863225 -277.546263) (xy 172.9124 -277.544282) (xy 172.961255 -277.550214) (xy 173.008526 -277.563906)
			(xy 173.052988 -277.585004) (xy 173.093491 -277.61296) (xy 173.128984 -277.647052) (xy 173.158549 -277.686396)
			(xy 173.18142 -277.729973) (xy 173.197004 -277.776654) (xy 173.204899 -277.825231) (xy 173.205394 -277.849838)
			(xy 173.204899 -277.874445) (xy 173.20472 -277.875546) (xy 173.523398 -277.875546) (xy 173.523398 -277.82413)
			(xy 173.531441 -277.773348) (xy 173.547329 -277.724449) (xy 173.570672 -277.678637) (xy 173.600893 -277.637041)
			(xy 173.637249 -277.600685) (xy 173.678845 -277.570464) (xy 173.724657 -277.547121) (xy 173.773556 -277.531233)
			(xy 173.824338 -277.52319) (xy 173.875754 -277.52319) (xy 173.926536 -277.531233) (xy 173.975435 -277.547121)
			(xy 174.021247 -277.570464) (xy 174.062843 -277.600685) (xy 174.099199 -277.637041) (xy 174.12942 -277.678637)
			(xy 174.152763 -277.724449) (xy 174.168651 -277.773348) (xy 174.176694 -277.82413) (xy 174.177198 -277.849838)
			(xy 174.494202 -277.849838) (xy 174.498162 -277.800784) (xy 174.509939 -277.753) (xy 174.52923 -277.707724)
			(xy 174.555533 -277.666128) (xy 174.588168 -277.629291) (xy 174.626289 -277.598166) (xy 174.66891 -277.573559)
			(xy 174.714926 -277.556107) (xy 174.763145 -277.546263) (xy 174.81232 -277.544282) (xy 174.861175 -277.550214)
			(xy 174.908446 -277.563906) (xy 174.952908 -277.585004) (xy 174.993411 -277.61296) (xy 175.028904 -277.647052)
			(xy 175.058469 -277.686396) (xy 175.08134 -277.729973) (xy 175.096924 -277.776654) (xy 175.104819 -277.825231)
			(xy 175.105314 -277.849838) (xy 175.104819 -277.874445) (xy 175.10464 -277.875546) (xy 175.423064 -277.875546)
			(xy 175.423064 -277.82413) (xy 175.431107 -277.773348) (xy 175.446995 -277.724449) (xy 175.470338 -277.678637)
			(xy 175.500559 -277.637041) (xy 175.536915 -277.600685) (xy 175.578511 -277.570464) (xy 175.624323 -277.547121)
			(xy 175.673222 -277.531233) (xy 175.724004 -277.52319) (xy 175.77542 -277.52319) (xy 175.826202 -277.531233)
			(xy 175.875101 -277.547121) (xy 175.920913 -277.570464) (xy 175.962509 -277.600685) (xy 175.998865 -277.637041)
			(xy 176.029086 -277.678637) (xy 176.052429 -277.724449) (xy 176.068317 -277.773348) (xy 176.07636 -277.82413)
			(xy 176.076864 -277.849838) (xy 176.394122 -277.849838) (xy 176.398082 -277.800784) (xy 176.409859 -277.753)
			(xy 176.42915 -277.707724) (xy 176.455453 -277.666128) (xy 176.488088 -277.629291) (xy 176.526209 -277.598166)
			(xy 176.56883 -277.573559) (xy 176.614846 -277.556107) (xy 176.663065 -277.546263) (xy 176.71224 -277.544282)
			(xy 176.761095 -277.550214) (xy 176.808366 -277.563906) (xy 176.852828 -277.585004) (xy 176.893331 -277.61296)
			(xy 176.928824 -277.647052) (xy 176.958389 -277.686396) (xy 176.98126 -277.729973) (xy 176.996844 -277.776654)
			(xy 177.004739 -277.825231) (xy 177.005234 -277.849838) (xy 177.004739 -277.874445) (xy 177.00456 -277.875546)
			(xy 177.322984 -277.875546) (xy 177.322984 -277.82413) (xy 177.331027 -277.773348) (xy 177.346915 -277.724449)
			(xy 177.370258 -277.678637) (xy 177.400479 -277.637041) (xy 177.436835 -277.600685) (xy 177.478431 -277.570464)
			(xy 177.524243 -277.547121) (xy 177.573142 -277.531233) (xy 177.623924 -277.52319) (xy 177.67534 -277.52319)
			(xy 177.726122 -277.531233) (xy 177.775021 -277.547121) (xy 177.820833 -277.570464) (xy 177.862429 -277.600685)
			(xy 177.898785 -277.637041) (xy 177.929006 -277.678637) (xy 177.952349 -277.724449) (xy 177.968237 -277.773348)
			(xy 177.97628 -277.82413) (xy 177.976784 -277.849838) (xy 178.294042 -277.849838) (xy 178.298002 -277.800784)
			(xy 178.309779 -277.753) (xy 178.32907 -277.707724) (xy 178.355373 -277.666128) (xy 178.388008 -277.629291)
			(xy 178.426129 -277.598166) (xy 178.46875 -277.573559) (xy 178.514766 -277.556107) (xy 178.562985 -277.546263)
			(xy 178.61216 -277.544282) (xy 178.661015 -277.550214) (xy 178.708286 -277.563906) (xy 178.752748 -277.585004)
			(xy 178.793251 -277.61296) (xy 178.828744 -277.647052) (xy 178.858309 -277.686396) (xy 178.88118 -277.729973)
			(xy 178.896764 -277.776654) (xy 178.904659 -277.825231) (xy 178.905154 -277.849838) (xy 178.904659 -277.874445)
			(xy 178.90448 -277.875546) (xy 179.223158 -277.875546) (xy 179.223158 -277.82413) (xy 179.231201 -277.773348)
			(xy 179.247089 -277.724449) (xy 179.270432 -277.678637) (xy 179.300653 -277.637041) (xy 179.337009 -277.600685)
			(xy 179.378605 -277.570464) (xy 179.424417 -277.547121) (xy 179.473316 -277.531233) (xy 179.524098 -277.52319)
			(xy 179.575514 -277.52319) (xy 179.626296 -277.531233) (xy 179.675195 -277.547121) (xy 179.721007 -277.570464)
			(xy 179.762603 -277.600685) (xy 179.798959 -277.637041) (xy 179.82918 -277.678637) (xy 179.852523 -277.724449)
			(xy 179.868411 -277.773348) (xy 179.876454 -277.82413) (xy 179.876958 -277.849838) (xy 180.194216 -277.849838)
			(xy 180.198176 -277.800784) (xy 180.209953 -277.753) (xy 180.229244 -277.707724) (xy 180.255547 -277.666128)
			(xy 180.288182 -277.629291) (xy 180.326303 -277.598166) (xy 180.368924 -277.573559) (xy 180.41494 -277.556107)
			(xy 180.463159 -277.546263) (xy 180.512334 -277.544282) (xy 180.561189 -277.550214) (xy 180.60846 -277.563906)
			(xy 180.652922 -277.585004) (xy 180.693425 -277.61296) (xy 180.728918 -277.647052) (xy 180.758483 -277.686396)
			(xy 180.781354 -277.729973) (xy 180.796938 -277.776654) (xy 180.804833 -277.825231) (xy 180.805328 -277.849838)
			(xy 180.804833 -277.874445) (xy 180.804654 -277.875546) (xy 181.123078 -277.875546) (xy 181.123078 -277.82413)
			(xy 181.131121 -277.773348) (xy 181.147009 -277.724449) (xy 181.170352 -277.678637) (xy 181.200573 -277.637041)
			(xy 181.236929 -277.600685) (xy 181.278525 -277.570464) (xy 181.324337 -277.547121) (xy 181.373236 -277.531233)
			(xy 181.424018 -277.52319) (xy 181.475434 -277.52319) (xy 181.526216 -277.531233) (xy 181.575115 -277.547121)
			(xy 181.620927 -277.570464) (xy 181.662523 -277.600685) (xy 181.698879 -277.637041) (xy 181.7291 -277.678637)
			(xy 181.752443 -277.724449) (xy 181.768331 -277.773348) (xy 181.776374 -277.82413) (xy 181.776878 -277.849838)
			(xy 182.094136 -277.849838) (xy 182.098096 -277.800784) (xy 182.109873 -277.753) (xy 182.129164 -277.707724)
			(xy 182.155467 -277.666128) (xy 182.188102 -277.629291) (xy 182.226223 -277.598166) (xy 182.268844 -277.573559)
			(xy 182.31486 -277.556107) (xy 182.363079 -277.546263) (xy 182.412254 -277.544282) (xy 182.461109 -277.550214)
			(xy 182.50838 -277.563906) (xy 182.552842 -277.585004) (xy 182.593345 -277.61296) (xy 182.628838 -277.647052)
			(xy 182.658403 -277.686396) (xy 182.681274 -277.729973) (xy 182.696858 -277.776654) (xy 182.704753 -277.825231)
			(xy 182.705248 -277.849838) (xy 182.704753 -277.874445) (xy 182.704574 -277.875546) (xy 183.022998 -277.875546)
			(xy 183.022998 -277.82413) (xy 183.031041 -277.773348) (xy 183.046929 -277.724449) (xy 183.070272 -277.678637)
			(xy 183.100493 -277.637041) (xy 183.136849 -277.600685) (xy 183.178445 -277.570464) (xy 183.224257 -277.547121)
			(xy 183.273156 -277.531233) (xy 183.323938 -277.52319) (xy 183.375354 -277.52319) (xy 183.426136 -277.531233)
			(xy 183.475035 -277.547121) (xy 183.520847 -277.570464) (xy 183.562443 -277.600685) (xy 183.598799 -277.637041)
			(xy 183.62902 -277.678637) (xy 183.652363 -277.724449) (xy 183.668251 -277.773348) (xy 183.676294 -277.82413)
			(xy 183.676798 -277.849838) (xy 183.994056 -277.849838) (xy 183.998016 -277.800784) (xy 184.009793 -277.753)
			(xy 184.029084 -277.707724) (xy 184.055387 -277.666128) (xy 184.088022 -277.629291) (xy 184.126143 -277.598166)
			(xy 184.168764 -277.573559) (xy 184.21478 -277.556107) (xy 184.262999 -277.546263) (xy 184.312174 -277.544282)
			(xy 184.361029 -277.550214) (xy 184.4083 -277.563906) (xy 184.452762 -277.585004) (xy 184.493265 -277.61296)
			(xy 184.528758 -277.647052) (xy 184.558323 -277.686396) (xy 184.581194 -277.729973) (xy 184.596778 -277.776654)
			(xy 184.604673 -277.825231) (xy 184.605168 -277.849838) (xy 184.604673 -277.874445) (xy 184.604494 -277.875546)
			(xy 184.923172 -277.875546) (xy 184.923172 -277.82413) (xy 184.931215 -277.773348) (xy 184.947103 -277.724449)
			(xy 184.970446 -277.678637) (xy 185.000667 -277.637041) (xy 185.037023 -277.600685) (xy 185.078619 -277.570464)
			(xy 185.124431 -277.547121) (xy 185.17333 -277.531233) (xy 185.224112 -277.52319) (xy 185.275528 -277.52319)
			(xy 185.32631 -277.531233) (xy 185.375209 -277.547121) (xy 185.421021 -277.570464) (xy 185.462617 -277.600685)
			(xy 185.498973 -277.637041) (xy 185.529194 -277.678637) (xy 185.552537 -277.724449) (xy 185.568425 -277.773348)
			(xy 185.576468 -277.82413) (xy 185.576972 -277.849838) (xy 185.89423 -277.849838) (xy 185.89819 -277.800784)
			(xy 185.909967 -277.753) (xy 185.929258 -277.707724) (xy 185.955561 -277.666128) (xy 185.988196 -277.629291)
			(xy 186.026317 -277.598166) (xy 186.068938 -277.573559) (xy 186.114954 -277.556107) (xy 186.163173 -277.546263)
			(xy 186.212348 -277.544282) (xy 186.261203 -277.550214) (xy 186.308474 -277.563906) (xy 186.352936 -277.585004)
			(xy 186.393439 -277.61296) (xy 186.428932 -277.647052) (xy 186.458497 -277.686396) (xy 186.481368 -277.729973)
			(xy 186.496952 -277.776654) (xy 186.504847 -277.825231) (xy 186.505342 -277.849838) (xy 186.504847 -277.874445)
			(xy 186.504668 -277.875546) (xy 186.823092 -277.875546) (xy 186.823092 -277.82413) (xy 186.831135 -277.773348)
			(xy 186.847023 -277.724449) (xy 186.870366 -277.678637) (xy 186.900587 -277.637041) (xy 186.936943 -277.600685)
			(xy 186.978539 -277.570464) (xy 187.024351 -277.547121) (xy 187.07325 -277.531233) (xy 187.124032 -277.52319)
			(xy 187.175448 -277.52319) (xy 187.22623 -277.531233) (xy 187.275129 -277.547121) (xy 187.320941 -277.570464)
			(xy 187.362537 -277.600685) (xy 187.398893 -277.637041) (xy 187.429114 -277.678637) (xy 187.452457 -277.724449)
			(xy 187.468345 -277.773348) (xy 187.476388 -277.82413) (xy 187.476892 -277.849838) (xy 187.79415 -277.849838)
			(xy 187.79811 -277.800784) (xy 187.809887 -277.753) (xy 187.829178 -277.707724) (xy 187.855481 -277.666128)
			(xy 187.888116 -277.629291) (xy 187.926237 -277.598166) (xy 187.968858 -277.573559) (xy 188.014874 -277.556107)
			(xy 188.063093 -277.546263) (xy 188.112268 -277.544282) (xy 188.161123 -277.550214) (xy 188.208394 -277.563906)
			(xy 188.252856 -277.585004) (xy 188.293359 -277.61296) (xy 188.328852 -277.647052) (xy 188.358417 -277.686396)
			(xy 188.381288 -277.729973) (xy 188.396872 -277.776654) (xy 188.404767 -277.825231) (xy 188.405262 -277.849838)
			(xy 188.404767 -277.874445) (xy 188.404588 -277.875546) (xy 188.723012 -277.875546) (xy 188.723012 -277.82413)
			(xy 188.731055 -277.773348) (xy 188.746943 -277.724449) (xy 188.770286 -277.678637) (xy 188.800507 -277.637041)
			(xy 188.836863 -277.600685) (xy 188.878459 -277.570464) (xy 188.924271 -277.547121) (xy 188.97317 -277.531233)
			(xy 189.023952 -277.52319) (xy 189.075368 -277.52319) (xy 189.12615 -277.531233) (xy 189.175049 -277.547121)
			(xy 189.220861 -277.570464) (xy 189.262457 -277.600685) (xy 189.298813 -277.637041) (xy 189.329034 -277.678637)
			(xy 189.352377 -277.724449) (xy 189.368265 -277.773348) (xy 189.376308 -277.82413) (xy 189.376812 -277.849838)
			(xy 189.69407 -277.849838) (xy 189.69803 -277.800784) (xy 189.709807 -277.753) (xy 189.729098 -277.707724)
			(xy 189.755401 -277.666128) (xy 189.788036 -277.629291) (xy 189.826157 -277.598166) (xy 189.868778 -277.573559)
			(xy 189.914794 -277.556107) (xy 189.963013 -277.546263) (xy 190.012188 -277.544282) (xy 190.061043 -277.550214)
			(xy 190.108314 -277.563906) (xy 190.152776 -277.585004) (xy 190.193279 -277.61296) (xy 190.228772 -277.647052)
			(xy 190.258337 -277.686396) (xy 190.281208 -277.729973) (xy 190.296792 -277.776654) (xy 190.304687 -277.825231)
			(xy 190.305182 -277.849838) (xy 190.304687 -277.874445) (xy 190.304508 -277.875546) (xy 190.623186 -277.875546)
			(xy 190.623186 -277.82413) (xy 190.631229 -277.773348) (xy 190.647117 -277.724449) (xy 190.67046 -277.678637)
			(xy 190.700681 -277.637041) (xy 190.737037 -277.600685) (xy 190.778633 -277.570464) (xy 190.824445 -277.547121)
			(xy 190.873344 -277.531233) (xy 190.924126 -277.52319) (xy 190.975542 -277.52319) (xy 191.026324 -277.531233)
			(xy 191.075223 -277.547121) (xy 191.121035 -277.570464) (xy 191.162631 -277.600685) (xy 191.198987 -277.637041)
			(xy 191.229208 -277.678637) (xy 191.252551 -277.724449) (xy 191.268439 -277.773348) (xy 191.276482 -277.82413)
			(xy 191.276986 -277.849838) (xy 191.594244 -277.849838) (xy 191.598204 -277.800784) (xy 191.609981 -277.753)
			(xy 191.629272 -277.707724) (xy 191.655575 -277.666128) (xy 191.68821 -277.629291) (xy 191.726331 -277.598166)
			(xy 191.768952 -277.573559) (xy 191.814968 -277.556107) (xy 191.863187 -277.546263) (xy 191.912362 -277.544282)
			(xy 191.961217 -277.550214) (xy 192.008488 -277.563906) (xy 192.05295 -277.585004) (xy 192.093453 -277.61296)
			(xy 192.128946 -277.647052) (xy 192.158511 -277.686396) (xy 192.181382 -277.729973) (xy 192.196966 -277.776654)
			(xy 192.204861 -277.825231) (xy 192.205356 -277.849838) (xy 192.204861 -277.874445) (xy 192.204682 -277.875546)
			(xy 192.523106 -277.875546) (xy 192.523106 -277.82413) (xy 192.531149 -277.773348) (xy 192.547037 -277.724449)
			(xy 192.57038 -277.678637) (xy 192.600601 -277.637041) (xy 192.636957 -277.600685) (xy 192.678553 -277.570464)
			(xy 192.724365 -277.547121) (xy 192.773264 -277.531233) (xy 192.824046 -277.52319) (xy 192.875462 -277.52319)
			(xy 192.926244 -277.531233) (xy 192.975143 -277.547121) (xy 193.020955 -277.570464) (xy 193.062551 -277.600685)
			(xy 193.098907 -277.637041) (xy 193.129128 -277.678637) (xy 193.152471 -277.724449) (xy 193.168359 -277.773348)
			(xy 193.176402 -277.82413) (xy 193.176906 -277.849838) (xy 193.494164 -277.849838) (xy 193.498124 -277.800784)
			(xy 193.509901 -277.753) (xy 193.529192 -277.707724) (xy 193.555495 -277.666128) (xy 193.58813 -277.629291)
			(xy 193.626251 -277.598166) (xy 193.668872 -277.573559) (xy 193.714888 -277.556107) (xy 193.763107 -277.546263)
			(xy 193.812282 -277.544282) (xy 193.861137 -277.550214) (xy 193.908408 -277.563906) (xy 193.95287 -277.585004)
			(xy 193.993373 -277.61296) (xy 194.028866 -277.647052) (xy 194.058431 -277.686396) (xy 194.081302 -277.729973)
			(xy 194.096886 -277.776654) (xy 194.104781 -277.825231) (xy 194.105276 -277.849838) (xy 194.104781 -277.874445)
			(xy 194.104602 -277.875546) (xy 194.423026 -277.875546) (xy 194.423026 -277.82413) (xy 194.431069 -277.773348)
			(xy 194.446957 -277.724449) (xy 194.4703 -277.678637) (xy 194.500521 -277.637041) (xy 194.536877 -277.600685)
			(xy 194.578473 -277.570464) (xy 194.624285 -277.547121) (xy 194.673184 -277.531233) (xy 194.723966 -277.52319)
			(xy 194.775382 -277.52319) (xy 194.826164 -277.531233) (xy 194.875063 -277.547121) (xy 194.920875 -277.570464)
			(xy 194.962471 -277.600685) (xy 194.998827 -277.637041) (xy 195.029048 -277.678637) (xy 195.052391 -277.724449)
			(xy 195.068279 -277.773348) (xy 195.076322 -277.82413) (xy 195.076826 -277.849838) (xy 195.394084 -277.849838)
			(xy 195.398044 -277.800784) (xy 195.409821 -277.753) (xy 195.429112 -277.707724) (xy 195.455415 -277.666128)
			(xy 195.48805 -277.629291) (xy 195.526171 -277.598166) (xy 195.568792 -277.573559) (xy 195.614808 -277.556107)
			(xy 195.663027 -277.546263) (xy 195.712202 -277.544282) (xy 195.761057 -277.550214) (xy 195.808328 -277.563906)
			(xy 195.85279 -277.585004) (xy 195.893293 -277.61296) (xy 195.928786 -277.647052) (xy 195.958351 -277.686396)
			(xy 195.981222 -277.729973) (xy 195.996806 -277.776654) (xy 196.004701 -277.825231) (xy 196.005196 -277.849838)
			(xy 196.004701 -277.874445) (xy 196.004522 -277.875546) (xy 196.3232 -277.875546) (xy 196.3232 -277.82413)
			(xy 196.331243 -277.773348) (xy 196.347131 -277.724449) (xy 196.370474 -277.678637) (xy 196.400695 -277.637041)
			(xy 196.437051 -277.600685) (xy 196.478647 -277.570464) (xy 196.524459 -277.547121) (xy 196.573358 -277.531233)
			(xy 196.62414 -277.52319) (xy 196.675556 -277.52319) (xy 196.726338 -277.531233) (xy 196.775237 -277.547121)
			(xy 196.821049 -277.570464) (xy 196.862645 -277.600685) (xy 196.899001 -277.637041) (xy 196.929222 -277.678637)
			(xy 196.952565 -277.724449) (xy 196.968453 -277.773348) (xy 196.976496 -277.82413) (xy 196.977 -277.849838)
			(xy 197.294258 -277.849838) (xy 197.298218 -277.800784) (xy 197.309995 -277.753) (xy 197.329286 -277.707724)
			(xy 197.355589 -277.666128) (xy 197.388224 -277.629291) (xy 197.426345 -277.598166) (xy 197.468966 -277.573559)
			(xy 197.514982 -277.556107) (xy 197.563201 -277.546263) (xy 197.612376 -277.544282) (xy 197.661231 -277.550214)
			(xy 197.708502 -277.563906) (xy 197.752964 -277.585004) (xy 197.793467 -277.61296) (xy 197.82896 -277.647052)
			(xy 197.858525 -277.686396) (xy 197.881396 -277.729973) (xy 197.89698 -277.776654) (xy 197.904875 -277.825231)
			(xy 197.90537 -277.849838) (xy 198.244218 -277.849838) (xy 198.248178 -277.800784) (xy 198.259955 -277.753)
			(xy 198.279246 -277.707724) (xy 198.305549 -277.666128) (xy 198.338184 -277.629291) (xy 198.376305 -277.598166)
			(xy 198.418926 -277.573559) (xy 198.464942 -277.556107) (xy 198.513161 -277.546263) (xy 198.562336 -277.544282)
			(xy 198.611191 -277.550214) (xy 198.658462 -277.563906) (xy 198.702924 -277.585004) (xy 198.743427 -277.61296)
			(xy 198.77892 -277.647052) (xy 198.808485 -277.686396) (xy 198.831356 -277.729973) (xy 198.84694 -277.776654)
			(xy 198.854835 -277.825231) (xy 198.85533 -277.849838) (xy 198.854835 -277.874445) (xy 198.84694 -277.923022)
			(xy 198.831356 -277.969703) (xy 198.808485 -278.01328) (xy 198.77892 -278.052624) (xy 198.743427 -278.086716)
			(xy 198.702924 -278.114672) (xy 198.658462 -278.13577) (xy 198.611191 -278.149462) (xy 198.562336 -278.155394)
			(xy 198.513161 -278.153413) (xy 198.464942 -278.143569) (xy 198.418926 -278.126117) (xy 198.376305 -278.10151)
			(xy 198.338184 -278.070385) (xy 198.305549 -278.033548) (xy 198.279246 -277.991952) (xy 198.259955 -277.946676)
			(xy 198.248178 -277.898892) (xy 198.244218 -277.849838) (xy 197.90537 -277.849838) (xy 197.904875 -277.874445)
			(xy 197.89698 -277.923022) (xy 197.881396 -277.969703) (xy 197.858525 -278.01328) (xy 197.82896 -278.052624)
			(xy 197.793467 -278.086716) (xy 197.752964 -278.114672) (xy 197.708502 -278.13577) (xy 197.661231 -278.149462)
			(xy 197.612376 -278.155394) (xy 197.563201 -278.153413) (xy 197.514982 -278.143569) (xy 197.468966 -278.126117)
			(xy 197.426345 -278.10151) (xy 197.388224 -278.070385) (xy 197.355589 -278.033548) (xy 197.329286 -277.991952)
			(xy 197.309995 -277.946676) (xy 197.298218 -277.898892) (xy 197.294258 -277.849838) (xy 196.977 -277.849838)
			(xy 196.976496 -277.875546) (xy 196.968453 -277.926328) (xy 196.952565 -277.975227) (xy 196.929222 -278.021039)
			(xy 196.899001 -278.062635) (xy 196.862645 -278.098991) (xy 196.821049 -278.129212) (xy 196.775237 -278.152555)
			(xy 196.726338 -278.168443) (xy 196.681996 -278.175466) (xy 215.523824 -278.175466) (xy 215.527895 -278.119844)
			(xy 215.540021 -278.065407) (xy 215.559944 -278.013316) (xy 215.58724 -277.964681) (xy 215.621326 -277.920538)
			(xy 215.661475 -277.881829) (xy 215.706833 -277.849378) (xy 215.756433 -277.823877) (xy 215.809217 -277.80587)
			(xy 215.86406 -277.79574) (xy 215.919794 -277.793703) (xy 215.975231 -277.799803) (xy 216.029188 -277.813909)
			(xy 216.080517 -277.835721) (xy 216.128123 -277.864775) (xy 216.170991 -277.90045) (xy 216.208208 -277.941987)
			(xy 216.238981 -277.9885) (xy 216.262653 -278.038997) (xy 216.278721 -278.092404) (xy 216.286841 -278.14758)
			(xy 216.28735 -278.175466) (xy 216.286841 -278.203352) (xy 216.278721 -278.258528) (xy 216.262653 -278.311935)
			(xy 216.238981 -278.362432) (xy 216.208208 -278.408945) (xy 216.170991 -278.450482) (xy 216.128123 -278.486157)
			(xy 216.080517 -278.515211) (xy 216.029188 -278.537023) (xy 215.975231 -278.551129) (xy 215.919794 -278.557229)
			(xy 215.86406 -278.555192) (xy 215.809217 -278.545062) (xy 215.756433 -278.527055) (xy 215.706833 -278.501554)
			(xy 215.661475 -278.469103) (xy 215.621326 -278.430394) (xy 215.58724 -278.386251) (xy 215.559944 -278.337616)
			(xy 215.540021 -278.285525) (xy 215.527895 -278.231088) (xy 215.523824 -278.175466) (xy 196.681996 -278.175466)
			(xy 196.675556 -278.176486) (xy 196.62414 -278.176486) (xy 196.573358 -278.168443) (xy 196.524459 -278.152555)
			(xy 196.478647 -278.129212) (xy 196.437051 -278.098991) (xy 196.400695 -278.062635) (xy 196.370474 -278.021039)
			(xy 196.347131 -277.975227) (xy 196.331243 -277.926328) (xy 196.3232 -277.875546) (xy 196.004522 -277.875546)
			(xy 195.996806 -277.923022) (xy 195.981222 -277.969703) (xy 195.958351 -278.01328) (xy 195.928786 -278.052624)
			(xy 195.893293 -278.086716) (xy 195.85279 -278.114672) (xy 195.808328 -278.13577) (xy 195.761057 -278.149462)
			(xy 195.712202 -278.155394) (xy 195.663027 -278.153413) (xy 195.614808 -278.143569) (xy 195.568792 -278.126117)
			(xy 195.526171 -278.10151) (xy 195.48805 -278.070385) (xy 195.455415 -278.033548) (xy 195.429112 -277.991952)
			(xy 195.409821 -277.946676) (xy 195.398044 -277.898892) (xy 195.394084 -277.849838) (xy 195.076826 -277.849838)
			(xy 195.076322 -277.875546) (xy 195.068279 -277.926328) (xy 195.052391 -277.975227) (xy 195.029048 -278.021039)
			(xy 194.998827 -278.062635) (xy 194.962471 -278.098991) (xy 194.920875 -278.129212) (xy 194.875063 -278.152555)
			(xy 194.826164 -278.168443) (xy 194.775382 -278.176486) (xy 194.723966 -278.176486) (xy 194.673184 -278.168443)
			(xy 194.624285 -278.152555) (xy 194.578473 -278.129212) (xy 194.536877 -278.098991) (xy 194.500521 -278.062635)
			(xy 194.4703 -278.021039) (xy 194.446957 -277.975227) (xy 194.431069 -277.926328) (xy 194.423026 -277.875546)
			(xy 194.104602 -277.875546) (xy 194.096886 -277.923022) (xy 194.081302 -277.969703) (xy 194.058431 -278.01328)
			(xy 194.028866 -278.052624) (xy 193.993373 -278.086716) (xy 193.95287 -278.114672) (xy 193.908408 -278.13577)
			(xy 193.861137 -278.149462) (xy 193.812282 -278.155394) (xy 193.763107 -278.153413) (xy 193.714888 -278.143569)
			(xy 193.668872 -278.126117) (xy 193.626251 -278.10151) (xy 193.58813 -278.070385) (xy 193.555495 -278.033548)
			(xy 193.529192 -277.991952) (xy 193.509901 -277.946676) (xy 193.498124 -277.898892) (xy 193.494164 -277.849838)
			(xy 193.176906 -277.849838) (xy 193.176402 -277.875546) (xy 193.168359 -277.926328) (xy 193.152471 -277.975227)
			(xy 193.129128 -278.021039) (xy 193.098907 -278.062635) (xy 193.062551 -278.098991) (xy 193.020955 -278.129212)
			(xy 192.975143 -278.152555) (xy 192.926244 -278.168443) (xy 192.875462 -278.176486) (xy 192.824046 -278.176486)
			(xy 192.773264 -278.168443) (xy 192.724365 -278.152555) (xy 192.678553 -278.129212) (xy 192.636957 -278.098991)
			(xy 192.600601 -278.062635) (xy 192.57038 -278.021039) (xy 192.547037 -277.975227) (xy 192.531149 -277.926328)
			(xy 192.523106 -277.875546) (xy 192.204682 -277.875546) (xy 192.196966 -277.923022) (xy 192.181382 -277.969703)
			(xy 192.158511 -278.01328) (xy 192.128946 -278.052624) (xy 192.093453 -278.086716) (xy 192.05295 -278.114672)
			(xy 192.008488 -278.13577) (xy 191.961217 -278.149462) (xy 191.912362 -278.155394) (xy 191.863187 -278.153413)
			(xy 191.814968 -278.143569) (xy 191.768952 -278.126117) (xy 191.726331 -278.10151) (xy 191.68821 -278.070385)
			(xy 191.655575 -278.033548) (xy 191.629272 -277.991952) (xy 191.609981 -277.946676) (xy 191.598204 -277.898892)
			(xy 191.594244 -277.849838) (xy 191.276986 -277.849838) (xy 191.276482 -277.875546) (xy 191.268439 -277.926328)
			(xy 191.252551 -277.975227) (xy 191.229208 -278.021039) (xy 191.198987 -278.062635) (xy 191.162631 -278.098991)
			(xy 191.121035 -278.129212) (xy 191.075223 -278.152555) (xy 191.026324 -278.168443) (xy 190.975542 -278.176486)
			(xy 190.924126 -278.176486) (xy 190.873344 -278.168443) (xy 190.824445 -278.152555) (xy 190.778633 -278.129212)
			(xy 190.737037 -278.098991) (xy 190.700681 -278.062635) (xy 190.67046 -278.021039) (xy 190.647117 -277.975227)
			(xy 190.631229 -277.926328) (xy 190.623186 -277.875546) (xy 190.304508 -277.875546) (xy 190.296792 -277.923022)
			(xy 190.281208 -277.969703) (xy 190.258337 -278.01328) (xy 190.228772 -278.052624) (xy 190.193279 -278.086716)
			(xy 190.152776 -278.114672) (xy 190.108314 -278.13577) (xy 190.061043 -278.149462) (xy 190.012188 -278.155394)
			(xy 189.963013 -278.153413) (xy 189.914794 -278.143569) (xy 189.868778 -278.126117) (xy 189.826157 -278.10151)
			(xy 189.788036 -278.070385) (xy 189.755401 -278.033548) (xy 189.729098 -277.991952) (xy 189.709807 -277.946676)
			(xy 189.69803 -277.898892) (xy 189.69407 -277.849838) (xy 189.376812 -277.849838) (xy 189.376308 -277.875546)
			(xy 189.368265 -277.926328) (xy 189.352377 -277.975227) (xy 189.329034 -278.021039) (xy 189.298813 -278.062635)
			(xy 189.262457 -278.098991) (xy 189.220861 -278.129212) (xy 189.175049 -278.152555) (xy 189.12615 -278.168443)
			(xy 189.075368 -278.176486) (xy 189.023952 -278.176486) (xy 188.97317 -278.168443) (xy 188.924271 -278.152555)
			(xy 188.878459 -278.129212) (xy 188.836863 -278.098991) (xy 188.800507 -278.062635) (xy 188.770286 -278.021039)
			(xy 188.746943 -277.975227) (xy 188.731055 -277.926328) (xy 188.723012 -277.875546) (xy 188.404588 -277.875546)
			(xy 188.396872 -277.923022) (xy 188.381288 -277.969703) (xy 188.358417 -278.01328) (xy 188.328852 -278.052624)
			(xy 188.293359 -278.086716) (xy 188.252856 -278.114672) (xy 188.208394 -278.13577) (xy 188.161123 -278.149462)
			(xy 188.112268 -278.155394) (xy 188.063093 -278.153413) (xy 188.014874 -278.143569) (xy 187.968858 -278.126117)
			(xy 187.926237 -278.10151) (xy 187.888116 -278.070385) (xy 187.855481 -278.033548) (xy 187.829178 -277.991952)
			(xy 187.809887 -277.946676) (xy 187.79811 -277.898892) (xy 187.79415 -277.849838) (xy 187.476892 -277.849838)
			(xy 187.476388 -277.875546) (xy 187.468345 -277.926328) (xy 187.452457 -277.975227) (xy 187.429114 -278.021039)
			(xy 187.398893 -278.062635) (xy 187.362537 -278.098991) (xy 187.320941 -278.129212) (xy 187.275129 -278.152555)
			(xy 187.22623 -278.168443) (xy 187.175448 -278.176486) (xy 187.124032 -278.176486) (xy 187.07325 -278.168443)
			(xy 187.024351 -278.152555) (xy 186.978539 -278.129212) (xy 186.936943 -278.098991) (xy 186.900587 -278.062635)
			(xy 186.870366 -278.021039) (xy 186.847023 -277.975227) (xy 186.831135 -277.926328) (xy 186.823092 -277.875546)
			(xy 186.504668 -277.875546) (xy 186.496952 -277.923022) (xy 186.481368 -277.969703) (xy 186.458497 -278.01328)
			(xy 186.428932 -278.052624) (xy 186.393439 -278.086716) (xy 186.352936 -278.114672) (xy 186.308474 -278.13577)
			(xy 186.261203 -278.149462) (xy 186.212348 -278.155394) (xy 186.163173 -278.153413) (xy 186.114954 -278.143569)
			(xy 186.068938 -278.126117) (xy 186.026317 -278.10151) (xy 185.988196 -278.070385) (xy 185.955561 -278.033548)
			(xy 185.929258 -277.991952) (xy 185.909967 -277.946676) (xy 185.89819 -277.898892) (xy 185.89423 -277.849838)
			(xy 185.576972 -277.849838) (xy 185.576468 -277.875546) (xy 185.568425 -277.926328) (xy 185.552537 -277.975227)
			(xy 185.529194 -278.021039) (xy 185.498973 -278.062635) (xy 185.462617 -278.098991) (xy 185.421021 -278.129212)
			(xy 185.375209 -278.152555) (xy 185.32631 -278.168443) (xy 185.275528 -278.176486) (xy 185.224112 -278.176486)
			(xy 185.17333 -278.168443) (xy 185.124431 -278.152555) (xy 185.078619 -278.129212) (xy 185.037023 -278.098991)
			(xy 185.000667 -278.062635) (xy 184.970446 -278.021039) (xy 184.947103 -277.975227) (xy 184.931215 -277.926328)
			(xy 184.923172 -277.875546) (xy 184.604494 -277.875546) (xy 184.596778 -277.923022) (xy 184.581194 -277.969703)
			(xy 184.558323 -278.01328) (xy 184.528758 -278.052624) (xy 184.493265 -278.086716) (xy 184.452762 -278.114672)
			(xy 184.4083 -278.13577) (xy 184.361029 -278.149462) (xy 184.312174 -278.155394) (xy 184.262999 -278.153413)
			(xy 184.21478 -278.143569) (xy 184.168764 -278.126117) (xy 184.126143 -278.10151) (xy 184.088022 -278.070385)
			(xy 184.055387 -278.033548) (xy 184.029084 -277.991952) (xy 184.009793 -277.946676) (xy 183.998016 -277.898892)
			(xy 183.994056 -277.849838) (xy 183.676798 -277.849838) (xy 183.676294 -277.875546) (xy 183.668251 -277.926328)
			(xy 183.652363 -277.975227) (xy 183.62902 -278.021039) (xy 183.598799 -278.062635) (xy 183.562443 -278.098991)
			(xy 183.520847 -278.129212) (xy 183.475035 -278.152555) (xy 183.426136 -278.168443) (xy 183.375354 -278.176486)
			(xy 183.323938 -278.176486) (xy 183.273156 -278.168443) (xy 183.224257 -278.152555) (xy 183.178445 -278.129212)
			(xy 183.136849 -278.098991) (xy 183.100493 -278.062635) (xy 183.070272 -278.021039) (xy 183.046929 -277.975227)
			(xy 183.031041 -277.926328) (xy 183.022998 -277.875546) (xy 182.704574 -277.875546) (xy 182.696858 -277.923022)
			(xy 182.681274 -277.969703) (xy 182.658403 -278.01328) (xy 182.628838 -278.052624) (xy 182.593345 -278.086716)
			(xy 182.552842 -278.114672) (xy 182.50838 -278.13577) (xy 182.461109 -278.149462) (xy 182.412254 -278.155394)
			(xy 182.363079 -278.153413) (xy 182.31486 -278.143569) (xy 182.268844 -278.126117) (xy 182.226223 -278.10151)
			(xy 182.188102 -278.070385) (xy 182.155467 -278.033548) (xy 182.129164 -277.991952) (xy 182.109873 -277.946676)
			(xy 182.098096 -277.898892) (xy 182.094136 -277.849838) (xy 181.776878 -277.849838) (xy 181.776374 -277.875546)
			(xy 181.768331 -277.926328) (xy 181.752443 -277.975227) (xy 181.7291 -278.021039) (xy 181.698879 -278.062635)
			(xy 181.662523 -278.098991) (xy 181.620927 -278.129212) (xy 181.575115 -278.152555) (xy 181.526216 -278.168443)
			(xy 181.475434 -278.176486) (xy 181.424018 -278.176486) (xy 181.373236 -278.168443) (xy 181.324337 -278.152555)
			(xy 181.278525 -278.129212) (xy 181.236929 -278.098991) (xy 181.200573 -278.062635) (xy 181.170352 -278.021039)
			(xy 181.147009 -277.975227) (xy 181.131121 -277.926328) (xy 181.123078 -277.875546) (xy 180.804654 -277.875546)
			(xy 180.796938 -277.923022) (xy 180.781354 -277.969703) (xy 180.758483 -278.01328) (xy 180.728918 -278.052624)
			(xy 180.693425 -278.086716) (xy 180.652922 -278.114672) (xy 180.60846 -278.13577) (xy 180.561189 -278.149462)
			(xy 180.512334 -278.155394) (xy 180.463159 -278.153413) (xy 180.41494 -278.143569) (xy 180.368924 -278.126117)
			(xy 180.326303 -278.10151) (xy 180.288182 -278.070385) (xy 180.255547 -278.033548) (xy 180.229244 -277.991952)
			(xy 180.209953 -277.946676) (xy 180.198176 -277.898892) (xy 180.194216 -277.849838) (xy 179.876958 -277.849838)
			(xy 179.876454 -277.875546) (xy 179.868411 -277.926328) (xy 179.852523 -277.975227) (xy 179.82918 -278.021039)
			(xy 179.798959 -278.062635) (xy 179.762603 -278.098991) (xy 179.721007 -278.129212) (xy 179.675195 -278.152555)
			(xy 179.626296 -278.168443) (xy 179.575514 -278.176486) (xy 179.524098 -278.176486) (xy 179.473316 -278.168443)
			(xy 179.424417 -278.152555) (xy 179.378605 -278.129212) (xy 179.337009 -278.098991) (xy 179.300653 -278.062635)
			(xy 179.270432 -278.021039) (xy 179.247089 -277.975227) (xy 179.231201 -277.926328) (xy 179.223158 -277.875546)
			(xy 178.90448 -277.875546) (xy 178.896764 -277.923022) (xy 178.88118 -277.969703) (xy 178.858309 -278.01328)
			(xy 178.828744 -278.052624) (xy 178.793251 -278.086716) (xy 178.752748 -278.114672) (xy 178.708286 -278.13577)
			(xy 178.661015 -278.149462) (xy 178.61216 -278.155394) (xy 178.562985 -278.153413) (xy 178.514766 -278.143569)
			(xy 178.46875 -278.126117) (xy 178.426129 -278.10151) (xy 178.388008 -278.070385) (xy 178.355373 -278.033548)
			(xy 178.32907 -277.991952) (xy 178.309779 -277.946676) (xy 178.298002 -277.898892) (xy 178.294042 -277.849838)
			(xy 177.976784 -277.849838) (xy 177.97628 -277.875546) (xy 177.968237 -277.926328) (xy 177.952349 -277.975227)
			(xy 177.929006 -278.021039) (xy 177.898785 -278.062635) (xy 177.862429 -278.098991) (xy 177.820833 -278.129212)
			(xy 177.775021 -278.152555) (xy 177.726122 -278.168443) (xy 177.67534 -278.176486) (xy 177.623924 -278.176486)
			(xy 177.573142 -278.168443) (xy 177.524243 -278.152555) (xy 177.478431 -278.129212) (xy 177.436835 -278.098991)
			(xy 177.400479 -278.062635) (xy 177.370258 -278.021039) (xy 177.346915 -277.975227) (xy 177.331027 -277.926328)
			(xy 177.322984 -277.875546) (xy 177.00456 -277.875546) (xy 176.996844 -277.923022) (xy 176.98126 -277.969703)
			(xy 176.958389 -278.01328) (xy 176.928824 -278.052624) (xy 176.893331 -278.086716) (xy 176.852828 -278.114672)
			(xy 176.808366 -278.13577) (xy 176.761095 -278.149462) (xy 176.71224 -278.155394) (xy 176.663065 -278.153413)
			(xy 176.614846 -278.143569) (xy 176.56883 -278.126117) (xy 176.526209 -278.10151) (xy 176.488088 -278.070385)
			(xy 176.455453 -278.033548) (xy 176.42915 -277.991952) (xy 176.409859 -277.946676) (xy 176.398082 -277.898892)
			(xy 176.394122 -277.849838) (xy 176.076864 -277.849838) (xy 176.07636 -277.875546) (xy 176.068317 -277.926328)
			(xy 176.052429 -277.975227) (xy 176.029086 -278.021039) (xy 175.998865 -278.062635) (xy 175.962509 -278.098991)
			(xy 175.920913 -278.129212) (xy 175.875101 -278.152555) (xy 175.826202 -278.168443) (xy 175.77542 -278.176486)
			(xy 175.724004 -278.176486) (xy 175.673222 -278.168443) (xy 175.624323 -278.152555) (xy 175.578511 -278.129212)
			(xy 175.536915 -278.098991) (xy 175.500559 -278.062635) (xy 175.470338 -278.021039) (xy 175.446995 -277.975227)
			(xy 175.431107 -277.926328) (xy 175.423064 -277.875546) (xy 175.10464 -277.875546) (xy 175.096924 -277.923022)
			(xy 175.08134 -277.969703) (xy 175.058469 -278.01328) (xy 175.028904 -278.052624) (xy 174.993411 -278.086716)
			(xy 174.952908 -278.114672) (xy 174.908446 -278.13577) (xy 174.861175 -278.149462) (xy 174.81232 -278.155394)
			(xy 174.763145 -278.153413) (xy 174.714926 -278.143569) (xy 174.66891 -278.126117) (xy 174.626289 -278.10151)
			(xy 174.588168 -278.070385) (xy 174.555533 -278.033548) (xy 174.52923 -277.991952) (xy 174.509939 -277.946676)
			(xy 174.498162 -277.898892) (xy 174.494202 -277.849838) (xy 174.177198 -277.849838) (xy 174.176694 -277.875546)
			(xy 174.168651 -277.926328) (xy 174.152763 -277.975227) (xy 174.12942 -278.021039) (xy 174.099199 -278.062635)
			(xy 174.062843 -278.098991) (xy 174.021247 -278.129212) (xy 173.975435 -278.152555) (xy 173.926536 -278.168443)
			(xy 173.875754 -278.176486) (xy 173.824338 -278.176486) (xy 173.773556 -278.168443) (xy 173.724657 -278.152555)
			(xy 173.678845 -278.129212) (xy 173.637249 -278.098991) (xy 173.600893 -278.062635) (xy 173.570672 -278.021039)
			(xy 173.547329 -277.975227) (xy 173.531441 -277.926328) (xy 173.523398 -277.875546) (xy 173.20472 -277.875546)
			(xy 173.197004 -277.923022) (xy 173.18142 -277.969703) (xy 173.158549 -278.01328) (xy 173.128984 -278.052624)
			(xy 173.093491 -278.086716) (xy 173.052988 -278.114672) (xy 173.008526 -278.13577) (xy 172.961255 -278.149462)
			(xy 172.9124 -278.155394) (xy 172.863225 -278.153413) (xy 172.815006 -278.143569) (xy 172.76899 -278.126117)
			(xy 172.726369 -278.10151) (xy 172.688248 -278.070385) (xy 172.655613 -278.033548) (xy 172.62931 -277.991952)
			(xy 172.610019 -277.946676) (xy 172.598242 -277.898892) (xy 172.594282 -277.849838) (xy 172.277024 -277.849838)
			(xy 172.27652 -277.875546) (xy 172.268477 -277.926328) (xy 172.252589 -277.975227) (xy 172.229246 -278.021039)
			(xy 172.199025 -278.062635) (xy 172.162669 -278.098991) (xy 172.121073 -278.129212) (xy 172.075261 -278.152555)
			(xy 172.026362 -278.168443) (xy 171.97558 -278.176486) (xy 171.924164 -278.176486) (xy 171.873382 -278.168443)
			(xy 171.824483 -278.152555) (xy 171.778671 -278.129212) (xy 171.737075 -278.098991) (xy 171.700719 -278.062635)
			(xy 171.670498 -278.021039) (xy 171.647155 -277.975227) (xy 171.631267 -277.926328) (xy 171.623224 -277.875546)
			(xy 171.304546 -277.875546) (xy 171.29683 -277.923022) (xy 171.281246 -277.969703) (xy 171.258375 -278.01328)
			(xy 171.22881 -278.052624) (xy 171.193317 -278.086716) (xy 171.152814 -278.114672) (xy 171.108352 -278.13577)
			(xy 171.061081 -278.149462) (xy 171.012226 -278.155394) (xy 170.963051 -278.153413) (xy 170.914832 -278.143569)
			(xy 170.868816 -278.126117) (xy 170.826195 -278.10151) (xy 170.788074 -278.070385) (xy 170.755439 -278.033548)
			(xy 170.729136 -277.991952) (xy 170.709845 -277.946676) (xy 170.698068 -277.898892) (xy 170.694108 -277.849838)
			(xy 170.377104 -277.849838) (xy 170.3766 -277.875546) (xy 170.368557 -277.926328) (xy 170.352669 -277.975227)
			(xy 170.329326 -278.021039) (xy 170.299105 -278.062635) (xy 170.262749 -278.098991) (xy 170.221153 -278.129212)
			(xy 170.175341 -278.152555) (xy 170.126442 -278.168443) (xy 170.07566 -278.176486) (xy 170.024244 -278.176486)
			(xy 169.973462 -278.168443) (xy 169.924563 -278.152555) (xy 169.878751 -278.129212) (xy 169.837155 -278.098991)
			(xy 169.800799 -278.062635) (xy 169.770578 -278.021039) (xy 169.747235 -277.975227) (xy 169.731347 -277.926328)
			(xy 169.723304 -277.875546) (xy 169.404626 -277.875546) (xy 169.39691 -277.923022) (xy 169.381326 -277.969703)
			(xy 169.358455 -278.01328) (xy 169.32889 -278.052624) (xy 169.293397 -278.086716) (xy 169.252894 -278.114672)
			(xy 169.208432 -278.13577) (xy 169.161161 -278.149462) (xy 169.112306 -278.155394) (xy 169.063131 -278.153413)
			(xy 169.014912 -278.143569) (xy 168.968896 -278.126117) (xy 168.926275 -278.10151) (xy 168.888154 -278.070385)
			(xy 168.855519 -278.033548) (xy 168.829216 -277.991952) (xy 168.809925 -277.946676) (xy 168.798148 -277.898892)
			(xy 168.794188 -277.849838) (xy 168.477184 -277.849838) (xy 168.47668 -277.875546) (xy 168.468637 -277.926328)
			(xy 168.452749 -277.975227) (xy 168.429406 -278.021039) (xy 168.399185 -278.062635) (xy 168.362829 -278.098991)
			(xy 168.321233 -278.129212) (xy 168.275421 -278.152555) (xy 168.226522 -278.168443) (xy 168.17574 -278.176486)
			(xy 168.124324 -278.176486) (xy 168.073542 -278.168443) (xy 168.024643 -278.152555) (xy 167.978831 -278.129212)
			(xy 167.937235 -278.098991) (xy 167.900879 -278.062635) (xy 167.870658 -278.021039) (xy 167.847315 -277.975227)
			(xy 167.831427 -277.926328) (xy 167.823384 -277.875546) (xy 167.504706 -277.875546) (xy 167.49699 -277.923022)
			(xy 167.481406 -277.969703) (xy 167.458535 -278.01328) (xy 167.42897 -278.052624) (xy 167.393477 -278.086716)
			(xy 167.352974 -278.114672) (xy 167.308512 -278.13577) (xy 167.261241 -278.149462) (xy 167.212386 -278.155394)
			(xy 167.163211 -278.153413) (xy 167.114992 -278.143569) (xy 167.068976 -278.126117) (xy 167.026355 -278.10151)
			(xy 166.988234 -278.070385) (xy 166.955599 -278.033548) (xy 166.929296 -277.991952) (xy 166.910005 -277.946676)
			(xy 166.898228 -277.898892) (xy 166.894268 -277.849838) (xy 166.57701 -277.849838) (xy 166.576506 -277.875546)
			(xy 166.568463 -277.926328) (xy 166.552575 -277.975227) (xy 166.529232 -278.021039) (xy 166.499011 -278.062635)
			(xy 166.462655 -278.098991) (xy 166.421059 -278.129212) (xy 166.375247 -278.152555) (xy 166.326348 -278.168443)
			(xy 166.275566 -278.176486) (xy 166.22415 -278.176486) (xy 166.173368 -278.168443) (xy 166.124469 -278.152555)
			(xy 166.078657 -278.129212) (xy 166.037061 -278.098991) (xy 166.000705 -278.062635) (xy 165.970484 -278.021039)
			(xy 165.947141 -277.975227) (xy 165.931253 -277.926328) (xy 165.92321 -277.875546) (xy 165.604493 -277.875546)
			(xy 165.597217 -277.921365) (xy 165.582316 -277.967102) (xy 165.560428 -278.009937) (xy 165.532094 -278.048809)
			(xy 165.498015 -278.082758) (xy 165.459034 -278.110942) (xy 165.416116 -278.132665) (xy 165.370322 -278.14739)
			(xy 165.346634 -278.15159) (xy 165.327838 -278.154384) (xy 165.303708 -278.182832) (xy 165.303708 -278.466804)
			(xy 165.327838 -278.495252) (xy 165.346634 -278.498046) (xy 165.370336 -278.502173) (xy 165.416136 -278.5169)
			(xy 165.459059 -278.538627) (xy 165.498045 -278.566816) (xy 165.532128 -278.600769) (xy 165.560465 -278.639647)
			(xy 165.582355 -278.682488) (xy 165.597257 -278.728231) (xy 165.604801 -278.775745) (xy 165.604801 -278.823854)
			(xy 165.604539 -278.825506) (xy 165.92321 -278.825506) (xy 165.92321 -278.77409) (xy 165.931253 -278.723308)
			(xy 165.947141 -278.674409) (xy 165.970484 -278.628597) (xy 166.000705 -278.587001) (xy 166.037061 -278.550645)
			(xy 166.078657 -278.520424) (xy 166.124469 -278.497081) (xy 166.173368 -278.481193) (xy 166.22415 -278.47315)
			(xy 166.275566 -278.47315) (xy 166.326348 -278.481193) (xy 166.375247 -278.497081) (xy 166.421059 -278.520424)
			(xy 166.462655 -278.550645) (xy 166.499011 -278.587001) (xy 166.529232 -278.628597) (xy 166.552575 -278.674409)
			(xy 166.568463 -278.723308) (xy 166.576506 -278.77409) (xy 166.57701 -278.799798) (xy 166.894268 -278.799798)
			(xy 166.898228 -278.750744) (xy 166.910005 -278.70296) (xy 166.929296 -278.657684) (xy 166.955599 -278.616088)
			(xy 166.988234 -278.579251) (xy 167.026355 -278.548126) (xy 167.068976 -278.523519) (xy 167.114992 -278.506067)
			(xy 167.163211 -278.496223) (xy 167.212386 -278.494242) (xy 167.261241 -278.500174) (xy 167.308512 -278.513866)
			(xy 167.352974 -278.534964) (xy 167.393477 -278.56292) (xy 167.42897 -278.597012) (xy 167.458535 -278.636356)
			(xy 167.481406 -278.679933) (xy 167.49699 -278.726614) (xy 167.504885 -278.775191) (xy 167.50538 -278.799798)
			(xy 167.504885 -278.824405) (xy 167.504706 -278.825506) (xy 167.823384 -278.825506) (xy 167.823384 -278.77409)
			(xy 167.831427 -278.723308) (xy 167.847315 -278.674409) (xy 167.870658 -278.628597) (xy 167.900879 -278.587001)
			(xy 167.937235 -278.550645) (xy 167.978831 -278.520424) (xy 168.024643 -278.497081) (xy 168.073542 -278.481193)
			(xy 168.124324 -278.47315) (xy 168.17574 -278.47315) (xy 168.226522 -278.481193) (xy 168.275421 -278.497081)
			(xy 168.321233 -278.520424) (xy 168.362829 -278.550645) (xy 168.399185 -278.587001) (xy 168.429406 -278.628597)
			(xy 168.452749 -278.674409) (xy 168.468637 -278.723308) (xy 168.47668 -278.77409) (xy 168.477184 -278.799798)
			(xy 168.794188 -278.799798) (xy 168.798148 -278.750744) (xy 168.809925 -278.70296) (xy 168.829216 -278.657684)
			(xy 168.855519 -278.616088) (xy 168.888154 -278.579251) (xy 168.926275 -278.548126) (xy 168.968896 -278.523519)
			(xy 169.014912 -278.506067) (xy 169.063131 -278.496223) (xy 169.112306 -278.494242) (xy 169.161161 -278.500174)
			(xy 169.208432 -278.513866) (xy 169.252894 -278.534964) (xy 169.293397 -278.56292) (xy 169.32889 -278.597012)
			(xy 169.358455 -278.636356) (xy 169.381326 -278.679933) (xy 169.39691 -278.726614) (xy 169.404805 -278.775191)
			(xy 169.4053 -278.799798) (xy 169.404805 -278.824405) (xy 169.404626 -278.825506) (xy 169.723304 -278.825506)
			(xy 169.723304 -278.77409) (xy 169.731347 -278.723308) (xy 169.747235 -278.674409) (xy 169.770578 -278.628597)
			(xy 169.800799 -278.587001) (xy 169.837155 -278.550645) (xy 169.878751 -278.520424) (xy 169.924563 -278.497081)
			(xy 169.973462 -278.481193) (xy 170.024244 -278.47315) (xy 170.07566 -278.47315) (xy 170.126442 -278.481193)
			(xy 170.175341 -278.497081) (xy 170.221153 -278.520424) (xy 170.262749 -278.550645) (xy 170.299105 -278.587001)
			(xy 170.329326 -278.628597) (xy 170.352669 -278.674409) (xy 170.368557 -278.723308) (xy 170.3766 -278.77409)
			(xy 170.377104 -278.799798) (xy 170.694108 -278.799798) (xy 170.698068 -278.750744) (xy 170.709845 -278.70296)
			(xy 170.729136 -278.657684) (xy 170.755439 -278.616088) (xy 170.788074 -278.579251) (xy 170.826195 -278.548126)
			(xy 170.868816 -278.523519) (xy 170.914832 -278.506067) (xy 170.963051 -278.496223) (xy 171.012226 -278.494242)
			(xy 171.061081 -278.500174) (xy 171.108352 -278.513866) (xy 171.152814 -278.534964) (xy 171.193317 -278.56292)
			(xy 171.22881 -278.597012) (xy 171.258375 -278.636356) (xy 171.281246 -278.679933) (xy 171.29683 -278.726614)
			(xy 171.304725 -278.775191) (xy 171.30522 -278.799798) (xy 171.304725 -278.824405) (xy 171.304546 -278.825506)
			(xy 171.623224 -278.825506) (xy 171.623224 -278.77409) (xy 171.631267 -278.723308) (xy 171.647155 -278.674409)
			(xy 171.670498 -278.628597) (xy 171.700719 -278.587001) (xy 171.737075 -278.550645) (xy 171.778671 -278.520424)
			(xy 171.824483 -278.497081) (xy 171.873382 -278.481193) (xy 171.924164 -278.47315) (xy 171.97558 -278.47315)
			(xy 172.026362 -278.481193) (xy 172.075261 -278.497081) (xy 172.121073 -278.520424) (xy 172.162669 -278.550645)
			(xy 172.199025 -278.587001) (xy 172.229246 -278.628597) (xy 172.252589 -278.674409) (xy 172.268477 -278.723308)
			(xy 172.27652 -278.77409) (xy 172.277024 -278.799798) (xy 172.594282 -278.799798) (xy 172.598242 -278.750744)
			(xy 172.610019 -278.70296) (xy 172.62931 -278.657684) (xy 172.655613 -278.616088) (xy 172.688248 -278.579251)
			(xy 172.726369 -278.548126) (xy 172.76899 -278.523519) (xy 172.815006 -278.506067) (xy 172.863225 -278.496223)
			(xy 172.9124 -278.494242) (xy 172.961255 -278.500174) (xy 173.008526 -278.513866) (xy 173.052988 -278.534964)
			(xy 173.093491 -278.56292) (xy 173.128984 -278.597012) (xy 173.158549 -278.636356) (xy 173.18142 -278.679933)
			(xy 173.197004 -278.726614) (xy 173.204899 -278.775191) (xy 173.205394 -278.799798) (xy 173.204899 -278.824405)
			(xy 173.20472 -278.825506) (xy 173.523398 -278.825506) (xy 173.523398 -278.77409) (xy 173.531441 -278.723308)
			(xy 173.547329 -278.674409) (xy 173.570672 -278.628597) (xy 173.600893 -278.587001) (xy 173.637249 -278.550645)
			(xy 173.678845 -278.520424) (xy 173.724657 -278.497081) (xy 173.773556 -278.481193) (xy 173.824338 -278.47315)
			(xy 173.875754 -278.47315) (xy 173.926536 -278.481193) (xy 173.975435 -278.497081) (xy 174.021247 -278.520424)
			(xy 174.062843 -278.550645) (xy 174.099199 -278.587001) (xy 174.12942 -278.628597) (xy 174.152763 -278.674409)
			(xy 174.168651 -278.723308) (xy 174.176694 -278.77409) (xy 174.177198 -278.799798) (xy 174.494202 -278.799798)
			(xy 174.498162 -278.750744) (xy 174.509939 -278.70296) (xy 174.52923 -278.657684) (xy 174.555533 -278.616088)
			(xy 174.588168 -278.579251) (xy 174.626289 -278.548126) (xy 174.66891 -278.523519) (xy 174.714926 -278.506067)
			(xy 174.763145 -278.496223) (xy 174.81232 -278.494242) (xy 174.861175 -278.500174) (xy 174.908446 -278.513866)
			(xy 174.952908 -278.534964) (xy 174.993411 -278.56292) (xy 175.028904 -278.597012) (xy 175.058469 -278.636356)
			(xy 175.08134 -278.679933) (xy 175.096924 -278.726614) (xy 175.104819 -278.775191) (xy 175.105314 -278.799798)
			(xy 175.104819 -278.824405) (xy 175.10464 -278.825506) (xy 175.423064 -278.825506) (xy 175.423064 -278.77409)
			(xy 175.431107 -278.723308) (xy 175.446995 -278.674409) (xy 175.470338 -278.628597) (xy 175.500559 -278.587001)
			(xy 175.536915 -278.550645) (xy 175.578511 -278.520424) (xy 175.624323 -278.497081) (xy 175.673222 -278.481193)
			(xy 175.724004 -278.47315) (xy 175.77542 -278.47315) (xy 175.826202 -278.481193) (xy 175.875101 -278.497081)
			(xy 175.920913 -278.520424) (xy 175.962509 -278.550645) (xy 175.998865 -278.587001) (xy 176.029086 -278.628597)
			(xy 176.052429 -278.674409) (xy 176.068317 -278.723308) (xy 176.07636 -278.77409) (xy 176.076864 -278.799798)
			(xy 176.394122 -278.799798) (xy 176.398082 -278.750744) (xy 176.409859 -278.70296) (xy 176.42915 -278.657684)
			(xy 176.455453 -278.616088) (xy 176.488088 -278.579251) (xy 176.526209 -278.548126) (xy 176.56883 -278.523519)
			(xy 176.614846 -278.506067) (xy 176.663065 -278.496223) (xy 176.71224 -278.494242) (xy 176.761095 -278.500174)
			(xy 176.808366 -278.513866) (xy 176.852828 -278.534964) (xy 176.893331 -278.56292) (xy 176.928824 -278.597012)
			(xy 176.958389 -278.636356) (xy 176.98126 -278.679933) (xy 176.996844 -278.726614) (xy 177.004739 -278.775191)
			(xy 177.005234 -278.799798) (xy 177.004739 -278.824405) (xy 177.00456 -278.825506) (xy 177.322984 -278.825506)
			(xy 177.322984 -278.77409) (xy 177.331027 -278.723308) (xy 177.346915 -278.674409) (xy 177.370258 -278.628597)
			(xy 177.400479 -278.587001) (xy 177.436835 -278.550645) (xy 177.478431 -278.520424) (xy 177.524243 -278.497081)
			(xy 177.573142 -278.481193) (xy 177.623924 -278.47315) (xy 177.67534 -278.47315) (xy 177.726122 -278.481193)
			(xy 177.775021 -278.497081) (xy 177.820833 -278.520424) (xy 177.862429 -278.550645) (xy 177.898785 -278.587001)
			(xy 177.929006 -278.628597) (xy 177.952349 -278.674409) (xy 177.968237 -278.723308) (xy 177.97628 -278.77409)
			(xy 177.976784 -278.799798) (xy 178.294042 -278.799798) (xy 178.298002 -278.750744) (xy 178.309779 -278.70296)
			(xy 178.32907 -278.657684) (xy 178.355373 -278.616088) (xy 178.388008 -278.579251) (xy 178.426129 -278.548126)
			(xy 178.46875 -278.523519) (xy 178.514766 -278.506067) (xy 178.562985 -278.496223) (xy 178.61216 -278.494242)
			(xy 178.661015 -278.500174) (xy 178.708286 -278.513866) (xy 178.752748 -278.534964) (xy 178.793251 -278.56292)
			(xy 178.828744 -278.597012) (xy 178.858309 -278.636356) (xy 178.88118 -278.679933) (xy 178.896764 -278.726614)
			(xy 178.904659 -278.775191) (xy 178.905154 -278.799798) (xy 178.904659 -278.824405) (xy 178.90448 -278.825506)
			(xy 179.223158 -278.825506) (xy 179.223158 -278.77409) (xy 179.231201 -278.723308) (xy 179.247089 -278.674409)
			(xy 179.270432 -278.628597) (xy 179.300653 -278.587001) (xy 179.337009 -278.550645) (xy 179.378605 -278.520424)
			(xy 179.424417 -278.497081) (xy 179.473316 -278.481193) (xy 179.524098 -278.47315) (xy 179.575514 -278.47315)
			(xy 179.626296 -278.481193) (xy 179.675195 -278.497081) (xy 179.721007 -278.520424) (xy 179.762603 -278.550645)
			(xy 179.798959 -278.587001) (xy 179.82918 -278.628597) (xy 179.852523 -278.674409) (xy 179.868411 -278.723308)
			(xy 179.876454 -278.77409) (xy 179.876958 -278.799798) (xy 180.194216 -278.799798) (xy 180.198176 -278.750744)
			(xy 180.209953 -278.70296) (xy 180.229244 -278.657684) (xy 180.255547 -278.616088) (xy 180.288182 -278.579251)
			(xy 180.326303 -278.548126) (xy 180.368924 -278.523519) (xy 180.41494 -278.506067) (xy 180.463159 -278.496223)
			(xy 180.512334 -278.494242) (xy 180.561189 -278.500174) (xy 180.60846 -278.513866) (xy 180.652922 -278.534964)
			(xy 180.693425 -278.56292) (xy 180.728918 -278.597012) (xy 180.758483 -278.636356) (xy 180.781354 -278.679933)
			(xy 180.796938 -278.726614) (xy 180.804833 -278.775191) (xy 180.805328 -278.799798) (xy 180.804833 -278.824405)
			(xy 180.804654 -278.825506) (xy 181.123078 -278.825506) (xy 181.123078 -278.77409) (xy 181.131121 -278.723308)
			(xy 181.147009 -278.674409) (xy 181.170352 -278.628597) (xy 181.200573 -278.587001) (xy 181.236929 -278.550645)
			(xy 181.278525 -278.520424) (xy 181.324337 -278.497081) (xy 181.373236 -278.481193) (xy 181.424018 -278.47315)
			(xy 181.475434 -278.47315) (xy 181.526216 -278.481193) (xy 181.575115 -278.497081) (xy 181.620927 -278.520424)
			(xy 181.662523 -278.550645) (xy 181.698879 -278.587001) (xy 181.7291 -278.628597) (xy 181.752443 -278.674409)
			(xy 181.768331 -278.723308) (xy 181.776374 -278.77409) (xy 181.776878 -278.799798) (xy 182.094136 -278.799798)
			(xy 182.098096 -278.750744) (xy 182.109873 -278.70296) (xy 182.129164 -278.657684) (xy 182.155467 -278.616088)
			(xy 182.188102 -278.579251) (xy 182.226223 -278.548126) (xy 182.268844 -278.523519) (xy 182.31486 -278.506067)
			(xy 182.363079 -278.496223) (xy 182.412254 -278.494242) (xy 182.461109 -278.500174) (xy 182.50838 -278.513866)
			(xy 182.552842 -278.534964) (xy 182.593345 -278.56292) (xy 182.628838 -278.597012) (xy 182.658403 -278.636356)
			(xy 182.681274 -278.679933) (xy 182.696858 -278.726614) (xy 182.704753 -278.775191) (xy 182.705248 -278.799798)
			(xy 182.704753 -278.824405) (xy 182.704574 -278.825506) (xy 183.022998 -278.825506) (xy 183.022998 -278.77409)
			(xy 183.031041 -278.723308) (xy 183.046929 -278.674409) (xy 183.070272 -278.628597) (xy 183.100493 -278.587001)
			(xy 183.136849 -278.550645) (xy 183.178445 -278.520424) (xy 183.224257 -278.497081) (xy 183.273156 -278.481193)
			(xy 183.323938 -278.47315) (xy 183.375354 -278.47315) (xy 183.426136 -278.481193) (xy 183.475035 -278.497081)
			(xy 183.520847 -278.520424) (xy 183.562443 -278.550645) (xy 183.598799 -278.587001) (xy 183.62902 -278.628597)
			(xy 183.652363 -278.674409) (xy 183.668251 -278.723308) (xy 183.676294 -278.77409) (xy 183.676798 -278.799798)
			(xy 183.994056 -278.799798) (xy 183.998016 -278.750744) (xy 184.009793 -278.70296) (xy 184.029084 -278.657684)
			(xy 184.055387 -278.616088) (xy 184.088022 -278.579251) (xy 184.126143 -278.548126) (xy 184.168764 -278.523519)
			(xy 184.21478 -278.506067) (xy 184.262999 -278.496223) (xy 184.312174 -278.494242) (xy 184.361029 -278.500174)
			(xy 184.4083 -278.513866) (xy 184.452762 -278.534964) (xy 184.493265 -278.56292) (xy 184.528758 -278.597012)
			(xy 184.558323 -278.636356) (xy 184.581194 -278.679933) (xy 184.596778 -278.726614) (xy 184.604673 -278.775191)
			(xy 184.605168 -278.799798) (xy 184.604673 -278.824405) (xy 184.604494 -278.825506) (xy 184.923172 -278.825506)
			(xy 184.923172 -278.77409) (xy 184.931215 -278.723308) (xy 184.947103 -278.674409) (xy 184.970446 -278.628597)
			(xy 185.000667 -278.587001) (xy 185.037023 -278.550645) (xy 185.078619 -278.520424) (xy 185.124431 -278.497081)
			(xy 185.17333 -278.481193) (xy 185.224112 -278.47315) (xy 185.275528 -278.47315) (xy 185.32631 -278.481193)
			(xy 185.375209 -278.497081) (xy 185.421021 -278.520424) (xy 185.462617 -278.550645) (xy 185.498973 -278.587001)
			(xy 185.529194 -278.628597) (xy 185.552537 -278.674409) (xy 185.568425 -278.723308) (xy 185.576468 -278.77409)
			(xy 185.576972 -278.799798) (xy 185.89423 -278.799798) (xy 185.89819 -278.750744) (xy 185.909967 -278.70296)
			(xy 185.929258 -278.657684) (xy 185.955561 -278.616088) (xy 185.988196 -278.579251) (xy 186.026317 -278.548126)
			(xy 186.068938 -278.523519) (xy 186.114954 -278.506067) (xy 186.163173 -278.496223) (xy 186.212348 -278.494242)
			(xy 186.261203 -278.500174) (xy 186.308474 -278.513866) (xy 186.352936 -278.534964) (xy 186.393439 -278.56292)
			(xy 186.428932 -278.597012) (xy 186.458497 -278.636356) (xy 186.481368 -278.679933) (xy 186.496952 -278.726614)
			(xy 186.504847 -278.775191) (xy 186.505342 -278.799798) (xy 186.504847 -278.824405) (xy 186.504668 -278.825506)
			(xy 186.823092 -278.825506) (xy 186.823092 -278.77409) (xy 186.831135 -278.723308) (xy 186.847023 -278.674409)
			(xy 186.870366 -278.628597) (xy 186.900587 -278.587001) (xy 186.936943 -278.550645) (xy 186.978539 -278.520424)
			(xy 187.024351 -278.497081) (xy 187.07325 -278.481193) (xy 187.124032 -278.47315) (xy 187.175448 -278.47315)
			(xy 187.22623 -278.481193) (xy 187.275129 -278.497081) (xy 187.320941 -278.520424) (xy 187.362537 -278.550645)
			(xy 187.398893 -278.587001) (xy 187.429114 -278.628597) (xy 187.452457 -278.674409) (xy 187.468345 -278.723308)
			(xy 187.476388 -278.77409) (xy 187.476892 -278.799798) (xy 187.79415 -278.799798) (xy 187.79811 -278.750744)
			(xy 187.809887 -278.70296) (xy 187.829178 -278.657684) (xy 187.855481 -278.616088) (xy 187.888116 -278.579251)
			(xy 187.926237 -278.548126) (xy 187.968858 -278.523519) (xy 188.014874 -278.506067) (xy 188.063093 -278.496223)
			(xy 188.112268 -278.494242) (xy 188.161123 -278.500174) (xy 188.208394 -278.513866) (xy 188.252856 -278.534964)
			(xy 188.293359 -278.56292) (xy 188.328852 -278.597012) (xy 188.358417 -278.636356) (xy 188.381288 -278.679933)
			(xy 188.396872 -278.726614) (xy 188.404767 -278.775191) (xy 188.405262 -278.799798) (xy 188.404767 -278.824405)
			(xy 188.404588 -278.825506) (xy 188.723012 -278.825506) (xy 188.723012 -278.77409) (xy 188.731055 -278.723308)
			(xy 188.746943 -278.674409) (xy 188.770286 -278.628597) (xy 188.800507 -278.587001) (xy 188.836863 -278.550645)
			(xy 188.878459 -278.520424) (xy 188.924271 -278.497081) (xy 188.97317 -278.481193) (xy 189.023952 -278.47315)
			(xy 189.075368 -278.47315) (xy 189.12615 -278.481193) (xy 189.175049 -278.497081) (xy 189.220861 -278.520424)
			(xy 189.262457 -278.550645) (xy 189.298813 -278.587001) (xy 189.329034 -278.628597) (xy 189.352377 -278.674409)
			(xy 189.368265 -278.723308) (xy 189.376308 -278.77409) (xy 189.376812 -278.799798) (xy 189.69407 -278.799798)
			(xy 189.69803 -278.750744) (xy 189.709807 -278.70296) (xy 189.729098 -278.657684) (xy 189.755401 -278.616088)
			(xy 189.788036 -278.579251) (xy 189.826157 -278.548126) (xy 189.868778 -278.523519) (xy 189.914794 -278.506067)
			(xy 189.963013 -278.496223) (xy 190.012188 -278.494242) (xy 190.061043 -278.500174) (xy 190.108314 -278.513866)
			(xy 190.152776 -278.534964) (xy 190.193279 -278.56292) (xy 190.228772 -278.597012) (xy 190.258337 -278.636356)
			(xy 190.281208 -278.679933) (xy 190.296792 -278.726614) (xy 190.304687 -278.775191) (xy 190.305182 -278.799798)
			(xy 190.304687 -278.824405) (xy 190.304508 -278.825506) (xy 190.623186 -278.825506) (xy 190.623186 -278.77409)
			(xy 190.631229 -278.723308) (xy 190.647117 -278.674409) (xy 190.67046 -278.628597) (xy 190.700681 -278.587001)
			(xy 190.737037 -278.550645) (xy 190.778633 -278.520424) (xy 190.824445 -278.497081) (xy 190.873344 -278.481193)
			(xy 190.924126 -278.47315) (xy 190.975542 -278.47315) (xy 191.026324 -278.481193) (xy 191.075223 -278.497081)
			(xy 191.121035 -278.520424) (xy 191.162631 -278.550645) (xy 191.198987 -278.587001) (xy 191.229208 -278.628597)
			(xy 191.252551 -278.674409) (xy 191.268439 -278.723308) (xy 191.276482 -278.77409) (xy 191.276986 -278.799798)
			(xy 191.594244 -278.799798) (xy 191.598204 -278.750744) (xy 191.609981 -278.70296) (xy 191.629272 -278.657684)
			(xy 191.655575 -278.616088) (xy 191.68821 -278.579251) (xy 191.726331 -278.548126) (xy 191.768952 -278.523519)
			(xy 191.814968 -278.506067) (xy 191.863187 -278.496223) (xy 191.912362 -278.494242) (xy 191.961217 -278.500174)
			(xy 192.008488 -278.513866) (xy 192.05295 -278.534964) (xy 192.093453 -278.56292) (xy 192.128946 -278.597012)
			(xy 192.158511 -278.636356) (xy 192.181382 -278.679933) (xy 192.196966 -278.726614) (xy 192.204861 -278.775191)
			(xy 192.205356 -278.799798) (xy 192.204861 -278.824405) (xy 192.204682 -278.825506) (xy 192.523106 -278.825506)
			(xy 192.523106 -278.77409) (xy 192.531149 -278.723308) (xy 192.547037 -278.674409) (xy 192.57038 -278.628597)
			(xy 192.600601 -278.587001) (xy 192.636957 -278.550645) (xy 192.678553 -278.520424) (xy 192.724365 -278.497081)
			(xy 192.773264 -278.481193) (xy 192.824046 -278.47315) (xy 192.875462 -278.47315) (xy 192.926244 -278.481193)
			(xy 192.975143 -278.497081) (xy 193.020955 -278.520424) (xy 193.062551 -278.550645) (xy 193.098907 -278.587001)
			(xy 193.129128 -278.628597) (xy 193.152471 -278.674409) (xy 193.168359 -278.723308) (xy 193.176402 -278.77409)
			(xy 193.176906 -278.799798) (xy 193.494164 -278.799798) (xy 193.498124 -278.750744) (xy 193.509901 -278.70296)
			(xy 193.529192 -278.657684) (xy 193.555495 -278.616088) (xy 193.58813 -278.579251) (xy 193.626251 -278.548126)
			(xy 193.668872 -278.523519) (xy 193.714888 -278.506067) (xy 193.763107 -278.496223) (xy 193.812282 -278.494242)
			(xy 193.861137 -278.500174) (xy 193.908408 -278.513866) (xy 193.95287 -278.534964) (xy 193.993373 -278.56292)
			(xy 194.028866 -278.597012) (xy 194.058431 -278.636356) (xy 194.081302 -278.679933) (xy 194.096886 -278.726614)
			(xy 194.104781 -278.775191) (xy 194.105276 -278.799798) (xy 194.104781 -278.824405) (xy 194.104602 -278.825506)
			(xy 194.423026 -278.825506) (xy 194.423026 -278.77409) (xy 194.431069 -278.723308) (xy 194.446957 -278.674409)
			(xy 194.4703 -278.628597) (xy 194.500521 -278.587001) (xy 194.536877 -278.550645) (xy 194.578473 -278.520424)
			(xy 194.624285 -278.497081) (xy 194.673184 -278.481193) (xy 194.723966 -278.47315) (xy 194.775382 -278.47315)
			(xy 194.826164 -278.481193) (xy 194.875063 -278.497081) (xy 194.920875 -278.520424) (xy 194.962471 -278.550645)
			(xy 194.998827 -278.587001) (xy 195.029048 -278.628597) (xy 195.052391 -278.674409) (xy 195.068279 -278.723308)
			(xy 195.076322 -278.77409) (xy 195.076826 -278.799798) (xy 195.394084 -278.799798) (xy 195.398044 -278.750744)
			(xy 195.409821 -278.70296) (xy 195.429112 -278.657684) (xy 195.455415 -278.616088) (xy 195.48805 -278.579251)
			(xy 195.526171 -278.548126) (xy 195.568792 -278.523519) (xy 195.614808 -278.506067) (xy 195.663027 -278.496223)
			(xy 195.712202 -278.494242) (xy 195.761057 -278.500174) (xy 195.808328 -278.513866) (xy 195.85279 -278.534964)
			(xy 195.893293 -278.56292) (xy 195.928786 -278.597012) (xy 195.958351 -278.636356) (xy 195.981222 -278.679933)
			(xy 195.996806 -278.726614) (xy 196.004701 -278.775191) (xy 196.005196 -278.799798) (xy 196.004701 -278.824405)
			(xy 196.004522 -278.825506) (xy 196.3232 -278.825506) (xy 196.3232 -278.77409) (xy 196.331243 -278.723308)
			(xy 196.347131 -278.674409) (xy 196.370474 -278.628597) (xy 196.400695 -278.587001) (xy 196.437051 -278.550645)
			(xy 196.478647 -278.520424) (xy 196.524459 -278.497081) (xy 196.573358 -278.481193) (xy 196.62414 -278.47315)
			(xy 196.675556 -278.47315) (xy 196.726338 -278.481193) (xy 196.775237 -278.497081) (xy 196.821049 -278.520424)
			(xy 196.862645 -278.550645) (xy 196.899001 -278.587001) (xy 196.929222 -278.628597) (xy 196.952565 -278.674409)
			(xy 196.968453 -278.723308) (xy 196.976496 -278.77409) (xy 196.977 -278.799798) (xy 197.294258 -278.799798)
			(xy 197.298218 -278.750744) (xy 197.309995 -278.70296) (xy 197.329286 -278.657684) (xy 197.355589 -278.616088)
			(xy 197.388224 -278.579251) (xy 197.426345 -278.548126) (xy 197.468966 -278.523519) (xy 197.514982 -278.506067)
			(xy 197.563201 -278.496223) (xy 197.612376 -278.494242) (xy 197.661231 -278.500174) (xy 197.708502 -278.513866)
			(xy 197.752964 -278.534964) (xy 197.793467 -278.56292) (xy 197.82896 -278.597012) (xy 197.858525 -278.636356)
			(xy 197.881396 -278.679933) (xy 197.89698 -278.726614) (xy 197.904875 -278.775191) (xy 197.90537 -278.799798)
			(xy 198.244218 -278.799798) (xy 198.248178 -278.750744) (xy 198.259955 -278.70296) (xy 198.279246 -278.657684)
			(xy 198.305549 -278.616088) (xy 198.338184 -278.579251) (xy 198.376305 -278.548126) (xy 198.418926 -278.523519)
			(xy 198.464942 -278.506067) (xy 198.513161 -278.496223) (xy 198.562336 -278.494242) (xy 198.611191 -278.500174)
			(xy 198.658462 -278.513866) (xy 198.702924 -278.534964) (xy 198.743427 -278.56292) (xy 198.77892 -278.597012)
			(xy 198.808485 -278.636356) (xy 198.831356 -278.679933) (xy 198.84694 -278.726614) (xy 198.854835 -278.775191)
			(xy 198.85533 -278.799798) (xy 198.854835 -278.824405) (xy 198.84694 -278.872982) (xy 198.831356 -278.919663)
			(xy 198.808485 -278.96324) (xy 198.77892 -279.002584) (xy 198.743427 -279.036676) (xy 198.702924 -279.064632)
			(xy 198.679186 -279.075896) (xy 224.380042 -279.075896) (xy 224.384113 -279.020274) (xy 224.396239 -278.965837)
			(xy 224.416162 -278.913746) (xy 224.443458 -278.865111) (xy 224.477544 -278.820968) (xy 224.517693 -278.782259)
			(xy 224.563051 -278.749808) (xy 224.612651 -278.724307) (xy 224.665435 -278.7063) (xy 224.720278 -278.69617)
			(xy 224.776012 -278.694133) (xy 224.831449 -278.700233) (xy 224.885406 -278.714339) (xy 224.936735 -278.736151)
			(xy 224.984341 -278.765205) (xy 225.027209 -278.80088) (xy 225.064426 -278.842417) (xy 225.095199 -278.88893)
			(xy 225.118871 -278.939427) (xy 225.134939 -278.992834) (xy 225.143059 -279.04801) (xy 225.143568 -279.075896)
			(xy 225.143059 -279.103782) (xy 225.134939 -279.158958) (xy 225.118871 -279.212365) (xy 225.095199 -279.262862)
			(xy 225.064426 -279.309375) (xy 225.027209 -279.350912) (xy 224.984341 -279.386587) (xy 224.936735 -279.415641)
			(xy 224.885406 -279.437453) (xy 224.831449 -279.451559) (xy 224.776012 -279.457659) (xy 224.720278 -279.455622)
			(xy 224.665435 -279.445492) (xy 224.612651 -279.427485) (xy 224.563051 -279.401984) (xy 224.517693 -279.369533)
			(xy 224.477544 -279.330824) (xy 224.443458 -279.286681) (xy 224.416162 -279.238046) (xy 224.396239 -279.185955)
			(xy 224.384113 -279.131518) (xy 224.380042 -279.075896) (xy 198.679186 -279.075896) (xy 198.658462 -279.08573)
			(xy 198.611191 -279.099422) (xy 198.562336 -279.105354) (xy 198.513161 -279.103373) (xy 198.464942 -279.093529)
			(xy 198.418926 -279.076077) (xy 198.376305 -279.05147) (xy 198.338184 -279.020345) (xy 198.305549 -278.983508)
			(xy 198.279246 -278.941912) (xy 198.259955 -278.896636) (xy 198.248178 -278.848852) (xy 198.244218 -278.799798)
			(xy 197.90537 -278.799798) (xy 197.904875 -278.824405) (xy 197.89698 -278.872982) (xy 197.881396 -278.919663)
			(xy 197.858525 -278.96324) (xy 197.82896 -279.002584) (xy 197.793467 -279.036676) (xy 197.752964 -279.064632)
			(xy 197.708502 -279.08573) (xy 197.661231 -279.099422) (xy 197.612376 -279.105354) (xy 197.563201 -279.103373)
			(xy 197.514982 -279.093529) (xy 197.468966 -279.076077) (xy 197.426345 -279.05147) (xy 197.388224 -279.020345)
			(xy 197.355589 -278.983508) (xy 197.329286 -278.941912) (xy 197.309995 -278.896636) (xy 197.298218 -278.848852)
			(xy 197.294258 -278.799798) (xy 196.977 -278.799798) (xy 196.976496 -278.825506) (xy 196.968453 -278.876288)
			(xy 196.952565 -278.925187) (xy 196.929222 -278.970999) (xy 196.899001 -279.012595) (xy 196.862645 -279.048951)
			(xy 196.821049 -279.079172) (xy 196.775237 -279.102515) (xy 196.726338 -279.118403) (xy 196.675556 -279.126446)
			(xy 196.62414 -279.126446) (xy 196.573358 -279.118403) (xy 196.524459 -279.102515) (xy 196.478647 -279.079172)
			(xy 196.437051 -279.048951) (xy 196.400695 -279.012595) (xy 196.370474 -278.970999) (xy 196.347131 -278.925187)
			(xy 196.331243 -278.876288) (xy 196.3232 -278.825506) (xy 196.004522 -278.825506) (xy 195.996806 -278.872982)
			(xy 195.981222 -278.919663) (xy 195.958351 -278.96324) (xy 195.928786 -279.002584) (xy 195.893293 -279.036676)
			(xy 195.85279 -279.064632) (xy 195.808328 -279.08573) (xy 195.761057 -279.099422) (xy 195.712202 -279.105354)
			(xy 195.663027 -279.103373) (xy 195.614808 -279.093529) (xy 195.568792 -279.076077) (xy 195.526171 -279.05147)
			(xy 195.48805 -279.020345) (xy 195.455415 -278.983508) (xy 195.429112 -278.941912) (xy 195.409821 -278.896636)
			(xy 195.398044 -278.848852) (xy 195.394084 -278.799798) (xy 195.076826 -278.799798) (xy 195.076322 -278.825506)
			(xy 195.068279 -278.876288) (xy 195.052391 -278.925187) (xy 195.029048 -278.970999) (xy 194.998827 -279.012595)
			(xy 194.962471 -279.048951) (xy 194.920875 -279.079172) (xy 194.875063 -279.102515) (xy 194.826164 -279.118403)
			(xy 194.775382 -279.126446) (xy 194.723966 -279.126446) (xy 194.673184 -279.118403) (xy 194.624285 -279.102515)
			(xy 194.578473 -279.079172) (xy 194.536877 -279.048951) (xy 194.500521 -279.012595) (xy 194.4703 -278.970999)
			(xy 194.446957 -278.925187) (xy 194.431069 -278.876288) (xy 194.423026 -278.825506) (xy 194.104602 -278.825506)
			(xy 194.096886 -278.872982) (xy 194.081302 -278.919663) (xy 194.058431 -278.96324) (xy 194.028866 -279.002584)
			(xy 193.993373 -279.036676) (xy 193.95287 -279.064632) (xy 193.908408 -279.08573) (xy 193.861137 -279.099422)
			(xy 193.812282 -279.105354) (xy 193.763107 -279.103373) (xy 193.714888 -279.093529) (xy 193.668872 -279.076077)
			(xy 193.626251 -279.05147) (xy 193.58813 -279.020345) (xy 193.555495 -278.983508) (xy 193.529192 -278.941912)
			(xy 193.509901 -278.896636) (xy 193.498124 -278.848852) (xy 193.494164 -278.799798) (xy 193.176906 -278.799798)
			(xy 193.176402 -278.825506) (xy 193.168359 -278.876288) (xy 193.152471 -278.925187) (xy 193.129128 -278.970999)
			(xy 193.098907 -279.012595) (xy 193.062551 -279.048951) (xy 193.020955 -279.079172) (xy 192.975143 -279.102515)
			(xy 192.926244 -279.118403) (xy 192.875462 -279.126446) (xy 192.824046 -279.126446) (xy 192.773264 -279.118403)
			(xy 192.724365 -279.102515) (xy 192.678553 -279.079172) (xy 192.636957 -279.048951) (xy 192.600601 -279.012595)
			(xy 192.57038 -278.970999) (xy 192.547037 -278.925187) (xy 192.531149 -278.876288) (xy 192.523106 -278.825506)
			(xy 192.204682 -278.825506) (xy 192.196966 -278.872982) (xy 192.181382 -278.919663) (xy 192.158511 -278.96324)
			(xy 192.128946 -279.002584) (xy 192.093453 -279.036676) (xy 192.05295 -279.064632) (xy 192.008488 -279.08573)
			(xy 191.961217 -279.099422) (xy 191.912362 -279.105354) (xy 191.863187 -279.103373) (xy 191.814968 -279.093529)
			(xy 191.768952 -279.076077) (xy 191.726331 -279.05147) (xy 191.68821 -279.020345) (xy 191.655575 -278.983508)
			(xy 191.629272 -278.941912) (xy 191.609981 -278.896636) (xy 191.598204 -278.848852) (xy 191.594244 -278.799798)
			(xy 191.276986 -278.799798) (xy 191.276482 -278.825506) (xy 191.268439 -278.876288) (xy 191.252551 -278.925187)
			(xy 191.229208 -278.970999) (xy 191.198987 -279.012595) (xy 191.162631 -279.048951) (xy 191.121035 -279.079172)
			(xy 191.075223 -279.102515) (xy 191.026324 -279.118403) (xy 190.975542 -279.126446) (xy 190.924126 -279.126446)
			(xy 190.873344 -279.118403) (xy 190.824445 -279.102515) (xy 190.778633 -279.079172) (xy 190.737037 -279.048951)
			(xy 190.700681 -279.012595) (xy 190.67046 -278.970999) (xy 190.647117 -278.925187) (xy 190.631229 -278.876288)
			(xy 190.623186 -278.825506) (xy 190.304508 -278.825506) (xy 190.296792 -278.872982) (xy 190.281208 -278.919663)
			(xy 190.258337 -278.96324) (xy 190.228772 -279.002584) (xy 190.193279 -279.036676) (xy 190.152776 -279.064632)
			(xy 190.108314 -279.08573) (xy 190.061043 -279.099422) (xy 190.012188 -279.105354) (xy 189.963013 -279.103373)
			(xy 189.914794 -279.093529) (xy 189.868778 -279.076077) (xy 189.826157 -279.05147) (xy 189.788036 -279.020345)
			(xy 189.755401 -278.983508) (xy 189.729098 -278.941912) (xy 189.709807 -278.896636) (xy 189.69803 -278.848852)
			(xy 189.69407 -278.799798) (xy 189.376812 -278.799798) (xy 189.376308 -278.825506) (xy 189.368265 -278.876288)
			(xy 189.352377 -278.925187) (xy 189.329034 -278.970999) (xy 189.298813 -279.012595) (xy 189.262457 -279.048951)
			(xy 189.220861 -279.079172) (xy 189.175049 -279.102515) (xy 189.12615 -279.118403) (xy 189.075368 -279.126446)
			(xy 189.023952 -279.126446) (xy 188.97317 -279.118403) (xy 188.924271 -279.102515) (xy 188.878459 -279.079172)
			(xy 188.836863 -279.048951) (xy 188.800507 -279.012595) (xy 188.770286 -278.970999) (xy 188.746943 -278.925187)
			(xy 188.731055 -278.876288) (xy 188.723012 -278.825506) (xy 188.404588 -278.825506) (xy 188.396872 -278.872982)
			(xy 188.381288 -278.919663) (xy 188.358417 -278.96324) (xy 188.328852 -279.002584) (xy 188.293359 -279.036676)
			(xy 188.252856 -279.064632) (xy 188.208394 -279.08573) (xy 188.161123 -279.099422) (xy 188.112268 -279.105354)
			(xy 188.063093 -279.103373) (xy 188.014874 -279.093529) (xy 187.968858 -279.076077) (xy 187.926237 -279.05147)
			(xy 187.888116 -279.020345) (xy 187.855481 -278.983508) (xy 187.829178 -278.941912) (xy 187.809887 -278.896636)
			(xy 187.79811 -278.848852) (xy 187.79415 -278.799798) (xy 187.476892 -278.799798) (xy 187.476388 -278.825506)
			(xy 187.468345 -278.876288) (xy 187.452457 -278.925187) (xy 187.429114 -278.970999) (xy 187.398893 -279.012595)
			(xy 187.362537 -279.048951) (xy 187.320941 -279.079172) (xy 187.275129 -279.102515) (xy 187.22623 -279.118403)
			(xy 187.175448 -279.126446) (xy 187.124032 -279.126446) (xy 187.07325 -279.118403) (xy 187.024351 -279.102515)
			(xy 186.978539 -279.079172) (xy 186.936943 -279.048951) (xy 186.900587 -279.012595) (xy 186.870366 -278.970999)
			(xy 186.847023 -278.925187) (xy 186.831135 -278.876288) (xy 186.823092 -278.825506) (xy 186.504668 -278.825506)
			(xy 186.496952 -278.872982) (xy 186.481368 -278.919663) (xy 186.458497 -278.96324) (xy 186.428932 -279.002584)
			(xy 186.393439 -279.036676) (xy 186.352936 -279.064632) (xy 186.308474 -279.08573) (xy 186.261203 -279.099422)
			(xy 186.212348 -279.105354) (xy 186.163173 -279.103373) (xy 186.114954 -279.093529) (xy 186.068938 -279.076077)
			(xy 186.026317 -279.05147) (xy 185.988196 -279.020345) (xy 185.955561 -278.983508) (xy 185.929258 -278.941912)
			(xy 185.909967 -278.896636) (xy 185.89819 -278.848852) (xy 185.89423 -278.799798) (xy 185.576972 -278.799798)
			(xy 185.576468 -278.825506) (xy 185.568425 -278.876288) (xy 185.552537 -278.925187) (xy 185.529194 -278.970999)
			(xy 185.498973 -279.012595) (xy 185.462617 -279.048951) (xy 185.421021 -279.079172) (xy 185.375209 -279.102515)
			(xy 185.32631 -279.118403) (xy 185.275528 -279.126446) (xy 185.224112 -279.126446) (xy 185.17333 -279.118403)
			(xy 185.124431 -279.102515) (xy 185.078619 -279.079172) (xy 185.037023 -279.048951) (xy 185.000667 -279.012595)
			(xy 184.970446 -278.970999) (xy 184.947103 -278.925187) (xy 184.931215 -278.876288) (xy 184.923172 -278.825506)
			(xy 184.604494 -278.825506) (xy 184.596778 -278.872982) (xy 184.581194 -278.919663) (xy 184.558323 -278.96324)
			(xy 184.528758 -279.002584) (xy 184.493265 -279.036676) (xy 184.452762 -279.064632) (xy 184.4083 -279.08573)
			(xy 184.361029 -279.099422) (xy 184.312174 -279.105354) (xy 184.262999 -279.103373) (xy 184.21478 -279.093529)
			(xy 184.168764 -279.076077) (xy 184.126143 -279.05147) (xy 184.088022 -279.020345) (xy 184.055387 -278.983508)
			(xy 184.029084 -278.941912) (xy 184.009793 -278.896636) (xy 183.998016 -278.848852) (xy 183.994056 -278.799798)
			(xy 183.676798 -278.799798) (xy 183.676294 -278.825506) (xy 183.668251 -278.876288) (xy 183.652363 -278.925187)
			(xy 183.62902 -278.970999) (xy 183.598799 -279.012595) (xy 183.562443 -279.048951) (xy 183.520847 -279.079172)
			(xy 183.475035 -279.102515) (xy 183.426136 -279.118403) (xy 183.375354 -279.126446) (xy 183.323938 -279.126446)
			(xy 183.273156 -279.118403) (xy 183.224257 -279.102515) (xy 183.178445 -279.079172) (xy 183.136849 -279.048951)
			(xy 183.100493 -279.012595) (xy 183.070272 -278.970999) (xy 183.046929 -278.925187) (xy 183.031041 -278.876288)
			(xy 183.022998 -278.825506) (xy 182.704574 -278.825506) (xy 182.696858 -278.872982) (xy 182.681274 -278.919663)
			(xy 182.658403 -278.96324) (xy 182.628838 -279.002584) (xy 182.593345 -279.036676) (xy 182.552842 -279.064632)
			(xy 182.50838 -279.08573) (xy 182.461109 -279.099422) (xy 182.412254 -279.105354) (xy 182.363079 -279.103373)
			(xy 182.31486 -279.093529) (xy 182.268844 -279.076077) (xy 182.226223 -279.05147) (xy 182.188102 -279.020345)
			(xy 182.155467 -278.983508) (xy 182.129164 -278.941912) (xy 182.109873 -278.896636) (xy 182.098096 -278.848852)
			(xy 182.094136 -278.799798) (xy 181.776878 -278.799798) (xy 181.776374 -278.825506) (xy 181.768331 -278.876288)
			(xy 181.752443 -278.925187) (xy 181.7291 -278.970999) (xy 181.698879 -279.012595) (xy 181.662523 -279.048951)
			(xy 181.620927 -279.079172) (xy 181.575115 -279.102515) (xy 181.526216 -279.118403) (xy 181.475434 -279.126446)
			(xy 181.424018 -279.126446) (xy 181.373236 -279.118403) (xy 181.324337 -279.102515) (xy 181.278525 -279.079172)
			(xy 181.236929 -279.048951) (xy 181.200573 -279.012595) (xy 181.170352 -278.970999) (xy 181.147009 -278.925187)
			(xy 181.131121 -278.876288) (xy 181.123078 -278.825506) (xy 180.804654 -278.825506) (xy 180.796938 -278.872982)
			(xy 180.781354 -278.919663) (xy 180.758483 -278.96324) (xy 180.728918 -279.002584) (xy 180.693425 -279.036676)
			(xy 180.652922 -279.064632) (xy 180.60846 -279.08573) (xy 180.561189 -279.099422) (xy 180.512334 -279.105354)
			(xy 180.463159 -279.103373) (xy 180.41494 -279.093529) (xy 180.368924 -279.076077) (xy 180.326303 -279.05147)
			(xy 180.288182 -279.020345) (xy 180.255547 -278.983508) (xy 180.229244 -278.941912) (xy 180.209953 -278.896636)
			(xy 180.198176 -278.848852) (xy 180.194216 -278.799798) (xy 179.876958 -278.799798) (xy 179.876454 -278.825506)
			(xy 179.868411 -278.876288) (xy 179.852523 -278.925187) (xy 179.82918 -278.970999) (xy 179.798959 -279.012595)
			(xy 179.762603 -279.048951) (xy 179.721007 -279.079172) (xy 179.675195 -279.102515) (xy 179.626296 -279.118403)
			(xy 179.575514 -279.126446) (xy 179.524098 -279.126446) (xy 179.473316 -279.118403) (xy 179.424417 -279.102515)
			(xy 179.378605 -279.079172) (xy 179.337009 -279.048951) (xy 179.300653 -279.012595) (xy 179.270432 -278.970999)
			(xy 179.247089 -278.925187) (xy 179.231201 -278.876288) (xy 179.223158 -278.825506) (xy 178.90448 -278.825506)
			(xy 178.896764 -278.872982) (xy 178.88118 -278.919663) (xy 178.858309 -278.96324) (xy 178.828744 -279.002584)
			(xy 178.793251 -279.036676) (xy 178.752748 -279.064632) (xy 178.708286 -279.08573) (xy 178.661015 -279.099422)
			(xy 178.61216 -279.105354) (xy 178.562985 -279.103373) (xy 178.514766 -279.093529) (xy 178.46875 -279.076077)
			(xy 178.426129 -279.05147) (xy 178.388008 -279.020345) (xy 178.355373 -278.983508) (xy 178.32907 -278.941912)
			(xy 178.309779 -278.896636) (xy 178.298002 -278.848852) (xy 178.294042 -278.799798) (xy 177.976784 -278.799798)
			(xy 177.97628 -278.825506) (xy 177.968237 -278.876288) (xy 177.952349 -278.925187) (xy 177.929006 -278.970999)
			(xy 177.898785 -279.012595) (xy 177.862429 -279.048951) (xy 177.820833 -279.079172) (xy 177.775021 -279.102515)
			(xy 177.726122 -279.118403) (xy 177.67534 -279.126446) (xy 177.623924 -279.126446) (xy 177.573142 -279.118403)
			(xy 177.524243 -279.102515) (xy 177.478431 -279.079172) (xy 177.436835 -279.048951) (xy 177.400479 -279.012595)
			(xy 177.370258 -278.970999) (xy 177.346915 -278.925187) (xy 177.331027 -278.876288) (xy 177.322984 -278.825506)
			(xy 177.00456 -278.825506) (xy 176.996844 -278.872982) (xy 176.98126 -278.919663) (xy 176.958389 -278.96324)
			(xy 176.928824 -279.002584) (xy 176.893331 -279.036676) (xy 176.852828 -279.064632) (xy 176.808366 -279.08573)
			(xy 176.761095 -279.099422) (xy 176.71224 -279.105354) (xy 176.663065 -279.103373) (xy 176.614846 -279.093529)
			(xy 176.56883 -279.076077) (xy 176.526209 -279.05147) (xy 176.488088 -279.020345) (xy 176.455453 -278.983508)
			(xy 176.42915 -278.941912) (xy 176.409859 -278.896636) (xy 176.398082 -278.848852) (xy 176.394122 -278.799798)
			(xy 176.076864 -278.799798) (xy 176.07636 -278.825506) (xy 176.068317 -278.876288) (xy 176.052429 -278.925187)
			(xy 176.029086 -278.970999) (xy 175.998865 -279.012595) (xy 175.962509 -279.048951) (xy 175.920913 -279.079172)
			(xy 175.875101 -279.102515) (xy 175.826202 -279.118403) (xy 175.77542 -279.126446) (xy 175.724004 -279.126446)
			(xy 175.673222 -279.118403) (xy 175.624323 -279.102515) (xy 175.578511 -279.079172) (xy 175.536915 -279.048951)
			(xy 175.500559 -279.012595) (xy 175.470338 -278.970999) (xy 175.446995 -278.925187) (xy 175.431107 -278.876288)
			(xy 175.423064 -278.825506) (xy 175.10464 -278.825506) (xy 175.096924 -278.872982) (xy 175.08134 -278.919663)
			(xy 175.058469 -278.96324) (xy 175.028904 -279.002584) (xy 174.993411 -279.036676) (xy 174.952908 -279.064632)
			(xy 174.908446 -279.08573) (xy 174.861175 -279.099422) (xy 174.81232 -279.105354) (xy 174.763145 -279.103373)
			(xy 174.714926 -279.093529) (xy 174.66891 -279.076077) (xy 174.626289 -279.05147) (xy 174.588168 -279.020345)
			(xy 174.555533 -278.983508) (xy 174.52923 -278.941912) (xy 174.509939 -278.896636) (xy 174.498162 -278.848852)
			(xy 174.494202 -278.799798) (xy 174.177198 -278.799798) (xy 174.176694 -278.825506) (xy 174.168651 -278.876288)
			(xy 174.152763 -278.925187) (xy 174.12942 -278.970999) (xy 174.099199 -279.012595) (xy 174.062843 -279.048951)
			(xy 174.021247 -279.079172) (xy 173.975435 -279.102515) (xy 173.926536 -279.118403) (xy 173.875754 -279.126446)
			(xy 173.824338 -279.126446) (xy 173.773556 -279.118403) (xy 173.724657 -279.102515) (xy 173.678845 -279.079172)
			(xy 173.637249 -279.048951) (xy 173.600893 -279.012595) (xy 173.570672 -278.970999) (xy 173.547329 -278.925187)
			(xy 173.531441 -278.876288) (xy 173.523398 -278.825506) (xy 173.20472 -278.825506) (xy 173.197004 -278.872982)
			(xy 173.18142 -278.919663) (xy 173.158549 -278.96324) (xy 173.128984 -279.002584) (xy 173.093491 -279.036676)
			(xy 173.052988 -279.064632) (xy 173.008526 -279.08573) (xy 172.961255 -279.099422) (xy 172.9124 -279.105354)
			(xy 172.863225 -279.103373) (xy 172.815006 -279.093529) (xy 172.76899 -279.076077) (xy 172.726369 -279.05147)
			(xy 172.688248 -279.020345) (xy 172.655613 -278.983508) (xy 172.62931 -278.941912) (xy 172.610019 -278.896636)
			(xy 172.598242 -278.848852) (xy 172.594282 -278.799798) (xy 172.277024 -278.799798) (xy 172.27652 -278.825506)
			(xy 172.268477 -278.876288) (xy 172.252589 -278.925187) (xy 172.229246 -278.970999) (xy 172.199025 -279.012595)
			(xy 172.162669 -279.048951) (xy 172.121073 -279.079172) (xy 172.075261 -279.102515) (xy 172.026362 -279.118403)
			(xy 171.97558 -279.126446) (xy 171.924164 -279.126446) (xy 171.873382 -279.118403) (xy 171.824483 -279.102515)
			(xy 171.778671 -279.079172) (xy 171.737075 -279.048951) (xy 171.700719 -279.012595) (xy 171.670498 -278.970999)
			(xy 171.647155 -278.925187) (xy 171.631267 -278.876288) (xy 171.623224 -278.825506) (xy 171.304546 -278.825506)
			(xy 171.29683 -278.872982) (xy 171.281246 -278.919663) (xy 171.258375 -278.96324) (xy 171.22881 -279.002584)
			(xy 171.193317 -279.036676) (xy 171.152814 -279.064632) (xy 171.108352 -279.08573) (xy 171.061081 -279.099422)
			(xy 171.012226 -279.105354) (xy 170.963051 -279.103373) (xy 170.914832 -279.093529) (xy 170.868816 -279.076077)
			(xy 170.826195 -279.05147) (xy 170.788074 -279.020345) (xy 170.755439 -278.983508) (xy 170.729136 -278.941912)
			(xy 170.709845 -278.896636) (xy 170.698068 -278.848852) (xy 170.694108 -278.799798) (xy 170.377104 -278.799798)
			(xy 170.3766 -278.825506) (xy 170.368557 -278.876288) (xy 170.352669 -278.925187) (xy 170.329326 -278.970999)
			(xy 170.299105 -279.012595) (xy 170.262749 -279.048951) (xy 170.221153 -279.079172) (xy 170.175341 -279.102515)
			(xy 170.126442 -279.118403) (xy 170.07566 -279.126446) (xy 170.024244 -279.126446) (xy 169.973462 -279.118403)
			(xy 169.924563 -279.102515) (xy 169.878751 -279.079172) (xy 169.837155 -279.048951) (xy 169.800799 -279.012595)
			(xy 169.770578 -278.970999) (xy 169.747235 -278.925187) (xy 169.731347 -278.876288) (xy 169.723304 -278.825506)
			(xy 169.404626 -278.825506) (xy 169.39691 -278.872982) (xy 169.381326 -278.919663) (xy 169.358455 -278.96324)
			(xy 169.32889 -279.002584) (xy 169.293397 -279.036676) (xy 169.252894 -279.064632) (xy 169.208432 -279.08573)
			(xy 169.161161 -279.099422) (xy 169.112306 -279.105354) (xy 169.063131 -279.103373) (xy 169.014912 -279.093529)
			(xy 168.968896 -279.076077) (xy 168.926275 -279.05147) (xy 168.888154 -279.020345) (xy 168.855519 -278.983508)
			(xy 168.829216 -278.941912) (xy 168.809925 -278.896636) (xy 168.798148 -278.848852) (xy 168.794188 -278.799798)
			(xy 168.477184 -278.799798) (xy 168.47668 -278.825506) (xy 168.468637 -278.876288) (xy 168.452749 -278.925187)
			(xy 168.429406 -278.970999) (xy 168.399185 -279.012595) (xy 168.362829 -279.048951) (xy 168.321233 -279.079172)
			(xy 168.275421 -279.102515) (xy 168.226522 -279.118403) (xy 168.17574 -279.126446) (xy 168.124324 -279.126446)
			(xy 168.073542 -279.118403) (xy 168.024643 -279.102515) (xy 167.978831 -279.079172) (xy 167.937235 -279.048951)
			(xy 167.900879 -279.012595) (xy 167.870658 -278.970999) (xy 167.847315 -278.925187) (xy 167.831427 -278.876288)
			(xy 167.823384 -278.825506) (xy 167.504706 -278.825506) (xy 167.49699 -278.872982) (xy 167.481406 -278.919663)
			(xy 167.458535 -278.96324) (xy 167.42897 -279.002584) (xy 167.393477 -279.036676) (xy 167.352974 -279.064632)
			(xy 167.308512 -279.08573) (xy 167.261241 -279.099422) (xy 167.212386 -279.105354) (xy 167.163211 -279.103373)
			(xy 167.114992 -279.093529) (xy 167.068976 -279.076077) (xy 167.026355 -279.05147) (xy 166.988234 -279.020345)
			(xy 166.955599 -278.983508) (xy 166.929296 -278.941912) (xy 166.910005 -278.896636) (xy 166.898228 -278.848852)
			(xy 166.894268 -278.799798) (xy 166.57701 -278.799798) (xy 166.576506 -278.825506) (xy 166.568463 -278.876288)
			(xy 166.552575 -278.925187) (xy 166.529232 -278.970999) (xy 166.499011 -279.012595) (xy 166.462655 -279.048951)
			(xy 166.421059 -279.079172) (xy 166.375247 -279.102515) (xy 166.326348 -279.118403) (xy 166.275566 -279.126446)
			(xy 166.22415 -279.126446) (xy 166.173368 -279.118403) (xy 166.124469 -279.102515) (xy 166.078657 -279.079172)
			(xy 166.037061 -279.048951) (xy 166.000705 -279.012595) (xy 165.970484 -278.970999) (xy 165.947141 -278.925187)
			(xy 165.931253 -278.876288) (xy 165.92321 -278.825506) (xy 165.604539 -278.825506) (xy 165.597257 -278.871368)
			(xy 165.582355 -278.917111) (xy 165.560465 -278.959952) (xy 165.532128 -278.99883) (xy 165.498045 -279.032784)
			(xy 165.45906 -279.060973) (xy 165.416136 -279.082699) (xy 165.370337 -279.097427) (xy 165.346634 -279.10155)
			(xy 165.327838 -279.104344) (xy 165.303708 -279.132792) (xy 165.303708 -279.394666) (xy 165.328092 -279.423114)
			(xy 165.347142 -279.425908) (xy 165.372701 -279.430162) (xy 165.422135 -279.445682) (xy 165.468504 -279.468801)
			(xy 165.510647 -279.498942) (xy 165.547512 -279.53535) (xy 165.578175 -279.577116) (xy 165.601869 -279.623193)
			(xy 165.618003 -279.67243) (xy 165.626172 -279.723594) (xy 165.626172 -279.749758) (xy 165.944054 -279.749758)
			(xy 165.948014 -279.700704) (xy 165.959791 -279.65292) (xy 165.979082 -279.607644) (xy 166.005385 -279.566048)
			(xy 166.03802 -279.529211) (xy 166.076141 -279.498086) (xy 166.118762 -279.473479) (xy 166.164778 -279.456027)
			(xy 166.212997 -279.446183) (xy 166.262172 -279.444202) (xy 166.311027 -279.450134) (xy 166.358298 -279.463826)
			(xy 166.40276 -279.484924) (xy 166.443263 -279.51288) (xy 166.478756 -279.546972) (xy 166.508321 -279.586316)
			(xy 166.531192 -279.629893) (xy 166.546776 -279.676574) (xy 166.554671 -279.725151) (xy 166.555166 -279.749758)
			(xy 166.554671 -279.774365) (xy 166.554533 -279.775212) (xy 166.873424 -279.775212) (xy 166.873424 -279.723796)
			(xy 166.881467 -279.673014) (xy 166.897355 -279.624115) (xy 166.920698 -279.578303) (xy 166.950919 -279.536707)
			(xy 166.987275 -279.500351) (xy 167.028871 -279.47013) (xy 167.074683 -279.446787) (xy 167.123582 -279.430899)
			(xy 167.174364 -279.422856) (xy 167.22578 -279.422856) (xy 167.276562 -279.430899) (xy 167.325461 -279.446787)
			(xy 167.371273 -279.47013) (xy 167.412869 -279.500351) (xy 167.449225 -279.536707) (xy 167.479446 -279.578303)
			(xy 167.502789 -279.624115) (xy 167.518677 -279.673014) (xy 167.52672 -279.723796) (xy 167.527224 -279.749504)
			(xy 167.527219 -279.749758) (xy 167.844228 -279.749758) (xy 167.848188 -279.700704) (xy 167.859965 -279.65292)
			(xy 167.879256 -279.607644) (xy 167.905559 -279.566048) (xy 167.938194 -279.529211) (xy 167.976315 -279.498086)
			(xy 168.018936 -279.473479) (xy 168.064952 -279.456027) (xy 168.113171 -279.446183) (xy 168.162346 -279.444202)
			(xy 168.211201 -279.450134) (xy 168.258472 -279.463826) (xy 168.302934 -279.484924) (xy 168.343437 -279.51288)
			(xy 168.37893 -279.546972) (xy 168.408495 -279.586316) (xy 168.431366 -279.629893) (xy 168.44695 -279.676574)
			(xy 168.454845 -279.725151) (xy 168.45534 -279.749758) (xy 168.454845 -279.774365) (xy 168.454707 -279.775212)
			(xy 168.773344 -279.775212) (xy 168.773344 -279.723796) (xy 168.781387 -279.673014) (xy 168.797275 -279.624115)
			(xy 168.820618 -279.578303) (xy 168.850839 -279.536707) (xy 168.887195 -279.500351) (xy 168.928791 -279.47013)
			(xy 168.974603 -279.446787) (xy 169.023502 -279.430899) (xy 169.074284 -279.422856) (xy 169.1257 -279.422856)
			(xy 169.176482 -279.430899) (xy 169.225381 -279.446787) (xy 169.271193 -279.47013) (xy 169.312789 -279.500351)
			(xy 169.349145 -279.536707) (xy 169.379366 -279.578303) (xy 169.402709 -279.624115) (xy 169.418597 -279.673014)
			(xy 169.42664 -279.723796) (xy 169.427144 -279.749504) (xy 169.427139 -279.749758) (xy 169.744148 -279.749758)
			(xy 169.748108 -279.700704) (xy 169.759885 -279.65292) (xy 169.779176 -279.607644) (xy 169.805479 -279.566048)
			(xy 169.838114 -279.529211) (xy 169.876235 -279.498086) (xy 169.918856 -279.473479) (xy 169.964872 -279.456027)
			(xy 170.013091 -279.446183) (xy 170.062266 -279.444202) (xy 170.111121 -279.450134) (xy 170.158392 -279.463826)
			(xy 170.202854 -279.484924) (xy 170.243357 -279.51288) (xy 170.27885 -279.546972) (xy 170.308415 -279.586316)
			(xy 170.331286 -279.629893) (xy 170.34687 -279.676574) (xy 170.354765 -279.725151) (xy 170.35526 -279.749758)
			(xy 170.354765 -279.774365) (xy 170.354627 -279.775212) (xy 170.673264 -279.775212) (xy 170.673264 -279.723796)
			(xy 170.681307 -279.673014) (xy 170.697195 -279.624115) (xy 170.720538 -279.578303) (xy 170.750759 -279.536707)
			(xy 170.787115 -279.500351) (xy 170.828711 -279.47013) (xy 170.874523 -279.446787) (xy 170.923422 -279.430899)
			(xy 170.974204 -279.422856) (xy 171.02562 -279.422856) (xy 171.076402 -279.430899) (xy 171.125301 -279.446787)
			(xy 171.171113 -279.47013) (xy 171.212709 -279.500351) (xy 171.249065 -279.536707) (xy 171.279286 -279.578303)
			(xy 171.302629 -279.624115) (xy 171.318517 -279.673014) (xy 171.32656 -279.723796) (xy 171.327064 -279.749504)
			(xy 171.327059 -279.749758) (xy 171.644068 -279.749758) (xy 171.648028 -279.700704) (xy 171.659805 -279.65292)
			(xy 171.679096 -279.607644) (xy 171.705399 -279.566048) (xy 171.738034 -279.529211) (xy 171.776155 -279.498086)
			(xy 171.818776 -279.473479) (xy 171.864792 -279.456027) (xy 171.913011 -279.446183) (xy 171.962186 -279.444202)
			(xy 172.011041 -279.450134) (xy 172.058312 -279.463826) (xy 172.102774 -279.484924) (xy 172.143277 -279.51288)
			(xy 172.17877 -279.546972) (xy 172.208335 -279.586316) (xy 172.231206 -279.629893) (xy 172.24679 -279.676574)
			(xy 172.254685 -279.725151) (xy 172.25518 -279.749758) (xy 172.254685 -279.774365) (xy 172.254547 -279.775212)
			(xy 172.573184 -279.775212) (xy 172.573184 -279.723796) (xy 172.581227 -279.673014) (xy 172.597115 -279.624115)
			(xy 172.620458 -279.578303) (xy 172.650679 -279.536707) (xy 172.687035 -279.500351) (xy 172.728631 -279.47013)
			(xy 172.774443 -279.446787) (xy 172.823342 -279.430899) (xy 172.874124 -279.422856) (xy 172.92554 -279.422856)
			(xy 172.976322 -279.430899) (xy 173.025221 -279.446787) (xy 173.071033 -279.47013) (xy 173.112629 -279.500351)
			(xy 173.148985 -279.536707) (xy 173.179206 -279.578303) (xy 173.202549 -279.624115) (xy 173.218437 -279.673014)
			(xy 173.22648 -279.723796) (xy 173.226984 -279.749504) (xy 173.226979 -279.749758) (xy 173.544242 -279.749758)
			(xy 173.548202 -279.700704) (xy 173.559979 -279.65292) (xy 173.57927 -279.607644) (xy 173.605573 -279.566048)
			(xy 173.638208 -279.529211) (xy 173.676329 -279.498086) (xy 173.71895 -279.473479) (xy 173.764966 -279.456027)
			(xy 173.813185 -279.446183) (xy 173.86236 -279.444202) (xy 173.911215 -279.450134) (xy 173.958486 -279.463826)
			(xy 174.002948 -279.484924) (xy 174.043451 -279.51288) (xy 174.078944 -279.546972) (xy 174.108509 -279.586316)
			(xy 174.13138 -279.629893) (xy 174.146964 -279.676574) (xy 174.154859 -279.725151) (xy 174.155354 -279.749758)
			(xy 174.154859 -279.774365) (xy 174.154721 -279.775212) (xy 174.473358 -279.775212) (xy 174.473358 -279.723796)
			(xy 174.481401 -279.673014) (xy 174.497289 -279.624115) (xy 174.520632 -279.578303) (xy 174.550853 -279.536707)
			(xy 174.587209 -279.500351) (xy 174.628805 -279.47013) (xy 174.674617 -279.446787) (xy 174.723516 -279.430899)
			(xy 174.774298 -279.422856) (xy 174.825714 -279.422856) (xy 174.876496 -279.430899) (xy 174.925395 -279.446787)
			(xy 174.971207 -279.47013) (xy 175.012803 -279.500351) (xy 175.049159 -279.536707) (xy 175.07938 -279.578303)
			(xy 175.102723 -279.624115) (xy 175.118611 -279.673014) (xy 175.126654 -279.723796) (xy 175.127158 -279.749504)
			(xy 175.127153 -279.749758) (xy 175.444162 -279.749758) (xy 175.448122 -279.700704) (xy 175.459899 -279.65292)
			(xy 175.47919 -279.607644) (xy 175.505493 -279.566048) (xy 175.538128 -279.529211) (xy 175.576249 -279.498086)
			(xy 175.61887 -279.473479) (xy 175.664886 -279.456027) (xy 175.713105 -279.446183) (xy 175.76228 -279.444202)
			(xy 175.811135 -279.450134) (xy 175.858406 -279.463826) (xy 175.902868 -279.484924) (xy 175.943371 -279.51288)
			(xy 175.978864 -279.546972) (xy 176.008429 -279.586316) (xy 176.0313 -279.629893) (xy 176.046884 -279.676574)
			(xy 176.054779 -279.725151) (xy 176.055274 -279.749758) (xy 176.054779 -279.774365) (xy 176.054641 -279.775212)
			(xy 176.373278 -279.775212) (xy 176.373278 -279.723796) (xy 176.381321 -279.673014) (xy 176.397209 -279.624115)
			(xy 176.420552 -279.578303) (xy 176.450773 -279.536707) (xy 176.487129 -279.500351) (xy 176.528725 -279.47013)
			(xy 176.574537 -279.446787) (xy 176.623436 -279.430899) (xy 176.674218 -279.422856) (xy 176.725634 -279.422856)
			(xy 176.776416 -279.430899) (xy 176.825315 -279.446787) (xy 176.871127 -279.47013) (xy 176.912723 -279.500351)
			(xy 176.949079 -279.536707) (xy 176.9793 -279.578303) (xy 177.002643 -279.624115) (xy 177.018531 -279.673014)
			(xy 177.026574 -279.723796) (xy 177.027078 -279.749504) (xy 177.027073 -279.749758) (xy 177.344082 -279.749758)
			(xy 177.348042 -279.700704) (xy 177.359819 -279.65292) (xy 177.37911 -279.607644) (xy 177.405413 -279.566048)
			(xy 177.438048 -279.529211) (xy 177.476169 -279.498086) (xy 177.51879 -279.473479) (xy 177.564806 -279.456027)
			(xy 177.613025 -279.446183) (xy 177.6622 -279.444202) (xy 177.711055 -279.450134) (xy 177.758326 -279.463826)
			(xy 177.802788 -279.484924) (xy 177.843291 -279.51288) (xy 177.878784 -279.546972) (xy 177.908349 -279.586316)
			(xy 177.93122 -279.629893) (xy 177.946804 -279.676574) (xy 177.954699 -279.725151) (xy 177.955194 -279.749758)
			(xy 177.954699 -279.774365) (xy 177.954561 -279.775212) (xy 178.273198 -279.775212) (xy 178.273198 -279.723796)
			(xy 178.281241 -279.673014) (xy 178.297129 -279.624115) (xy 178.320472 -279.578303) (xy 178.350693 -279.536707)
			(xy 178.387049 -279.500351) (xy 178.428645 -279.47013) (xy 178.474457 -279.446787) (xy 178.523356 -279.430899)
			(xy 178.574138 -279.422856) (xy 178.625554 -279.422856) (xy 178.676336 -279.430899) (xy 178.725235 -279.446787)
			(xy 178.771047 -279.47013) (xy 178.812643 -279.500351) (xy 178.848999 -279.536707) (xy 178.87922 -279.578303)
			(xy 178.902563 -279.624115) (xy 178.918451 -279.673014) (xy 178.926494 -279.723796) (xy 178.926998 -279.749504)
			(xy 178.926993 -279.749758) (xy 179.244256 -279.749758) (xy 179.248216 -279.700704) (xy 179.259993 -279.65292)
			(xy 179.279284 -279.607644) (xy 179.305587 -279.566048) (xy 179.338222 -279.529211) (xy 179.376343 -279.498086)
			(xy 179.418964 -279.473479) (xy 179.46498 -279.456027) (xy 179.513199 -279.446183) (xy 179.562374 -279.444202)
			(xy 179.611229 -279.450134) (xy 179.6585 -279.463826) (xy 179.702962 -279.484924) (xy 179.743465 -279.51288)
			(xy 179.778958 -279.546972) (xy 179.808523 -279.586316) (xy 179.831394 -279.629893) (xy 179.846978 -279.676574)
			(xy 179.854873 -279.725151) (xy 179.855368 -279.749758) (xy 179.854873 -279.774365) (xy 179.854735 -279.775212)
			(xy 180.173372 -279.775212) (xy 180.173372 -279.723796) (xy 180.181415 -279.673014) (xy 180.197303 -279.624115)
			(xy 180.220646 -279.578303) (xy 180.250867 -279.536707) (xy 180.287223 -279.500351) (xy 180.328819 -279.47013)
			(xy 180.374631 -279.446787) (xy 180.42353 -279.430899) (xy 180.474312 -279.422856) (xy 180.525728 -279.422856)
			(xy 180.57651 -279.430899) (xy 180.625409 -279.446787) (xy 180.671221 -279.47013) (xy 180.712817 -279.500351)
			(xy 180.749173 -279.536707) (xy 180.779394 -279.578303) (xy 180.802737 -279.624115) (xy 180.818625 -279.673014)
			(xy 180.826668 -279.723796) (xy 180.827172 -279.749504) (xy 180.827167 -279.749758) (xy 181.144176 -279.749758)
			(xy 181.148136 -279.700704) (xy 181.159913 -279.65292) (xy 181.179204 -279.607644) (xy 181.205507 -279.566048)
			(xy 181.238142 -279.529211) (xy 181.276263 -279.498086) (xy 181.318884 -279.473479) (xy 181.3649 -279.456027)
			(xy 181.413119 -279.446183) (xy 181.462294 -279.444202) (xy 181.511149 -279.450134) (xy 181.55842 -279.463826)
			(xy 181.602882 -279.484924) (xy 181.643385 -279.51288) (xy 181.678878 -279.546972) (xy 181.708443 -279.586316)
			(xy 181.731314 -279.629893) (xy 181.746898 -279.676574) (xy 181.754793 -279.725151) (xy 181.755288 -279.749758)
			(xy 181.754793 -279.774365) (xy 181.754655 -279.775212) (xy 182.073292 -279.775212) (xy 182.073292 -279.723796)
			(xy 182.081335 -279.673014) (xy 182.097223 -279.624115) (xy 182.120566 -279.578303) (xy 182.150787 -279.536707)
			(xy 182.187143 -279.500351) (xy 182.228739 -279.47013) (xy 182.274551 -279.446787) (xy 182.32345 -279.430899)
			(xy 182.374232 -279.422856) (xy 182.425648 -279.422856) (xy 182.47643 -279.430899) (xy 182.525329 -279.446787)
			(xy 182.571141 -279.47013) (xy 182.612737 -279.500351) (xy 182.649093 -279.536707) (xy 182.679314 -279.578303)
			(xy 182.702657 -279.624115) (xy 182.718545 -279.673014) (xy 182.726588 -279.723796) (xy 182.727092 -279.749504)
			(xy 182.727087 -279.749758) (xy 183.044096 -279.749758) (xy 183.048056 -279.700704) (xy 183.059833 -279.65292)
			(xy 183.079124 -279.607644) (xy 183.105427 -279.566048) (xy 183.138062 -279.529211) (xy 183.176183 -279.498086)
			(xy 183.218804 -279.473479) (xy 183.26482 -279.456027) (xy 183.313039 -279.446183) (xy 183.362214 -279.444202)
			(xy 183.411069 -279.450134) (xy 183.45834 -279.463826) (xy 183.502802 -279.484924) (xy 183.543305 -279.51288)
			(xy 183.578798 -279.546972) (xy 183.608363 -279.586316) (xy 183.631234 -279.629893) (xy 183.646818 -279.676574)
			(xy 183.654713 -279.725151) (xy 183.655208 -279.749758) (xy 183.654713 -279.774365) (xy 183.654575 -279.775212)
			(xy 183.973212 -279.775212) (xy 183.973212 -279.723796) (xy 183.981255 -279.673014) (xy 183.997143 -279.624115)
			(xy 184.020486 -279.578303) (xy 184.050707 -279.536707) (xy 184.087063 -279.500351) (xy 184.128659 -279.47013)
			(xy 184.174471 -279.446787) (xy 184.22337 -279.430899) (xy 184.274152 -279.422856) (xy 184.325568 -279.422856)
			(xy 184.37635 -279.430899) (xy 184.425249 -279.446787) (xy 184.471061 -279.47013) (xy 184.512657 -279.500351)
			(xy 184.549013 -279.536707) (xy 184.579234 -279.578303) (xy 184.602577 -279.624115) (xy 184.618465 -279.673014)
			(xy 184.626508 -279.723796) (xy 184.627012 -279.749504) (xy 184.627007 -279.749758) (xy 184.94427 -279.749758)
			(xy 184.94823 -279.700704) (xy 184.960007 -279.65292) (xy 184.979298 -279.607644) (xy 185.005601 -279.566048)
			(xy 185.038236 -279.529211) (xy 185.076357 -279.498086) (xy 185.118978 -279.473479) (xy 185.164994 -279.456027)
			(xy 185.213213 -279.446183) (xy 185.262388 -279.444202) (xy 185.311243 -279.450134) (xy 185.358514 -279.463826)
			(xy 185.402976 -279.484924) (xy 185.443479 -279.51288) (xy 185.478972 -279.546972) (xy 185.508537 -279.586316)
			(xy 185.531408 -279.629893) (xy 185.546992 -279.676574) (xy 185.554887 -279.725151) (xy 185.555382 -279.749758)
			(xy 185.554887 -279.774365) (xy 185.554749 -279.775212) (xy 185.873386 -279.775212) (xy 185.873386 -279.723796)
			(xy 185.881429 -279.673014) (xy 185.897317 -279.624115) (xy 185.92066 -279.578303) (xy 185.950881 -279.536707)
			(xy 185.987237 -279.500351) (xy 186.028833 -279.47013) (xy 186.074645 -279.446787) (xy 186.123544 -279.430899)
			(xy 186.174326 -279.422856) (xy 186.225742 -279.422856) (xy 186.276524 -279.430899) (xy 186.325423 -279.446787)
			(xy 186.371235 -279.47013) (xy 186.412831 -279.500351) (xy 186.449187 -279.536707) (xy 186.479408 -279.578303)
			(xy 186.502751 -279.624115) (xy 186.518639 -279.673014) (xy 186.526682 -279.723796) (xy 186.527186 -279.749504)
			(xy 186.527181 -279.749758) (xy 186.84419 -279.749758) (xy 186.84815 -279.700704) (xy 186.859927 -279.65292)
			(xy 186.879218 -279.607644) (xy 186.905521 -279.566048) (xy 186.938156 -279.529211) (xy 186.976277 -279.498086)
			(xy 187.018898 -279.473479) (xy 187.064914 -279.456027) (xy 187.113133 -279.446183) (xy 187.162308 -279.444202)
			(xy 187.211163 -279.450134) (xy 187.258434 -279.463826) (xy 187.302896 -279.484924) (xy 187.343399 -279.51288)
			(xy 187.378892 -279.546972) (xy 187.408457 -279.586316) (xy 187.431328 -279.629893) (xy 187.446912 -279.676574)
			(xy 187.454807 -279.725151) (xy 187.455302 -279.749758) (xy 187.454807 -279.774365) (xy 187.454669 -279.775212)
			(xy 187.773306 -279.775212) (xy 187.773306 -279.723796) (xy 187.781349 -279.673014) (xy 187.797237 -279.624115)
			(xy 187.82058 -279.578303) (xy 187.850801 -279.536707) (xy 187.887157 -279.500351) (xy 187.928753 -279.47013)
			(xy 187.974565 -279.446787) (xy 188.023464 -279.430899) (xy 188.074246 -279.422856) (xy 188.125662 -279.422856)
			(xy 188.176444 -279.430899) (xy 188.225343 -279.446787) (xy 188.271155 -279.47013) (xy 188.312751 -279.500351)
			(xy 188.349107 -279.536707) (xy 188.379328 -279.578303) (xy 188.402671 -279.624115) (xy 188.418559 -279.673014)
			(xy 188.426602 -279.723796) (xy 188.427106 -279.749504) (xy 188.427101 -279.749758) (xy 188.74411 -279.749758)
			(xy 188.74807 -279.700704) (xy 188.759847 -279.65292) (xy 188.779138 -279.607644) (xy 188.805441 -279.566048)
			(xy 188.838076 -279.529211) (xy 188.876197 -279.498086) (xy 188.918818 -279.473479) (xy 188.964834 -279.456027)
			(xy 189.013053 -279.446183) (xy 189.062228 -279.444202) (xy 189.111083 -279.450134) (xy 189.158354 -279.463826)
			(xy 189.202816 -279.484924) (xy 189.243319 -279.51288) (xy 189.278812 -279.546972) (xy 189.308377 -279.586316)
			(xy 189.331248 -279.629893) (xy 189.346832 -279.676574) (xy 189.354727 -279.725151) (xy 189.355222 -279.749758)
			(xy 189.354727 -279.774365) (xy 189.354589 -279.775212) (xy 189.673226 -279.775212) (xy 189.673226 -279.723796)
			(xy 189.681269 -279.673014) (xy 189.697157 -279.624115) (xy 189.7205 -279.578303) (xy 189.750721 -279.536707)
			(xy 189.787077 -279.500351) (xy 189.828673 -279.47013) (xy 189.874485 -279.446787) (xy 189.923384 -279.430899)
			(xy 189.974166 -279.422856) (xy 190.025582 -279.422856) (xy 190.076364 -279.430899) (xy 190.125263 -279.446787)
			(xy 190.171075 -279.47013) (xy 190.212671 -279.500351) (xy 190.249027 -279.536707) (xy 190.279248 -279.578303)
			(xy 190.302591 -279.624115) (xy 190.318479 -279.673014) (xy 190.326522 -279.723796) (xy 190.327026 -279.749504)
			(xy 190.327021 -279.749758) (xy 190.64403 -279.749758) (xy 190.64799 -279.700704) (xy 190.659767 -279.65292)
			(xy 190.679058 -279.607644) (xy 190.705361 -279.566048) (xy 190.737996 -279.529211) (xy 190.776117 -279.498086)
			(xy 190.818738 -279.473479) (xy 190.864754 -279.456027) (xy 190.912973 -279.446183) (xy 190.962148 -279.444202)
			(xy 191.011003 -279.450134) (xy 191.058274 -279.463826) (xy 191.102736 -279.484924) (xy 191.143239 -279.51288)
			(xy 191.178732 -279.546972) (xy 191.208297 -279.586316) (xy 191.231168 -279.629893) (xy 191.246752 -279.676574)
			(xy 191.254647 -279.725151) (xy 191.255142 -279.749758) (xy 191.254647 -279.774365) (xy 191.254509 -279.775212)
			(xy 191.5734 -279.775212) (xy 191.5734 -279.723796) (xy 191.581443 -279.673014) (xy 191.597331 -279.624115)
			(xy 191.620674 -279.578303) (xy 191.650895 -279.536707) (xy 191.687251 -279.500351) (xy 191.728847 -279.47013)
			(xy 191.774659 -279.446787) (xy 191.823558 -279.430899) (xy 191.87434 -279.422856) (xy 191.925756 -279.422856)
			(xy 191.976538 -279.430899) (xy 192.025437 -279.446787) (xy 192.071249 -279.47013) (xy 192.112845 -279.500351)
			(xy 192.149201 -279.536707) (xy 192.179422 -279.578303) (xy 192.202765 -279.624115) (xy 192.218653 -279.673014)
			(xy 192.226696 -279.723796) (xy 192.2272 -279.749504) (xy 192.227195 -279.749758) (xy 192.544204 -279.749758)
			(xy 192.548164 -279.700704) (xy 192.559941 -279.65292) (xy 192.579232 -279.607644) (xy 192.605535 -279.566048)
			(xy 192.63817 -279.529211) (xy 192.676291 -279.498086) (xy 192.718912 -279.473479) (xy 192.764928 -279.456027)
			(xy 192.813147 -279.446183) (xy 192.862322 -279.444202) (xy 192.911177 -279.450134) (xy 192.958448 -279.463826)
			(xy 193.00291 -279.484924) (xy 193.043413 -279.51288) (xy 193.078906 -279.546972) (xy 193.108471 -279.586316)
			(xy 193.131342 -279.629893) (xy 193.146926 -279.676574) (xy 193.154821 -279.725151) (xy 193.155316 -279.749758)
			(xy 193.154821 -279.774365) (xy 193.154683 -279.775212) (xy 193.47332 -279.775212) (xy 193.47332 -279.723796)
			(xy 193.481363 -279.673014) (xy 193.497251 -279.624115) (xy 193.520594 -279.578303) (xy 193.550815 -279.536707)
			(xy 193.587171 -279.500351) (xy 193.628767 -279.47013) (xy 193.674579 -279.446787) (xy 193.723478 -279.430899)
			(xy 193.77426 -279.422856) (xy 193.825676 -279.422856) (xy 193.876458 -279.430899) (xy 193.925357 -279.446787)
			(xy 193.971169 -279.47013) (xy 194.012765 -279.500351) (xy 194.049121 -279.536707) (xy 194.079342 -279.578303)
			(xy 194.102685 -279.624115) (xy 194.118573 -279.673014) (xy 194.126616 -279.723796) (xy 194.12712 -279.749504)
			(xy 194.127115 -279.749758) (xy 194.444124 -279.749758) (xy 194.448084 -279.700704) (xy 194.459861 -279.65292)
			(xy 194.479152 -279.607644) (xy 194.505455 -279.566048) (xy 194.53809 -279.529211) (xy 194.576211 -279.498086)
			(xy 194.618832 -279.473479) (xy 194.664848 -279.456027) (xy 194.713067 -279.446183) (xy 194.762242 -279.444202)
			(xy 194.811097 -279.450134) (xy 194.858368 -279.463826) (xy 194.90283 -279.484924) (xy 194.943333 -279.51288)
			(xy 194.978826 -279.546972) (xy 195.008391 -279.586316) (xy 195.031262 -279.629893) (xy 195.046846 -279.676574)
			(xy 195.054741 -279.725151) (xy 195.055236 -279.749758) (xy 195.054741 -279.774365) (xy 195.054562 -279.775466)
			(xy 195.37324 -279.775466) (xy 195.37324 -279.72405) (xy 195.381283 -279.673268) (xy 195.397171 -279.624369)
			(xy 195.420514 -279.578557) (xy 195.450735 -279.536961) (xy 195.487091 -279.500605) (xy 195.528687 -279.470384)
			(xy 195.574499 -279.447041) (xy 195.623398 -279.431153) (xy 195.67418 -279.42311) (xy 195.725596 -279.42311)
			(xy 195.776378 -279.431153) (xy 195.825277 -279.447041) (xy 195.871089 -279.470384) (xy 195.912685 -279.500605)
			(xy 195.949041 -279.536961) (xy 195.979262 -279.578557) (xy 196.002605 -279.624369) (xy 196.018493 -279.673268)
			(xy 196.026536 -279.72405) (xy 196.02704 -279.749758) (xy 196.344044 -279.749758) (xy 196.348004 -279.700704)
			(xy 196.359781 -279.65292) (xy 196.379072 -279.607644) (xy 196.405375 -279.566048) (xy 196.43801 -279.529211)
			(xy 196.476131 -279.498086) (xy 196.518752 -279.473479) (xy 196.564768 -279.456027) (xy 196.612987 -279.446183)
			(xy 196.662162 -279.444202) (xy 196.711017 -279.450134) (xy 196.758288 -279.463826) (xy 196.80275 -279.484924)
			(xy 196.843253 -279.51288) (xy 196.878746 -279.546972) (xy 196.908311 -279.586316) (xy 196.931182 -279.629893)
			(xy 196.946766 -279.676574) (xy 196.954661 -279.725151) (xy 196.955156 -279.749758) (xy 196.954661 -279.774365)
			(xy 196.954482 -279.775466) (xy 197.273414 -279.775466) (xy 197.273414 -279.72405) (xy 197.281457 -279.673268)
			(xy 197.297345 -279.624369) (xy 197.320688 -279.578557) (xy 197.350909 -279.536961) (xy 197.387265 -279.500605)
			(xy 197.428861 -279.470384) (xy 197.474673 -279.447041) (xy 197.523572 -279.431153) (xy 197.574354 -279.42311)
			(xy 197.62577 -279.42311) (xy 197.676552 -279.431153) (xy 197.725451 -279.447041) (xy 197.771263 -279.470384)
			(xy 197.812859 -279.500605) (xy 197.849215 -279.536961) (xy 197.879436 -279.578557) (xy 197.902779 -279.624369)
			(xy 197.918667 -279.673268) (xy 197.92671 -279.72405) (xy 197.927214 -279.749758) (xy 197.92671 -279.775466)
			(xy 198.223374 -279.775466) (xy 198.223374 -279.72405) (xy 198.231417 -279.673268) (xy 198.247305 -279.624369)
			(xy 198.270648 -279.578557) (xy 198.300869 -279.536961) (xy 198.337225 -279.500605) (xy 198.378821 -279.470384)
			(xy 198.424633 -279.447041) (xy 198.473532 -279.431153) (xy 198.524314 -279.42311) (xy 198.57573 -279.42311)
			(xy 198.626512 -279.431153) (xy 198.675411 -279.447041) (xy 198.721223 -279.470384) (xy 198.762819 -279.500605)
			(xy 198.799175 -279.536961) (xy 198.829396 -279.578557) (xy 198.852739 -279.624369) (xy 198.868627 -279.673268)
			(xy 198.87667 -279.72405) (xy 198.877174 -279.749758) (xy 198.877169 -279.750012) (xy 199.194432 -279.750012)
			(xy 199.198392 -279.700958) (xy 199.210169 -279.653174) (xy 199.22946 -279.607898) (xy 199.255763 -279.566302)
			(xy 199.288398 -279.529465) (xy 199.326519 -279.49834) (xy 199.36914 -279.473733) (xy 199.415156 -279.456281)
			(xy 199.463375 -279.446437) (xy 199.51255 -279.444456) (xy 199.561405 -279.450388) (xy 199.608676 -279.46408)
			(xy 199.653138 -279.485178) (xy 199.693641 -279.513134) (xy 199.729134 -279.547226) (xy 199.758699 -279.58657)
			(xy 199.78157 -279.630147) (xy 199.797154 -279.676828) (xy 199.805049 -279.725405) (xy 199.805544 -279.750012)
			(xy 199.805049 -279.774619) (xy 199.797154 -279.823196) (xy 199.78157 -279.869877) (xy 199.758699 -279.913454)
			(xy 199.729134 -279.952798) (xy 199.693641 -279.98689) (xy 199.653138 -280.014846) (xy 199.608676 -280.035944)
			(xy 199.561405 -280.049636) (xy 199.51255 -280.055568) (xy 199.463375 -280.053587) (xy 199.415156 -280.043743)
			(xy 199.36914 -280.026291) (xy 199.326519 -280.001684) (xy 199.288398 -279.970559) (xy 199.255763 -279.933722)
			(xy 199.22946 -279.892126) (xy 199.210169 -279.84685) (xy 199.198392 -279.799066) (xy 199.194432 -279.750012)
			(xy 198.877169 -279.750012) (xy 198.87667 -279.775466) (xy 198.868627 -279.826248) (xy 198.852739 -279.875147)
			(xy 198.829396 -279.920959) (xy 198.799175 -279.962555) (xy 198.762819 -279.998911) (xy 198.721223 -280.029132)
			(xy 198.675411 -280.052475) (xy 198.626512 -280.068363) (xy 198.57573 -280.076406) (xy 198.524314 -280.076406)
			(xy 198.473532 -280.068363) (xy 198.424633 -280.052475) (xy 198.378821 -280.029132) (xy 198.337225 -279.998911)
			(xy 198.300869 -279.962555) (xy 198.270648 -279.920959) (xy 198.247305 -279.875147) (xy 198.231417 -279.826248)
			(xy 198.223374 -279.775466) (xy 197.92671 -279.775466) (xy 197.918667 -279.826248) (xy 197.902779 -279.875147)
			(xy 197.879436 -279.920959) (xy 197.849215 -279.962555) (xy 197.812859 -279.998911) (xy 197.771263 -280.029132)
			(xy 197.725451 -280.052475) (xy 197.676552 -280.068363) (xy 197.62577 -280.076406) (xy 197.574354 -280.076406)
			(xy 197.523572 -280.068363) (xy 197.474673 -280.052475) (xy 197.428861 -280.029132) (xy 197.387265 -279.998911)
			(xy 197.350909 -279.962555) (xy 197.320688 -279.920959) (xy 197.297345 -279.875147) (xy 197.281457 -279.826248)
			(xy 197.273414 -279.775466) (xy 196.954482 -279.775466) (xy 196.946766 -279.822942) (xy 196.931182 -279.869623)
			(xy 196.908311 -279.9132) (xy 196.878746 -279.952544) (xy 196.843253 -279.986636) (xy 196.80275 -280.014592)
			(xy 196.758288 -280.03569) (xy 196.711017 -280.049382) (xy 196.662162 -280.055314) (xy 196.612987 -280.053333)
			(xy 196.564768 -280.043489) (xy 196.518752 -280.026037) (xy 196.476131 -280.00143) (xy 196.43801 -279.970305)
			(xy 196.405375 -279.933468) (xy 196.379072 -279.891872) (xy 196.359781 -279.846596) (xy 196.348004 -279.798812)
			(xy 196.344044 -279.749758) (xy 196.02704 -279.749758) (xy 196.026536 -279.775466) (xy 196.018493 -279.826248)
			(xy 196.002605 -279.875147) (xy 195.979262 -279.920959) (xy 195.949041 -279.962555) (xy 195.912685 -279.998911)
			(xy 195.871089 -280.029132) (xy 195.825277 -280.052475) (xy 195.776378 -280.068363) (xy 195.725596 -280.076406)
			(xy 195.67418 -280.076406) (xy 195.623398 -280.068363) (xy 195.574499 -280.052475) (xy 195.528687 -280.029132)
			(xy 195.487091 -279.998911) (xy 195.450735 -279.962555) (xy 195.420514 -279.920959) (xy 195.397171 -279.875147)
			(xy 195.381283 -279.826248) (xy 195.37324 -279.775466) (xy 195.054562 -279.775466) (xy 195.046846 -279.822942)
			(xy 195.031262 -279.869623) (xy 195.008391 -279.9132) (xy 194.978826 -279.952544) (xy 194.943333 -279.986636)
			(xy 194.90283 -280.014592) (xy 194.858368 -280.03569) (xy 194.811097 -280.049382) (xy 194.762242 -280.055314)
			(xy 194.713067 -280.053333) (xy 194.664848 -280.043489) (xy 194.618832 -280.026037) (xy 194.576211 -280.00143)
			(xy 194.53809 -279.970305) (xy 194.505455 -279.933468) (xy 194.479152 -279.891872) (xy 194.459861 -279.846596)
			(xy 194.448084 -279.798812) (xy 194.444124 -279.749758) (xy 194.127115 -279.749758) (xy 194.126616 -279.775212)
			(xy 194.118573 -279.825994) (xy 194.102685 -279.874893) (xy 194.079342 -279.920705) (xy 194.049121 -279.962301)
			(xy 194.012765 -279.998657) (xy 193.971169 -280.028878) (xy 193.925357 -280.052221) (xy 193.876458 -280.068109)
			(xy 193.825676 -280.076152) (xy 193.77426 -280.076152) (xy 193.723478 -280.068109) (xy 193.674579 -280.052221)
			(xy 193.628767 -280.028878) (xy 193.587171 -279.998657) (xy 193.550815 -279.962301) (xy 193.520594 -279.920705)
			(xy 193.497251 -279.874893) (xy 193.481363 -279.825994) (xy 193.47332 -279.775212) (xy 193.154683 -279.775212)
			(xy 193.146926 -279.822942) (xy 193.131342 -279.869623) (xy 193.108471 -279.9132) (xy 193.078906 -279.952544)
			(xy 193.043413 -279.986636) (xy 193.00291 -280.014592) (xy 192.958448 -280.03569) (xy 192.911177 -280.049382)
			(xy 192.862322 -280.055314) (xy 192.813147 -280.053333) (xy 192.764928 -280.043489) (xy 192.718912 -280.026037)
			(xy 192.676291 -280.00143) (xy 192.63817 -279.970305) (xy 192.605535 -279.933468) (xy 192.579232 -279.891872)
			(xy 192.559941 -279.846596) (xy 192.548164 -279.798812) (xy 192.544204 -279.749758) (xy 192.227195 -279.749758)
			(xy 192.226696 -279.775212) (xy 192.218653 -279.825994) (xy 192.202765 -279.874893) (xy 192.179422 -279.920705)
			(xy 192.149201 -279.962301) (xy 192.112845 -279.998657) (xy 192.071249 -280.028878) (xy 192.025437 -280.052221)
			(xy 191.976538 -280.068109) (xy 191.925756 -280.076152) (xy 191.87434 -280.076152) (xy 191.823558 -280.068109)
			(xy 191.774659 -280.052221) (xy 191.728847 -280.028878) (xy 191.687251 -279.998657) (xy 191.650895 -279.962301)
			(xy 191.620674 -279.920705) (xy 191.597331 -279.874893) (xy 191.581443 -279.825994) (xy 191.5734 -279.775212)
			(xy 191.254509 -279.775212) (xy 191.246752 -279.822942) (xy 191.231168 -279.869623) (xy 191.208297 -279.9132)
			(xy 191.178732 -279.952544) (xy 191.143239 -279.986636) (xy 191.102736 -280.014592) (xy 191.058274 -280.03569)
			(xy 191.011003 -280.049382) (xy 190.962148 -280.055314) (xy 190.912973 -280.053333) (xy 190.864754 -280.043489)
			(xy 190.818738 -280.026037) (xy 190.776117 -280.00143) (xy 190.737996 -279.970305) (xy 190.705361 -279.933468)
			(xy 190.679058 -279.891872) (xy 190.659767 -279.846596) (xy 190.64799 -279.798812) (xy 190.64403 -279.749758)
			(xy 190.327021 -279.749758) (xy 190.326522 -279.775212) (xy 190.318479 -279.825994) (xy 190.302591 -279.874893)
			(xy 190.279248 -279.920705) (xy 190.249027 -279.962301) (xy 190.212671 -279.998657) (xy 190.171075 -280.028878)
			(xy 190.125263 -280.052221) (xy 190.076364 -280.068109) (xy 190.025582 -280.076152) (xy 189.974166 -280.076152)
			(xy 189.923384 -280.068109) (xy 189.874485 -280.052221) (xy 189.828673 -280.028878) (xy 189.787077 -279.998657)
			(xy 189.750721 -279.962301) (xy 189.7205 -279.920705) (xy 189.697157 -279.874893) (xy 189.681269 -279.825994)
			(xy 189.673226 -279.775212) (xy 189.354589 -279.775212) (xy 189.346832 -279.822942) (xy 189.331248 -279.869623)
			(xy 189.308377 -279.9132) (xy 189.278812 -279.952544) (xy 189.243319 -279.986636) (xy 189.202816 -280.014592)
			(xy 189.158354 -280.03569) (xy 189.111083 -280.049382) (xy 189.062228 -280.055314) (xy 189.013053 -280.053333)
			(xy 188.964834 -280.043489) (xy 188.918818 -280.026037) (xy 188.876197 -280.00143) (xy 188.838076 -279.970305)
			(xy 188.805441 -279.933468) (xy 188.779138 -279.891872) (xy 188.759847 -279.846596) (xy 188.74807 -279.798812)
			(xy 188.74411 -279.749758) (xy 188.427101 -279.749758) (xy 188.426602 -279.775212) (xy 188.418559 -279.825994)
			(xy 188.402671 -279.874893) (xy 188.379328 -279.920705) (xy 188.349107 -279.962301) (xy 188.312751 -279.998657)
			(xy 188.271155 -280.028878) (xy 188.225343 -280.052221) (xy 188.176444 -280.068109) (xy 188.125662 -280.076152)
			(xy 188.074246 -280.076152) (xy 188.023464 -280.068109) (xy 187.974565 -280.052221) (xy 187.928753 -280.028878)
			(xy 187.887157 -279.998657) (xy 187.850801 -279.962301) (xy 187.82058 -279.920705) (xy 187.797237 -279.874893)
			(xy 187.781349 -279.825994) (xy 187.773306 -279.775212) (xy 187.454669 -279.775212) (xy 187.446912 -279.822942)
			(xy 187.431328 -279.869623) (xy 187.408457 -279.9132) (xy 187.378892 -279.952544) (xy 187.343399 -279.986636)
			(xy 187.302896 -280.014592) (xy 187.258434 -280.03569) (xy 187.211163 -280.049382) (xy 187.162308 -280.055314)
			(xy 187.113133 -280.053333) (xy 187.064914 -280.043489) (xy 187.018898 -280.026037) (xy 186.976277 -280.00143)
			(xy 186.938156 -279.970305) (xy 186.905521 -279.933468) (xy 186.879218 -279.891872) (xy 186.859927 -279.846596)
			(xy 186.84815 -279.798812) (xy 186.84419 -279.749758) (xy 186.527181 -279.749758) (xy 186.526682 -279.775212)
			(xy 186.518639 -279.825994) (xy 186.502751 -279.874893) (xy 186.479408 -279.920705) (xy 186.449187 -279.962301)
			(xy 186.412831 -279.998657) (xy 186.371235 -280.028878) (xy 186.325423 -280.052221) (xy 186.276524 -280.068109)
			(xy 186.225742 -280.076152) (xy 186.174326 -280.076152) (xy 186.123544 -280.068109) (xy 186.074645 -280.052221)
			(xy 186.028833 -280.028878) (xy 185.987237 -279.998657) (xy 185.950881 -279.962301) (xy 185.92066 -279.920705)
			(xy 185.897317 -279.874893) (xy 185.881429 -279.825994) (xy 185.873386 -279.775212) (xy 185.554749 -279.775212)
			(xy 185.546992 -279.822942) (xy 185.531408 -279.869623) (xy 185.508537 -279.9132) (xy 185.478972 -279.952544)
			(xy 185.443479 -279.986636) (xy 185.402976 -280.014592) (xy 185.358514 -280.03569) (xy 185.311243 -280.049382)
			(xy 185.262388 -280.055314) (xy 185.213213 -280.053333) (xy 185.164994 -280.043489) (xy 185.118978 -280.026037)
			(xy 185.076357 -280.00143) (xy 185.038236 -279.970305) (xy 185.005601 -279.933468) (xy 184.979298 -279.891872)
			(xy 184.960007 -279.846596) (xy 184.94823 -279.798812) (xy 184.94427 -279.749758) (xy 184.627007 -279.749758)
			(xy 184.626508 -279.775212) (xy 184.618465 -279.825994) (xy 184.602577 -279.874893) (xy 184.579234 -279.920705)
			(xy 184.549013 -279.962301) (xy 184.512657 -279.998657) (xy 184.471061 -280.028878) (xy 184.425249 -280.052221)
			(xy 184.37635 -280.068109) (xy 184.325568 -280.076152) (xy 184.274152 -280.076152) (xy 184.22337 -280.068109)
			(xy 184.174471 -280.052221) (xy 184.128659 -280.028878) (xy 184.087063 -279.998657) (xy 184.050707 -279.962301)
			(xy 184.020486 -279.920705) (xy 183.997143 -279.874893) (xy 183.981255 -279.825994) (xy 183.973212 -279.775212)
			(xy 183.654575 -279.775212) (xy 183.646818 -279.822942) (xy 183.631234 -279.869623) (xy 183.608363 -279.9132)
			(xy 183.578798 -279.952544) (xy 183.543305 -279.986636) (xy 183.502802 -280.014592) (xy 183.45834 -280.03569)
			(xy 183.411069 -280.049382) (xy 183.362214 -280.055314) (xy 183.313039 -280.053333) (xy 183.26482 -280.043489)
			(xy 183.218804 -280.026037) (xy 183.176183 -280.00143) (xy 183.138062 -279.970305) (xy 183.105427 -279.933468)
			(xy 183.079124 -279.891872) (xy 183.059833 -279.846596) (xy 183.048056 -279.798812) (xy 183.044096 -279.749758)
			(xy 182.727087 -279.749758) (xy 182.726588 -279.775212) (xy 182.718545 -279.825994) (xy 182.702657 -279.874893)
			(xy 182.679314 -279.920705) (xy 182.649093 -279.962301) (xy 182.612737 -279.998657) (xy 182.571141 -280.028878)
			(xy 182.525329 -280.052221) (xy 182.47643 -280.068109) (xy 182.425648 -280.076152) (xy 182.374232 -280.076152)
			(xy 182.32345 -280.068109) (xy 182.274551 -280.052221) (xy 182.228739 -280.028878) (xy 182.187143 -279.998657)
			(xy 182.150787 -279.962301) (xy 182.120566 -279.920705) (xy 182.097223 -279.874893) (xy 182.081335 -279.825994)
			(xy 182.073292 -279.775212) (xy 181.754655 -279.775212) (xy 181.746898 -279.822942) (xy 181.731314 -279.869623)
			(xy 181.708443 -279.9132) (xy 181.678878 -279.952544) (xy 181.643385 -279.986636) (xy 181.602882 -280.014592)
			(xy 181.55842 -280.03569) (xy 181.511149 -280.049382) (xy 181.462294 -280.055314) (xy 181.413119 -280.053333)
			(xy 181.3649 -280.043489) (xy 181.318884 -280.026037) (xy 181.276263 -280.00143) (xy 181.238142 -279.970305)
			(xy 181.205507 -279.933468) (xy 181.179204 -279.891872) (xy 181.159913 -279.846596) (xy 181.148136 -279.798812)
			(xy 181.144176 -279.749758) (xy 180.827167 -279.749758) (xy 180.826668 -279.775212) (xy 180.818625 -279.825994)
			(xy 180.802737 -279.874893) (xy 180.779394 -279.920705) (xy 180.749173 -279.962301) (xy 180.712817 -279.998657)
			(xy 180.671221 -280.028878) (xy 180.625409 -280.052221) (xy 180.57651 -280.068109) (xy 180.525728 -280.076152)
			(xy 180.474312 -280.076152) (xy 180.42353 -280.068109) (xy 180.374631 -280.052221) (xy 180.328819 -280.028878)
			(xy 180.287223 -279.998657) (xy 180.250867 -279.962301) (xy 180.220646 -279.920705) (xy 180.197303 -279.874893)
			(xy 180.181415 -279.825994) (xy 180.173372 -279.775212) (xy 179.854735 -279.775212) (xy 179.846978 -279.822942)
			(xy 179.831394 -279.869623) (xy 179.808523 -279.9132) (xy 179.778958 -279.952544) (xy 179.743465 -279.986636)
			(xy 179.702962 -280.014592) (xy 179.6585 -280.03569) (xy 179.611229 -280.049382) (xy 179.562374 -280.055314)
			(xy 179.513199 -280.053333) (xy 179.46498 -280.043489) (xy 179.418964 -280.026037) (xy 179.376343 -280.00143)
			(xy 179.338222 -279.970305) (xy 179.305587 -279.933468) (xy 179.279284 -279.891872) (xy 179.259993 -279.846596)
			(xy 179.248216 -279.798812) (xy 179.244256 -279.749758) (xy 178.926993 -279.749758) (xy 178.926494 -279.775212)
			(xy 178.918451 -279.825994) (xy 178.902563 -279.874893) (xy 178.87922 -279.920705) (xy 178.848999 -279.962301)
			(xy 178.812643 -279.998657) (xy 178.771047 -280.028878) (xy 178.725235 -280.052221) (xy 178.676336 -280.068109)
			(xy 178.625554 -280.076152) (xy 178.574138 -280.076152) (xy 178.523356 -280.068109) (xy 178.474457 -280.052221)
			(xy 178.428645 -280.028878) (xy 178.387049 -279.998657) (xy 178.350693 -279.962301) (xy 178.320472 -279.920705)
			(xy 178.297129 -279.874893) (xy 178.281241 -279.825994) (xy 178.273198 -279.775212) (xy 177.954561 -279.775212)
			(xy 177.946804 -279.822942) (xy 177.93122 -279.869623) (xy 177.908349 -279.9132) (xy 177.878784 -279.952544)
			(xy 177.843291 -279.986636) (xy 177.802788 -280.014592) (xy 177.758326 -280.03569) (xy 177.711055 -280.049382)
			(xy 177.6622 -280.055314) (xy 177.613025 -280.053333) (xy 177.564806 -280.043489) (xy 177.51879 -280.026037)
			(xy 177.476169 -280.00143) (xy 177.438048 -279.970305) (xy 177.405413 -279.933468) (xy 177.37911 -279.891872)
			(xy 177.359819 -279.846596) (xy 177.348042 -279.798812) (xy 177.344082 -279.749758) (xy 177.027073 -279.749758)
			(xy 177.026574 -279.775212) (xy 177.018531 -279.825994) (xy 177.002643 -279.874893) (xy 176.9793 -279.920705)
			(xy 176.949079 -279.962301) (xy 176.912723 -279.998657) (xy 176.871127 -280.028878) (xy 176.825315 -280.052221)
			(xy 176.776416 -280.068109) (xy 176.725634 -280.076152) (xy 176.674218 -280.076152) (xy 176.623436 -280.068109)
			(xy 176.574537 -280.052221) (xy 176.528725 -280.028878) (xy 176.487129 -279.998657) (xy 176.450773 -279.962301)
			(xy 176.420552 -279.920705) (xy 176.397209 -279.874893) (xy 176.381321 -279.825994) (xy 176.373278 -279.775212)
			(xy 176.054641 -279.775212) (xy 176.046884 -279.822942) (xy 176.0313 -279.869623) (xy 176.008429 -279.9132)
			(xy 175.978864 -279.952544) (xy 175.943371 -279.986636) (xy 175.902868 -280.014592) (xy 175.858406 -280.03569)
			(xy 175.811135 -280.049382) (xy 175.76228 -280.055314) (xy 175.713105 -280.053333) (xy 175.664886 -280.043489)
			(xy 175.61887 -280.026037) (xy 175.576249 -280.00143) (xy 175.538128 -279.970305) (xy 175.505493 -279.933468)
			(xy 175.47919 -279.891872) (xy 175.459899 -279.846596) (xy 175.448122 -279.798812) (xy 175.444162 -279.749758)
			(xy 175.127153 -279.749758) (xy 175.126654 -279.775212) (xy 175.118611 -279.825994) (xy 175.102723 -279.874893)
			(xy 175.07938 -279.920705) (xy 175.049159 -279.962301) (xy 175.012803 -279.998657) (xy 174.971207 -280.028878)
			(xy 174.925395 -280.052221) (xy 174.876496 -280.068109) (xy 174.825714 -280.076152) (xy 174.774298 -280.076152)
			(xy 174.723516 -280.068109) (xy 174.674617 -280.052221) (xy 174.628805 -280.028878) (xy 174.587209 -279.998657)
			(xy 174.550853 -279.962301) (xy 174.520632 -279.920705) (xy 174.497289 -279.874893) (xy 174.481401 -279.825994)
			(xy 174.473358 -279.775212) (xy 174.154721 -279.775212) (xy 174.146964 -279.822942) (xy 174.13138 -279.869623)
			(xy 174.108509 -279.9132) (xy 174.078944 -279.952544) (xy 174.043451 -279.986636) (xy 174.002948 -280.014592)
			(xy 173.958486 -280.03569) (xy 173.911215 -280.049382) (xy 173.86236 -280.055314) (xy 173.813185 -280.053333)
			(xy 173.764966 -280.043489) (xy 173.71895 -280.026037) (xy 173.676329 -280.00143) (xy 173.638208 -279.970305)
			(xy 173.605573 -279.933468) (xy 173.57927 -279.891872) (xy 173.559979 -279.846596) (xy 173.548202 -279.798812)
			(xy 173.544242 -279.749758) (xy 173.226979 -279.749758) (xy 173.22648 -279.775212) (xy 173.218437 -279.825994)
			(xy 173.202549 -279.874893) (xy 173.179206 -279.920705) (xy 173.148985 -279.962301) (xy 173.112629 -279.998657)
			(xy 173.071033 -280.028878) (xy 173.025221 -280.052221) (xy 172.976322 -280.068109) (xy 172.92554 -280.076152)
			(xy 172.874124 -280.076152) (xy 172.823342 -280.068109) (xy 172.774443 -280.052221) (xy 172.728631 -280.028878)
			(xy 172.687035 -279.998657) (xy 172.650679 -279.962301) (xy 172.620458 -279.920705) (xy 172.597115 -279.874893)
			(xy 172.581227 -279.825994) (xy 172.573184 -279.775212) (xy 172.254547 -279.775212) (xy 172.24679 -279.822942)
			(xy 172.231206 -279.869623) (xy 172.208335 -279.9132) (xy 172.17877 -279.952544) (xy 172.143277 -279.986636)
			(xy 172.102774 -280.014592) (xy 172.058312 -280.03569) (xy 172.011041 -280.049382) (xy 171.962186 -280.055314)
			(xy 171.913011 -280.053333) (xy 171.864792 -280.043489) (xy 171.818776 -280.026037) (xy 171.776155 -280.00143)
			(xy 171.738034 -279.970305) (xy 171.705399 -279.933468) (xy 171.679096 -279.891872) (xy 171.659805 -279.846596)
			(xy 171.648028 -279.798812) (xy 171.644068 -279.749758) (xy 171.327059 -279.749758) (xy 171.32656 -279.775212)
			(xy 171.318517 -279.825994) (xy 171.302629 -279.874893) (xy 171.279286 -279.920705) (xy 171.249065 -279.962301)
			(xy 171.212709 -279.998657) (xy 171.171113 -280.028878) (xy 171.125301 -280.052221) (xy 171.076402 -280.068109)
			(xy 171.02562 -280.076152) (xy 170.974204 -280.076152) (xy 170.923422 -280.068109) (xy 170.874523 -280.052221)
			(xy 170.828711 -280.028878) (xy 170.787115 -279.998657) (xy 170.750759 -279.962301) (xy 170.720538 -279.920705)
			(xy 170.697195 -279.874893) (xy 170.681307 -279.825994) (xy 170.673264 -279.775212) (xy 170.354627 -279.775212)
			(xy 170.34687 -279.822942) (xy 170.331286 -279.869623) (xy 170.308415 -279.9132) (xy 170.27885 -279.952544)
			(xy 170.243357 -279.986636) (xy 170.202854 -280.014592) (xy 170.158392 -280.03569) (xy 170.111121 -280.049382)
			(xy 170.062266 -280.055314) (xy 170.013091 -280.053333) (xy 169.964872 -280.043489) (xy 169.918856 -280.026037)
			(xy 169.876235 -280.00143) (xy 169.838114 -279.970305) (xy 169.805479 -279.933468) (xy 169.779176 -279.891872)
			(xy 169.759885 -279.846596) (xy 169.748108 -279.798812) (xy 169.744148 -279.749758) (xy 169.427139 -279.749758)
			(xy 169.42664 -279.775212) (xy 169.418597 -279.825994) (xy 169.402709 -279.874893) (xy 169.379366 -279.920705)
			(xy 169.349145 -279.962301) (xy 169.312789 -279.998657) (xy 169.271193 -280.028878) (xy 169.225381 -280.052221)
			(xy 169.176482 -280.068109) (xy 169.1257 -280.076152) (xy 169.074284 -280.076152) (xy 169.023502 -280.068109)
			(xy 168.974603 -280.052221) (xy 168.928791 -280.028878) (xy 168.887195 -279.998657) (xy 168.850839 -279.962301)
			(xy 168.820618 -279.920705) (xy 168.797275 -279.874893) (xy 168.781387 -279.825994) (xy 168.773344 -279.775212)
			(xy 168.454707 -279.775212) (xy 168.44695 -279.822942) (xy 168.431366 -279.869623) (xy 168.408495 -279.9132)
			(xy 168.37893 -279.952544) (xy 168.343437 -279.986636) (xy 168.302934 -280.014592) (xy 168.258472 -280.03569)
			(xy 168.211201 -280.049382) (xy 168.162346 -280.055314) (xy 168.113171 -280.053333) (xy 168.064952 -280.043489)
			(xy 168.018936 -280.026037) (xy 167.976315 -280.00143) (xy 167.938194 -279.970305) (xy 167.905559 -279.933468)
			(xy 167.879256 -279.891872) (xy 167.859965 -279.846596) (xy 167.848188 -279.798812) (xy 167.844228 -279.749758)
			(xy 167.527219 -279.749758) (xy 167.52672 -279.775212) (xy 167.518677 -279.825994) (xy 167.502789 -279.874893)
			(xy 167.479446 -279.920705) (xy 167.449225 -279.962301) (xy 167.412869 -279.998657) (xy 167.371273 -280.028878)
			(xy 167.325461 -280.052221) (xy 167.276562 -280.068109) (xy 167.22578 -280.076152) (xy 167.174364 -280.076152)
			(xy 167.123582 -280.068109) (xy 167.074683 -280.052221) (xy 167.028871 -280.028878) (xy 166.987275 -279.998657)
			(xy 166.950919 -279.962301) (xy 166.920698 -279.920705) (xy 166.897355 -279.874893) (xy 166.881467 -279.825994)
			(xy 166.873424 -279.775212) (xy 166.554533 -279.775212) (xy 166.546776 -279.822942) (xy 166.531192 -279.869623)
			(xy 166.508321 -279.9132) (xy 166.478756 -279.952544) (xy 166.443263 -279.986636) (xy 166.40276 -280.014592)
			(xy 166.358298 -280.03569) (xy 166.311027 -280.049382) (xy 166.262172 -280.055314) (xy 166.212997 -280.053333)
			(xy 166.164778 -280.043489) (xy 166.118762 -280.026037) (xy 166.076141 -280.00143) (xy 166.03802 -279.970305)
			(xy 166.005385 -279.933468) (xy 165.979082 -279.891872) (xy 165.959791 -279.846596) (xy 165.948014 -279.798812)
			(xy 165.944054 -279.749758) (xy 165.626172 -279.749758) (xy 165.626172 -279.775407) (xy 165.618003 -279.826572)
			(xy 165.601869 -279.875808) (xy 165.578174 -279.921885) (xy 165.547511 -279.963651) (xy 165.510646 -280.000059)
			(xy 165.468503 -280.030199) (xy 165.422134 -280.053319) (xy 165.3727 -280.068838) (xy 165.347142 -280.0731)
			(xy 165.328092 -280.075894) (xy 165.306538 -280.10104) (xy 224.384106 -280.10104) (xy 224.388177 -280.045418)
			(xy 224.400303 -279.990981) (xy 224.420226 -279.93889) (xy 224.447522 -279.890255) (xy 224.481608 -279.846112)
			(xy 224.521757 -279.807403) (xy 224.567115 -279.774952) (xy 224.616715 -279.749451) (xy 224.669499 -279.731444)
			(xy 224.724342 -279.721314) (xy 224.780076 -279.719277) (xy 224.835513 -279.725377) (xy 224.88947 -279.739483)
			(xy 224.940799 -279.761295) (xy 224.988405 -279.790349) (xy 225.031273 -279.826024) (xy 225.06849 -279.867561)
			(xy 225.099263 -279.914074) (xy 225.122935 -279.964571) (xy 225.139003 -280.017978) (xy 225.147123 -280.073154)
			(xy 225.147632 -280.10104) (xy 225.147123 -280.128926) (xy 225.139003 -280.184102) (xy 225.122935 -280.237509)
			(xy 225.099263 -280.288006) (xy 225.06849 -280.334519) (xy 225.031273 -280.376056) (xy 224.988405 -280.411731)
			(xy 224.940799 -280.440785) (xy 224.88947 -280.462597) (xy 224.835513 -280.476703) (xy 224.780076 -280.482803)
			(xy 224.724342 -280.480766) (xy 224.669499 -280.470636) (xy 224.616715 -280.452629) (xy 224.567115 -280.427128)
			(xy 224.521757 -280.394677) (xy 224.481608 -280.355968) (xy 224.447522 -280.311825) (xy 224.420226 -280.26319)
			(xy 224.400303 -280.211099) (xy 224.388177 -280.156662) (xy 224.384106 -280.10104) (xy 165.306538 -280.10104)
			(xy 165.303708 -280.104342) (xy 165.303708 -280.34488) (xy 165.328092 -280.373328) (xy 165.347142 -280.376122)
			(xy 165.3727 -280.380376) (xy 165.422132 -280.395896) (xy 165.468498 -280.419014) (xy 165.51064 -280.449154)
			(xy 165.547503 -280.485561) (xy 165.578164 -280.527325) (xy 165.601857 -280.5734) (xy 165.61799 -280.622635)
			(xy 165.626158 -280.673797) (xy 165.626158 -280.699718) (xy 165.944054 -280.699718) (xy 165.948014 -280.650664)
			(xy 165.959791 -280.60288) (xy 165.979082 -280.557604) (xy 166.005385 -280.516008) (xy 166.03802 -280.479171)
			(xy 166.076141 -280.448046) (xy 166.118762 -280.423439) (xy 166.164778 -280.405987) (xy 166.212997 -280.396143)
			(xy 166.262172 -280.394162) (xy 166.311027 -280.400094) (xy 166.358298 -280.413786) (xy 166.40276 -280.434884)
			(xy 166.443263 -280.46284) (xy 166.478756 -280.496932) (xy 166.508321 -280.536276) (xy 166.531192 -280.579853)
			(xy 166.546776 -280.626534) (xy 166.554671 -280.675111) (xy 166.555166 -280.699718) (xy 166.554671 -280.724325)
			(xy 166.554492 -280.725426) (xy 166.873424 -280.725426) (xy 166.873424 -280.67401) (xy 166.881467 -280.623228)
			(xy 166.897355 -280.574329) (xy 166.920698 -280.528517) (xy 166.950919 -280.486921) (xy 166.987275 -280.450565)
			(xy 167.028871 -280.420344) (xy 167.074683 -280.397001) (xy 167.123582 -280.381113) (xy 167.174364 -280.37307)
			(xy 167.22578 -280.37307) (xy 167.276562 -280.381113) (xy 167.325461 -280.397001) (xy 167.371273 -280.420344)
			(xy 167.412869 -280.450565) (xy 167.449225 -280.486921) (xy 167.479446 -280.528517) (xy 167.502789 -280.574329)
			(xy 167.518677 -280.623228) (xy 167.52672 -280.67401) (xy 167.527224 -280.699718) (xy 167.844228 -280.699718)
			(xy 167.848188 -280.650664) (xy 167.859965 -280.60288) (xy 167.879256 -280.557604) (xy 167.905559 -280.516008)
			(xy 167.938194 -280.479171) (xy 167.976315 -280.448046) (xy 168.018936 -280.423439) (xy 168.064952 -280.405987)
			(xy 168.113171 -280.396143) (xy 168.162346 -280.394162) (xy 168.211201 -280.400094) (xy 168.258472 -280.413786)
			(xy 168.302934 -280.434884) (xy 168.343437 -280.46284) (xy 168.37893 -280.496932) (xy 168.408495 -280.536276)
			(xy 168.431366 -280.579853) (xy 168.44695 -280.626534) (xy 168.454845 -280.675111) (xy 168.45534 -280.699718)
			(xy 168.454845 -280.724325) (xy 168.454666 -280.725426) (xy 168.773344 -280.725426) (xy 168.773344 -280.67401)
			(xy 168.781387 -280.623228) (xy 168.797275 -280.574329) (xy 168.820618 -280.528517) (xy 168.850839 -280.486921)
			(xy 168.887195 -280.450565) (xy 168.928791 -280.420344) (xy 168.974603 -280.397001) (xy 169.023502 -280.381113)
			(xy 169.074284 -280.37307) (xy 169.1257 -280.37307) (xy 169.176482 -280.381113) (xy 169.225381 -280.397001)
			(xy 169.271193 -280.420344) (xy 169.312789 -280.450565) (xy 169.349145 -280.486921) (xy 169.379366 -280.528517)
			(xy 169.402709 -280.574329) (xy 169.418597 -280.623228) (xy 169.42664 -280.67401) (xy 169.427144 -280.699718)
			(xy 169.744148 -280.699718) (xy 169.748108 -280.650664) (xy 169.759885 -280.60288) (xy 169.779176 -280.557604)
			(xy 169.805479 -280.516008) (xy 169.838114 -280.479171) (xy 169.876235 -280.448046) (xy 169.918856 -280.423439)
			(xy 169.964872 -280.405987) (xy 170.013091 -280.396143) (xy 170.062266 -280.394162) (xy 170.111121 -280.400094)
			(xy 170.158392 -280.413786) (xy 170.202854 -280.434884) (xy 170.243357 -280.46284) (xy 170.27885 -280.496932)
			(xy 170.308415 -280.536276) (xy 170.331286 -280.579853) (xy 170.34687 -280.626534) (xy 170.354765 -280.675111)
			(xy 170.35526 -280.699718) (xy 170.354765 -280.724325) (xy 170.354586 -280.725426) (xy 170.673264 -280.725426)
			(xy 170.673264 -280.67401) (xy 170.681307 -280.623228) (xy 170.697195 -280.574329) (xy 170.720538 -280.528517)
			(xy 170.750759 -280.486921) (xy 170.787115 -280.450565) (xy 170.828711 -280.420344) (xy 170.874523 -280.397001)
			(xy 170.923422 -280.381113) (xy 170.974204 -280.37307) (xy 171.02562 -280.37307) (xy 171.076402 -280.381113)
			(xy 171.125301 -280.397001) (xy 171.171113 -280.420344) (xy 171.212709 -280.450565) (xy 171.249065 -280.486921)
			(xy 171.279286 -280.528517) (xy 171.302629 -280.574329) (xy 171.318517 -280.623228) (xy 171.32656 -280.67401)
			(xy 171.327064 -280.699718) (xy 171.644068 -280.699718) (xy 171.648028 -280.650664) (xy 171.659805 -280.60288)
			(xy 171.679096 -280.557604) (xy 171.705399 -280.516008) (xy 171.738034 -280.479171) (xy 171.776155 -280.448046)
			(xy 171.818776 -280.423439) (xy 171.864792 -280.405987) (xy 171.913011 -280.396143) (xy 171.962186 -280.394162)
			(xy 172.011041 -280.400094) (xy 172.058312 -280.413786) (xy 172.102774 -280.434884) (xy 172.143277 -280.46284)
			(xy 172.17877 -280.496932) (xy 172.208335 -280.536276) (xy 172.231206 -280.579853) (xy 172.24679 -280.626534)
			(xy 172.254685 -280.675111) (xy 172.25518 -280.699718) (xy 172.254685 -280.724325) (xy 172.254506 -280.725426)
			(xy 172.573184 -280.725426) (xy 172.573184 -280.67401) (xy 172.581227 -280.623228) (xy 172.597115 -280.574329)
			(xy 172.620458 -280.528517) (xy 172.650679 -280.486921) (xy 172.687035 -280.450565) (xy 172.728631 -280.420344)
			(xy 172.774443 -280.397001) (xy 172.823342 -280.381113) (xy 172.874124 -280.37307) (xy 172.92554 -280.37307)
			(xy 172.976322 -280.381113) (xy 173.025221 -280.397001) (xy 173.071033 -280.420344) (xy 173.112629 -280.450565)
			(xy 173.148985 -280.486921) (xy 173.179206 -280.528517) (xy 173.202549 -280.574329) (xy 173.218437 -280.623228)
			(xy 173.22648 -280.67401) (xy 173.226984 -280.699718) (xy 173.544242 -280.699718) (xy 173.548202 -280.650664)
			(xy 173.559979 -280.60288) (xy 173.57927 -280.557604) (xy 173.605573 -280.516008) (xy 173.638208 -280.479171)
			(xy 173.676329 -280.448046) (xy 173.71895 -280.423439) (xy 173.764966 -280.405987) (xy 173.813185 -280.396143)
			(xy 173.86236 -280.394162) (xy 173.911215 -280.400094) (xy 173.958486 -280.413786) (xy 174.002948 -280.434884)
			(xy 174.043451 -280.46284) (xy 174.078944 -280.496932) (xy 174.108509 -280.536276) (xy 174.13138 -280.579853)
			(xy 174.146964 -280.626534) (xy 174.154859 -280.675111) (xy 174.155354 -280.699718) (xy 174.154859 -280.724325)
			(xy 174.15468 -280.725426) (xy 174.473358 -280.725426) (xy 174.473358 -280.67401) (xy 174.481401 -280.623228)
			(xy 174.497289 -280.574329) (xy 174.520632 -280.528517) (xy 174.550853 -280.486921) (xy 174.587209 -280.450565)
			(xy 174.628805 -280.420344) (xy 174.674617 -280.397001) (xy 174.723516 -280.381113) (xy 174.774298 -280.37307)
			(xy 174.825714 -280.37307) (xy 174.876496 -280.381113) (xy 174.925395 -280.397001) (xy 174.971207 -280.420344)
			(xy 175.012803 -280.450565) (xy 175.049159 -280.486921) (xy 175.07938 -280.528517) (xy 175.102723 -280.574329)
			(xy 175.118611 -280.623228) (xy 175.126654 -280.67401) (xy 175.127158 -280.699718) (xy 175.444162 -280.699718)
			(xy 175.448122 -280.650664) (xy 175.459899 -280.60288) (xy 175.47919 -280.557604) (xy 175.505493 -280.516008)
			(xy 175.538128 -280.479171) (xy 175.576249 -280.448046) (xy 175.61887 -280.423439) (xy 175.664886 -280.405987)
			(xy 175.713105 -280.396143) (xy 175.76228 -280.394162) (xy 175.811135 -280.400094) (xy 175.858406 -280.413786)
			(xy 175.902868 -280.434884) (xy 175.943371 -280.46284) (xy 175.978864 -280.496932) (xy 176.008429 -280.536276)
			(xy 176.0313 -280.579853) (xy 176.046884 -280.626534) (xy 176.054779 -280.675111) (xy 176.055274 -280.699718)
			(xy 176.054779 -280.724325) (xy 176.0546 -280.725426) (xy 176.373278 -280.725426) (xy 176.373278 -280.67401)
			(xy 176.381321 -280.623228) (xy 176.397209 -280.574329) (xy 176.420552 -280.528517) (xy 176.450773 -280.486921)
			(xy 176.487129 -280.450565) (xy 176.528725 -280.420344) (xy 176.574537 -280.397001) (xy 176.623436 -280.381113)
			(xy 176.674218 -280.37307) (xy 176.725634 -280.37307) (xy 176.776416 -280.381113) (xy 176.825315 -280.397001)
			(xy 176.871127 -280.420344) (xy 176.912723 -280.450565) (xy 176.949079 -280.486921) (xy 176.9793 -280.528517)
			(xy 177.002643 -280.574329) (xy 177.018531 -280.623228) (xy 177.026574 -280.67401) (xy 177.027078 -280.699718)
			(xy 177.344082 -280.699718) (xy 177.348042 -280.650664) (xy 177.359819 -280.60288) (xy 177.37911 -280.557604)
			(xy 177.405413 -280.516008) (xy 177.438048 -280.479171) (xy 177.476169 -280.448046) (xy 177.51879 -280.423439)
			(xy 177.564806 -280.405987) (xy 177.613025 -280.396143) (xy 177.6622 -280.394162) (xy 177.711055 -280.400094)
			(xy 177.758326 -280.413786) (xy 177.802788 -280.434884) (xy 177.843291 -280.46284) (xy 177.878784 -280.496932)
			(xy 177.908349 -280.536276) (xy 177.93122 -280.579853) (xy 177.946804 -280.626534) (xy 177.954699 -280.675111)
			(xy 177.955194 -280.699718) (xy 177.954699 -280.724325) (xy 177.95452 -280.725426) (xy 178.273198 -280.725426)
			(xy 178.273198 -280.67401) (xy 178.281241 -280.623228) (xy 178.297129 -280.574329) (xy 178.320472 -280.528517)
			(xy 178.350693 -280.486921) (xy 178.387049 -280.450565) (xy 178.428645 -280.420344) (xy 178.474457 -280.397001)
			(xy 178.523356 -280.381113) (xy 178.574138 -280.37307) (xy 178.625554 -280.37307) (xy 178.676336 -280.381113)
			(xy 178.725235 -280.397001) (xy 178.771047 -280.420344) (xy 178.812643 -280.450565) (xy 178.848999 -280.486921)
			(xy 178.87922 -280.528517) (xy 178.902563 -280.574329) (xy 178.918451 -280.623228) (xy 178.926494 -280.67401)
			(xy 178.926998 -280.699718) (xy 179.244256 -280.699718) (xy 179.248216 -280.650664) (xy 179.259993 -280.60288)
			(xy 179.279284 -280.557604) (xy 179.305587 -280.516008) (xy 179.338222 -280.479171) (xy 179.376343 -280.448046)
			(xy 179.418964 -280.423439) (xy 179.46498 -280.405987) (xy 179.513199 -280.396143) (xy 179.562374 -280.394162)
			(xy 179.611229 -280.400094) (xy 179.6585 -280.413786) (xy 179.702962 -280.434884) (xy 179.743465 -280.46284)
			(xy 179.778958 -280.496932) (xy 179.808523 -280.536276) (xy 179.831394 -280.579853) (xy 179.846978 -280.626534)
			(xy 179.854873 -280.675111) (xy 179.855368 -280.699718) (xy 179.854873 -280.724325) (xy 179.854694 -280.725426)
			(xy 180.173372 -280.725426) (xy 180.173372 -280.67401) (xy 180.181415 -280.623228) (xy 180.197303 -280.574329)
			(xy 180.220646 -280.528517) (xy 180.250867 -280.486921) (xy 180.287223 -280.450565) (xy 180.328819 -280.420344)
			(xy 180.374631 -280.397001) (xy 180.42353 -280.381113) (xy 180.474312 -280.37307) (xy 180.525728 -280.37307)
			(xy 180.57651 -280.381113) (xy 180.625409 -280.397001) (xy 180.671221 -280.420344) (xy 180.712817 -280.450565)
			(xy 180.749173 -280.486921) (xy 180.779394 -280.528517) (xy 180.802737 -280.574329) (xy 180.818625 -280.623228)
			(xy 180.826668 -280.67401) (xy 180.827172 -280.699718) (xy 181.144176 -280.699718) (xy 181.148136 -280.650664)
			(xy 181.159913 -280.60288) (xy 181.179204 -280.557604) (xy 181.205507 -280.516008) (xy 181.238142 -280.479171)
			(xy 181.276263 -280.448046) (xy 181.318884 -280.423439) (xy 181.3649 -280.405987) (xy 181.413119 -280.396143)
			(xy 181.462294 -280.394162) (xy 181.511149 -280.400094) (xy 181.55842 -280.413786) (xy 181.602882 -280.434884)
			(xy 181.643385 -280.46284) (xy 181.678878 -280.496932) (xy 181.708443 -280.536276) (xy 181.731314 -280.579853)
			(xy 181.746898 -280.626534) (xy 181.754793 -280.675111) (xy 181.755288 -280.699718) (xy 181.754793 -280.724325)
			(xy 181.754614 -280.725426) (xy 182.073292 -280.725426) (xy 182.073292 -280.67401) (xy 182.081335 -280.623228)
			(xy 182.097223 -280.574329) (xy 182.120566 -280.528517) (xy 182.150787 -280.486921) (xy 182.187143 -280.450565)
			(xy 182.228739 -280.420344) (xy 182.274551 -280.397001) (xy 182.32345 -280.381113) (xy 182.374232 -280.37307)
			(xy 182.425648 -280.37307) (xy 182.47643 -280.381113) (xy 182.525329 -280.397001) (xy 182.571141 -280.420344)
			(xy 182.612737 -280.450565) (xy 182.649093 -280.486921) (xy 182.679314 -280.528517) (xy 182.702657 -280.574329)
			(xy 182.718545 -280.623228) (xy 182.726588 -280.67401) (xy 182.727092 -280.699718) (xy 183.044096 -280.699718)
			(xy 183.048056 -280.650664) (xy 183.059833 -280.60288) (xy 183.079124 -280.557604) (xy 183.105427 -280.516008)
			(xy 183.138062 -280.479171) (xy 183.176183 -280.448046) (xy 183.218804 -280.423439) (xy 183.26482 -280.405987)
			(xy 183.313039 -280.396143) (xy 183.362214 -280.394162) (xy 183.411069 -280.400094) (xy 183.45834 -280.413786)
			(xy 183.502802 -280.434884) (xy 183.543305 -280.46284) (xy 183.578798 -280.496932) (xy 183.608363 -280.536276)
			(xy 183.631234 -280.579853) (xy 183.646818 -280.626534) (xy 183.654713 -280.675111) (xy 183.655208 -280.699718)
			(xy 183.654713 -280.724325) (xy 183.654534 -280.725426) (xy 183.973212 -280.725426) (xy 183.973212 -280.67401)
			(xy 183.981255 -280.623228) (xy 183.997143 -280.574329) (xy 184.020486 -280.528517) (xy 184.050707 -280.486921)
			(xy 184.087063 -280.450565) (xy 184.128659 -280.420344) (xy 184.174471 -280.397001) (xy 184.22337 -280.381113)
			(xy 184.274152 -280.37307) (xy 184.325568 -280.37307) (xy 184.37635 -280.381113) (xy 184.425249 -280.397001)
			(xy 184.471061 -280.420344) (xy 184.512657 -280.450565) (xy 184.549013 -280.486921) (xy 184.579234 -280.528517)
			(xy 184.602577 -280.574329) (xy 184.618465 -280.623228) (xy 184.626508 -280.67401) (xy 184.627012 -280.699718)
			(xy 184.94427 -280.699718) (xy 184.94823 -280.650664) (xy 184.960007 -280.60288) (xy 184.979298 -280.557604)
			(xy 185.005601 -280.516008) (xy 185.038236 -280.479171) (xy 185.076357 -280.448046) (xy 185.118978 -280.423439)
			(xy 185.164994 -280.405987) (xy 185.213213 -280.396143) (xy 185.262388 -280.394162) (xy 185.311243 -280.400094)
			(xy 185.358514 -280.413786) (xy 185.402976 -280.434884) (xy 185.443479 -280.46284) (xy 185.478972 -280.496932)
			(xy 185.508537 -280.536276) (xy 185.531408 -280.579853) (xy 185.546992 -280.626534) (xy 185.554887 -280.675111)
			(xy 185.555382 -280.699718) (xy 185.554887 -280.724325) (xy 185.554708 -280.725426) (xy 185.873386 -280.725426)
			(xy 185.873386 -280.67401) (xy 185.881429 -280.623228) (xy 185.897317 -280.574329) (xy 185.92066 -280.528517)
			(xy 185.950881 -280.486921) (xy 185.987237 -280.450565) (xy 186.028833 -280.420344) (xy 186.074645 -280.397001)
			(xy 186.123544 -280.381113) (xy 186.174326 -280.37307) (xy 186.225742 -280.37307) (xy 186.276524 -280.381113)
			(xy 186.325423 -280.397001) (xy 186.371235 -280.420344) (xy 186.412831 -280.450565) (xy 186.449187 -280.486921)
			(xy 186.479408 -280.528517) (xy 186.502751 -280.574329) (xy 186.518639 -280.623228) (xy 186.526682 -280.67401)
			(xy 186.527186 -280.699718) (xy 186.84419 -280.699718) (xy 186.84815 -280.650664) (xy 186.859927 -280.60288)
			(xy 186.879218 -280.557604) (xy 186.905521 -280.516008) (xy 186.938156 -280.479171) (xy 186.976277 -280.448046)
			(xy 187.018898 -280.423439) (xy 187.064914 -280.405987) (xy 187.113133 -280.396143) (xy 187.162308 -280.394162)
			(xy 187.211163 -280.400094) (xy 187.258434 -280.413786) (xy 187.302896 -280.434884) (xy 187.343399 -280.46284)
			(xy 187.378892 -280.496932) (xy 187.408457 -280.536276) (xy 187.431328 -280.579853) (xy 187.446912 -280.626534)
			(xy 187.454807 -280.675111) (xy 187.455302 -280.699718) (xy 187.454807 -280.724325) (xy 187.454628 -280.725426)
			(xy 187.773306 -280.725426) (xy 187.773306 -280.67401) (xy 187.781349 -280.623228) (xy 187.797237 -280.574329)
			(xy 187.82058 -280.528517) (xy 187.850801 -280.486921) (xy 187.887157 -280.450565) (xy 187.928753 -280.420344)
			(xy 187.974565 -280.397001) (xy 188.023464 -280.381113) (xy 188.074246 -280.37307) (xy 188.125662 -280.37307)
			(xy 188.176444 -280.381113) (xy 188.225343 -280.397001) (xy 188.271155 -280.420344) (xy 188.312751 -280.450565)
			(xy 188.349107 -280.486921) (xy 188.379328 -280.528517) (xy 188.402671 -280.574329) (xy 188.418559 -280.623228)
			(xy 188.426602 -280.67401) (xy 188.427106 -280.699718) (xy 188.74411 -280.699718) (xy 188.74807 -280.650664)
			(xy 188.759847 -280.60288) (xy 188.779138 -280.557604) (xy 188.805441 -280.516008) (xy 188.838076 -280.479171)
			(xy 188.876197 -280.448046) (xy 188.918818 -280.423439) (xy 188.964834 -280.405987) (xy 189.013053 -280.396143)
			(xy 189.062228 -280.394162) (xy 189.111083 -280.400094) (xy 189.158354 -280.413786) (xy 189.202816 -280.434884)
			(xy 189.243319 -280.46284) (xy 189.278812 -280.496932) (xy 189.308377 -280.536276) (xy 189.331248 -280.579853)
			(xy 189.346832 -280.626534) (xy 189.354727 -280.675111) (xy 189.355222 -280.699718) (xy 189.354727 -280.724325)
			(xy 189.354548 -280.725426) (xy 189.673226 -280.725426) (xy 189.673226 -280.67401) (xy 189.681269 -280.623228)
			(xy 189.697157 -280.574329) (xy 189.7205 -280.528517) (xy 189.750721 -280.486921) (xy 189.787077 -280.450565)
			(xy 189.828673 -280.420344) (xy 189.874485 -280.397001) (xy 189.923384 -280.381113) (xy 189.974166 -280.37307)
			(xy 190.025582 -280.37307) (xy 190.076364 -280.381113) (xy 190.125263 -280.397001) (xy 190.171075 -280.420344)
			(xy 190.212671 -280.450565) (xy 190.249027 -280.486921) (xy 190.279248 -280.528517) (xy 190.302591 -280.574329)
			(xy 190.318479 -280.623228) (xy 190.326522 -280.67401) (xy 190.327026 -280.699718) (xy 190.644284 -280.699718)
			(xy 190.648244 -280.650664) (xy 190.660021 -280.60288) (xy 190.679312 -280.557604) (xy 190.705615 -280.516008)
			(xy 190.73825 -280.479171) (xy 190.776371 -280.448046) (xy 190.818992 -280.423439) (xy 190.865008 -280.405987)
			(xy 190.913227 -280.396143) (xy 190.962402 -280.394162) (xy 191.011257 -280.400094) (xy 191.058528 -280.413786)
			(xy 191.10299 -280.434884) (xy 191.143493 -280.46284) (xy 191.178986 -280.496932) (xy 191.208551 -280.536276)
			(xy 191.231422 -280.579853) (xy 191.247006 -280.626534) (xy 191.254901 -280.675111) (xy 191.255396 -280.699718)
			(xy 191.254901 -280.724325) (xy 191.254722 -280.725426) (xy 191.5734 -280.725426) (xy 191.5734 -280.67401)
			(xy 191.581443 -280.623228) (xy 191.597331 -280.574329) (xy 191.620674 -280.528517) (xy 191.650895 -280.486921)
			(xy 191.687251 -280.450565) (xy 191.728847 -280.420344) (xy 191.774659 -280.397001) (xy 191.823558 -280.381113)
			(xy 191.87434 -280.37307) (xy 191.925756 -280.37307) (xy 191.976538 -280.381113) (xy 192.025437 -280.397001)
			(xy 192.071249 -280.420344) (xy 192.112845 -280.450565) (xy 192.149201 -280.486921) (xy 192.179422 -280.528517)
			(xy 192.202765 -280.574329) (xy 192.218653 -280.623228) (xy 192.226696 -280.67401) (xy 192.2272 -280.699718)
			(xy 192.544204 -280.699718) (xy 192.548164 -280.650664) (xy 192.559941 -280.60288) (xy 192.579232 -280.557604)
			(xy 192.605535 -280.516008) (xy 192.63817 -280.479171) (xy 192.676291 -280.448046) (xy 192.718912 -280.423439)
			(xy 192.764928 -280.405987) (xy 192.813147 -280.396143) (xy 192.862322 -280.394162) (xy 192.911177 -280.400094)
			(xy 192.958448 -280.413786) (xy 193.00291 -280.434884) (xy 193.043413 -280.46284) (xy 193.078906 -280.496932)
			(xy 193.108471 -280.536276) (xy 193.131342 -280.579853) (xy 193.146926 -280.626534) (xy 193.154821 -280.675111)
			(xy 193.155316 -280.699718) (xy 193.154821 -280.724325) (xy 193.154642 -280.725426) (xy 193.47332 -280.725426)
			(xy 193.47332 -280.67401) (xy 193.481363 -280.623228) (xy 193.497251 -280.574329) (xy 193.520594 -280.528517)
			(xy 193.550815 -280.486921) (xy 193.587171 -280.450565) (xy 193.628767 -280.420344) (xy 193.674579 -280.397001)
			(xy 193.723478 -280.381113) (xy 193.77426 -280.37307) (xy 193.825676 -280.37307) (xy 193.876458 -280.381113)
			(xy 193.925357 -280.397001) (xy 193.971169 -280.420344) (xy 194.012765 -280.450565) (xy 194.049121 -280.486921)
			(xy 194.079342 -280.528517) (xy 194.102685 -280.574329) (xy 194.118573 -280.623228) (xy 194.126616 -280.67401)
			(xy 194.12712 -280.699718) (xy 194.444124 -280.699718) (xy 194.448084 -280.650664) (xy 194.459861 -280.60288)
			(xy 194.479152 -280.557604) (xy 194.505455 -280.516008) (xy 194.53809 -280.479171) (xy 194.576211 -280.448046)
			(xy 194.618832 -280.423439) (xy 194.664848 -280.405987) (xy 194.713067 -280.396143) (xy 194.762242 -280.394162)
			(xy 194.811097 -280.400094) (xy 194.858368 -280.413786) (xy 194.90283 -280.434884) (xy 194.943333 -280.46284)
			(xy 194.978826 -280.496932) (xy 195.008391 -280.536276) (xy 195.031262 -280.579853) (xy 195.046846 -280.626534)
			(xy 195.054741 -280.675111) (xy 195.055236 -280.699718) (xy 195.054741 -280.724325) (xy 195.054562 -280.725426)
			(xy 195.37324 -280.725426) (xy 195.37324 -280.67401) (xy 195.381283 -280.623228) (xy 195.397171 -280.574329)
			(xy 195.420514 -280.528517) (xy 195.450735 -280.486921) (xy 195.487091 -280.450565) (xy 195.528687 -280.420344)
			(xy 195.574499 -280.397001) (xy 195.623398 -280.381113) (xy 195.67418 -280.37307) (xy 195.725596 -280.37307)
			(xy 195.776378 -280.381113) (xy 195.825277 -280.397001) (xy 195.871089 -280.420344) (xy 195.912685 -280.450565)
			(xy 195.949041 -280.486921) (xy 195.979262 -280.528517) (xy 196.002605 -280.574329) (xy 196.018493 -280.623228)
			(xy 196.026536 -280.67401) (xy 196.02704 -280.699718) (xy 196.344298 -280.699718) (xy 196.348258 -280.650664)
			(xy 196.360035 -280.60288) (xy 196.379326 -280.557604) (xy 196.405629 -280.516008) (xy 196.438264 -280.479171)
			(xy 196.476385 -280.448046) (xy 196.519006 -280.423439) (xy 196.565022 -280.405987) (xy 196.613241 -280.396143)
			(xy 196.662416 -280.394162) (xy 196.711271 -280.400094) (xy 196.758542 -280.413786) (xy 196.803004 -280.434884)
			(xy 196.843507 -280.46284) (xy 196.879 -280.496932) (xy 196.908565 -280.536276) (xy 196.931436 -280.579853)
			(xy 196.94702 -280.626534) (xy 196.954915 -280.675111) (xy 196.95541 -280.699718) (xy 197.294258 -280.699718)
			(xy 197.298218 -280.650664) (xy 197.309995 -280.60288) (xy 197.329286 -280.557604) (xy 197.355589 -280.516008)
			(xy 197.388224 -280.479171) (xy 197.426345 -280.448046) (xy 197.468966 -280.423439) (xy 197.514982 -280.405987)
			(xy 197.563201 -280.396143) (xy 197.612376 -280.394162) (xy 197.661231 -280.400094) (xy 197.708502 -280.413786)
			(xy 197.752964 -280.434884) (xy 197.793467 -280.46284) (xy 197.82896 -280.496932) (xy 197.858525 -280.536276)
			(xy 197.881396 -280.579853) (xy 197.89698 -280.626534) (xy 197.904875 -280.675111) (xy 197.90537 -280.699718)
			(xy 198.244218 -280.699718) (xy 198.248178 -280.650664) (xy 198.259955 -280.60288) (xy 198.279246 -280.557604)
			(xy 198.305549 -280.516008) (xy 198.338184 -280.479171) (xy 198.376305 -280.448046) (xy 198.418926 -280.423439)
			(xy 198.464942 -280.405987) (xy 198.513161 -280.396143) (xy 198.562336 -280.394162) (xy 198.611191 -280.400094)
			(xy 198.658462 -280.413786) (xy 198.702924 -280.434884) (xy 198.743427 -280.46284) (xy 198.77892 -280.496932)
			(xy 198.808485 -280.536276) (xy 198.831356 -280.579853) (xy 198.84694 -280.626534) (xy 198.854835 -280.675111)
			(xy 198.85533 -280.699718) (xy 198.854835 -280.724325) (xy 198.84694 -280.772902) (xy 198.831356 -280.819583)
			(xy 198.808485 -280.86316) (xy 198.77892 -280.902504) (xy 198.743427 -280.936596) (xy 198.702924 -280.964552)
			(xy 198.658462 -280.98565) (xy 198.611191 -280.999342) (xy 198.562336 -281.005274) (xy 198.513161 -281.003293)
			(xy 198.464942 -280.993449) (xy 198.418926 -280.975997) (xy 198.376305 -280.95139) (xy 198.338184 -280.920265)
			(xy 198.305549 -280.883428) (xy 198.279246 -280.841832) (xy 198.259955 -280.796556) (xy 198.248178 -280.748772)
			(xy 198.244218 -280.699718) (xy 197.90537 -280.699718) (xy 197.904875 -280.724325) (xy 197.89698 -280.772902)
			(xy 197.881396 -280.819583) (xy 197.858525 -280.86316) (xy 197.82896 -280.902504) (xy 197.793467 -280.936596)
			(xy 197.752964 -280.964552) (xy 197.708502 -280.98565) (xy 197.661231 -280.999342) (xy 197.612376 -281.005274)
			(xy 197.563201 -281.003293) (xy 197.514982 -280.993449) (xy 197.468966 -280.975997) (xy 197.426345 -280.95139)
			(xy 197.388224 -280.920265) (xy 197.355589 -280.883428) (xy 197.329286 -280.841832) (xy 197.309995 -280.796556)
			(xy 197.298218 -280.748772) (xy 197.294258 -280.699718) (xy 196.95541 -280.699718) (xy 196.954915 -280.724325)
			(xy 196.94702 -280.772902) (xy 196.931436 -280.819583) (xy 196.908565 -280.86316) (xy 196.879 -280.902504)
			(xy 196.843507 -280.936596) (xy 196.803004 -280.964552) (xy 196.758542 -280.98565) (xy 196.711271 -280.999342)
			(xy 196.662416 -281.005274) (xy 196.613241 -281.003293) (xy 196.565022 -280.993449) (xy 196.519006 -280.975997)
			(xy 196.476385 -280.95139) (xy 196.438264 -280.920265) (xy 196.405629 -280.883428) (xy 196.379326 -280.841832)
			(xy 196.360035 -280.796556) (xy 196.348258 -280.748772) (xy 196.344298 -280.699718) (xy 196.02704 -280.699718)
			(xy 196.026536 -280.725426) (xy 196.018493 -280.776208) (xy 196.002605 -280.825107) (xy 195.979262 -280.870919)
			(xy 195.949041 -280.912515) (xy 195.912685 -280.948871) (xy 195.871089 -280.979092) (xy 195.825277 -281.002435)
			(xy 195.776378 -281.018323) (xy 195.725596 -281.026366) (xy 195.67418 -281.026366) (xy 195.623398 -281.018323)
			(xy 195.574499 -281.002435) (xy 195.528687 -280.979092) (xy 195.487091 -280.948871) (xy 195.450735 -280.912515)
			(xy 195.420514 -280.870919) (xy 195.397171 -280.825107) (xy 195.381283 -280.776208) (xy 195.37324 -280.725426)
			(xy 195.054562 -280.725426) (xy 195.046846 -280.772902) (xy 195.031262 -280.819583) (xy 195.008391 -280.86316)
			(xy 194.978826 -280.902504) (xy 194.943333 -280.936596) (xy 194.90283 -280.964552) (xy 194.858368 -280.98565)
			(xy 194.811097 -280.999342) (xy 194.762242 -281.005274) (xy 194.713067 -281.003293) (xy 194.664848 -280.993449)
			(xy 194.618832 -280.975997) (xy 194.576211 -280.95139) (xy 194.53809 -280.920265) (xy 194.505455 -280.883428)
			(xy 194.479152 -280.841832) (xy 194.459861 -280.796556) (xy 194.448084 -280.748772) (xy 194.444124 -280.699718)
			(xy 194.12712 -280.699718) (xy 194.126616 -280.725426) (xy 194.118573 -280.776208) (xy 194.102685 -280.825107)
			(xy 194.079342 -280.870919) (xy 194.049121 -280.912515) (xy 194.012765 -280.948871) (xy 193.971169 -280.979092)
			(xy 193.925357 -281.002435) (xy 193.876458 -281.018323) (xy 193.825676 -281.026366) (xy 193.77426 -281.026366)
			(xy 193.723478 -281.018323) (xy 193.674579 -281.002435) (xy 193.628767 -280.979092) (xy 193.587171 -280.948871)
			(xy 193.550815 -280.912515) (xy 193.520594 -280.870919) (xy 193.497251 -280.825107) (xy 193.481363 -280.776208)
			(xy 193.47332 -280.725426) (xy 193.154642 -280.725426) (xy 193.146926 -280.772902) (xy 193.131342 -280.819583)
			(xy 193.108471 -280.86316) (xy 193.078906 -280.902504) (xy 193.043413 -280.936596) (xy 193.00291 -280.964552)
			(xy 192.958448 -280.98565) (xy 192.911177 -280.999342) (xy 192.862322 -281.005274) (xy 192.813147 -281.003293)
			(xy 192.764928 -280.993449) (xy 192.718912 -280.975997) (xy 192.676291 -280.95139) (xy 192.63817 -280.920265)
			(xy 192.605535 -280.883428) (xy 192.579232 -280.841832) (xy 192.559941 -280.796556) (xy 192.548164 -280.748772)
			(xy 192.544204 -280.699718) (xy 192.2272 -280.699718) (xy 192.226696 -280.725426) (xy 192.218653 -280.776208)
			(xy 192.202765 -280.825107) (xy 192.179422 -280.870919) (xy 192.149201 -280.912515) (xy 192.112845 -280.948871)
			(xy 192.071249 -280.979092) (xy 192.025437 -281.002435) (xy 191.976538 -281.018323) (xy 191.925756 -281.026366)
			(xy 191.87434 -281.026366) (xy 191.823558 -281.018323) (xy 191.774659 -281.002435) (xy 191.728847 -280.979092)
			(xy 191.687251 -280.948871) (xy 191.650895 -280.912515) (xy 191.620674 -280.870919) (xy 191.597331 -280.825107)
			(xy 191.581443 -280.776208) (xy 191.5734 -280.725426) (xy 191.254722 -280.725426) (xy 191.247006 -280.772902)
			(xy 191.231422 -280.819583) (xy 191.208551 -280.86316) (xy 191.178986 -280.902504) (xy 191.143493 -280.936596)
			(xy 191.10299 -280.964552) (xy 191.058528 -280.98565) (xy 191.011257 -280.999342) (xy 190.962402 -281.005274)
			(xy 190.913227 -281.003293) (xy 190.865008 -280.993449) (xy 190.818992 -280.975997) (xy 190.776371 -280.95139)
			(xy 190.73825 -280.920265) (xy 190.705615 -280.883428) (xy 190.679312 -280.841832) (xy 190.660021 -280.796556)
			(xy 190.648244 -280.748772) (xy 190.644284 -280.699718) (xy 190.327026 -280.699718) (xy 190.326522 -280.725426)
			(xy 190.318479 -280.776208) (xy 190.302591 -280.825107) (xy 190.279248 -280.870919) (xy 190.249027 -280.912515)
			(xy 190.212671 -280.948871) (xy 190.171075 -280.979092) (xy 190.125263 -281.002435) (xy 190.076364 -281.018323)
			(xy 190.025582 -281.026366) (xy 189.974166 -281.026366) (xy 189.923384 -281.018323) (xy 189.874485 -281.002435)
			(xy 189.828673 -280.979092) (xy 189.787077 -280.948871) (xy 189.750721 -280.912515) (xy 189.7205 -280.870919)
			(xy 189.697157 -280.825107) (xy 189.681269 -280.776208) (xy 189.673226 -280.725426) (xy 189.354548 -280.725426)
			(xy 189.346832 -280.772902) (xy 189.331248 -280.819583) (xy 189.308377 -280.86316) (xy 189.278812 -280.902504)
			(xy 189.243319 -280.936596) (xy 189.202816 -280.964552) (xy 189.158354 -280.98565) (xy 189.111083 -280.999342)
			(xy 189.062228 -281.005274) (xy 189.013053 -281.003293) (xy 188.964834 -280.993449) (xy 188.918818 -280.975997)
			(xy 188.876197 -280.95139) (xy 188.838076 -280.920265) (xy 188.805441 -280.883428) (xy 188.779138 -280.841832)
			(xy 188.759847 -280.796556) (xy 188.74807 -280.748772) (xy 188.74411 -280.699718) (xy 188.427106 -280.699718)
			(xy 188.426602 -280.725426) (xy 188.418559 -280.776208) (xy 188.402671 -280.825107) (xy 188.379328 -280.870919)
			(xy 188.349107 -280.912515) (xy 188.312751 -280.948871) (xy 188.271155 -280.979092) (xy 188.225343 -281.002435)
			(xy 188.176444 -281.018323) (xy 188.125662 -281.026366) (xy 188.074246 -281.026366) (xy 188.023464 -281.018323)
			(xy 187.974565 -281.002435) (xy 187.928753 -280.979092) (xy 187.887157 -280.948871) (xy 187.850801 -280.912515)
			(xy 187.82058 -280.870919) (xy 187.797237 -280.825107) (xy 187.781349 -280.776208) (xy 187.773306 -280.725426)
			(xy 187.454628 -280.725426) (xy 187.446912 -280.772902) (xy 187.431328 -280.819583) (xy 187.408457 -280.86316)
			(xy 187.378892 -280.902504) (xy 187.343399 -280.936596) (xy 187.302896 -280.964552) (xy 187.258434 -280.98565)
			(xy 187.211163 -280.999342) (xy 187.162308 -281.005274) (xy 187.113133 -281.003293) (xy 187.064914 -280.993449)
			(xy 187.018898 -280.975997) (xy 186.976277 -280.95139) (xy 186.938156 -280.920265) (xy 186.905521 -280.883428)
			(xy 186.879218 -280.841832) (xy 186.859927 -280.796556) (xy 186.84815 -280.748772) (xy 186.84419 -280.699718)
			(xy 186.527186 -280.699718) (xy 186.526682 -280.725426) (xy 186.518639 -280.776208) (xy 186.502751 -280.825107)
			(xy 186.479408 -280.870919) (xy 186.449187 -280.912515) (xy 186.412831 -280.948871) (xy 186.371235 -280.979092)
			(xy 186.325423 -281.002435) (xy 186.276524 -281.018323) (xy 186.225742 -281.026366) (xy 186.174326 -281.026366)
			(xy 186.123544 -281.018323) (xy 186.074645 -281.002435) (xy 186.028833 -280.979092) (xy 185.987237 -280.948871)
			(xy 185.950881 -280.912515) (xy 185.92066 -280.870919) (xy 185.897317 -280.825107) (xy 185.881429 -280.776208)
			(xy 185.873386 -280.725426) (xy 185.554708 -280.725426) (xy 185.546992 -280.772902) (xy 185.531408 -280.819583)
			(xy 185.508537 -280.86316) (xy 185.478972 -280.902504) (xy 185.443479 -280.936596) (xy 185.402976 -280.964552)
			(xy 185.358514 -280.98565) (xy 185.311243 -280.999342) (xy 185.262388 -281.005274) (xy 185.213213 -281.003293)
			(xy 185.164994 -280.993449) (xy 185.118978 -280.975997) (xy 185.076357 -280.95139) (xy 185.038236 -280.920265)
			(xy 185.005601 -280.883428) (xy 184.979298 -280.841832) (xy 184.960007 -280.796556) (xy 184.94823 -280.748772)
			(xy 184.94427 -280.699718) (xy 184.627012 -280.699718) (xy 184.626508 -280.725426) (xy 184.618465 -280.776208)
			(xy 184.602577 -280.825107) (xy 184.579234 -280.870919) (xy 184.549013 -280.912515) (xy 184.512657 -280.948871)
			(xy 184.471061 -280.979092) (xy 184.425249 -281.002435) (xy 184.37635 -281.018323) (xy 184.325568 -281.026366)
			(xy 184.274152 -281.026366) (xy 184.22337 -281.018323) (xy 184.174471 -281.002435) (xy 184.128659 -280.979092)
			(xy 184.087063 -280.948871) (xy 184.050707 -280.912515) (xy 184.020486 -280.870919) (xy 183.997143 -280.825107)
			(xy 183.981255 -280.776208) (xy 183.973212 -280.725426) (xy 183.654534 -280.725426) (xy 183.646818 -280.772902)
			(xy 183.631234 -280.819583) (xy 183.608363 -280.86316) (xy 183.578798 -280.902504) (xy 183.543305 -280.936596)
			(xy 183.502802 -280.964552) (xy 183.45834 -280.98565) (xy 183.411069 -280.999342) (xy 183.362214 -281.005274)
			(xy 183.313039 -281.003293) (xy 183.26482 -280.993449) (xy 183.218804 -280.975997) (xy 183.176183 -280.95139)
			(xy 183.138062 -280.920265) (xy 183.105427 -280.883428) (xy 183.079124 -280.841832) (xy 183.059833 -280.796556)
			(xy 183.048056 -280.748772) (xy 183.044096 -280.699718) (xy 182.727092 -280.699718) (xy 182.726588 -280.725426)
			(xy 182.718545 -280.776208) (xy 182.702657 -280.825107) (xy 182.679314 -280.870919) (xy 182.649093 -280.912515)
			(xy 182.612737 -280.948871) (xy 182.571141 -280.979092) (xy 182.525329 -281.002435) (xy 182.47643 -281.018323)
			(xy 182.425648 -281.026366) (xy 182.374232 -281.026366) (xy 182.32345 -281.018323) (xy 182.274551 -281.002435)
			(xy 182.228739 -280.979092) (xy 182.187143 -280.948871) (xy 182.150787 -280.912515) (xy 182.120566 -280.870919)
			(xy 182.097223 -280.825107) (xy 182.081335 -280.776208) (xy 182.073292 -280.725426) (xy 181.754614 -280.725426)
			(xy 181.746898 -280.772902) (xy 181.731314 -280.819583) (xy 181.708443 -280.86316) (xy 181.678878 -280.902504)
			(xy 181.643385 -280.936596) (xy 181.602882 -280.964552) (xy 181.55842 -280.98565) (xy 181.511149 -280.999342)
			(xy 181.462294 -281.005274) (xy 181.413119 -281.003293) (xy 181.3649 -280.993449) (xy 181.318884 -280.975997)
			(xy 181.276263 -280.95139) (xy 181.238142 -280.920265) (xy 181.205507 -280.883428) (xy 181.179204 -280.841832)
			(xy 181.159913 -280.796556) (xy 181.148136 -280.748772) (xy 181.144176 -280.699718) (xy 180.827172 -280.699718)
			(xy 180.826668 -280.725426) (xy 180.818625 -280.776208) (xy 180.802737 -280.825107) (xy 180.779394 -280.870919)
			(xy 180.749173 -280.912515) (xy 180.712817 -280.948871) (xy 180.671221 -280.979092) (xy 180.625409 -281.002435)
			(xy 180.57651 -281.018323) (xy 180.525728 -281.026366) (xy 180.474312 -281.026366) (xy 180.42353 -281.018323)
			(xy 180.374631 -281.002435) (xy 180.328819 -280.979092) (xy 180.287223 -280.948871) (xy 180.250867 -280.912515)
			(xy 180.220646 -280.870919) (xy 180.197303 -280.825107) (xy 180.181415 -280.776208) (xy 180.173372 -280.725426)
			(xy 179.854694 -280.725426) (xy 179.846978 -280.772902) (xy 179.831394 -280.819583) (xy 179.808523 -280.86316)
			(xy 179.778958 -280.902504) (xy 179.743465 -280.936596) (xy 179.702962 -280.964552) (xy 179.6585 -280.98565)
			(xy 179.611229 -280.999342) (xy 179.562374 -281.005274) (xy 179.513199 -281.003293) (xy 179.46498 -280.993449)
			(xy 179.418964 -280.975997) (xy 179.376343 -280.95139) (xy 179.338222 -280.920265) (xy 179.305587 -280.883428)
			(xy 179.279284 -280.841832) (xy 179.259993 -280.796556) (xy 179.248216 -280.748772) (xy 179.244256 -280.699718)
			(xy 178.926998 -280.699718) (xy 178.926494 -280.725426) (xy 178.918451 -280.776208) (xy 178.902563 -280.825107)
			(xy 178.87922 -280.870919) (xy 178.848999 -280.912515) (xy 178.812643 -280.948871) (xy 178.771047 -280.979092)
			(xy 178.725235 -281.002435) (xy 178.676336 -281.018323) (xy 178.625554 -281.026366) (xy 178.574138 -281.026366)
			(xy 178.523356 -281.018323) (xy 178.474457 -281.002435) (xy 178.428645 -280.979092) (xy 178.387049 -280.948871)
			(xy 178.350693 -280.912515) (xy 178.320472 -280.870919) (xy 178.297129 -280.825107) (xy 178.281241 -280.776208)
			(xy 178.273198 -280.725426) (xy 177.95452 -280.725426) (xy 177.946804 -280.772902) (xy 177.93122 -280.819583)
			(xy 177.908349 -280.86316) (xy 177.878784 -280.902504) (xy 177.843291 -280.936596) (xy 177.802788 -280.964552)
			(xy 177.758326 -280.98565) (xy 177.711055 -280.999342) (xy 177.6622 -281.005274) (xy 177.613025 -281.003293)
			(xy 177.564806 -280.993449) (xy 177.51879 -280.975997) (xy 177.476169 -280.95139) (xy 177.438048 -280.920265)
			(xy 177.405413 -280.883428) (xy 177.37911 -280.841832) (xy 177.359819 -280.796556) (xy 177.348042 -280.748772)
			(xy 177.344082 -280.699718) (xy 177.027078 -280.699718) (xy 177.026574 -280.725426) (xy 177.018531 -280.776208)
			(xy 177.002643 -280.825107) (xy 176.9793 -280.870919) (xy 176.949079 -280.912515) (xy 176.912723 -280.948871)
			(xy 176.871127 -280.979092) (xy 176.825315 -281.002435) (xy 176.776416 -281.018323) (xy 176.725634 -281.026366)
			(xy 176.674218 -281.026366) (xy 176.623436 -281.018323) (xy 176.574537 -281.002435) (xy 176.528725 -280.979092)
			(xy 176.487129 -280.948871) (xy 176.450773 -280.912515) (xy 176.420552 -280.870919) (xy 176.397209 -280.825107)
			(xy 176.381321 -280.776208) (xy 176.373278 -280.725426) (xy 176.0546 -280.725426) (xy 176.046884 -280.772902)
			(xy 176.0313 -280.819583) (xy 176.008429 -280.86316) (xy 175.978864 -280.902504) (xy 175.943371 -280.936596)
			(xy 175.902868 -280.964552) (xy 175.858406 -280.98565) (xy 175.811135 -280.999342) (xy 175.76228 -281.005274)
			(xy 175.713105 -281.003293) (xy 175.664886 -280.993449) (xy 175.61887 -280.975997) (xy 175.576249 -280.95139)
			(xy 175.538128 -280.920265) (xy 175.505493 -280.883428) (xy 175.47919 -280.841832) (xy 175.459899 -280.796556)
			(xy 175.448122 -280.748772) (xy 175.444162 -280.699718) (xy 175.127158 -280.699718) (xy 175.126654 -280.725426)
			(xy 175.118611 -280.776208) (xy 175.102723 -280.825107) (xy 175.07938 -280.870919) (xy 175.049159 -280.912515)
			(xy 175.012803 -280.948871) (xy 174.971207 -280.979092) (xy 174.925395 -281.002435) (xy 174.876496 -281.018323)
			(xy 174.825714 -281.026366) (xy 174.774298 -281.026366) (xy 174.723516 -281.018323) (xy 174.674617 -281.002435)
			(xy 174.628805 -280.979092) (xy 174.587209 -280.948871) (xy 174.550853 -280.912515) (xy 174.520632 -280.870919)
			(xy 174.497289 -280.825107) (xy 174.481401 -280.776208) (xy 174.473358 -280.725426) (xy 174.15468 -280.725426)
			(xy 174.146964 -280.772902) (xy 174.13138 -280.819583) (xy 174.108509 -280.86316) (xy 174.078944 -280.902504)
			(xy 174.043451 -280.936596) (xy 174.002948 -280.964552) (xy 173.958486 -280.98565) (xy 173.911215 -280.999342)
			(xy 173.86236 -281.005274) (xy 173.813185 -281.003293) (xy 173.764966 -280.993449) (xy 173.71895 -280.975997)
			(xy 173.676329 -280.95139) (xy 173.638208 -280.920265) (xy 173.605573 -280.883428) (xy 173.57927 -280.841832)
			(xy 173.559979 -280.796556) (xy 173.548202 -280.748772) (xy 173.544242 -280.699718) (xy 173.226984 -280.699718)
			(xy 173.22648 -280.725426) (xy 173.218437 -280.776208) (xy 173.202549 -280.825107) (xy 173.179206 -280.870919)
			(xy 173.148985 -280.912515) (xy 173.112629 -280.948871) (xy 173.071033 -280.979092) (xy 173.025221 -281.002435)
			(xy 172.976322 -281.018323) (xy 172.92554 -281.026366) (xy 172.874124 -281.026366) (xy 172.823342 -281.018323)
			(xy 172.774443 -281.002435) (xy 172.728631 -280.979092) (xy 172.687035 -280.948871) (xy 172.650679 -280.912515)
			(xy 172.620458 -280.870919) (xy 172.597115 -280.825107) (xy 172.581227 -280.776208) (xy 172.573184 -280.725426)
			(xy 172.254506 -280.725426) (xy 172.24679 -280.772902) (xy 172.231206 -280.819583) (xy 172.208335 -280.86316)
			(xy 172.17877 -280.902504) (xy 172.143277 -280.936596) (xy 172.102774 -280.964552) (xy 172.058312 -280.98565)
			(xy 172.011041 -280.999342) (xy 171.962186 -281.005274) (xy 171.913011 -281.003293) (xy 171.864792 -280.993449)
			(xy 171.818776 -280.975997) (xy 171.776155 -280.95139) (xy 171.738034 -280.920265) (xy 171.705399 -280.883428)
			(xy 171.679096 -280.841832) (xy 171.659805 -280.796556) (xy 171.648028 -280.748772) (xy 171.644068 -280.699718)
			(xy 171.327064 -280.699718) (xy 171.32656 -280.725426) (xy 171.318517 -280.776208) (xy 171.302629 -280.825107)
			(xy 171.279286 -280.870919) (xy 171.249065 -280.912515) (xy 171.212709 -280.948871) (xy 171.171113 -280.979092)
			(xy 171.125301 -281.002435) (xy 171.076402 -281.018323) (xy 171.02562 -281.026366) (xy 170.974204 -281.026366)
			(xy 170.923422 -281.018323) (xy 170.874523 -281.002435) (xy 170.828711 -280.979092) (xy 170.787115 -280.948871)
			(xy 170.750759 -280.912515) (xy 170.720538 -280.870919) (xy 170.697195 -280.825107) (xy 170.681307 -280.776208)
			(xy 170.673264 -280.725426) (xy 170.354586 -280.725426) (xy 170.34687 -280.772902) (xy 170.331286 -280.819583)
			(xy 170.308415 -280.86316) (xy 170.27885 -280.902504) (xy 170.243357 -280.936596) (xy 170.202854 -280.964552)
			(xy 170.158392 -280.98565) (xy 170.111121 -280.999342) (xy 170.062266 -281.005274) (xy 170.013091 -281.003293)
			(xy 169.964872 -280.993449) (xy 169.918856 -280.975997) (xy 169.876235 -280.95139) (xy 169.838114 -280.920265)
			(xy 169.805479 -280.883428) (xy 169.779176 -280.841832) (xy 169.759885 -280.796556) (xy 169.748108 -280.748772)
			(xy 169.744148 -280.699718) (xy 169.427144 -280.699718) (xy 169.42664 -280.725426) (xy 169.418597 -280.776208)
			(xy 169.402709 -280.825107) (xy 169.379366 -280.870919) (xy 169.349145 -280.912515) (xy 169.312789 -280.948871)
			(xy 169.271193 -280.979092) (xy 169.225381 -281.002435) (xy 169.176482 -281.018323) (xy 169.1257 -281.026366)
			(xy 169.074284 -281.026366) (xy 169.023502 -281.018323) (xy 168.974603 -281.002435) (xy 168.928791 -280.979092)
			(xy 168.887195 -280.948871) (xy 168.850839 -280.912515) (xy 168.820618 -280.870919) (xy 168.797275 -280.825107)
			(xy 168.781387 -280.776208) (xy 168.773344 -280.725426) (xy 168.454666 -280.725426) (xy 168.44695 -280.772902)
			(xy 168.431366 -280.819583) (xy 168.408495 -280.86316) (xy 168.37893 -280.902504) (xy 168.343437 -280.936596)
			(xy 168.302934 -280.964552) (xy 168.258472 -280.98565) (xy 168.211201 -280.999342) (xy 168.162346 -281.005274)
			(xy 168.113171 -281.003293) (xy 168.064952 -280.993449) (xy 168.018936 -280.975997) (xy 167.976315 -280.95139)
			(xy 167.938194 -280.920265) (xy 167.905559 -280.883428) (xy 167.879256 -280.841832) (xy 167.859965 -280.796556)
			(xy 167.848188 -280.748772) (xy 167.844228 -280.699718) (xy 167.527224 -280.699718) (xy 167.52672 -280.725426)
			(xy 167.518677 -280.776208) (xy 167.502789 -280.825107) (xy 167.479446 -280.870919) (xy 167.449225 -280.912515)
			(xy 167.412869 -280.948871) (xy 167.371273 -280.979092) (xy 167.325461 -281.002435) (xy 167.276562 -281.018323)
			(xy 167.22578 -281.026366) (xy 167.174364 -281.026366) (xy 167.123582 -281.018323) (xy 167.074683 -281.002435)
			(xy 167.028871 -280.979092) (xy 166.987275 -280.948871) (xy 166.950919 -280.912515) (xy 166.920698 -280.870919)
			(xy 166.897355 -280.825107) (xy 166.881467 -280.776208) (xy 166.873424 -280.725426) (xy 166.554492 -280.725426)
			(xy 166.546776 -280.772902) (xy 166.531192 -280.819583) (xy 166.508321 -280.86316) (xy 166.478756 -280.902504)
			(xy 166.443263 -280.936596) (xy 166.40276 -280.964552) (xy 166.358298 -280.98565) (xy 166.311027 -280.999342)
			(xy 166.262172 -281.005274) (xy 166.212997 -281.003293) (xy 166.164778 -280.993449) (xy 166.118762 -280.975997)
			(xy 166.076141 -280.95139) (xy 166.03802 -280.920265) (xy 166.005385 -280.883428) (xy 165.979082 -280.841832)
			(xy 165.959791 -280.796556) (xy 165.948014 -280.748772) (xy 165.944054 -280.699718) (xy 165.626158 -280.699718)
			(xy 165.626158 -280.725608) (xy 165.617989 -280.77677) (xy 165.601855 -280.826005) (xy 165.578161 -280.87208)
			(xy 165.547499 -280.913843) (xy 165.510636 -280.950249) (xy 165.468494 -280.980389) (xy 165.422127 -281.003506)
			(xy 165.372695 -281.019025) (xy 165.347142 -281.023314) (xy 165.328092 -281.026108) (xy 165.303708 -281.054556)
			(xy 165.303708 -281.316938) (xy 165.327838 -281.345386) (xy 165.346634 -281.34818) (xy 165.370333 -281.352307)
			(xy 165.416128 -281.367033) (xy 165.459046 -281.388758) (xy 165.498027 -281.416945) (xy 165.532106 -281.450895)
			(xy 165.560439 -281.489769) (xy 165.582326 -281.532606) (xy 165.597225 -281.578344) (xy 165.604767 -281.625853)
			(xy 165.604767 -281.649932) (xy 165.944054 -281.649932) (xy 165.948014 -281.600878) (xy 165.959791 -281.553094)
			(xy 165.979082 -281.507818) (xy 166.005385 -281.466222) (xy 166.03802 -281.429385) (xy 166.076141 -281.39826)
			(xy 166.118762 -281.373653) (xy 166.164778 -281.356201) (xy 166.212997 -281.346357) (xy 166.262172 -281.344376)
			(xy 166.311027 -281.350308) (xy 166.358298 -281.364) (xy 166.40276 -281.385098) (xy 166.443263 -281.413054)
			(xy 166.478756 -281.447146) (xy 166.508321 -281.48649) (xy 166.531192 -281.530067) (xy 166.546776 -281.576748)
			(xy 166.554671 -281.625325) (xy 166.555166 -281.649932) (xy 166.894268 -281.649932) (xy 166.898228 -281.600878)
			(xy 166.910005 -281.553094) (xy 166.929296 -281.507818) (xy 166.955599 -281.466222) (xy 166.988234 -281.429385)
			(xy 167.026355 -281.39826) (xy 167.068976 -281.373653) (xy 167.114992 -281.356201) (xy 167.163211 -281.346357)
			(xy 167.212386 -281.344376) (xy 167.261241 -281.350308) (xy 167.308512 -281.364) (xy 167.352974 -281.385098)
			(xy 167.393477 -281.413054) (xy 167.42897 -281.447146) (xy 167.458535 -281.48649) (xy 167.481406 -281.530067)
			(xy 167.49699 -281.576748) (xy 167.504885 -281.625325) (xy 167.50538 -281.649932) (xy 167.844228 -281.649932)
			(xy 167.848188 -281.600878) (xy 167.859965 -281.553094) (xy 167.879256 -281.507818) (xy 167.905559 -281.466222)
			(xy 167.938194 -281.429385) (xy 167.976315 -281.39826) (xy 168.018936 -281.373653) (xy 168.064952 -281.356201)
			(xy 168.113171 -281.346357) (xy 168.162346 -281.344376) (xy 168.211201 -281.350308) (xy 168.258472 -281.364)
			(xy 168.302934 -281.385098) (xy 168.343437 -281.413054) (xy 168.37893 -281.447146) (xy 168.408495 -281.48649)
			(xy 168.431366 -281.530067) (xy 168.44695 -281.576748) (xy 168.454845 -281.625325) (xy 168.45534 -281.649932)
			(xy 168.794188 -281.649932) (xy 168.798148 -281.600878) (xy 168.809925 -281.553094) (xy 168.829216 -281.507818)
			(xy 168.855519 -281.466222) (xy 168.888154 -281.429385) (xy 168.926275 -281.39826) (xy 168.968896 -281.373653)
			(xy 169.014912 -281.356201) (xy 169.063131 -281.346357) (xy 169.112306 -281.344376) (xy 169.161161 -281.350308)
			(xy 169.208432 -281.364) (xy 169.252894 -281.385098) (xy 169.293397 -281.413054) (xy 169.32889 -281.447146)
			(xy 169.358455 -281.48649) (xy 169.381326 -281.530067) (xy 169.39691 -281.576748) (xy 169.404805 -281.625325)
			(xy 169.4053 -281.649932) (xy 169.744148 -281.649932) (xy 169.748108 -281.600878) (xy 169.759885 -281.553094)
			(xy 169.779176 -281.507818) (xy 169.805479 -281.466222) (xy 169.838114 -281.429385) (xy 169.876235 -281.39826)
			(xy 169.918856 -281.373653) (xy 169.964872 -281.356201) (xy 170.013091 -281.346357) (xy 170.062266 -281.344376)
			(xy 170.111121 -281.350308) (xy 170.158392 -281.364) (xy 170.202854 -281.385098) (xy 170.243357 -281.413054)
			(xy 170.27885 -281.447146) (xy 170.308415 -281.48649) (xy 170.331286 -281.530067) (xy 170.34687 -281.576748)
			(xy 170.354765 -281.625325) (xy 170.35526 -281.649932) (xy 170.694108 -281.649932) (xy 170.698068 -281.600878)
			(xy 170.709845 -281.553094) (xy 170.729136 -281.507818) (xy 170.755439 -281.466222) (xy 170.788074 -281.429385)
			(xy 170.826195 -281.39826) (xy 170.868816 -281.373653) (xy 170.914832 -281.356201) (xy 170.963051 -281.346357)
			(xy 171.012226 -281.344376) (xy 171.061081 -281.350308) (xy 171.108352 -281.364) (xy 171.152814 -281.385098)
			(xy 171.193317 -281.413054) (xy 171.22881 -281.447146) (xy 171.258375 -281.48649) (xy 171.281246 -281.530067)
			(xy 171.29683 -281.576748) (xy 171.304725 -281.625325) (xy 171.30522 -281.649932) (xy 171.644068 -281.649932)
			(xy 171.648028 -281.600878) (xy 171.659805 -281.553094) (xy 171.679096 -281.507818) (xy 171.705399 -281.466222)
			(xy 171.738034 -281.429385) (xy 171.776155 -281.39826) (xy 171.818776 -281.373653) (xy 171.864792 -281.356201)
			(xy 171.913011 -281.346357) (xy 171.962186 -281.344376) (xy 172.011041 -281.350308) (xy 172.058312 -281.364)
			(xy 172.102774 -281.385098) (xy 172.143277 -281.413054) (xy 172.17877 -281.447146) (xy 172.208335 -281.48649)
			(xy 172.231206 -281.530067) (xy 172.24679 -281.576748) (xy 172.254685 -281.625325) (xy 172.25518 -281.649932)
			(xy 172.594282 -281.649932) (xy 172.598242 -281.600878) (xy 172.610019 -281.553094) (xy 172.62931 -281.507818)
			(xy 172.655613 -281.466222) (xy 172.688248 -281.429385) (xy 172.726369 -281.39826) (xy 172.76899 -281.373653)
			(xy 172.815006 -281.356201) (xy 172.863225 -281.346357) (xy 172.9124 -281.344376) (xy 172.961255 -281.350308)
			(xy 173.008526 -281.364) (xy 173.052988 -281.385098) (xy 173.093491 -281.413054) (xy 173.128984 -281.447146)
			(xy 173.158549 -281.48649) (xy 173.18142 -281.530067) (xy 173.197004 -281.576748) (xy 173.204899 -281.625325)
			(xy 173.205394 -281.649932) (xy 173.544242 -281.649932) (xy 173.548202 -281.600878) (xy 173.559979 -281.553094)
			(xy 173.57927 -281.507818) (xy 173.605573 -281.466222) (xy 173.638208 -281.429385) (xy 173.676329 -281.39826)
			(xy 173.71895 -281.373653) (xy 173.764966 -281.356201) (xy 173.813185 -281.346357) (xy 173.86236 -281.344376)
			(xy 173.911215 -281.350308) (xy 173.958486 -281.364) (xy 174.002948 -281.385098) (xy 174.043451 -281.413054)
			(xy 174.078944 -281.447146) (xy 174.108509 -281.48649) (xy 174.13138 -281.530067) (xy 174.146964 -281.576748)
			(xy 174.154859 -281.625325) (xy 174.155354 -281.649932) (xy 174.494202 -281.649932) (xy 174.498162 -281.600878)
			(xy 174.509939 -281.553094) (xy 174.52923 -281.507818) (xy 174.555533 -281.466222) (xy 174.588168 -281.429385)
			(xy 174.626289 -281.39826) (xy 174.66891 -281.373653) (xy 174.714926 -281.356201) (xy 174.763145 -281.346357)
			(xy 174.81232 -281.344376) (xy 174.861175 -281.350308) (xy 174.908446 -281.364) (xy 174.952908 -281.385098)
			(xy 174.993411 -281.413054) (xy 175.028904 -281.447146) (xy 175.058469 -281.48649) (xy 175.08134 -281.530067)
			(xy 175.096924 -281.576748) (xy 175.104819 -281.625325) (xy 175.105314 -281.649932) (xy 175.444162 -281.649932)
			(xy 175.448122 -281.600878) (xy 175.459899 -281.553094) (xy 175.47919 -281.507818) (xy 175.505493 -281.466222)
			(xy 175.538128 -281.429385) (xy 175.576249 -281.39826) (xy 175.61887 -281.373653) (xy 175.664886 -281.356201)
			(xy 175.713105 -281.346357) (xy 175.76228 -281.344376) (xy 175.811135 -281.350308) (xy 175.858406 -281.364)
			(xy 175.902868 -281.385098) (xy 175.943371 -281.413054) (xy 175.978864 -281.447146) (xy 176.008429 -281.48649)
			(xy 176.0313 -281.530067) (xy 176.046884 -281.576748) (xy 176.054779 -281.625325) (xy 176.055274 -281.649932)
			(xy 176.394122 -281.649932) (xy 176.398082 -281.600878) (xy 176.409859 -281.553094) (xy 176.42915 -281.507818)
			(xy 176.455453 -281.466222) (xy 176.488088 -281.429385) (xy 176.526209 -281.39826) (xy 176.56883 -281.373653)
			(xy 176.614846 -281.356201) (xy 176.663065 -281.346357) (xy 176.71224 -281.344376) (xy 176.761095 -281.350308)
			(xy 176.808366 -281.364) (xy 176.852828 -281.385098) (xy 176.893331 -281.413054) (xy 176.928824 -281.447146)
			(xy 176.958389 -281.48649) (xy 176.98126 -281.530067) (xy 176.996844 -281.576748) (xy 177.004739 -281.625325)
			(xy 177.005234 -281.649932) (xy 177.344082 -281.649932) (xy 177.348042 -281.600878) (xy 177.359819 -281.553094)
			(xy 177.37911 -281.507818) (xy 177.405413 -281.466222) (xy 177.438048 -281.429385) (xy 177.476169 -281.39826)
			(xy 177.51879 -281.373653) (xy 177.564806 -281.356201) (xy 177.613025 -281.346357) (xy 177.6622 -281.344376)
			(xy 177.711055 -281.350308) (xy 177.758326 -281.364) (xy 177.802788 -281.385098) (xy 177.843291 -281.413054)
			(xy 177.878784 -281.447146) (xy 177.908349 -281.48649) (xy 177.93122 -281.530067) (xy 177.946804 -281.576748)
			(xy 177.954699 -281.625325) (xy 177.955194 -281.649932) (xy 178.294042 -281.649932) (xy 178.298002 -281.600878)
			(xy 178.309779 -281.553094) (xy 178.32907 -281.507818) (xy 178.355373 -281.466222) (xy 178.388008 -281.429385)
			(xy 178.426129 -281.39826) (xy 178.46875 -281.373653) (xy 178.514766 -281.356201) (xy 178.562985 -281.346357)
			(xy 178.61216 -281.344376) (xy 178.661015 -281.350308) (xy 178.708286 -281.364) (xy 178.752748 -281.385098)
			(xy 178.793251 -281.413054) (xy 178.828744 -281.447146) (xy 178.858309 -281.48649) (xy 178.88118 -281.530067)
			(xy 178.896764 -281.576748) (xy 178.904659 -281.625325) (xy 178.905154 -281.649932) (xy 179.244256 -281.649932)
			(xy 179.248216 -281.600878) (xy 179.259993 -281.553094) (xy 179.279284 -281.507818) (xy 179.305587 -281.466222)
			(xy 179.338222 -281.429385) (xy 179.376343 -281.39826) (xy 179.418964 -281.373653) (xy 179.46498 -281.356201)
			(xy 179.513199 -281.346357) (xy 179.562374 -281.344376) (xy 179.611229 -281.350308) (xy 179.6585 -281.364)
			(xy 179.702962 -281.385098) (xy 179.743465 -281.413054) (xy 179.778958 -281.447146) (xy 179.808523 -281.48649)
			(xy 179.831394 -281.530067) (xy 179.846978 -281.576748) (xy 179.854873 -281.625325) (xy 179.855368 -281.649932)
			(xy 180.194216 -281.649932) (xy 180.198176 -281.600878) (xy 180.209953 -281.553094) (xy 180.229244 -281.507818)
			(xy 180.255547 -281.466222) (xy 180.288182 -281.429385) (xy 180.326303 -281.39826) (xy 180.368924 -281.373653)
			(xy 180.41494 -281.356201) (xy 180.463159 -281.346357) (xy 180.512334 -281.344376) (xy 180.561189 -281.350308)
			(xy 180.60846 -281.364) (xy 180.652922 -281.385098) (xy 180.693425 -281.413054) (xy 180.728918 -281.447146)
			(xy 180.758483 -281.48649) (xy 180.781354 -281.530067) (xy 180.796938 -281.576748) (xy 180.804833 -281.625325)
			(xy 180.805328 -281.649932) (xy 181.144176 -281.649932) (xy 181.148136 -281.600878) (xy 181.159913 -281.553094)
			(xy 181.179204 -281.507818) (xy 181.205507 -281.466222) (xy 181.238142 -281.429385) (xy 181.276263 -281.39826)
			(xy 181.318884 -281.373653) (xy 181.3649 -281.356201) (xy 181.413119 -281.346357) (xy 181.462294 -281.344376)
			(xy 181.511149 -281.350308) (xy 181.55842 -281.364) (xy 181.602882 -281.385098) (xy 181.643385 -281.413054)
			(xy 181.678878 -281.447146) (xy 181.708443 -281.48649) (xy 181.731314 -281.530067) (xy 181.746898 -281.576748)
			(xy 181.754793 -281.625325) (xy 181.755288 -281.649932) (xy 182.094136 -281.649932) (xy 182.098096 -281.600878)
			(xy 182.109873 -281.553094) (xy 182.129164 -281.507818) (xy 182.155467 -281.466222) (xy 182.188102 -281.429385)
			(xy 182.226223 -281.39826) (xy 182.268844 -281.373653) (xy 182.31486 -281.356201) (xy 182.363079 -281.346357)
			(xy 182.412254 -281.344376) (xy 182.461109 -281.350308) (xy 182.50838 -281.364) (xy 182.552842 -281.385098)
			(xy 182.593345 -281.413054) (xy 182.628838 -281.447146) (xy 182.658403 -281.48649) (xy 182.681274 -281.530067)
			(xy 182.696858 -281.576748) (xy 182.704753 -281.625325) (xy 182.705248 -281.649932) (xy 183.044096 -281.649932)
			(xy 183.048056 -281.600878) (xy 183.059833 -281.553094) (xy 183.079124 -281.507818) (xy 183.105427 -281.466222)
			(xy 183.138062 -281.429385) (xy 183.176183 -281.39826) (xy 183.218804 -281.373653) (xy 183.26482 -281.356201)
			(xy 183.313039 -281.346357) (xy 183.362214 -281.344376) (xy 183.411069 -281.350308) (xy 183.45834 -281.364)
			(xy 183.502802 -281.385098) (xy 183.543305 -281.413054) (xy 183.578798 -281.447146) (xy 183.608363 -281.48649)
			(xy 183.631234 -281.530067) (xy 183.646818 -281.576748) (xy 183.654713 -281.625325) (xy 183.655208 -281.649932)
			(xy 183.994056 -281.649932) (xy 183.998016 -281.600878) (xy 184.009793 -281.553094) (xy 184.029084 -281.507818)
			(xy 184.055387 -281.466222) (xy 184.088022 -281.429385) (xy 184.126143 -281.39826) (xy 184.168764 -281.373653)
			(xy 184.21478 -281.356201) (xy 184.262999 -281.346357) (xy 184.312174 -281.344376) (xy 184.361029 -281.350308)
			(xy 184.4083 -281.364) (xy 184.452762 -281.385098) (xy 184.493265 -281.413054) (xy 184.528758 -281.447146)
			(xy 184.558323 -281.48649) (xy 184.581194 -281.530067) (xy 184.596778 -281.576748) (xy 184.604673 -281.625325)
			(xy 184.605168 -281.649932) (xy 184.94427 -281.649932) (xy 184.94823 -281.600878) (xy 184.960007 -281.553094)
			(xy 184.979298 -281.507818) (xy 185.005601 -281.466222) (xy 185.038236 -281.429385) (xy 185.076357 -281.39826)
			(xy 185.118978 -281.373653) (xy 185.164994 -281.356201) (xy 185.213213 -281.346357) (xy 185.262388 -281.344376)
			(xy 185.311243 -281.350308) (xy 185.358514 -281.364) (xy 185.402976 -281.385098) (xy 185.443479 -281.413054)
			(xy 185.478972 -281.447146) (xy 185.508537 -281.48649) (xy 185.531408 -281.530067) (xy 185.546992 -281.576748)
			(xy 185.554887 -281.625325) (xy 185.555382 -281.649932) (xy 185.89423 -281.649932) (xy 185.89819 -281.600878)
			(xy 185.909967 -281.553094) (xy 185.929258 -281.507818) (xy 185.955561 -281.466222) (xy 185.988196 -281.429385)
			(xy 186.026317 -281.39826) (xy 186.068938 -281.373653) (xy 186.114954 -281.356201) (xy 186.163173 -281.346357)
			(xy 186.212348 -281.344376) (xy 186.261203 -281.350308) (xy 186.308474 -281.364) (xy 186.352936 -281.385098)
			(xy 186.393439 -281.413054) (xy 186.428932 -281.447146) (xy 186.458497 -281.48649) (xy 186.481368 -281.530067)
			(xy 186.496952 -281.576748) (xy 186.504847 -281.625325) (xy 186.505342 -281.649932) (xy 186.84419 -281.649932)
			(xy 186.84815 -281.600878) (xy 186.859927 -281.553094) (xy 186.879218 -281.507818) (xy 186.905521 -281.466222)
			(xy 186.938156 -281.429385) (xy 186.976277 -281.39826) (xy 187.018898 -281.373653) (xy 187.064914 -281.356201)
			(xy 187.113133 -281.346357) (xy 187.162308 -281.344376) (xy 187.211163 -281.350308) (xy 187.258434 -281.364)
			(xy 187.302896 -281.385098) (xy 187.343399 -281.413054) (xy 187.378892 -281.447146) (xy 187.408457 -281.48649)
			(xy 187.431328 -281.530067) (xy 187.446912 -281.576748) (xy 187.454807 -281.625325) (xy 187.455302 -281.649932)
			(xy 187.79415 -281.649932) (xy 187.79811 -281.600878) (xy 187.809887 -281.553094) (xy 187.829178 -281.507818)
			(xy 187.855481 -281.466222) (xy 187.888116 -281.429385) (xy 187.926237 -281.39826) (xy 187.968858 -281.373653)
			(xy 188.014874 -281.356201) (xy 188.063093 -281.346357) (xy 188.112268 -281.344376) (xy 188.161123 -281.350308)
			(xy 188.208394 -281.364) (xy 188.252856 -281.385098) (xy 188.293359 -281.413054) (xy 188.328852 -281.447146)
			(xy 188.358417 -281.48649) (xy 188.381288 -281.530067) (xy 188.396872 -281.576748) (xy 188.404767 -281.625325)
			(xy 188.405262 -281.649932) (xy 188.74411 -281.649932) (xy 188.74807 -281.600878) (xy 188.759847 -281.553094)
			(xy 188.779138 -281.507818) (xy 188.805441 -281.466222) (xy 188.838076 -281.429385) (xy 188.876197 -281.39826)
			(xy 188.918818 -281.373653) (xy 188.964834 -281.356201) (xy 189.013053 -281.346357) (xy 189.062228 -281.344376)
			(xy 189.111083 -281.350308) (xy 189.158354 -281.364) (xy 189.202816 -281.385098) (xy 189.243319 -281.413054)
			(xy 189.278812 -281.447146) (xy 189.308377 -281.48649) (xy 189.331248 -281.530067) (xy 189.346832 -281.576748)
			(xy 189.354727 -281.625325) (xy 189.355222 -281.649932) (xy 189.69407 -281.649932) (xy 189.69803 -281.600878)
			(xy 189.709807 -281.553094) (xy 189.729098 -281.507818) (xy 189.755401 -281.466222) (xy 189.788036 -281.429385)
			(xy 189.826157 -281.39826) (xy 189.868778 -281.373653) (xy 189.914794 -281.356201) (xy 189.963013 -281.346357)
			(xy 190.012188 -281.344376) (xy 190.061043 -281.350308) (xy 190.108314 -281.364) (xy 190.152776 -281.385098)
			(xy 190.193279 -281.413054) (xy 190.228772 -281.447146) (xy 190.258337 -281.48649) (xy 190.281208 -281.530067)
			(xy 190.296792 -281.576748) (xy 190.304687 -281.625325) (xy 190.305182 -281.649932) (xy 190.644284 -281.649932)
			(xy 190.648244 -281.600878) (xy 190.660021 -281.553094) (xy 190.679312 -281.507818) (xy 190.705615 -281.466222)
			(xy 190.73825 -281.429385) (xy 190.776371 -281.39826) (xy 190.818992 -281.373653) (xy 190.865008 -281.356201)
			(xy 190.913227 -281.346357) (xy 190.962402 -281.344376) (xy 191.011257 -281.350308) (xy 191.058528 -281.364)
			(xy 191.10299 -281.385098) (xy 191.143493 -281.413054) (xy 191.178986 -281.447146) (xy 191.208551 -281.48649)
			(xy 191.231422 -281.530067) (xy 191.247006 -281.576748) (xy 191.254901 -281.625325) (xy 191.255396 -281.649932)
			(xy 191.594244 -281.649932) (xy 191.598204 -281.600878) (xy 191.609981 -281.553094) (xy 191.629272 -281.507818)
			(xy 191.655575 -281.466222) (xy 191.68821 -281.429385) (xy 191.726331 -281.39826) (xy 191.768952 -281.373653)
			(xy 191.814968 -281.356201) (xy 191.863187 -281.346357) (xy 191.912362 -281.344376) (xy 191.961217 -281.350308)
			(xy 192.008488 -281.364) (xy 192.05295 -281.385098) (xy 192.093453 -281.413054) (xy 192.128946 -281.447146)
			(xy 192.158511 -281.48649) (xy 192.181382 -281.530067) (xy 192.196966 -281.576748) (xy 192.204861 -281.625325)
			(xy 192.205356 -281.649932) (xy 192.544204 -281.649932) (xy 192.548164 -281.600878) (xy 192.559941 -281.553094)
			(xy 192.579232 -281.507818) (xy 192.605535 -281.466222) (xy 192.63817 -281.429385) (xy 192.676291 -281.39826)
			(xy 192.718912 -281.373653) (xy 192.764928 -281.356201) (xy 192.813147 -281.346357) (xy 192.862322 -281.344376)
			(xy 192.911177 -281.350308) (xy 192.958448 -281.364) (xy 193.00291 -281.385098) (xy 193.043413 -281.413054)
			(xy 193.078906 -281.447146) (xy 193.108471 -281.48649) (xy 193.131342 -281.530067) (xy 193.146926 -281.576748)
			(xy 193.154821 -281.625325) (xy 193.155311 -281.649678) (xy 193.49391 -281.649678) (xy 193.49787 -281.600624)
			(xy 193.509647 -281.55284) (xy 193.528938 -281.507564) (xy 193.555241 -281.465968) (xy 193.587876 -281.429131)
			(xy 193.625997 -281.398006) (xy 193.668618 -281.373399) (xy 193.714634 -281.355947) (xy 193.762853 -281.346103)
			(xy 193.812028 -281.344122) (xy 193.860883 -281.350054) (xy 193.908154 -281.363746) (xy 193.952616 -281.384844)
			(xy 193.993119 -281.4128) (xy 194.028612 -281.446892) (xy 194.058177 -281.486236) (xy 194.081048 -281.529813)
			(xy 194.096632 -281.576494) (xy 194.104527 -281.625071) (xy 194.105022 -281.649678) (xy 194.105017 -281.649932)
			(xy 194.44387 -281.649932) (xy 194.44783 -281.600878) (xy 194.459607 -281.553094) (xy 194.478898 -281.507818)
			(xy 194.505201 -281.466222) (xy 194.537836 -281.429385) (xy 194.575957 -281.39826) (xy 194.618578 -281.373653)
			(xy 194.664594 -281.356201) (xy 194.712813 -281.346357) (xy 194.761988 -281.344376) (xy 194.810843 -281.350308)
			(xy 194.858114 -281.364) (xy 194.902576 -281.385098) (xy 194.943079 -281.413054) (xy 194.978572 -281.447146)
			(xy 195.008137 -281.48649) (xy 195.031008 -281.530067) (xy 195.046592 -281.576748) (xy 195.054487 -281.625325)
			(xy 195.054982 -281.649932) (xy 195.394084 -281.649932) (xy 195.398044 -281.600878) (xy 195.409821 -281.553094)
			(xy 195.429112 -281.507818) (xy 195.455415 -281.466222) (xy 195.48805 -281.429385) (xy 195.526171 -281.39826)
			(xy 195.568792 -281.373653) (xy 195.614808 -281.356201) (xy 195.663027 -281.346357) (xy 195.712202 -281.344376)
			(xy 195.761057 -281.350308) (xy 195.808328 -281.364) (xy 195.85279 -281.385098) (xy 195.893293 -281.413054)
			(xy 195.928786 -281.447146) (xy 195.958351 -281.48649) (xy 195.981222 -281.530067) (xy 195.996806 -281.576748)
			(xy 196.004701 -281.625325) (xy 196.005196 -281.649932) (xy 196.344044 -281.649932) (xy 196.348004 -281.600878)
			(xy 196.359781 -281.553094) (xy 196.379072 -281.507818) (xy 196.405375 -281.466222) (xy 196.43801 -281.429385)
			(xy 196.476131 -281.39826) (xy 196.518752 -281.373653) (xy 196.564768 -281.356201) (xy 196.612987 -281.346357)
			(xy 196.662162 -281.344376) (xy 196.711017 -281.350308) (xy 196.758288 -281.364) (xy 196.80275 -281.385098)
			(xy 196.843253 -281.413054) (xy 196.878746 -281.447146) (xy 196.908311 -281.48649) (xy 196.931182 -281.530067)
			(xy 196.946766 -281.576748) (xy 196.954661 -281.625325) (xy 196.955156 -281.649932) (xy 196.954661 -281.674539)
			(xy 196.954482 -281.67564) (xy 197.273414 -281.67564) (xy 197.273414 -281.624224) (xy 197.281457 -281.573442)
			(xy 197.297345 -281.524543) (xy 197.320688 -281.478731) (xy 197.350909 -281.437135) (xy 197.387265 -281.400779)
			(xy 197.428861 -281.370558) (xy 197.474673 -281.347215) (xy 197.523572 -281.331327) (xy 197.574354 -281.323284)
			(xy 197.62577 -281.323284) (xy 197.676552 -281.331327) (xy 197.725451 -281.347215) (xy 197.771263 -281.370558)
			(xy 197.812859 -281.400779) (xy 197.849215 -281.437135) (xy 197.879436 -281.478731) (xy 197.902779 -281.524543)
			(xy 197.918667 -281.573442) (xy 197.92671 -281.624224) (xy 197.927214 -281.649932) (xy 197.92671 -281.67564)
			(xy 198.223374 -281.67564) (xy 198.223374 -281.624224) (xy 198.231417 -281.573442) (xy 198.247305 -281.524543)
			(xy 198.270648 -281.478731) (xy 198.300869 -281.437135) (xy 198.337225 -281.400779) (xy 198.378821 -281.370558)
			(xy 198.424633 -281.347215) (xy 198.473532 -281.331327) (xy 198.524314 -281.323284) (xy 198.57573 -281.323284)
			(xy 198.626512 -281.331327) (xy 198.660401 -281.342338) (xy 219.957142 -281.342338) (xy 219.957591 -281.315084)
			(xy 219.965344 -281.26113) (xy 219.980698 -281.208829) (xy 220.003339 -281.159245) (xy 220.032808 -281.11339)
			(xy 220.068504 -281.072195) (xy 220.109699 -281.036501) (xy 220.155556 -281.007034) (xy 220.20514 -280.984393)
			(xy 220.257441 -280.969041) (xy 220.311396 -280.96129) (xy 220.33865 -280.96083) (xy 220.367389 -280.961342)
			(xy 220.424216 -280.96997) (xy 220.479106 -280.987024) (xy 220.530818 -281.012118) (xy 220.578181 -281.044683)
			(xy 220.599508 -281.063954) (xy 220.60662 -281.070558) (xy 220.624146 -281.07767) (xy 220.713554 -281.07767)
			(xy 220.73108 -281.070558) (xy 220.738192 -281.063954) (xy 220.759519 -281.044684) (xy 220.806882 -281.012119)
			(xy 220.858593 -280.987028) (xy 220.913484 -280.969978) (xy 220.970311 -280.961356) (xy 221.027789 -280.961356)
			(xy 221.084616 -280.969978) (xy 221.139507 -280.987028) (xy 221.191218 -281.012119) (xy 221.238581 -281.044684)
			(xy 221.259908 -281.063954) (xy 221.26702 -281.070558) (xy 221.284546 -281.07767) (xy 221.373954 -281.07767)
			(xy 221.39148 -281.070558) (xy 221.398592 -281.063954) (xy 221.419901 -281.044662) (xy 221.467268 -281.012098)
			(xy 221.518984 -280.987009) (xy 221.573879 -280.969964) (xy 221.63071 -280.961347) (xy 221.65945 -280.96083)
			(xy 221.689572 -280.961438) (xy 221.749066 -280.970911) (xy 221.806334 -280.989613) (xy 221.859951 -281.017081)
			(xy 221.908588 -281.052631) (xy 221.930214 -281.073606) (xy 221.937326 -281.080972) (xy 221.956122 -281.088592)
			(xy 222.048578 -281.088592) (xy 222.067374 -281.080972) (xy 222.074486 -281.073606) (xy 222.096095 -281.052608)
			(xy 222.144728 -281.017042) (xy 222.198348 -280.989565) (xy 222.255622 -280.970861) (xy 222.315125 -280.961395)
			(xy 222.34525 -280.96083) (xy 222.372503 -280.961302) (xy 222.426456 -280.969053) (xy 222.478756 -280.984405)
			(xy 222.528338 -281.007044) (xy 222.574194 -281.03651) (xy 222.615388 -281.072204) (xy 222.651082 -281.113397)
			(xy 222.68055 -281.159251) (xy 222.703191 -281.208833) (xy 222.718544 -281.261132) (xy 222.726297 -281.315085)
			(xy 222.726758 -281.342338) (xy 222.726303 -281.370075) (xy 222.718308 -281.42497) (xy 222.702434 -281.478124)
			(xy 222.679017 -281.528413) (xy 222.648552 -281.574772) (xy 222.630492 -281.59583) (xy 222.624142 -281.602688)
			(xy 222.617538 -281.620214) (xy 222.617538 -281.706574) (xy 222.624142 -281.723846) (xy 222.630492 -281.730704)
			(xy 222.648552 -281.751802) (xy 222.679062 -281.798204) (xy 222.702529 -281.848536) (xy 222.718457 -281.901736)
			(xy 222.726509 -281.956683) (xy 222.727012 -281.98445) (xy 222.726498 -282.011701) (xy 222.718748 -282.06565)
			(xy 222.703399 -282.117947) (xy 222.680762 -282.167527) (xy 222.6513 -282.21338) (xy 222.615611 -282.254573)
			(xy 222.574423 -282.290267) (xy 222.528574 -282.319736) (xy 222.478998 -282.34238) (xy 222.426703 -282.357737)
			(xy 222.372755 -282.365494) (xy 222.345504 -282.365958) (xy 222.315381 -282.365383) (xy 222.255885 -282.355902)
			(xy 222.198617 -282.337192) (xy 222.145 -282.309718) (xy 222.096365 -282.27416) (xy 222.07474 -282.253182)
			(xy 222.067628 -282.245816) (xy 222.048832 -282.238196) (xy 221.956376 -282.238196) (xy 221.93758 -282.245816)
			(xy 221.930468 -282.253182) (xy 221.908833 -282.274152) (xy 221.860207 -282.309722) (xy 221.806594 -282.337204)
			(xy 221.749325 -282.355915) (xy 221.689828 -282.365389) (xy 221.659704 -282.365958) (xy 221.630966 -282.365416)
			(xy 221.57414 -282.356796) (xy 221.51925 -282.339749) (xy 221.467538 -282.314662) (xy 221.420174 -282.282102)
			(xy 221.398846 -282.262834) (xy 221.391734 -282.25623) (xy 221.374208 -282.249118) (xy 221.2848 -282.249118)
			(xy 221.267274 -282.25623) (xy 221.260162 -282.262834) (xy 221.238835 -282.282104) (xy 221.191472 -282.314669)
			(xy 221.139761 -282.33976) (xy 221.08487 -282.35681) (xy 221.028043 -282.365432) (xy 220.970565 -282.365432)
			(xy 220.913738 -282.35681) (xy 220.858847 -282.33976) (xy 220.807136 -282.314669) (xy 220.759773 -282.282104)
			(xy 220.738446 -282.262834) (xy 220.731334 -282.25623) (xy 220.713808 -282.249118) (xy 220.6244 -282.249118)
			(xy 220.606874 -282.25623) (xy 220.599762 -282.262834) (xy 220.578429 -282.282098) (xy 220.531069 -282.314666)
			(xy 220.479359 -282.339761) (xy 220.424469 -282.356813) (xy 220.367643 -282.365437) (xy 220.338904 -282.365958)
			(xy 220.311649 -282.365541) (xy 220.257694 -282.357783) (xy 220.205392 -282.342425) (xy 220.155809 -282.319779)
			(xy 220.109953 -282.290307) (xy 220.068759 -282.254608) (xy 220.033065 -282.21341) (xy 220.003599 -282.167551)
			(xy 219.980959 -282.117965) (xy 219.965607 -282.065661) (xy 219.957856 -282.011705) (xy 219.957396 -281.98445)
			(xy 219.957855 -281.956713) (xy 219.965851 -281.901819) (xy 219.981725 -281.848666) (xy 220.005141 -281.798377)
			(xy 220.035603 -281.752016) (xy 220.053662 -281.730958) (xy 220.060012 -281.7241) (xy 220.066616 -281.706574)
			(xy 220.066616 -281.620214) (xy 220.060012 -281.602942) (xy 220.053662 -281.596084) (xy 220.035589 -281.574997)
			(xy 220.005082 -281.528592) (xy 219.981619 -281.478257) (xy 219.965694 -281.425054) (xy 219.957644 -281.370105)
			(xy 219.957142 -281.342338) (xy 198.660401 -281.342338) (xy 198.675411 -281.347215) (xy 198.721223 -281.370558)
			(xy 198.762819 -281.400779) (xy 198.799175 -281.437135) (xy 198.829396 -281.478731) (xy 198.852739 -281.524543)
			(xy 198.868627 -281.573442) (xy 198.87667 -281.624224) (xy 198.877174 -281.649932) (xy 198.877169 -281.650186)
			(xy 199.194432 -281.650186) (xy 199.198392 -281.601132) (xy 199.210169 -281.553348) (xy 199.22946 -281.508072)
			(xy 199.255763 -281.466476) (xy 199.288398 -281.429639) (xy 199.326519 -281.398514) (xy 199.36914 -281.373907)
			(xy 199.415156 -281.356455) (xy 199.463375 -281.346611) (xy 199.51255 -281.34463) (xy 199.561405 -281.350562)
			(xy 199.608676 -281.364254) (xy 199.653138 -281.385352) (xy 199.693641 -281.413308) (xy 199.729134 -281.4474)
			(xy 199.758699 -281.486744) (xy 199.78157 -281.530321) (xy 199.797154 -281.577002) (xy 199.805049 -281.625579)
			(xy 199.805544 -281.650186) (xy 199.805049 -281.674793) (xy 199.797154 -281.72337) (xy 199.78157 -281.770051)
			(xy 199.758699 -281.813628) (xy 199.729134 -281.852972) (xy 199.693641 -281.887064) (xy 199.653138 -281.91502)
			(xy 199.608676 -281.936118) (xy 199.561405 -281.94981) (xy 199.51255 -281.955742) (xy 199.463375 -281.953761)
			(xy 199.415156 -281.943917) (xy 199.36914 -281.926465) (xy 199.326519 -281.901858) (xy 199.288398 -281.870733)
			(xy 199.255763 -281.833896) (xy 199.22946 -281.7923) (xy 199.210169 -281.747024) (xy 199.198392 -281.69924)
			(xy 199.194432 -281.650186) (xy 198.877169 -281.650186) (xy 198.87667 -281.67564) (xy 198.868627 -281.726422)
			(xy 198.852739 -281.775321) (xy 198.829396 -281.821133) (xy 198.799175 -281.862729) (xy 198.762819 -281.899085)
			(xy 198.721223 -281.929306) (xy 198.675411 -281.952649) (xy 198.626512 -281.968537) (xy 198.57573 -281.97658)
			(xy 198.524314 -281.97658) (xy 198.473532 -281.968537) (xy 198.424633 -281.952649) (xy 198.378821 -281.929306)
			(xy 198.337225 -281.899085) (xy 198.300869 -281.862729) (xy 198.270648 -281.821133) (xy 198.247305 -281.775321)
			(xy 198.231417 -281.726422) (xy 198.223374 -281.67564) (xy 197.92671 -281.67564) (xy 197.918667 -281.726422)
			(xy 197.902779 -281.775321) (xy 197.879436 -281.821133) (xy 197.849215 -281.862729) (xy 197.812859 -281.899085)
			(xy 197.771263 -281.929306) (xy 197.725451 -281.952649) (xy 197.676552 -281.968537) (xy 197.62577 -281.97658)
			(xy 197.574354 -281.97658) (xy 197.523572 -281.968537) (xy 197.474673 -281.952649) (xy 197.428861 -281.929306)
			(xy 197.387265 -281.899085) (xy 197.350909 -281.862729) (xy 197.320688 -281.821133) (xy 197.297345 -281.775321)
			(xy 197.281457 -281.726422) (xy 197.273414 -281.67564) (xy 196.954482 -281.67564) (xy 196.946766 -281.723116)
			(xy 196.931182 -281.769797) (xy 196.908311 -281.813374) (xy 196.878746 -281.852718) (xy 196.843253 -281.88681)
			(xy 196.80275 -281.914766) (xy 196.758288 -281.935864) (xy 196.711017 -281.949556) (xy 196.662162 -281.955488)
			(xy 196.612987 -281.953507) (xy 196.564768 -281.943663) (xy 196.518752 -281.926211) (xy 196.476131 -281.901604)
			(xy 196.43801 -281.870479) (xy 196.405375 -281.833642) (xy 196.379072 -281.792046) (xy 196.359781 -281.74677)
			(xy 196.348004 -281.698986) (xy 196.344044 -281.649932) (xy 196.005196 -281.649932) (xy 196.004701 -281.674539)
			(xy 195.996806 -281.723116) (xy 195.981222 -281.769797) (xy 195.958351 -281.813374) (xy 195.928786 -281.852718)
			(xy 195.893293 -281.88681) (xy 195.85279 -281.914766) (xy 195.808328 -281.935864) (xy 195.761057 -281.949556)
			(xy 195.712202 -281.955488) (xy 195.663027 -281.953507) (xy 195.614808 -281.943663) (xy 195.568792 -281.926211)
			(xy 195.526171 -281.901604) (xy 195.48805 -281.870479) (xy 195.455415 -281.833642) (xy 195.429112 -281.792046)
			(xy 195.409821 -281.74677) (xy 195.398044 -281.698986) (xy 195.394084 -281.649932) (xy 195.054982 -281.649932)
			(xy 195.054487 -281.674539) (xy 195.046592 -281.723116) (xy 195.031008 -281.769797) (xy 195.008137 -281.813374)
			(xy 194.978572 -281.852718) (xy 194.943079 -281.88681) (xy 194.902576 -281.914766) (xy 194.858114 -281.935864)
			(xy 194.810843 -281.949556) (xy 194.761988 -281.955488) (xy 194.712813 -281.953507) (xy 194.664594 -281.943663)
			(xy 194.618578 -281.926211) (xy 194.575957 -281.901604) (xy 194.537836 -281.870479) (xy 194.505201 -281.833642)
			(xy 194.478898 -281.792046) (xy 194.459607 -281.74677) (xy 194.44783 -281.698986) (xy 194.44387 -281.649932)
			(xy 194.105017 -281.649932) (xy 194.104527 -281.674285) (xy 194.096632 -281.722862) (xy 194.081048 -281.769543)
			(xy 194.058177 -281.81312) (xy 194.028612 -281.852464) (xy 193.993119 -281.886556) (xy 193.952616 -281.914512)
			(xy 193.908154 -281.93561) (xy 193.860883 -281.949302) (xy 193.812028 -281.955234) (xy 193.762853 -281.953253)
			(xy 193.714634 -281.943409) (xy 193.668618 -281.925957) (xy 193.625997 -281.90135) (xy 193.587876 -281.870225)
			(xy 193.555241 -281.833388) (xy 193.528938 -281.791792) (xy 193.509647 -281.746516) (xy 193.49787 -281.698732)
			(xy 193.49391 -281.649678) (xy 193.155311 -281.649678) (xy 193.155316 -281.649932) (xy 193.154821 -281.674539)
			(xy 193.146926 -281.723116) (xy 193.131342 -281.769797) (xy 193.108471 -281.813374) (xy 193.078906 -281.852718)
			(xy 193.043413 -281.88681) (xy 193.00291 -281.914766) (xy 192.958448 -281.935864) (xy 192.911177 -281.949556)
			(xy 192.862322 -281.955488) (xy 192.813147 -281.953507) (xy 192.764928 -281.943663) (xy 192.718912 -281.926211)
			(xy 192.676291 -281.901604) (xy 192.63817 -281.870479) (xy 192.605535 -281.833642) (xy 192.579232 -281.792046)
			(xy 192.559941 -281.74677) (xy 192.548164 -281.698986) (xy 192.544204 -281.649932) (xy 192.205356 -281.649932)
			(xy 192.204861 -281.674539) (xy 192.196966 -281.723116) (xy 192.181382 -281.769797) (xy 192.158511 -281.813374)
			(xy 192.128946 -281.852718) (xy 192.093453 -281.88681) (xy 192.05295 -281.914766) (xy 192.008488 -281.935864)
			(xy 191.961217 -281.949556) (xy 191.912362 -281.955488) (xy 191.863187 -281.953507) (xy 191.814968 -281.943663)
			(xy 191.768952 -281.926211) (xy 191.726331 -281.901604) (xy 191.68821 -281.870479) (xy 191.655575 -281.833642)
			(xy 191.629272 -281.792046) (xy 191.609981 -281.74677) (xy 191.598204 -281.698986) (xy 191.594244 -281.649932)
			(xy 191.255396 -281.649932) (xy 191.254901 -281.674539) (xy 191.247006 -281.723116) (xy 191.231422 -281.769797)
			(xy 191.208551 -281.813374) (xy 191.178986 -281.852718) (xy 191.143493 -281.88681) (xy 191.10299 -281.914766)
			(xy 191.058528 -281.935864) (xy 191.011257 -281.949556) (xy 190.962402 -281.955488) (xy 190.913227 -281.953507)
			(xy 190.865008 -281.943663) (xy 190.818992 -281.926211) (xy 190.776371 -281.901604) (xy 190.73825 -281.870479)
			(xy 190.705615 -281.833642) (xy 190.679312 -281.792046) (xy 190.660021 -281.74677) (xy 190.648244 -281.698986)
			(xy 190.644284 -281.649932) (xy 190.305182 -281.649932) (xy 190.304687 -281.674539) (xy 190.296792 -281.723116)
			(xy 190.281208 -281.769797) (xy 190.258337 -281.813374) (xy 190.228772 -281.852718) (xy 190.193279 -281.88681)
			(xy 190.152776 -281.914766) (xy 190.108314 -281.935864) (xy 190.061043 -281.949556) (xy 190.012188 -281.955488)
			(xy 189.963013 -281.953507) (xy 189.914794 -281.943663) (xy 189.868778 -281.926211) (xy 189.826157 -281.901604)
			(xy 189.788036 -281.870479) (xy 189.755401 -281.833642) (xy 189.729098 -281.792046) (xy 189.709807 -281.74677)
			(xy 189.69803 -281.698986) (xy 189.69407 -281.649932) (xy 189.355222 -281.649932) (xy 189.354727 -281.674539)
			(xy 189.346832 -281.723116) (xy 189.331248 -281.769797) (xy 189.308377 -281.813374) (xy 189.278812 -281.852718)
			(xy 189.243319 -281.88681) (xy 189.202816 -281.914766) (xy 189.158354 -281.935864) (xy 189.111083 -281.949556)
			(xy 189.062228 -281.955488) (xy 189.013053 -281.953507) (xy 188.964834 -281.943663) (xy 188.918818 -281.926211)
			(xy 188.876197 -281.901604) (xy 188.838076 -281.870479) (xy 188.805441 -281.833642) (xy 188.779138 -281.792046)
			(xy 188.759847 -281.74677) (xy 188.74807 -281.698986) (xy 188.74411 -281.649932) (xy 188.405262 -281.649932)
			(xy 188.404767 -281.674539) (xy 188.396872 -281.723116) (xy 188.381288 -281.769797) (xy 188.358417 -281.813374)
			(xy 188.328852 -281.852718) (xy 188.293359 -281.88681) (xy 188.252856 -281.914766) (xy 188.208394 -281.935864)
			(xy 188.161123 -281.949556) (xy 188.112268 -281.955488) (xy 188.063093 -281.953507) (xy 188.014874 -281.943663)
			(xy 187.968858 -281.926211) (xy 187.926237 -281.901604) (xy 187.888116 -281.870479) (xy 187.855481 -281.833642)
			(xy 187.829178 -281.792046) (xy 187.809887 -281.74677) (xy 187.79811 -281.698986) (xy 187.79415 -281.649932)
			(xy 187.455302 -281.649932) (xy 187.454807 -281.674539) (xy 187.446912 -281.723116) (xy 187.431328 -281.769797)
			(xy 187.408457 -281.813374) (xy 187.378892 -281.852718) (xy 187.343399 -281.88681) (xy 187.302896 -281.914766)
			(xy 187.258434 -281.935864) (xy 187.211163 -281.949556) (xy 187.162308 -281.955488) (xy 187.113133 -281.953507)
			(xy 187.064914 -281.943663) (xy 187.018898 -281.926211) (xy 186.976277 -281.901604) (xy 186.938156 -281.870479)
			(xy 186.905521 -281.833642) (xy 186.879218 -281.792046) (xy 186.859927 -281.74677) (xy 186.84815 -281.698986)
			(xy 186.84419 -281.649932) (xy 186.505342 -281.649932) (xy 186.504847 -281.674539) (xy 186.496952 -281.723116)
			(xy 186.481368 -281.769797) (xy 186.458497 -281.813374) (xy 186.428932 -281.852718) (xy 186.393439 -281.88681)
			(xy 186.352936 -281.914766) (xy 186.308474 -281.935864) (xy 186.261203 -281.949556) (xy 186.212348 -281.955488)
			(xy 186.163173 -281.953507) (xy 186.114954 -281.943663) (xy 186.068938 -281.926211) (xy 186.026317 -281.901604)
			(xy 185.988196 -281.870479) (xy 185.955561 -281.833642) (xy 185.929258 -281.792046) (xy 185.909967 -281.74677)
			(xy 185.89819 -281.698986) (xy 185.89423 -281.649932) (xy 185.555382 -281.649932) (xy 185.554887 -281.674539)
			(xy 185.546992 -281.723116) (xy 185.531408 -281.769797) (xy 185.508537 -281.813374) (xy 185.478972 -281.852718)
			(xy 185.443479 -281.88681) (xy 185.402976 -281.914766) (xy 185.358514 -281.935864) (xy 185.311243 -281.949556)
			(xy 185.262388 -281.955488) (xy 185.213213 -281.953507) (xy 185.164994 -281.943663) (xy 185.118978 -281.926211)
			(xy 185.076357 -281.901604) (xy 185.038236 -281.870479) (xy 185.005601 -281.833642) (xy 184.979298 -281.792046)
			(xy 184.960007 -281.74677) (xy 184.94823 -281.698986) (xy 184.94427 -281.649932) (xy 184.605168 -281.649932)
			(xy 184.604673 -281.674539) (xy 184.596778 -281.723116) (xy 184.581194 -281.769797) (xy 184.558323 -281.813374)
			(xy 184.528758 -281.852718) (xy 184.493265 -281.88681) (xy 184.452762 -281.914766) (xy 184.4083 -281.935864)
			(xy 184.361029 -281.949556) (xy 184.312174 -281.955488) (xy 184.262999 -281.953507) (xy 184.21478 -281.943663)
			(xy 184.168764 -281.926211) (xy 184.126143 -281.901604) (xy 184.088022 -281.870479) (xy 184.055387 -281.833642)
			(xy 184.029084 -281.792046) (xy 184.009793 -281.74677) (xy 183.998016 -281.698986) (xy 183.994056 -281.649932)
			(xy 183.655208 -281.649932) (xy 183.654713 -281.674539) (xy 183.646818 -281.723116) (xy 183.631234 -281.769797)
			(xy 183.608363 -281.813374) (xy 183.578798 -281.852718) (xy 183.543305 -281.88681) (xy 183.502802 -281.914766)
			(xy 183.45834 -281.935864) (xy 183.411069 -281.949556) (xy 183.362214 -281.955488) (xy 183.313039 -281.953507)
			(xy 183.26482 -281.943663) (xy 183.218804 -281.926211) (xy 183.176183 -281.901604) (xy 183.138062 -281.870479)
			(xy 183.105427 -281.833642) (xy 183.079124 -281.792046) (xy 183.059833 -281.74677) (xy 183.048056 -281.698986)
			(xy 183.044096 -281.649932) (xy 182.705248 -281.649932) (xy 182.704753 -281.674539) (xy 182.696858 -281.723116)
			(xy 182.681274 -281.769797) (xy 182.658403 -281.813374) (xy 182.628838 -281.852718) (xy 182.593345 -281.88681)
			(xy 182.552842 -281.914766) (xy 182.50838 -281.935864) (xy 182.461109 -281.949556) (xy 182.412254 -281.955488)
			(xy 182.363079 -281.953507) (xy 182.31486 -281.943663) (xy 182.268844 -281.926211) (xy 182.226223 -281.901604)
			(xy 182.188102 -281.870479) (xy 182.155467 -281.833642) (xy 182.129164 -281.792046) (xy 182.109873 -281.74677)
			(xy 182.098096 -281.698986) (xy 182.094136 -281.649932) (xy 181.755288 -281.649932) (xy 181.754793 -281.674539)
			(xy 181.746898 -281.723116) (xy 181.731314 -281.769797) (xy 181.708443 -281.813374) (xy 181.678878 -281.852718)
			(xy 181.643385 -281.88681) (xy 181.602882 -281.914766) (xy 181.55842 -281.935864) (xy 181.511149 -281.949556)
			(xy 181.462294 -281.955488) (xy 181.413119 -281.953507) (xy 181.3649 -281.943663) (xy 181.318884 -281.926211)
			(xy 181.276263 -281.901604) (xy 181.238142 -281.870479) (xy 181.205507 -281.833642) (xy 181.179204 -281.792046)
			(xy 181.159913 -281.74677) (xy 181.148136 -281.698986) (xy 181.144176 -281.649932) (xy 180.805328 -281.649932)
			(xy 180.804833 -281.674539) (xy 180.796938 -281.723116) (xy 180.781354 -281.769797) (xy 180.758483 -281.813374)
			(xy 180.728918 -281.852718) (xy 180.693425 -281.88681) (xy 180.652922 -281.914766) (xy 180.60846 -281.935864)
			(xy 180.561189 -281.949556) (xy 180.512334 -281.955488) (xy 180.463159 -281.953507) (xy 180.41494 -281.943663)
			(xy 180.368924 -281.926211) (xy 180.326303 -281.901604) (xy 180.288182 -281.870479) (xy 180.255547 -281.833642)
			(xy 180.229244 -281.792046) (xy 180.209953 -281.74677) (xy 180.198176 -281.698986) (xy 180.194216 -281.649932)
			(xy 179.855368 -281.649932) (xy 179.854873 -281.674539) (xy 179.846978 -281.723116) (xy 179.831394 -281.769797)
			(xy 179.808523 -281.813374) (xy 179.778958 -281.852718) (xy 179.743465 -281.88681) (xy 179.702962 -281.914766)
			(xy 179.6585 -281.935864) (xy 179.611229 -281.949556) (xy 179.562374 -281.955488) (xy 179.513199 -281.953507)
			(xy 179.46498 -281.943663) (xy 179.418964 -281.926211) (xy 179.376343 -281.901604) (xy 179.338222 -281.870479)
			(xy 179.305587 -281.833642) (xy 179.279284 -281.792046) (xy 179.259993 -281.74677) (xy 179.248216 -281.698986)
			(xy 179.244256 -281.649932) (xy 178.905154 -281.649932) (xy 178.904659 -281.674539) (xy 178.896764 -281.723116)
			(xy 178.88118 -281.769797) (xy 178.858309 -281.813374) (xy 178.828744 -281.852718) (xy 178.793251 -281.88681)
			(xy 178.752748 -281.914766) (xy 178.708286 -281.935864) (xy 178.661015 -281.949556) (xy 178.61216 -281.955488)
			(xy 178.562985 -281.953507) (xy 178.514766 -281.943663) (xy 178.46875 -281.926211) (xy 178.426129 -281.901604)
			(xy 178.388008 -281.870479) (xy 178.355373 -281.833642) (xy 178.32907 -281.792046) (xy 178.309779 -281.74677)
			(xy 178.298002 -281.698986) (xy 178.294042 -281.649932) (xy 177.955194 -281.649932) (xy 177.954699 -281.674539)
			(xy 177.946804 -281.723116) (xy 177.93122 -281.769797) (xy 177.908349 -281.813374) (xy 177.878784 -281.852718)
			(xy 177.843291 -281.88681) (xy 177.802788 -281.914766) (xy 177.758326 -281.935864) (xy 177.711055 -281.949556)
			(xy 177.6622 -281.955488) (xy 177.613025 -281.953507) (xy 177.564806 -281.943663) (xy 177.51879 -281.926211)
			(xy 177.476169 -281.901604) (xy 177.438048 -281.870479) (xy 177.405413 -281.833642) (xy 177.37911 -281.792046)
			(xy 177.359819 -281.74677) (xy 177.348042 -281.698986) (xy 177.344082 -281.649932) (xy 177.005234 -281.649932)
			(xy 177.004739 -281.674539) (xy 176.996844 -281.723116) (xy 176.98126 -281.769797) (xy 176.958389 -281.813374)
			(xy 176.928824 -281.852718) (xy 176.893331 -281.88681) (xy 176.852828 -281.914766) (xy 176.808366 -281.935864)
			(xy 176.761095 -281.949556) (xy 176.71224 -281.955488) (xy 176.663065 -281.953507) (xy 176.614846 -281.943663)
			(xy 176.56883 -281.926211) (xy 176.526209 -281.901604) (xy 176.488088 -281.870479) (xy 176.455453 -281.833642)
			(xy 176.42915 -281.792046) (xy 176.409859 -281.74677) (xy 176.398082 -281.698986) (xy 176.394122 -281.649932)
			(xy 176.055274 -281.649932) (xy 176.054779 -281.674539) (xy 176.046884 -281.723116) (xy 176.0313 -281.769797)
			(xy 176.008429 -281.813374) (xy 175.978864 -281.852718) (xy 175.943371 -281.88681) (xy 175.902868 -281.914766)
			(xy 175.858406 -281.935864) (xy 175.811135 -281.949556) (xy 175.76228 -281.955488) (xy 175.713105 -281.953507)
			(xy 175.664886 -281.943663) (xy 175.61887 -281.926211) (xy 175.576249 -281.901604) (xy 175.538128 -281.870479)
			(xy 175.505493 -281.833642) (xy 175.47919 -281.792046) (xy 175.459899 -281.74677) (xy 175.448122 -281.698986)
			(xy 175.444162 -281.649932) (xy 175.105314 -281.649932) (xy 175.104819 -281.674539) (xy 175.096924 -281.723116)
			(xy 175.08134 -281.769797) (xy 175.058469 -281.813374) (xy 175.028904 -281.852718) (xy 174.993411 -281.88681)
			(xy 174.952908 -281.914766) (xy 174.908446 -281.935864) (xy 174.861175 -281.949556) (xy 174.81232 -281.955488)
			(xy 174.763145 -281.953507) (xy 174.714926 -281.943663) (xy 174.66891 -281.926211) (xy 174.626289 -281.901604)
			(xy 174.588168 -281.870479) (xy 174.555533 -281.833642) (xy 174.52923 -281.792046) (xy 174.509939 -281.74677)
			(xy 174.498162 -281.698986) (xy 174.494202 -281.649932) (xy 174.155354 -281.649932) (xy 174.154859 -281.674539)
			(xy 174.146964 -281.723116) (xy 174.13138 -281.769797) (xy 174.108509 -281.813374) (xy 174.078944 -281.852718)
			(xy 174.043451 -281.88681) (xy 174.002948 -281.914766) (xy 173.958486 -281.935864) (xy 173.911215 -281.949556)
			(xy 173.86236 -281.955488) (xy 173.813185 -281.953507) (xy 173.764966 -281.943663) (xy 173.71895 -281.926211)
			(xy 173.676329 -281.901604) (xy 173.638208 -281.870479) (xy 173.605573 -281.833642) (xy 173.57927 -281.792046)
			(xy 173.559979 -281.74677) (xy 173.548202 -281.698986) (xy 173.544242 -281.649932) (xy 173.205394 -281.649932)
			(xy 173.204899 -281.674539) (xy 173.197004 -281.723116) (xy 173.18142 -281.769797) (xy 173.158549 -281.813374)
			(xy 173.128984 -281.852718) (xy 173.093491 -281.88681) (xy 173.052988 -281.914766) (xy 173.008526 -281.935864)
			(xy 172.961255 -281.949556) (xy 172.9124 -281.955488) (xy 172.863225 -281.953507) (xy 172.815006 -281.943663)
			(xy 172.76899 -281.926211) (xy 172.726369 -281.901604) (xy 172.688248 -281.870479) (xy 172.655613 -281.833642)
			(xy 172.62931 -281.792046) (xy 172.610019 -281.74677) (xy 172.598242 -281.698986) (xy 172.594282 -281.649932)
			(xy 172.25518 -281.649932) (xy 172.254685 -281.674539) (xy 172.24679 -281.723116) (xy 172.231206 -281.769797)
			(xy 172.208335 -281.813374) (xy 172.17877 -281.852718) (xy 172.143277 -281.88681) (xy 172.102774 -281.914766)
			(xy 172.058312 -281.935864) (xy 172.011041 -281.949556) (xy 171.962186 -281.955488) (xy 171.913011 -281.953507)
			(xy 171.864792 -281.943663) (xy 171.818776 -281.926211) (xy 171.776155 -281.901604) (xy 171.738034 -281.870479)
			(xy 171.705399 -281.833642) (xy 171.679096 -281.792046) (xy 171.659805 -281.74677) (xy 171.648028 -281.698986)
			(xy 171.644068 -281.649932) (xy 171.30522 -281.649932) (xy 171.304725 -281.674539) (xy 171.29683 -281.723116)
			(xy 171.281246 -281.769797) (xy 171.258375 -281.813374) (xy 171.22881 -281.852718) (xy 171.193317 -281.88681)
			(xy 171.152814 -281.914766) (xy 171.108352 -281.935864) (xy 171.061081 -281.949556) (xy 171.012226 -281.955488)
			(xy 170.963051 -281.953507) (xy 170.914832 -281.943663) (xy 170.868816 -281.926211) (xy 170.826195 -281.901604)
			(xy 170.788074 -281.870479) (xy 170.755439 -281.833642) (xy 170.729136 -281.792046) (xy 170.709845 -281.74677)
			(xy 170.698068 -281.698986) (xy 170.694108 -281.649932) (xy 170.35526 -281.649932) (xy 170.354765 -281.674539)
			(xy 170.34687 -281.723116) (xy 170.331286 -281.769797) (xy 170.308415 -281.813374) (xy 170.27885 -281.852718)
			(xy 170.243357 -281.88681) (xy 170.202854 -281.914766) (xy 170.158392 -281.935864) (xy 170.111121 -281.949556)
			(xy 170.062266 -281.955488) (xy 170.013091 -281.953507) (xy 169.964872 -281.943663) (xy 169.918856 -281.926211)
			(xy 169.876235 -281.901604) (xy 169.838114 -281.870479) (xy 169.805479 -281.833642) (xy 169.779176 -281.792046)
			(xy 169.759885 -281.74677) (xy 169.748108 -281.698986) (xy 169.744148 -281.649932) (xy 169.4053 -281.649932)
			(xy 169.404805 -281.674539) (xy 169.39691 -281.723116) (xy 169.381326 -281.769797) (xy 169.358455 -281.813374)
			(xy 169.32889 -281.852718) (xy 169.293397 -281.88681) (xy 169.252894 -281.914766) (xy 169.208432 -281.935864)
			(xy 169.161161 -281.949556) (xy 169.112306 -281.955488) (xy 169.063131 -281.953507) (xy 169.014912 -281.943663)
			(xy 168.968896 -281.926211) (xy 168.926275 -281.901604) (xy 168.888154 -281.870479) (xy 168.855519 -281.833642)
			(xy 168.829216 -281.792046) (xy 168.809925 -281.74677) (xy 168.798148 -281.698986) (xy 168.794188 -281.649932)
			(xy 168.45534 -281.649932) (xy 168.454845 -281.674539) (xy 168.44695 -281.723116) (xy 168.431366 -281.769797)
			(xy 168.408495 -281.813374) (xy 168.37893 -281.852718) (xy 168.343437 -281.88681) (xy 168.302934 -281.914766)
			(xy 168.258472 -281.935864) (xy 168.211201 -281.949556) (xy 168.162346 -281.955488) (xy 168.113171 -281.953507)
			(xy 168.064952 -281.943663) (xy 168.018936 -281.926211) (xy 167.976315 -281.901604) (xy 167.938194 -281.870479)
			(xy 167.905559 -281.833642) (xy 167.879256 -281.792046) (xy 167.859965 -281.74677) (xy 167.848188 -281.698986)
			(xy 167.844228 -281.649932) (xy 167.50538 -281.649932) (xy 167.504885 -281.674539) (xy 167.49699 -281.723116)
			(xy 167.481406 -281.769797) (xy 167.458535 -281.813374) (xy 167.42897 -281.852718) (xy 167.393477 -281.88681)
			(xy 167.352974 -281.914766) (xy 167.308512 -281.935864) (xy 167.261241 -281.949556) (xy 167.212386 -281.955488)
			(xy 167.163211 -281.953507) (xy 167.114992 -281.943663) (xy 167.068976 -281.926211) (xy 167.026355 -281.901604)
			(xy 166.988234 -281.870479) (xy 166.955599 -281.833642) (xy 166.929296 -281.792046) (xy 166.910005 -281.74677)
			(xy 166.898228 -281.698986) (xy 166.894268 -281.649932) (xy 166.555166 -281.649932) (xy 166.554671 -281.674539)
			(xy 166.546776 -281.723116) (xy 166.531192 -281.769797) (xy 166.508321 -281.813374) (xy 166.478756 -281.852718)
			(xy 166.443263 -281.88681) (xy 166.40276 -281.914766) (xy 166.358298 -281.935864) (xy 166.311027 -281.949556)
			(xy 166.262172 -281.955488) (xy 166.212997 -281.953507) (xy 166.164778 -281.943663) (xy 166.118762 -281.926211)
			(xy 166.076141 -281.901604) (xy 166.03802 -281.870479) (xy 166.005385 -281.833642) (xy 165.979082 -281.792046)
			(xy 165.959791 -281.74677) (xy 165.948014 -281.698986) (xy 165.944054 -281.649932) (xy 165.604767 -281.649932)
			(xy 165.604767 -281.673957) (xy 165.597223 -281.721465) (xy 165.582322 -281.767203) (xy 165.560434 -281.810039)
			(xy 165.532099 -281.848912) (xy 165.49802 -281.882861) (xy 165.459038 -281.911047) (xy 165.416119 -281.93277)
			(xy 165.370324 -281.947495) (xy 165.346634 -281.951684) (xy 165.327838 -281.954478) (xy 165.303708 -281.982926)
			(xy 165.303708 -282.599892) (xy 189.69407 -282.599892) (xy 189.69803 -282.550838) (xy 189.709807 -282.503054)
			(xy 189.729098 -282.457778) (xy 189.755401 -282.416182) (xy 189.788036 -282.379345) (xy 189.826157 -282.34822)
			(xy 189.868778 -282.323613) (xy 189.914794 -282.306161) (xy 189.963013 -282.296317) (xy 190.012188 -282.294336)
			(xy 190.061043 -282.300268) (xy 190.108314 -282.31396) (xy 190.152776 -282.335058) (xy 190.193279 -282.363014)
			(xy 190.228772 -282.397106) (xy 190.258337 -282.43645) (xy 190.281208 -282.480027) (xy 190.296792 -282.526708)
			(xy 190.304687 -282.575285) (xy 190.305182 -282.599892) (xy 190.64403 -282.599892) (xy 190.64799 -282.550838)
			(xy 190.659767 -282.503054) (xy 190.679058 -282.457778) (xy 190.705361 -282.416182) (xy 190.737996 -282.379345)
			(xy 190.776117 -282.34822) (xy 190.818738 -282.323613) (xy 190.864754 -282.306161) (xy 190.912973 -282.296317)
			(xy 190.962148 -282.294336) (xy 191.011003 -282.300268) (xy 191.058274 -282.31396) (xy 191.102736 -282.335058)
			(xy 191.143239 -282.363014) (xy 191.178732 -282.397106) (xy 191.208297 -282.43645) (xy 191.231168 -282.480027)
			(xy 191.246752 -282.526708) (xy 191.254647 -282.575285) (xy 191.255142 -282.599892) (xy 191.254647 -282.624499)
			(xy 191.254468 -282.6256) (xy 192.52336 -282.6256) (xy 192.52336 -282.574184) (xy 192.531403 -282.523402)
			(xy 192.547291 -282.474503) (xy 192.570634 -282.428691) (xy 192.600855 -282.387095) (xy 192.637211 -282.350739)
			(xy 192.678807 -282.320518) (xy 192.724619 -282.297175) (xy 192.773518 -282.281287) (xy 192.8243 -282.273244)
			(xy 192.875716 -282.273244) (xy 192.926498 -282.281287) (xy 192.975397 -282.297175) (xy 193.021209 -282.320518)
			(xy 193.062805 -282.350739) (xy 193.099161 -282.387095) (xy 193.129382 -282.428691) (xy 193.152725 -282.474503)
			(xy 193.168613 -282.523402) (xy 193.176656 -282.574184) (xy 193.17716 -282.599892) (xy 193.176656 -282.6256)
			(xy 193.47332 -282.6256) (xy 193.47332 -282.574184) (xy 193.481363 -282.523402) (xy 193.497251 -282.474503)
			(xy 193.520594 -282.428691) (xy 193.550815 -282.387095) (xy 193.587171 -282.350739) (xy 193.628767 -282.320518)
			(xy 193.674579 -282.297175) (xy 193.723478 -282.281287) (xy 193.77426 -282.273244) (xy 193.825676 -282.273244)
			(xy 193.876458 -282.281287) (xy 193.925357 -282.297175) (xy 193.971169 -282.320518) (xy 194.012765 -282.350739)
			(xy 194.049121 -282.387095) (xy 194.079342 -282.428691) (xy 194.102685 -282.474503) (xy 194.118573 -282.523402)
			(xy 194.126616 -282.574184) (xy 194.12712 -282.599892) (xy 194.444124 -282.599892) (xy 194.448084 -282.550838)
			(xy 194.459861 -282.503054) (xy 194.479152 -282.457778) (xy 194.505455 -282.416182) (xy 194.53809 -282.379345)
			(xy 194.576211 -282.34822) (xy 194.618832 -282.323613) (xy 194.664848 -282.306161) (xy 194.713067 -282.296317)
			(xy 194.762242 -282.294336) (xy 194.811097 -282.300268) (xy 194.858368 -282.31396) (xy 194.90283 -282.335058)
			(xy 194.943333 -282.363014) (xy 194.978826 -282.397106) (xy 195.008391 -282.43645) (xy 195.031262 -282.480027)
			(xy 195.046846 -282.526708) (xy 195.054741 -282.575285) (xy 195.055236 -282.599892) (xy 195.054741 -282.624499)
			(xy 195.054562 -282.6256) (xy 195.37324 -282.6256) (xy 195.37324 -282.574184) (xy 195.381283 -282.523402)
			(xy 195.397171 -282.474503) (xy 195.420514 -282.428691) (xy 195.450735 -282.387095) (xy 195.487091 -282.350739)
			(xy 195.528687 -282.320518) (xy 195.574499 -282.297175) (xy 195.623398 -282.281287) (xy 195.67418 -282.273244)
			(xy 195.725596 -282.273244) (xy 195.776378 -282.281287) (xy 195.825277 -282.297175) (xy 195.871089 -282.320518)
			(xy 195.912685 -282.350739) (xy 195.949041 -282.387095) (xy 195.979262 -282.428691) (xy 196.002605 -282.474503)
			(xy 196.018493 -282.523402) (xy 196.026536 -282.574184) (xy 196.02704 -282.599892) (xy 196.026536 -282.6256)
			(xy 196.3232 -282.6256) (xy 196.3232 -282.574184) (xy 196.331243 -282.523402) (xy 196.347131 -282.474503)
			(xy 196.370474 -282.428691) (xy 196.400695 -282.387095) (xy 196.437051 -282.350739) (xy 196.478647 -282.320518)
			(xy 196.524459 -282.297175) (xy 196.573358 -282.281287) (xy 196.62414 -282.273244) (xy 196.675556 -282.273244)
			(xy 196.726338 -282.281287) (xy 196.775237 -282.297175) (xy 196.821049 -282.320518) (xy 196.862645 -282.350739)
			(xy 196.899001 -282.387095) (xy 196.929222 -282.428691) (xy 196.952565 -282.474503) (xy 196.968453 -282.523402)
			(xy 196.976496 -282.574184) (xy 196.977 -282.599892) (xy 197.294258 -282.599892) (xy 197.298218 -282.550838)
			(xy 197.309995 -282.503054) (xy 197.329286 -282.457778) (xy 197.355589 -282.416182) (xy 197.388224 -282.379345)
			(xy 197.426345 -282.34822) (xy 197.468966 -282.323613) (xy 197.514982 -282.306161) (xy 197.563201 -282.296317)
			(xy 197.612376 -282.294336) (xy 197.661231 -282.300268) (xy 197.708502 -282.31396) (xy 197.752964 -282.335058)
			(xy 197.793467 -282.363014) (xy 197.82896 -282.397106) (xy 197.858525 -282.43645) (xy 197.881396 -282.480027)
			(xy 197.89698 -282.526708) (xy 197.904875 -282.575285) (xy 197.90537 -282.599892) (xy 198.244218 -282.599892)
			(xy 198.248178 -282.550838) (xy 198.259955 -282.503054) (xy 198.279246 -282.457778) (xy 198.305549 -282.416182)
			(xy 198.338184 -282.379345) (xy 198.376305 -282.34822) (xy 198.418926 -282.323613) (xy 198.464942 -282.306161)
			(xy 198.513161 -282.296317) (xy 198.562336 -282.294336) (xy 198.611191 -282.300268) (xy 198.658462 -282.31396)
			(xy 198.702924 -282.335058) (xy 198.743427 -282.363014) (xy 198.77892 -282.397106) (xy 198.808485 -282.43645)
			(xy 198.831356 -282.480027) (xy 198.84694 -282.526708) (xy 198.854835 -282.575285) (xy 198.85533 -282.599892)
			(xy 198.854835 -282.624499) (xy 198.84694 -282.673076) (xy 198.831356 -282.719757) (xy 198.808485 -282.763334)
			(xy 198.77892 -282.802678) (xy 198.743427 -282.83677) (xy 198.702924 -282.864726) (xy 198.658462 -282.885824)
			(xy 198.611191 -282.899516) (xy 198.562336 -282.905448) (xy 198.513161 -282.903467) (xy 198.464942 -282.893623)
			(xy 198.418926 -282.876171) (xy 198.376305 -282.851564) (xy 198.338184 -282.820439) (xy 198.305549 -282.783602)
			(xy 198.279246 -282.742006) (xy 198.259955 -282.69673) (xy 198.248178 -282.648946) (xy 198.244218 -282.599892)
			(xy 197.90537 -282.599892) (xy 197.904875 -282.624499) (xy 197.89698 -282.673076) (xy 197.881396 -282.719757)
			(xy 197.858525 -282.763334) (xy 197.82896 -282.802678) (xy 197.793467 -282.83677) (xy 197.752964 -282.864726)
			(xy 197.708502 -282.885824) (xy 197.661231 -282.899516) (xy 197.612376 -282.905448) (xy 197.563201 -282.903467)
			(xy 197.514982 -282.893623) (xy 197.468966 -282.876171) (xy 197.426345 -282.851564) (xy 197.388224 -282.820439)
			(xy 197.355589 -282.783602) (xy 197.329286 -282.742006) (xy 197.309995 -282.69673) (xy 197.298218 -282.648946)
			(xy 197.294258 -282.599892) (xy 196.977 -282.599892) (xy 196.976496 -282.6256) (xy 196.968453 -282.676382)
			(xy 196.952565 -282.725281) (xy 196.929222 -282.771093) (xy 196.899001 -282.812689) (xy 196.862645 -282.849045)
			(xy 196.821049 -282.879266) (xy 196.775237 -282.902609) (xy 196.726338 -282.918497) (xy 196.675556 -282.92654)
			(xy 196.62414 -282.92654) (xy 196.573358 -282.918497) (xy 196.524459 -282.902609) (xy 196.478647 -282.879266)
			(xy 196.437051 -282.849045) (xy 196.400695 -282.812689) (xy 196.370474 -282.771093) (xy 196.347131 -282.725281)
			(xy 196.331243 -282.676382) (xy 196.3232 -282.6256) (xy 196.026536 -282.6256) (xy 196.018493 -282.676382)
			(xy 196.002605 -282.725281) (xy 195.979262 -282.771093) (xy 195.949041 -282.812689) (xy 195.912685 -282.849045)
			(xy 195.871089 -282.879266) (xy 195.825277 -282.902609) (xy 195.776378 -282.918497) (xy 195.725596 -282.92654)
			(xy 195.67418 -282.92654) (xy 195.623398 -282.918497) (xy 195.574499 -282.902609) (xy 195.528687 -282.879266)
			(xy 195.487091 -282.849045) (xy 195.450735 -282.812689) (xy 195.420514 -282.771093) (xy 195.397171 -282.725281)
			(xy 195.381283 -282.676382) (xy 195.37324 -282.6256) (xy 195.054562 -282.6256) (xy 195.046846 -282.673076)
			(xy 195.031262 -282.719757) (xy 195.008391 -282.763334) (xy 194.978826 -282.802678) (xy 194.943333 -282.83677)
			(xy 194.90283 -282.864726) (xy 194.858368 -282.885824) (xy 194.811097 -282.899516) (xy 194.762242 -282.905448)
			(xy 194.713067 -282.903467) (xy 194.664848 -282.893623) (xy 194.618832 -282.876171) (xy 194.576211 -282.851564)
			(xy 194.53809 -282.820439) (xy 194.505455 -282.783602) (xy 194.479152 -282.742006) (xy 194.459861 -282.69673)
			(xy 194.448084 -282.648946) (xy 194.444124 -282.599892) (xy 194.12712 -282.599892) (xy 194.126616 -282.6256)
			(xy 194.118573 -282.676382) (xy 194.102685 -282.725281) (xy 194.079342 -282.771093) (xy 194.049121 -282.812689)
			(xy 194.012765 -282.849045) (xy 193.971169 -282.879266) (xy 193.925357 -282.902609) (xy 193.876458 -282.918497)
			(xy 193.825676 -282.92654) (xy 193.77426 -282.92654) (xy 193.723478 -282.918497) (xy 193.674579 -282.902609)
			(xy 193.628767 -282.879266) (xy 193.587171 -282.849045) (xy 193.550815 -282.812689) (xy 193.520594 -282.771093)
			(xy 193.497251 -282.725281) (xy 193.481363 -282.676382) (xy 193.47332 -282.6256) (xy 193.176656 -282.6256)
			(xy 193.168613 -282.676382) (xy 193.152725 -282.725281) (xy 193.129382 -282.771093) (xy 193.099161 -282.812689)
			(xy 193.062805 -282.849045) (xy 193.021209 -282.879266) (xy 192.975397 -282.902609) (xy 192.926498 -282.918497)
			(xy 192.875716 -282.92654) (xy 192.8243 -282.92654) (xy 192.773518 -282.918497) (xy 192.724619 -282.902609)
			(xy 192.678807 -282.879266) (xy 192.637211 -282.849045) (xy 192.600855 -282.812689) (xy 192.570634 -282.771093)
			(xy 192.547291 -282.725281) (xy 192.531403 -282.676382) (xy 192.52336 -282.6256) (xy 191.254468 -282.6256)
			(xy 191.246752 -282.673076) (xy 191.231168 -282.719757) (xy 191.208297 -282.763334) (xy 191.178732 -282.802678)
			(xy 191.143239 -282.83677) (xy 191.102736 -282.864726) (xy 191.058274 -282.885824) (xy 191.011003 -282.899516)
			(xy 190.962148 -282.905448) (xy 190.912973 -282.903467) (xy 190.864754 -282.893623) (xy 190.818738 -282.876171)
			(xy 190.776117 -282.851564) (xy 190.737996 -282.820439) (xy 190.705361 -282.783602) (xy 190.679058 -282.742006)
			(xy 190.659767 -282.69673) (xy 190.64799 -282.648946) (xy 190.64403 -282.599892) (xy 190.305182 -282.599892)
			(xy 190.304687 -282.624499) (xy 190.296792 -282.673076) (xy 190.281208 -282.719757) (xy 190.258337 -282.763334)
			(xy 190.228772 -282.802678) (xy 190.193279 -282.83677) (xy 190.152776 -282.864726) (xy 190.108314 -282.885824)
			(xy 190.061043 -282.899516) (xy 190.012188 -282.905448) (xy 189.963013 -282.903467) (xy 189.914794 -282.893623)
			(xy 189.868778 -282.876171) (xy 189.826157 -282.851564) (xy 189.788036 -282.820439) (xy 189.755401 -282.783602)
			(xy 189.729098 -282.742006) (xy 189.709807 -282.69673) (xy 189.69803 -282.648946) (xy 189.69407 -282.599892)
			(xy 165.303708 -282.599892) (xy 165.303708 -283.074872) (xy 165.469074 -283.074872) (xy 165.473034 -283.025818)
			(xy 165.484811 -282.978034) (xy 165.504102 -282.932758) (xy 165.530405 -282.891162) (xy 165.56304 -282.854325)
			(xy 165.601161 -282.8232) (xy 165.643782 -282.798593) (xy 165.689798 -282.781141) (xy 165.738017 -282.771297)
			(xy 165.787192 -282.769316) (xy 165.836047 -282.775248) (xy 165.883318 -282.78894) (xy 165.92778 -282.810038)
			(xy 165.968283 -282.837994) (xy 166.003776 -282.872086) (xy 166.033341 -282.91143) (xy 166.056212 -282.955007)
			(xy 166.071796 -283.001688) (xy 166.079691 -283.050265) (xy 166.080186 -283.074872) (xy 166.419288 -283.074872)
			(xy 166.423248 -283.025818) (xy 166.435025 -282.978034) (xy 166.454316 -282.932758) (xy 166.480619 -282.891162)
			(xy 166.513254 -282.854325) (xy 166.551375 -282.8232) (xy 166.593996 -282.798593) (xy 166.640012 -282.781141)
			(xy 166.688231 -282.771297) (xy 166.737406 -282.769316) (xy 166.786261 -282.775248) (xy 166.833532 -282.78894)
			(xy 166.877994 -282.810038) (xy 166.918497 -282.837994) (xy 166.95399 -282.872086) (xy 166.983555 -282.91143)
			(xy 167.006426 -282.955007) (xy 167.02201 -283.001688) (xy 167.029905 -283.050265) (xy 167.0304 -283.074872)
			(xy 167.369248 -283.074872) (xy 167.373208 -283.025818) (xy 167.384985 -282.978034) (xy 167.404276 -282.932758)
			(xy 167.430579 -282.891162) (xy 167.463214 -282.854325) (xy 167.501335 -282.8232) (xy 167.543956 -282.798593)
			(xy 167.589972 -282.781141) (xy 167.638191 -282.771297) (xy 167.687366 -282.769316) (xy 167.736221 -282.775248)
			(xy 167.783492 -282.78894) (xy 167.827954 -282.810038) (xy 167.868457 -282.837994) (xy 167.90395 -282.872086)
			(xy 167.933515 -282.91143) (xy 167.956386 -282.955007) (xy 167.97197 -283.001688) (xy 167.979865 -283.050265)
			(xy 167.98036 -283.074872) (xy 168.319208 -283.074872) (xy 168.323168 -283.025818) (xy 168.334945 -282.978034)
			(xy 168.354236 -282.932758) (xy 168.380539 -282.891162) (xy 168.413174 -282.854325) (xy 168.451295 -282.8232)
			(xy 168.493916 -282.798593) (xy 168.539932 -282.781141) (xy 168.588151 -282.771297) (xy 168.637326 -282.769316)
			(xy 168.686181 -282.775248) (xy 168.733452 -282.78894) (xy 168.777914 -282.810038) (xy 168.818417 -282.837994)
			(xy 168.85391 -282.872086) (xy 168.883475 -282.91143) (xy 168.906346 -282.955007) (xy 168.92193 -283.001688)
			(xy 168.929825 -283.050265) (xy 168.93032 -283.074872) (xy 169.269168 -283.074872) (xy 169.273128 -283.025818)
			(xy 169.284905 -282.978034) (xy 169.304196 -282.932758) (xy 169.330499 -282.891162) (xy 169.363134 -282.854325)
			(xy 169.401255 -282.8232) (xy 169.443876 -282.798593) (xy 169.489892 -282.781141) (xy 169.538111 -282.771297)
			(xy 169.587286 -282.769316) (xy 169.636141 -282.775248) (xy 169.683412 -282.78894) (xy 169.727874 -282.810038)
			(xy 169.768377 -282.837994) (xy 169.80387 -282.872086) (xy 169.833435 -282.91143) (xy 169.856306 -282.955007)
			(xy 169.87189 -283.001688) (xy 169.879785 -283.050265) (xy 169.88028 -283.074872) (xy 170.219128 -283.074872)
			(xy 170.223088 -283.025818) (xy 170.234865 -282.978034) (xy 170.254156 -282.932758) (xy 170.280459 -282.891162)
			(xy 170.313094 -282.854325) (xy 170.351215 -282.8232) (xy 170.393836 -282.798593) (xy 170.439852 -282.781141)
			(xy 170.488071 -282.771297) (xy 170.537246 -282.769316) (xy 170.586101 -282.775248) (xy 170.633372 -282.78894)
			(xy 170.677834 -282.810038) (xy 170.718337 -282.837994) (xy 170.75383 -282.872086) (xy 170.783395 -282.91143)
			(xy 170.806266 -282.955007) (xy 170.82185 -283.001688) (xy 170.829745 -283.050265) (xy 170.83024 -283.074872)
			(xy 171.169088 -283.074872) (xy 171.173048 -283.025818) (xy 171.184825 -282.978034) (xy 171.204116 -282.932758)
			(xy 171.230419 -282.891162) (xy 171.263054 -282.854325) (xy 171.301175 -282.8232) (xy 171.343796 -282.798593)
			(xy 171.389812 -282.781141) (xy 171.438031 -282.771297) (xy 171.487206 -282.769316) (xy 171.536061 -282.775248)
			(xy 171.583332 -282.78894) (xy 171.627794 -282.810038) (xy 171.668297 -282.837994) (xy 171.70379 -282.872086)
			(xy 171.733355 -282.91143) (xy 171.756226 -282.955007) (xy 171.77181 -283.001688) (xy 171.779705 -283.050265)
			(xy 171.7802 -283.074872) (xy 172.119302 -283.074872) (xy 172.123262 -283.025818) (xy 172.135039 -282.978034)
			(xy 172.15433 -282.932758) (xy 172.180633 -282.891162) (xy 172.213268 -282.854325) (xy 172.251389 -282.8232)
			(xy 172.29401 -282.798593) (xy 172.340026 -282.781141) (xy 172.388245 -282.771297) (xy 172.43742 -282.769316)
			(xy 172.486275 -282.775248) (xy 172.533546 -282.78894) (xy 172.578008 -282.810038) (xy 172.618511 -282.837994)
			(xy 172.654004 -282.872086) (xy 172.683569 -282.91143) (xy 172.70644 -282.955007) (xy 172.722024 -283.001688)
			(xy 172.729919 -283.050265) (xy 172.730414 -283.074872) (xy 173.069262 -283.074872) (xy 173.073222 -283.025818)
			(xy 173.084999 -282.978034) (xy 173.10429 -282.932758) (xy 173.130593 -282.891162) (xy 173.163228 -282.854325)
			(xy 173.201349 -282.8232) (xy 173.24397 -282.798593) (xy 173.289986 -282.781141) (xy 173.338205 -282.771297)
			(xy 173.38738 -282.769316) (xy 173.436235 -282.775248) (xy 173.483506 -282.78894) (xy 173.527968 -282.810038)
			(xy 173.568471 -282.837994) (xy 173.603964 -282.872086) (xy 173.633529 -282.91143) (xy 173.6564 -282.955007)
			(xy 173.671984 -283.001688) (xy 173.679879 -283.050265) (xy 173.680374 -283.074872) (xy 174.019222 -283.074872)
			(xy 174.023182 -283.025818) (xy 174.034959 -282.978034) (xy 174.05425 -282.932758) (xy 174.080553 -282.891162)
			(xy 174.113188 -282.854325) (xy 174.151309 -282.8232) (xy 174.19393 -282.798593) (xy 174.239946 -282.781141)
			(xy 174.288165 -282.771297) (xy 174.33734 -282.769316) (xy 174.386195 -282.775248) (xy 174.433466 -282.78894)
			(xy 174.477928 -282.810038) (xy 174.518431 -282.837994) (xy 174.553924 -282.872086) (xy 174.583489 -282.91143)
			(xy 174.60636 -282.955007) (xy 174.621944 -283.001688) (xy 174.629839 -283.050265) (xy 174.630334 -283.074872)
			(xy 175.919142 -283.074872) (xy 175.923102 -283.025818) (xy 175.934879 -282.978034) (xy 175.95417 -282.932758)
			(xy 175.980473 -282.891162) (xy 176.013108 -282.854325) (xy 176.051229 -282.8232) (xy 176.09385 -282.798593)
			(xy 176.139866 -282.781141) (xy 176.188085 -282.771297) (xy 176.23726 -282.769316) (xy 176.286115 -282.775248)
			(xy 176.333386 -282.78894) (xy 176.377848 -282.810038) (xy 176.418351 -282.837994) (xy 176.453844 -282.872086)
			(xy 176.483409 -282.91143) (xy 176.50628 -282.955007) (xy 176.521864 -283.001688) (xy 176.529759 -283.050265)
			(xy 176.530254 -283.074872) (xy 176.869102 -283.074872) (xy 176.873062 -283.025818) (xy 176.884839 -282.978034)
			(xy 176.90413 -282.932758) (xy 176.930433 -282.891162) (xy 176.963068 -282.854325) (xy 177.001189 -282.8232)
			(xy 177.04381 -282.798593) (xy 177.089826 -282.781141) (xy 177.138045 -282.771297) (xy 177.18722 -282.769316)
			(xy 177.236075 -282.775248) (xy 177.283346 -282.78894) (xy 177.327808 -282.810038) (xy 177.368311 -282.837994)
			(xy 177.403804 -282.872086) (xy 177.433369 -282.91143) (xy 177.45624 -282.955007) (xy 177.471824 -283.001688)
			(xy 177.479719 -283.050265) (xy 177.480214 -283.074872) (xy 177.819062 -283.074872) (xy 177.823022 -283.025818)
			(xy 177.834799 -282.978034) (xy 177.85409 -282.932758) (xy 177.880393 -282.891162) (xy 177.913028 -282.854325)
			(xy 177.951149 -282.8232) (xy 177.99377 -282.798593) (xy 178.039786 -282.781141) (xy 178.088005 -282.771297)
			(xy 178.13718 -282.769316) (xy 178.186035 -282.775248) (xy 178.233306 -282.78894) (xy 178.277768 -282.810038)
			(xy 178.318271 -282.837994) (xy 178.353764 -282.872086) (xy 178.383329 -282.91143) (xy 178.4062 -282.955007)
			(xy 178.421784 -283.001688) (xy 178.429679 -283.050265) (xy 178.430174 -283.074872) (xy 178.769276 -283.074872)
			(xy 178.773236 -283.025818) (xy 178.785013 -282.978034) (xy 178.804304 -282.932758) (xy 178.830607 -282.891162)
			(xy 178.863242 -282.854325) (xy 178.901363 -282.8232) (xy 178.943984 -282.798593) (xy 178.99 -282.781141)
			(xy 179.038219 -282.771297) (xy 179.087394 -282.769316) (xy 179.136249 -282.775248) (xy 179.18352 -282.78894)
			(xy 179.227982 -282.810038) (xy 179.268485 -282.837994) (xy 179.303978 -282.872086) (xy 179.333543 -282.91143)
			(xy 179.356414 -282.955007) (xy 179.371998 -283.001688) (xy 179.379893 -283.050265) (xy 179.380388 -283.074872)
			(xy 179.719236 -283.074872) (xy 179.723196 -283.025818) (xy 179.734973 -282.978034) (xy 179.754264 -282.932758)
			(xy 179.780567 -282.891162) (xy 179.813202 -282.854325) (xy 179.851323 -282.8232) (xy 179.893944 -282.798593)
			(xy 179.93996 -282.781141) (xy 179.988179 -282.771297) (xy 180.037354 -282.769316) (xy 180.086209 -282.775248)
			(xy 180.13348 -282.78894) (xy 180.177942 -282.810038) (xy 180.218445 -282.837994) (xy 180.253938 -282.872086)
			(xy 180.283503 -282.91143) (xy 180.306374 -282.955007) (xy 180.321958 -283.001688) (xy 180.329853 -283.050265)
			(xy 180.330348 -283.074872) (xy 180.669196 -283.074872) (xy 180.673156 -283.025818) (xy 180.684933 -282.978034)
			(xy 180.704224 -282.932758) (xy 180.730527 -282.891162) (xy 180.763162 -282.854325) (xy 180.801283 -282.8232)
			(xy 180.843904 -282.798593) (xy 180.88992 -282.781141) (xy 180.938139 -282.771297) (xy 180.987314 -282.769316)
			(xy 181.036169 -282.775248) (xy 181.08344 -282.78894) (xy 181.127902 -282.810038) (xy 181.168405 -282.837994)
			(xy 181.203898 -282.872086) (xy 181.233463 -282.91143) (xy 181.256334 -282.955007) (xy 181.271918 -283.001688)
			(xy 181.279813 -283.050265) (xy 181.280308 -283.074872) (xy 181.619156 -283.074872) (xy 181.623116 -283.025818)
			(xy 181.634893 -282.978034) (xy 181.654184 -282.932758) (xy 181.680487 -282.891162) (xy 181.713122 -282.854325)
			(xy 181.751243 -282.8232) (xy 181.793864 -282.798593) (xy 181.83988 -282.781141) (xy 181.888099 -282.771297)
			(xy 181.937274 -282.769316) (xy 181.986129 -282.775248) (xy 182.0334 -282.78894) (xy 182.077862 -282.810038)
			(xy 182.118365 -282.837994) (xy 182.153858 -282.872086) (xy 182.183423 -282.91143) (xy 182.206294 -282.955007)
			(xy 182.221878 -283.001688) (xy 182.229773 -283.050265) (xy 182.230268 -283.074872) (xy 182.569116 -283.074872)
			(xy 182.573076 -283.025818) (xy 182.584853 -282.978034) (xy 182.604144 -282.932758) (xy 182.630447 -282.891162)
			(xy 182.663082 -282.854325) (xy 182.701203 -282.8232) (xy 182.743824 -282.798593) (xy 182.78984 -282.781141)
			(xy 182.838059 -282.771297) (xy 182.887234 -282.769316) (xy 182.936089 -282.775248) (xy 182.98336 -282.78894)
			(xy 183.027822 -282.810038) (xy 183.068325 -282.837994) (xy 183.103818 -282.872086) (xy 183.133383 -282.91143)
			(xy 183.156254 -282.955007) (xy 183.171838 -283.001688) (xy 183.179733 -283.050265) (xy 183.180228 -283.074872)
			(xy 184.469036 -283.074872) (xy 184.472996 -283.025818) (xy 184.484773 -282.978034) (xy 184.504064 -282.932758)
			(xy 184.530367 -282.891162) (xy 184.563002 -282.854325) (xy 184.601123 -282.8232) (xy 184.643744 -282.798593)
			(xy 184.68976 -282.781141) (xy 184.737979 -282.771297) (xy 184.787154 -282.769316) (xy 184.836009 -282.775248)
			(xy 184.88328 -282.78894) (xy 184.927742 -282.810038) (xy 184.968245 -282.837994) (xy 185.003738 -282.872086)
			(xy 185.033303 -282.91143) (xy 185.056174 -282.955007) (xy 185.071758 -283.001688) (xy 185.079653 -283.050265)
			(xy 185.080148 -283.074872) (xy 185.41925 -283.074872) (xy 185.42321 -283.025818) (xy 185.434987 -282.978034)
			(xy 185.454278 -282.932758) (xy 185.480581 -282.891162) (xy 185.513216 -282.854325) (xy 185.551337 -282.8232)
			(xy 185.593958 -282.798593) (xy 185.639974 -282.781141) (xy 185.688193 -282.771297) (xy 185.737368 -282.769316)
			(xy 185.786223 -282.775248) (xy 185.833494 -282.78894) (xy 185.877956 -282.810038) (xy 185.918459 -282.837994)
			(xy 185.953952 -282.872086) (xy 185.983517 -282.91143) (xy 186.006388 -282.955007) (xy 186.021972 -283.001688)
			(xy 186.029867 -283.050265) (xy 186.030362 -283.074872) (xy 186.36921 -283.074872) (xy 186.37317 -283.025818)
			(xy 186.384947 -282.978034) (xy 186.404238 -282.932758) (xy 186.430541 -282.891162) (xy 186.463176 -282.854325)
			(xy 186.501297 -282.8232) (xy 186.543918 -282.798593) (xy 186.589934 -282.781141) (xy 186.638153 -282.771297)
			(xy 186.687328 -282.769316) (xy 186.736183 -282.775248) (xy 186.783454 -282.78894) (xy 186.827916 -282.810038)
			(xy 186.868419 -282.837994) (xy 186.903912 -282.872086) (xy 186.933477 -282.91143) (xy 186.956348 -282.955007)
			(xy 186.971932 -283.001688) (xy 186.979827 -283.050265) (xy 186.980322 -283.074872) (xy 187.31917 -283.074872)
			(xy 187.32313 -283.025818) (xy 187.334907 -282.978034) (xy 187.354198 -282.932758) (xy 187.380501 -282.891162)
			(xy 187.413136 -282.854325) (xy 187.451257 -282.8232) (xy 187.493878 -282.798593) (xy 187.539894 -282.781141)
			(xy 187.588113 -282.771297) (xy 187.637288 -282.769316) (xy 187.686143 -282.775248) (xy 187.733414 -282.78894)
			(xy 187.777876 -282.810038) (xy 187.818379 -282.837994) (xy 187.853872 -282.872086) (xy 187.883437 -282.91143)
			(xy 187.906308 -282.955007) (xy 187.921892 -283.001688) (xy 187.929787 -283.050265) (xy 187.930282 -283.074872)
			(xy 188.26913 -283.074872) (xy 188.27309 -283.025818) (xy 188.284867 -282.978034) (xy 188.304158 -282.932758)
			(xy 188.330461 -282.891162) (xy 188.363096 -282.854325) (xy 188.401217 -282.8232) (xy 188.443838 -282.798593)
			(xy 188.489854 -282.781141) (xy 188.538073 -282.771297) (xy 188.587248 -282.769316) (xy 188.636103 -282.775248)
			(xy 188.683374 -282.78894) (xy 188.727836 -282.810038) (xy 188.768339 -282.837994) (xy 188.803832 -282.872086)
			(xy 188.833397 -282.91143) (xy 188.856268 -282.955007) (xy 188.871852 -283.001688) (xy 188.873115 -283.009458)
			(xy 224.751517 -283.009458) (xy 224.751517 -282.954942) (xy 224.759276 -282.900982) (xy 224.774636 -282.848675)
			(xy 224.797284 -282.799087) (xy 224.826759 -282.753227) (xy 224.862462 -282.712029) (xy 224.903664 -282.676332)
			(xy 224.949527 -282.646862) (xy 224.999118 -282.62422) (xy 225.051427 -282.608866) (xy 225.105388 -282.601114)
			(xy 225.132646 -282.600654) (xy 225.161385 -282.601162) (xy 225.218213 -282.60979) (xy 225.273103 -282.626845)
			(xy 225.324815 -282.651939) (xy 225.372177 -282.684507) (xy 225.393504 -282.703778) (xy 225.400616 -282.710382)
			(xy 225.418142 -282.717494) (xy 225.50755 -282.717494) (xy 225.525076 -282.710382) (xy 225.532188 -282.703778)
			(xy 225.553515 -282.684508) (xy 225.600878 -282.651943) (xy 225.652589 -282.626852) (xy 225.70748 -282.609802)
			(xy 225.764307 -282.60118) (xy 225.821785 -282.60118) (xy 225.878612 -282.609802) (xy 225.933503 -282.626852)
			(xy 225.985214 -282.651943) (xy 226.032577 -282.684508) (xy 226.053904 -282.703778) (xy 226.061016 -282.710382)
			(xy 226.078542 -282.717494) (xy 226.16795 -282.717494) (xy 226.185476 -282.710382) (xy 226.192588 -282.703778)
			(xy 226.213902 -282.684492) (xy 226.261267 -282.651926) (xy 226.312982 -282.626836) (xy 226.367876 -282.609789)
			(xy 226.424706 -282.601172) (xy 226.453446 -282.600654) (xy 226.483568 -282.601258) (xy 226.543063 -282.610731)
			(xy 226.60033 -282.629434) (xy 226.653948 -282.656902) (xy 226.702584 -282.692454) (xy 226.72421 -282.71343)
			(xy 226.731322 -282.720796) (xy 226.750118 -282.728416) (xy 226.842574 -282.728416) (xy 226.86137 -282.720796)
			(xy 226.868482 -282.71343) (xy 226.890097 -282.692439) (xy 226.938728 -282.65687) (xy 226.992347 -282.629392)
			(xy 227.049619 -282.610687) (xy 227.109121 -282.60122) (xy 227.139246 -282.600654) (xy 227.166492 -282.601219)
			(xy 227.22043 -282.60898) (xy 227.272714 -282.624338) (xy 227.32228 -282.646979) (xy 227.36812 -282.676444)
			(xy 227.409301 -282.712132) (xy 227.444984 -282.753317) (xy 227.474443 -282.79916) (xy 227.497078 -282.84873)
			(xy 227.512429 -282.901015) (xy 227.520184 -282.954954) (xy 227.520184 -283.009446) (xy 227.512429 -283.063385)
			(xy 227.497078 -283.11567) (xy 227.474443 -283.16524) (xy 227.444984 -283.211083) (xy 227.409301 -283.252268)
			(xy 227.36812 -283.287956) (xy 227.32228 -283.317421) (xy 227.272714 -283.340062) (xy 227.22043 -283.35542)
			(xy 227.166492 -283.363181) (xy 227.139246 -283.36367) (xy 227.109124 -283.363065) (xy 227.04963 -283.353591)
			(xy 226.992362 -283.334888) (xy 226.938745 -283.30742) (xy 226.890108 -283.271869) (xy 226.868482 -283.250894)
			(xy 226.86137 -283.243528) (xy 226.842574 -283.235908) (xy 226.750118 -283.235908) (xy 226.731322 -283.243528)
			(xy 226.72421 -283.250894) (xy 226.702603 -283.271894) (xy 226.653969 -283.30746) (xy 226.600349 -283.334936)
			(xy 226.543074 -283.35364) (xy 226.483572 -283.363105) (xy 226.453446 -283.36367) (xy 226.424707 -283.36316)
			(xy 226.36788 -283.354532) (xy 226.312989 -283.337477) (xy 226.261278 -283.312383) (xy 226.213915 -283.279817)
			(xy 226.192588 -283.260546) (xy 226.185476 -283.253942) (xy 226.16795 -283.24683) (xy 226.078542 -283.24683)
			(xy 226.061016 -283.253942) (xy 226.053904 -283.260546) (xy 226.032577 -283.279816) (xy 225.985214 -283.312381)
			(xy 225.933503 -283.337472) (xy 225.878612 -283.354522) (xy 225.821785 -283.363144) (xy 225.764307 -283.363144)
			(xy 225.70748 -283.354522) (xy 225.652589 -283.337472) (xy 225.600878 -283.312381) (xy 225.553515 -283.279816)
			(xy 225.532188 -283.260546) (xy 225.525076 -283.253942) (xy 225.50755 -283.24683) (xy 225.418142 -283.24683)
			(xy 225.400616 -283.253942) (xy 225.393504 -283.260546) (xy 225.372197 -283.27984) (xy 225.32483 -283.312403)
			(xy 225.273113 -283.337492) (xy 225.218218 -283.354537) (xy 225.161386 -283.363153) (xy 225.132646 -283.36367)
			(xy 225.105388 -283.363286) (xy 225.051427 -283.355534) (xy 224.999118 -283.34018) (xy 224.949527 -283.317538)
			(xy 224.903664 -283.288068) (xy 224.862462 -283.252371) (xy 224.826759 -283.211173) (xy 224.797284 -283.165313)
			(xy 224.774636 -283.115725) (xy 224.759276 -283.063418) (xy 224.751517 -283.009458) (xy 188.873115 -283.009458)
			(xy 188.879747 -283.050265) (xy 188.880242 -283.074872) (xy 188.879747 -283.099479) (xy 188.871852 -283.148056)
			(xy 188.856268 -283.194737) (xy 188.833397 -283.238314) (xy 188.803832 -283.277658) (xy 188.768339 -283.31175)
			(xy 188.727836 -283.339706) (xy 188.683374 -283.360804) (xy 188.636103 -283.374496) (xy 188.587248 -283.380428)
			(xy 188.538073 -283.378447) (xy 188.489854 -283.368603) (xy 188.443838 -283.351151) (xy 188.401217 -283.326544)
			(xy 188.363096 -283.295419) (xy 188.330461 -283.258582) (xy 188.304158 -283.216986) (xy 188.284867 -283.17171)
			(xy 188.27309 -283.123926) (xy 188.26913 -283.074872) (xy 187.930282 -283.074872) (xy 187.929787 -283.099479)
			(xy 187.921892 -283.148056) (xy 187.906308 -283.194737) (xy 187.883437 -283.238314) (xy 187.853872 -283.277658)
			(xy 187.818379 -283.31175) (xy 187.777876 -283.339706) (xy 187.733414 -283.360804) (xy 187.686143 -283.374496)
			(xy 187.637288 -283.380428) (xy 187.588113 -283.378447) (xy 187.539894 -283.368603) (xy 187.493878 -283.351151)
			(xy 187.451257 -283.326544) (xy 187.413136 -283.295419) (xy 187.380501 -283.258582) (xy 187.354198 -283.216986)
			(xy 187.334907 -283.17171) (xy 187.32313 -283.123926) (xy 187.31917 -283.074872) (xy 186.980322 -283.074872)
			(xy 186.979827 -283.099479) (xy 186.971932 -283.148056) (xy 186.956348 -283.194737) (xy 186.933477 -283.238314)
			(xy 186.903912 -283.277658) (xy 186.868419 -283.31175) (xy 186.827916 -283.339706) (xy 186.783454 -283.360804)
			(xy 186.736183 -283.374496) (xy 186.687328 -283.380428) (xy 186.638153 -283.378447) (xy 186.589934 -283.368603)
			(xy 186.543918 -283.351151) (xy 186.501297 -283.326544) (xy 186.463176 -283.295419) (xy 186.430541 -283.258582)
			(xy 186.404238 -283.216986) (xy 186.384947 -283.17171) (xy 186.37317 -283.123926) (xy 186.36921 -283.074872)
			(xy 186.030362 -283.074872) (xy 186.029867 -283.099479) (xy 186.021972 -283.148056) (xy 186.006388 -283.194737)
			(xy 185.983517 -283.238314) (xy 185.953952 -283.277658) (xy 185.918459 -283.31175) (xy 185.877956 -283.339706)
			(xy 185.833494 -283.360804) (xy 185.786223 -283.374496) (xy 185.737368 -283.380428) (xy 185.688193 -283.378447)
			(xy 185.639974 -283.368603) (xy 185.593958 -283.351151) (xy 185.551337 -283.326544) (xy 185.513216 -283.295419)
			(xy 185.480581 -283.258582) (xy 185.454278 -283.216986) (xy 185.434987 -283.17171) (xy 185.42321 -283.123926)
			(xy 185.41925 -283.074872) (xy 185.080148 -283.074872) (xy 185.079653 -283.099479) (xy 185.071758 -283.148056)
			(xy 185.056174 -283.194737) (xy 185.033303 -283.238314) (xy 185.003738 -283.277658) (xy 184.968245 -283.31175)
			(xy 184.927742 -283.339706) (xy 184.88328 -283.360804) (xy 184.836009 -283.374496) (xy 184.787154 -283.380428)
			(xy 184.737979 -283.378447) (xy 184.68976 -283.368603) (xy 184.643744 -283.351151) (xy 184.601123 -283.326544)
			(xy 184.563002 -283.295419) (xy 184.530367 -283.258582) (xy 184.504064 -283.216986) (xy 184.484773 -283.17171)
			(xy 184.472996 -283.123926) (xy 184.469036 -283.074872) (xy 183.180228 -283.074872) (xy 183.179733 -283.099479)
			(xy 183.171838 -283.148056) (xy 183.156254 -283.194737) (xy 183.133383 -283.238314) (xy 183.103818 -283.277658)
			(xy 183.068325 -283.31175) (xy 183.027822 -283.339706) (xy 182.98336 -283.360804) (xy 182.936089 -283.374496)
			(xy 182.887234 -283.380428) (xy 182.838059 -283.378447) (xy 182.78984 -283.368603) (xy 182.743824 -283.351151)
			(xy 182.701203 -283.326544) (xy 182.663082 -283.295419) (xy 182.630447 -283.258582) (xy 182.604144 -283.216986)
			(xy 182.584853 -283.17171) (xy 182.573076 -283.123926) (xy 182.569116 -283.074872) (xy 182.230268 -283.074872)
			(xy 182.229773 -283.099479) (xy 182.221878 -283.148056) (xy 182.206294 -283.194737) (xy 182.183423 -283.238314)
			(xy 182.153858 -283.277658) (xy 182.118365 -283.31175) (xy 182.077862 -283.339706) (xy 182.0334 -283.360804)
			(xy 181.986129 -283.374496) (xy 181.937274 -283.380428) (xy 181.888099 -283.378447) (xy 181.83988 -283.368603)
			(xy 181.793864 -283.351151) (xy 181.751243 -283.326544) (xy 181.713122 -283.295419) (xy 181.680487 -283.258582)
			(xy 181.654184 -283.216986) (xy 181.634893 -283.17171) (xy 181.623116 -283.123926) (xy 181.619156 -283.074872)
			(xy 181.280308 -283.074872) (xy 181.279813 -283.099479) (xy 181.271918 -283.148056) (xy 181.256334 -283.194737)
			(xy 181.233463 -283.238314) (xy 181.203898 -283.277658) (xy 181.168405 -283.31175) (xy 181.127902 -283.339706)
			(xy 181.08344 -283.360804) (xy 181.036169 -283.374496) (xy 180.987314 -283.380428) (xy 180.938139 -283.378447)
			(xy 180.88992 -283.368603) (xy 180.843904 -283.351151) (xy 180.801283 -283.326544) (xy 180.763162 -283.295419)
			(xy 180.730527 -283.258582) (xy 180.704224 -283.216986) (xy 180.684933 -283.17171) (xy 180.673156 -283.123926)
			(xy 180.669196 -283.074872) (xy 180.330348 -283.074872) (xy 180.329853 -283.099479) (xy 180.321958 -283.148056)
			(xy 180.306374 -283.194737) (xy 180.283503 -283.238314) (xy 180.253938 -283.277658) (xy 180.218445 -283.31175)
			(xy 180.177942 -283.339706) (xy 180.13348 -283.360804) (xy 180.086209 -283.374496) (xy 180.037354 -283.380428)
			(xy 179.988179 -283.378447) (xy 179.93996 -283.368603) (xy 179.893944 -283.351151) (xy 179.851323 -283.326544)
			(xy 179.813202 -283.295419) (xy 179.780567 -283.258582) (xy 179.754264 -283.216986) (xy 179.734973 -283.17171)
			(xy 179.723196 -283.123926) (xy 179.719236 -283.074872) (xy 179.380388 -283.074872) (xy 179.379893 -283.099479)
			(xy 179.371998 -283.148056) (xy 179.356414 -283.194737) (xy 179.333543 -283.238314) (xy 179.303978 -283.277658)
			(xy 179.268485 -283.31175) (xy 179.227982 -283.339706) (xy 179.18352 -283.360804) (xy 179.136249 -283.374496)
			(xy 179.087394 -283.380428) (xy 179.038219 -283.378447) (xy 178.99 -283.368603) (xy 178.943984 -283.351151)
			(xy 178.901363 -283.326544) (xy 178.863242 -283.295419) (xy 178.830607 -283.258582) (xy 178.804304 -283.216986)
			(xy 178.785013 -283.17171) (xy 178.773236 -283.123926) (xy 178.769276 -283.074872) (xy 178.430174 -283.074872)
			(xy 178.429679 -283.099479) (xy 178.421784 -283.148056) (xy 178.4062 -283.194737) (xy 178.383329 -283.238314)
			(xy 178.353764 -283.277658) (xy 178.318271 -283.31175) (xy 178.277768 -283.339706) (xy 178.233306 -283.360804)
			(xy 178.186035 -283.374496) (xy 178.13718 -283.380428) (xy 178.088005 -283.378447) (xy 178.039786 -283.368603)
			(xy 177.99377 -283.351151) (xy 177.951149 -283.326544) (xy 177.913028 -283.295419) (xy 177.880393 -283.258582)
			(xy 177.85409 -283.216986) (xy 177.834799 -283.17171) (xy 177.823022 -283.123926) (xy 177.819062 -283.074872)
			(xy 177.480214 -283.074872) (xy 177.479719 -283.099479) (xy 177.471824 -283.148056) (xy 177.45624 -283.194737)
			(xy 177.433369 -283.238314) (xy 177.403804 -283.277658) (xy 177.368311 -283.31175) (xy 177.327808 -283.339706)
			(xy 177.283346 -283.360804) (xy 177.236075 -283.374496) (xy 177.18722 -283.380428) (xy 177.138045 -283.378447)
			(xy 177.089826 -283.368603) (xy 177.04381 -283.351151) (xy 177.001189 -283.326544) (xy 176.963068 -283.295419)
			(xy 176.930433 -283.258582) (xy 176.90413 -283.216986) (xy 176.884839 -283.17171) (xy 176.873062 -283.123926)
			(xy 176.869102 -283.074872) (xy 176.530254 -283.074872) (xy 176.529759 -283.099479) (xy 176.521864 -283.148056)
			(xy 176.50628 -283.194737) (xy 176.483409 -283.238314) (xy 176.453844 -283.277658) (xy 176.418351 -283.31175)
			(xy 176.377848 -283.339706) (xy 176.333386 -283.360804) (xy 176.286115 -283.374496) (xy 176.23726 -283.380428)
			(xy 176.188085 -283.378447) (xy 176.139866 -283.368603) (xy 176.09385 -283.351151) (xy 176.051229 -283.326544)
			(xy 176.013108 -283.295419) (xy 175.980473 -283.258582) (xy 175.95417 -283.216986) (xy 175.934879 -283.17171)
			(xy 175.923102 -283.123926) (xy 175.919142 -283.074872) (xy 174.630334 -283.074872) (xy 174.629839 -283.099479)
			(xy 174.621944 -283.148056) (xy 174.60636 -283.194737) (xy 174.583489 -283.238314) (xy 174.553924 -283.277658)
			(xy 174.518431 -283.31175) (xy 174.477928 -283.339706) (xy 174.433466 -283.360804) (xy 174.386195 -283.374496)
			(xy 174.33734 -283.380428) (xy 174.288165 -283.378447) (xy 174.239946 -283.368603) (xy 174.19393 -283.351151)
			(xy 174.151309 -283.326544) (xy 174.113188 -283.295419) (xy 174.080553 -283.258582) (xy 174.05425 -283.216986)
			(xy 174.034959 -283.17171) (xy 174.023182 -283.123926) (xy 174.019222 -283.074872) (xy 173.680374 -283.074872)
			(xy 173.679879 -283.099479) (xy 173.671984 -283.148056) (xy 173.6564 -283.194737) (xy 173.633529 -283.238314)
			(xy 173.603964 -283.277658) (xy 173.568471 -283.31175) (xy 173.527968 -283.339706) (xy 173.483506 -283.360804)
			(xy 173.436235 -283.374496) (xy 173.38738 -283.380428) (xy 173.338205 -283.378447) (xy 173.289986 -283.368603)
			(xy 173.24397 -283.351151) (xy 173.201349 -283.326544) (xy 173.163228 -283.295419) (xy 173.130593 -283.258582)
			(xy 173.10429 -283.216986) (xy 173.084999 -283.17171) (xy 173.073222 -283.123926) (xy 173.069262 -283.074872)
			(xy 172.730414 -283.074872) (xy 172.729919 -283.099479) (xy 172.722024 -283.148056) (xy 172.70644 -283.194737)
			(xy 172.683569 -283.238314) (xy 172.654004 -283.277658) (xy 172.618511 -283.31175) (xy 172.578008 -283.339706)
			(xy 172.533546 -283.360804) (xy 172.486275 -283.374496) (xy 172.43742 -283.380428) (xy 172.388245 -283.378447)
			(xy 172.340026 -283.368603) (xy 172.29401 -283.351151) (xy 172.251389 -283.326544) (xy 172.213268 -283.295419)
			(xy 172.180633 -283.258582) (xy 172.15433 -283.216986) (xy 172.135039 -283.17171) (xy 172.123262 -283.123926)
			(xy 172.119302 -283.074872) (xy 171.7802 -283.074872) (xy 171.779705 -283.099479) (xy 171.77181 -283.148056)
			(xy 171.756226 -283.194737) (xy 171.733355 -283.238314) (xy 171.70379 -283.277658) (xy 171.668297 -283.31175)
			(xy 171.627794 -283.339706) (xy 171.583332 -283.360804) (xy 171.536061 -283.374496) (xy 171.487206 -283.380428)
			(xy 171.438031 -283.378447) (xy 171.389812 -283.368603) (xy 171.343796 -283.351151) (xy 171.301175 -283.326544)
			(xy 171.263054 -283.295419) (xy 171.230419 -283.258582) (xy 171.204116 -283.216986) (xy 171.184825 -283.17171)
			(xy 171.173048 -283.123926) (xy 171.169088 -283.074872) (xy 170.83024 -283.074872) (xy 170.829745 -283.099479)
			(xy 170.82185 -283.148056) (xy 170.806266 -283.194737) (xy 170.783395 -283.238314) (xy 170.75383 -283.277658)
			(xy 170.718337 -283.31175) (xy 170.677834 -283.339706) (xy 170.633372 -283.360804) (xy 170.586101 -283.374496)
			(xy 170.537246 -283.380428) (xy 170.488071 -283.378447) (xy 170.439852 -283.368603) (xy 170.393836 -283.351151)
			(xy 170.351215 -283.326544) (xy 170.313094 -283.295419) (xy 170.280459 -283.258582) (xy 170.254156 -283.216986)
			(xy 170.234865 -283.17171) (xy 170.223088 -283.123926) (xy 170.219128 -283.074872) (xy 169.88028 -283.074872)
			(xy 169.879785 -283.099479) (xy 169.87189 -283.148056) (xy 169.856306 -283.194737) (xy 169.833435 -283.238314)
			(xy 169.80387 -283.277658) (xy 169.768377 -283.31175) (xy 169.727874 -283.339706) (xy 169.683412 -283.360804)
			(xy 169.636141 -283.374496) (xy 169.587286 -283.380428) (xy 169.538111 -283.378447) (xy 169.489892 -283.368603)
			(xy 169.443876 -283.351151) (xy 169.401255 -283.326544) (xy 169.363134 -283.295419) (xy 169.330499 -283.258582)
			(xy 169.304196 -283.216986) (xy 169.284905 -283.17171) (xy 169.273128 -283.123926) (xy 169.269168 -283.074872)
			(xy 168.93032 -283.074872) (xy 168.929825 -283.099479) (xy 168.92193 -283.148056) (xy 168.906346 -283.194737)
			(xy 168.883475 -283.238314) (xy 168.85391 -283.277658) (xy 168.818417 -283.31175) (xy 168.777914 -283.339706)
			(xy 168.733452 -283.360804) (xy 168.686181 -283.374496) (xy 168.637326 -283.380428) (xy 168.588151 -283.378447)
			(xy 168.539932 -283.368603) (xy 168.493916 -283.351151) (xy 168.451295 -283.326544) (xy 168.413174 -283.295419)
			(xy 168.380539 -283.258582) (xy 168.354236 -283.216986) (xy 168.334945 -283.17171) (xy 168.323168 -283.123926)
			(xy 168.319208 -283.074872) (xy 167.98036 -283.074872) (xy 167.979865 -283.099479) (xy 167.97197 -283.148056)
			(xy 167.956386 -283.194737) (xy 167.933515 -283.238314) (xy 167.90395 -283.277658) (xy 167.868457 -283.31175)
			(xy 167.827954 -283.339706) (xy 167.783492 -283.360804) (xy 167.736221 -283.374496) (xy 167.687366 -283.380428)
			(xy 167.638191 -283.378447) (xy 167.589972 -283.368603) (xy 167.543956 -283.351151) (xy 167.501335 -283.326544)
			(xy 167.463214 -283.295419) (xy 167.430579 -283.258582) (xy 167.404276 -283.216986) (xy 167.384985 -283.17171)
			(xy 167.373208 -283.123926) (xy 167.369248 -283.074872) (xy 167.0304 -283.074872) (xy 167.029905 -283.099479)
			(xy 167.02201 -283.148056) (xy 167.006426 -283.194737) (xy 166.983555 -283.238314) (xy 166.95399 -283.277658)
			(xy 166.918497 -283.31175) (xy 166.877994 -283.339706) (xy 166.833532 -283.360804) (xy 166.786261 -283.374496)
			(xy 166.737406 -283.380428) (xy 166.688231 -283.378447) (xy 166.640012 -283.368603) (xy 166.593996 -283.351151)
			(xy 166.551375 -283.326544) (xy 166.513254 -283.295419) (xy 166.480619 -283.258582) (xy 166.454316 -283.216986)
			(xy 166.435025 -283.17171) (xy 166.423248 -283.123926) (xy 166.419288 -283.074872) (xy 166.080186 -283.074872)
			(xy 166.079691 -283.099479) (xy 166.071796 -283.148056) (xy 166.056212 -283.194737) (xy 166.033341 -283.238314)
			(xy 166.003776 -283.277658) (xy 165.968283 -283.31175) (xy 165.92778 -283.339706) (xy 165.883318 -283.360804)
			(xy 165.836047 -283.374496) (xy 165.787192 -283.380428) (xy 165.738017 -283.378447) (xy 165.689798 -283.368603)
			(xy 165.643782 -283.351151) (xy 165.601161 -283.326544) (xy 165.56304 -283.295419) (xy 165.530405 -283.258582)
			(xy 165.504102 -283.216986) (xy 165.484811 -283.17171) (xy 165.473034 -283.123926) (xy 165.469074 -283.074872)
			(xy 165.303708 -283.074872) (xy 165.303708 -283.549852) (xy 189.69407 -283.549852) (xy 189.69803 -283.500798)
			(xy 189.709807 -283.453014) (xy 189.729098 -283.407738) (xy 189.755401 -283.366142) (xy 189.788036 -283.329305)
			(xy 189.826157 -283.29818) (xy 189.868778 -283.273573) (xy 189.914794 -283.256121) (xy 189.963013 -283.246277)
			(xy 190.012188 -283.244296) (xy 190.061043 -283.250228) (xy 190.108314 -283.26392) (xy 190.152776 -283.285018)
			(xy 190.193279 -283.312974) (xy 190.228772 -283.347066) (xy 190.258337 -283.38641) (xy 190.281208 -283.429987)
			(xy 190.296792 -283.476668) (xy 190.304687 -283.525245) (xy 190.305182 -283.549852) (xy 190.304687 -283.574459)
			(xy 190.304508 -283.57556) (xy 190.623186 -283.57556) (xy 190.623186 -283.524144) (xy 190.631229 -283.473362)
			(xy 190.647117 -283.424463) (xy 190.67046 -283.378651) (xy 190.700681 -283.337055) (xy 190.737037 -283.300699)
			(xy 190.778633 -283.270478) (xy 190.824445 -283.247135) (xy 190.873344 -283.231247) (xy 190.924126 -283.223204)
			(xy 190.975542 -283.223204) (xy 191.026324 -283.231247) (xy 191.075223 -283.247135) (xy 191.121035 -283.270478)
			(xy 191.162631 -283.300699) (xy 191.198987 -283.337055) (xy 191.229208 -283.378651) (xy 191.252551 -283.424463)
			(xy 191.268439 -283.473362) (xy 191.276482 -283.524144) (xy 191.276986 -283.549852) (xy 191.276482 -283.57556)
			(xy 191.5734 -283.57556) (xy 191.5734 -283.524144) (xy 191.581443 -283.473362) (xy 191.597331 -283.424463)
			(xy 191.620674 -283.378651) (xy 191.650895 -283.337055) (xy 191.687251 -283.300699) (xy 191.728847 -283.270478)
			(xy 191.774659 -283.247135) (xy 191.823558 -283.231247) (xy 191.87434 -283.223204) (xy 191.925756 -283.223204)
			(xy 191.976538 -283.231247) (xy 192.025437 -283.247135) (xy 192.071249 -283.270478) (xy 192.112845 -283.300699)
			(xy 192.149201 -283.337055) (xy 192.179422 -283.378651) (xy 192.202765 -283.424463) (xy 192.218653 -283.473362)
			(xy 192.226696 -283.524144) (xy 192.2272 -283.549852) (xy 192.544204 -283.549852) (xy 192.548164 -283.500798)
			(xy 192.559941 -283.453014) (xy 192.579232 -283.407738) (xy 192.605535 -283.366142) (xy 192.63817 -283.329305)
			(xy 192.676291 -283.29818) (xy 192.718912 -283.273573) (xy 192.764928 -283.256121) (xy 192.813147 -283.246277)
			(xy 192.862322 -283.244296) (xy 192.911177 -283.250228) (xy 192.958448 -283.26392) (xy 193.00291 -283.285018)
			(xy 193.043413 -283.312974) (xy 193.078906 -283.347066) (xy 193.108471 -283.38641) (xy 193.131342 -283.429987)
			(xy 193.146926 -283.476668) (xy 193.154821 -283.525245) (xy 193.155316 -283.549852) (xy 193.494164 -283.549852)
			(xy 193.498124 -283.500798) (xy 193.509901 -283.453014) (xy 193.529192 -283.407738) (xy 193.555495 -283.366142)
			(xy 193.58813 -283.329305) (xy 193.626251 -283.29818) (xy 193.668872 -283.273573) (xy 193.714888 -283.256121)
			(xy 193.763107 -283.246277) (xy 193.812282 -283.244296) (xy 193.861137 -283.250228) (xy 193.908408 -283.26392)
			(xy 193.95287 -283.285018) (xy 193.993373 -283.312974) (xy 194.028866 -283.347066) (xy 194.058431 -283.38641)
			(xy 194.081302 -283.429987) (xy 194.096886 -283.476668) (xy 194.104781 -283.525245) (xy 194.105276 -283.549852)
			(xy 194.444124 -283.549852) (xy 194.448084 -283.500798) (xy 194.459861 -283.453014) (xy 194.479152 -283.407738)
			(xy 194.505455 -283.366142) (xy 194.53809 -283.329305) (xy 194.576211 -283.29818) (xy 194.618832 -283.273573)
			(xy 194.664848 -283.256121) (xy 194.713067 -283.246277) (xy 194.762242 -283.244296) (xy 194.811097 -283.250228)
			(xy 194.858368 -283.26392) (xy 194.90283 -283.285018) (xy 194.943333 -283.312974) (xy 194.978826 -283.347066)
			(xy 195.008391 -283.38641) (xy 195.031262 -283.429987) (xy 195.046846 -283.476668) (xy 195.054741 -283.525245)
			(xy 195.055236 -283.549852) (xy 195.394084 -283.549852) (xy 195.398044 -283.500798) (xy 195.409821 -283.453014)
			(xy 195.429112 -283.407738) (xy 195.455415 -283.366142) (xy 195.48805 -283.329305) (xy 195.526171 -283.29818)
			(xy 195.568792 -283.273573) (xy 195.614808 -283.256121) (xy 195.663027 -283.246277) (xy 195.712202 -283.244296)
			(xy 195.761057 -283.250228) (xy 195.808328 -283.26392) (xy 195.85279 -283.285018) (xy 195.893293 -283.312974)
			(xy 195.928786 -283.347066) (xy 195.958351 -283.38641) (xy 195.981222 -283.429987) (xy 195.996806 -283.476668)
			(xy 196.004701 -283.525245) (xy 196.005196 -283.549852) (xy 196.344044 -283.549852) (xy 196.348004 -283.500798)
			(xy 196.359781 -283.453014) (xy 196.379072 -283.407738) (xy 196.405375 -283.366142) (xy 196.43801 -283.329305)
			(xy 196.476131 -283.29818) (xy 196.518752 -283.273573) (xy 196.564768 -283.256121) (xy 196.612987 -283.246277)
			(xy 196.662162 -283.244296) (xy 196.711017 -283.250228) (xy 196.758288 -283.26392) (xy 196.80275 -283.285018)
			(xy 196.843253 -283.312974) (xy 196.878746 -283.347066) (xy 196.908311 -283.38641) (xy 196.931182 -283.429987)
			(xy 196.946766 -283.476668) (xy 196.954661 -283.525245) (xy 196.955156 -283.549852) (xy 196.954661 -283.574459)
			(xy 196.954482 -283.57556) (xy 197.273414 -283.57556) (xy 197.273414 -283.524144) (xy 197.281457 -283.473362)
			(xy 197.297345 -283.424463) (xy 197.320688 -283.378651) (xy 197.350909 -283.337055) (xy 197.387265 -283.300699)
			(xy 197.428861 -283.270478) (xy 197.474673 -283.247135) (xy 197.523572 -283.231247) (xy 197.574354 -283.223204)
			(xy 197.62577 -283.223204) (xy 197.676552 -283.231247) (xy 197.725451 -283.247135) (xy 197.771263 -283.270478)
			(xy 197.812859 -283.300699) (xy 197.849215 -283.337055) (xy 197.879436 -283.378651) (xy 197.902779 -283.424463)
			(xy 197.918667 -283.473362) (xy 197.92671 -283.524144) (xy 197.927214 -283.549852) (xy 197.92671 -283.57556)
			(xy 198.223374 -283.57556) (xy 198.223374 -283.524144) (xy 198.231417 -283.473362) (xy 198.247305 -283.424463)
			(xy 198.270648 -283.378651) (xy 198.300869 -283.337055) (xy 198.337225 -283.300699) (xy 198.378821 -283.270478)
			(xy 198.424633 -283.247135) (xy 198.473532 -283.231247) (xy 198.524314 -283.223204) (xy 198.57573 -283.223204)
			(xy 198.626512 -283.231247) (xy 198.675411 -283.247135) (xy 198.721223 -283.270478) (xy 198.762819 -283.300699)
			(xy 198.799175 -283.337055) (xy 198.829396 -283.378651) (xy 198.852739 -283.424463) (xy 198.868627 -283.473362)
			(xy 198.87667 -283.524144) (xy 198.877174 -283.549852) (xy 198.877169 -283.550106) (xy 199.194432 -283.550106)
			(xy 199.198392 -283.501052) (xy 199.210169 -283.453268) (xy 199.22946 -283.407992) (xy 199.255763 -283.366396)
			(xy 199.288398 -283.329559) (xy 199.326519 -283.298434) (xy 199.36914 -283.273827) (xy 199.415156 -283.256375)
			(xy 199.463375 -283.246531) (xy 199.51255 -283.24455) (xy 199.561405 -283.250482) (xy 199.608676 -283.264174)
			(xy 199.653138 -283.285272) (xy 199.693641 -283.313228) (xy 199.729134 -283.34732) (xy 199.758699 -283.386664)
			(xy 199.78157 -283.430241) (xy 199.797154 -283.476922) (xy 199.805049 -283.525499) (xy 199.805544 -283.550106)
			(xy 199.805444 -283.555057) (xy 209.894309 -283.555057) (xy 209.894309 -283.500543) (xy 209.902068 -283.446583)
			(xy 209.917427 -283.394277) (xy 209.940074 -283.344689) (xy 209.969548 -283.298829) (xy 210.005248 -283.257631)
			(xy 210.046449 -283.221933) (xy 210.09231 -283.192462) (xy 210.1419 -283.169818) (xy 210.194207 -283.154462)
			(xy 210.248167 -283.146707) (xy 210.275424 -283.146246) (xy 210.302795 -283.146687) (xy 210.356976 -283.154509)
			(xy 210.40948 -283.170003) (xy 210.459226 -283.192851) (xy 210.505192 -283.222582) (xy 210.526122 -283.240226)
			(xy 210.533234 -283.246322) (xy 210.550252 -283.252672) (xy 210.635596 -283.252672) (xy 210.652614 -283.246322)
			(xy 210.659726 -283.240226) (xy 210.680679 -283.222612) (xy 210.726645 -283.192896) (xy 210.776388 -283.170054)
			(xy 210.828884 -283.154558) (xy 210.883056 -283.146723) (xy 210.910424 -283.146246) (xy 210.937671 -283.146826)
			(xy 210.991609 -283.154584) (xy 211.043895 -283.169939) (xy 211.093463 -283.192579) (xy 211.139305 -283.222043)
			(xy 211.180487 -283.25773) (xy 211.216172 -283.298914) (xy 211.245632 -283.344758) (xy 211.268269 -283.394328)
			(xy 211.283621 -283.446614) (xy 211.291376 -283.500553) (xy 211.291376 -283.555047) (xy 211.283621 -283.608986)
			(xy 211.268269 -283.661272) (xy 211.245632 -283.710842) (xy 211.216172 -283.756686) (xy 211.180487 -283.79787)
			(xy 211.139305 -283.833557) (xy 211.093463 -283.863021) (xy 211.043895 -283.885661) (xy 210.991609 -283.901016)
			(xy 210.937671 -283.908774) (xy 210.910424 -283.909262) (xy 210.883054 -283.908791) (xy 210.828875 -283.900976)
			(xy 210.776371 -283.885488) (xy 210.726624 -283.862648) (xy 210.680657 -283.832923) (xy 210.659726 -283.815282)
			(xy 210.652614 -283.809186) (xy 210.635596 -283.802836) (xy 210.550252 -283.802836) (xy 210.533234 -283.809186)
			(xy 210.526122 -283.815282) (xy 210.50519 -283.832921) (xy 210.459218 -283.862634) (xy 210.40947 -283.88547)
			(xy 210.356969 -283.900961) (xy 210.302793 -283.908788) (xy 210.275424 -283.909262) (xy 210.248167 -283.908893)
			(xy 210.194207 -283.901138) (xy 210.1419 -283.885782) (xy 210.09231 -283.863138) (xy 210.046449 -283.833667)
			(xy 210.005248 -283.797969) (xy 209.969548 -283.756771) (xy 209.940074 -283.710911) (xy 209.917427 -283.661323)
			(xy 209.902068 -283.609017) (xy 209.894309 -283.555057) (xy 199.805444 -283.555057) (xy 199.805049 -283.574713)
			(xy 199.797154 -283.62329) (xy 199.78157 -283.669971) (xy 199.758699 -283.713548) (xy 199.729134 -283.752892)
			(xy 199.693641 -283.786984) (xy 199.653138 -283.81494) (xy 199.608676 -283.836038) (xy 199.561405 -283.84973)
			(xy 199.51255 -283.855662) (xy 199.463375 -283.853681) (xy 199.415156 -283.843837) (xy 199.36914 -283.826385)
			(xy 199.326519 -283.801778) (xy 199.288398 -283.770653) (xy 199.255763 -283.733816) (xy 199.22946 -283.69222)
			(xy 199.210169 -283.646944) (xy 199.198392 -283.59916) (xy 199.194432 -283.550106) (xy 198.877169 -283.550106)
			(xy 198.87667 -283.57556) (xy 198.868627 -283.626342) (xy 198.852739 -283.675241) (xy 198.829396 -283.721053)
			(xy 198.799175 -283.762649) (xy 198.762819 -283.799005) (xy 198.721223 -283.829226) (xy 198.675411 -283.852569)
			(xy 198.626512 -283.868457) (xy 198.57573 -283.8765) (xy 198.524314 -283.8765) (xy 198.473532 -283.868457)
			(xy 198.424633 -283.852569) (xy 198.378821 -283.829226) (xy 198.337225 -283.799005) (xy 198.300869 -283.762649)
			(xy 198.270648 -283.721053) (xy 198.247305 -283.675241) (xy 198.231417 -283.626342) (xy 198.223374 -283.57556)
			(xy 197.92671 -283.57556) (xy 197.918667 -283.626342) (xy 197.902779 -283.675241) (xy 197.879436 -283.721053)
			(xy 197.849215 -283.762649) (xy 197.812859 -283.799005) (xy 197.771263 -283.829226) (xy 197.725451 -283.852569)
			(xy 197.676552 -283.868457) (xy 197.62577 -283.8765) (xy 197.574354 -283.8765) (xy 197.523572 -283.868457)
			(xy 197.474673 -283.852569) (xy 197.428861 -283.829226) (xy 197.387265 -283.799005) (xy 197.350909 -283.762649)
			(xy 197.320688 -283.721053) (xy 197.297345 -283.675241) (xy 197.281457 -283.626342) (xy 197.273414 -283.57556)
			(xy 196.954482 -283.57556) (xy 196.946766 -283.623036) (xy 196.931182 -283.669717) (xy 196.908311 -283.713294)
			(xy 196.878746 -283.752638) (xy 196.843253 -283.78673) (xy 196.80275 -283.814686) (xy 196.758288 -283.835784)
			(xy 196.711017 -283.849476) (xy 196.662162 -283.855408) (xy 196.612987 -283.853427) (xy 196.564768 -283.843583)
			(xy 196.518752 -283.826131) (xy 196.476131 -283.801524) (xy 196.43801 -283.770399) (xy 196.405375 -283.733562)
			(xy 196.379072 -283.691966) (xy 196.359781 -283.64669) (xy 196.348004 -283.598906) (xy 196.344044 -283.549852)
			(xy 196.005196 -283.549852) (xy 196.004701 -283.574459) (xy 195.996806 -283.623036) (xy 195.981222 -283.669717)
			(xy 195.958351 -283.713294) (xy 195.928786 -283.752638) (xy 195.893293 -283.78673) (xy 195.85279 -283.814686)
			(xy 195.808328 -283.835784) (xy 195.761057 -283.849476) (xy 195.712202 -283.855408) (xy 195.663027 -283.853427)
			(xy 195.614808 -283.843583) (xy 195.568792 -283.826131) (xy 195.526171 -283.801524) (xy 195.48805 -283.770399)
			(xy 195.455415 -283.733562) (xy 195.429112 -283.691966) (xy 195.409821 -283.64669) (xy 195.398044 -283.598906)
			(xy 195.394084 -283.549852) (xy 195.055236 -283.549852) (xy 195.054741 -283.574459) (xy 195.046846 -283.623036)
			(xy 195.031262 -283.669717) (xy 195.008391 -283.713294) (xy 194.978826 -283.752638) (xy 194.943333 -283.78673)
			(xy 194.90283 -283.814686) (xy 194.858368 -283.835784) (xy 194.811097 -283.849476) (xy 194.762242 -283.855408)
			(xy 194.713067 -283.853427) (xy 194.664848 -283.843583) (xy 194.618832 -283.826131) (xy 194.576211 -283.801524)
			(xy 194.53809 -283.770399) (xy 194.505455 -283.733562) (xy 194.479152 -283.691966) (xy 194.459861 -283.64669)
			(xy 194.448084 -283.598906) (xy 194.444124 -283.549852) (xy 194.105276 -283.549852) (xy 194.104781 -283.574459)
			(xy 194.096886 -283.623036) (xy 194.081302 -283.669717) (xy 194.058431 -283.713294) (xy 194.028866 -283.752638)
			(xy 193.993373 -283.78673) (xy 193.95287 -283.814686) (xy 193.908408 -283.835784) (xy 193.861137 -283.849476)
			(xy 193.812282 -283.855408) (xy 193.763107 -283.853427) (xy 193.714888 -283.843583) (xy 193.668872 -283.826131)
			(xy 193.626251 -283.801524) (xy 193.58813 -283.770399) (xy 193.555495 -283.733562) (xy 193.529192 -283.691966)
			(xy 193.509901 -283.64669) (xy 193.498124 -283.598906) (xy 193.494164 -283.549852) (xy 193.155316 -283.549852)
			(xy 193.154821 -283.574459) (xy 193.146926 -283.623036) (xy 193.131342 -283.669717) (xy 193.108471 -283.713294)
			(xy 193.078906 -283.752638) (xy 193.043413 -283.78673) (xy 193.00291 -283.814686) (xy 192.958448 -283.835784)
			(xy 192.911177 -283.849476) (xy 192.862322 -283.855408) (xy 192.813147 -283.853427) (xy 192.764928 -283.843583)
			(xy 192.718912 -283.826131) (xy 192.676291 -283.801524) (xy 192.63817 -283.770399) (xy 192.605535 -283.733562)
			(xy 192.579232 -283.691966) (xy 192.559941 -283.64669) (xy 192.548164 -283.598906) (xy 192.544204 -283.549852)
			(xy 192.2272 -283.549852) (xy 192.226696 -283.57556) (xy 192.218653 -283.626342) (xy 192.202765 -283.675241)
			(xy 192.179422 -283.721053) (xy 192.149201 -283.762649) (xy 192.112845 -283.799005) (xy 192.071249 -283.829226)
			(xy 192.025437 -283.852569) (xy 191.976538 -283.868457) (xy 191.925756 -283.8765) (xy 191.87434 -283.8765)
			(xy 191.823558 -283.868457) (xy 191.774659 -283.852569) (xy 191.728847 -283.829226) (xy 191.687251 -283.799005)
			(xy 191.650895 -283.762649) (xy 191.620674 -283.721053) (xy 191.597331 -283.675241) (xy 191.581443 -283.626342)
			(xy 191.5734 -283.57556) (xy 191.276482 -283.57556) (xy 191.268439 -283.626342) (xy 191.252551 -283.675241)
			(xy 191.229208 -283.721053) (xy 191.198987 -283.762649) (xy 191.162631 -283.799005) (xy 191.121035 -283.829226)
			(xy 191.075223 -283.852569) (xy 191.026324 -283.868457) (xy 190.975542 -283.8765) (xy 190.924126 -283.8765)
			(xy 190.873344 -283.868457) (xy 190.824445 -283.852569) (xy 190.778633 -283.829226) (xy 190.737037 -283.799005)
			(xy 190.700681 -283.762649) (xy 190.67046 -283.721053) (xy 190.647117 -283.675241) (xy 190.631229 -283.626342)
			(xy 190.623186 -283.57556) (xy 190.304508 -283.57556) (xy 190.296792 -283.623036) (xy 190.281208 -283.669717)
			(xy 190.258337 -283.713294) (xy 190.228772 -283.752638) (xy 190.193279 -283.78673) (xy 190.152776 -283.814686)
			(xy 190.108314 -283.835784) (xy 190.061043 -283.849476) (xy 190.012188 -283.855408) (xy 189.963013 -283.853427)
			(xy 189.914794 -283.843583) (xy 189.868778 -283.826131) (xy 189.826157 -283.801524) (xy 189.788036 -283.770399)
			(xy 189.755401 -283.733562) (xy 189.729098 -283.691966) (xy 189.709807 -283.64669) (xy 189.69803 -283.598906)
			(xy 189.69407 -283.549852) (xy 165.303708 -283.549852) (xy 165.303708 -284.024832) (xy 165.469074 -284.024832)
			(xy 165.473034 -283.975778) (xy 165.484811 -283.927994) (xy 165.504102 -283.882718) (xy 165.530405 -283.841122)
			(xy 165.56304 -283.804285) (xy 165.601161 -283.77316) (xy 165.643782 -283.748553) (xy 165.689798 -283.731101)
			(xy 165.738017 -283.721257) (xy 165.787192 -283.719276) (xy 165.836047 -283.725208) (xy 165.883318 -283.7389)
			(xy 165.92778 -283.759998) (xy 165.968283 -283.787954) (xy 166.003776 -283.822046) (xy 166.033341 -283.86139)
			(xy 166.056212 -283.904967) (xy 166.071796 -283.951648) (xy 166.079691 -284.000225) (xy 166.080186 -284.024832)
			(xy 166.419288 -284.024832) (xy 166.423248 -283.975778) (xy 166.435025 -283.927994) (xy 166.454316 -283.882718)
			(xy 166.480619 -283.841122) (xy 166.513254 -283.804285) (xy 166.551375 -283.77316) (xy 166.593996 -283.748553)
			(xy 166.640012 -283.731101) (xy 166.688231 -283.721257) (xy 166.737406 -283.719276) (xy 166.786261 -283.725208)
			(xy 166.833532 -283.7389) (xy 166.877994 -283.759998) (xy 166.918497 -283.787954) (xy 166.95399 -283.822046)
			(xy 166.983555 -283.86139) (xy 167.006426 -283.904967) (xy 167.02201 -283.951648) (xy 167.029905 -284.000225)
			(xy 167.0304 -284.024832) (xy 167.369248 -284.024832) (xy 167.373208 -283.975778) (xy 167.384985 -283.927994)
			(xy 167.404276 -283.882718) (xy 167.430579 -283.841122) (xy 167.463214 -283.804285) (xy 167.501335 -283.77316)
			(xy 167.543956 -283.748553) (xy 167.589972 -283.731101) (xy 167.638191 -283.721257) (xy 167.687366 -283.719276)
			(xy 167.736221 -283.725208) (xy 167.783492 -283.7389) (xy 167.827954 -283.759998) (xy 167.868457 -283.787954)
			(xy 167.90395 -283.822046) (xy 167.933515 -283.86139) (xy 167.956386 -283.904967) (xy 167.97197 -283.951648)
			(xy 167.979865 -284.000225) (xy 167.98036 -284.024832) (xy 168.319208 -284.024832) (xy 168.323168 -283.975778)
			(xy 168.334945 -283.927994) (xy 168.354236 -283.882718) (xy 168.380539 -283.841122) (xy 168.413174 -283.804285)
			(xy 168.451295 -283.77316) (xy 168.493916 -283.748553) (xy 168.539932 -283.731101) (xy 168.588151 -283.721257)
			(xy 168.637326 -283.719276) (xy 168.686181 -283.725208) (xy 168.733452 -283.7389) (xy 168.777914 -283.759998)
			(xy 168.818417 -283.787954) (xy 168.85391 -283.822046) (xy 168.883475 -283.86139) (xy 168.906346 -283.904967)
			(xy 168.92193 -283.951648) (xy 168.929825 -284.000225) (xy 168.93032 -284.024832) (xy 169.269168 -284.024832)
			(xy 169.273128 -283.975778) (xy 169.284905 -283.927994) (xy 169.304196 -283.882718) (xy 169.330499 -283.841122)
			(xy 169.363134 -283.804285) (xy 169.401255 -283.77316) (xy 169.443876 -283.748553) (xy 169.489892 -283.731101)
			(xy 169.538111 -283.721257) (xy 169.587286 -283.719276) (xy 169.636141 -283.725208) (xy 169.683412 -283.7389)
			(xy 169.727874 -283.759998) (xy 169.768377 -283.787954) (xy 169.80387 -283.822046) (xy 169.833435 -283.86139)
			(xy 169.856306 -283.904967) (xy 169.87189 -283.951648) (xy 169.879785 -284.000225) (xy 169.88028 -284.024832)
			(xy 170.219128 -284.024832) (xy 170.223088 -283.975778) (xy 170.234865 -283.927994) (xy 170.254156 -283.882718)
			(xy 170.280459 -283.841122) (xy 170.313094 -283.804285) (xy 170.351215 -283.77316) (xy 170.393836 -283.748553)
			(xy 170.439852 -283.731101) (xy 170.488071 -283.721257) (xy 170.537246 -283.719276) (xy 170.586101 -283.725208)
			(xy 170.633372 -283.7389) (xy 170.677834 -283.759998) (xy 170.718337 -283.787954) (xy 170.75383 -283.822046)
			(xy 170.783395 -283.86139) (xy 170.806266 -283.904967) (xy 170.82185 -283.951648) (xy 170.829745 -284.000225)
			(xy 170.83024 -284.024832) (xy 171.169088 -284.024832) (xy 171.173048 -283.975778) (xy 171.184825 -283.927994)
			(xy 171.204116 -283.882718) (xy 171.230419 -283.841122) (xy 171.263054 -283.804285) (xy 171.301175 -283.77316)
			(xy 171.343796 -283.748553) (xy 171.389812 -283.731101) (xy 171.438031 -283.721257) (xy 171.487206 -283.719276)
			(xy 171.536061 -283.725208) (xy 171.583332 -283.7389) (xy 171.627794 -283.759998) (xy 171.668297 -283.787954)
			(xy 171.70379 -283.822046) (xy 171.733355 -283.86139) (xy 171.756226 -283.904967) (xy 171.77181 -283.951648)
			(xy 171.779705 -284.000225) (xy 171.7802 -284.024832) (xy 172.119048 -284.024832) (xy 172.123008 -283.975778)
			(xy 172.134785 -283.927994) (xy 172.154076 -283.882718) (xy 172.180379 -283.841122) (xy 172.213014 -283.804285)
			(xy 172.251135 -283.77316) (xy 172.293756 -283.748553) (xy 172.339772 -283.731101) (xy 172.387991 -283.721257)
			(xy 172.437166 -283.719276) (xy 172.486021 -283.725208) (xy 172.533292 -283.7389) (xy 172.577754 -283.759998)
			(xy 172.618257 -283.787954) (xy 172.65375 -283.822046) (xy 172.683315 -283.86139) (xy 172.706186 -283.904967)
			(xy 172.72177 -283.951648) (xy 172.729665 -284.000225) (xy 172.73016 -284.024832) (xy 173.069262 -284.024832)
			(xy 173.073222 -283.975778) (xy 173.084999 -283.927994) (xy 173.10429 -283.882718) (xy 173.130593 -283.841122)
			(xy 173.163228 -283.804285) (xy 173.201349 -283.77316) (xy 173.24397 -283.748553) (xy 173.289986 -283.731101)
			(xy 173.338205 -283.721257) (xy 173.38738 -283.719276) (xy 173.436235 -283.725208) (xy 173.483506 -283.7389)
			(xy 173.527968 -283.759998) (xy 173.568471 -283.787954) (xy 173.603964 -283.822046) (xy 173.633529 -283.86139)
			(xy 173.6564 -283.904967) (xy 173.671984 -283.951648) (xy 173.679879 -284.000225) (xy 173.680374 -284.024832)
			(xy 174.019222 -284.024832) (xy 174.023182 -283.975778) (xy 174.034959 -283.927994) (xy 174.05425 -283.882718)
			(xy 174.080553 -283.841122) (xy 174.113188 -283.804285) (xy 174.151309 -283.77316) (xy 174.19393 -283.748553)
			(xy 174.239946 -283.731101) (xy 174.288165 -283.721257) (xy 174.33734 -283.719276) (xy 174.386195 -283.725208)
			(xy 174.433466 -283.7389) (xy 174.477928 -283.759998) (xy 174.518431 -283.787954) (xy 174.553924 -283.822046)
			(xy 174.583489 -283.86139) (xy 174.60636 -283.904967) (xy 174.621944 -283.951648) (xy 174.629839 -284.000225)
			(xy 174.630334 -284.024832) (xy 175.919142 -284.024832) (xy 175.923102 -283.975778) (xy 175.934879 -283.927994)
			(xy 175.95417 -283.882718) (xy 175.980473 -283.841122) (xy 176.013108 -283.804285) (xy 176.051229 -283.77316)
			(xy 176.09385 -283.748553) (xy 176.139866 -283.731101) (xy 176.188085 -283.721257) (xy 176.23726 -283.719276)
			(xy 176.286115 -283.725208) (xy 176.333386 -283.7389) (xy 176.377848 -283.759998) (xy 176.418351 -283.787954)
			(xy 176.453844 -283.822046) (xy 176.483409 -283.86139) (xy 176.50628 -283.904967) (xy 176.521864 -283.951648)
			(xy 176.529759 -284.000225) (xy 176.530254 -284.024832) (xy 176.869102 -284.024832) (xy 176.873062 -283.975778)
			(xy 176.884839 -283.927994) (xy 176.90413 -283.882718) (xy 176.930433 -283.841122) (xy 176.963068 -283.804285)
			(xy 177.001189 -283.77316) (xy 177.04381 -283.748553) (xy 177.089826 -283.731101) (xy 177.138045 -283.721257)
			(xy 177.18722 -283.719276) (xy 177.236075 -283.725208) (xy 177.283346 -283.7389) (xy 177.327808 -283.759998)
			(xy 177.368311 -283.787954) (xy 177.403804 -283.822046) (xy 177.433369 -283.86139) (xy 177.45624 -283.904967)
			(xy 177.471824 -283.951648) (xy 177.479719 -284.000225) (xy 177.480214 -284.024832) (xy 177.819062 -284.024832)
			(xy 177.823022 -283.975778) (xy 177.834799 -283.927994) (xy 177.85409 -283.882718) (xy 177.880393 -283.841122)
			(xy 177.913028 -283.804285) (xy 177.951149 -283.77316) (xy 177.99377 -283.748553) (xy 178.039786 -283.731101)
			(xy 178.088005 -283.721257) (xy 178.13718 -283.719276) (xy 178.186035 -283.725208) (xy 178.233306 -283.7389)
			(xy 178.277768 -283.759998) (xy 178.318271 -283.787954) (xy 178.353764 -283.822046) (xy 178.383329 -283.86139)
			(xy 178.4062 -283.904967) (xy 178.421784 -283.951648) (xy 178.429679 -284.000225) (xy 178.430174 -284.024832)
			(xy 178.769276 -284.024832) (xy 178.773236 -283.975778) (xy 178.785013 -283.927994) (xy 178.804304 -283.882718)
			(xy 178.830607 -283.841122) (xy 178.863242 -283.804285) (xy 178.901363 -283.77316) (xy 178.943984 -283.748553)
			(xy 178.99 -283.731101) (xy 179.038219 -283.721257) (xy 179.087394 -283.719276) (xy 179.136249 -283.725208)
			(xy 179.18352 -283.7389) (xy 179.227982 -283.759998) (xy 179.268485 -283.787954) (xy 179.303978 -283.822046)
			(xy 179.333543 -283.86139) (xy 179.356414 -283.904967) (xy 179.371998 -283.951648) (xy 179.379893 -284.000225)
			(xy 179.380388 -284.024832) (xy 179.719236 -284.024832) (xy 179.723196 -283.975778) (xy 179.734973 -283.927994)
			(xy 179.754264 -283.882718) (xy 179.780567 -283.841122) (xy 179.813202 -283.804285) (xy 179.851323 -283.77316)
			(xy 179.893944 -283.748553) (xy 179.93996 -283.731101) (xy 179.988179 -283.721257) (xy 180.037354 -283.719276)
			(xy 180.086209 -283.725208) (xy 180.13348 -283.7389) (xy 180.177942 -283.759998) (xy 180.218445 -283.787954)
			(xy 180.253938 -283.822046) (xy 180.283503 -283.86139) (xy 180.306374 -283.904967) (xy 180.321958 -283.951648)
			(xy 180.329853 -284.000225) (xy 180.330348 -284.024832) (xy 180.669196 -284.024832) (xy 180.673156 -283.975778)
			(xy 180.684933 -283.927994) (xy 180.704224 -283.882718) (xy 180.730527 -283.841122) (xy 180.763162 -283.804285)
			(xy 180.801283 -283.77316) (xy 180.843904 -283.748553) (xy 180.88992 -283.731101) (xy 180.938139 -283.721257)
			(xy 180.987314 -283.719276) (xy 181.036169 -283.725208) (xy 181.08344 -283.7389) (xy 181.127902 -283.759998)
			(xy 181.168405 -283.787954) (xy 181.203898 -283.822046) (xy 181.233463 -283.86139) (xy 181.256334 -283.904967)
			(xy 181.271918 -283.951648) (xy 181.279813 -284.000225) (xy 181.280308 -284.024832) (xy 181.619156 -284.024832)
			(xy 181.623116 -283.975778) (xy 181.634893 -283.927994) (xy 181.654184 -283.882718) (xy 181.680487 -283.841122)
			(xy 181.713122 -283.804285) (xy 181.751243 -283.77316) (xy 181.793864 -283.748553) (xy 181.83988 -283.731101)
			(xy 181.888099 -283.721257) (xy 181.937274 -283.719276) (xy 181.986129 -283.725208) (xy 182.0334 -283.7389)
			(xy 182.077862 -283.759998) (xy 182.118365 -283.787954) (xy 182.153858 -283.822046) (xy 182.183423 -283.86139)
			(xy 182.206294 -283.904967) (xy 182.221878 -283.951648) (xy 182.229773 -284.000225) (xy 182.230268 -284.024832)
			(xy 182.569116 -284.024832) (xy 182.573076 -283.975778) (xy 182.584853 -283.927994) (xy 182.604144 -283.882718)
			(xy 182.630447 -283.841122) (xy 182.663082 -283.804285) (xy 182.701203 -283.77316) (xy 182.743824 -283.748553)
			(xy 182.78984 -283.731101) (xy 182.838059 -283.721257) (xy 182.887234 -283.719276) (xy 182.936089 -283.725208)
			(xy 182.98336 -283.7389) (xy 183.027822 -283.759998) (xy 183.068325 -283.787954) (xy 183.103818 -283.822046)
			(xy 183.133383 -283.86139) (xy 183.156254 -283.904967) (xy 183.171838 -283.951648) (xy 183.179733 -284.000225)
			(xy 183.180228 -284.024832) (xy 184.469036 -284.024832) (xy 184.472996 -283.975778) (xy 184.484773 -283.927994)
			(xy 184.504064 -283.882718) (xy 184.530367 -283.841122) (xy 184.563002 -283.804285) (xy 184.601123 -283.77316)
			(xy 184.643744 -283.748553) (xy 184.68976 -283.731101) (xy 184.737979 -283.721257) (xy 184.787154 -283.719276)
			(xy 184.836009 -283.725208) (xy 184.88328 -283.7389) (xy 184.927742 -283.759998) (xy 184.968245 -283.787954)
			(xy 185.003738 -283.822046) (xy 185.033303 -283.86139) (xy 185.056174 -283.904967) (xy 185.071758 -283.951648)
			(xy 185.079653 -284.000225) (xy 185.080148 -284.024832) (xy 185.41925 -284.024832) (xy 185.42321 -283.975778)
			(xy 185.434987 -283.927994) (xy 185.454278 -283.882718) (xy 185.480581 -283.841122) (xy 185.513216 -283.804285)
			(xy 185.551337 -283.77316) (xy 185.593958 -283.748553) (xy 185.639974 -283.731101) (xy 185.688193 -283.721257)
			(xy 185.737368 -283.719276) (xy 185.786223 -283.725208) (xy 185.833494 -283.7389) (xy 185.877956 -283.759998)
			(xy 185.918459 -283.787954) (xy 185.953952 -283.822046) (xy 185.983517 -283.86139) (xy 186.006388 -283.904967)
			(xy 186.021972 -283.951648) (xy 186.029867 -284.000225) (xy 186.030362 -284.024832) (xy 186.36921 -284.024832)
			(xy 186.37317 -283.975778) (xy 186.384947 -283.927994) (xy 186.404238 -283.882718) (xy 186.430541 -283.841122)
			(xy 186.463176 -283.804285) (xy 186.501297 -283.77316) (xy 186.543918 -283.748553) (xy 186.589934 -283.731101)
			(xy 186.638153 -283.721257) (xy 186.687328 -283.719276) (xy 186.736183 -283.725208) (xy 186.783454 -283.7389)
			(xy 186.827916 -283.759998) (xy 186.868419 -283.787954) (xy 186.903912 -283.822046) (xy 186.933477 -283.86139)
			(xy 186.956348 -283.904967) (xy 186.971932 -283.951648) (xy 186.979827 -284.000225) (xy 186.980322 -284.024832)
			(xy 187.31917 -284.024832) (xy 187.32313 -283.975778) (xy 187.334907 -283.927994) (xy 187.354198 -283.882718)
			(xy 187.380501 -283.841122) (xy 187.413136 -283.804285) (xy 187.451257 -283.77316) (xy 187.493878 -283.748553)
			(xy 187.539894 -283.731101) (xy 187.588113 -283.721257) (xy 187.637288 -283.719276) (xy 187.686143 -283.725208)
			(xy 187.733414 -283.7389) (xy 187.777876 -283.759998) (xy 187.818379 -283.787954) (xy 187.853872 -283.822046)
			(xy 187.883437 -283.86139) (xy 187.906308 -283.904967) (xy 187.921892 -283.951648) (xy 187.929787 -284.000225)
			(xy 187.930282 -284.024832) (xy 188.26913 -284.024832) (xy 188.27309 -283.975778) (xy 188.284867 -283.927994)
			(xy 188.304158 -283.882718) (xy 188.330461 -283.841122) (xy 188.363096 -283.804285) (xy 188.401217 -283.77316)
			(xy 188.443838 -283.748553) (xy 188.489854 -283.731101) (xy 188.538073 -283.721257) (xy 188.587248 -283.719276)
			(xy 188.636103 -283.725208) (xy 188.683374 -283.7389) (xy 188.727836 -283.759998) (xy 188.768339 -283.787954)
			(xy 188.803832 -283.822046) (xy 188.833397 -283.86139) (xy 188.856268 -283.904967) (xy 188.871852 -283.951648)
			(xy 188.879747 -284.000225) (xy 188.880242 -284.024832) (xy 188.879747 -284.049439) (xy 188.871852 -284.098016)
			(xy 188.856268 -284.144697) (xy 188.833397 -284.188274) (xy 188.803832 -284.227618) (xy 188.768339 -284.26171)
			(xy 188.727836 -284.289666) (xy 188.683374 -284.310764) (xy 188.636103 -284.324456) (xy 188.587248 -284.330388)
			(xy 188.538073 -284.328407) (xy 188.489854 -284.318563) (xy 188.443838 -284.301111) (xy 188.401217 -284.276504)
			(xy 188.363096 -284.245379) (xy 188.330461 -284.208542) (xy 188.304158 -284.166946) (xy 188.284867 -284.12167)
			(xy 188.27309 -284.073886) (xy 188.26913 -284.024832) (xy 187.930282 -284.024832) (xy 187.929787 -284.049439)
			(xy 187.921892 -284.098016) (xy 187.906308 -284.144697) (xy 187.883437 -284.188274) (xy 187.853872 -284.227618)
			(xy 187.818379 -284.26171) (xy 187.777876 -284.289666) (xy 187.733414 -284.310764) (xy 187.686143 -284.324456)
			(xy 187.637288 -284.330388) (xy 187.588113 -284.328407) (xy 187.539894 -284.318563) (xy 187.493878 -284.301111)
			(xy 187.451257 -284.276504) (xy 187.413136 -284.245379) (xy 187.380501 -284.208542) (xy 187.354198 -284.166946)
			(xy 187.334907 -284.12167) (xy 187.32313 -284.073886) (xy 187.31917 -284.024832) (xy 186.980322 -284.024832)
			(xy 186.979827 -284.049439) (xy 186.971932 -284.098016) (xy 186.956348 -284.144697) (xy 186.933477 -284.188274)
			(xy 186.903912 -284.227618) (xy 186.868419 -284.26171) (xy 186.827916 -284.289666) (xy 186.783454 -284.310764)
			(xy 186.736183 -284.324456) (xy 186.687328 -284.330388) (xy 186.638153 -284.328407) (xy 186.589934 -284.318563)
			(xy 186.543918 -284.301111) (xy 186.501297 -284.276504) (xy 186.463176 -284.245379) (xy 186.430541 -284.208542)
			(xy 186.404238 -284.166946) (xy 186.384947 -284.12167) (xy 186.37317 -284.073886) (xy 186.36921 -284.024832)
			(xy 186.030362 -284.024832) (xy 186.029867 -284.049439) (xy 186.021972 -284.098016) (xy 186.006388 -284.144697)
			(xy 185.983517 -284.188274) (xy 185.953952 -284.227618) (xy 185.918459 -284.26171) (xy 185.877956 -284.289666)
			(xy 185.833494 -284.310764) (xy 185.786223 -284.324456) (xy 185.737368 -284.330388) (xy 185.688193 -284.328407)
			(xy 185.639974 -284.318563) (xy 185.593958 -284.301111) (xy 185.551337 -284.276504) (xy 185.513216 -284.245379)
			(xy 185.480581 -284.208542) (xy 185.454278 -284.166946) (xy 185.434987 -284.12167) (xy 185.42321 -284.073886)
			(xy 185.41925 -284.024832) (xy 185.080148 -284.024832) (xy 185.079653 -284.049439) (xy 185.071758 -284.098016)
			(xy 185.056174 -284.144697) (xy 185.033303 -284.188274) (xy 185.003738 -284.227618) (xy 184.968245 -284.26171)
			(xy 184.927742 -284.289666) (xy 184.88328 -284.310764) (xy 184.836009 -284.324456) (xy 184.787154 -284.330388)
			(xy 184.737979 -284.328407) (xy 184.68976 -284.318563) (xy 184.643744 -284.301111) (xy 184.601123 -284.276504)
			(xy 184.563002 -284.245379) (xy 184.530367 -284.208542) (xy 184.504064 -284.166946) (xy 184.484773 -284.12167)
			(xy 184.472996 -284.073886) (xy 184.469036 -284.024832) (xy 183.180228 -284.024832) (xy 183.179733 -284.049439)
			(xy 183.171838 -284.098016) (xy 183.156254 -284.144697) (xy 183.133383 -284.188274) (xy 183.103818 -284.227618)
			(xy 183.068325 -284.26171) (xy 183.027822 -284.289666) (xy 182.98336 -284.310764) (xy 182.936089 -284.324456)
			(xy 182.887234 -284.330388) (xy 182.838059 -284.328407) (xy 182.78984 -284.318563) (xy 182.743824 -284.301111)
			(xy 182.701203 -284.276504) (xy 182.663082 -284.245379) (xy 182.630447 -284.208542) (xy 182.604144 -284.166946)
			(xy 182.584853 -284.12167) (xy 182.573076 -284.073886) (xy 182.569116 -284.024832) (xy 182.230268 -284.024832)
			(xy 182.229773 -284.049439) (xy 182.221878 -284.098016) (xy 182.206294 -284.144697) (xy 182.183423 -284.188274)
			(xy 182.153858 -284.227618) (xy 182.118365 -284.26171) (xy 182.077862 -284.289666) (xy 182.0334 -284.310764)
			(xy 181.986129 -284.324456) (xy 181.937274 -284.330388) (xy 181.888099 -284.328407) (xy 181.83988 -284.318563)
			(xy 181.793864 -284.301111) (xy 181.751243 -284.276504) (xy 181.713122 -284.245379) (xy 181.680487 -284.208542)
			(xy 181.654184 -284.166946) (xy 181.634893 -284.12167) (xy 181.623116 -284.073886) (xy 181.619156 -284.024832)
			(xy 181.280308 -284.024832) (xy 181.279813 -284.049439) (xy 181.271918 -284.098016) (xy 181.256334 -284.144697)
			(xy 181.233463 -284.188274) (xy 181.203898 -284.227618) (xy 181.168405 -284.26171) (xy 181.127902 -284.289666)
			(xy 181.08344 -284.310764) (xy 181.036169 -284.324456) (xy 180.987314 -284.330388) (xy 180.938139 -284.328407)
			(xy 180.88992 -284.318563) (xy 180.843904 -284.301111) (xy 180.801283 -284.276504) (xy 180.763162 -284.245379)
			(xy 180.730527 -284.208542) (xy 180.704224 -284.166946) (xy 180.684933 -284.12167) (xy 180.673156 -284.073886)
			(xy 180.669196 -284.024832) (xy 180.330348 -284.024832) (xy 180.329853 -284.049439) (xy 180.321958 -284.098016)
			(xy 180.306374 -284.144697) (xy 180.283503 -284.188274) (xy 180.253938 -284.227618) (xy 180.218445 -284.26171)
			(xy 180.177942 -284.289666) (xy 180.13348 -284.310764) (xy 180.086209 -284.324456) (xy 180.037354 -284.330388)
			(xy 179.988179 -284.328407) (xy 179.93996 -284.318563) (xy 179.893944 -284.301111) (xy 179.851323 -284.276504)
			(xy 179.813202 -284.245379) (xy 179.780567 -284.208542) (xy 179.754264 -284.166946) (xy 179.734973 -284.12167)
			(xy 179.723196 -284.073886) (xy 179.719236 -284.024832) (xy 179.380388 -284.024832) (xy 179.379893 -284.049439)
			(xy 179.371998 -284.098016) (xy 179.356414 -284.144697) (xy 179.333543 -284.188274) (xy 179.303978 -284.227618)
			(xy 179.268485 -284.26171) (xy 179.227982 -284.289666) (xy 179.18352 -284.310764) (xy 179.136249 -284.324456)
			(xy 179.087394 -284.330388) (xy 179.038219 -284.328407) (xy 178.99 -284.318563) (xy 178.943984 -284.301111)
			(xy 178.901363 -284.276504) (xy 178.863242 -284.245379) (xy 178.830607 -284.208542) (xy 178.804304 -284.166946)
			(xy 178.785013 -284.12167) (xy 178.773236 -284.073886) (xy 178.769276 -284.024832) (xy 178.430174 -284.024832)
			(xy 178.429679 -284.049439) (xy 178.421784 -284.098016) (xy 178.4062 -284.144697) (xy 178.383329 -284.188274)
			(xy 178.353764 -284.227618) (xy 178.318271 -284.26171) (xy 178.277768 -284.289666) (xy 178.233306 -284.310764)
			(xy 178.186035 -284.324456) (xy 178.13718 -284.330388) (xy 178.088005 -284.328407) (xy 178.039786 -284.318563)
			(xy 177.99377 -284.301111) (xy 177.951149 -284.276504) (xy 177.913028 -284.245379) (xy 177.880393 -284.208542)
			(xy 177.85409 -284.166946) (xy 177.834799 -284.12167) (xy 177.823022 -284.073886) (xy 177.819062 -284.024832)
			(xy 177.480214 -284.024832) (xy 177.479719 -284.049439) (xy 177.471824 -284.098016) (xy 177.45624 -284.144697)
			(xy 177.433369 -284.188274) (xy 177.403804 -284.227618) (xy 177.368311 -284.26171) (xy 177.327808 -284.289666)
			(xy 177.283346 -284.310764) (xy 177.236075 -284.324456) (xy 177.18722 -284.330388) (xy 177.138045 -284.328407)
			(xy 177.089826 -284.318563) (xy 177.04381 -284.301111) (xy 177.001189 -284.276504) (xy 176.963068 -284.245379)
			(xy 176.930433 -284.208542) (xy 176.90413 -284.166946) (xy 176.884839 -284.12167) (xy 176.873062 -284.073886)
			(xy 176.869102 -284.024832) (xy 176.530254 -284.024832) (xy 176.529759 -284.049439) (xy 176.521864 -284.098016)
			(xy 176.50628 -284.144697) (xy 176.483409 -284.188274) (xy 176.453844 -284.227618) (xy 176.418351 -284.26171)
			(xy 176.377848 -284.289666) (xy 176.333386 -284.310764) (xy 176.286115 -284.324456) (xy 176.23726 -284.330388)
			(xy 176.188085 -284.328407) (xy 176.139866 -284.318563) (xy 176.09385 -284.301111) (xy 176.051229 -284.276504)
			(xy 176.013108 -284.245379) (xy 175.980473 -284.208542) (xy 175.95417 -284.166946) (xy 175.934879 -284.12167)
			(xy 175.923102 -284.073886) (xy 175.919142 -284.024832) (xy 174.630334 -284.024832) (xy 174.629839 -284.049439)
			(xy 174.621944 -284.098016) (xy 174.60636 -284.144697) (xy 174.583489 -284.188274) (xy 174.553924 -284.227618)
			(xy 174.518431 -284.26171) (xy 174.477928 -284.289666) (xy 174.433466 -284.310764) (xy 174.386195 -284.324456)
			(xy 174.33734 -284.330388) (xy 174.288165 -284.328407) (xy 174.239946 -284.318563) (xy 174.19393 -284.301111)
			(xy 174.151309 -284.276504) (xy 174.113188 -284.245379) (xy 174.080553 -284.208542) (xy 174.05425 -284.166946)
			(xy 174.034959 -284.12167) (xy 174.023182 -284.073886) (xy 174.019222 -284.024832) (xy 173.680374 -284.024832)
			(xy 173.679879 -284.049439) (xy 173.671984 -284.098016) (xy 173.6564 -284.144697) (xy 173.633529 -284.188274)
			(xy 173.603964 -284.227618) (xy 173.568471 -284.26171) (xy 173.527968 -284.289666) (xy 173.483506 -284.310764)
			(xy 173.436235 -284.324456) (xy 173.38738 -284.330388) (xy 173.338205 -284.328407) (xy 173.289986 -284.318563)
			(xy 173.24397 -284.301111) (xy 173.201349 -284.276504) (xy 173.163228 -284.245379) (xy 173.130593 -284.208542)
			(xy 173.10429 -284.166946) (xy 173.084999 -284.12167) (xy 173.073222 -284.073886) (xy 173.069262 -284.024832)
			(xy 172.73016 -284.024832) (xy 172.729665 -284.049439) (xy 172.72177 -284.098016) (xy 172.706186 -284.144697)
			(xy 172.683315 -284.188274) (xy 172.65375 -284.227618) (xy 172.618257 -284.26171) (xy 172.577754 -284.289666)
			(xy 172.533292 -284.310764) (xy 172.486021 -284.324456) (xy 172.437166 -284.330388) (xy 172.387991 -284.328407)
			(xy 172.339772 -284.318563) (xy 172.293756 -284.301111) (xy 172.251135 -284.276504) (xy 172.213014 -284.245379)
			(xy 172.180379 -284.208542) (xy 172.154076 -284.166946) (xy 172.134785 -284.12167) (xy 172.123008 -284.073886)
			(xy 172.119048 -284.024832) (xy 171.7802 -284.024832) (xy 171.779705 -284.049439) (xy 171.77181 -284.098016)
			(xy 171.756226 -284.144697) (xy 171.733355 -284.188274) (xy 171.70379 -284.227618) (xy 171.668297 -284.26171)
			(xy 171.627794 -284.289666) (xy 171.583332 -284.310764) (xy 171.536061 -284.324456) (xy 171.487206 -284.330388)
			(xy 171.438031 -284.328407) (xy 171.389812 -284.318563) (xy 171.343796 -284.301111) (xy 171.301175 -284.276504)
			(xy 171.263054 -284.245379) (xy 171.230419 -284.208542) (xy 171.204116 -284.166946) (xy 171.184825 -284.12167)
			(xy 171.173048 -284.073886) (xy 171.169088 -284.024832) (xy 170.83024 -284.024832) (xy 170.829745 -284.049439)
			(xy 170.82185 -284.098016) (xy 170.806266 -284.144697) (xy 170.783395 -284.188274) (xy 170.75383 -284.227618)
			(xy 170.718337 -284.26171) (xy 170.677834 -284.289666) (xy 170.633372 -284.310764) (xy 170.586101 -284.324456)
			(xy 170.537246 -284.330388) (xy 170.488071 -284.328407) (xy 170.439852 -284.318563) (xy 170.393836 -284.301111)
			(xy 170.351215 -284.276504) (xy 170.313094 -284.245379) (xy 170.280459 -284.208542) (xy 170.254156 -284.166946)
			(xy 170.234865 -284.12167) (xy 170.223088 -284.073886) (xy 170.219128 -284.024832) (xy 169.88028 -284.024832)
			(xy 169.879785 -284.049439) (xy 169.87189 -284.098016) (xy 169.856306 -284.144697) (xy 169.833435 -284.188274)
			(xy 169.80387 -284.227618) (xy 169.768377 -284.26171) (xy 169.727874 -284.289666) (xy 169.683412 -284.310764)
			(xy 169.636141 -284.324456) (xy 169.587286 -284.330388) (xy 169.538111 -284.328407) (xy 169.489892 -284.318563)
			(xy 169.443876 -284.301111) (xy 169.401255 -284.276504) (xy 169.363134 -284.245379) (xy 169.330499 -284.208542)
			(xy 169.304196 -284.166946) (xy 169.284905 -284.12167) (xy 169.273128 -284.073886) (xy 169.269168 -284.024832)
			(xy 168.93032 -284.024832) (xy 168.929825 -284.049439) (xy 168.92193 -284.098016) (xy 168.906346 -284.144697)
			(xy 168.883475 -284.188274) (xy 168.85391 -284.227618) (xy 168.818417 -284.26171) (xy 168.777914 -284.289666)
			(xy 168.733452 -284.310764) (xy 168.686181 -284.324456) (xy 168.637326 -284.330388) (xy 168.588151 -284.328407)
			(xy 168.539932 -284.318563) (xy 168.493916 -284.301111) (xy 168.451295 -284.276504) (xy 168.413174 -284.245379)
			(xy 168.380539 -284.208542) (xy 168.354236 -284.166946) (xy 168.334945 -284.12167) (xy 168.323168 -284.073886)
			(xy 168.319208 -284.024832) (xy 167.98036 -284.024832) (xy 167.979865 -284.049439) (xy 167.97197 -284.098016)
			(xy 167.956386 -284.144697) (xy 167.933515 -284.188274) (xy 167.90395 -284.227618) (xy 167.868457 -284.26171)
			(xy 167.827954 -284.289666) (xy 167.783492 -284.310764) (xy 167.736221 -284.324456) (xy 167.687366 -284.330388)
			(xy 167.638191 -284.328407) (xy 167.589972 -284.318563) (xy 167.543956 -284.301111) (xy 167.501335 -284.276504)
			(xy 167.463214 -284.245379) (xy 167.430579 -284.208542) (xy 167.404276 -284.166946) (xy 167.384985 -284.12167)
			(xy 167.373208 -284.073886) (xy 167.369248 -284.024832) (xy 167.0304 -284.024832) (xy 167.029905 -284.049439)
			(xy 167.02201 -284.098016) (xy 167.006426 -284.144697) (xy 166.983555 -284.188274) (xy 166.95399 -284.227618)
			(xy 166.918497 -284.26171) (xy 166.877994 -284.289666) (xy 166.833532 -284.310764) (xy 166.786261 -284.324456)
			(xy 166.737406 -284.330388) (xy 166.688231 -284.328407) (xy 166.640012 -284.318563) (xy 166.593996 -284.301111)
			(xy 166.551375 -284.276504) (xy 166.513254 -284.245379) (xy 166.480619 -284.208542) (xy 166.454316 -284.166946)
			(xy 166.435025 -284.12167) (xy 166.423248 -284.073886) (xy 166.419288 -284.024832) (xy 166.080186 -284.024832)
			(xy 166.079691 -284.049439) (xy 166.071796 -284.098016) (xy 166.056212 -284.144697) (xy 166.033341 -284.188274)
			(xy 166.003776 -284.227618) (xy 165.968283 -284.26171) (xy 165.92778 -284.289666) (xy 165.883318 -284.310764)
			(xy 165.836047 -284.324456) (xy 165.787192 -284.330388) (xy 165.738017 -284.328407) (xy 165.689798 -284.318563)
			(xy 165.643782 -284.301111) (xy 165.601161 -284.276504) (xy 165.56304 -284.245379) (xy 165.530405 -284.208542)
			(xy 165.504102 -284.166946) (xy 165.484811 -284.12167) (xy 165.473034 -284.073886) (xy 165.469074 -284.024832)
			(xy 165.303708 -284.024832) (xy 165.303708 -284.499812) (xy 189.69407 -284.499812) (xy 189.69803 -284.450758)
			(xy 189.709807 -284.402974) (xy 189.729098 -284.357698) (xy 189.755401 -284.316102) (xy 189.788036 -284.279265)
			(xy 189.826157 -284.24814) (xy 189.868778 -284.223533) (xy 189.914794 -284.206081) (xy 189.963013 -284.196237)
			(xy 190.012188 -284.194256) (xy 190.061043 -284.200188) (xy 190.108314 -284.21388) (xy 190.152776 -284.234978)
			(xy 190.193279 -284.262934) (xy 190.228772 -284.297026) (xy 190.258337 -284.33637) (xy 190.281208 -284.379947)
			(xy 190.296792 -284.426628) (xy 190.304687 -284.475205) (xy 190.305182 -284.499812) (xy 190.64403 -284.499812)
			(xy 190.64799 -284.450758) (xy 190.659767 -284.402974) (xy 190.679058 -284.357698) (xy 190.705361 -284.316102)
			(xy 190.737996 -284.279265) (xy 190.776117 -284.24814) (xy 190.818738 -284.223533) (xy 190.864754 -284.206081)
			(xy 190.912973 -284.196237) (xy 190.962148 -284.194256) (xy 191.011003 -284.200188) (xy 191.058274 -284.21388)
			(xy 191.102736 -284.234978) (xy 191.143239 -284.262934) (xy 191.178732 -284.297026) (xy 191.208297 -284.33637)
			(xy 191.231168 -284.379947) (xy 191.246752 -284.426628) (xy 191.254647 -284.475205) (xy 191.255142 -284.499812)
			(xy 191.594244 -284.499812) (xy 191.598204 -284.450758) (xy 191.609981 -284.402974) (xy 191.629272 -284.357698)
			(xy 191.655575 -284.316102) (xy 191.68821 -284.279265) (xy 191.726331 -284.24814) (xy 191.768952 -284.223533)
			(xy 191.814968 -284.206081) (xy 191.863187 -284.196237) (xy 191.912362 -284.194256) (xy 191.961217 -284.200188)
			(xy 192.008488 -284.21388) (xy 192.05295 -284.234978) (xy 192.093453 -284.262934) (xy 192.128946 -284.297026)
			(xy 192.158511 -284.33637) (xy 192.181382 -284.379947) (xy 192.196966 -284.426628) (xy 192.204861 -284.475205)
			(xy 192.205356 -284.499812) (xy 192.204861 -284.524419) (xy 192.204682 -284.52552) (xy 192.52336 -284.52552)
			(xy 192.52336 -284.474104) (xy 192.531403 -284.423322) (xy 192.547291 -284.374423) (xy 192.570634 -284.328611)
			(xy 192.600855 -284.287015) (xy 192.637211 -284.250659) (xy 192.678807 -284.220438) (xy 192.724619 -284.197095)
			(xy 192.773518 -284.181207) (xy 192.8243 -284.173164) (xy 192.875716 -284.173164) (xy 192.926498 -284.181207)
			(xy 192.975397 -284.197095) (xy 193.021209 -284.220438) (xy 193.062805 -284.250659) (xy 193.099161 -284.287015)
			(xy 193.129382 -284.328611) (xy 193.152725 -284.374423) (xy 193.168613 -284.423322) (xy 193.176656 -284.474104)
			(xy 193.17716 -284.499812) (xy 193.176656 -284.52552) (xy 193.47332 -284.52552) (xy 193.47332 -284.474104)
			(xy 193.481363 -284.423322) (xy 193.497251 -284.374423) (xy 193.520594 -284.328611) (xy 193.550815 -284.287015)
			(xy 193.587171 -284.250659) (xy 193.628767 -284.220438) (xy 193.674579 -284.197095) (xy 193.723478 -284.181207)
			(xy 193.77426 -284.173164) (xy 193.825676 -284.173164) (xy 193.876458 -284.181207) (xy 193.925357 -284.197095)
			(xy 193.971169 -284.220438) (xy 194.012765 -284.250659) (xy 194.049121 -284.287015) (xy 194.079342 -284.328611)
			(xy 194.102685 -284.374423) (xy 194.118573 -284.423322) (xy 194.126616 -284.474104) (xy 194.12712 -284.499812)
			(xy 194.444124 -284.499812) (xy 194.448084 -284.450758) (xy 194.459861 -284.402974) (xy 194.479152 -284.357698)
			(xy 194.505455 -284.316102) (xy 194.53809 -284.279265) (xy 194.576211 -284.24814) (xy 194.618832 -284.223533)
			(xy 194.664848 -284.206081) (xy 194.713067 -284.196237) (xy 194.762242 -284.194256) (xy 194.811097 -284.200188)
			(xy 194.858368 -284.21388) (xy 194.90283 -284.234978) (xy 194.943333 -284.262934) (xy 194.978826 -284.297026)
			(xy 195.008391 -284.33637) (xy 195.031262 -284.379947) (xy 195.046846 -284.426628) (xy 195.054741 -284.475205)
			(xy 195.055236 -284.499812) (xy 195.054741 -284.524419) (xy 195.054562 -284.52552) (xy 195.37324 -284.52552)
			(xy 195.37324 -284.474104) (xy 195.381283 -284.423322) (xy 195.397171 -284.374423) (xy 195.420514 -284.328611)
			(xy 195.450735 -284.287015) (xy 195.487091 -284.250659) (xy 195.528687 -284.220438) (xy 195.574499 -284.197095)
			(xy 195.623398 -284.181207) (xy 195.67418 -284.173164) (xy 195.725596 -284.173164) (xy 195.776378 -284.181207)
			(xy 195.825277 -284.197095) (xy 195.871089 -284.220438) (xy 195.912685 -284.250659) (xy 195.949041 -284.287015)
			(xy 195.979262 -284.328611) (xy 196.002605 -284.374423) (xy 196.018493 -284.423322) (xy 196.026536 -284.474104)
			(xy 196.02704 -284.499812) (xy 196.026536 -284.52552) (xy 196.3232 -284.52552) (xy 196.3232 -284.474104)
			(xy 196.331243 -284.423322) (xy 196.347131 -284.374423) (xy 196.370474 -284.328611) (xy 196.400695 -284.287015)
			(xy 196.437051 -284.250659) (xy 196.478647 -284.220438) (xy 196.524459 -284.197095) (xy 196.573358 -284.181207)
			(xy 196.62414 -284.173164) (xy 196.675556 -284.173164) (xy 196.726338 -284.181207) (xy 196.775237 -284.197095)
			(xy 196.821049 -284.220438) (xy 196.862645 -284.250659) (xy 196.899001 -284.287015) (xy 196.929222 -284.328611)
			(xy 196.952565 -284.374423) (xy 196.968453 -284.423322) (xy 196.976496 -284.474104) (xy 196.977 -284.499812)
			(xy 197.294258 -284.499812) (xy 197.298218 -284.450758) (xy 197.309995 -284.402974) (xy 197.329286 -284.357698)
			(xy 197.355589 -284.316102) (xy 197.388224 -284.279265) (xy 197.426345 -284.24814) (xy 197.468966 -284.223533)
			(xy 197.514982 -284.206081) (xy 197.563201 -284.196237) (xy 197.612376 -284.194256) (xy 197.661231 -284.200188)
			(xy 197.708502 -284.21388) (xy 197.752964 -284.234978) (xy 197.793467 -284.262934) (xy 197.82896 -284.297026)
			(xy 197.858525 -284.33637) (xy 197.881396 -284.379947) (xy 197.89698 -284.426628) (xy 197.904875 -284.475205)
			(xy 197.90537 -284.499812) (xy 198.244218 -284.499812) (xy 198.248178 -284.450758) (xy 198.259955 -284.402974)
			(xy 198.279246 -284.357698) (xy 198.305549 -284.316102) (xy 198.338184 -284.279265) (xy 198.376305 -284.24814)
			(xy 198.418926 -284.223533) (xy 198.464942 -284.206081) (xy 198.513161 -284.196237) (xy 198.562336 -284.194256)
			(xy 198.611191 -284.200188) (xy 198.658462 -284.21388) (xy 198.702924 -284.234978) (xy 198.743427 -284.262934)
			(xy 198.77892 -284.297026) (xy 198.808485 -284.33637) (xy 198.831356 -284.379947) (xy 198.84694 -284.426628)
			(xy 198.854835 -284.475205) (xy 198.85533 -284.499812) (xy 198.854835 -284.524419) (xy 198.84694 -284.572996)
			(xy 198.831356 -284.619677) (xy 198.809776 -284.660794) (xy 210.009235 -284.660794) (xy 210.009235 -284.603498)
			(xy 210.017389 -284.546784) (xy 210.033532 -284.491809) (xy 210.057333 -284.43969) (xy 210.08831 -284.391489)
			(xy 210.125831 -284.348187) (xy 210.169133 -284.310666) (xy 210.217334 -284.279689) (xy 210.269453 -284.255888)
			(xy 210.324428 -284.239745) (xy 210.381142 -284.231591) (xy 210.438438 -284.231591) (xy 210.495152 -284.239745)
			(xy 210.550127 -284.255888) (xy 210.602246 -284.279689) (xy 210.650447 -284.310666) (xy 210.693749 -284.348187)
			(xy 210.73127 -284.391489) (xy 210.762247 -284.43969) (xy 210.786048 -284.491809) (xy 210.802191 -284.546784)
			(xy 210.810345 -284.603498) (xy 210.810856 -284.632146) (xy 210.810345 -284.660794) (xy 210.809202 -284.668747)
			(xy 216.926722 -284.668747) (xy 216.926722 -284.614253) (xy 216.934477 -284.560315) (xy 216.949829 -284.508029)
			(xy 216.972465 -284.458459) (xy 217.001925 -284.412616) (xy 217.037609 -284.371431) (xy 217.07879 -284.335744)
			(xy 217.124631 -284.30628) (xy 217.174199 -284.28364) (xy 217.226483 -284.268284) (xy 217.280421 -284.260524)
			(xy 217.307668 -284.260036) (xy 217.336408 -284.260535) (xy 217.393235 -284.269167) (xy 217.448126 -284.286223)
			(xy 217.499837 -284.31132) (xy 217.547199 -284.343888) (xy 217.568526 -284.36316) (xy 217.575638 -284.369764)
			(xy 217.593164 -284.376876) (xy 217.682572 -284.376876) (xy 217.700098 -284.369764) (xy 217.70721 -284.36316)
			(xy 217.728553 -284.343908) (xy 217.775911 -284.311338) (xy 217.827618 -284.286242) (xy 217.882505 -284.269187)
			(xy 217.93933 -284.260559) (xy 217.968068 -284.260036) (xy 217.99819 -284.260631) (xy 218.057685 -284.270107)
			(xy 218.114953 -284.288812) (xy 218.16857 -284.316282) (xy 218.217206 -284.351836) (xy 218.238832 -284.372812)
			(xy 218.245944 -284.380178) (xy 218.26474 -284.387798) (xy 218.357196 -284.387798) (xy 218.375992 -284.380178)
			(xy 218.383104 -284.372812) (xy 218.404706 -284.351807) (xy 218.453341 -284.316241) (xy 218.506963 -284.288766)
			(xy 218.564238 -284.270063) (xy 218.623742 -284.2606) (xy 218.653868 -284.260036) (xy 218.681238 -284.260512)
			(xy 218.735417 -284.268326) (xy 218.78792 -284.283812) (xy 218.837667 -284.306652) (xy 218.883634 -284.336375)
			(xy 218.904566 -284.354016) (xy 218.911678 -284.360112) (xy 218.928696 -284.366462) (xy 219.01404 -284.366462)
			(xy 219.031058 -284.360112) (xy 219.03817 -284.354016) (xy 219.059105 -284.33638) (xy 219.105076 -284.306667)
			(xy 219.154823 -284.28383) (xy 219.207324 -284.268339) (xy 219.261499 -284.26051) (xy 219.288868 -284.260036)
			(xy 219.316126 -284.260409) (xy 219.370086 -284.268163) (xy 219.422394 -284.283518) (xy 219.471984 -284.306161)
			(xy 219.517846 -284.335632) (xy 219.559048 -284.37133) (xy 219.594749 -284.412528) (xy 219.624223 -284.458388)
			(xy 219.646871 -284.507976) (xy 219.66223 -284.560283) (xy 219.669989 -284.614243) (xy 219.669989 -284.668746)
			(xy 220.945522 -284.668746) (xy 220.945522 -284.614254) (xy 220.953276 -284.560316) (xy 220.968628 -284.508031)
			(xy 220.991263 -284.458463) (xy 221.020722 -284.41262) (xy 221.056404 -284.371435) (xy 221.097584 -284.335748)
			(xy 221.143424 -284.306284) (xy 221.19299 -284.283643) (xy 221.245273 -284.268286) (xy 221.29921 -284.260525)
			(xy 221.326456 -284.260036) (xy 221.355195 -284.260543) (xy 221.412023 -284.269172) (xy 221.466913 -284.286227)
			(xy 221.518624 -284.311322) (xy 221.565987 -284.343889) (xy 221.587314 -284.36316) (xy 221.594426 -284.369764)
			(xy 221.611952 -284.376876) (xy 221.70136 -284.376876) (xy 221.718886 -284.369764) (xy 221.725998 -284.36316)
			(xy 221.747325 -284.34389) (xy 221.794688 -284.311325) (xy 221.846399 -284.286234) (xy 221.90129 -284.269184)
			(xy 221.958117 -284.260562) (xy 222.015595 -284.260562) (xy 222.072422 -284.269184) (xy 222.127313 -284.286234)
			(xy 222.179024 -284.311325) (xy 222.226387 -284.34389) (xy 222.247714 -284.36316) (xy 222.254826 -284.369764)
			(xy 222.272352 -284.376876) (xy 222.36176 -284.376876) (xy 222.379286 -284.369764) (xy 222.386398 -284.36316)
			(xy 222.407705 -284.343866) (xy 222.455072 -284.311302) (xy 222.506789 -284.286214) (xy 222.561684 -284.269169)
			(xy 222.618516 -284.260553) (xy 222.647256 -284.260036) (xy 222.677378 -284.260638) (xy 222.736873 -284.270112)
			(xy 222.79414 -284.288816) (xy 222.847758 -284.316285) (xy 222.896394 -284.351836) (xy 222.91802 -284.372812)
			(xy 222.925132 -284.380178) (xy 222.943928 -284.387798) (xy 223.036384 -284.387798) (xy 223.05518 -284.380178)
			(xy 223.062292 -284.372812) (xy 223.083899 -284.351813) (xy 223.132533 -284.316246) (xy 223.186153 -284.28877)
			(xy 223.243428 -284.270066) (xy 223.30293 -284.260601) (xy 223.333056 -284.260036) (xy 223.360314 -284.260408)
			(xy 223.414276 -284.268161) (xy 223.466585 -284.283515) (xy 223.516177 -284.306157) (xy 223.562041 -284.335628)
			(xy 223.603243 -284.371325) (xy 223.638946 -284.412524) (xy 223.668422 -284.458385) (xy 223.69107 -284.507973)
			(xy 223.70643 -284.560281) (xy 223.714189 -284.614242) (xy 223.714189 -284.668758) (xy 223.70643 -284.722719)
			(xy 223.69107 -284.775027) (xy 223.668422 -284.824615) (xy 223.638946 -284.870476) (xy 223.603243 -284.911675)
			(xy 223.562041 -284.947372) (xy 223.516177 -284.976843) (xy 223.466585 -284.999485) (xy 223.414276 -285.014839)
			(xy 223.360314 -285.022592) (xy 223.333056 -285.023052) (xy 223.302934 -285.022445) (xy 223.243439 -285.012973)
			(xy 223.186172 -284.99427) (xy 223.132554 -284.966802) (xy 223.083918 -284.931251) (xy 223.062292 -284.910276)
			(xy 223.05518 -284.90291) (xy 223.036384 -284.89529) (xy 222.943928 -284.89529) (xy 222.925132 -284.90291)
			(xy 222.91802 -284.910276) (xy 222.896406 -284.931268) (xy 222.847774 -284.966835) (xy 222.794155 -284.994314)
			(xy 222.736883 -285.013019) (xy 222.677381 -285.022486) (xy 222.647256 -285.023052) (xy 222.618517 -285.022541)
			(xy 222.561689 -285.013913) (xy 222.506799 -284.996859) (xy 222.455088 -284.971765) (xy 222.407725 -284.939199)
			(xy 222.386398 -284.919928) (xy 222.379286 -284.913324) (xy 222.36176 -284.906212) (xy 222.272352 -284.906212)
			(xy 222.254826 -284.913324) (xy 222.247714 -284.919928) (xy 222.226387 -284.939198) (xy 222.179024 -284.971763)
			(xy 222.127313 -284.996854) (xy 222.072422 -285.013904) (xy 222.015595 -285.022526) (xy 221.958117 -285.022526)
			(xy 221.90129 -285.013904) (xy 221.846399 -284.996854) (xy 221.794688 -284.971763) (xy 221.747325 -284.939198)
			(xy 221.725998 -284.919928) (xy 221.718886 -284.913324) (xy 221.70136 -284.906212) (xy 221.611952 -284.906212)
			(xy 221.594426 -284.913324) (xy 221.587314 -284.919928) (xy 221.566 -284.939214) (xy 221.518635 -284.971779)
			(xy 221.46692 -284.99687) (xy 221.412026 -285.013916) (xy 221.355196 -285.022534) (xy 221.326456 -285.023052)
			(xy 221.29921 -285.022475) (xy 221.245273 -285.014714) (xy 221.19299 -284.999357) (xy 221.143424 -284.976716)
			(xy 221.097584 -284.947252) (xy 221.056404 -284.911565) (xy 221.020722 -284.87038) (xy 220.991263 -284.824537)
			(xy 220.968628 -284.774969) (xy 220.953276 -284.722684) (xy 220.945522 -284.668746) (xy 219.669989 -284.668746)
			(xy 219.669989 -284.668757) (xy 219.66223 -284.722717) (xy 219.646871 -284.775024) (xy 219.624223 -284.824612)
			(xy 219.594749 -284.870472) (xy 219.559048 -284.91167) (xy 219.517846 -284.947368) (xy 219.471984 -284.976839)
			(xy 219.422394 -284.999482) (xy 219.370086 -285.014837) (xy 219.316126 -285.022591) (xy 219.288868 -285.023052)
			(xy 219.261497 -285.022616) (xy 219.207316 -285.014793) (xy 219.154812 -284.999297) (xy 219.105065 -284.976449)
			(xy 219.0591 -284.946717) (xy 219.03817 -284.929072) (xy 219.031058 -284.922976) (xy 219.01404 -284.916626)
			(xy 218.928696 -284.916626) (xy 218.911678 -284.922976) (xy 218.904566 -284.929072) (xy 218.883616 -284.946689)
			(xy 218.837649 -284.976405) (xy 218.787906 -284.999246) (xy 218.735409 -285.014742) (xy 218.681236 -285.022575)
			(xy 218.653868 -285.023052) (xy 218.623744 -285.022501) (xy 218.564247 -285.013015) (xy 218.506978 -284.994299)
			(xy 218.453362 -284.966819) (xy 218.404728 -284.931257) (xy 218.383104 -284.910276) (xy 218.375992 -284.90291)
			(xy 218.357196 -284.89529) (xy 218.26474 -284.89529) (xy 218.245944 -284.90291) (xy 218.238832 -284.910276)
			(xy 218.217212 -284.931262) (xy 218.168583 -284.96683) (xy 218.114965 -284.99431) (xy 218.057693 -285.013017)
			(xy 217.998193 -285.022485) (xy 217.968068 -285.023052) (xy 217.939329 -285.022534) (xy 217.882502 -285.013908)
			(xy 217.827612 -284.996856) (xy 217.7759 -284.971763) (xy 217.728537 -284.939198) (xy 217.70721 -284.919928)
			(xy 217.700098 -284.913324) (xy 217.682572 -284.906212) (xy 217.593164 -284.906212) (xy 217.575638 -284.913324)
			(xy 217.568526 -284.919928) (xy 217.547207 -284.939208) (xy 217.499843 -284.971774) (xy 217.44813 -284.996866)
			(xy 217.393237 -285.013914) (xy 217.336408 -285.022533) (xy 217.307668 -285.023052) (xy 217.280421 -285.022476)
			(xy 217.226483 -285.014716) (xy 217.174199 -284.99936) (xy 217.124631 -284.97672) (xy 217.07879 -284.947256)
			(xy 217.037609 -284.911569) (xy 217.001925 -284.870384) (xy 216.972465 -284.824541) (xy 216.949829 -284.774971)
			(xy 216.934477 -284.722685) (xy 216.926722 -284.668747) (xy 210.809202 -284.668747) (xy 210.802191 -284.717508)
			(xy 210.786048 -284.772483) (xy 210.762247 -284.824602) (xy 210.73127 -284.872803) (xy 210.693749 -284.916105)
			(xy 210.650447 -284.953626) (xy 210.602246 -284.984603) (xy 210.550127 -285.008404) (xy 210.495152 -285.024547)
			(xy 210.438438 -285.032701) (xy 210.381142 -285.032701) (xy 210.324428 -285.024547) (xy 210.269453 -285.008404)
			(xy 210.217334 -284.984603) (xy 210.169133 -284.953626) (xy 210.125831 -284.916105) (xy 210.08831 -284.872803)
			(xy 210.057333 -284.824602) (xy 210.033532 -284.772483) (xy 210.017389 -284.717508) (xy 210.009235 -284.660794)
			(xy 198.809776 -284.660794) (xy 198.808485 -284.663254) (xy 198.77892 -284.702598) (xy 198.743427 -284.73669)
			(xy 198.702924 -284.764646) (xy 198.658462 -284.785744) (xy 198.611191 -284.799436) (xy 198.562336 -284.805368)
			(xy 198.513161 -284.803387) (xy 198.464942 -284.793543) (xy 198.418926 -284.776091) (xy 198.376305 -284.751484)
			(xy 198.338184 -284.720359) (xy 198.305549 -284.683522) (xy 198.279246 -284.641926) (xy 198.259955 -284.59665)
			(xy 198.248178 -284.548866) (xy 198.244218 -284.499812) (xy 197.90537 -284.499812) (xy 197.904875 -284.524419)
			(xy 197.89698 -284.572996) (xy 197.881396 -284.619677) (xy 197.858525 -284.663254) (xy 197.82896 -284.702598)
			(xy 197.793467 -284.73669) (xy 197.752964 -284.764646) (xy 197.708502 -284.785744) (xy 197.661231 -284.799436)
			(xy 197.612376 -284.805368) (xy 197.563201 -284.803387) (xy 197.514982 -284.793543) (xy 197.468966 -284.776091)
			(xy 197.426345 -284.751484) (xy 197.388224 -284.720359) (xy 197.355589 -284.683522) (xy 197.329286 -284.641926)
			(xy 197.309995 -284.59665) (xy 197.298218 -284.548866) (xy 197.294258 -284.499812) (xy 196.977 -284.499812)
			(xy 196.976496 -284.52552) (xy 196.968453 -284.576302) (xy 196.952565 -284.625201) (xy 196.929222 -284.671013)
			(xy 196.899001 -284.712609) (xy 196.862645 -284.748965) (xy 196.821049 -284.779186) (xy 196.775237 -284.802529)
			(xy 196.726338 -284.818417) (xy 196.675556 -284.82646) (xy 196.62414 -284.82646) (xy 196.573358 -284.818417)
			(xy 196.524459 -284.802529) (xy 196.478647 -284.779186) (xy 196.437051 -284.748965) (xy 196.400695 -284.712609)
			(xy 196.370474 -284.671013) (xy 196.347131 -284.625201) (xy 196.331243 -284.576302) (xy 196.3232 -284.52552)
			(xy 196.026536 -284.52552) (xy 196.018493 -284.576302) (xy 196.002605 -284.625201) (xy 195.979262 -284.671013)
			(xy 195.949041 -284.712609) (xy 195.912685 -284.748965) (xy 195.871089 -284.779186) (xy 195.825277 -284.802529)
			(xy 195.776378 -284.818417) (xy 195.725596 -284.82646) (xy 195.67418 -284.82646) (xy 195.623398 -284.818417)
			(xy 195.574499 -284.802529) (xy 195.528687 -284.779186) (xy 195.487091 -284.748965) (xy 195.450735 -284.712609)
			(xy 195.420514 -284.671013) (xy 195.397171 -284.625201) (xy 195.381283 -284.576302) (xy 195.37324 -284.52552)
			(xy 195.054562 -284.52552) (xy 195.046846 -284.572996) (xy 195.031262 -284.619677) (xy 195.008391 -284.663254)
			(xy 194.978826 -284.702598) (xy 194.943333 -284.73669) (xy 194.90283 -284.764646) (xy 194.858368 -284.785744)
			(xy 194.811097 -284.799436) (xy 194.762242 -284.805368) (xy 194.713067 -284.803387) (xy 194.664848 -284.793543)
			(xy 194.618832 -284.776091) (xy 194.576211 -284.751484) (xy 194.53809 -284.720359) (xy 194.505455 -284.683522)
			(xy 194.479152 -284.641926) (xy 194.459861 -284.59665) (xy 194.448084 -284.548866) (xy 194.444124 -284.499812)
			(xy 194.12712 -284.499812) (xy 194.126616 -284.52552) (xy 194.118573 -284.576302) (xy 194.102685 -284.625201)
			(xy 194.079342 -284.671013) (xy 194.049121 -284.712609) (xy 194.012765 -284.748965) (xy 193.971169 -284.779186)
			(xy 193.925357 -284.802529) (xy 193.876458 -284.818417) (xy 193.825676 -284.82646) (xy 193.77426 -284.82646)
			(xy 193.723478 -284.818417) (xy 193.674579 -284.802529) (xy 193.628767 -284.779186) (xy 193.587171 -284.748965)
			(xy 193.550815 -284.712609) (xy 193.520594 -284.671013) (xy 193.497251 -284.625201) (xy 193.481363 -284.576302)
			(xy 193.47332 -284.52552) (xy 193.176656 -284.52552) (xy 193.168613 -284.576302) (xy 193.152725 -284.625201)
			(xy 193.129382 -284.671013) (xy 193.099161 -284.712609) (xy 193.062805 -284.748965) (xy 193.021209 -284.779186)
			(xy 192.975397 -284.802529) (xy 192.926498 -284.818417) (xy 192.875716 -284.82646) (xy 192.8243 -284.82646)
			(xy 192.773518 -284.818417) (xy 192.724619 -284.802529) (xy 192.678807 -284.779186) (xy 192.637211 -284.748965)
			(xy 192.600855 -284.712609) (xy 192.570634 -284.671013) (xy 192.547291 -284.625201) (xy 192.531403 -284.576302)
			(xy 192.52336 -284.52552) (xy 192.204682 -284.52552) (xy 192.196966 -284.572996) (xy 192.181382 -284.619677)
			(xy 192.158511 -284.663254) (xy 192.128946 -284.702598) (xy 192.093453 -284.73669) (xy 192.05295 -284.764646)
			(xy 192.008488 -284.785744) (xy 191.961217 -284.799436) (xy 191.912362 -284.805368) (xy 191.863187 -284.803387)
			(xy 191.814968 -284.793543) (xy 191.768952 -284.776091) (xy 191.726331 -284.751484) (xy 191.68821 -284.720359)
			(xy 191.655575 -284.683522) (xy 191.629272 -284.641926) (xy 191.609981 -284.59665) (xy 191.598204 -284.548866)
			(xy 191.594244 -284.499812) (xy 191.255142 -284.499812) (xy 191.254647 -284.524419) (xy 191.246752 -284.572996)
			(xy 191.231168 -284.619677) (xy 191.208297 -284.663254) (xy 191.178732 -284.702598) (xy 191.143239 -284.73669)
			(xy 191.102736 -284.764646) (xy 191.058274 -284.785744) (xy 191.011003 -284.799436) (xy 190.962148 -284.805368)
			(xy 190.912973 -284.803387) (xy 190.864754 -284.793543) (xy 190.818738 -284.776091) (xy 190.776117 -284.751484)
			(xy 190.737996 -284.720359) (xy 190.705361 -284.683522) (xy 190.679058 -284.641926) (xy 190.659767 -284.59665)
			(xy 190.64799 -284.548866) (xy 190.64403 -284.499812) (xy 190.305182 -284.499812) (xy 190.304687 -284.524419)
			(xy 190.296792 -284.572996) (xy 190.281208 -284.619677) (xy 190.258337 -284.663254) (xy 190.228772 -284.702598)
			(xy 190.193279 -284.73669) (xy 190.152776 -284.764646) (xy 190.108314 -284.785744) (xy 190.061043 -284.799436)
			(xy 190.012188 -284.805368) (xy 189.963013 -284.803387) (xy 189.914794 -284.793543) (xy 189.868778 -284.776091)
			(xy 189.826157 -284.751484) (xy 189.788036 -284.720359) (xy 189.755401 -284.683522) (xy 189.729098 -284.641926)
			(xy 189.709807 -284.59665) (xy 189.69803 -284.548866) (xy 189.69407 -284.499812) (xy 165.303708 -284.499812)
			(xy 165.303708 -284.974792) (xy 165.469074 -284.974792) (xy 165.473034 -284.925738) (xy 165.484811 -284.877954)
			(xy 165.504102 -284.832678) (xy 165.530405 -284.791082) (xy 165.56304 -284.754245) (xy 165.601161 -284.72312)
			(xy 165.643782 -284.698513) (xy 165.689798 -284.681061) (xy 165.738017 -284.671217) (xy 165.787192 -284.669236)
			(xy 165.836047 -284.675168) (xy 165.883318 -284.68886) (xy 165.92778 -284.709958) (xy 165.968283 -284.737914)
			(xy 166.003776 -284.772006) (xy 166.033341 -284.81135) (xy 166.056212 -284.854927) (xy 166.071796 -284.901608)
			(xy 166.079691 -284.950185) (xy 166.080186 -284.974792) (xy 166.419288 -284.974792) (xy 166.423248 -284.925738)
			(xy 166.435025 -284.877954) (xy 166.454316 -284.832678) (xy 166.480619 -284.791082) (xy 166.513254 -284.754245)
			(xy 166.551375 -284.72312) (xy 166.593996 -284.698513) (xy 166.640012 -284.681061) (xy 166.688231 -284.671217)
			(xy 166.737406 -284.669236) (xy 166.786261 -284.675168) (xy 166.833532 -284.68886) (xy 166.877994 -284.709958)
			(xy 166.918497 -284.737914) (xy 166.95399 -284.772006) (xy 166.983555 -284.81135) (xy 167.006426 -284.854927)
			(xy 167.02201 -284.901608) (xy 167.029905 -284.950185) (xy 167.0304 -284.974792) (xy 167.369248 -284.974792)
			(xy 167.373208 -284.925738) (xy 167.384985 -284.877954) (xy 167.404276 -284.832678) (xy 167.430579 -284.791082)
			(xy 167.463214 -284.754245) (xy 167.501335 -284.72312) (xy 167.543956 -284.698513) (xy 167.589972 -284.681061)
			(xy 167.638191 -284.671217) (xy 167.687366 -284.669236) (xy 167.736221 -284.675168) (xy 167.783492 -284.68886)
			(xy 167.827954 -284.709958) (xy 167.868457 -284.737914) (xy 167.90395 -284.772006) (xy 167.933515 -284.81135)
			(xy 167.956386 -284.854927) (xy 167.97197 -284.901608) (xy 167.979865 -284.950185) (xy 167.98036 -284.974792)
			(xy 168.319208 -284.974792) (xy 168.323168 -284.925738) (xy 168.334945 -284.877954) (xy 168.354236 -284.832678)
			(xy 168.380539 -284.791082) (xy 168.413174 -284.754245) (xy 168.451295 -284.72312) (xy 168.493916 -284.698513)
			(xy 168.539932 -284.681061) (xy 168.588151 -284.671217) (xy 168.637326 -284.669236) (xy 168.686181 -284.675168)
			(xy 168.733452 -284.68886) (xy 168.777914 -284.709958) (xy 168.818417 -284.737914) (xy 168.85391 -284.772006)
			(xy 168.883475 -284.81135) (xy 168.906346 -284.854927) (xy 168.92193 -284.901608) (xy 168.929825 -284.950185)
			(xy 168.93032 -284.974792) (xy 169.269168 -284.974792) (xy 169.273128 -284.925738) (xy 169.284905 -284.877954)
			(xy 169.304196 -284.832678) (xy 169.330499 -284.791082) (xy 169.363134 -284.754245) (xy 169.401255 -284.72312)
			(xy 169.443876 -284.698513) (xy 169.489892 -284.681061) (xy 169.538111 -284.671217) (xy 169.587286 -284.669236)
			(xy 169.636141 -284.675168) (xy 169.683412 -284.68886) (xy 169.727874 -284.709958) (xy 169.768377 -284.737914)
			(xy 169.80387 -284.772006) (xy 169.833435 -284.81135) (xy 169.856306 -284.854927) (xy 169.87189 -284.901608)
			(xy 169.879785 -284.950185) (xy 169.88028 -284.974792) (xy 170.219128 -284.974792) (xy 170.223088 -284.925738)
			(xy 170.234865 -284.877954) (xy 170.254156 -284.832678) (xy 170.280459 -284.791082) (xy 170.313094 -284.754245)
			(xy 170.351215 -284.72312) (xy 170.393836 -284.698513) (xy 170.439852 -284.681061) (xy 170.488071 -284.671217)
			(xy 170.537246 -284.669236) (xy 170.586101 -284.675168) (xy 170.633372 -284.68886) (xy 170.677834 -284.709958)
			(xy 170.718337 -284.737914) (xy 170.75383 -284.772006) (xy 170.783395 -284.81135) (xy 170.806266 -284.854927)
			(xy 170.82185 -284.901608) (xy 170.829745 -284.950185) (xy 170.83024 -284.974792) (xy 171.169088 -284.974792)
			(xy 171.173048 -284.925738) (xy 171.184825 -284.877954) (xy 171.204116 -284.832678) (xy 171.230419 -284.791082)
			(xy 171.263054 -284.754245) (xy 171.301175 -284.72312) (xy 171.343796 -284.698513) (xy 171.389812 -284.681061)
			(xy 171.438031 -284.671217) (xy 171.487206 -284.669236) (xy 171.536061 -284.675168) (xy 171.583332 -284.68886)
			(xy 171.627794 -284.709958) (xy 171.668297 -284.737914) (xy 171.70379 -284.772006) (xy 171.733355 -284.81135)
			(xy 171.756226 -284.854927) (xy 171.77181 -284.901608) (xy 171.779705 -284.950185) (xy 171.7802 -284.974792)
			(xy 172.119048 -284.974792) (xy 172.123008 -284.925738) (xy 172.134785 -284.877954) (xy 172.154076 -284.832678)
			(xy 172.180379 -284.791082) (xy 172.213014 -284.754245) (xy 172.251135 -284.72312) (xy 172.293756 -284.698513)
			(xy 172.339772 -284.681061) (xy 172.387991 -284.671217) (xy 172.437166 -284.669236) (xy 172.486021 -284.675168)
			(xy 172.533292 -284.68886) (xy 172.577754 -284.709958) (xy 172.618257 -284.737914) (xy 172.65375 -284.772006)
			(xy 172.683315 -284.81135) (xy 172.706186 -284.854927) (xy 172.72177 -284.901608) (xy 172.729665 -284.950185)
			(xy 172.73016 -284.974792) (xy 173.069262 -284.974792) (xy 173.073222 -284.925738) (xy 173.084999 -284.877954)
			(xy 173.10429 -284.832678) (xy 173.130593 -284.791082) (xy 173.163228 -284.754245) (xy 173.201349 -284.72312)
			(xy 173.24397 -284.698513) (xy 173.289986 -284.681061) (xy 173.338205 -284.671217) (xy 173.38738 -284.669236)
			(xy 173.436235 -284.675168) (xy 173.483506 -284.68886) (xy 173.527968 -284.709958) (xy 173.568471 -284.737914)
			(xy 173.603964 -284.772006) (xy 173.633529 -284.81135) (xy 173.6564 -284.854927) (xy 173.671984 -284.901608)
			(xy 173.679879 -284.950185) (xy 173.680374 -284.974792) (xy 174.019222 -284.974792) (xy 174.023182 -284.925738)
			(xy 174.034959 -284.877954) (xy 174.05425 -284.832678) (xy 174.080553 -284.791082) (xy 174.113188 -284.754245)
			(xy 174.151309 -284.72312) (xy 174.19393 -284.698513) (xy 174.239946 -284.681061) (xy 174.288165 -284.671217)
			(xy 174.33734 -284.669236) (xy 174.386195 -284.675168) (xy 174.433466 -284.68886) (xy 174.477928 -284.709958)
			(xy 174.518431 -284.737914) (xy 174.553924 -284.772006) (xy 174.583489 -284.81135) (xy 174.60636 -284.854927)
			(xy 174.621944 -284.901608) (xy 174.629839 -284.950185) (xy 174.630334 -284.974792) (xy 175.919142 -284.974792)
			(xy 175.923102 -284.925738) (xy 175.934879 -284.877954) (xy 175.95417 -284.832678) (xy 175.980473 -284.791082)
			(xy 176.013108 -284.754245) (xy 176.051229 -284.72312) (xy 176.09385 -284.698513) (xy 176.139866 -284.681061)
			(xy 176.188085 -284.671217) (xy 176.23726 -284.669236) (xy 176.286115 -284.675168) (xy 176.333386 -284.68886)
			(xy 176.377848 -284.709958) (xy 176.418351 -284.737914) (xy 176.453844 -284.772006) (xy 176.483409 -284.81135)
			(xy 176.50628 -284.854927) (xy 176.521864 -284.901608) (xy 176.529759 -284.950185) (xy 176.530254 -284.974792)
			(xy 176.869102 -284.974792) (xy 176.873062 -284.925738) (xy 176.884839 -284.877954) (xy 176.90413 -284.832678)
			(xy 176.930433 -284.791082) (xy 176.963068 -284.754245) (xy 177.001189 -284.72312) (xy 177.04381 -284.698513)
			(xy 177.089826 -284.681061) (xy 177.138045 -284.671217) (xy 177.18722 -284.669236) (xy 177.236075 -284.675168)
			(xy 177.283346 -284.68886) (xy 177.327808 -284.709958) (xy 177.368311 -284.737914) (xy 177.403804 -284.772006)
			(xy 177.433369 -284.81135) (xy 177.45624 -284.854927) (xy 177.471824 -284.901608) (xy 177.479719 -284.950185)
			(xy 177.480214 -284.974792) (xy 177.819062 -284.974792) (xy 177.823022 -284.925738) (xy 177.834799 -284.877954)
			(xy 177.85409 -284.832678) (xy 177.880393 -284.791082) (xy 177.913028 -284.754245) (xy 177.951149 -284.72312)
			(xy 177.99377 -284.698513) (xy 178.039786 -284.681061) (xy 178.088005 -284.671217) (xy 178.13718 -284.669236)
			(xy 178.186035 -284.675168) (xy 178.233306 -284.68886) (xy 178.277768 -284.709958) (xy 178.318271 -284.737914)
			(xy 178.353764 -284.772006) (xy 178.383329 -284.81135) (xy 178.4062 -284.854927) (xy 178.421784 -284.901608)
			(xy 178.429679 -284.950185) (xy 178.430174 -284.974792) (xy 178.769276 -284.974792) (xy 178.773236 -284.925738)
			(xy 178.785013 -284.877954) (xy 178.804304 -284.832678) (xy 178.830607 -284.791082) (xy 178.863242 -284.754245)
			(xy 178.901363 -284.72312) (xy 178.943984 -284.698513) (xy 178.99 -284.681061) (xy 179.038219 -284.671217)
			(xy 179.087394 -284.669236) (xy 179.136249 -284.675168) (xy 179.18352 -284.68886) (xy 179.227982 -284.709958)
			(xy 179.268485 -284.737914) (xy 179.303978 -284.772006) (xy 179.333543 -284.81135) (xy 179.356414 -284.854927)
			(xy 179.371998 -284.901608) (xy 179.379893 -284.950185) (xy 179.380388 -284.974792) (xy 179.719236 -284.974792)
			(xy 179.723196 -284.925738) (xy 179.734973 -284.877954) (xy 179.754264 -284.832678) (xy 179.780567 -284.791082)
			(xy 179.813202 -284.754245) (xy 179.851323 -284.72312) (xy 179.893944 -284.698513) (xy 179.93996 -284.681061)
			(xy 179.988179 -284.671217) (xy 180.037354 -284.669236) (xy 180.086209 -284.675168) (xy 180.13348 -284.68886)
			(xy 180.177942 -284.709958) (xy 180.218445 -284.737914) (xy 180.253938 -284.772006) (xy 180.283503 -284.81135)
			(xy 180.306374 -284.854927) (xy 180.321958 -284.901608) (xy 180.329853 -284.950185) (xy 180.330348 -284.974792)
			(xy 180.669196 -284.974792) (xy 180.673156 -284.925738) (xy 180.684933 -284.877954) (xy 180.704224 -284.832678)
			(xy 180.730527 -284.791082) (xy 180.763162 -284.754245) (xy 180.801283 -284.72312) (xy 180.843904 -284.698513)
			(xy 180.88992 -284.681061) (xy 180.938139 -284.671217) (xy 180.987314 -284.669236) (xy 181.036169 -284.675168)
			(xy 181.08344 -284.68886) (xy 181.127902 -284.709958) (xy 181.168405 -284.737914) (xy 181.203898 -284.772006)
			(xy 181.233463 -284.81135) (xy 181.256334 -284.854927) (xy 181.271918 -284.901608) (xy 181.279813 -284.950185)
			(xy 181.280308 -284.974792) (xy 181.619156 -284.974792) (xy 181.623116 -284.925738) (xy 181.634893 -284.877954)
			(xy 181.654184 -284.832678) (xy 181.680487 -284.791082) (xy 181.713122 -284.754245) (xy 181.751243 -284.72312)
			(xy 181.793864 -284.698513) (xy 181.83988 -284.681061) (xy 181.888099 -284.671217) (xy 181.937274 -284.669236)
			(xy 181.986129 -284.675168) (xy 182.0334 -284.68886) (xy 182.077862 -284.709958) (xy 182.118365 -284.737914)
			(xy 182.153858 -284.772006) (xy 182.183423 -284.81135) (xy 182.206294 -284.854927) (xy 182.221878 -284.901608)
			(xy 182.229773 -284.950185) (xy 182.230268 -284.974792) (xy 182.569116 -284.974792) (xy 182.573076 -284.925738)
			(xy 182.584853 -284.877954) (xy 182.604144 -284.832678) (xy 182.630447 -284.791082) (xy 182.663082 -284.754245)
			(xy 182.701203 -284.72312) (xy 182.743824 -284.698513) (xy 182.78984 -284.681061) (xy 182.838059 -284.671217)
			(xy 182.887234 -284.669236) (xy 182.936089 -284.675168) (xy 182.98336 -284.68886) (xy 183.027822 -284.709958)
			(xy 183.068325 -284.737914) (xy 183.103818 -284.772006) (xy 183.133383 -284.81135) (xy 183.156254 -284.854927)
			(xy 183.171838 -284.901608) (xy 183.179733 -284.950185) (xy 183.180228 -284.974792) (xy 183.519076 -284.974792)
			(xy 183.523036 -284.925738) (xy 183.534813 -284.877954) (xy 183.554104 -284.832678) (xy 183.580407 -284.791082)
			(xy 183.613042 -284.754245) (xy 183.651163 -284.72312) (xy 183.693784 -284.698513) (xy 183.7398 -284.681061)
			(xy 183.788019 -284.671217) (xy 183.837194 -284.669236) (xy 183.886049 -284.675168) (xy 183.93332 -284.68886)
			(xy 183.977782 -284.709958) (xy 184.018285 -284.737914) (xy 184.053778 -284.772006) (xy 184.083343 -284.81135)
			(xy 184.106214 -284.854927) (xy 184.121798 -284.901608) (xy 184.129693 -284.950185) (xy 184.130188 -284.974792)
			(xy 184.469036 -284.974792) (xy 184.472996 -284.925738) (xy 184.484773 -284.877954) (xy 184.504064 -284.832678)
			(xy 184.530367 -284.791082) (xy 184.563002 -284.754245) (xy 184.601123 -284.72312) (xy 184.643744 -284.698513)
			(xy 184.68976 -284.681061) (xy 184.737979 -284.671217) (xy 184.787154 -284.669236) (xy 184.836009 -284.675168)
			(xy 184.88328 -284.68886) (xy 184.927742 -284.709958) (xy 184.968245 -284.737914) (xy 185.003738 -284.772006)
			(xy 185.033303 -284.81135) (xy 185.056174 -284.854927) (xy 185.071758 -284.901608) (xy 185.079653 -284.950185)
			(xy 185.080148 -284.974792) (xy 185.41925 -284.974792) (xy 185.42321 -284.925738) (xy 185.434987 -284.877954)
			(xy 185.454278 -284.832678) (xy 185.480581 -284.791082) (xy 185.513216 -284.754245) (xy 185.551337 -284.72312)
			(xy 185.593958 -284.698513) (xy 185.639974 -284.681061) (xy 185.688193 -284.671217) (xy 185.737368 -284.669236)
			(xy 185.786223 -284.675168) (xy 185.833494 -284.68886) (xy 185.877956 -284.709958) (xy 185.918459 -284.737914)
			(xy 185.953952 -284.772006) (xy 185.983517 -284.81135) (xy 186.006388 -284.854927) (xy 186.021972 -284.901608)
			(xy 186.029867 -284.950185) (xy 186.030362 -284.974792) (xy 186.36921 -284.974792) (xy 186.37317 -284.925738)
			(xy 186.384947 -284.877954) (xy 186.404238 -284.832678) (xy 186.430541 -284.791082) (xy 186.463176 -284.754245)
			(xy 186.501297 -284.72312) (xy 186.543918 -284.698513) (xy 186.589934 -284.681061) (xy 186.638153 -284.671217)
			(xy 186.687328 -284.669236) (xy 186.736183 -284.675168) (xy 186.783454 -284.68886) (xy 186.827916 -284.709958)
			(xy 186.868419 -284.737914) (xy 186.903912 -284.772006) (xy 186.933477 -284.81135) (xy 186.956348 -284.854927)
			(xy 186.971932 -284.901608) (xy 186.979827 -284.950185) (xy 186.980322 -284.974792) (xy 186.979827 -284.999399)
			(xy 186.971932 -285.047976) (xy 186.956348 -285.094657) (xy 186.933477 -285.138234) (xy 186.903912 -285.177578)
			(xy 186.868419 -285.21167) (xy 186.827916 -285.239626) (xy 186.783454 -285.260724) (xy 186.736183 -285.274416)
			(xy 186.687328 -285.280348) (xy 186.638153 -285.278367) (xy 186.589934 -285.268523) (xy 186.543918 -285.251071)
			(xy 186.501297 -285.226464) (xy 186.463176 -285.195339) (xy 186.430541 -285.158502) (xy 186.404238 -285.116906)
			(xy 186.384947 -285.07163) (xy 186.37317 -285.023846) (xy 186.36921 -284.974792) (xy 186.030362 -284.974792)
			(xy 186.029867 -284.999399) (xy 186.021972 -285.047976) (xy 186.006388 -285.094657) (xy 185.983517 -285.138234)
			(xy 185.953952 -285.177578) (xy 185.918459 -285.21167) (xy 185.877956 -285.239626) (xy 185.833494 -285.260724)
			(xy 185.786223 -285.274416) (xy 185.737368 -285.280348) (xy 185.688193 -285.278367) (xy 185.639974 -285.268523)
			(xy 185.593958 -285.251071) (xy 185.551337 -285.226464) (xy 185.513216 -285.195339) (xy 185.480581 -285.158502)
			(xy 185.454278 -285.116906) (xy 185.434987 -285.07163) (xy 185.42321 -285.023846) (xy 185.41925 -284.974792)
			(xy 185.080148 -284.974792) (xy 185.079653 -284.999399) (xy 185.071758 -285.047976) (xy 185.056174 -285.094657)
			(xy 185.033303 -285.138234) (xy 185.003738 -285.177578) (xy 184.968245 -285.21167) (xy 184.927742 -285.239626)
			(xy 184.88328 -285.260724) (xy 184.836009 -285.274416) (xy 184.787154 -285.280348) (xy 184.737979 -285.278367)
			(xy 184.68976 -285.268523) (xy 184.643744 -285.251071) (xy 184.601123 -285.226464) (xy 184.563002 -285.195339)
			(xy 184.530367 -285.158502) (xy 184.504064 -285.116906) (xy 184.484773 -285.07163) (xy 184.472996 -285.023846)
			(xy 184.469036 -284.974792) (xy 184.130188 -284.974792) (xy 184.129693 -284.999399) (xy 184.121798 -285.047976)
			(xy 184.106214 -285.094657) (xy 184.083343 -285.138234) (xy 184.053778 -285.177578) (xy 184.018285 -285.21167)
			(xy 183.977782 -285.239626) (xy 183.93332 -285.260724) (xy 183.886049 -285.274416) (xy 183.837194 -285.280348)
			(xy 183.788019 -285.278367) (xy 183.7398 -285.268523) (xy 183.693784 -285.251071) (xy 183.651163 -285.226464)
			(xy 183.613042 -285.195339) (xy 183.580407 -285.158502) (xy 183.554104 -285.116906) (xy 183.534813 -285.07163)
			(xy 183.523036 -285.023846) (xy 183.519076 -284.974792) (xy 183.180228 -284.974792) (xy 183.179733 -284.999399)
			(xy 183.171838 -285.047976) (xy 183.156254 -285.094657) (xy 183.133383 -285.138234) (xy 183.103818 -285.177578)
			(xy 183.068325 -285.21167) (xy 183.027822 -285.239626) (xy 182.98336 -285.260724) (xy 182.936089 -285.274416)
			(xy 182.887234 -285.280348) (xy 182.838059 -285.278367) (xy 182.78984 -285.268523) (xy 182.743824 -285.251071)
			(xy 182.701203 -285.226464) (xy 182.663082 -285.195339) (xy 182.630447 -285.158502) (xy 182.604144 -285.116906)
			(xy 182.584853 -285.07163) (xy 182.573076 -285.023846) (xy 182.569116 -284.974792) (xy 182.230268 -284.974792)
			(xy 182.229773 -284.999399) (xy 182.221878 -285.047976) (xy 182.206294 -285.094657) (xy 182.183423 -285.138234)
			(xy 182.153858 -285.177578) (xy 182.118365 -285.21167) (xy 182.077862 -285.239626) (xy 182.0334 -285.260724)
			(xy 181.986129 -285.274416) (xy 181.937274 -285.280348) (xy 181.888099 -285.278367) (xy 181.83988 -285.268523)
			(xy 181.793864 -285.251071) (xy 181.751243 -285.226464) (xy 181.713122 -285.195339) (xy 181.680487 -285.158502)
			(xy 181.654184 -285.116906) (xy 181.634893 -285.07163) (xy 181.623116 -285.023846) (xy 181.619156 -284.974792)
			(xy 181.280308 -284.974792) (xy 181.279813 -284.999399) (xy 181.271918 -285.047976) (xy 181.256334 -285.094657)
			(xy 181.233463 -285.138234) (xy 181.203898 -285.177578) (xy 181.168405 -285.21167) (xy 181.127902 -285.239626)
			(xy 181.08344 -285.260724) (xy 181.036169 -285.274416) (xy 180.987314 -285.280348) (xy 180.938139 -285.278367)
			(xy 180.88992 -285.268523) (xy 180.843904 -285.251071) (xy 180.801283 -285.226464) (xy 180.763162 -285.195339)
			(xy 180.730527 -285.158502) (xy 180.704224 -285.116906) (xy 180.684933 -285.07163) (xy 180.673156 -285.023846)
			(xy 180.669196 -284.974792) (xy 180.330348 -284.974792) (xy 180.329853 -284.999399) (xy 180.321958 -285.047976)
			(xy 180.306374 -285.094657) (xy 180.283503 -285.138234) (xy 180.253938 -285.177578) (xy 180.218445 -285.21167)
			(xy 180.177942 -285.239626) (xy 180.13348 -285.260724) (xy 180.086209 -285.274416) (xy 180.037354 -285.280348)
			(xy 179.988179 -285.278367) (xy 179.93996 -285.268523) (xy 179.893944 -285.251071) (xy 179.851323 -285.226464)
			(xy 179.813202 -285.195339) (xy 179.780567 -285.158502) (xy 179.754264 -285.116906) (xy 179.734973 -285.07163)
			(xy 179.723196 -285.023846) (xy 179.719236 -284.974792) (xy 179.380388 -284.974792) (xy 179.379893 -284.999399)
			(xy 179.371998 -285.047976) (xy 179.356414 -285.094657) (xy 179.333543 -285.138234) (xy 179.303978 -285.177578)
			(xy 179.268485 -285.21167) (xy 179.227982 -285.239626) (xy 179.18352 -285.260724) (xy 179.136249 -285.274416)
			(xy 179.087394 -285.280348) (xy 179.038219 -285.278367) (xy 178.99 -285.268523) (xy 178.943984 -285.251071)
			(xy 178.901363 -285.226464) (xy 178.863242 -285.195339) (xy 178.830607 -285.158502) (xy 178.804304 -285.116906)
			(xy 178.785013 -285.07163) (xy 178.773236 -285.023846) (xy 178.769276 -284.974792) (xy 178.430174 -284.974792)
			(xy 178.429679 -284.999399) (xy 178.421784 -285.047976) (xy 178.4062 -285.094657) (xy 178.383329 -285.138234)
			(xy 178.353764 -285.177578) (xy 178.318271 -285.21167) (xy 178.277768 -285.239626) (xy 178.233306 -285.260724)
			(xy 178.186035 -285.274416) (xy 178.13718 -285.280348) (xy 178.088005 -285.278367) (xy 178.039786 -285.268523)
			(xy 177.99377 -285.251071) (xy 177.951149 -285.226464) (xy 177.913028 -285.195339) (xy 177.880393 -285.158502)
			(xy 177.85409 -285.116906) (xy 177.834799 -285.07163) (xy 177.823022 -285.023846) (xy 177.819062 -284.974792)
			(xy 177.480214 -284.974792) (xy 177.479719 -284.999399) (xy 177.471824 -285.047976) (xy 177.45624 -285.094657)
			(xy 177.433369 -285.138234) (xy 177.403804 -285.177578) (xy 177.368311 -285.21167) (xy 177.327808 -285.239626)
			(xy 177.283346 -285.260724) (xy 177.236075 -285.274416) (xy 177.18722 -285.280348) (xy 177.138045 -285.278367)
			(xy 177.089826 -285.268523) (xy 177.04381 -285.251071) (xy 177.001189 -285.226464) (xy 176.963068 -285.195339)
			(xy 176.930433 -285.158502) (xy 176.90413 -285.116906) (xy 176.884839 -285.07163) (xy 176.873062 -285.023846)
			(xy 176.869102 -284.974792) (xy 176.530254 -284.974792) (xy 176.529759 -284.999399) (xy 176.521864 -285.047976)
			(xy 176.50628 -285.094657) (xy 176.483409 -285.138234) (xy 176.453844 -285.177578) (xy 176.418351 -285.21167)
			(xy 176.377848 -285.239626) (xy 176.333386 -285.260724) (xy 176.286115 -285.274416) (xy 176.23726 -285.280348)
			(xy 176.188085 -285.278367) (xy 176.139866 -285.268523) (xy 176.09385 -285.251071) (xy 176.051229 -285.226464)
			(xy 176.013108 -285.195339) (xy 175.980473 -285.158502) (xy 175.95417 -285.116906) (xy 175.934879 -285.07163)
			(xy 175.923102 -285.023846) (xy 175.919142 -284.974792) (xy 174.630334 -284.974792) (xy 174.629839 -284.999399)
			(xy 174.621944 -285.047976) (xy 174.60636 -285.094657) (xy 174.583489 -285.138234) (xy 174.553924 -285.177578)
			(xy 174.518431 -285.21167) (xy 174.477928 -285.239626) (xy 174.433466 -285.260724) (xy 174.386195 -285.274416)
			(xy 174.33734 -285.280348) (xy 174.288165 -285.278367) (xy 174.239946 -285.268523) (xy 174.19393 -285.251071)
			(xy 174.151309 -285.226464) (xy 174.113188 -285.195339) (xy 174.080553 -285.158502) (xy 174.05425 -285.116906)
			(xy 174.034959 -285.07163) (xy 174.023182 -285.023846) (xy 174.019222 -284.974792) (xy 173.680374 -284.974792)
			(xy 173.679879 -284.999399) (xy 173.671984 -285.047976) (xy 173.6564 -285.094657) (xy 173.633529 -285.138234)
			(xy 173.603964 -285.177578) (xy 173.568471 -285.21167) (xy 173.527968 -285.239626) (xy 173.483506 -285.260724)
			(xy 173.436235 -285.274416) (xy 173.38738 -285.280348) (xy 173.338205 -285.278367) (xy 173.289986 -285.268523)
			(xy 173.24397 -285.251071) (xy 173.201349 -285.226464) (xy 173.163228 -285.195339) (xy 173.130593 -285.158502)
			(xy 173.10429 -285.116906) (xy 173.084999 -285.07163) (xy 173.073222 -285.023846) (xy 173.069262 -284.974792)
			(xy 172.73016 -284.974792) (xy 172.729665 -284.999399) (xy 172.72177 -285.047976) (xy 172.706186 -285.094657)
			(xy 172.683315 -285.138234) (xy 172.65375 -285.177578) (xy 172.618257 -285.21167) (xy 172.577754 -285.239626)
			(xy 172.533292 -285.260724) (xy 172.486021 -285.274416) (xy 172.437166 -285.280348) (xy 172.387991 -285.278367)
			(xy 172.339772 -285.268523) (xy 172.293756 -285.251071) (xy 172.251135 -285.226464) (xy 172.213014 -285.195339)
			(xy 172.180379 -285.158502) (xy 172.154076 -285.116906) (xy 172.134785 -285.07163) (xy 172.123008 -285.023846)
			(xy 172.119048 -284.974792) (xy 171.7802 -284.974792) (xy 171.779705 -284.999399) (xy 171.77181 -285.047976)
			(xy 171.756226 -285.094657) (xy 171.733355 -285.138234) (xy 171.70379 -285.177578) (xy 171.668297 -285.21167)
			(xy 171.627794 -285.239626) (xy 171.583332 -285.260724) (xy 171.536061 -285.274416) (xy 171.487206 -285.280348)
			(xy 171.438031 -285.278367) (xy 171.389812 -285.268523) (xy 171.343796 -285.251071) (xy 171.301175 -285.226464)
			(xy 171.263054 -285.195339) (xy 171.230419 -285.158502) (xy 171.204116 -285.116906) (xy 171.184825 -285.07163)
			(xy 171.173048 -285.023846) (xy 171.169088 -284.974792) (xy 170.83024 -284.974792) (xy 170.829745 -284.999399)
			(xy 170.82185 -285.047976) (xy 170.806266 -285.094657) (xy 170.783395 -285.138234) (xy 170.75383 -285.177578)
			(xy 170.718337 -285.21167) (xy 170.677834 -285.239626) (xy 170.633372 -285.260724) (xy 170.586101 -285.274416)
			(xy 170.537246 -285.280348) (xy 170.488071 -285.278367) (xy 170.439852 -285.268523) (xy 170.393836 -285.251071)
			(xy 170.351215 -285.226464) (xy 170.313094 -285.195339) (xy 170.280459 -285.158502) (xy 170.254156 -285.116906)
			(xy 170.234865 -285.07163) (xy 170.223088 -285.023846) (xy 170.219128 -284.974792) (xy 169.88028 -284.974792)
			(xy 169.879785 -284.999399) (xy 169.87189 -285.047976) (xy 169.856306 -285.094657) (xy 169.833435 -285.138234)
			(xy 169.80387 -285.177578) (xy 169.768377 -285.21167) (xy 169.727874 -285.239626) (xy 169.683412 -285.260724)
			(xy 169.636141 -285.274416) (xy 169.587286 -285.280348) (xy 169.538111 -285.278367) (xy 169.489892 -285.268523)
			(xy 169.443876 -285.251071) (xy 169.401255 -285.226464) (xy 169.363134 -285.195339) (xy 169.330499 -285.158502)
			(xy 169.304196 -285.116906) (xy 169.284905 -285.07163) (xy 169.273128 -285.023846) (xy 169.269168 -284.974792)
			(xy 168.93032 -284.974792) (xy 168.929825 -284.999399) (xy 168.92193 -285.047976) (xy 168.906346 -285.094657)
			(xy 168.883475 -285.138234) (xy 168.85391 -285.177578) (xy 168.818417 -285.21167) (xy 168.777914 -285.239626)
			(xy 168.733452 -285.260724) (xy 168.686181 -285.274416) (xy 168.637326 -285.280348) (xy 168.588151 -285.278367)
			(xy 168.539932 -285.268523) (xy 168.493916 -285.251071) (xy 168.451295 -285.226464) (xy 168.413174 -285.195339)
			(xy 168.380539 -285.158502) (xy 168.354236 -285.116906) (xy 168.334945 -285.07163) (xy 168.323168 -285.023846)
			(xy 168.319208 -284.974792) (xy 167.98036 -284.974792) (xy 167.979865 -284.999399) (xy 167.97197 -285.047976)
			(xy 167.956386 -285.094657) (xy 167.933515 -285.138234) (xy 167.90395 -285.177578) (xy 167.868457 -285.21167)
			(xy 167.827954 -285.239626) (xy 167.783492 -285.260724) (xy 167.736221 -285.274416) (xy 167.687366 -285.280348)
			(xy 167.638191 -285.278367) (xy 167.589972 -285.268523) (xy 167.543956 -285.251071) (xy 167.501335 -285.226464)
			(xy 167.463214 -285.195339) (xy 167.430579 -285.158502) (xy 167.404276 -285.116906) (xy 167.384985 -285.07163)
			(xy 167.373208 -285.023846) (xy 167.369248 -284.974792) (xy 167.0304 -284.974792) (xy 167.029905 -284.999399)
			(xy 167.02201 -285.047976) (xy 167.006426 -285.094657) (xy 166.983555 -285.138234) (xy 166.95399 -285.177578)
			(xy 166.918497 -285.21167) (xy 166.877994 -285.239626) (xy 166.833532 -285.260724) (xy 166.786261 -285.274416)
			(xy 166.737406 -285.280348) (xy 166.688231 -285.278367) (xy 166.640012 -285.268523) (xy 166.593996 -285.251071)
			(xy 166.551375 -285.226464) (xy 166.513254 -285.195339) (xy 166.480619 -285.158502) (xy 166.454316 -285.116906)
			(xy 166.435025 -285.07163) (xy 166.423248 -285.023846) (xy 166.419288 -284.974792) (xy 166.080186 -284.974792)
			(xy 166.079691 -284.999399) (xy 166.071796 -285.047976) (xy 166.056212 -285.094657) (xy 166.033341 -285.138234)
			(xy 166.003776 -285.177578) (xy 165.968283 -285.21167) (xy 165.92778 -285.239626) (xy 165.883318 -285.260724)
			(xy 165.836047 -285.274416) (xy 165.787192 -285.280348) (xy 165.738017 -285.278367) (xy 165.689798 -285.268523)
			(xy 165.643782 -285.251071) (xy 165.601161 -285.226464) (xy 165.56304 -285.195339) (xy 165.530405 -285.158502)
			(xy 165.504102 -285.116906) (xy 165.484811 -285.07163) (xy 165.473034 -285.023846) (xy 165.469074 -284.974792)
			(xy 165.303708 -284.974792) (xy 165.303708 -285.449772) (xy 189.69407 -285.449772) (xy 189.69803 -285.400718)
			(xy 189.709807 -285.352934) (xy 189.729098 -285.307658) (xy 189.755401 -285.266062) (xy 189.788036 -285.229225)
			(xy 189.826157 -285.1981) (xy 189.868778 -285.173493) (xy 189.914794 -285.156041) (xy 189.963013 -285.146197)
			(xy 190.012188 -285.144216) (xy 190.061043 -285.150148) (xy 190.108314 -285.16384) (xy 190.152776 -285.184938)
			(xy 190.193279 -285.212894) (xy 190.228772 -285.246986) (xy 190.258337 -285.28633) (xy 190.281208 -285.329907)
			(xy 190.296792 -285.376588) (xy 190.304687 -285.425165) (xy 190.305182 -285.449772) (xy 190.304687 -285.474379)
			(xy 190.304508 -285.47548) (xy 190.623186 -285.47548) (xy 190.623186 -285.424064) (xy 190.631229 -285.373282)
			(xy 190.647117 -285.324383) (xy 190.67046 -285.278571) (xy 190.700681 -285.236975) (xy 190.737037 -285.200619)
			(xy 190.778633 -285.170398) (xy 190.824445 -285.147055) (xy 190.873344 -285.131167) (xy 190.924126 -285.123124)
			(xy 190.975542 -285.123124) (xy 191.026324 -285.131167) (xy 191.075223 -285.147055) (xy 191.121035 -285.170398)
			(xy 191.162631 -285.200619) (xy 191.198987 -285.236975) (xy 191.229208 -285.278571) (xy 191.252551 -285.324383)
			(xy 191.268439 -285.373282) (xy 191.276482 -285.424064) (xy 191.276986 -285.449772) (xy 191.276482 -285.47548)
			(xy 191.5734 -285.47548) (xy 191.5734 -285.424064) (xy 191.581443 -285.373282) (xy 191.597331 -285.324383)
			(xy 191.620674 -285.278571) (xy 191.650895 -285.236975) (xy 191.687251 -285.200619) (xy 191.728847 -285.170398)
			(xy 191.774659 -285.147055) (xy 191.823558 -285.131167) (xy 191.87434 -285.123124) (xy 191.925756 -285.123124)
			(xy 191.976538 -285.131167) (xy 192.025437 -285.147055) (xy 192.071249 -285.170398) (xy 192.112845 -285.200619)
			(xy 192.149201 -285.236975) (xy 192.179422 -285.278571) (xy 192.202765 -285.324383) (xy 192.218653 -285.373282)
			(xy 192.226696 -285.424064) (xy 192.2272 -285.449772) (xy 192.544204 -285.449772) (xy 192.548164 -285.400718)
			(xy 192.559941 -285.352934) (xy 192.579232 -285.307658) (xy 192.605535 -285.266062) (xy 192.63817 -285.229225)
			(xy 192.676291 -285.1981) (xy 192.718912 -285.173493) (xy 192.764928 -285.156041) (xy 192.813147 -285.146197)
			(xy 192.862322 -285.144216) (xy 192.911177 -285.150148) (xy 192.958448 -285.16384) (xy 193.00291 -285.184938)
			(xy 193.043413 -285.212894) (xy 193.078906 -285.246986) (xy 193.108471 -285.28633) (xy 193.131342 -285.329907)
			(xy 193.146926 -285.376588) (xy 193.154821 -285.425165) (xy 193.155316 -285.449772) (xy 193.494164 -285.449772)
			(xy 193.498124 -285.400718) (xy 193.509901 -285.352934) (xy 193.529192 -285.307658) (xy 193.555495 -285.266062)
			(xy 193.58813 -285.229225) (xy 193.626251 -285.1981) (xy 193.668872 -285.173493) (xy 193.714888 -285.156041)
			(xy 193.763107 -285.146197) (xy 193.812282 -285.144216) (xy 193.861137 -285.150148) (xy 193.908408 -285.16384)
			(xy 193.95287 -285.184938) (xy 193.993373 -285.212894) (xy 194.028866 -285.246986) (xy 194.058431 -285.28633)
			(xy 194.081302 -285.329907) (xy 194.096886 -285.376588) (xy 194.104781 -285.425165) (xy 194.105276 -285.449772)
			(xy 194.444124 -285.449772) (xy 194.448084 -285.400718) (xy 194.459861 -285.352934) (xy 194.479152 -285.307658)
			(xy 194.505455 -285.266062) (xy 194.53809 -285.229225) (xy 194.576211 -285.1981) (xy 194.618832 -285.173493)
			(xy 194.664848 -285.156041) (xy 194.713067 -285.146197) (xy 194.762242 -285.144216) (xy 194.811097 -285.150148)
			(xy 194.858368 -285.16384) (xy 194.90283 -285.184938) (xy 194.943333 -285.212894) (xy 194.978826 -285.246986)
			(xy 195.008391 -285.28633) (xy 195.031262 -285.329907) (xy 195.046846 -285.376588) (xy 195.054741 -285.425165)
			(xy 195.055236 -285.449772) (xy 195.394084 -285.449772) (xy 195.398044 -285.400718) (xy 195.409821 -285.352934)
			(xy 195.429112 -285.307658) (xy 195.455415 -285.266062) (xy 195.48805 -285.229225) (xy 195.526171 -285.1981)
			(xy 195.568792 -285.173493) (xy 195.614808 -285.156041) (xy 195.663027 -285.146197) (xy 195.712202 -285.144216)
			(xy 195.761057 -285.150148) (xy 195.808328 -285.16384) (xy 195.85279 -285.184938) (xy 195.893293 -285.212894)
			(xy 195.928786 -285.246986) (xy 195.958351 -285.28633) (xy 195.981222 -285.329907) (xy 195.996806 -285.376588)
			(xy 196.004701 -285.425165) (xy 196.005196 -285.449772) (xy 196.344044 -285.449772) (xy 196.348004 -285.400718)
			(xy 196.359781 -285.352934) (xy 196.379072 -285.307658) (xy 196.405375 -285.266062) (xy 196.43801 -285.229225)
			(xy 196.476131 -285.1981) (xy 196.518752 -285.173493) (xy 196.564768 -285.156041) (xy 196.612987 -285.146197)
			(xy 196.662162 -285.144216) (xy 196.711017 -285.150148) (xy 196.758288 -285.16384) (xy 196.80275 -285.184938)
			(xy 196.843253 -285.212894) (xy 196.878746 -285.246986) (xy 196.908311 -285.28633) (xy 196.931182 -285.329907)
			(xy 196.946766 -285.376588) (xy 196.954661 -285.425165) (xy 196.955156 -285.449772) (xy 196.954661 -285.474379)
			(xy 196.954482 -285.47548) (xy 197.273414 -285.47548) (xy 197.273414 -285.424064) (xy 197.281457 -285.373282)
			(xy 197.297345 -285.324383) (xy 197.320688 -285.278571) (xy 197.350909 -285.236975) (xy 197.387265 -285.200619)
			(xy 197.428861 -285.170398) (xy 197.474673 -285.147055) (xy 197.523572 -285.131167) (xy 197.574354 -285.123124)
			(xy 197.62577 -285.123124) (xy 197.676552 -285.131167) (xy 197.725451 -285.147055) (xy 197.771263 -285.170398)
			(xy 197.812859 -285.200619) (xy 197.849215 -285.236975) (xy 197.879436 -285.278571) (xy 197.902779 -285.324383)
			(xy 197.918667 -285.373282) (xy 197.92671 -285.424064) (xy 197.927214 -285.449772) (xy 197.92671 -285.47548)
			(xy 198.223374 -285.47548) (xy 198.223374 -285.424064) (xy 198.231417 -285.373282) (xy 198.247305 -285.324383)
			(xy 198.270648 -285.278571) (xy 198.300869 -285.236975) (xy 198.337225 -285.200619) (xy 198.378821 -285.170398)
			(xy 198.424633 -285.147055) (xy 198.473532 -285.131167) (xy 198.524314 -285.123124) (xy 198.57573 -285.123124)
			(xy 198.626512 -285.131167) (xy 198.675411 -285.147055) (xy 198.721223 -285.170398) (xy 198.762819 -285.200619)
			(xy 198.799175 -285.236975) (xy 198.829396 -285.278571) (xy 198.852739 -285.324383) (xy 198.868627 -285.373282)
			(xy 198.87667 -285.424064) (xy 198.877174 -285.449772) (xy 198.877169 -285.450026) (xy 199.194432 -285.450026)
			(xy 199.198392 -285.400972) (xy 199.210169 -285.353188) (xy 199.22946 -285.307912) (xy 199.255763 -285.266316)
			(xy 199.288398 -285.229479) (xy 199.326519 -285.198354) (xy 199.36914 -285.173747) (xy 199.415156 -285.156295)
			(xy 199.463375 -285.146451) (xy 199.51255 -285.14447) (xy 199.561405 -285.150402) (xy 199.608676 -285.164094)
			(xy 199.653138 -285.185192) (xy 199.693641 -285.213148) (xy 199.729134 -285.24724) (xy 199.758699 -285.286584)
			(xy 199.78157 -285.330161) (xy 199.797154 -285.376842) (xy 199.805049 -285.425419) (xy 199.805544 -285.450026)
			(xy 199.805077 -285.473258) (xy 224.751517 -285.473258) (xy 224.751517 -285.418742) (xy 224.759276 -285.364782)
			(xy 224.774636 -285.312475) (xy 224.797284 -285.262887) (xy 224.826759 -285.217027) (xy 224.862462 -285.175829)
			(xy 224.903664 -285.140132) (xy 224.949527 -285.110662) (xy 224.999118 -285.08802) (xy 225.051427 -285.072666)
			(xy 225.105388 -285.064914) (xy 225.132646 -285.064454) (xy 225.161385 -285.064962) (xy 225.218213 -285.07359)
			(xy 225.273103 -285.090645) (xy 225.324815 -285.115739) (xy 225.372177 -285.148307) (xy 225.393504 -285.167578)
			(xy 225.400616 -285.174182) (xy 225.418142 -285.181294) (xy 225.50755 -285.181294) (xy 225.525076 -285.174182)
			(xy 225.532188 -285.167578) (xy 225.553515 -285.148308) (xy 225.600878 -285.115743) (xy 225.652589 -285.090652)
			(xy 225.70748 -285.073602) (xy 225.764307 -285.06498) (xy 225.821785 -285.06498) (xy 225.878612 -285.073602)
			(xy 225.933503 -285.090652) (xy 225.985214 -285.115743) (xy 226.032577 -285.148308) (xy 226.053904 -285.167578)
			(xy 226.061016 -285.174182) (xy 226.078542 -285.181294) (xy 226.16795 -285.181294) (xy 226.185476 -285.174182)
			(xy 226.192588 -285.167578) (xy 226.213902 -285.148292) (xy 226.261267 -285.115726) (xy 226.312982 -285.090636)
			(xy 226.367876 -285.073589) (xy 226.424706 -285.064972) (xy 226.453446 -285.064454) (xy 226.483568 -285.065058)
			(xy 226.543063 -285.074531) (xy 226.60033 -285.093234) (xy 226.653948 -285.120702) (xy 226.702584 -285.156254)
			(xy 226.72421 -285.17723) (xy 226.731322 -285.184596) (xy 226.750118 -285.192216) (xy 226.842574 -285.192216)
			(xy 226.86137 -285.184596) (xy 226.868482 -285.17723) (xy 226.890097 -285.156239) (xy 226.938728 -285.12067)
			(xy 226.992347 -285.093192) (xy 227.049619 -285.074487) (xy 227.109121 -285.06502) (xy 227.139246 -285.064454)
			(xy 227.166492 -285.065019) (xy 227.22043 -285.07278) (xy 227.272714 -285.088138) (xy 227.32228 -285.110779)
			(xy 227.36812 -285.140244) (xy 227.409301 -285.175932) (xy 227.444984 -285.217117) (xy 227.474443 -285.26296)
			(xy 227.497078 -285.31253) (xy 227.512429 -285.364815) (xy 227.520184 -285.418754) (xy 227.520184 -285.473246)
			(xy 227.512429 -285.527185) (xy 227.497078 -285.57947) (xy 227.474443 -285.62904) (xy 227.444984 -285.674883)
			(xy 227.409301 -285.716068) (xy 227.36812 -285.751756) (xy 227.32228 -285.781221) (xy 227.272714 -285.803862)
			(xy 227.22043 -285.81922) (xy 227.166492 -285.826981) (xy 227.139246 -285.82747) (xy 227.109124 -285.826865)
			(xy 227.04963 -285.817391) (xy 226.992362 -285.798688) (xy 226.938745 -285.77122) (xy 226.890108 -285.735669)
			(xy 226.868482 -285.714694) (xy 226.86137 -285.707328) (xy 226.842574 -285.699708) (xy 226.750118 -285.699708)
			(xy 226.731322 -285.707328) (xy 226.72421 -285.714694) (xy 226.702603 -285.735694) (xy 226.653969 -285.77126)
			(xy 226.600349 -285.798736) (xy 226.543074 -285.81744) (xy 226.483572 -285.826905) (xy 226.453446 -285.82747)
			(xy 226.424707 -285.82696) (xy 226.36788 -285.818332) (xy 226.312989 -285.801277) (xy 226.261278 -285.776183)
			(xy 226.213915 -285.743617) (xy 226.192588 -285.724346) (xy 226.185476 -285.717742) (xy 226.16795 -285.71063)
			(xy 226.078542 -285.71063) (xy 226.061016 -285.717742) (xy 226.053904 -285.724346) (xy 226.032577 -285.743616)
			(xy 225.985214 -285.776181) (xy 225.933503 -285.801272) (xy 225.878612 -285.818322) (xy 225.821785 -285.826944)
			(xy 225.764307 -285.826944) (xy 225.70748 -285.818322) (xy 225.652589 -285.801272) (xy 225.600878 -285.776181)
			(xy 225.553515 -285.743616) (xy 225.532188 -285.724346) (xy 225.525076 -285.717742) (xy 225.50755 -285.71063)
			(xy 225.418142 -285.71063) (xy 225.400616 -285.717742) (xy 225.393504 -285.724346) (xy 225.372197 -285.74364)
			(xy 225.32483 -285.776203) (xy 225.273113 -285.801292) (xy 225.218218 -285.818337) (xy 225.161386 -285.826953)
			(xy 225.132646 -285.82747) (xy 225.105388 -285.827086) (xy 225.051427 -285.819334) (xy 224.999118 -285.80398)
			(xy 224.949527 -285.781338) (xy 224.903664 -285.751868) (xy 224.862462 -285.716171) (xy 224.826759 -285.674973)
			(xy 224.797284 -285.629113) (xy 224.774636 -285.579525) (xy 224.759276 -285.527218) (xy 224.751517 -285.473258)
			(xy 199.805077 -285.473258) (xy 199.805049 -285.474633) (xy 199.797154 -285.52321) (xy 199.78157 -285.569891)
			(xy 199.758699 -285.613468) (xy 199.729134 -285.652812) (xy 199.693641 -285.686904) (xy 199.653138 -285.71486)
			(xy 199.608676 -285.735958) (xy 199.561405 -285.74965) (xy 199.51255 -285.755582) (xy 199.463375 -285.753601)
			(xy 199.415156 -285.743757) (xy 199.36914 -285.726305) (xy 199.326519 -285.701698) (xy 199.288398 -285.670573)
			(xy 199.255763 -285.633736) (xy 199.22946 -285.59214) (xy 199.210169 -285.546864) (xy 199.198392 -285.49908)
			(xy 199.194432 -285.450026) (xy 198.877169 -285.450026) (xy 198.87667 -285.47548) (xy 198.868627 -285.526262)
			(xy 198.852739 -285.575161) (xy 198.829396 -285.620973) (xy 198.799175 -285.662569) (xy 198.762819 -285.698925)
			(xy 198.721223 -285.729146) (xy 198.675411 -285.752489) (xy 198.626512 -285.768377) (xy 198.57573 -285.77642)
			(xy 198.524314 -285.77642) (xy 198.473532 -285.768377) (xy 198.424633 -285.752489) (xy 198.378821 -285.729146)
			(xy 198.337225 -285.698925) (xy 198.300869 -285.662569) (xy 198.270648 -285.620973) (xy 198.247305 -285.575161)
			(xy 198.231417 -285.526262) (xy 198.223374 -285.47548) (xy 197.92671 -285.47548) (xy 197.918667 -285.526262)
			(xy 197.902779 -285.575161) (xy 197.879436 -285.620973) (xy 197.849215 -285.662569) (xy 197.812859 -285.698925)
			(xy 197.771263 -285.729146) (xy 197.725451 -285.752489) (xy 197.676552 -285.768377) (xy 197.62577 -285.77642)
			(xy 197.574354 -285.77642) (xy 197.523572 -285.768377) (xy 197.474673 -285.752489) (xy 197.428861 -285.729146)
			(xy 197.387265 -285.698925) (xy 197.350909 -285.662569) (xy 197.320688 -285.620973) (xy 197.297345 -285.575161)
			(xy 197.281457 -285.526262) (xy 197.273414 -285.47548) (xy 196.954482 -285.47548) (xy 196.946766 -285.522956)
			(xy 196.931182 -285.569637) (xy 196.908311 -285.613214) (xy 196.878746 -285.652558) (xy 196.843253 -285.68665)
			(xy 196.80275 -285.714606) (xy 196.758288 -285.735704) (xy 196.711017 -285.749396) (xy 196.662162 -285.755328)
			(xy 196.612987 -285.753347) (xy 196.564768 -285.743503) (xy 196.518752 -285.726051) (xy 196.476131 -285.701444)
			(xy 196.43801 -285.670319) (xy 196.405375 -285.633482) (xy 196.379072 -285.591886) (xy 196.359781 -285.54661)
			(xy 196.348004 -285.498826) (xy 196.344044 -285.449772) (xy 196.005196 -285.449772) (xy 196.004701 -285.474379)
			(xy 195.996806 -285.522956) (xy 195.981222 -285.569637) (xy 195.958351 -285.613214) (xy 195.928786 -285.652558)
			(xy 195.893293 -285.68665) (xy 195.85279 -285.714606) (xy 195.808328 -285.735704) (xy 195.761057 -285.749396)
			(xy 195.712202 -285.755328) (xy 195.663027 -285.753347) (xy 195.614808 -285.743503) (xy 195.568792 -285.726051)
			(xy 195.526171 -285.701444) (xy 195.48805 -285.670319) (xy 195.455415 -285.633482) (xy 195.429112 -285.591886)
			(xy 195.409821 -285.54661) (xy 195.398044 -285.498826) (xy 195.394084 -285.449772) (xy 195.055236 -285.449772)
			(xy 195.054741 -285.474379) (xy 195.046846 -285.522956) (xy 195.031262 -285.569637) (xy 195.008391 -285.613214)
			(xy 194.978826 -285.652558) (xy 194.943333 -285.68665) (xy 194.90283 -285.714606) (xy 194.858368 -285.735704)
			(xy 194.811097 -285.749396) (xy 194.762242 -285.755328) (xy 194.713067 -285.753347) (xy 194.664848 -285.743503)
			(xy 194.618832 -285.726051) (xy 194.576211 -285.701444) (xy 194.53809 -285.670319) (xy 194.505455 -285.633482)
			(xy 194.479152 -285.591886) (xy 194.459861 -285.54661) (xy 194.448084 -285.498826) (xy 194.444124 -285.449772)
			(xy 194.105276 -285.449772) (xy 194.104781 -285.474379) (xy 194.096886 -285.522956) (xy 194.081302 -285.569637)
			(xy 194.058431 -285.613214) (xy 194.028866 -285.652558) (xy 193.993373 -285.68665) (xy 193.95287 -285.714606)
			(xy 193.908408 -285.735704) (xy 193.861137 -285.749396) (xy 193.812282 -285.755328) (xy 193.763107 -285.753347)
			(xy 193.714888 -285.743503) (xy 193.668872 -285.726051) (xy 193.626251 -285.701444) (xy 193.58813 -285.670319)
			(xy 193.555495 -285.633482) (xy 193.529192 -285.591886) (xy 193.509901 -285.54661) (xy 193.498124 -285.498826)
			(xy 193.494164 -285.449772) (xy 193.155316 -285.449772) (xy 193.154821 -285.474379) (xy 193.146926 -285.522956)
			(xy 193.131342 -285.569637) (xy 193.108471 -285.613214) (xy 193.078906 -285.652558) (xy 193.043413 -285.68665)
			(xy 193.00291 -285.714606) (xy 192.958448 -285.735704) (xy 192.911177 -285.749396) (xy 192.862322 -285.755328)
			(xy 192.813147 -285.753347) (xy 192.764928 -285.743503) (xy 192.718912 -285.726051) (xy 192.676291 -285.701444)
			(xy 192.63817 -285.670319) (xy 192.605535 -285.633482) (xy 192.579232 -285.591886) (xy 192.559941 -285.54661)
			(xy 192.548164 -285.498826) (xy 192.544204 -285.449772) (xy 192.2272 -285.449772) (xy 192.226696 -285.47548)
			(xy 192.218653 -285.526262) (xy 192.202765 -285.575161) (xy 192.179422 -285.620973) (xy 192.149201 -285.662569)
			(xy 192.112845 -285.698925) (xy 192.071249 -285.729146) (xy 192.025437 -285.752489) (xy 191.976538 -285.768377)
			(xy 191.925756 -285.77642) (xy 191.87434 -285.77642) (xy 191.823558 -285.768377) (xy 191.774659 -285.752489)
			(xy 191.728847 -285.729146) (xy 191.687251 -285.698925) (xy 191.650895 -285.662569) (xy 191.620674 -285.620973)
			(xy 191.597331 -285.575161) (xy 191.581443 -285.526262) (xy 191.5734 -285.47548) (xy 191.276482 -285.47548)
			(xy 191.268439 -285.526262) (xy 191.252551 -285.575161) (xy 191.229208 -285.620973) (xy 191.198987 -285.662569)
			(xy 191.162631 -285.698925) (xy 191.121035 -285.729146) (xy 191.075223 -285.752489) (xy 191.026324 -285.768377)
			(xy 190.975542 -285.77642) (xy 190.924126 -285.77642) (xy 190.873344 -285.768377) (xy 190.824445 -285.752489)
			(xy 190.778633 -285.729146) (xy 190.737037 -285.698925) (xy 190.700681 -285.662569) (xy 190.67046 -285.620973)
			(xy 190.647117 -285.575161) (xy 190.631229 -285.526262) (xy 190.623186 -285.47548) (xy 190.304508 -285.47548)
			(xy 190.296792 -285.522956) (xy 190.281208 -285.569637) (xy 190.258337 -285.613214) (xy 190.228772 -285.652558)
			(xy 190.193279 -285.68665) (xy 190.152776 -285.714606) (xy 190.108314 -285.735704) (xy 190.061043 -285.749396)
			(xy 190.012188 -285.755328) (xy 189.963013 -285.753347) (xy 189.914794 -285.743503) (xy 189.868778 -285.726051)
			(xy 189.826157 -285.701444) (xy 189.788036 -285.670319) (xy 189.755401 -285.633482) (xy 189.729098 -285.591886)
			(xy 189.709807 -285.54661) (xy 189.69803 -285.498826) (xy 189.69407 -285.449772) (xy 165.303708 -285.449772)
			(xy 165.303708 -285.924752) (xy 165.469074 -285.924752) (xy 165.473034 -285.875698) (xy 165.484811 -285.827914)
			(xy 165.504102 -285.782638) (xy 165.530405 -285.741042) (xy 165.56304 -285.704205) (xy 165.601161 -285.67308)
			(xy 165.643782 -285.648473) (xy 165.689798 -285.631021) (xy 165.738017 -285.621177) (xy 165.787192 -285.619196)
			(xy 165.836047 -285.625128) (xy 165.883318 -285.63882) (xy 165.92778 -285.659918) (xy 165.968283 -285.687874)
			(xy 166.003776 -285.721966) (xy 166.033341 -285.76131) (xy 166.056212 -285.804887) (xy 166.071796 -285.851568)
			(xy 166.079691 -285.900145) (xy 166.080186 -285.924752) (xy 166.419288 -285.924752) (xy 166.423248 -285.875698)
			(xy 166.435025 -285.827914) (xy 166.454316 -285.782638) (xy 166.480619 -285.741042) (xy 166.513254 -285.704205)
			(xy 166.551375 -285.67308) (xy 166.593996 -285.648473) (xy 166.640012 -285.631021) (xy 166.688231 -285.621177)
			(xy 166.737406 -285.619196) (xy 166.786261 -285.625128) (xy 166.833532 -285.63882) (xy 166.877994 -285.659918)
			(xy 166.918497 -285.687874) (xy 166.95399 -285.721966) (xy 166.983555 -285.76131) (xy 167.006426 -285.804887)
			(xy 167.02201 -285.851568) (xy 167.029905 -285.900145) (xy 167.0304 -285.924752) (xy 167.369248 -285.924752)
			(xy 167.373208 -285.875698) (xy 167.384985 -285.827914) (xy 167.404276 -285.782638) (xy 167.430579 -285.741042)
			(xy 167.463214 -285.704205) (xy 167.501335 -285.67308) (xy 167.543956 -285.648473) (xy 167.589972 -285.631021)
			(xy 167.638191 -285.621177) (xy 167.687366 -285.619196) (xy 167.736221 -285.625128) (xy 167.783492 -285.63882)
			(xy 167.827954 -285.659918) (xy 167.868457 -285.687874) (xy 167.90395 -285.721966) (xy 167.933515 -285.76131)
			(xy 167.956386 -285.804887) (xy 167.97197 -285.851568) (xy 167.979865 -285.900145) (xy 167.98036 -285.924752)
			(xy 168.319208 -285.924752) (xy 168.323168 -285.875698) (xy 168.334945 -285.827914) (xy 168.354236 -285.782638)
			(xy 168.380539 -285.741042) (xy 168.413174 -285.704205) (xy 168.451295 -285.67308) (xy 168.493916 -285.648473)
			(xy 168.539932 -285.631021) (xy 168.588151 -285.621177) (xy 168.637326 -285.619196) (xy 168.686181 -285.625128)
			(xy 168.733452 -285.63882) (xy 168.777914 -285.659918) (xy 168.818417 -285.687874) (xy 168.85391 -285.721966)
			(xy 168.883475 -285.76131) (xy 168.906346 -285.804887) (xy 168.92193 -285.851568) (xy 168.929825 -285.900145)
			(xy 168.93032 -285.924752) (xy 169.269168 -285.924752) (xy 169.273128 -285.875698) (xy 169.284905 -285.827914)
			(xy 169.304196 -285.782638) (xy 169.330499 -285.741042) (xy 169.363134 -285.704205) (xy 169.401255 -285.67308)
			(xy 169.443876 -285.648473) (xy 169.489892 -285.631021) (xy 169.538111 -285.621177) (xy 169.587286 -285.619196)
			(xy 169.636141 -285.625128) (xy 169.683412 -285.63882) (xy 169.727874 -285.659918) (xy 169.768377 -285.687874)
			(xy 169.80387 -285.721966) (xy 169.833435 -285.76131) (xy 169.856306 -285.804887) (xy 169.87189 -285.851568)
			(xy 169.879785 -285.900145) (xy 169.88028 -285.924752) (xy 170.219128 -285.924752) (xy 170.223088 -285.875698)
			(xy 170.234865 -285.827914) (xy 170.254156 -285.782638) (xy 170.280459 -285.741042) (xy 170.313094 -285.704205)
			(xy 170.351215 -285.67308) (xy 170.393836 -285.648473) (xy 170.439852 -285.631021) (xy 170.488071 -285.621177)
			(xy 170.537246 -285.619196) (xy 170.586101 -285.625128) (xy 170.633372 -285.63882) (xy 170.677834 -285.659918)
			(xy 170.718337 -285.687874) (xy 170.75383 -285.721966) (xy 170.783395 -285.76131) (xy 170.806266 -285.804887)
			(xy 170.82185 -285.851568) (xy 170.829745 -285.900145) (xy 170.83024 -285.924752) (xy 171.169088 -285.924752)
			(xy 171.173048 -285.875698) (xy 171.184825 -285.827914) (xy 171.204116 -285.782638) (xy 171.230419 -285.741042)
			(xy 171.263054 -285.704205) (xy 171.301175 -285.67308) (xy 171.343796 -285.648473) (xy 171.389812 -285.631021)
			(xy 171.438031 -285.621177) (xy 171.487206 -285.619196) (xy 171.536061 -285.625128) (xy 171.583332 -285.63882)
			(xy 171.627794 -285.659918) (xy 171.668297 -285.687874) (xy 171.70379 -285.721966) (xy 171.733355 -285.76131)
			(xy 171.756226 -285.804887) (xy 171.77181 -285.851568) (xy 171.779705 -285.900145) (xy 171.7802 -285.924752)
			(xy 172.119048 -285.924752) (xy 172.123008 -285.875698) (xy 172.134785 -285.827914) (xy 172.154076 -285.782638)
			(xy 172.180379 -285.741042) (xy 172.213014 -285.704205) (xy 172.251135 -285.67308) (xy 172.293756 -285.648473)
			(xy 172.339772 -285.631021) (xy 172.387991 -285.621177) (xy 172.437166 -285.619196) (xy 172.486021 -285.625128)
			(xy 172.533292 -285.63882) (xy 172.577754 -285.659918) (xy 172.618257 -285.687874) (xy 172.65375 -285.721966)
			(xy 172.683315 -285.76131) (xy 172.706186 -285.804887) (xy 172.72177 -285.851568) (xy 172.729665 -285.900145)
			(xy 172.73016 -285.924752) (xy 173.069262 -285.924752) (xy 173.073222 -285.875698) (xy 173.084999 -285.827914)
			(xy 173.10429 -285.782638) (xy 173.130593 -285.741042) (xy 173.163228 -285.704205) (xy 173.201349 -285.67308)
			(xy 173.24397 -285.648473) (xy 173.289986 -285.631021) (xy 173.338205 -285.621177) (xy 173.38738 -285.619196)
			(xy 173.436235 -285.625128) (xy 173.483506 -285.63882) (xy 173.527968 -285.659918) (xy 173.568471 -285.687874)
			(xy 173.603964 -285.721966) (xy 173.633529 -285.76131) (xy 173.6564 -285.804887) (xy 173.671984 -285.851568)
			(xy 173.679879 -285.900145) (xy 173.680374 -285.924752) (xy 174.019222 -285.924752) (xy 174.023182 -285.875698)
			(xy 174.034959 -285.827914) (xy 174.05425 -285.782638) (xy 174.080553 -285.741042) (xy 174.113188 -285.704205)
			(xy 174.151309 -285.67308) (xy 174.19393 -285.648473) (xy 174.239946 -285.631021) (xy 174.288165 -285.621177)
			(xy 174.33734 -285.619196) (xy 174.386195 -285.625128) (xy 174.433466 -285.63882) (xy 174.477928 -285.659918)
			(xy 174.518431 -285.687874) (xy 174.553924 -285.721966) (xy 174.583489 -285.76131) (xy 174.60636 -285.804887)
			(xy 174.621944 -285.851568) (xy 174.629839 -285.900145) (xy 174.630334 -285.924752) (xy 175.919142 -285.924752)
			(xy 175.923102 -285.875698) (xy 175.934879 -285.827914) (xy 175.95417 -285.782638) (xy 175.980473 -285.741042)
			(xy 176.013108 -285.704205) (xy 176.051229 -285.67308) (xy 176.09385 -285.648473) (xy 176.139866 -285.631021)
			(xy 176.188085 -285.621177) (xy 176.23726 -285.619196) (xy 176.286115 -285.625128) (xy 176.333386 -285.63882)
			(xy 176.377848 -285.659918) (xy 176.418351 -285.687874) (xy 176.453844 -285.721966) (xy 176.483409 -285.76131)
			(xy 176.50628 -285.804887) (xy 176.521864 -285.851568) (xy 176.529759 -285.900145) (xy 176.530254 -285.924752)
			(xy 176.869102 -285.924752) (xy 176.873062 -285.875698) (xy 176.884839 -285.827914) (xy 176.90413 -285.782638)
			(xy 176.930433 -285.741042) (xy 176.963068 -285.704205) (xy 177.001189 -285.67308) (xy 177.04381 -285.648473)
			(xy 177.089826 -285.631021) (xy 177.138045 -285.621177) (xy 177.18722 -285.619196) (xy 177.236075 -285.625128)
			(xy 177.283346 -285.63882) (xy 177.327808 -285.659918) (xy 177.368311 -285.687874) (xy 177.403804 -285.721966)
			(xy 177.433369 -285.76131) (xy 177.45624 -285.804887) (xy 177.471824 -285.851568) (xy 177.479719 -285.900145)
			(xy 177.480214 -285.924752) (xy 177.819062 -285.924752) (xy 177.823022 -285.875698) (xy 177.834799 -285.827914)
			(xy 177.85409 -285.782638) (xy 177.880393 -285.741042) (xy 177.913028 -285.704205) (xy 177.951149 -285.67308)
			(xy 177.99377 -285.648473) (xy 178.039786 -285.631021) (xy 178.088005 -285.621177) (xy 178.13718 -285.619196)
			(xy 178.186035 -285.625128) (xy 178.233306 -285.63882) (xy 178.277768 -285.659918) (xy 178.318271 -285.687874)
			(xy 178.353764 -285.721966) (xy 178.383329 -285.76131) (xy 178.4062 -285.804887) (xy 178.421784 -285.851568)
			(xy 178.429679 -285.900145) (xy 178.430174 -285.924752) (xy 178.769276 -285.924752) (xy 178.773236 -285.875698)
			(xy 178.785013 -285.827914) (xy 178.804304 -285.782638) (xy 178.830607 -285.741042) (xy 178.863242 -285.704205)
			(xy 178.901363 -285.67308) (xy 178.943984 -285.648473) (xy 178.99 -285.631021) (xy 179.038219 -285.621177)
			(xy 179.087394 -285.619196) (xy 179.136249 -285.625128) (xy 179.18352 -285.63882) (xy 179.227982 -285.659918)
			(xy 179.268485 -285.687874) (xy 179.303978 -285.721966) (xy 179.333543 -285.76131) (xy 179.356414 -285.804887)
			(xy 179.371998 -285.851568) (xy 179.379893 -285.900145) (xy 179.380388 -285.924752) (xy 179.719236 -285.924752)
			(xy 179.723196 -285.875698) (xy 179.734973 -285.827914) (xy 179.754264 -285.782638) (xy 179.780567 -285.741042)
			(xy 179.813202 -285.704205) (xy 179.851323 -285.67308) (xy 179.893944 -285.648473) (xy 179.93996 -285.631021)
			(xy 179.988179 -285.621177) (xy 180.037354 -285.619196) (xy 180.086209 -285.625128) (xy 180.13348 -285.63882)
			(xy 180.177942 -285.659918) (xy 180.218445 -285.687874) (xy 180.253938 -285.721966) (xy 180.283503 -285.76131)
			(xy 180.306374 -285.804887) (xy 180.321958 -285.851568) (xy 180.329853 -285.900145) (xy 180.330348 -285.924752)
			(xy 180.669196 -285.924752) (xy 180.673156 -285.875698) (xy 180.684933 -285.827914) (xy 180.704224 -285.782638)
			(xy 180.730527 -285.741042) (xy 180.763162 -285.704205) (xy 180.801283 -285.67308) (xy 180.843904 -285.648473)
			(xy 180.88992 -285.631021) (xy 180.938139 -285.621177) (xy 180.987314 -285.619196) (xy 181.036169 -285.625128)
			(xy 181.08344 -285.63882) (xy 181.127902 -285.659918) (xy 181.168405 -285.687874) (xy 181.203898 -285.721966)
			(xy 181.233463 -285.76131) (xy 181.256334 -285.804887) (xy 181.271918 -285.851568) (xy 181.279813 -285.900145)
			(xy 181.280308 -285.924752) (xy 181.619156 -285.924752) (xy 181.623116 -285.875698) (xy 181.634893 -285.827914)
			(xy 181.654184 -285.782638) (xy 181.680487 -285.741042) (xy 181.713122 -285.704205) (xy 181.751243 -285.67308)
			(xy 181.793864 -285.648473) (xy 181.83988 -285.631021) (xy 181.888099 -285.621177) (xy 181.937274 -285.619196)
			(xy 181.986129 -285.625128) (xy 182.0334 -285.63882) (xy 182.077862 -285.659918) (xy 182.118365 -285.687874)
			(xy 182.153858 -285.721966) (xy 182.183423 -285.76131) (xy 182.206294 -285.804887) (xy 182.221878 -285.851568)
			(xy 182.229773 -285.900145) (xy 182.230268 -285.924752) (xy 182.569116 -285.924752) (xy 182.573076 -285.875698)
			(xy 182.584853 -285.827914) (xy 182.604144 -285.782638) (xy 182.630447 -285.741042) (xy 182.663082 -285.704205)
			(xy 182.701203 -285.67308) (xy 182.743824 -285.648473) (xy 182.78984 -285.631021) (xy 182.838059 -285.621177)
			(xy 182.887234 -285.619196) (xy 182.936089 -285.625128) (xy 182.98336 -285.63882) (xy 183.027822 -285.659918)
			(xy 183.068325 -285.687874) (xy 183.103818 -285.721966) (xy 183.133383 -285.76131) (xy 183.156254 -285.804887)
			(xy 183.171838 -285.851568) (xy 183.179733 -285.900145) (xy 183.180228 -285.924752) (xy 183.519076 -285.924752)
			(xy 183.523036 -285.875698) (xy 183.534813 -285.827914) (xy 183.554104 -285.782638) (xy 183.580407 -285.741042)
			(xy 183.613042 -285.704205) (xy 183.651163 -285.67308) (xy 183.693784 -285.648473) (xy 183.7398 -285.631021)
			(xy 183.788019 -285.621177) (xy 183.837194 -285.619196) (xy 183.886049 -285.625128) (xy 183.93332 -285.63882)
			(xy 183.977782 -285.659918) (xy 184.018285 -285.687874) (xy 184.053778 -285.721966) (xy 184.083343 -285.76131)
			(xy 184.106214 -285.804887) (xy 184.121798 -285.851568) (xy 184.129693 -285.900145) (xy 184.130188 -285.924752)
			(xy 184.469036 -285.924752) (xy 184.472996 -285.875698) (xy 184.484773 -285.827914) (xy 184.504064 -285.782638)
			(xy 184.530367 -285.741042) (xy 184.563002 -285.704205) (xy 184.601123 -285.67308) (xy 184.643744 -285.648473)
			(xy 184.68976 -285.631021) (xy 184.737979 -285.621177) (xy 184.787154 -285.619196) (xy 184.836009 -285.625128)
			(xy 184.88328 -285.63882) (xy 184.927742 -285.659918) (xy 184.968245 -285.687874) (xy 185.003738 -285.721966)
			(xy 185.033303 -285.76131) (xy 185.056174 -285.804887) (xy 185.071758 -285.851568) (xy 185.079653 -285.900145)
			(xy 185.080148 -285.924752) (xy 185.41925 -285.924752) (xy 185.42321 -285.875698) (xy 185.434987 -285.827914)
			(xy 185.454278 -285.782638) (xy 185.480581 -285.741042) (xy 185.513216 -285.704205) (xy 185.551337 -285.67308)
			(xy 185.593958 -285.648473) (xy 185.639974 -285.631021) (xy 185.688193 -285.621177) (xy 185.737368 -285.619196)
			(xy 185.786223 -285.625128) (xy 185.833494 -285.63882) (xy 185.877956 -285.659918) (xy 185.918459 -285.687874)
			(xy 185.953952 -285.721966) (xy 185.983517 -285.76131) (xy 186.006388 -285.804887) (xy 186.021972 -285.851568)
			(xy 186.029867 -285.900145) (xy 186.030362 -285.924752) (xy 186.36921 -285.924752) (xy 186.37317 -285.875698)
			(xy 186.384947 -285.827914) (xy 186.404238 -285.782638) (xy 186.430541 -285.741042) (xy 186.463176 -285.704205)
			(xy 186.501297 -285.67308) (xy 186.543918 -285.648473) (xy 186.589934 -285.631021) (xy 186.638153 -285.621177)
			(xy 186.687328 -285.619196) (xy 186.736183 -285.625128) (xy 186.783454 -285.63882) (xy 186.827916 -285.659918)
			(xy 186.868419 -285.687874) (xy 186.903912 -285.721966) (xy 186.933477 -285.76131) (xy 186.956348 -285.804887)
			(xy 186.971932 -285.851568) (xy 186.979827 -285.900145) (xy 186.980322 -285.924752) (xy 186.979827 -285.949359)
			(xy 186.971932 -285.997936) (xy 186.956348 -286.044617) (xy 186.933477 -286.088194) (xy 186.903912 -286.127538)
			(xy 186.868419 -286.16163) (xy 186.827916 -286.189586) (xy 186.783454 -286.210684) (xy 186.736183 -286.224376)
			(xy 186.687328 -286.230308) (xy 186.638153 -286.228327) (xy 186.589934 -286.218483) (xy 186.543918 -286.201031)
			(xy 186.501297 -286.176424) (xy 186.463176 -286.145299) (xy 186.430541 -286.108462) (xy 186.404238 -286.066866)
			(xy 186.384947 -286.02159) (xy 186.37317 -285.973806) (xy 186.36921 -285.924752) (xy 186.030362 -285.924752)
			(xy 186.029867 -285.949359) (xy 186.021972 -285.997936) (xy 186.006388 -286.044617) (xy 185.983517 -286.088194)
			(xy 185.953952 -286.127538) (xy 185.918459 -286.16163) (xy 185.877956 -286.189586) (xy 185.833494 -286.210684)
			(xy 185.786223 -286.224376) (xy 185.737368 -286.230308) (xy 185.688193 -286.228327) (xy 185.639974 -286.218483)
			(xy 185.593958 -286.201031) (xy 185.551337 -286.176424) (xy 185.513216 -286.145299) (xy 185.480581 -286.108462)
			(xy 185.454278 -286.066866) (xy 185.434987 -286.02159) (xy 185.42321 -285.973806) (xy 185.41925 -285.924752)
			(xy 185.080148 -285.924752) (xy 185.079653 -285.949359) (xy 185.071758 -285.997936) (xy 185.056174 -286.044617)
			(xy 185.033303 -286.088194) (xy 185.003738 -286.127538) (xy 184.968245 -286.16163) (xy 184.927742 -286.189586)
			(xy 184.88328 -286.210684) (xy 184.836009 -286.224376) (xy 184.787154 -286.230308) (xy 184.737979 -286.228327)
			(xy 184.68976 -286.218483) (xy 184.643744 -286.201031) (xy 184.601123 -286.176424) (xy 184.563002 -286.145299)
			(xy 184.530367 -286.108462) (xy 184.504064 -286.066866) (xy 184.484773 -286.02159) (xy 184.472996 -285.973806)
			(xy 184.469036 -285.924752) (xy 184.130188 -285.924752) (xy 184.129693 -285.949359) (xy 184.121798 -285.997936)
			(xy 184.106214 -286.044617) (xy 184.083343 -286.088194) (xy 184.053778 -286.127538) (xy 184.018285 -286.16163)
			(xy 183.977782 -286.189586) (xy 183.93332 -286.210684) (xy 183.886049 -286.224376) (xy 183.837194 -286.230308)
			(xy 183.788019 -286.228327) (xy 183.7398 -286.218483) (xy 183.693784 -286.201031) (xy 183.651163 -286.176424)
			(xy 183.613042 -286.145299) (xy 183.580407 -286.108462) (xy 183.554104 -286.066866) (xy 183.534813 -286.02159)
			(xy 183.523036 -285.973806) (xy 183.519076 -285.924752) (xy 183.180228 -285.924752) (xy 183.179733 -285.949359)
			(xy 183.171838 -285.997936) (xy 183.156254 -286.044617) (xy 183.133383 -286.088194) (xy 183.103818 -286.127538)
			(xy 183.068325 -286.16163) (xy 183.027822 -286.189586) (xy 182.98336 -286.210684) (xy 182.936089 -286.224376)
			(xy 182.887234 -286.230308) (xy 182.838059 -286.228327) (xy 182.78984 -286.218483) (xy 182.743824 -286.201031)
			(xy 182.701203 -286.176424) (xy 182.663082 -286.145299) (xy 182.630447 -286.108462) (xy 182.604144 -286.066866)
			(xy 182.584853 -286.02159) (xy 182.573076 -285.973806) (xy 182.569116 -285.924752) (xy 182.230268 -285.924752)
			(xy 182.229773 -285.949359) (xy 182.221878 -285.997936) (xy 182.206294 -286.044617) (xy 182.183423 -286.088194)
			(xy 182.153858 -286.127538) (xy 182.118365 -286.16163) (xy 182.077862 -286.189586) (xy 182.0334 -286.210684)
			(xy 181.986129 -286.224376) (xy 181.937274 -286.230308) (xy 181.888099 -286.228327) (xy 181.83988 -286.218483)
			(xy 181.793864 -286.201031) (xy 181.751243 -286.176424) (xy 181.713122 -286.145299) (xy 181.680487 -286.108462)
			(xy 181.654184 -286.066866) (xy 181.634893 -286.02159) (xy 181.623116 -285.973806) (xy 181.619156 -285.924752)
			(xy 181.280308 -285.924752) (xy 181.279813 -285.949359) (xy 181.271918 -285.997936) (xy 181.256334 -286.044617)
			(xy 181.233463 -286.088194) (xy 181.203898 -286.127538) (xy 181.168405 -286.16163) (xy 181.127902 -286.189586)
			(xy 181.08344 -286.210684) (xy 181.036169 -286.224376) (xy 180.987314 -286.230308) (xy 180.938139 -286.228327)
			(xy 180.88992 -286.218483) (xy 180.843904 -286.201031) (xy 180.801283 -286.176424) (xy 180.763162 -286.145299)
			(xy 180.730527 -286.108462) (xy 180.704224 -286.066866) (xy 180.684933 -286.02159) (xy 180.673156 -285.973806)
			(xy 180.669196 -285.924752) (xy 180.330348 -285.924752) (xy 180.329853 -285.949359) (xy 180.321958 -285.997936)
			(xy 180.306374 -286.044617) (xy 180.283503 -286.088194) (xy 180.253938 -286.127538) (xy 180.218445 -286.16163)
			(xy 180.177942 -286.189586) (xy 180.13348 -286.210684) (xy 180.086209 -286.224376) (xy 180.037354 -286.230308)
			(xy 179.988179 -286.228327) (xy 179.93996 -286.218483) (xy 179.893944 -286.201031) (xy 179.851323 -286.176424)
			(xy 179.813202 -286.145299) (xy 179.780567 -286.108462) (xy 179.754264 -286.066866) (xy 179.734973 -286.02159)
			(xy 179.723196 -285.973806) (xy 179.719236 -285.924752) (xy 179.380388 -285.924752) (xy 179.379893 -285.949359)
			(xy 179.371998 -285.997936) (xy 179.356414 -286.044617) (xy 179.333543 -286.088194) (xy 179.303978 -286.127538)
			(xy 179.268485 -286.16163) (xy 179.227982 -286.189586) (xy 179.18352 -286.210684) (xy 179.136249 -286.224376)
			(xy 179.087394 -286.230308) (xy 179.038219 -286.228327) (xy 178.99 -286.218483) (xy 178.943984 -286.201031)
			(xy 178.901363 -286.176424) (xy 178.863242 -286.145299) (xy 178.830607 -286.108462) (xy 178.804304 -286.066866)
			(xy 178.785013 -286.02159) (xy 178.773236 -285.973806) (xy 178.769276 -285.924752) (xy 178.430174 -285.924752)
			(xy 178.429679 -285.949359) (xy 178.421784 -285.997936) (xy 178.4062 -286.044617) (xy 178.383329 -286.088194)
			(xy 178.353764 -286.127538) (xy 178.318271 -286.16163) (xy 178.277768 -286.189586) (xy 178.233306 -286.210684)
			(xy 178.186035 -286.224376) (xy 178.13718 -286.230308) (xy 178.088005 -286.228327) (xy 178.039786 -286.218483)
			(xy 177.99377 -286.201031) (xy 177.951149 -286.176424) (xy 177.913028 -286.145299) (xy 177.880393 -286.108462)
			(xy 177.85409 -286.066866) (xy 177.834799 -286.02159) (xy 177.823022 -285.973806) (xy 177.819062 -285.924752)
			(xy 177.480214 -285.924752) (xy 177.479719 -285.949359) (xy 177.471824 -285.997936) (xy 177.45624 -286.044617)
			(xy 177.433369 -286.088194) (xy 177.403804 -286.127538) (xy 177.368311 -286.16163) (xy 177.327808 -286.189586)
			(xy 177.283346 -286.210684) (xy 177.236075 -286.224376) (xy 177.18722 -286.230308) (xy 177.138045 -286.228327)
			(xy 177.089826 -286.218483) (xy 177.04381 -286.201031) (xy 177.001189 -286.176424) (xy 176.963068 -286.145299)
			(xy 176.930433 -286.108462) (xy 176.90413 -286.066866) (xy 176.884839 -286.02159) (xy 176.873062 -285.973806)
			(xy 176.869102 -285.924752) (xy 176.530254 -285.924752) (xy 176.529759 -285.949359) (xy 176.521864 -285.997936)
			(xy 176.50628 -286.044617) (xy 176.483409 -286.088194) (xy 176.453844 -286.127538) (xy 176.418351 -286.16163)
			(xy 176.377848 -286.189586) (xy 176.333386 -286.210684) (xy 176.286115 -286.224376) (xy 176.23726 -286.230308)
			(xy 176.188085 -286.228327) (xy 176.139866 -286.218483) (xy 176.09385 -286.201031) (xy 176.051229 -286.176424)
			(xy 176.013108 -286.145299) (xy 175.980473 -286.108462) (xy 175.95417 -286.066866) (xy 175.934879 -286.02159)
			(xy 175.923102 -285.973806) (xy 175.919142 -285.924752) (xy 174.630334 -285.924752) (xy 174.629839 -285.949359)
			(xy 174.621944 -285.997936) (xy 174.60636 -286.044617) (xy 174.583489 -286.088194) (xy 174.553924 -286.127538)
			(xy 174.518431 -286.16163) (xy 174.477928 -286.189586) (xy 174.433466 -286.210684) (xy 174.386195 -286.224376)
			(xy 174.33734 -286.230308) (xy 174.288165 -286.228327) (xy 174.239946 -286.218483) (xy 174.19393 -286.201031)
			(xy 174.151309 -286.176424) (xy 174.113188 -286.145299) (xy 174.080553 -286.108462) (xy 174.05425 -286.066866)
			(xy 174.034959 -286.02159) (xy 174.023182 -285.973806) (xy 174.019222 -285.924752) (xy 173.680374 -285.924752)
			(xy 173.679879 -285.949359) (xy 173.671984 -285.997936) (xy 173.6564 -286.044617) (xy 173.633529 -286.088194)
			(xy 173.603964 -286.127538) (xy 173.568471 -286.16163) (xy 173.527968 -286.189586) (xy 173.483506 -286.210684)
			(xy 173.436235 -286.224376) (xy 173.38738 -286.230308) (xy 173.338205 -286.228327) (xy 173.289986 -286.218483)
			(xy 173.24397 -286.201031) (xy 173.201349 -286.176424) (xy 173.163228 -286.145299) (xy 173.130593 -286.108462)
			(xy 173.10429 -286.066866) (xy 173.084999 -286.02159) (xy 173.073222 -285.973806) (xy 173.069262 -285.924752)
			(xy 172.73016 -285.924752) (xy 172.729665 -285.949359) (xy 172.72177 -285.997936) (xy 172.706186 -286.044617)
			(xy 172.683315 -286.088194) (xy 172.65375 -286.127538) (xy 172.618257 -286.16163) (xy 172.577754 -286.189586)
			(xy 172.533292 -286.210684) (xy 172.486021 -286.224376) (xy 172.437166 -286.230308) (xy 172.387991 -286.228327)
			(xy 172.339772 -286.218483) (xy 172.293756 -286.201031) (xy 172.251135 -286.176424) (xy 172.213014 -286.145299)
			(xy 172.180379 -286.108462) (xy 172.154076 -286.066866) (xy 172.134785 -286.02159) (xy 172.123008 -285.973806)
			(xy 172.119048 -285.924752) (xy 171.7802 -285.924752) (xy 171.779705 -285.949359) (xy 171.77181 -285.997936)
			(xy 171.756226 -286.044617) (xy 171.733355 -286.088194) (xy 171.70379 -286.127538) (xy 171.668297 -286.16163)
			(xy 171.627794 -286.189586) (xy 171.583332 -286.210684) (xy 171.536061 -286.224376) (xy 171.487206 -286.230308)
			(xy 171.438031 -286.228327) (xy 171.389812 -286.218483) (xy 171.343796 -286.201031) (xy 171.301175 -286.176424)
			(xy 171.263054 -286.145299) (xy 171.230419 -286.108462) (xy 171.204116 -286.066866) (xy 171.184825 -286.02159)
			(xy 171.173048 -285.973806) (xy 171.169088 -285.924752) (xy 170.83024 -285.924752) (xy 170.829745 -285.949359)
			(xy 170.82185 -285.997936) (xy 170.806266 -286.044617) (xy 170.783395 -286.088194) (xy 170.75383 -286.127538)
			(xy 170.718337 -286.16163) (xy 170.677834 -286.189586) (xy 170.633372 -286.210684) (xy 170.586101 -286.224376)
			(xy 170.537246 -286.230308) (xy 170.488071 -286.228327) (xy 170.439852 -286.218483) (xy 170.393836 -286.201031)
			(xy 170.351215 -286.176424) (xy 170.313094 -286.145299) (xy 170.280459 -286.108462) (xy 170.254156 -286.066866)
			(xy 170.234865 -286.02159) (xy 170.223088 -285.973806) (xy 170.219128 -285.924752) (xy 169.88028 -285.924752)
			(xy 169.879785 -285.949359) (xy 169.87189 -285.997936) (xy 169.856306 -286.044617) (xy 169.833435 -286.088194)
			(xy 169.80387 -286.127538) (xy 169.768377 -286.16163) (xy 169.727874 -286.189586) (xy 169.683412 -286.210684)
			(xy 169.636141 -286.224376) (xy 169.587286 -286.230308) (xy 169.538111 -286.228327) (xy 169.489892 -286.218483)
			(xy 169.443876 -286.201031) (xy 169.401255 -286.176424) (xy 169.363134 -286.145299) (xy 169.330499 -286.108462)
			(xy 169.304196 -286.066866) (xy 169.284905 -286.02159) (xy 169.273128 -285.973806) (xy 169.269168 -285.924752)
			(xy 168.93032 -285.924752) (xy 168.929825 -285.949359) (xy 168.92193 -285.997936) (xy 168.906346 -286.044617)
			(xy 168.883475 -286.088194) (xy 168.85391 -286.127538) (xy 168.818417 -286.16163) (xy 168.777914 -286.189586)
			(xy 168.733452 -286.210684) (xy 168.686181 -286.224376) (xy 168.637326 -286.230308) (xy 168.588151 -286.228327)
			(xy 168.539932 -286.218483) (xy 168.493916 -286.201031) (xy 168.451295 -286.176424) (xy 168.413174 -286.145299)
			(xy 168.380539 -286.108462) (xy 168.354236 -286.066866) (xy 168.334945 -286.02159) (xy 168.323168 -285.973806)
			(xy 168.319208 -285.924752) (xy 167.98036 -285.924752) (xy 167.979865 -285.949359) (xy 167.97197 -285.997936)
			(xy 167.956386 -286.044617) (xy 167.933515 -286.088194) (xy 167.90395 -286.127538) (xy 167.868457 -286.16163)
			(xy 167.827954 -286.189586) (xy 167.783492 -286.210684) (xy 167.736221 -286.224376) (xy 167.687366 -286.230308)
			(xy 167.638191 -286.228327) (xy 167.589972 -286.218483) (xy 167.543956 -286.201031) (xy 167.501335 -286.176424)
			(xy 167.463214 -286.145299) (xy 167.430579 -286.108462) (xy 167.404276 -286.066866) (xy 167.384985 -286.02159)
			(xy 167.373208 -285.973806) (xy 167.369248 -285.924752) (xy 167.0304 -285.924752) (xy 167.029905 -285.949359)
			(xy 167.02201 -285.997936) (xy 167.006426 -286.044617) (xy 166.983555 -286.088194) (xy 166.95399 -286.127538)
			(xy 166.918497 -286.16163) (xy 166.877994 -286.189586) (xy 166.833532 -286.210684) (xy 166.786261 -286.224376)
			(xy 166.737406 -286.230308) (xy 166.688231 -286.228327) (xy 166.640012 -286.218483) (xy 166.593996 -286.201031)
			(xy 166.551375 -286.176424) (xy 166.513254 -286.145299) (xy 166.480619 -286.108462) (xy 166.454316 -286.066866)
			(xy 166.435025 -286.02159) (xy 166.423248 -285.973806) (xy 166.419288 -285.924752) (xy 166.080186 -285.924752)
			(xy 166.079691 -285.949359) (xy 166.071796 -285.997936) (xy 166.056212 -286.044617) (xy 166.033341 -286.088194)
			(xy 166.003776 -286.127538) (xy 165.968283 -286.16163) (xy 165.92778 -286.189586) (xy 165.883318 -286.210684)
			(xy 165.836047 -286.224376) (xy 165.787192 -286.230308) (xy 165.738017 -286.228327) (xy 165.689798 -286.218483)
			(xy 165.643782 -286.201031) (xy 165.601161 -286.176424) (xy 165.56304 -286.145299) (xy 165.530405 -286.108462)
			(xy 165.504102 -286.066866) (xy 165.484811 -286.02159) (xy 165.473034 -285.973806) (xy 165.469074 -285.924752)
			(xy 165.303708 -285.924752) (xy 165.303708 -286.399732) (xy 189.69407 -286.399732) (xy 189.69803 -286.350678)
			(xy 189.709807 -286.302894) (xy 189.729098 -286.257618) (xy 189.755401 -286.216022) (xy 189.788036 -286.179185)
			(xy 189.826157 -286.14806) (xy 189.868778 -286.123453) (xy 189.914794 -286.106001) (xy 189.963013 -286.096157)
			(xy 190.012188 -286.094176) (xy 190.061043 -286.100108) (xy 190.108314 -286.1138) (xy 190.152776 -286.134898)
			(xy 190.193279 -286.162854) (xy 190.228772 -286.196946) (xy 190.258337 -286.23629) (xy 190.281208 -286.279867)
			(xy 190.296792 -286.326548) (xy 190.304687 -286.375125) (xy 190.305182 -286.399732) (xy 190.644284 -286.399732)
			(xy 190.648244 -286.350678) (xy 190.660021 -286.302894) (xy 190.679312 -286.257618) (xy 190.705615 -286.216022)
			(xy 190.73825 -286.179185) (xy 190.776371 -286.14806) (xy 190.818992 -286.123453) (xy 190.865008 -286.106001)
			(xy 190.913227 -286.096157) (xy 190.962402 -286.094176) (xy 191.011257 -286.100108) (xy 191.058528 -286.1138)
			(xy 191.10299 -286.134898) (xy 191.143493 -286.162854) (xy 191.178986 -286.196946) (xy 191.208551 -286.23629)
			(xy 191.231422 -286.279867) (xy 191.247006 -286.326548) (xy 191.254901 -286.375125) (xy 191.255396 -286.399732)
			(xy 191.594244 -286.399732) (xy 191.598204 -286.350678) (xy 191.609981 -286.302894) (xy 191.629272 -286.257618)
			(xy 191.655575 -286.216022) (xy 191.68821 -286.179185) (xy 191.726331 -286.14806) (xy 191.768952 -286.123453)
			(xy 191.814968 -286.106001) (xy 191.863187 -286.096157) (xy 191.912362 -286.094176) (xy 191.961217 -286.100108)
			(xy 192.008488 -286.1138) (xy 192.05295 -286.134898) (xy 192.093453 -286.162854) (xy 192.128946 -286.196946)
			(xy 192.158511 -286.23629) (xy 192.181382 -286.279867) (xy 192.196966 -286.326548) (xy 192.204861 -286.375125)
			(xy 192.205356 -286.399732) (xy 192.204861 -286.424339) (xy 192.204641 -286.425694) (xy 192.52336 -286.425694)
			(xy 192.52336 -286.374278) (xy 192.531403 -286.323496) (xy 192.547291 -286.274597) (xy 192.570634 -286.228785)
			(xy 192.600855 -286.187189) (xy 192.637211 -286.150833) (xy 192.678807 -286.120612) (xy 192.724619 -286.097269)
			(xy 192.773518 -286.081381) (xy 192.8243 -286.073338) (xy 192.875716 -286.073338) (xy 192.926498 -286.081381)
			(xy 192.975397 -286.097269) (xy 193.021209 -286.120612) (xy 193.062805 -286.150833) (xy 193.099161 -286.187189)
			(xy 193.129382 -286.228785) (xy 193.152725 -286.274597) (xy 193.168613 -286.323496) (xy 193.176656 -286.374278)
			(xy 193.17716 -286.399986) (xy 193.176656 -286.425694) (xy 193.47332 -286.425694) (xy 193.47332 -286.374278)
			(xy 193.481363 -286.323496) (xy 193.497251 -286.274597) (xy 193.520594 -286.228785) (xy 193.550815 -286.187189)
			(xy 193.587171 -286.150833) (xy 193.628767 -286.120612) (xy 193.674579 -286.097269) (xy 193.723478 -286.081381)
			(xy 193.77426 -286.073338) (xy 193.825676 -286.073338) (xy 193.876458 -286.081381) (xy 193.925357 -286.097269)
			(xy 193.971169 -286.120612) (xy 194.012765 -286.150833) (xy 194.049121 -286.187189) (xy 194.079342 -286.228785)
			(xy 194.102685 -286.274597) (xy 194.118573 -286.323496) (xy 194.126616 -286.374278) (xy 194.127115 -286.399732)
			(xy 194.444124 -286.399732) (xy 194.448084 -286.350678) (xy 194.459861 -286.302894) (xy 194.479152 -286.257618)
			(xy 194.505455 -286.216022) (xy 194.53809 -286.179185) (xy 194.576211 -286.14806) (xy 194.618832 -286.123453)
			(xy 194.664848 -286.106001) (xy 194.713067 -286.096157) (xy 194.762242 -286.094176) (xy 194.811097 -286.100108)
			(xy 194.858368 -286.1138) (xy 194.90283 -286.134898) (xy 194.943333 -286.162854) (xy 194.978826 -286.196946)
			(xy 195.008391 -286.23629) (xy 195.031262 -286.279867) (xy 195.046846 -286.326548) (xy 195.054741 -286.375125)
			(xy 195.055236 -286.399732) (xy 195.054741 -286.424339) (xy 195.054562 -286.42544) (xy 195.37324 -286.42544)
			(xy 195.37324 -286.374024) (xy 195.381283 -286.323242) (xy 195.397171 -286.274343) (xy 195.420514 -286.228531)
			(xy 195.450735 -286.186935) (xy 195.487091 -286.150579) (xy 195.528687 -286.120358) (xy 195.574499 -286.097015)
			(xy 195.623398 -286.081127) (xy 195.67418 -286.073084) (xy 195.725596 -286.073084) (xy 195.776378 -286.081127)
			(xy 195.825277 -286.097015) (xy 195.871089 -286.120358) (xy 195.912685 -286.150579) (xy 195.949041 -286.186935)
			(xy 195.979262 -286.228531) (xy 196.002605 -286.274343) (xy 196.018493 -286.323242) (xy 196.026536 -286.374024)
			(xy 196.02704 -286.399732) (xy 196.026536 -286.42544) (xy 196.3232 -286.42544) (xy 196.3232 -286.374024)
			(xy 196.331243 -286.323242) (xy 196.347131 -286.274343) (xy 196.370474 -286.228531) (xy 196.400695 -286.186935)
			(xy 196.437051 -286.150579) (xy 196.478647 -286.120358) (xy 196.524459 -286.097015) (xy 196.573358 -286.081127)
			(xy 196.62414 -286.073084) (xy 196.675556 -286.073084) (xy 196.726338 -286.081127) (xy 196.775237 -286.097015)
			(xy 196.821049 -286.120358) (xy 196.862645 -286.150579) (xy 196.899001 -286.186935) (xy 196.929222 -286.228531)
			(xy 196.952565 -286.274343) (xy 196.968453 -286.323242) (xy 196.976496 -286.374024) (xy 196.977 -286.399732)
			(xy 197.294258 -286.399732) (xy 197.298218 -286.350678) (xy 197.309995 -286.302894) (xy 197.329286 -286.257618)
			(xy 197.355589 -286.216022) (xy 197.388224 -286.179185) (xy 197.426345 -286.14806) (xy 197.468966 -286.123453)
			(xy 197.514982 -286.106001) (xy 197.563201 -286.096157) (xy 197.612376 -286.094176) (xy 197.661231 -286.100108)
			(xy 197.708502 -286.1138) (xy 197.752964 -286.134898) (xy 197.793467 -286.162854) (xy 197.82896 -286.196946)
			(xy 197.858525 -286.23629) (xy 197.881396 -286.279867) (xy 197.89698 -286.326548) (xy 197.904875 -286.375125)
			(xy 197.90537 -286.399732) (xy 198.244218 -286.399732) (xy 198.248178 -286.350678) (xy 198.259955 -286.302894)
			(xy 198.279246 -286.257618) (xy 198.305549 -286.216022) (xy 198.338184 -286.179185) (xy 198.376305 -286.14806)
			(xy 198.418926 -286.123453) (xy 198.464942 -286.106001) (xy 198.513161 -286.096157) (xy 198.562336 -286.094176)
			(xy 198.611191 -286.100108) (xy 198.658462 -286.1138) (xy 198.702924 -286.134898) (xy 198.743427 -286.162854)
			(xy 198.77892 -286.196946) (xy 198.808485 -286.23629) (xy 198.831356 -286.279867) (xy 198.84694 -286.326548)
			(xy 198.854835 -286.375125) (xy 198.85533 -286.399732) (xy 198.854835 -286.424339) (xy 198.84694 -286.472916)
			(xy 198.831356 -286.519597) (xy 198.81708 -286.546798) (xy 207.650586 -286.546798) (xy 207.654657 -286.491176)
			(xy 207.666783 -286.436739) (xy 207.686706 -286.384648) (xy 207.714002 -286.336013) (xy 207.748088 -286.29187)
			(xy 207.788237 -286.253161) (xy 207.833595 -286.22071) (xy 207.883195 -286.195209) (xy 207.935979 -286.177202)
			(xy 207.990822 -286.167072) (xy 208.046556 -286.165035) (xy 208.101993 -286.171135) (xy 208.15595 -286.185241)
			(xy 208.207279 -286.207053) (xy 208.254885 -286.236107) (xy 208.297753 -286.271782) (xy 208.33497 -286.313319)
			(xy 208.365743 -286.359832) (xy 208.389415 -286.410329) (xy 208.405483 -286.463736) (xy 208.413603 -286.518912)
			(xy 208.414112 -286.546798) (xy 208.413603 -286.574684) (xy 208.405483 -286.62986) (xy 208.389415 -286.683267)
			(xy 208.365743 -286.733764) (xy 208.33497 -286.780277) (xy 208.297753 -286.821814) (xy 208.254885 -286.857489)
			(xy 208.207279 -286.886543) (xy 208.15595 -286.908355) (xy 208.101993 -286.922461) (xy 208.046556 -286.928561)
			(xy 207.990822 -286.926524) (xy 207.935979 -286.916394) (xy 207.883195 -286.898387) (xy 207.833595 -286.872886)
			(xy 207.788237 -286.840435) (xy 207.748088 -286.801726) (xy 207.714002 -286.757583) (xy 207.686706 -286.708948)
			(xy 207.666783 -286.656857) (xy 207.654657 -286.60242) (xy 207.650586 -286.546798) (xy 198.81708 -286.546798)
			(xy 198.808485 -286.563174) (xy 198.77892 -286.602518) (xy 198.743427 -286.63661) (xy 198.702924 -286.664566)
			(xy 198.658462 -286.685664) (xy 198.611191 -286.699356) (xy 198.562336 -286.705288) (xy 198.513161 -286.703307)
			(xy 198.464942 -286.693463) (xy 198.418926 -286.676011) (xy 198.376305 -286.651404) (xy 198.338184 -286.620279)
			(xy 198.305549 -286.583442) (xy 198.279246 -286.541846) (xy 198.259955 -286.49657) (xy 198.248178 -286.448786)
			(xy 198.244218 -286.399732) (xy 197.90537 -286.399732) (xy 197.904875 -286.424339) (xy 197.89698 -286.472916)
			(xy 197.881396 -286.519597) (xy 197.858525 -286.563174) (xy 197.82896 -286.602518) (xy 197.793467 -286.63661)
			(xy 197.752964 -286.664566) (xy 197.708502 -286.685664) (xy 197.661231 -286.699356) (xy 197.612376 -286.705288)
			(xy 197.563201 -286.703307) (xy 197.514982 -286.693463) (xy 197.468966 -286.676011) (xy 197.426345 -286.651404)
			(xy 197.388224 -286.620279) (xy 197.355589 -286.583442) (xy 197.329286 -286.541846) (xy 197.309995 -286.49657)
			(xy 197.298218 -286.448786) (xy 197.294258 -286.399732) (xy 196.977 -286.399732) (xy 196.976496 -286.42544)
			(xy 196.968453 -286.476222) (xy 196.952565 -286.525121) (xy 196.929222 -286.570933) (xy 196.899001 -286.612529)
			(xy 196.862645 -286.648885) (xy 196.821049 -286.679106) (xy 196.775237 -286.702449) (xy 196.726338 -286.718337)
			(xy 196.675556 -286.72638) (xy 196.62414 -286.72638) (xy 196.573358 -286.718337) (xy 196.524459 -286.702449)
			(xy 196.478647 -286.679106) (xy 196.437051 -286.648885) (xy 196.400695 -286.612529) (xy 196.370474 -286.570933)
			(xy 196.347131 -286.525121) (xy 196.331243 -286.476222) (xy 196.3232 -286.42544) (xy 196.026536 -286.42544)
			(xy 196.018493 -286.476222) (xy 196.002605 -286.525121) (xy 195.979262 -286.570933) (xy 195.949041 -286.612529)
			(xy 195.912685 -286.648885) (xy 195.871089 -286.679106) (xy 195.825277 -286.702449) (xy 195.776378 -286.718337)
			(xy 195.725596 -286.72638) (xy 195.67418 -286.72638) (xy 195.623398 -286.718337) (xy 195.574499 -286.702449)
			(xy 195.528687 -286.679106) (xy 195.487091 -286.648885) (xy 195.450735 -286.612529) (xy 195.420514 -286.570933)
			(xy 195.397171 -286.525121) (xy 195.381283 -286.476222) (xy 195.37324 -286.42544) (xy 195.054562 -286.42544)
			(xy 195.046846 -286.472916) (xy 195.031262 -286.519597) (xy 195.008391 -286.563174) (xy 194.978826 -286.602518)
			(xy 194.943333 -286.63661) (xy 194.90283 -286.664566) (xy 194.858368 -286.685664) (xy 194.811097 -286.699356)
			(xy 194.762242 -286.705288) (xy 194.713067 -286.703307) (xy 194.664848 -286.693463) (xy 194.618832 -286.676011)
			(xy 194.576211 -286.651404) (xy 194.53809 -286.620279) (xy 194.505455 -286.583442) (xy 194.479152 -286.541846)
			(xy 194.459861 -286.49657) (xy 194.448084 -286.448786) (xy 194.444124 -286.399732) (xy 194.127115 -286.399732)
			(xy 194.12712 -286.399986) (xy 194.126616 -286.425694) (xy 194.118573 -286.476476) (xy 194.102685 -286.525375)
			(xy 194.079342 -286.571187) (xy 194.049121 -286.612783) (xy 194.012765 -286.649139) (xy 193.971169 -286.67936)
			(xy 193.925357 -286.702703) (xy 193.876458 -286.718591) (xy 193.825676 -286.726634) (xy 193.77426 -286.726634)
			(xy 193.723478 -286.718591) (xy 193.674579 -286.702703) (xy 193.628767 -286.67936) (xy 193.587171 -286.649139)
			(xy 193.550815 -286.612783) (xy 193.520594 -286.571187) (xy 193.497251 -286.525375) (xy 193.481363 -286.476476)
			(xy 193.47332 -286.425694) (xy 193.176656 -286.425694) (xy 193.168613 -286.476476) (xy 193.152725 -286.525375)
			(xy 193.129382 -286.571187) (xy 193.099161 -286.612783) (xy 193.062805 -286.649139) (xy 193.021209 -286.67936)
			(xy 192.975397 -286.702703) (xy 192.926498 -286.718591) (xy 192.875716 -286.726634) (xy 192.8243 -286.726634)
			(xy 192.773518 -286.718591) (xy 192.724619 -286.702703) (xy 192.678807 -286.67936) (xy 192.637211 -286.649139)
			(xy 192.600855 -286.612783) (xy 192.570634 -286.571187) (xy 192.547291 -286.525375) (xy 192.531403 -286.476476)
			(xy 192.52336 -286.425694) (xy 192.204641 -286.425694) (xy 192.196966 -286.472916) (xy 192.181382 -286.519597)
			(xy 192.158511 -286.563174) (xy 192.128946 -286.602518) (xy 192.093453 -286.63661) (xy 192.05295 -286.664566)
			(xy 192.008488 -286.685664) (xy 191.961217 -286.699356) (xy 191.912362 -286.705288) (xy 191.863187 -286.703307)
			(xy 191.814968 -286.693463) (xy 191.768952 -286.676011) (xy 191.726331 -286.651404) (xy 191.68821 -286.620279)
			(xy 191.655575 -286.583442) (xy 191.629272 -286.541846) (xy 191.609981 -286.49657) (xy 191.598204 -286.448786)
			(xy 191.594244 -286.399732) (xy 191.255396 -286.399732) (xy 191.254901 -286.424339) (xy 191.247006 -286.472916)
			(xy 191.231422 -286.519597) (xy 191.208551 -286.563174) (xy 191.178986 -286.602518) (xy 191.143493 -286.63661)
			(xy 191.10299 -286.664566) (xy 191.058528 -286.685664) (xy 191.011257 -286.699356) (xy 190.962402 -286.705288)
			(xy 190.913227 -286.703307) (xy 190.865008 -286.693463) (xy 190.818992 -286.676011) (xy 190.776371 -286.651404)
			(xy 190.73825 -286.620279) (xy 190.705615 -286.583442) (xy 190.679312 -286.541846) (xy 190.660021 -286.49657)
			(xy 190.648244 -286.448786) (xy 190.644284 -286.399732) (xy 190.305182 -286.399732) (xy 190.304687 -286.424339)
			(xy 190.296792 -286.472916) (xy 190.281208 -286.519597) (xy 190.258337 -286.563174) (xy 190.228772 -286.602518)
			(xy 190.193279 -286.63661) (xy 190.152776 -286.664566) (xy 190.108314 -286.685664) (xy 190.061043 -286.699356)
			(xy 190.012188 -286.705288) (xy 189.963013 -286.703307) (xy 189.914794 -286.693463) (xy 189.868778 -286.676011)
			(xy 189.826157 -286.651404) (xy 189.788036 -286.620279) (xy 189.755401 -286.583442) (xy 189.729098 -286.541846)
			(xy 189.709807 -286.49657) (xy 189.69803 -286.448786) (xy 189.69407 -286.399732) (xy 165.303708 -286.399732)
			(xy 165.303708 -286.86125) (xy 165.30318 -286.871242) (xy 165.301625 -286.874966) (xy 165.469074 -286.874966)
			(xy 165.473034 -286.825912) (xy 165.484811 -286.778128) (xy 165.504102 -286.732852) (xy 165.530405 -286.691256)
			(xy 165.56304 -286.654419) (xy 165.601161 -286.623294) (xy 165.643782 -286.598687) (xy 165.689798 -286.581235)
			(xy 165.738017 -286.571391) (xy 165.787192 -286.56941) (xy 165.836047 -286.575342) (xy 165.883318 -286.589034)
			(xy 165.92778 -286.610132) (xy 165.968283 -286.638088) (xy 166.003776 -286.67218) (xy 166.033341 -286.711524)
			(xy 166.056212 -286.755101) (xy 166.071796 -286.801782) (xy 166.079691 -286.850359) (xy 166.080186 -286.874966)
			(xy 166.419288 -286.874966) (xy 166.423248 -286.825912) (xy 166.435025 -286.778128) (xy 166.454316 -286.732852)
			(xy 166.480619 -286.691256) (xy 166.513254 -286.654419) (xy 166.551375 -286.623294) (xy 166.593996 -286.598687)
			(xy 166.640012 -286.581235) (xy 166.688231 -286.571391) (xy 166.737406 -286.56941) (xy 166.786261 -286.575342)
			(xy 166.833532 -286.589034) (xy 166.877994 -286.610132) (xy 166.918497 -286.638088) (xy 166.95399 -286.67218)
			(xy 166.983555 -286.711524) (xy 167.006426 -286.755101) (xy 167.02201 -286.801782) (xy 167.029905 -286.850359)
			(xy 167.0304 -286.874966) (xy 167.369248 -286.874966) (xy 167.373208 -286.825912) (xy 167.384985 -286.778128)
			(xy 167.404276 -286.732852) (xy 167.430579 -286.691256) (xy 167.463214 -286.654419) (xy 167.501335 -286.623294)
			(xy 167.543956 -286.598687) (xy 167.589972 -286.581235) (xy 167.638191 -286.571391) (xy 167.687366 -286.56941)
			(xy 167.736221 -286.575342) (xy 167.783492 -286.589034) (xy 167.827954 -286.610132) (xy 167.868457 -286.638088)
			(xy 167.90395 -286.67218) (xy 167.933515 -286.711524) (xy 167.956386 -286.755101) (xy 167.97197 -286.801782)
			(xy 167.979865 -286.850359) (xy 167.98036 -286.874966) (xy 168.319208 -286.874966) (xy 168.323168 -286.825912)
			(xy 168.334945 -286.778128) (xy 168.354236 -286.732852) (xy 168.380539 -286.691256) (xy 168.413174 -286.654419)
			(xy 168.451295 -286.623294) (xy 168.493916 -286.598687) (xy 168.539932 -286.581235) (xy 168.588151 -286.571391)
			(xy 168.637326 -286.56941) (xy 168.686181 -286.575342) (xy 168.733452 -286.589034) (xy 168.777914 -286.610132)
			(xy 168.818417 -286.638088) (xy 168.85391 -286.67218) (xy 168.883475 -286.711524) (xy 168.906346 -286.755101)
			(xy 168.92193 -286.801782) (xy 168.929825 -286.850359) (xy 168.93032 -286.874966) (xy 169.269168 -286.874966)
			(xy 169.273128 -286.825912) (xy 169.284905 -286.778128) (xy 169.304196 -286.732852) (xy 169.330499 -286.691256)
			(xy 169.363134 -286.654419) (xy 169.401255 -286.623294) (xy 169.443876 -286.598687) (xy 169.489892 -286.581235)
			(xy 169.538111 -286.571391) (xy 169.587286 -286.56941) (xy 169.636141 -286.575342) (xy 169.683412 -286.589034)
			(xy 169.727874 -286.610132) (xy 169.768377 -286.638088) (xy 169.80387 -286.67218) (xy 169.833435 -286.711524)
			(xy 169.856306 -286.755101) (xy 169.87189 -286.801782) (xy 169.879785 -286.850359) (xy 169.88028 -286.874966)
			(xy 170.219128 -286.874966) (xy 170.223088 -286.825912) (xy 170.234865 -286.778128) (xy 170.254156 -286.732852)
			(xy 170.280459 -286.691256) (xy 170.313094 -286.654419) (xy 170.351215 -286.623294) (xy 170.393836 -286.598687)
			(xy 170.439852 -286.581235) (xy 170.488071 -286.571391) (xy 170.537246 -286.56941) (xy 170.586101 -286.575342)
			(xy 170.633372 -286.589034) (xy 170.677834 -286.610132) (xy 170.718337 -286.638088) (xy 170.75383 -286.67218)
			(xy 170.783395 -286.711524) (xy 170.806266 -286.755101) (xy 170.82185 -286.801782) (xy 170.829745 -286.850359)
			(xy 170.83024 -286.874966) (xy 171.169088 -286.874966) (xy 171.173048 -286.825912) (xy 171.184825 -286.778128)
			(xy 171.204116 -286.732852) (xy 171.230419 -286.691256) (xy 171.263054 -286.654419) (xy 171.301175 -286.623294)
			(xy 171.343796 -286.598687) (xy 171.389812 -286.581235) (xy 171.438031 -286.571391) (xy 171.487206 -286.56941)
			(xy 171.536061 -286.575342) (xy 171.583332 -286.589034) (xy 171.627794 -286.610132) (xy 171.668297 -286.638088)
			(xy 171.70379 -286.67218) (xy 171.733355 -286.711524) (xy 171.756226 -286.755101) (xy 171.77181 -286.801782)
			(xy 171.779705 -286.850359) (xy 171.7802 -286.874966) (xy 172.119048 -286.874966) (xy 172.123008 -286.825912)
			(xy 172.134785 -286.778128) (xy 172.154076 -286.732852) (xy 172.180379 -286.691256) (xy 172.213014 -286.654419)
			(xy 172.251135 -286.623294) (xy 172.293756 -286.598687) (xy 172.339772 -286.581235) (xy 172.387991 -286.571391)
			(xy 172.437166 -286.56941) (xy 172.486021 -286.575342) (xy 172.533292 -286.589034) (xy 172.577754 -286.610132)
			(xy 172.618257 -286.638088) (xy 172.65375 -286.67218) (xy 172.683315 -286.711524) (xy 172.706186 -286.755101)
			(xy 172.72177 -286.801782) (xy 172.729665 -286.850359) (xy 172.73016 -286.874966) (xy 173.069262 -286.874966)
			(xy 173.073222 -286.825912) (xy 173.084999 -286.778128) (xy 173.10429 -286.732852) (xy 173.130593 -286.691256)
			(xy 173.163228 -286.654419) (xy 173.201349 -286.623294) (xy 173.24397 -286.598687) (xy 173.289986 -286.581235)
			(xy 173.338205 -286.571391) (xy 173.38738 -286.56941) (xy 173.436235 -286.575342) (xy 173.483506 -286.589034)
			(xy 173.527968 -286.610132) (xy 173.568471 -286.638088) (xy 173.603964 -286.67218) (xy 173.633529 -286.711524)
			(xy 173.6564 -286.755101) (xy 173.671984 -286.801782) (xy 173.679879 -286.850359) (xy 173.680374 -286.874966)
			(xy 174.019222 -286.874966) (xy 174.023182 -286.825912) (xy 174.034959 -286.778128) (xy 174.05425 -286.732852)
			(xy 174.080553 -286.691256) (xy 174.113188 -286.654419) (xy 174.151309 -286.623294) (xy 174.19393 -286.598687)
			(xy 174.239946 -286.581235) (xy 174.288165 -286.571391) (xy 174.33734 -286.56941) (xy 174.386195 -286.575342)
			(xy 174.433466 -286.589034) (xy 174.477928 -286.610132) (xy 174.518431 -286.638088) (xy 174.553924 -286.67218)
			(xy 174.583489 -286.711524) (xy 174.60636 -286.755101) (xy 174.621944 -286.801782) (xy 174.629839 -286.850359)
			(xy 174.630334 -286.874966) (xy 175.919142 -286.874966) (xy 175.923102 -286.825912) (xy 175.934879 -286.778128)
			(xy 175.95417 -286.732852) (xy 175.980473 -286.691256) (xy 176.013108 -286.654419) (xy 176.051229 -286.623294)
			(xy 176.09385 -286.598687) (xy 176.139866 -286.581235) (xy 176.188085 -286.571391) (xy 176.23726 -286.56941)
			(xy 176.286115 -286.575342) (xy 176.333386 -286.589034) (xy 176.377848 -286.610132) (xy 176.418351 -286.638088)
			(xy 176.453844 -286.67218) (xy 176.483409 -286.711524) (xy 176.50628 -286.755101) (xy 176.521864 -286.801782)
			(xy 176.529759 -286.850359) (xy 176.530254 -286.874966) (xy 176.869102 -286.874966) (xy 176.873062 -286.825912)
			(xy 176.884839 -286.778128) (xy 176.90413 -286.732852) (xy 176.930433 -286.691256) (xy 176.963068 -286.654419)
			(xy 177.001189 -286.623294) (xy 177.04381 -286.598687) (xy 177.089826 -286.581235) (xy 177.138045 -286.571391)
			(xy 177.18722 -286.56941) (xy 177.236075 -286.575342) (xy 177.283346 -286.589034) (xy 177.327808 -286.610132)
			(xy 177.368311 -286.638088) (xy 177.403804 -286.67218) (xy 177.433369 -286.711524) (xy 177.45624 -286.755101)
			(xy 177.471824 -286.801782) (xy 177.479719 -286.850359) (xy 177.480214 -286.874966) (xy 177.819062 -286.874966)
			(xy 177.823022 -286.825912) (xy 177.834799 -286.778128) (xy 177.85409 -286.732852) (xy 177.880393 -286.691256)
			(xy 177.913028 -286.654419) (xy 177.951149 -286.623294) (xy 177.99377 -286.598687) (xy 178.039786 -286.581235)
			(xy 178.088005 -286.571391) (xy 178.13718 -286.56941) (xy 178.186035 -286.575342) (xy 178.233306 -286.589034)
			(xy 178.277768 -286.610132) (xy 178.318271 -286.638088) (xy 178.353764 -286.67218) (xy 178.383329 -286.711524)
			(xy 178.4062 -286.755101) (xy 178.421784 -286.801782) (xy 178.429679 -286.850359) (xy 178.430174 -286.874966)
			(xy 178.769276 -286.874966) (xy 178.773236 -286.825912) (xy 178.785013 -286.778128) (xy 178.804304 -286.732852)
			(xy 178.830607 -286.691256) (xy 178.863242 -286.654419) (xy 178.901363 -286.623294) (xy 178.943984 -286.598687)
			(xy 178.99 -286.581235) (xy 179.038219 -286.571391) (xy 179.087394 -286.56941) (xy 179.136249 -286.575342)
			(xy 179.18352 -286.589034) (xy 179.227982 -286.610132) (xy 179.268485 -286.638088) (xy 179.303978 -286.67218)
			(xy 179.333543 -286.711524) (xy 179.356414 -286.755101) (xy 179.371998 -286.801782) (xy 179.379893 -286.850359)
			(xy 179.380388 -286.874966) (xy 179.719236 -286.874966) (xy 179.723196 -286.825912) (xy 179.734973 -286.778128)
			(xy 179.754264 -286.732852) (xy 179.780567 -286.691256) (xy 179.813202 -286.654419) (xy 179.851323 -286.623294)
			(xy 179.893944 -286.598687) (xy 179.93996 -286.581235) (xy 179.988179 -286.571391) (xy 180.037354 -286.56941)
			(xy 180.086209 -286.575342) (xy 180.13348 -286.589034) (xy 180.177942 -286.610132) (xy 180.218445 -286.638088)
			(xy 180.253938 -286.67218) (xy 180.283503 -286.711524) (xy 180.306374 -286.755101) (xy 180.321958 -286.801782)
			(xy 180.329853 -286.850359) (xy 180.330348 -286.874966) (xy 180.669196 -286.874966) (xy 180.673156 -286.825912)
			(xy 180.684933 -286.778128) (xy 180.704224 -286.732852) (xy 180.730527 -286.691256) (xy 180.763162 -286.654419)
			(xy 180.801283 -286.623294) (xy 180.843904 -286.598687) (xy 180.88992 -286.581235) (xy 180.938139 -286.571391)
			(xy 180.987314 -286.56941) (xy 181.036169 -286.575342) (xy 181.08344 -286.589034) (xy 181.127902 -286.610132)
			(xy 181.168405 -286.638088) (xy 181.203898 -286.67218) (xy 181.233463 -286.711524) (xy 181.256334 -286.755101)
			(xy 181.271918 -286.801782) (xy 181.279813 -286.850359) (xy 181.280308 -286.874966) (xy 181.619156 -286.874966)
			(xy 181.623116 -286.825912) (xy 181.634893 -286.778128) (xy 181.654184 -286.732852) (xy 181.680487 -286.691256)
			(xy 181.713122 -286.654419) (xy 181.751243 -286.623294) (xy 181.793864 -286.598687) (xy 181.83988 -286.581235)
			(xy 181.888099 -286.571391) (xy 181.937274 -286.56941) (xy 181.986129 -286.575342) (xy 182.0334 -286.589034)
			(xy 182.077862 -286.610132) (xy 182.118365 -286.638088) (xy 182.153858 -286.67218) (xy 182.183423 -286.711524)
			(xy 182.206294 -286.755101) (xy 182.221878 -286.801782) (xy 182.229773 -286.850359) (xy 182.230268 -286.874966)
			(xy 182.569116 -286.874966) (xy 182.573076 -286.825912) (xy 182.584853 -286.778128) (xy 182.604144 -286.732852)
			(xy 182.630447 -286.691256) (xy 182.663082 -286.654419) (xy 182.701203 -286.623294) (xy 182.743824 -286.598687)
			(xy 182.78984 -286.581235) (xy 182.838059 -286.571391) (xy 182.887234 -286.56941) (xy 182.936089 -286.575342)
			(xy 182.98336 -286.589034) (xy 183.027822 -286.610132) (xy 183.068325 -286.638088) (xy 183.103818 -286.67218)
			(xy 183.133383 -286.711524) (xy 183.156254 -286.755101) (xy 183.171838 -286.801782) (xy 183.179733 -286.850359)
			(xy 183.180228 -286.874966) (xy 183.519076 -286.874966) (xy 183.523036 -286.825912) (xy 183.534813 -286.778128)
			(xy 183.554104 -286.732852) (xy 183.580407 -286.691256) (xy 183.613042 -286.654419) (xy 183.651163 -286.623294)
			(xy 183.693784 -286.598687) (xy 183.7398 -286.581235) (xy 183.788019 -286.571391) (xy 183.837194 -286.56941)
			(xy 183.886049 -286.575342) (xy 183.93332 -286.589034) (xy 183.977782 -286.610132) (xy 184.018285 -286.638088)
			(xy 184.053778 -286.67218) (xy 184.083343 -286.711524) (xy 184.106214 -286.755101) (xy 184.121798 -286.801782)
			(xy 184.129693 -286.850359) (xy 184.130188 -286.874966) (xy 184.469036 -286.874966) (xy 184.472996 -286.825912)
			(xy 184.484773 -286.778128) (xy 184.504064 -286.732852) (xy 184.530367 -286.691256) (xy 184.563002 -286.654419)
			(xy 184.601123 -286.623294) (xy 184.643744 -286.598687) (xy 184.68976 -286.581235) (xy 184.737979 -286.571391)
			(xy 184.787154 -286.56941) (xy 184.836009 -286.575342) (xy 184.88328 -286.589034) (xy 184.927742 -286.610132)
			(xy 184.968245 -286.638088) (xy 185.003738 -286.67218) (xy 185.033303 -286.711524) (xy 185.056174 -286.755101)
			(xy 185.071758 -286.801782) (xy 185.079653 -286.850359) (xy 185.080148 -286.874966) (xy 185.41925 -286.874966)
			(xy 185.42321 -286.825912) (xy 185.434987 -286.778128) (xy 185.454278 -286.732852) (xy 185.480581 -286.691256)
			(xy 185.513216 -286.654419) (xy 185.551337 -286.623294) (xy 185.593958 -286.598687) (xy 185.639974 -286.581235)
			(xy 185.688193 -286.571391) (xy 185.737368 -286.56941) (xy 185.786223 -286.575342) (xy 185.833494 -286.589034)
			(xy 185.877956 -286.610132) (xy 185.918459 -286.638088) (xy 185.953952 -286.67218) (xy 185.983517 -286.711524)
			(xy 186.006388 -286.755101) (xy 186.021972 -286.801782) (xy 186.029867 -286.850359) (xy 186.030362 -286.874966)
			(xy 186.36921 -286.874966) (xy 186.37317 -286.825912) (xy 186.384947 -286.778128) (xy 186.404238 -286.732852)
			(xy 186.430541 -286.691256) (xy 186.463176 -286.654419) (xy 186.501297 -286.623294) (xy 186.543918 -286.598687)
			(xy 186.589934 -286.581235) (xy 186.638153 -286.571391) (xy 186.687328 -286.56941) (xy 186.736183 -286.575342)
			(xy 186.783454 -286.589034) (xy 186.827916 -286.610132) (xy 186.868419 -286.638088) (xy 186.903912 -286.67218)
			(xy 186.933477 -286.711524) (xy 186.956348 -286.755101) (xy 186.971932 -286.801782) (xy 186.979827 -286.850359)
			(xy 186.980322 -286.874966) (xy 186.979827 -286.899573) (xy 186.971932 -286.94815) (xy 186.956348 -286.994831)
			(xy 186.933477 -287.038408) (xy 186.903912 -287.077752) (xy 186.868419 -287.111844) (xy 186.827916 -287.1398)
			(xy 186.783454 -287.160898) (xy 186.736183 -287.17459) (xy 186.687328 -287.180522) (xy 186.638153 -287.178541)
			(xy 186.589934 -287.168697) (xy 186.543918 -287.151245) (xy 186.501297 -287.126638) (xy 186.463176 -287.095513)
			(xy 186.430541 -287.058676) (xy 186.404238 -287.01708) (xy 186.384947 -286.971804) (xy 186.37317 -286.92402)
			(xy 186.36921 -286.874966) (xy 186.030362 -286.874966) (xy 186.029867 -286.899573) (xy 186.021972 -286.94815)
			(xy 186.006388 -286.994831) (xy 185.983517 -287.038408) (xy 185.953952 -287.077752) (xy 185.918459 -287.111844)
			(xy 185.877956 -287.1398) (xy 185.833494 -287.160898) (xy 185.786223 -287.17459) (xy 185.737368 -287.180522)
			(xy 185.688193 -287.178541) (xy 185.639974 -287.168697) (xy 185.593958 -287.151245) (xy 185.551337 -287.126638)
			(xy 185.513216 -287.095513) (xy 185.480581 -287.058676) (xy 185.454278 -287.01708) (xy 185.434987 -286.971804)
			(xy 185.42321 -286.92402) (xy 185.41925 -286.874966) (xy 185.080148 -286.874966) (xy 185.079653 -286.899573)
			(xy 185.071758 -286.94815) (xy 185.056174 -286.994831) (xy 185.033303 -287.038408) (xy 185.003738 -287.077752)
			(xy 184.968245 -287.111844) (xy 184.927742 -287.1398) (xy 184.88328 -287.160898) (xy 184.836009 -287.17459)
			(xy 184.787154 -287.180522) (xy 184.737979 -287.178541) (xy 184.68976 -287.168697) (xy 184.643744 -287.151245)
			(xy 184.601123 -287.126638) (xy 184.563002 -287.095513) (xy 184.530367 -287.058676) (xy 184.504064 -287.01708)
			(xy 184.484773 -286.971804) (xy 184.472996 -286.92402) (xy 184.469036 -286.874966) (xy 184.130188 -286.874966)
			(xy 184.129693 -286.899573) (xy 184.121798 -286.94815) (xy 184.106214 -286.994831) (xy 184.083343 -287.038408)
			(xy 184.053778 -287.077752) (xy 184.018285 -287.111844) (xy 183.977782 -287.1398) (xy 183.93332 -287.160898)
			(xy 183.886049 -287.17459) (xy 183.837194 -287.180522) (xy 183.788019 -287.178541) (xy 183.7398 -287.168697)
			(xy 183.693784 -287.151245) (xy 183.651163 -287.126638) (xy 183.613042 -287.095513) (xy 183.580407 -287.058676)
			(xy 183.554104 -287.01708) (xy 183.534813 -286.971804) (xy 183.523036 -286.92402) (xy 183.519076 -286.874966)
			(xy 183.180228 -286.874966) (xy 183.179733 -286.899573) (xy 183.171838 -286.94815) (xy 183.156254 -286.994831)
			(xy 183.133383 -287.038408) (xy 183.103818 -287.077752) (xy 183.068325 -287.111844) (xy 183.027822 -287.1398)
			(xy 182.98336 -287.160898) (xy 182.936089 -287.17459) (xy 182.887234 -287.180522) (xy 182.838059 -287.178541)
			(xy 182.78984 -287.168697) (xy 182.743824 -287.151245) (xy 182.701203 -287.126638) (xy 182.663082 -287.095513)
			(xy 182.630447 -287.058676) (xy 182.604144 -287.01708) (xy 182.584853 -286.971804) (xy 182.573076 -286.92402)
			(xy 182.569116 -286.874966) (xy 182.230268 -286.874966) (xy 182.229773 -286.899573) (xy 182.221878 -286.94815)
			(xy 182.206294 -286.994831) (xy 182.183423 -287.038408) (xy 182.153858 -287.077752) (xy 182.118365 -287.111844)
			(xy 182.077862 -287.1398) (xy 182.0334 -287.160898) (xy 181.986129 -287.17459) (xy 181.937274 -287.180522)
			(xy 181.888099 -287.178541) (xy 181.83988 -287.168697) (xy 181.793864 -287.151245) (xy 181.751243 -287.126638)
			(xy 181.713122 -287.095513) (xy 181.680487 -287.058676) (xy 181.654184 -287.01708) (xy 181.634893 -286.971804)
			(xy 181.623116 -286.92402) (xy 181.619156 -286.874966) (xy 181.280308 -286.874966) (xy 181.279813 -286.899573)
			(xy 181.271918 -286.94815) (xy 181.256334 -286.994831) (xy 181.233463 -287.038408) (xy 181.203898 -287.077752)
			(xy 181.168405 -287.111844) (xy 181.127902 -287.1398) (xy 181.08344 -287.160898) (xy 181.036169 -287.17459)
			(xy 180.987314 -287.180522) (xy 180.938139 -287.178541) (xy 180.88992 -287.168697) (xy 180.843904 -287.151245)
			(xy 180.801283 -287.126638) (xy 180.763162 -287.095513) (xy 180.730527 -287.058676) (xy 180.704224 -287.01708)
			(xy 180.684933 -286.971804) (xy 180.673156 -286.92402) (xy 180.669196 -286.874966) (xy 180.330348 -286.874966)
			(xy 180.329853 -286.899573) (xy 180.321958 -286.94815) (xy 180.306374 -286.994831) (xy 180.283503 -287.038408)
			(xy 180.253938 -287.077752) (xy 180.218445 -287.111844) (xy 180.177942 -287.1398) (xy 180.13348 -287.160898)
			(xy 180.086209 -287.17459) (xy 180.037354 -287.180522) (xy 179.988179 -287.178541) (xy 179.93996 -287.168697)
			(xy 179.893944 -287.151245) (xy 179.851323 -287.126638) (xy 179.813202 -287.095513) (xy 179.780567 -287.058676)
			(xy 179.754264 -287.01708) (xy 179.734973 -286.971804) (xy 179.723196 -286.92402) (xy 179.719236 -286.874966)
			(xy 179.380388 -286.874966) (xy 179.379893 -286.899573) (xy 179.371998 -286.94815) (xy 179.356414 -286.994831)
			(xy 179.333543 -287.038408) (xy 179.303978 -287.077752) (xy 179.268485 -287.111844) (xy 179.227982 -287.1398)
			(xy 179.18352 -287.160898) (xy 179.136249 -287.17459) (xy 179.087394 -287.180522) (xy 179.038219 -287.178541)
			(xy 178.99 -287.168697) (xy 178.943984 -287.151245) (xy 178.901363 -287.126638) (xy 178.863242 -287.095513)
			(xy 178.830607 -287.058676) (xy 178.804304 -287.01708) (xy 178.785013 -286.971804) (xy 178.773236 -286.92402)
			(xy 178.769276 -286.874966) (xy 178.430174 -286.874966) (xy 178.429679 -286.899573) (xy 178.421784 -286.94815)
			(xy 178.4062 -286.994831) (xy 178.383329 -287.038408) (xy 178.353764 -287.077752) (xy 178.318271 -287.111844)
			(xy 178.277768 -287.1398) (xy 178.233306 -287.160898) (xy 178.186035 -287.17459) (xy 178.13718 -287.180522)
			(xy 178.088005 -287.178541) (xy 178.039786 -287.168697) (xy 177.99377 -287.151245) (xy 177.951149 -287.126638)
			(xy 177.913028 -287.095513) (xy 177.880393 -287.058676) (xy 177.85409 -287.01708) (xy 177.834799 -286.971804)
			(xy 177.823022 -286.92402) (xy 177.819062 -286.874966) (xy 177.480214 -286.874966) (xy 177.479719 -286.899573)
			(xy 177.471824 -286.94815) (xy 177.45624 -286.994831) (xy 177.433369 -287.038408) (xy 177.403804 -287.077752)
			(xy 177.368311 -287.111844) (xy 177.327808 -287.1398) (xy 177.283346 -287.160898) (xy 177.236075 -287.17459)
			(xy 177.18722 -287.180522) (xy 177.138045 -287.178541) (xy 177.089826 -287.168697) (xy 177.04381 -287.151245)
			(xy 177.001189 -287.126638) (xy 176.963068 -287.095513) (xy 176.930433 -287.058676) (xy 176.90413 -287.01708)
			(xy 176.884839 -286.971804) (xy 176.873062 -286.92402) (xy 176.869102 -286.874966) (xy 176.530254 -286.874966)
			(xy 176.529759 -286.899573) (xy 176.521864 -286.94815) (xy 176.50628 -286.994831) (xy 176.483409 -287.038408)
			(xy 176.453844 -287.077752) (xy 176.418351 -287.111844) (xy 176.377848 -287.1398) (xy 176.333386 -287.160898)
			(xy 176.286115 -287.17459) (xy 176.23726 -287.180522) (xy 176.188085 -287.178541) (xy 176.139866 -287.168697)
			(xy 176.09385 -287.151245) (xy 176.051229 -287.126638) (xy 176.013108 -287.095513) (xy 175.980473 -287.058676)
			(xy 175.95417 -287.01708) (xy 175.934879 -286.971804) (xy 175.923102 -286.92402) (xy 175.919142 -286.874966)
			(xy 174.630334 -286.874966) (xy 174.629839 -286.899573) (xy 174.621944 -286.94815) (xy 174.60636 -286.994831)
			(xy 174.583489 -287.038408) (xy 174.553924 -287.077752) (xy 174.518431 -287.111844) (xy 174.477928 -287.1398)
			(xy 174.433466 -287.160898) (xy 174.386195 -287.17459) (xy 174.33734 -287.180522) (xy 174.288165 -287.178541)
			(xy 174.239946 -287.168697) (xy 174.19393 -287.151245) (xy 174.151309 -287.126638) (xy 174.113188 -287.095513)
			(xy 174.080553 -287.058676) (xy 174.05425 -287.01708) (xy 174.034959 -286.971804) (xy 174.023182 -286.92402)
			(xy 174.019222 -286.874966) (xy 173.680374 -286.874966) (xy 173.679879 -286.899573) (xy 173.671984 -286.94815)
			(xy 173.6564 -286.994831) (xy 173.633529 -287.038408) (xy 173.603964 -287.077752) (xy 173.568471 -287.111844)
			(xy 173.527968 -287.1398) (xy 173.483506 -287.160898) (xy 173.436235 -287.17459) (xy 173.38738 -287.180522)
			(xy 173.338205 -287.178541) (xy 173.289986 -287.168697) (xy 173.24397 -287.151245) (xy 173.201349 -287.126638)
			(xy 173.163228 -287.095513) (xy 173.130593 -287.058676) (xy 173.10429 -287.01708) (xy 173.084999 -286.971804)
			(xy 173.073222 -286.92402) (xy 173.069262 -286.874966) (xy 172.73016 -286.874966) (xy 172.729665 -286.899573)
			(xy 172.72177 -286.94815) (xy 172.706186 -286.994831) (xy 172.683315 -287.038408) (xy 172.65375 -287.077752)
			(xy 172.618257 -287.111844) (xy 172.577754 -287.1398) (xy 172.533292 -287.160898) (xy 172.486021 -287.17459)
			(xy 172.437166 -287.180522) (xy 172.387991 -287.178541) (xy 172.339772 -287.168697) (xy 172.293756 -287.151245)
			(xy 172.251135 -287.126638) (xy 172.213014 -287.095513) (xy 172.180379 -287.058676) (xy 172.154076 -287.01708)
			(xy 172.134785 -286.971804) (xy 172.123008 -286.92402) (xy 172.119048 -286.874966) (xy 171.7802 -286.874966)
			(xy 171.779705 -286.899573) (xy 171.77181 -286.94815) (xy 171.756226 -286.994831) (xy 171.733355 -287.038408)
			(xy 171.70379 -287.077752) (xy 171.668297 -287.111844) (xy 171.627794 -287.1398) (xy 171.583332 -287.160898)
			(xy 171.536061 -287.17459) (xy 171.487206 -287.180522) (xy 171.438031 -287.178541) (xy 171.389812 -287.168697)
			(xy 171.343796 -287.151245) (xy 171.301175 -287.126638) (xy 171.263054 -287.095513) (xy 171.230419 -287.058676)
			(xy 171.204116 -287.01708) (xy 171.184825 -286.971804) (xy 171.173048 -286.92402) (xy 171.169088 -286.874966)
			(xy 170.83024 -286.874966) (xy 170.829745 -286.899573) (xy 170.82185 -286.94815) (xy 170.806266 -286.994831)
			(xy 170.783395 -287.038408) (xy 170.75383 -287.077752) (xy 170.718337 -287.111844) (xy 170.677834 -287.1398)
			(xy 170.633372 -287.160898) (xy 170.586101 -287.17459) (xy 170.537246 -287.180522) (xy 170.488071 -287.178541)
			(xy 170.439852 -287.168697) (xy 170.393836 -287.151245) (xy 170.351215 -287.126638) (xy 170.313094 -287.095513)
			(xy 170.280459 -287.058676) (xy 170.254156 -287.01708) (xy 170.234865 -286.971804) (xy 170.223088 -286.92402)
			(xy 170.219128 -286.874966) (xy 169.88028 -286.874966) (xy 169.879785 -286.899573) (xy 169.87189 -286.94815)
			(xy 169.856306 -286.994831) (xy 169.833435 -287.038408) (xy 169.80387 -287.077752) (xy 169.768377 -287.111844)
			(xy 169.727874 -287.1398) (xy 169.683412 -287.160898) (xy 169.636141 -287.17459) (xy 169.587286 -287.180522)
			(xy 169.538111 -287.178541) (xy 169.489892 -287.168697) (xy 169.443876 -287.151245) (xy 169.401255 -287.126638)
			(xy 169.363134 -287.095513) (xy 169.330499 -287.058676) (xy 169.304196 -287.01708) (xy 169.284905 -286.971804)
			(xy 169.273128 -286.92402) (xy 169.269168 -286.874966) (xy 168.93032 -286.874966) (xy 168.929825 -286.899573)
			(xy 168.92193 -286.94815) (xy 168.906346 -286.994831) (xy 168.883475 -287.038408) (xy 168.85391 -287.077752)
			(xy 168.818417 -287.111844) (xy 168.777914 -287.1398) (xy 168.733452 -287.160898) (xy 168.686181 -287.17459)
			(xy 168.637326 -287.180522) (xy 168.588151 -287.178541) (xy 168.539932 -287.168697) (xy 168.493916 -287.151245)
			(xy 168.451295 -287.126638) (xy 168.413174 -287.095513) (xy 168.380539 -287.058676) (xy 168.354236 -287.01708)
			(xy 168.334945 -286.971804) (xy 168.323168 -286.92402) (xy 168.319208 -286.874966) (xy 167.98036 -286.874966)
			(xy 167.979865 -286.899573) (xy 167.97197 -286.94815) (xy 167.956386 -286.994831) (xy 167.933515 -287.038408)
			(xy 167.90395 -287.077752) (xy 167.868457 -287.111844) (xy 167.827954 -287.1398) (xy 167.783492 -287.160898)
			(xy 167.736221 -287.17459) (xy 167.687366 -287.180522) (xy 167.638191 -287.178541) (xy 167.589972 -287.168697)
			(xy 167.543956 -287.151245) (xy 167.501335 -287.126638) (xy 167.463214 -287.095513) (xy 167.430579 -287.058676)
			(xy 167.404276 -287.01708) (xy 167.384985 -286.971804) (xy 167.373208 -286.92402) (xy 167.369248 -286.874966)
			(xy 167.0304 -286.874966) (xy 167.029905 -286.899573) (xy 167.02201 -286.94815) (xy 167.006426 -286.994831)
			(xy 166.983555 -287.038408) (xy 166.95399 -287.077752) (xy 166.918497 -287.111844) (xy 166.877994 -287.1398)
			(xy 166.833532 -287.160898) (xy 166.786261 -287.17459) (xy 166.737406 -287.180522) (xy 166.688231 -287.178541)
			(xy 166.640012 -287.168697) (xy 166.593996 -287.151245) (xy 166.551375 -287.126638) (xy 166.513254 -287.095513)
			(xy 166.480619 -287.058676) (xy 166.454316 -287.01708) (xy 166.435025 -286.971804) (xy 166.423248 -286.92402)
			(xy 166.419288 -286.874966) (xy 166.080186 -286.874966) (xy 166.079691 -286.899573) (xy 166.071796 -286.94815)
			(xy 166.056212 -286.994831) (xy 166.033341 -287.038408) (xy 166.003776 -287.077752) (xy 165.968283 -287.111844)
			(xy 165.92778 -287.1398) (xy 165.883318 -287.160898) (xy 165.836047 -287.17459) (xy 165.787192 -287.180522)
			(xy 165.738017 -287.178541) (xy 165.689798 -287.168697) (xy 165.643782 -287.151245) (xy 165.601161 -287.126638)
			(xy 165.56304 -287.095513) (xy 165.530405 -287.058676) (xy 165.504102 -287.01708) (xy 165.484811 -286.971804)
			(xy 165.473034 -286.92402) (xy 165.469074 -286.874966) (xy 165.301625 -286.874966) (xy 165.29548 -286.889688)
			(xy 165.288722 -286.897064) (xy 165.283134 -286.902652) (xy 165.283134 -287.349946) (xy 189.69407 -287.349946)
			(xy 189.69803 -287.300892) (xy 189.709807 -287.253108) (xy 189.729098 -287.207832) (xy 189.755401 -287.166236)
			(xy 189.788036 -287.129399) (xy 189.826157 -287.098274) (xy 189.868778 -287.073667) (xy 189.914794 -287.056215)
			(xy 189.963013 -287.046371) (xy 190.012188 -287.04439) (xy 190.061043 -287.050322) (xy 190.108314 -287.064014)
			(xy 190.152776 -287.085112) (xy 190.193279 -287.113068) (xy 190.228772 -287.14716) (xy 190.258337 -287.186504)
			(xy 190.281208 -287.230081) (xy 190.296792 -287.276762) (xy 190.304687 -287.325339) (xy 190.305182 -287.349946)
			(xy 190.304687 -287.374553) (xy 190.304508 -287.375654) (xy 190.623186 -287.375654) (xy 190.623186 -287.324238)
			(xy 190.631229 -287.273456) (xy 190.647117 -287.224557) (xy 190.67046 -287.178745) (xy 190.700681 -287.137149)
			(xy 190.737037 -287.100793) (xy 190.778633 -287.070572) (xy 190.824445 -287.047229) (xy 190.873344 -287.031341)
			(xy 190.924126 -287.023298) (xy 190.975542 -287.023298) (xy 191.026324 -287.031341) (xy 191.075223 -287.047229)
			(xy 191.121035 -287.070572) (xy 191.162631 -287.100793) (xy 191.198987 -287.137149) (xy 191.229208 -287.178745)
			(xy 191.252551 -287.224557) (xy 191.268439 -287.273456) (xy 191.276482 -287.324238) (xy 191.276986 -287.349946)
			(xy 191.276482 -287.375654) (xy 191.5734 -287.375654) (xy 191.5734 -287.324238) (xy 191.581443 -287.273456)
			(xy 191.597331 -287.224557) (xy 191.620674 -287.178745) (xy 191.650895 -287.137149) (xy 191.687251 -287.100793)
			(xy 191.728847 -287.070572) (xy 191.774659 -287.047229) (xy 191.823558 -287.031341) (xy 191.87434 -287.023298)
			(xy 191.925756 -287.023298) (xy 191.976538 -287.031341) (xy 192.025437 -287.047229) (xy 192.071249 -287.070572)
			(xy 192.112845 -287.100793) (xy 192.149201 -287.137149) (xy 192.179422 -287.178745) (xy 192.202765 -287.224557)
			(xy 192.218653 -287.273456) (xy 192.226696 -287.324238) (xy 192.2272 -287.349946) (xy 192.544204 -287.349946)
			(xy 192.548164 -287.300892) (xy 192.559941 -287.253108) (xy 192.579232 -287.207832) (xy 192.605535 -287.166236)
			(xy 192.63817 -287.129399) (xy 192.676291 -287.098274) (xy 192.718912 -287.073667) (xy 192.764928 -287.056215)
			(xy 192.813147 -287.046371) (xy 192.862322 -287.04439) (xy 192.911177 -287.050322) (xy 192.958448 -287.064014)
			(xy 193.00291 -287.085112) (xy 193.043413 -287.113068) (xy 193.078906 -287.14716) (xy 193.108471 -287.186504)
			(xy 193.131342 -287.230081) (xy 193.146926 -287.276762) (xy 193.154821 -287.325339) (xy 193.155316 -287.349946)
			(xy 193.494164 -287.349946) (xy 193.498124 -287.300892) (xy 193.509901 -287.253108) (xy 193.529192 -287.207832)
			(xy 193.555495 -287.166236) (xy 193.58813 -287.129399) (xy 193.626251 -287.098274) (xy 193.668872 -287.073667)
			(xy 193.714888 -287.056215) (xy 193.763107 -287.046371) (xy 193.812282 -287.04439) (xy 193.861137 -287.050322)
			(xy 193.908408 -287.064014) (xy 193.95287 -287.085112) (xy 193.993373 -287.113068) (xy 194.028866 -287.14716)
			(xy 194.058431 -287.186504) (xy 194.081302 -287.230081) (xy 194.096886 -287.276762) (xy 194.104781 -287.325339)
			(xy 194.105276 -287.349946) (xy 194.444124 -287.349946) (xy 194.448084 -287.300892) (xy 194.459861 -287.253108)
			(xy 194.479152 -287.207832) (xy 194.505455 -287.166236) (xy 194.53809 -287.129399) (xy 194.576211 -287.098274)
			(xy 194.618832 -287.073667) (xy 194.664848 -287.056215) (xy 194.713067 -287.046371) (xy 194.762242 -287.04439)
			(xy 194.811097 -287.050322) (xy 194.858368 -287.064014) (xy 194.90283 -287.085112) (xy 194.943333 -287.113068)
			(xy 194.978826 -287.14716) (xy 195.008391 -287.186504) (xy 195.031262 -287.230081) (xy 195.046846 -287.276762)
			(xy 195.054741 -287.325339) (xy 195.055236 -287.349946) (xy 195.39383 -287.349946) (xy 195.39779 -287.300892)
			(xy 195.409567 -287.253108) (xy 195.428858 -287.207832) (xy 195.455161 -287.166236) (xy 195.487796 -287.129399)
			(xy 195.525917 -287.098274) (xy 195.568538 -287.073667) (xy 195.614554 -287.056215) (xy 195.662773 -287.046371)
			(xy 195.711948 -287.04439) (xy 195.760803 -287.050322) (xy 195.808074 -287.064014) (xy 195.852536 -287.085112)
			(xy 195.893039 -287.113068) (xy 195.928532 -287.14716) (xy 195.958097 -287.186504) (xy 195.980968 -287.230081)
			(xy 195.996552 -287.276762) (xy 196.004447 -287.325339) (xy 196.004942 -287.349946) (xy 196.344044 -287.349946)
			(xy 196.348004 -287.300892) (xy 196.359781 -287.253108) (xy 196.379072 -287.207832) (xy 196.405375 -287.166236)
			(xy 196.43801 -287.129399) (xy 196.476131 -287.098274) (xy 196.518752 -287.073667) (xy 196.564768 -287.056215)
			(xy 196.612987 -287.046371) (xy 196.662162 -287.04439) (xy 196.711017 -287.050322) (xy 196.758288 -287.064014)
			(xy 196.80275 -287.085112) (xy 196.843253 -287.113068) (xy 196.878746 -287.14716) (xy 196.908311 -287.186504)
			(xy 196.931182 -287.230081) (xy 196.946766 -287.276762) (xy 196.954661 -287.325339) (xy 196.955156 -287.349946)
			(xy 196.954661 -287.374553) (xy 196.954482 -287.375654) (xy 197.273414 -287.375654) (xy 197.273414 -287.324238)
			(xy 197.281457 -287.273456) (xy 197.297345 -287.224557) (xy 197.320688 -287.178745) (xy 197.350909 -287.137149)
			(xy 197.387265 -287.100793) (xy 197.428861 -287.070572) (xy 197.474673 -287.047229) (xy 197.523572 -287.031341)
			(xy 197.574354 -287.023298) (xy 197.62577 -287.023298) (xy 197.676552 -287.031341) (xy 197.725451 -287.047229)
			(xy 197.771263 -287.070572) (xy 197.812859 -287.100793) (xy 197.849215 -287.137149) (xy 197.879436 -287.178745)
			(xy 197.902779 -287.224557) (xy 197.918667 -287.273456) (xy 197.92671 -287.324238) (xy 197.927214 -287.349946)
			(xy 197.92671 -287.375654) (xy 198.223374 -287.375654) (xy 198.223374 -287.324238) (xy 198.231417 -287.273456)
			(xy 198.247305 -287.224557) (xy 198.270648 -287.178745) (xy 198.300869 -287.137149) (xy 198.337225 -287.100793)
			(xy 198.378821 -287.070572) (xy 198.424633 -287.047229) (xy 198.473532 -287.031341) (xy 198.524314 -287.023298)
			(xy 198.57573 -287.023298) (xy 198.626512 -287.031341) (xy 198.675411 -287.047229) (xy 198.721223 -287.070572)
			(xy 198.762819 -287.100793) (xy 198.799175 -287.137149) (xy 198.829396 -287.178745) (xy 198.852739 -287.224557)
			(xy 198.868627 -287.273456) (xy 198.87667 -287.324238) (xy 198.877174 -287.349946) (xy 198.877169 -287.3502)
			(xy 199.194432 -287.3502) (xy 199.198392 -287.301146) (xy 199.210169 -287.253362) (xy 199.22946 -287.208086)
			(xy 199.255763 -287.16649) (xy 199.288398 -287.129653) (xy 199.326519 -287.098528) (xy 199.36914 -287.073921)
			(xy 199.415156 -287.056469) (xy 199.463375 -287.046625) (xy 199.51255 -287.044644) (xy 199.561405 -287.050576)
			(xy 199.608676 -287.064268) (xy 199.653138 -287.085366) (xy 199.676484 -287.10148) (xy 208.388969 -287.10148)
			(xy 208.388969 -287.044184) (xy 208.397123 -286.98747) (xy 208.413266 -286.932495) (xy 208.437067 -286.880376)
			(xy 208.468044 -286.832175) (xy 208.505565 -286.788873) (xy 208.548867 -286.751352) (xy 208.597068 -286.720375)
			(xy 208.649187 -286.696574) (xy 208.704162 -286.680431) (xy 208.760876 -286.672277) (xy 208.818172 -286.672277)
			(xy 208.874886 -286.680431) (xy 208.929861 -286.696574) (xy 208.98198 -286.720375) (xy 209.030181 -286.751352)
			(xy 209.073483 -286.788873) (xy 209.111004 -286.832175) (xy 209.141981 -286.880376) (xy 209.165782 -286.932495)
			(xy 209.181925 -286.98747) (xy 209.190079 -287.044184) (xy 209.19059 -287.072832) (xy 209.190079 -287.10148)
			(xy 209.185612 -287.132547) (xy 216.952122 -287.132547) (xy 216.952122 -287.078053) (xy 216.959877 -287.024115)
			(xy 216.975229 -286.971829) (xy 216.997865 -286.922259) (xy 217.027325 -286.876416) (xy 217.063009 -286.835231)
			(xy 217.10419 -286.799544) (xy 217.150031 -286.77008) (xy 217.199599 -286.74744) (xy 217.251883 -286.732084)
			(xy 217.305821 -286.724324) (xy 217.333068 -286.723836) (xy 217.361808 -286.724335) (xy 217.418635 -286.732967)
			(xy 217.473526 -286.750023) (xy 217.525237 -286.77512) (xy 217.572599 -286.807688) (xy 217.593926 -286.82696)
			(xy 217.601038 -286.833564) (xy 217.618564 -286.840676) (xy 217.707972 -286.840676) (xy 217.725498 -286.833564)
			(xy 217.73261 -286.82696) (xy 217.753953 -286.807708) (xy 217.801311 -286.775138) (xy 217.853018 -286.750042)
			(xy 217.907905 -286.732987) (xy 217.96473 -286.724359) (xy 217.993468 -286.723836) (xy 218.02359 -286.724431)
			(xy 218.083085 -286.733907) (xy 218.140353 -286.752612) (xy 218.19397 -286.780082) (xy 218.242606 -286.815636)
			(xy 218.264232 -286.836612) (xy 218.271344 -286.843978) (xy 218.29014 -286.851598) (xy 218.382596 -286.851598)
			(xy 218.401392 -286.843978) (xy 218.408504 -286.836612) (xy 218.430106 -286.815607) (xy 218.478741 -286.780041)
			(xy 218.532363 -286.752566) (xy 218.589638 -286.733863) (xy 218.649142 -286.7244) (xy 218.679268 -286.723836)
			(xy 218.706638 -286.724312) (xy 218.760817 -286.732126) (xy 218.81332 -286.747612) (xy 218.863067 -286.770452)
			(xy 218.909034 -286.800175) (xy 218.929966 -286.817816) (xy 218.937078 -286.823912) (xy 218.954096 -286.830262)
			(xy 219.03944 -286.830262) (xy 219.056458 -286.823912) (xy 219.06357 -286.817816) (xy 219.084505 -286.80018)
			(xy 219.130476 -286.770467) (xy 219.180223 -286.74763) (xy 219.232724 -286.732139) (xy 219.286899 -286.72431)
			(xy 219.314268 -286.723836) (xy 219.341526 -286.724209) (xy 219.395486 -286.731963) (xy 219.447794 -286.747318)
			(xy 219.497384 -286.769961) (xy 219.543246 -286.799432) (xy 219.584448 -286.83513) (xy 219.620149 -286.876328)
			(xy 219.649623 -286.922188) (xy 219.672271 -286.971776) (xy 219.68763 -287.024083) (xy 219.695389 -287.078043)
			(xy 219.695389 -287.132546) (xy 220.945522 -287.132546) (xy 220.945522 -287.078054) (xy 220.953276 -287.024116)
			(xy 220.968628 -286.971831) (xy 220.991263 -286.922263) (xy 221.020722 -286.87642) (xy 221.056404 -286.835235)
			(xy 221.097584 -286.799548) (xy 221.143424 -286.770084) (xy 221.19299 -286.747443) (xy 221.245273 -286.732086)
			(xy 221.29921 -286.724325) (xy 221.326456 -286.723836) (xy 221.355195 -286.724343) (xy 221.412023 -286.732972)
			(xy 221.466913 -286.750027) (xy 221.518624 -286.775122) (xy 221.565987 -286.807689) (xy 221.587314 -286.82696)
			(xy 221.594426 -286.833564) (xy 221.611952 -286.840676) (xy 221.70136 -286.840676) (xy 221.718886 -286.833564)
			(xy 221.725998 -286.82696) (xy 221.747325 -286.80769) (xy 221.794688 -286.775125) (xy 221.846399 -286.750034)
			(xy 221.90129 -286.732984) (xy 221.958117 -286.724362) (xy 222.015595 -286.724362) (xy 222.072422 -286.732984)
			(xy 222.127313 -286.750034) (xy 222.179024 -286.775125) (xy 222.226387 -286.80769) (xy 222.247714 -286.82696)
			(xy 222.254826 -286.833564) (xy 222.272352 -286.840676) (xy 222.36176 -286.840676) (xy 222.379286 -286.833564)
			(xy 222.386398 -286.82696) (xy 222.407705 -286.807666) (xy 222.455072 -286.775102) (xy 222.506789 -286.750014)
			(xy 222.561684 -286.732969) (xy 222.618516 -286.724353) (xy 222.647256 -286.723836) (xy 222.677378 -286.724438)
			(xy 222.736873 -286.733912) (xy 222.79414 -286.752616) (xy 222.847758 -286.780085) (xy 222.896394 -286.815636)
			(xy 222.91802 -286.836612) (xy 222.925132 -286.843978) (xy 222.943928 -286.851598) (xy 223.036384 -286.851598)
			(xy 223.05518 -286.843978) (xy 223.062292 -286.836612) (xy 223.083899 -286.815613) (xy 223.132533 -286.780046)
			(xy 223.186153 -286.75257) (xy 223.243428 -286.733866) (xy 223.30293 -286.724401) (xy 223.333056 -286.723836)
			(xy 223.360314 -286.724208) (xy 223.414276 -286.731961) (xy 223.466585 -286.747315) (xy 223.516177 -286.769957)
			(xy 223.562041 -286.799428) (xy 223.603243 -286.835125) (xy 223.638946 -286.876324) (xy 223.668422 -286.922185)
			(xy 223.69107 -286.971773) (xy 223.70643 -287.024081) (xy 223.714189 -287.078042) (xy 223.714189 -287.132558)
			(xy 223.70643 -287.186519) (xy 223.69107 -287.238827) (xy 223.668422 -287.288415) (xy 223.638946 -287.334276)
			(xy 223.603243 -287.375475) (xy 223.562041 -287.411172) (xy 223.516177 -287.440643) (xy 223.466585 -287.463285)
			(xy 223.414276 -287.478639) (xy 223.360314 -287.486392) (xy 223.333056 -287.486852) (xy 223.302934 -287.486245)
			(xy 223.243439 -287.476773) (xy 223.186172 -287.45807) (xy 223.132554 -287.430602) (xy 223.083918 -287.395051)
			(xy 223.062292 -287.374076) (xy 223.05518 -287.36671) (xy 223.036384 -287.35909) (xy 222.943928 -287.35909)
			(xy 222.925132 -287.36671) (xy 222.91802 -287.374076) (xy 222.896406 -287.395068) (xy 222.847774 -287.430635)
			(xy 222.794155 -287.458114) (xy 222.736883 -287.476819) (xy 222.677381 -287.486286) (xy 222.647256 -287.486852)
			(xy 222.618517 -287.486341) (xy 222.561689 -287.477713) (xy 222.506799 -287.460659) (xy 222.455088 -287.435565)
			(xy 222.407725 -287.402999) (xy 222.386398 -287.383728) (xy 222.379286 -287.377124) (xy 222.36176 -287.370012)
			(xy 222.272352 -287.370012) (xy 222.254826 -287.377124) (xy 222.247714 -287.383728) (xy 222.226387 -287.402998)
			(xy 222.179024 -287.435563) (xy 222.127313 -287.460654) (xy 222.072422 -287.477704) (xy 222.015595 -287.486326)
			(xy 221.958117 -287.486326) (xy 221.90129 -287.477704) (xy 221.846399 -287.460654) (xy 221.794688 -287.435563)
			(xy 221.747325 -287.402998) (xy 221.725998 -287.383728) (xy 221.718886 -287.377124) (xy 221.70136 -287.370012)
			(xy 221.611952 -287.370012) (xy 221.594426 -287.377124) (xy 221.587314 -287.383728) (xy 221.566 -287.403014)
			(xy 221.518635 -287.435579) (xy 221.46692 -287.46067) (xy 221.412026 -287.477716) (xy 221.355196 -287.486334)
			(xy 221.326456 -287.486852) (xy 221.29921 -287.486275) (xy 221.245273 -287.478514) (xy 221.19299 -287.463157)
			(xy 221.143424 -287.440516) (xy 221.097584 -287.411052) (xy 221.056404 -287.375365) (xy 221.020722 -287.33418)
			(xy 220.991263 -287.288337) (xy 220.968628 -287.238769) (xy 220.953276 -287.186484) (xy 220.945522 -287.132546)
			(xy 219.695389 -287.132546) (xy 219.695389 -287.132557) (xy 219.68763 -287.186517) (xy 219.672271 -287.238824)
			(xy 219.649623 -287.288412) (xy 219.620149 -287.334272) (xy 219.584448 -287.37547) (xy 219.543246 -287.411168)
			(xy 219.497384 -287.440639) (xy 219.447794 -287.463282) (xy 219.395486 -287.478637) (xy 219.341526 -287.486391)
			(xy 219.314268 -287.486852) (xy 219.286897 -287.486416) (xy 219.232716 -287.478593) (xy 219.180212 -287.463097)
			(xy 219.130465 -287.440249) (xy 219.0845 -287.410517) (xy 219.06357 -287.392872) (xy 219.056458 -287.386776)
			(xy 219.03944 -287.380426) (xy 218.954096 -287.380426) (xy 218.937078 -287.386776) (xy 218.929966 -287.392872)
			(xy 218.909016 -287.410489) (xy 218.863049 -287.440205) (xy 218.813306 -287.463046) (xy 218.760809 -287.478542)
			(xy 218.706636 -287.486375) (xy 218.679268 -287.486852) (xy 218.649144 -287.486301) (xy 218.589647 -287.476815)
			(xy 218.532378 -287.458099) (xy 218.478762 -287.430619) (xy 218.430128 -287.395057) (xy 218.408504 -287.374076)
			(xy 218.401392 -287.36671) (xy 218.382596 -287.35909) (xy 218.29014 -287.35909) (xy 218.271344 -287.36671)
			(xy 218.264232 -287.374076) (xy 218.242612 -287.395062) (xy 218.193983 -287.43063) (xy 218.140365 -287.45811)
			(xy 218.083093 -287.476817) (xy 218.023593 -287.486285) (xy 217.993468 -287.486852) (xy 217.964729 -287.486334)
			(xy 217.907902 -287.477708) (xy 217.853012 -287.460656) (xy 217.8013 -287.435563) (xy 217.753937 -287.402998)
			(xy 217.73261 -287.383728) (xy 217.725498 -287.377124) (xy 217.707972 -287.370012) (xy 217.618564 -287.370012)
			(xy 217.601038 -287.377124) (xy 217.593926 -287.383728) (xy 217.572607 -287.403008) (xy 217.525243 -287.435574)
			(xy 217.47353 -287.460666) (xy 217.418637 -287.477714) (xy 217.361808 -287.486333) (xy 217.333068 -287.486852)
			(xy 217.305821 -287.486276) (xy 217.251883 -287.478516) (xy 217.199599 -287.46316) (xy 217.150031 -287.44052)
			(xy 217.10419 -287.411056) (xy 217.063009 -287.375369) (xy 217.027325 -287.334184) (xy 216.997865 -287.288341)
			(xy 216.975229 -287.238771) (xy 216.959877 -287.186485) (xy 216.952122 -287.132547) (xy 209.185612 -287.132547)
			(xy 209.181925 -287.158194) (xy 209.165782 -287.213169) (xy 209.141981 -287.265288) (xy 209.111004 -287.313489)
			(xy 209.073483 -287.356791) (xy 209.030181 -287.394312) (xy 208.98198 -287.425289) (xy 208.929861 -287.44909)
			(xy 208.874886 -287.465233) (xy 208.818172 -287.473387) (xy 208.760876 -287.473387) (xy 208.704162 -287.465233)
			(xy 208.649187 -287.44909) (xy 208.597068 -287.425289) (xy 208.548867 -287.394312) (xy 208.505565 -287.356791)
			(xy 208.468044 -287.313489) (xy 208.437067 -287.265288) (xy 208.413266 -287.213169) (xy 208.397123 -287.158194)
			(xy 208.388969 -287.10148) (xy 199.676484 -287.10148) (xy 199.693641 -287.113322) (xy 199.729134 -287.147414)
			(xy 199.758699 -287.186758) (xy 199.78157 -287.230335) (xy 199.797154 -287.277016) (xy 199.805049 -287.325593)
			(xy 199.805544 -287.3502) (xy 199.805049 -287.374807) (xy 199.797154 -287.423384) (xy 199.78157 -287.470065)
			(xy 199.758699 -287.513642) (xy 199.729134 -287.552986) (xy 199.693641 -287.587078) (xy 199.653138 -287.615034)
			(xy 199.608676 -287.636132) (xy 199.561405 -287.649824) (xy 199.51255 -287.655756) (xy 199.463375 -287.653775)
			(xy 199.415156 -287.643931) (xy 199.36914 -287.626479) (xy 199.326519 -287.601872) (xy 199.288398 -287.570747)
			(xy 199.255763 -287.53391) (xy 199.22946 -287.492314) (xy 199.210169 -287.447038) (xy 199.198392 -287.399254)
			(xy 199.194432 -287.3502) (xy 198.877169 -287.3502) (xy 198.87667 -287.375654) (xy 198.868627 -287.426436)
			(xy 198.852739 -287.475335) (xy 198.829396 -287.521147) (xy 198.799175 -287.562743) (xy 198.762819 -287.599099)
			(xy 198.721223 -287.62932) (xy 198.675411 -287.652663) (xy 198.626512 -287.668551) (xy 198.57573 -287.676594)
			(xy 198.524314 -287.676594) (xy 198.473532 -287.668551) (xy 198.424633 -287.652663) (xy 198.378821 -287.62932)
			(xy 198.337225 -287.599099) (xy 198.300869 -287.562743) (xy 198.270648 -287.521147) (xy 198.247305 -287.475335)
			(xy 198.231417 -287.426436) (xy 198.223374 -287.375654) (xy 197.92671 -287.375654) (xy 197.918667 -287.426436)
			(xy 197.902779 -287.475335) (xy 197.879436 -287.521147) (xy 197.849215 -287.562743) (xy 197.812859 -287.599099)
			(xy 197.771263 -287.62932) (xy 197.725451 -287.652663) (xy 197.676552 -287.668551) (xy 197.62577 -287.676594)
			(xy 197.574354 -287.676594) (xy 197.523572 -287.668551) (xy 197.474673 -287.652663) (xy 197.428861 -287.62932)
			(xy 197.387265 -287.599099) (xy 197.350909 -287.562743) (xy 197.320688 -287.521147) (xy 197.297345 -287.475335)
			(xy 197.281457 -287.426436) (xy 197.273414 -287.375654) (xy 196.954482 -287.375654) (xy 196.946766 -287.42313)
			(xy 196.931182 -287.469811) (xy 196.908311 -287.513388) (xy 196.878746 -287.552732) (xy 196.843253 -287.586824)
			(xy 196.80275 -287.61478) (xy 196.758288 -287.635878) (xy 196.711017 -287.64957) (xy 196.662162 -287.655502)
			(xy 196.612987 -287.653521) (xy 196.564768 -287.643677) (xy 196.518752 -287.626225) (xy 196.476131 -287.601618)
			(xy 196.43801 -287.570493) (xy 196.405375 -287.533656) (xy 196.379072 -287.49206) (xy 196.359781 -287.446784)
			(xy 196.348004 -287.399) (xy 196.344044 -287.349946) (xy 196.004942 -287.349946) (xy 196.004447 -287.374553)
			(xy 195.996552 -287.42313) (xy 195.980968 -287.469811) (xy 195.958097 -287.513388) (xy 195.928532 -287.552732)
			(xy 195.893039 -287.586824) (xy 195.852536 -287.61478) (xy 195.808074 -287.635878) (xy 195.760803 -287.64957)
			(xy 195.711948 -287.655502) (xy 195.662773 -287.653521) (xy 195.614554 -287.643677) (xy 195.568538 -287.626225)
			(xy 195.525917 -287.601618) (xy 195.487796 -287.570493) (xy 195.455161 -287.533656) (xy 195.428858 -287.49206)
			(xy 195.409567 -287.446784) (xy 195.39779 -287.399) (xy 195.39383 -287.349946) (xy 195.055236 -287.349946)
			(xy 195.054741 -287.374553) (xy 195.046846 -287.42313) (xy 195.031262 -287.469811) (xy 195.008391 -287.513388)
			(xy 194.978826 -287.552732) (xy 194.943333 -287.586824) (xy 194.90283 -287.61478) (xy 194.858368 -287.635878)
			(xy 194.811097 -287.64957) (xy 194.762242 -287.655502) (xy 194.713067 -287.653521) (xy 194.664848 -287.643677)
			(xy 194.618832 -287.626225) (xy 194.576211 -287.601618) (xy 194.53809 -287.570493) (xy 194.505455 -287.533656)
			(xy 194.479152 -287.49206) (xy 194.459861 -287.446784) (xy 194.448084 -287.399) (xy 194.444124 -287.349946)
			(xy 194.105276 -287.349946) (xy 194.104781 -287.374553) (xy 194.096886 -287.42313) (xy 194.081302 -287.469811)
			(xy 194.058431 -287.513388) (xy 194.028866 -287.552732) (xy 193.993373 -287.586824) (xy 193.95287 -287.61478)
			(xy 193.908408 -287.635878) (xy 193.861137 -287.64957) (xy 193.812282 -287.655502) (xy 193.763107 -287.653521)
			(xy 193.714888 -287.643677) (xy 193.668872 -287.626225) (xy 193.626251 -287.601618) (xy 193.58813 -287.570493)
			(xy 193.555495 -287.533656) (xy 193.529192 -287.49206) (xy 193.509901 -287.446784) (xy 193.498124 -287.399)
			(xy 193.494164 -287.349946) (xy 193.155316 -287.349946) (xy 193.154821 -287.374553) (xy 193.146926 -287.42313)
			(xy 193.131342 -287.469811) (xy 193.108471 -287.513388) (xy 193.078906 -287.552732) (xy 193.043413 -287.586824)
			(xy 193.00291 -287.61478) (xy 192.958448 -287.635878) (xy 192.911177 -287.64957) (xy 192.862322 -287.655502)
			(xy 192.813147 -287.653521) (xy 192.764928 -287.643677) (xy 192.718912 -287.626225) (xy 192.676291 -287.601618)
			(xy 192.63817 -287.570493) (xy 192.605535 -287.533656) (xy 192.579232 -287.49206) (xy 192.559941 -287.446784)
			(xy 192.548164 -287.399) (xy 192.544204 -287.349946) (xy 192.2272 -287.349946) (xy 192.226696 -287.375654)
			(xy 192.218653 -287.426436) (xy 192.202765 -287.475335) (xy 192.179422 -287.521147) (xy 192.149201 -287.562743)
			(xy 192.112845 -287.599099) (xy 192.071249 -287.62932) (xy 192.025437 -287.652663) (xy 191.976538 -287.668551)
			(xy 191.925756 -287.676594) (xy 191.87434 -287.676594) (xy 191.823558 -287.668551) (xy 191.774659 -287.652663)
			(xy 191.728847 -287.62932) (xy 191.687251 -287.599099) (xy 191.650895 -287.562743) (xy 191.620674 -287.521147)
			(xy 191.597331 -287.475335) (xy 191.581443 -287.426436) (xy 191.5734 -287.375654) (xy 191.276482 -287.375654)
			(xy 191.268439 -287.426436) (xy 191.252551 -287.475335) (xy 191.229208 -287.521147) (xy 191.198987 -287.562743)
			(xy 191.162631 -287.599099) (xy 191.121035 -287.62932) (xy 191.075223 -287.652663) (xy 191.026324 -287.668551)
			(xy 190.975542 -287.676594) (xy 190.924126 -287.676594) (xy 190.873344 -287.668551) (xy 190.824445 -287.652663)
			(xy 190.778633 -287.62932) (xy 190.737037 -287.599099) (xy 190.700681 -287.562743) (xy 190.67046 -287.521147)
			(xy 190.647117 -287.475335) (xy 190.631229 -287.426436) (xy 190.623186 -287.375654) (xy 190.304508 -287.375654)
			(xy 190.296792 -287.42313) (xy 190.281208 -287.469811) (xy 190.258337 -287.513388) (xy 190.228772 -287.552732)
			(xy 190.193279 -287.586824) (xy 190.152776 -287.61478) (xy 190.108314 -287.635878) (xy 190.061043 -287.64957)
			(xy 190.012188 -287.655502) (xy 189.963013 -287.653521) (xy 189.914794 -287.643677) (xy 189.868778 -287.626225)
			(xy 189.826157 -287.601618) (xy 189.788036 -287.570493) (xy 189.755401 -287.533656) (xy 189.729098 -287.49206)
			(xy 189.709807 -287.446784) (xy 189.69803 -287.399) (xy 189.69407 -287.349946) (xy 165.283134 -287.349946)
			(xy 165.283134 -287.824926) (xy 165.469074 -287.824926) (xy 165.473034 -287.775872) (xy 165.484811 -287.728088)
			(xy 165.504102 -287.682812) (xy 165.530405 -287.641216) (xy 165.56304 -287.604379) (xy 165.601161 -287.573254)
			(xy 165.643782 -287.548647) (xy 165.689798 -287.531195) (xy 165.738017 -287.521351) (xy 165.787192 -287.51937)
			(xy 165.836047 -287.525302) (xy 165.883318 -287.538994) (xy 165.92778 -287.560092) (xy 165.968283 -287.588048)
			(xy 166.003776 -287.62214) (xy 166.033341 -287.661484) (xy 166.056212 -287.705061) (xy 166.071796 -287.751742)
			(xy 166.079691 -287.800319) (xy 166.080186 -287.824926) (xy 166.419288 -287.824926) (xy 166.423248 -287.775872)
			(xy 166.435025 -287.728088) (xy 166.454316 -287.682812) (xy 166.480619 -287.641216) (xy 166.513254 -287.604379)
			(xy 166.551375 -287.573254) (xy 166.593996 -287.548647) (xy 166.640012 -287.531195) (xy 166.688231 -287.521351)
			(xy 166.737406 -287.51937) (xy 166.786261 -287.525302) (xy 166.833532 -287.538994) (xy 166.877994 -287.560092)
			(xy 166.918497 -287.588048) (xy 166.95399 -287.62214) (xy 166.983555 -287.661484) (xy 167.006426 -287.705061)
			(xy 167.02201 -287.751742) (xy 167.029905 -287.800319) (xy 167.0304 -287.824926) (xy 167.369248 -287.824926)
			(xy 167.373208 -287.775872) (xy 167.384985 -287.728088) (xy 167.404276 -287.682812) (xy 167.430579 -287.641216)
			(xy 167.463214 -287.604379) (xy 167.501335 -287.573254) (xy 167.543956 -287.548647) (xy 167.589972 -287.531195)
			(xy 167.638191 -287.521351) (xy 167.687366 -287.51937) (xy 167.736221 -287.525302) (xy 167.783492 -287.538994)
			(xy 167.827954 -287.560092) (xy 167.868457 -287.588048) (xy 167.90395 -287.62214) (xy 167.933515 -287.661484)
			(xy 167.956386 -287.705061) (xy 167.97197 -287.751742) (xy 167.979865 -287.800319) (xy 167.98036 -287.824926)
			(xy 168.319208 -287.824926) (xy 168.323168 -287.775872) (xy 168.334945 -287.728088) (xy 168.354236 -287.682812)
			(xy 168.380539 -287.641216) (xy 168.413174 -287.604379) (xy 168.451295 -287.573254) (xy 168.493916 -287.548647)
			(xy 168.539932 -287.531195) (xy 168.588151 -287.521351) (xy 168.637326 -287.51937) (xy 168.686181 -287.525302)
			(xy 168.733452 -287.538994) (xy 168.777914 -287.560092) (xy 168.818417 -287.588048) (xy 168.85391 -287.62214)
			(xy 168.883475 -287.661484) (xy 168.906346 -287.705061) (xy 168.92193 -287.751742) (xy 168.929825 -287.800319)
			(xy 168.93032 -287.824926) (xy 169.269168 -287.824926) (xy 169.273128 -287.775872) (xy 169.284905 -287.728088)
			(xy 169.304196 -287.682812) (xy 169.330499 -287.641216) (xy 169.363134 -287.604379) (xy 169.401255 -287.573254)
			(xy 169.443876 -287.548647) (xy 169.489892 -287.531195) (xy 169.538111 -287.521351) (xy 169.587286 -287.51937)
			(xy 169.636141 -287.525302) (xy 169.683412 -287.538994) (xy 169.727874 -287.560092) (xy 169.768377 -287.588048)
			(xy 169.80387 -287.62214) (xy 169.833435 -287.661484) (xy 169.856306 -287.705061) (xy 169.87189 -287.751742)
			(xy 169.879785 -287.800319) (xy 169.88028 -287.824926) (xy 170.219128 -287.824926) (xy 170.223088 -287.775872)
			(xy 170.234865 -287.728088) (xy 170.254156 -287.682812) (xy 170.280459 -287.641216) (xy 170.313094 -287.604379)
			(xy 170.351215 -287.573254) (xy 170.393836 -287.548647) (xy 170.439852 -287.531195) (xy 170.488071 -287.521351)
			(xy 170.537246 -287.51937) (xy 170.586101 -287.525302) (xy 170.633372 -287.538994) (xy 170.677834 -287.560092)
			(xy 170.718337 -287.588048) (xy 170.75383 -287.62214) (xy 170.783395 -287.661484) (xy 170.806266 -287.705061)
			(xy 170.82185 -287.751742) (xy 170.829745 -287.800319) (xy 170.83024 -287.824926) (xy 171.169088 -287.824926)
			(xy 171.173048 -287.775872) (xy 171.184825 -287.728088) (xy 171.204116 -287.682812) (xy 171.230419 -287.641216)
			(xy 171.263054 -287.604379) (xy 171.301175 -287.573254) (xy 171.343796 -287.548647) (xy 171.389812 -287.531195)
			(xy 171.438031 -287.521351) (xy 171.487206 -287.51937) (xy 171.536061 -287.525302) (xy 171.583332 -287.538994)
			(xy 171.627794 -287.560092) (xy 171.668297 -287.588048) (xy 171.70379 -287.62214) (xy 171.733355 -287.661484)
			(xy 171.756226 -287.705061) (xy 171.77181 -287.751742) (xy 171.779705 -287.800319) (xy 171.7802 -287.824926)
			(xy 172.119048 -287.824926) (xy 172.123008 -287.775872) (xy 172.134785 -287.728088) (xy 172.154076 -287.682812)
			(xy 172.180379 -287.641216) (xy 172.213014 -287.604379) (xy 172.251135 -287.573254) (xy 172.293756 -287.548647)
			(xy 172.339772 -287.531195) (xy 172.387991 -287.521351) (xy 172.437166 -287.51937) (xy 172.486021 -287.525302)
			(xy 172.533292 -287.538994) (xy 172.577754 -287.560092) (xy 172.618257 -287.588048) (xy 172.65375 -287.62214)
			(xy 172.683315 -287.661484) (xy 172.706186 -287.705061) (xy 172.72177 -287.751742) (xy 172.729665 -287.800319)
			(xy 172.73016 -287.824926) (xy 173.069262 -287.824926) (xy 173.073222 -287.775872) (xy 173.084999 -287.728088)
			(xy 173.10429 -287.682812) (xy 173.130593 -287.641216) (xy 173.163228 -287.604379) (xy 173.201349 -287.573254)
			(xy 173.24397 -287.548647) (xy 173.289986 -287.531195) (xy 173.338205 -287.521351) (xy 173.38738 -287.51937)
			(xy 173.436235 -287.525302) (xy 173.483506 -287.538994) (xy 173.527968 -287.560092) (xy 173.568471 -287.588048)
			(xy 173.603964 -287.62214) (xy 173.633529 -287.661484) (xy 173.653722 -287.699958) (xy 174.044114 -287.699958)
			(xy 174.048074 -287.650904) (xy 174.059851 -287.60312) (xy 174.079142 -287.557844) (xy 174.105445 -287.516248)
			(xy 174.13808 -287.479411) (xy 174.176201 -287.448286) (xy 174.218822 -287.423679) (xy 174.264838 -287.406227)
			(xy 174.313057 -287.396383) (xy 174.362232 -287.394402) (xy 174.411087 -287.400334) (xy 174.458358 -287.414026)
			(xy 174.50282 -287.435124) (xy 174.543323 -287.46308) (xy 174.578816 -287.497172) (xy 174.608381 -287.536516)
			(xy 174.631252 -287.580093) (xy 174.646836 -287.626774) (xy 174.654731 -287.675351) (xy 174.655226 -287.699958)
			(xy 174.654731 -287.724565) (xy 174.646836 -287.773142) (xy 174.631252 -287.819823) (xy 174.608381 -287.8634)
			(xy 174.580986 -287.899856) (xy 175.919142 -287.899856) (xy 175.923102 -287.850802) (xy 175.934879 -287.803018)
			(xy 175.95417 -287.757742) (xy 175.980473 -287.716146) (xy 176.013108 -287.679309) (xy 176.051229 -287.648184)
			(xy 176.09385 -287.623577) (xy 176.139866 -287.606125) (xy 176.188085 -287.596281) (xy 176.23726 -287.5943)
			(xy 176.286115 -287.600232) (xy 176.333386 -287.613924) (xy 176.377848 -287.635022) (xy 176.418351 -287.662978)
			(xy 176.453844 -287.69707) (xy 176.483409 -287.736414) (xy 176.50628 -287.779991) (xy 176.521281 -287.824926)
			(xy 176.869102 -287.824926) (xy 176.873062 -287.775872) (xy 176.884839 -287.728088) (xy 176.90413 -287.682812)
			(xy 176.930433 -287.641216) (xy 176.963068 -287.604379) (xy 177.001189 -287.573254) (xy 177.04381 -287.548647)
			(xy 177.089826 -287.531195) (xy 177.138045 -287.521351) (xy 177.18722 -287.51937) (xy 177.236075 -287.525302)
			(xy 177.283346 -287.538994) (xy 177.327808 -287.560092) (xy 177.368311 -287.588048) (xy 177.403804 -287.62214)
			(xy 177.433369 -287.661484) (xy 177.45624 -287.705061) (xy 177.471824 -287.751742) (xy 177.479719 -287.800319)
			(xy 177.480214 -287.824926) (xy 177.819062 -287.824926) (xy 177.823022 -287.775872) (xy 177.834799 -287.728088)
			(xy 177.85409 -287.682812) (xy 177.880393 -287.641216) (xy 177.913028 -287.604379) (xy 177.951149 -287.573254)
			(xy 177.99377 -287.548647) (xy 178.039786 -287.531195) (xy 178.088005 -287.521351) (xy 178.13718 -287.51937)
			(xy 178.186035 -287.525302) (xy 178.233306 -287.538994) (xy 178.277768 -287.560092) (xy 178.318271 -287.588048)
			(xy 178.353764 -287.62214) (xy 178.383329 -287.661484) (xy 178.4062 -287.705061) (xy 178.421784 -287.751742)
			(xy 178.429679 -287.800319) (xy 178.430174 -287.824926) (xy 178.769276 -287.824926) (xy 178.773236 -287.775872)
			(xy 178.785013 -287.728088) (xy 178.804304 -287.682812) (xy 178.830607 -287.641216) (xy 178.863242 -287.604379)
			(xy 178.901363 -287.573254) (xy 178.943984 -287.548647) (xy 178.99 -287.531195) (xy 179.038219 -287.521351)
			(xy 179.087394 -287.51937) (xy 179.136249 -287.525302) (xy 179.18352 -287.538994) (xy 179.227982 -287.560092)
			(xy 179.268485 -287.588048) (xy 179.303978 -287.62214) (xy 179.333543 -287.661484) (xy 179.356414 -287.705061)
			(xy 179.371998 -287.751742) (xy 179.379893 -287.800319) (xy 179.380388 -287.824926) (xy 179.719236 -287.824926)
			(xy 179.723196 -287.775872) (xy 179.734973 -287.728088) (xy 179.754264 -287.682812) (xy 179.780567 -287.641216)
			(xy 179.813202 -287.604379) (xy 179.851323 -287.573254) (xy 179.893944 -287.548647) (xy 179.93996 -287.531195)
			(xy 179.988179 -287.521351) (xy 180.037354 -287.51937) (xy 180.086209 -287.525302) (xy 180.13348 -287.538994)
			(xy 180.177942 -287.560092) (xy 180.218445 -287.588048) (xy 180.253938 -287.62214) (xy 180.283503 -287.661484)
			(xy 180.306374 -287.705061) (xy 180.321958 -287.751742) (xy 180.329853 -287.800319) (xy 180.330348 -287.824926)
			(xy 180.669196 -287.824926) (xy 180.673156 -287.775872) (xy 180.684933 -287.728088) (xy 180.704224 -287.682812)
			(xy 180.730527 -287.641216) (xy 180.763162 -287.604379) (xy 180.801283 -287.573254) (xy 180.843904 -287.548647)
			(xy 180.88992 -287.531195) (xy 180.938139 -287.521351) (xy 180.987314 -287.51937) (xy 181.036169 -287.525302)
			(xy 181.08344 -287.538994) (xy 181.127902 -287.560092) (xy 181.168405 -287.588048) (xy 181.203898 -287.62214)
			(xy 181.233463 -287.661484) (xy 181.256334 -287.705061) (xy 181.271918 -287.751742) (xy 181.279813 -287.800319)
			(xy 181.280308 -287.824926) (xy 181.619156 -287.824926) (xy 181.623116 -287.775872) (xy 181.634893 -287.728088)
			(xy 181.654184 -287.682812) (xy 181.680487 -287.641216) (xy 181.713122 -287.604379) (xy 181.751243 -287.573254)
			(xy 181.793864 -287.548647) (xy 181.83988 -287.531195) (xy 181.888099 -287.521351) (xy 181.937274 -287.51937)
			(xy 181.986129 -287.525302) (xy 182.0334 -287.538994) (xy 182.077862 -287.560092) (xy 182.118365 -287.588048)
			(xy 182.153858 -287.62214) (xy 182.183423 -287.661484) (xy 182.206294 -287.705061) (xy 182.221878 -287.751742)
			(xy 182.229773 -287.800319) (xy 182.230268 -287.824926) (xy 182.569116 -287.824926) (xy 182.573076 -287.775872)
			(xy 182.584853 -287.728088) (xy 182.604144 -287.682812) (xy 182.630447 -287.641216) (xy 182.663082 -287.604379)
			(xy 182.701203 -287.573254) (xy 182.743824 -287.548647) (xy 182.78984 -287.531195) (xy 182.838059 -287.521351)
			(xy 182.887234 -287.51937) (xy 182.936089 -287.525302) (xy 182.98336 -287.538994) (xy 183.027822 -287.560092)
			(xy 183.068325 -287.588048) (xy 183.103818 -287.62214) (xy 183.133383 -287.661484) (xy 183.156254 -287.705061)
			(xy 183.171838 -287.751742) (xy 183.179733 -287.800319) (xy 183.180228 -287.824926) (xy 183.519076 -287.824926)
			(xy 183.523036 -287.775872) (xy 183.534813 -287.728088) (xy 183.554104 -287.682812) (xy 183.580407 -287.641216)
			(xy 183.613042 -287.604379) (xy 183.651163 -287.573254) (xy 183.693784 -287.548647) (xy 183.7398 -287.531195)
			(xy 183.788019 -287.521351) (xy 183.837194 -287.51937) (xy 183.886049 -287.525302) (xy 183.93332 -287.538994)
			(xy 183.977782 -287.560092) (xy 184.018285 -287.588048) (xy 184.053778 -287.62214) (xy 184.083343 -287.661484)
			(xy 184.106214 -287.705061) (xy 184.121798 -287.751742) (xy 184.129693 -287.800319) (xy 184.130188 -287.824926)
			(xy 184.469036 -287.824926) (xy 184.472996 -287.775872) (xy 184.484773 -287.728088) (xy 184.504064 -287.682812)
			(xy 184.530367 -287.641216) (xy 184.563002 -287.604379) (xy 184.601123 -287.573254) (xy 184.643744 -287.548647)
			(xy 184.68976 -287.531195) (xy 184.737979 -287.521351) (xy 184.787154 -287.51937) (xy 184.836009 -287.525302)
			(xy 184.88328 -287.538994) (xy 184.927742 -287.560092) (xy 184.968245 -287.588048) (xy 185.003738 -287.62214)
			(xy 185.033303 -287.661484) (xy 185.056174 -287.705061) (xy 185.071758 -287.751742) (xy 185.079653 -287.800319)
			(xy 185.080148 -287.824926) (xy 186.36921 -287.824926) (xy 186.37317 -287.775872) (xy 186.384947 -287.728088)
			(xy 186.404238 -287.682812) (xy 186.430541 -287.641216) (xy 186.463176 -287.604379) (xy 186.501297 -287.573254)
			(xy 186.543918 -287.548647) (xy 186.589934 -287.531195) (xy 186.638153 -287.521351) (xy 186.687328 -287.51937)
			(xy 186.736183 -287.525302) (xy 186.783454 -287.538994) (xy 186.827916 -287.560092) (xy 186.868419 -287.588048)
			(xy 186.903912 -287.62214) (xy 186.933477 -287.661484) (xy 186.956348 -287.705061) (xy 186.971932 -287.751742)
			(xy 186.979827 -287.800319) (xy 186.980322 -287.824926) (xy 186.979827 -287.849533) (xy 186.971932 -287.89811)
			(xy 186.956348 -287.944791) (xy 186.933477 -287.988368) (xy 186.903912 -288.027712) (xy 186.868419 -288.061804)
			(xy 186.827916 -288.08976) (xy 186.783454 -288.110858) (xy 186.736183 -288.12455) (xy 186.687328 -288.130482)
			(xy 186.638153 -288.128501) (xy 186.589934 -288.118657) (xy 186.543918 -288.101205) (xy 186.501297 -288.076598)
			(xy 186.463176 -288.045473) (xy 186.430541 -288.008636) (xy 186.404238 -287.96704) (xy 186.384947 -287.921764)
			(xy 186.37317 -287.87398) (xy 186.36921 -287.824926) (xy 185.080148 -287.824926) (xy 185.079653 -287.849533)
			(xy 185.071758 -287.89811) (xy 185.056174 -287.944791) (xy 185.033303 -287.988368) (xy 185.003738 -288.027712)
			(xy 184.968245 -288.061804) (xy 184.927742 -288.08976) (xy 184.88328 -288.110858) (xy 184.836009 -288.12455)
			(xy 184.787154 -288.130482) (xy 184.737979 -288.128501) (xy 184.68976 -288.118657) (xy 184.643744 -288.101205)
			(xy 184.601123 -288.076598) (xy 184.563002 -288.045473) (xy 184.530367 -288.008636) (xy 184.504064 -287.96704)
			(xy 184.484773 -287.921764) (xy 184.472996 -287.87398) (xy 184.469036 -287.824926) (xy 184.130188 -287.824926)
			(xy 184.129693 -287.849533) (xy 184.121798 -287.89811) (xy 184.106214 -287.944791) (xy 184.083343 -287.988368)
			(xy 184.053778 -288.027712) (xy 184.018285 -288.061804) (xy 183.977782 -288.08976) (xy 183.93332 -288.110858)
			(xy 183.886049 -288.12455) (xy 183.837194 -288.130482) (xy 183.788019 -288.128501) (xy 183.7398 -288.118657)
			(xy 183.693784 -288.101205) (xy 183.651163 -288.076598) (xy 183.613042 -288.045473) (xy 183.580407 -288.008636)
			(xy 183.554104 -287.96704) (xy 183.534813 -287.921764) (xy 183.523036 -287.87398) (xy 183.519076 -287.824926)
			(xy 183.180228 -287.824926) (xy 183.179733 -287.849533) (xy 183.171838 -287.89811) (xy 183.156254 -287.944791)
			(xy 183.133383 -287.988368) (xy 183.103818 -288.027712) (xy 183.068325 -288.061804) (xy 183.027822 -288.08976)
			(xy 182.98336 -288.110858) (xy 182.936089 -288.12455) (xy 182.887234 -288.130482) (xy 182.838059 -288.128501)
			(xy 182.78984 -288.118657) (xy 182.743824 -288.101205) (xy 182.701203 -288.076598) (xy 182.663082 -288.045473)
			(xy 182.630447 -288.008636) (xy 182.604144 -287.96704) (xy 182.584853 -287.921764) (xy 182.573076 -287.87398)
			(xy 182.569116 -287.824926) (xy 182.230268 -287.824926) (xy 182.229773 -287.849533) (xy 182.221878 -287.89811)
			(xy 182.206294 -287.944791) (xy 182.183423 -287.988368) (xy 182.153858 -288.027712) (xy 182.118365 -288.061804)
			(xy 182.077862 -288.08976) (xy 182.0334 -288.110858) (xy 181.986129 -288.12455) (xy 181.937274 -288.130482)
			(xy 181.888099 -288.128501) (xy 181.83988 -288.118657) (xy 181.793864 -288.101205) (xy 181.751243 -288.076598)
			(xy 181.713122 -288.045473) (xy 181.680487 -288.008636) (xy 181.654184 -287.96704) (xy 181.634893 -287.921764)
			(xy 181.623116 -287.87398) (xy 181.619156 -287.824926) (xy 181.280308 -287.824926) (xy 181.279813 -287.849533)
			(xy 181.271918 -287.89811) (xy 181.256334 -287.944791) (xy 181.233463 -287.988368) (xy 181.203898 -288.027712)
			(xy 181.168405 -288.061804) (xy 181.127902 -288.08976) (xy 181.08344 -288.110858) (xy 181.036169 -288.12455)
			(xy 180.987314 -288.130482) (xy 180.938139 -288.128501) (xy 180.88992 -288.118657) (xy 180.843904 -288.101205)
			(xy 180.801283 -288.076598) (xy 180.763162 -288.045473) (xy 180.730527 -288.008636) (xy 180.704224 -287.96704)
			(xy 180.684933 -287.921764) (xy 180.673156 -287.87398) (xy 180.669196 -287.824926) (xy 180.330348 -287.824926)
			(xy 180.329853 -287.849533) (xy 180.321958 -287.89811) (xy 180.306374 -287.944791) (xy 180.283503 -287.988368)
			(xy 180.253938 -288.027712) (xy 180.218445 -288.061804) (xy 180.177942 -288.08976) (xy 180.13348 -288.110858)
			(xy 180.086209 -288.12455) (xy 180.037354 -288.130482) (xy 179.988179 -288.128501) (xy 179.93996 -288.118657)
			(xy 179.893944 -288.101205) (xy 179.851323 -288.076598) (xy 179.813202 -288.045473) (xy 179.780567 -288.008636)
			(xy 179.754264 -287.96704) (xy 179.734973 -287.921764) (xy 179.723196 -287.87398) (xy 179.719236 -287.824926)
			(xy 179.380388 -287.824926) (xy 179.379893 -287.849533) (xy 179.371998 -287.89811) (xy 179.356414 -287.944791)
			(xy 179.333543 -287.988368) (xy 179.303978 -288.027712) (xy 179.268485 -288.061804) (xy 179.227982 -288.08976)
			(xy 179.18352 -288.110858) (xy 179.136249 -288.12455) (xy 179.087394 -288.130482) (xy 179.038219 -288.128501)
			(xy 178.99 -288.118657) (xy 178.943984 -288.101205) (xy 178.901363 -288.076598) (xy 178.863242 -288.045473)
			(xy 178.830607 -288.008636) (xy 178.804304 -287.96704) (xy 178.785013 -287.921764) (xy 178.773236 -287.87398)
			(xy 178.769276 -287.824926) (xy 178.430174 -287.824926) (xy 178.429679 -287.849533) (xy 178.421784 -287.89811)
			(xy 178.4062 -287.944791) (xy 178.383329 -287.988368) (xy 178.353764 -288.027712) (xy 178.318271 -288.061804)
			(xy 178.277768 -288.08976) (xy 178.233306 -288.110858) (xy 178.186035 -288.12455) (xy 178.13718 -288.130482)
			(xy 178.088005 -288.128501) (xy 178.039786 -288.118657) (xy 177.99377 -288.101205) (xy 177.951149 -288.076598)
			(xy 177.913028 -288.045473) (xy 177.880393 -288.008636) (xy 177.85409 -287.96704) (xy 177.834799 -287.921764)
			(xy 177.823022 -287.87398) (xy 177.819062 -287.824926) (xy 177.480214 -287.824926) (xy 177.479719 -287.849533)
			(xy 177.471824 -287.89811) (xy 177.45624 -287.944791) (xy 177.433369 -287.988368) (xy 177.403804 -288.027712)
			(xy 177.368311 -288.061804) (xy 177.327808 -288.08976) (xy 177.283346 -288.110858) (xy 177.236075 -288.12455)
			(xy 177.18722 -288.130482) (xy 177.138045 -288.128501) (xy 177.089826 -288.118657) (xy 177.04381 -288.101205)
			(xy 177.001189 -288.076598) (xy 176.963068 -288.045473) (xy 176.930433 -288.008636) (xy 176.90413 -287.96704)
			(xy 176.884839 -287.921764) (xy 176.873062 -287.87398) (xy 176.869102 -287.824926) (xy 176.521281 -287.824926)
			(xy 176.521864 -287.826672) (xy 176.529759 -287.875249) (xy 176.530254 -287.899856) (xy 176.529759 -287.924463)
			(xy 176.521864 -287.97304) (xy 176.50628 -288.019721) (xy 176.483409 -288.063298) (xy 176.453844 -288.102642)
			(xy 176.418351 -288.136734) (xy 176.377848 -288.16469) (xy 176.333386 -288.185788) (xy 176.286115 -288.19948)
			(xy 176.23726 -288.205412) (xy 176.188085 -288.203431) (xy 176.139866 -288.193587) (xy 176.09385 -288.176135)
			(xy 176.051229 -288.151528) (xy 176.013108 -288.120403) (xy 175.980473 -288.083566) (xy 175.95417 -288.04197)
			(xy 175.934879 -287.996694) (xy 175.923102 -287.94891) (xy 175.919142 -287.899856) (xy 174.580986 -287.899856)
			(xy 174.578816 -287.902744) (xy 174.543323 -287.936836) (xy 174.50282 -287.964792) (xy 174.458358 -287.98589)
			(xy 174.411087 -287.999582) (xy 174.362232 -288.005514) (xy 174.313057 -288.003533) (xy 174.264838 -287.993689)
			(xy 174.218822 -287.976237) (xy 174.176201 -287.95163) (xy 174.13808 -287.920505) (xy 174.105445 -287.883668)
			(xy 174.079142 -287.842072) (xy 174.059851 -287.796796) (xy 174.048074 -287.749012) (xy 174.044114 -287.699958)
			(xy 173.653722 -287.699958) (xy 173.6564 -287.705061) (xy 173.671984 -287.751742) (xy 173.679879 -287.800319)
			(xy 173.680374 -287.824926) (xy 173.679879 -287.849533) (xy 173.671984 -287.89811) (xy 173.6564 -287.944791)
			(xy 173.633529 -287.988368) (xy 173.603964 -288.027712) (xy 173.568471 -288.061804) (xy 173.527968 -288.08976)
			(xy 173.483506 -288.110858) (xy 173.436235 -288.12455) (xy 173.38738 -288.130482) (xy 173.338205 -288.128501)
			(xy 173.289986 -288.118657) (xy 173.24397 -288.101205) (xy 173.201349 -288.076598) (xy 173.163228 -288.045473)
			(xy 173.130593 -288.008636) (xy 173.10429 -287.96704) (xy 173.084999 -287.921764) (xy 173.073222 -287.87398)
			(xy 173.069262 -287.824926) (xy 172.73016 -287.824926) (xy 172.729665 -287.849533) (xy 172.72177 -287.89811)
			(xy 172.706186 -287.944791) (xy 172.683315 -287.988368) (xy 172.65375 -288.027712) (xy 172.618257 -288.061804)
			(xy 172.577754 -288.08976) (xy 172.533292 -288.110858) (xy 172.486021 -288.12455) (xy 172.437166 -288.130482)
			(xy 172.387991 -288.128501) (xy 172.339772 -288.118657) (xy 172.293756 -288.101205) (xy 172.251135 -288.076598)
			(xy 172.213014 -288.045473) (xy 172.180379 -288.008636) (xy 172.154076 -287.96704) (xy 172.134785 -287.921764)
			(xy 172.123008 -287.87398) (xy 172.119048 -287.824926) (xy 171.7802 -287.824926) (xy 171.779705 -287.849533)
			(xy 171.77181 -287.89811) (xy 171.756226 -287.944791) (xy 171.733355 -287.988368) (xy 171.70379 -288.027712)
			(xy 171.668297 -288.061804) (xy 171.627794 -288.08976) (xy 171.583332 -288.110858) (xy 171.536061 -288.12455)
			(xy 171.487206 -288.130482) (xy 171.438031 -288.128501) (xy 171.389812 -288.118657) (xy 171.343796 -288.101205)
			(xy 171.301175 -288.076598) (xy 171.263054 -288.045473) (xy 171.230419 -288.008636) (xy 171.204116 -287.96704)
			(xy 171.184825 -287.921764) (xy 171.173048 -287.87398) (xy 171.169088 -287.824926) (xy 170.83024 -287.824926)
			(xy 170.829745 -287.849533) (xy 170.82185 -287.89811) (xy 170.806266 -287.944791) (xy 170.783395 -287.988368)
			(xy 170.75383 -288.027712) (xy 170.718337 -288.061804) (xy 170.677834 -288.08976) (xy 170.633372 -288.110858)
			(xy 170.586101 -288.12455) (xy 170.537246 -288.130482) (xy 170.488071 -288.128501) (xy 170.439852 -288.118657)
			(xy 170.393836 -288.101205) (xy 170.351215 -288.076598) (xy 170.313094 -288.045473) (xy 170.280459 -288.008636)
			(xy 170.254156 -287.96704) (xy 170.234865 -287.921764) (xy 170.223088 -287.87398) (xy 170.219128 -287.824926)
			(xy 169.88028 -287.824926) (xy 169.879785 -287.849533) (xy 169.87189 -287.89811) (xy 169.856306 -287.944791)
			(xy 169.833435 -287.988368) (xy 169.80387 -288.027712) (xy 169.768377 -288.061804) (xy 169.727874 -288.08976)
			(xy 169.683412 -288.110858) (xy 169.636141 -288.12455) (xy 169.587286 -288.130482) (xy 169.538111 -288.128501)
			(xy 169.489892 -288.118657) (xy 169.443876 -288.101205) (xy 169.401255 -288.076598) (xy 169.363134 -288.045473)
			(xy 169.330499 -288.008636) (xy 169.304196 -287.96704) (xy 169.284905 -287.921764) (xy 169.273128 -287.87398)
			(xy 169.269168 -287.824926) (xy 168.93032 -287.824926) (xy 168.929825 -287.849533) (xy 168.92193 -287.89811)
			(xy 168.906346 -287.944791) (xy 168.883475 -287.988368) (xy 168.85391 -288.027712) (xy 168.818417 -288.061804)
			(xy 168.777914 -288.08976) (xy 168.733452 -288.110858) (xy 168.686181 -288.12455) (xy 168.637326 -288.130482)
			(xy 168.588151 -288.128501) (xy 168.539932 -288.118657) (xy 168.493916 -288.101205) (xy 168.451295 -288.076598)
			(xy 168.413174 -288.045473) (xy 168.380539 -288.008636) (xy 168.354236 -287.96704) (xy 168.334945 -287.921764)
			(xy 168.323168 -287.87398) (xy 168.319208 -287.824926) (xy 167.98036 -287.824926) (xy 167.979865 -287.849533)
			(xy 167.97197 -287.89811) (xy 167.956386 -287.944791) (xy 167.933515 -287.988368) (xy 167.90395 -288.027712)
			(xy 167.868457 -288.061804) (xy 167.827954 -288.08976) (xy 167.783492 -288.110858) (xy 167.736221 -288.12455)
			(xy 167.687366 -288.130482) (xy 167.638191 -288.128501) (xy 167.589972 -288.118657) (xy 167.543956 -288.101205)
			(xy 167.501335 -288.076598) (xy 167.463214 -288.045473) (xy 167.430579 -288.008636) (xy 167.404276 -287.96704)
			(xy 167.384985 -287.921764) (xy 167.373208 -287.87398) (xy 167.369248 -287.824926) (xy 167.0304 -287.824926)
			(xy 167.029905 -287.849533) (xy 167.02201 -287.89811) (xy 167.006426 -287.944791) (xy 166.983555 -287.988368)
			(xy 166.95399 -288.027712) (xy 166.918497 -288.061804) (xy 166.877994 -288.08976) (xy 166.833532 -288.110858)
			(xy 166.786261 -288.12455) (xy 166.737406 -288.130482) (xy 166.688231 -288.128501) (xy 166.640012 -288.118657)
			(xy 166.593996 -288.101205) (xy 166.551375 -288.076598) (xy 166.513254 -288.045473) (xy 166.480619 -288.008636)
			(xy 166.454316 -287.96704) (xy 166.435025 -287.921764) (xy 166.423248 -287.87398) (xy 166.419288 -287.824926)
			(xy 166.080186 -287.824926) (xy 166.079691 -287.849533) (xy 166.071796 -287.89811) (xy 166.056212 -287.944791)
			(xy 166.033341 -287.988368) (xy 166.003776 -288.027712) (xy 165.968283 -288.061804) (xy 165.92778 -288.08976)
			(xy 165.883318 -288.110858) (xy 165.836047 -288.12455) (xy 165.787192 -288.130482) (xy 165.738017 -288.128501)
			(xy 165.689798 -288.118657) (xy 165.643782 -288.101205) (xy 165.601161 -288.076598) (xy 165.56304 -288.045473)
			(xy 165.530405 -288.008636) (xy 165.504102 -287.96704) (xy 165.484811 -287.921764) (xy 165.473034 -287.87398)
			(xy 165.469074 -287.824926) (xy 165.283134 -287.824926) (xy 165.283134 -288.163) (xy 165.283388 -288.174176)
			(xy 165.283388 -288.299906) (xy 189.69407 -288.299906) (xy 189.69803 -288.250852) (xy 189.709807 -288.203068)
			(xy 189.729098 -288.157792) (xy 189.755401 -288.116196) (xy 189.788036 -288.079359) (xy 189.826157 -288.048234)
			(xy 189.868778 -288.023627) (xy 189.914794 -288.006175) (xy 189.963013 -287.996331) (xy 190.012188 -287.99435)
			(xy 190.061043 -288.000282) (xy 190.108314 -288.013974) (xy 190.152776 -288.035072) (xy 190.193279 -288.063028)
			(xy 190.228772 -288.09712) (xy 190.258337 -288.136464) (xy 190.281208 -288.180041) (xy 190.296792 -288.226722)
			(xy 190.304687 -288.275299) (xy 190.305182 -288.299906) (xy 190.644284 -288.299906) (xy 190.648244 -288.250852)
			(xy 190.660021 -288.203068) (xy 190.679312 -288.157792) (xy 190.705615 -288.116196) (xy 190.73825 -288.079359)
			(xy 190.776371 -288.048234) (xy 190.818992 -288.023627) (xy 190.865008 -288.006175) (xy 190.913227 -287.996331)
			(xy 190.962402 -287.99435) (xy 191.011257 -288.000282) (xy 191.058528 -288.013974) (xy 191.10299 -288.035072)
			(xy 191.143493 -288.063028) (xy 191.178986 -288.09712) (xy 191.208551 -288.136464) (xy 191.231422 -288.180041)
			(xy 191.247006 -288.226722) (xy 191.254901 -288.275299) (xy 191.255396 -288.299906) (xy 191.594244 -288.299906)
			(xy 191.598204 -288.250852) (xy 191.609981 -288.203068) (xy 191.629272 -288.157792) (xy 191.655575 -288.116196)
			(xy 191.68821 -288.079359) (xy 191.726331 -288.048234) (xy 191.768952 -288.023627) (xy 191.814968 -288.006175)
			(xy 191.863187 -287.996331) (xy 191.912362 -287.99435) (xy 191.961217 -288.000282) (xy 192.008488 -288.013974)
			(xy 192.05295 -288.035072) (xy 192.093453 -288.063028) (xy 192.128946 -288.09712) (xy 192.158511 -288.136464)
			(xy 192.181382 -288.180041) (xy 192.196966 -288.226722) (xy 192.204861 -288.275299) (xy 192.205356 -288.299906)
			(xy 192.204861 -288.324513) (xy 192.204682 -288.325614) (xy 192.52336 -288.325614) (xy 192.52336 -288.274198)
			(xy 192.531403 -288.223416) (xy 192.547291 -288.174517) (xy 192.570634 -288.128705) (xy 192.600855 -288.087109)
			(xy 192.637211 -288.050753) (xy 192.678807 -288.020532) (xy 192.724619 -287.997189) (xy 192.773518 -287.981301)
			(xy 192.8243 -287.973258) (xy 192.875716 -287.973258) (xy 192.926498 -287.981301) (xy 192.975397 -287.997189)
			(xy 193.021209 -288.020532) (xy 193.062805 -288.050753) (xy 193.099161 -288.087109) (xy 193.129382 -288.128705)
			(xy 193.152725 -288.174517) (xy 193.168613 -288.223416) (xy 193.176656 -288.274198) (xy 193.17716 -288.299906)
			(xy 193.176656 -288.325614) (xy 193.47332 -288.325614) (xy 193.47332 -288.274198) (xy 193.481363 -288.223416)
			(xy 193.497251 -288.174517) (xy 193.520594 -288.128705) (xy 193.550815 -288.087109) (xy 193.587171 -288.050753)
			(xy 193.628767 -288.020532) (xy 193.674579 -287.997189) (xy 193.723478 -287.981301) (xy 193.77426 -287.973258)
			(xy 193.825676 -287.973258) (xy 193.876458 -287.981301) (xy 193.925357 -287.997189) (xy 193.971169 -288.020532)
			(xy 194.012765 -288.050753) (xy 194.049121 -288.087109) (xy 194.079342 -288.128705) (xy 194.102685 -288.174517)
			(xy 194.118573 -288.223416) (xy 194.126616 -288.274198) (xy 194.12712 -288.299906) (xy 194.444124 -288.299906)
			(xy 194.448084 -288.250852) (xy 194.459861 -288.203068) (xy 194.479152 -288.157792) (xy 194.505455 -288.116196)
			(xy 194.53809 -288.079359) (xy 194.576211 -288.048234) (xy 194.618832 -288.023627) (xy 194.664848 -288.006175)
			(xy 194.713067 -287.996331) (xy 194.762242 -287.99435) (xy 194.811097 -288.000282) (xy 194.858368 -288.013974)
			(xy 194.90283 -288.035072) (xy 194.943333 -288.063028) (xy 194.978826 -288.09712) (xy 195.008391 -288.136464)
			(xy 195.031262 -288.180041) (xy 195.046846 -288.226722) (xy 195.054741 -288.275299) (xy 195.055236 -288.299906)
			(xy 195.054741 -288.324513) (xy 195.054562 -288.325614) (xy 195.37324 -288.325614) (xy 195.37324 -288.274198)
			(xy 195.381283 -288.223416) (xy 195.397171 -288.174517) (xy 195.420514 -288.128705) (xy 195.450735 -288.087109)
			(xy 195.487091 -288.050753) (xy 195.528687 -288.020532) (xy 195.574499 -287.997189) (xy 195.623398 -287.981301)
			(xy 195.67418 -287.973258) (xy 195.725596 -287.973258) (xy 195.776378 -287.981301) (xy 195.825277 -287.997189)
			(xy 195.871089 -288.020532) (xy 195.912685 -288.050753) (xy 195.949041 -288.087109) (xy 195.979262 -288.128705)
			(xy 196.002605 -288.174517) (xy 196.018493 -288.223416) (xy 196.026536 -288.274198) (xy 196.02704 -288.299906)
			(xy 196.026536 -288.325614) (xy 196.3232 -288.325614) (xy 196.3232 -288.274198) (xy 196.331243 -288.223416)
			(xy 196.347131 -288.174517) (xy 196.370474 -288.128705) (xy 196.400695 -288.087109) (xy 196.437051 -288.050753)
			(xy 196.478647 -288.020532) (xy 196.524459 -287.997189) (xy 196.573358 -287.981301) (xy 196.62414 -287.973258)
			(xy 196.675556 -287.973258) (xy 196.726338 -287.981301) (xy 196.775237 -287.997189) (xy 196.821049 -288.020532)
			(xy 196.862645 -288.050753) (xy 196.899001 -288.087109) (xy 196.929222 -288.128705) (xy 196.952565 -288.174517)
			(xy 196.968453 -288.223416) (xy 196.976496 -288.274198) (xy 196.977 -288.299906) (xy 197.294258 -288.299906)
			(xy 197.298218 -288.250852) (xy 197.309995 -288.203068) (xy 197.329286 -288.157792) (xy 197.355589 -288.116196)
			(xy 197.388224 -288.079359) (xy 197.426345 -288.048234) (xy 197.468966 -288.023627) (xy 197.514982 -288.006175)
			(xy 197.563201 -287.996331) (xy 197.612376 -287.99435) (xy 197.661231 -288.000282) (xy 197.708502 -288.013974)
			(xy 197.752964 -288.035072) (xy 197.793467 -288.063028) (xy 197.82896 -288.09712) (xy 197.858525 -288.136464)
			(xy 197.881396 -288.180041) (xy 197.89698 -288.226722) (xy 197.904875 -288.275299) (xy 197.90537 -288.299906)
			(xy 198.244218 -288.299906) (xy 198.248178 -288.250852) (xy 198.259955 -288.203068) (xy 198.279246 -288.157792)
			(xy 198.305549 -288.116196) (xy 198.338184 -288.079359) (xy 198.376305 -288.048234) (xy 198.418926 -288.023627)
			(xy 198.464942 -288.006175) (xy 198.513161 -287.996331) (xy 198.562336 -287.99435) (xy 198.611191 -288.000282)
			(xy 198.658462 -288.013974) (xy 198.702924 -288.035072) (xy 198.743427 -288.063028) (xy 198.77892 -288.09712)
			(xy 198.808485 -288.136464) (xy 198.831356 -288.180041) (xy 198.84694 -288.226722) (xy 198.850472 -288.248452)
			(xy 203.696044 -288.248452) (xy 203.696044 -288.193948) (xy 203.7038 -288.139999) (xy 203.719155 -288.087702)
			(xy 203.741795 -288.038123) (xy 203.77126 -287.992271) (xy 203.806951 -287.951078) (xy 203.84814 -287.915383)
			(xy 203.89399 -287.885913) (xy 203.943567 -287.863268) (xy 203.995862 -287.847908) (xy 204.04981 -287.840146)
			(xy 204.077062 -287.839658) (xy 204.103177 -287.840144) (xy 204.154919 -287.847276) (xy 204.205204 -287.861399)
			(xy 204.253093 -287.882248) (xy 204.297691 -287.909434) (xy 204.338165 -287.942449) (xy 204.373757 -287.980675)
			(xy 204.403803 -288.023399) (xy 204.416152 -288.046414) (xy 204.422756 -288.059368) (xy 204.446886 -288.0741)
			(xy 204.566266 -288.0741) (xy 204.590396 -288.059368) (xy 204.597 -288.046414) (xy 204.609391 -288.023419)
			(xy 204.639416 -287.980676) (xy 204.674993 -287.942432) (xy 204.715458 -287.909401) (xy 204.760052 -287.882202)
			(xy 204.807941 -287.861344) (xy 204.858228 -287.847218) (xy 204.909973 -287.840087) (xy 204.93609 -287.839658)
			(xy 204.966795 -287.840291) (xy 205.027407 -287.850163) (xy 205.085654 -287.869621) (xy 205.113128 -287.883346)
			(xy 205.124558 -287.889188) (xy 205.149196 -287.889188) (xy 205.245716 -287.838642) (xy 205.259686 -287.818068)
			(xy 205.26121 -287.805622) (xy 205.265313 -287.776842) (xy 205.280616 -287.720762) (xy 205.303858 -287.667481)
			(xy 205.334553 -287.618116) (xy 205.372056 -287.573701) (xy 205.41558 -287.535169) (xy 205.464213 -287.503327)
			(xy 205.516936 -287.478843) (xy 205.572642 -287.462232) (xy 205.630163 -287.45384) (xy 205.659228 -287.453324)
			(xy 205.687859 -287.453765) (xy 205.744539 -287.461917) (xy 205.799481 -287.478053) (xy 205.851568 -287.501844)
			(xy 205.899739 -287.532805) (xy 205.943014 -287.570306) (xy 205.980512 -287.613583) (xy 206.01147 -287.661756)
			(xy 206.035256 -287.713845) (xy 206.051388 -287.768789) (xy 206.059537 -287.825469) (xy 206.059537 -287.882731)
			(xy 206.051388 -287.939411) (xy 206.035256 -287.994355) (xy 206.01147 -288.046444) (xy 205.980512 -288.094617)
			(xy 205.943014 -288.137894) (xy 205.899739 -288.175395) (xy 205.851568 -288.206356) (xy 205.799481 -288.230147)
			(xy 205.744539 -288.246283) (xy 205.729451 -288.248453) (xy 206.587044 -288.248453) (xy 206.587044 -288.193947)
			(xy 206.594801 -288.139995) (xy 206.610157 -288.087697) (xy 206.632799 -288.038116) (xy 206.662267 -287.992262)
			(xy 206.697961 -287.951068) (xy 206.739154 -287.915373) (xy 206.785007 -287.885904) (xy 206.834587 -287.86326)
			(xy 206.886885 -287.847903) (xy 206.940837 -287.840145) (xy 206.96809 -287.839658) (xy 206.978205 -287.839696)
			(xy 206.998409 -287.840712) (xy 207.008476 -287.84169) (xy 207.018636 -287.84296) (xy 207.038194 -287.837118)
			(xy 207.109822 -287.778444) (xy 207.119474 -287.760664) (xy 207.12049 -287.750504) (xy 207.123861 -287.721106)
			(xy 207.138095 -287.663672) (xy 207.160616 -287.608955) (xy 207.190934 -287.558142) (xy 207.228393 -287.512337)
			(xy 207.272177 -287.472536) (xy 207.321336 -287.439602) (xy 207.374801 -287.414252) (xy 207.431412 -287.397036)
			(xy 207.489939 -287.388327) (xy 207.519524 -287.387792) (xy 207.547672 -287.388268) (xy 207.603415 -287.396149)
			(xy 207.657507 -287.411753) (xy 207.708882 -287.434772) (xy 207.756531 -287.464754) (xy 207.799516 -287.501109)
			(xy 207.83699 -287.543121) (xy 207.868217 -287.589964) (xy 207.892582 -287.640716) (xy 207.909605 -287.694377)
			(xy 207.914748 -287.722056) (xy 207.916526 -287.73247) (xy 207.928464 -287.750504) (xy 208.009744 -287.802574)
			(xy 208.030826 -287.805876) (xy 208.04124 -287.803082) (xy 208.065488 -287.797005) (xy 208.115052 -287.790505)
			(xy 208.140046 -287.790128) (xy 208.167298 -287.790545) (xy 208.221246 -287.798308) (xy 208.27354 -287.813668)
			(xy 208.323116 -287.836314) (xy 208.368965 -287.865784) (xy 208.410153 -287.901479) (xy 208.445843 -287.942672)
			(xy 208.475308 -287.988525) (xy 208.497948 -288.038103) (xy 208.513302 -288.0904) (xy 208.521058 -288.144348)
			(xy 208.521058 -288.198852) (xy 208.513302 -288.252801) (xy 208.497948 -288.305097) (xy 208.475308 -288.354675)
			(xy 208.445843 -288.400528) (xy 208.410153 -288.441721) (xy 208.368965 -288.477416) (xy 208.323116 -288.506886)
			(xy 208.27354 -288.529532) (xy 208.221246 -288.544892) (xy 208.167298 -288.552655) (xy 208.140046 -288.553144)
			(xy 208.111055 -288.552635) (xy 208.05374 -288.543867) (xy 207.998412 -288.526526) (xy 207.946345 -288.501013)
			(xy 207.898739 -288.467913) (xy 207.85669 -288.42799) (xy 207.821168 -288.382164) (xy 207.792989 -288.33149)
			(xy 207.772804 -288.277135) (xy 207.766412 -288.248852) (xy 207.764126 -288.238184) (xy 207.751934 -288.220912)
			(xy 207.668622 -288.171636) (xy 207.64754 -288.169096) (xy 207.637126 -288.172144) (xy 207.608429 -288.180411)
			(xy 207.549382 -288.189337) (xy 207.519524 -288.189924) (xy 207.504992 -288.18977) (xy 207.476007 -288.187606)
			(xy 207.461612 -288.185606) (xy 207.451452 -288.184082) (xy 207.431894 -288.189162) (xy 207.357726 -288.244788)
			(xy 207.347566 -288.262314) (xy 207.346042 -288.272474) (xy 207.341975 -288.299578) (xy 207.32692 -288.352279)
			(xy 207.304475 -288.402282) (xy 207.275104 -288.448557) (xy 207.23941 -288.49015) (xy 207.19813 -288.526206)
			(xy 207.152114 -288.555981) (xy 207.102309 -288.578861) (xy 207.049742 -288.594377) (xy 206.995495 -288.602207)
			(xy 206.96809 -288.602674) (xy 206.940837 -288.602255) (xy 206.886885 -288.594497) (xy 206.834587 -288.57914)
			(xy 206.785007 -288.556496) (xy 206.739154 -288.527027) (xy 206.697961 -288.491332) (xy 206.662267 -288.450138)
			(xy 206.632799 -288.404284) (xy 206.610157 -288.354703) (xy 206.594801 -288.302405) (xy 206.587044 -288.248453)
			(xy 205.729451 -288.248453) (xy 205.687859 -288.254435) (xy 205.659228 -288.254948) (xy 205.633654 -288.254557)
			(xy 205.582914 -288.248113) (xy 205.533404 -288.235274) (xy 205.485927 -288.216249) (xy 205.463394 -288.204148)
			(xy 205.452472 -288.197798) (xy 205.42758 -288.19729) (xy 205.32979 -288.245042) (xy 205.315312 -288.265108)
			(xy 205.31328 -288.277554) (xy 205.308806 -288.304327) (xy 205.293258 -288.356333) (xy 205.270496 -288.405609)
			(xy 205.240978 -288.451162) (xy 205.205302 -288.49207) (xy 205.164187 -288.527509) (xy 205.118463 -288.556761)
			(xy 205.069055 -288.579237) (xy 205.01696 -288.594482) (xy 204.96323 -288.602189) (xy 204.93609 -288.602674)
			(xy 204.909972 -288.602264) (xy 204.858225 -288.595124) (xy 204.807936 -288.580992) (xy 204.760045 -288.560133)
			(xy 204.715447 -288.532936) (xy 204.674975 -288.499911) (xy 204.639386 -288.461673) (xy 204.609346 -288.418938)
			(xy 204.597 -288.395918) (xy 204.590396 -288.382964) (xy 204.566266 -288.368232) (xy 204.446886 -288.368232)
			(xy 204.422756 -288.382964) (xy 204.416152 -288.395918) (xy 204.40381 -288.418941) (xy 204.373777 -288.461683)
			(xy 204.338192 -288.499926) (xy 204.29772 -288.532954) (xy 204.25312 -288.560149) (xy 204.205224 -288.581002)
			(xy 204.154931 -288.595123) (xy 204.103181 -288.602248) (xy 204.077062 -288.602674) (xy 204.04981 -288.602254)
			(xy 203.995862 -288.594492) (xy 203.943567 -288.579132) (xy 203.89399 -288.556487) (xy 203.84814 -288.527017)
			(xy 203.806951 -288.491322) (xy 203.77126 -288.450129) (xy 203.741795 -288.404277) (xy 203.719155 -288.354698)
			(xy 203.7038 -288.302401) (xy 203.696044 -288.248452) (xy 198.850472 -288.248452) (xy 198.854835 -288.275299)
			(xy 198.85533 -288.299906) (xy 198.854835 -288.324513) (xy 198.84694 -288.37309) (xy 198.831356 -288.419771)
			(xy 198.808485 -288.463348) (xy 198.77892 -288.502692) (xy 198.743427 -288.536784) (xy 198.702924 -288.56474)
			(xy 198.658462 -288.585838) (xy 198.611191 -288.59953) (xy 198.562336 -288.605462) (xy 198.513161 -288.603481)
			(xy 198.464942 -288.593637) (xy 198.418926 -288.576185) (xy 198.376305 -288.551578) (xy 198.338184 -288.520453)
			(xy 198.305549 -288.483616) (xy 198.279246 -288.44202) (xy 198.259955 -288.396744) (xy 198.248178 -288.34896)
			(xy 198.244218 -288.299906) (xy 197.90537 -288.299906) (xy 197.904875 -288.324513) (xy 197.89698 -288.37309)
			(xy 197.881396 -288.419771) (xy 197.858525 -288.463348) (xy 197.82896 -288.502692) (xy 197.793467 -288.536784)
			(xy 197.752964 -288.56474) (xy 197.708502 -288.585838) (xy 197.661231 -288.59953) (xy 197.612376 -288.605462)
			(xy 197.563201 -288.603481) (xy 197.514982 -288.593637) (xy 197.468966 -288.576185) (xy 197.426345 -288.551578)
			(xy 197.388224 -288.520453) (xy 197.355589 -288.483616) (xy 197.329286 -288.44202) (xy 197.309995 -288.396744)
			(xy 197.298218 -288.34896) (xy 197.294258 -288.299906) (xy 196.977 -288.299906) (xy 196.976496 -288.325614)
			(xy 196.968453 -288.376396) (xy 196.952565 -288.425295) (xy 196.929222 -288.471107) (xy 196.899001 -288.512703)
			(xy 196.862645 -288.549059) (xy 196.821049 -288.57928) (xy 196.775237 -288.602623) (xy 196.726338 -288.618511)
			(xy 196.675556 -288.626554) (xy 196.62414 -288.626554) (xy 196.573358 -288.618511) (xy 196.524459 -288.602623)
			(xy 196.478647 -288.57928) (xy 196.437051 -288.549059) (xy 196.400695 -288.512703) (xy 196.370474 -288.471107)
			(xy 196.347131 -288.425295) (xy 196.331243 -288.376396) (xy 196.3232 -288.325614) (xy 196.026536 -288.325614)
			(xy 196.018493 -288.376396) (xy 196.002605 -288.425295) (xy 195.979262 -288.471107) (xy 195.949041 -288.512703)
			(xy 195.912685 -288.549059) (xy 195.871089 -288.57928) (xy 195.825277 -288.602623) (xy 195.776378 -288.618511)
			(xy 195.725596 -288.626554) (xy 195.67418 -288.626554) (xy 195.623398 -288.618511) (xy 195.574499 -288.602623)
			(xy 195.528687 -288.57928) (xy 195.487091 -288.549059) (xy 195.450735 -288.512703) (xy 195.420514 -288.471107)
			(xy 195.397171 -288.425295) (xy 195.381283 -288.376396) (xy 195.37324 -288.325614) (xy 195.054562 -288.325614)
			(xy 195.046846 -288.37309) (xy 195.031262 -288.419771) (xy 195.008391 -288.463348) (xy 194.978826 -288.502692)
			(xy 194.943333 -288.536784) (xy 194.90283 -288.56474) (xy 194.858368 -288.585838) (xy 194.811097 -288.59953)
			(xy 194.762242 -288.605462) (xy 194.713067 -288.603481) (xy 194.664848 -288.593637) (xy 194.618832 -288.576185)
			(xy 194.576211 -288.551578) (xy 194.53809 -288.520453) (xy 194.505455 -288.483616) (xy 194.479152 -288.44202)
			(xy 194.459861 -288.396744) (xy 194.448084 -288.34896) (xy 194.444124 -288.299906) (xy 194.12712 -288.299906)
			(xy 194.126616 -288.325614) (xy 194.118573 -288.376396) (xy 194.102685 -288.425295) (xy 194.079342 -288.471107)
			(xy 194.049121 -288.512703) (xy 194.012765 -288.549059) (xy 193.971169 -288.57928) (xy 193.925357 -288.602623)
			(xy 193.876458 -288.618511) (xy 193.825676 -288.626554) (xy 193.77426 -288.626554) (xy 193.723478 -288.618511)
			(xy 193.674579 -288.602623) (xy 193.628767 -288.57928) (xy 193.587171 -288.549059) (xy 193.550815 -288.512703)
			(xy 193.520594 -288.471107) (xy 193.497251 -288.425295) (xy 193.481363 -288.376396) (xy 193.47332 -288.325614)
			(xy 193.176656 -288.325614) (xy 193.168613 -288.376396) (xy 193.152725 -288.425295) (xy 193.129382 -288.471107)
			(xy 193.099161 -288.512703) (xy 193.062805 -288.549059) (xy 193.021209 -288.57928) (xy 192.975397 -288.602623)
			(xy 192.926498 -288.618511) (xy 192.875716 -288.626554) (xy 192.8243 -288.626554) (xy 192.773518 -288.618511)
			(xy 192.724619 -288.602623) (xy 192.678807 -288.57928) (xy 192.637211 -288.549059) (xy 192.600855 -288.512703)
			(xy 192.570634 -288.471107) (xy 192.547291 -288.425295) (xy 192.531403 -288.376396) (xy 192.52336 -288.325614)
			(xy 192.204682 -288.325614) (xy 192.196966 -288.37309) (xy 192.181382 -288.419771) (xy 192.158511 -288.463348)
			(xy 192.128946 -288.502692) (xy 192.093453 -288.536784) (xy 192.05295 -288.56474) (xy 192.008488 -288.585838)
			(xy 191.961217 -288.59953) (xy 191.912362 -288.605462) (xy 191.863187 -288.603481) (xy 191.814968 -288.593637)
			(xy 191.768952 -288.576185) (xy 191.726331 -288.551578) (xy 191.68821 -288.520453) (xy 191.655575 -288.483616)
			(xy 191.629272 -288.44202) (xy 191.609981 -288.396744) (xy 191.598204 -288.34896) (xy 191.594244 -288.299906)
			(xy 191.255396 -288.299906) (xy 191.254901 -288.324513) (xy 191.247006 -288.37309) (xy 191.231422 -288.419771)
			(xy 191.208551 -288.463348) (xy 191.178986 -288.502692) (xy 191.143493 -288.536784) (xy 191.10299 -288.56474)
			(xy 191.058528 -288.585838) (xy 191.011257 -288.59953) (xy 190.962402 -288.605462) (xy 190.913227 -288.603481)
			(xy 190.865008 -288.593637) (xy 190.818992 -288.576185) (xy 190.776371 -288.551578) (xy 190.73825 -288.520453)
			(xy 190.705615 -288.483616) (xy 190.679312 -288.44202) (xy 190.660021 -288.396744) (xy 190.648244 -288.34896)
			(xy 190.644284 -288.299906) (xy 190.305182 -288.299906) (xy 190.304687 -288.324513) (xy 190.296792 -288.37309)
			(xy 190.281208 -288.419771) (xy 190.258337 -288.463348) (xy 190.228772 -288.502692) (xy 190.193279 -288.536784)
			(xy 190.152776 -288.56474) (xy 190.108314 -288.585838) (xy 190.061043 -288.59953) (xy 190.012188 -288.605462)
			(xy 189.963013 -288.603481) (xy 189.914794 -288.593637) (xy 189.868778 -288.576185) (xy 189.826157 -288.551578)
			(xy 189.788036 -288.520453) (xy 189.755401 -288.483616) (xy 189.729098 -288.44202) (xy 189.709807 -288.396744)
			(xy 189.69803 -288.34896) (xy 189.69407 -288.299906) (xy 165.283388 -288.299906) (xy 165.283388 -288.429446)
			(xy 165.283819 -288.439513) (xy 165.291544 -288.458106) (xy 165.298374 -288.465514) (xy 165.388544 -288.555684)
			(xy 165.39591 -288.562796) (xy 165.396672 -288.563558) (xy 165.399974 -288.566606) (xy 165.404038 -288.57067)
			(xy 165.411437 -288.577514) (xy 165.430036 -288.585239) (xy 165.440106 -288.585656) (xy 165.441376 -288.585656)
			(xy 165.51402 -288.584132) (xy 165.52355 -288.583551) (xy 165.54118 -288.576256) (xy 165.54831 -288.569908)
			(xy 165.549326 -288.568892) (xy 165.556946 -288.560764) (xy 165.574291 -288.543819) (xy 165.613344 -288.515082)
			(xy 165.656442 -288.492867) (xy 165.702506 -288.477731) (xy 165.750381 -288.470052) (xy 165.774624 -288.469578)
			(xy 165.774878 -288.469578) (xy 165.800478 -288.470105) (xy 165.850959 -288.478656) (xy 165.899307 -288.495504)
			(xy 165.944169 -288.520178) (xy 165.984288 -288.551987) (xy 166.018542 -288.590041) (xy 166.045971 -288.633274)
			(xy 166.065807 -288.680475) (xy 166.077495 -288.730323) (xy 166.079678 -288.755836) (xy 166.080186 -288.767012)
			(xy 166.08044 -288.774378) (xy 166.08044 -288.775648) (xy 166.079951 -288.800922) (xy 166.071638 -288.850781)
			(xy 166.05523 -288.898591) (xy 166.031175 -288.943048) (xy 166.00013 -288.982938) (xy 165.981888 -289.000438)
			(xy 165.974014 -289.00755) (xy 165.965632 -289.026346) (xy 165.965378 -289.038792) (xy 165.965378 -289.040824)
			(xy 165.965124 -289.056826) (xy 165.96487 -289.071812) (xy 165.96487 -289.07232) (xy 165.964616 -289.084258)
			(xy 165.964616 -289.08756) (xy 165.964108 -289.10407) (xy 165.964108 -289.109912) (xy 165.964534 -289.119981)
			(xy 165.972252 -289.138582) (xy 165.979094 -289.14598) (xy 165.98265 -289.149536) (xy 165.984428 -289.15106)
			(xy 165.990778 -289.15741) (xy 166.00932 -289.16503) (xy 166.115746 -289.16503) (xy 166.127176 -289.164776)
			(xy 166.454328 -289.164776) (xy 166.479982 -289.146996) (xy 166.485824 -289.13201) (xy 166.486332 -289.13074)
			(xy 166.506652 -289.084258) (xy 166.50589 -289.08375) (xy 166.516812 -289.057334) (xy 166.510208 -289.026854)
			(xy 166.498524 -289.015678) (xy 166.479221 -288.996801) (xy 166.446413 -288.953925) (xy 166.421012 -288.906285)
			(xy 166.403694 -288.85515) (xy 166.394919 -288.80188) (xy 166.394384 -288.774886) (xy 166.394894 -288.748899)
			(xy 166.403024 -288.697564) (xy 166.419085 -288.648134) (xy 166.442681 -288.601824) (xy 166.473231 -288.559776)
			(xy 166.509982 -288.523025) (xy 166.55203 -288.492475) (xy 166.59834 -288.468879) (xy 166.64777 -288.452818)
			(xy 166.699105 -288.444688) (xy 166.751079 -288.444688) (xy 166.802414 -288.452818) (xy 166.851844 -288.468879)
			(xy 166.898154 -288.492475) (xy 166.940202 -288.523025) (xy 166.976953 -288.559776) (xy 167.007503 -288.601824)
			(xy 167.031099 -288.648134) (xy 167.04716 -288.697564) (xy 167.05529 -288.748899) (xy 167.0558 -288.774886)
			(xy 167.055179 -288.803685) (xy 167.045206 -288.860414) (xy 167.02556 -288.914559) (xy 166.996833 -288.964483)
			(xy 166.978838 -288.986976) (xy 166.97325 -288.993834) (xy 166.96563 -289.013646) (xy 166.96405 -289.018115)
			(xy 166.962397 -289.027448) (xy 166.962328 -289.032188) (xy 166.962582 -289.04057) (xy 166.962534 -289.045717)
			(xy 166.960607 -289.055826) (xy 166.958772 -289.060636) (xy 166.954708 -289.070034) (xy 166.951269 -289.079528)
			(xy 166.951396 -289.099703) (xy 166.954962 -289.10915) (xy 166.958772 -289.118548) (xy 166.961786 -289.125035)
			(xy 166.970814 -289.136121) (xy 166.976552 -289.140392) (xy 166.976552 -289.140646) (xy 166.998396 -289.155632)
			(xy 167.002574 -289.158456) (xy 167.011791 -289.16254) (xy 167.016684 -289.16376) (xy 167.022018 -289.164776)
			(xy 167.404288 -289.164776) (xy 167.429942 -289.146996) (xy 167.435784 -289.13201) (xy 167.436292 -289.13074)
			(xy 167.456612 -289.084258) (xy 167.45585 -289.08375) (xy 167.466772 -289.057334) (xy 167.460168 -289.026854)
			(xy 167.448484 -289.015678) (xy 167.429183 -288.9968) (xy 167.396379 -288.953922) (xy 167.370981 -288.906283)
			(xy 167.353665 -288.855148) (xy 167.344892 -288.801879) (xy 167.344344 -288.774886) (xy 167.344854 -288.748899)
			(xy 167.352984 -288.697564) (xy 167.369045 -288.648134) (xy 167.392641 -288.601824) (xy 167.423191 -288.559776)
			(xy 167.459942 -288.523025) (xy 167.50199 -288.492475) (xy 167.5483 -288.468879) (xy 167.59773 -288.452818)
			(xy 167.649065 -288.444688) (xy 167.701039 -288.444688) (xy 167.752374 -288.452818) (xy 167.801804 -288.468879)
			(xy 167.848114 -288.492475) (xy 167.890162 -288.523025) (xy 167.926913 -288.559776) (xy 167.957463 -288.601824)
			(xy 167.981059 -288.648134) (xy 167.99712 -288.697564) (xy 168.00525 -288.748899) (xy 168.00576 -288.774886)
			(xy 168.005139 -288.803686) (xy 167.995168 -288.860416) (xy 167.975524 -288.914562) (xy 167.946802 -288.964489)
			(xy 167.928798 -288.986976) (xy 167.92321 -288.993834) (xy 167.91559 -289.013646) (xy 167.914011 -289.018115)
			(xy 167.912359 -289.027448) (xy 167.912288 -289.032188) (xy 167.912542 -289.04057) (xy 167.912494 -289.045717)
			(xy 167.910565 -289.055826) (xy 167.908732 -289.060636) (xy 167.904668 -289.070034) (xy 167.901231 -289.079528)
			(xy 167.901358 -289.099703) (xy 167.904922 -289.10915) (xy 167.908732 -289.118548) (xy 167.911749 -289.125032)
			(xy 167.920783 -289.13611) (xy 167.926512 -289.140392) (xy 167.926512 -289.140646) (xy 167.948356 -289.155632)
			(xy 167.952532 -289.158459) (xy 167.961748 -289.16255) (xy 167.966644 -289.16376) (xy 167.971978 -289.164776)
			(xy 168.354248 -289.164776) (xy 168.379902 -289.146996) (xy 168.385744 -289.13201) (xy 168.386252 -289.13074)
			(xy 168.406572 -289.084258) (xy 168.40581 -289.08375) (xy 168.416732 -289.057334) (xy 168.410128 -289.026854)
			(xy 168.398444 -289.015678) (xy 168.379144 -288.996799) (xy 168.346344 -288.95392) (xy 168.32095 -288.90628)
			(xy 168.303636 -288.855147) (xy 168.294864 -288.801879) (xy 168.294304 -288.774886) (xy 168.294814 -288.748899)
			(xy 168.302944 -288.697564) (xy 168.319005 -288.648134) (xy 168.342601 -288.601824) (xy 168.373151 -288.559776)
			(xy 168.409902 -288.523025) (xy 168.45195 -288.492475) (xy 168.49826 -288.468879) (xy 168.54769 -288.452818)
			(xy 168.599025 -288.444688) (xy 168.650999 -288.444688) (xy 168.702334 -288.452818) (xy 168.751764 -288.468879)
			(xy 168.798074 -288.492475) (xy 168.840122 -288.523025) (xy 168.876873 -288.559776) (xy 168.907423 -288.601824)
			(xy 168.931019 -288.648134) (xy 168.94708 -288.697564) (xy 168.95521 -288.748899) (xy 168.95572 -288.774886)
			(xy 168.955099 -288.803686) (xy 168.945127 -288.860415) (xy 168.925481 -288.91456) (xy 168.896756 -288.964485)
			(xy 168.878758 -288.986976) (xy 168.87317 -288.993834) (xy 168.86555 -289.013646) (xy 168.86397 -289.018115)
			(xy 168.862316 -289.027448) (xy 168.862248 -289.032188) (xy 168.862502 -289.04057) (xy 168.862455 -289.045717)
			(xy 168.860527 -289.055827) (xy 168.858692 -289.060636) (xy 168.854628 -289.070034) (xy 168.851192 -289.079528)
			(xy 168.851319 -289.099703) (xy 168.854882 -289.10915) (xy 168.858692 -289.118548) (xy 168.861707 -289.125034)
			(xy 168.870737 -289.136117) (xy 168.876472 -289.140392) (xy 168.876472 -289.140646) (xy 168.898316 -289.155632)
			(xy 168.902491 -289.158462) (xy 168.911705 -289.162561) (xy 168.916604 -289.16376) (xy 168.921938 -289.164776)
			(xy 169.304208 -289.164776) (xy 169.329862 -289.146996) (xy 169.335704 -289.13201) (xy 169.336212 -289.13074)
			(xy 169.356532 -289.084258) (xy 169.35577 -289.08375) (xy 169.366692 -289.057334) (xy 169.360088 -289.026854)
			(xy 169.348404 -289.015678) (xy 169.329102 -288.9968) (xy 169.296296 -288.953924) (xy 169.270897 -288.906284)
			(xy 169.25358 -288.855149) (xy 169.244805 -288.80188) (xy 169.244264 -288.774886) (xy 169.244774 -288.748899)
			(xy 169.252904 -288.697564) (xy 169.268965 -288.648134) (xy 169.292561 -288.601824) (xy 169.323111 -288.559776)
			(xy 169.359862 -288.523025) (xy 169.40191 -288.492475) (xy 169.44822 -288.468879) (xy 169.49765 -288.452818)
			(xy 169.548985 -288.444688) (xy 169.600959 -288.444688) (xy 169.652294 -288.452818) (xy 169.701724 -288.468879)
			(xy 169.748034 -288.492475) (xy 169.790082 -288.523025) (xy 169.826833 -288.559776) (xy 169.857383 -288.601824)
			(xy 169.880979 -288.648134) (xy 169.89704 -288.697564) (xy 169.90517 -288.748899) (xy 169.90568 -288.774886)
			(xy 169.905059 -288.803685) (xy 169.895086 -288.860414) (xy 169.875438 -288.914558) (xy 169.84671 -288.96448)
			(xy 169.828718 -288.986976) (xy 169.82313 -288.993834) (xy 169.81551 -289.013646) (xy 169.81393 -289.018115)
			(xy 169.812277 -289.027448) (xy 169.812208 -289.032188) (xy 169.812462 -289.04057) (xy 169.812414 -289.045717)
			(xy 169.810486 -289.055826) (xy 169.808652 -289.060636) (xy 169.804588 -289.070034) (xy 169.80115 -289.079528)
			(xy 169.801277 -289.099703) (xy 169.804842 -289.10915) (xy 169.808652 -289.118548) (xy 169.811665 -289.125036)
			(xy 169.820691 -289.136125) (xy 169.826432 -289.140392) (xy 169.826432 -289.140646) (xy 169.848276 -289.155632)
			(xy 169.852453 -289.158457) (xy 169.861669 -289.162545) (xy 169.866564 -289.16376) (xy 169.871898 -289.164776)
			(xy 170.254168 -289.164776) (xy 170.279822 -289.146996) (xy 170.285664 -289.13201) (xy 170.286172 -289.13074)
			(xy 170.306492 -289.084258) (xy 170.30573 -289.08375) (xy 170.316652 -289.057334) (xy 170.310048 -289.026854)
			(xy 170.298364 -289.015678) (xy 170.279063 -288.9968) (xy 170.246261 -288.953921) (xy 170.220865 -288.906282)
			(xy 170.20355 -288.855148) (xy 170.194777 -288.801879) (xy 170.194224 -288.774886) (xy 170.194734 -288.748899)
			(xy 170.202864 -288.697564) (xy 170.218925 -288.648134) (xy 170.242521 -288.601824) (xy 170.273071 -288.559776)
			(xy 170.309822 -288.523025) (xy 170.35187 -288.492475) (xy 170.39818 -288.468879) (xy 170.44761 -288.452818)
			(xy 170.498945 -288.444688) (xy 170.550919 -288.444688) (xy 170.602254 -288.452818) (xy 170.651684 -288.468879)
			(xy 170.697994 -288.492475) (xy 170.740042 -288.523025) (xy 170.776793 -288.559776) (xy 170.807343 -288.601824)
			(xy 170.830939 -288.648134) (xy 170.847 -288.697564) (xy 170.85513 -288.748899) (xy 170.85564 -288.774886)
			(xy 170.855019 -288.803686) (xy 170.845047 -288.860415) (xy 170.825403 -288.914561) (xy 170.796679 -288.964487)
			(xy 170.778678 -288.986976) (xy 170.77309 -288.993834) (xy 170.76547 -289.013646) (xy 170.763889 -289.018115)
			(xy 170.762234 -289.027448) (xy 170.762168 -289.032188) (xy 170.762422 -289.04057) (xy 170.762366 -289.045716)
			(xy 170.76044 -289.055825) (xy 170.758612 -289.060636) (xy 170.754548 -289.070034) (xy 170.751111 -289.079528)
			(xy 170.751238 -289.099703) (xy 170.754802 -289.10915) (xy 170.758612 -289.118548) (xy 170.761628 -289.125033)
			(xy 170.77066 -289.136113) (xy 170.776392 -289.140392) (xy 170.776392 -289.140646) (xy 170.798236 -289.155632)
			(xy 170.802412 -289.15846) (xy 170.811626 -289.162556) (xy 170.816524 -289.16376) (xy 170.821858 -289.164776)
			(xy 171.204128 -289.164776) (xy 171.229782 -289.146996) (xy 171.235624 -289.13201) (xy 171.236132 -289.13074)
			(xy 171.256452 -289.084258) (xy 171.25569 -289.08375) (xy 171.266612 -289.057334) (xy 171.260008 -289.026854)
			(xy 171.248324 -289.015678) (xy 171.229021 -288.996801) (xy 171.196213 -288.953925) (xy 171.170812 -288.906285)
			(xy 171.153494 -288.85515) (xy 171.144719 -288.80188) (xy 171.144184 -288.774886) (xy 171.144694 -288.748899)
			(xy 171.152824 -288.697564) (xy 171.168885 -288.648134) (xy 171.192481 -288.601824) (xy 171.223031 -288.559776)
			(xy 171.259782 -288.523025) (xy 171.30183 -288.492475) (xy 171.34814 -288.468879) (xy 171.39757 -288.452818)
			(xy 171.448905 -288.444688) (xy 171.500879 -288.444688) (xy 171.552214 -288.452818) (xy 171.601644 -288.468879)
			(xy 171.647954 -288.492475) (xy 171.690002 -288.523025) (xy 171.726753 -288.559776) (xy 171.757303 -288.601824)
			(xy 171.780899 -288.648134) (xy 171.79696 -288.697564) (xy 171.80509 -288.748899) (xy 171.8056 -288.774886)
			(xy 171.804979 -288.803685) (xy 171.795006 -288.860414) (xy 171.77536 -288.914559) (xy 171.746633 -288.964483)
			(xy 171.728638 -288.986976) (xy 171.72305 -288.993834) (xy 171.71543 -289.013646) (xy 171.71385 -289.018115)
			(xy 171.712197 -289.027448) (xy 171.712128 -289.032188) (xy 171.712382 -289.04057) (xy 171.712334 -289.045717)
			(xy 171.710407 -289.055826) (xy 171.708572 -289.060636) (xy 171.704508 -289.070034) (xy 171.701069 -289.079528)
			(xy 171.701196 -289.099703) (xy 171.704762 -289.10915) (xy 171.708572 -289.118548) (xy 171.711586 -289.125035)
			(xy 171.720614 -289.136121) (xy 171.726352 -289.140392) (xy 171.726352 -289.140646) (xy 171.748196 -289.155632)
			(xy 171.752374 -289.158456) (xy 171.761591 -289.16254) (xy 171.766484 -289.16376) (xy 171.771818 -289.164776)
			(xy 172.154088 -289.164776) (xy 172.179742 -289.146996) (xy 172.185584 -289.13201) (xy 172.186092 -289.13074)
			(xy 172.206412 -289.084258) (xy 172.20565 -289.08375) (xy 172.216572 -289.057334) (xy 172.209968 -289.026854)
			(xy 172.198284 -289.015678) (xy 172.178983 -288.9968) (xy 172.146179 -288.953922) (xy 172.120781 -288.906283)
			(xy 172.103465 -288.855148) (xy 172.094692 -288.801879) (xy 172.094144 -288.774886) (xy 172.094654 -288.748899)
			(xy 172.102784 -288.697564) (xy 172.118845 -288.648134) (xy 172.142441 -288.601824) (xy 172.172991 -288.559776)
			(xy 172.209742 -288.523025) (xy 172.25179 -288.492475) (xy 172.2981 -288.468879) (xy 172.34753 -288.452818)
			(xy 172.398865 -288.444688) (xy 172.450839 -288.444688) (xy 172.502174 -288.452818) (xy 172.551604 -288.468879)
			(xy 172.597914 -288.492475) (xy 172.639962 -288.523025) (xy 172.676713 -288.559776) (xy 172.707263 -288.601824)
			(xy 172.730859 -288.648134) (xy 172.74692 -288.697564) (xy 172.75505 -288.748899) (xy 172.75556 -288.774886)
			(xy 172.754939 -288.803686) (xy 172.744968 -288.860416) (xy 172.725324 -288.914562) (xy 172.696602 -288.964489)
			(xy 172.678598 -288.986976) (xy 172.67301 -288.993834) (xy 172.66539 -289.013646) (xy 172.663811 -289.018115)
			(xy 172.662159 -289.027448) (xy 172.662088 -289.032188) (xy 172.662342 -289.04057) (xy 172.662294 -289.045717)
			(xy 172.660365 -289.055826) (xy 172.658532 -289.060636) (xy 172.654468 -289.070034) (xy 172.651031 -289.079528)
			(xy 172.651158 -289.099703) (xy 172.654722 -289.10915) (xy 172.658532 -289.118548) (xy 172.661549 -289.125032)
			(xy 172.670583 -289.13611) (xy 172.676312 -289.140392) (xy 172.676312 -289.140646) (xy 172.698156 -289.155632)
			(xy 172.702332 -289.158459) (xy 172.711548 -289.16255) (xy 172.716444 -289.16376) (xy 172.721778 -289.164776)
			(xy 173.104302 -289.164776) (xy 173.129956 -289.146996) (xy 173.135798 -289.13201) (xy 173.136306 -289.13074)
			(xy 173.156626 -289.084258) (xy 173.155864 -289.08375) (xy 173.166786 -289.057334) (xy 173.160182 -289.026854)
			(xy 173.148498 -289.015678) (xy 173.129196 -288.9968) (xy 173.096391 -288.953923) (xy 173.070992 -288.906284)
			(xy 173.053675 -288.855149) (xy 173.044901 -288.80188) (xy 173.044358 -288.774886) (xy 173.044868 -288.748899)
			(xy 173.052998 -288.697564) (xy 173.069059 -288.648134) (xy 173.092655 -288.601824) (xy 173.123205 -288.559776)
			(xy 173.159956 -288.523025) (xy 173.202004 -288.492475) (xy 173.248314 -288.468879) (xy 173.297744 -288.452818)
			(xy 173.349079 -288.444688) (xy 173.401053 -288.444688) (xy 173.452388 -288.452818) (xy 173.501818 -288.468879)
			(xy 173.548128 -288.492475) (xy 173.590176 -288.523025) (xy 173.626927 -288.559776) (xy 173.657477 -288.601824)
			(xy 173.681073 -288.648134) (xy 173.697134 -288.697564) (xy 173.705264 -288.748899) (xy 173.705774 -288.774886)
			(xy 173.705153 -288.803686) (xy 173.695183 -288.860416) (xy 173.67554 -288.914563) (xy 173.646818 -288.964491)
			(xy 173.628812 -288.986976) (xy 173.623224 -288.993834) (xy 173.615604 -289.013646) (xy 173.614024 -289.018115)
			(xy 173.612372 -289.027448) (xy 173.612302 -289.032188) (xy 173.612556 -289.04057) (xy 173.612508 -289.045717)
			(xy 173.61058 -289.055826) (xy 173.608746 -289.060636) (xy 173.604682 -289.070034) (xy 173.601244 -289.079528)
			(xy 173.601371 -289.099703) (xy 173.604936 -289.10915) (xy 173.608746 -289.118548) (xy 173.611764 -289.125031)
			(xy 173.620799 -289.136107) (xy 173.626526 -289.140392) (xy 173.626526 -289.140646) (xy 173.64837 -289.155632)
			(xy 173.652547 -289.158458) (xy 173.661763 -289.162547) (xy 173.666658 -289.16376) (xy 173.671992 -289.164776)
			(xy 174.054262 -289.164776) (xy 174.079916 -289.146996) (xy 174.085758 -289.13201) (xy 174.086266 -289.13074)
			(xy 174.106586 -289.084258) (xy 174.105824 -289.08375) (xy 174.116746 -289.057334) (xy 174.110142 -289.026854)
			(xy 174.098458 -289.015678) (xy 174.079158 -288.996799) (xy 174.046356 -288.953921) (xy 174.020961 -288.906281)
			(xy 174.003646 -288.855147) (xy 173.994873 -288.801879) (xy 173.994318 -288.774886) (xy 173.994828 -288.748899)
			(xy 174.002958 -288.697564) (xy 174.019019 -288.648134) (xy 174.042615 -288.601824) (xy 174.073165 -288.559776)
			(xy 174.109916 -288.523025) (xy 174.151964 -288.492475) (xy 174.198274 -288.468879) (xy 174.247704 -288.452818)
			(xy 174.299039 -288.444688) (xy 174.351013 -288.444688) (xy 174.402348 -288.452818) (xy 174.451778 -288.468879)
			(xy 174.498088 -288.492475) (xy 174.540136 -288.523025) (xy 174.576887 -288.559776) (xy 174.607437 -288.601824)
			(xy 174.631033 -288.648134) (xy 174.647094 -288.697564) (xy 174.655224 -288.748899) (xy 174.655734 -288.774886)
			(xy 174.655113 -288.803686) (xy 174.645141 -288.860415) (xy 174.625496 -288.914561) (xy 174.596772 -288.964486)
			(xy 174.578772 -288.986976) (xy 174.573184 -288.993834) (xy 174.565564 -289.013646) (xy 174.563983 -289.018115)
			(xy 174.562329 -289.027448) (xy 174.562262 -289.032188) (xy 174.562516 -289.04057) (xy 174.562469 -289.045717)
			(xy 174.560542 -289.055827) (xy 174.558706 -289.060636) (xy 174.554642 -289.070034) (xy 174.551206 -289.079528)
			(xy 174.551333 -289.099703) (xy 174.554896 -289.10915) (xy 174.558706 -289.118548) (xy 174.561722 -289.125033)
			(xy 174.570753 -289.136114) (xy 174.576486 -289.140392) (xy 174.576486 -289.140646) (xy 174.59833 -289.155632)
			(xy 174.602506 -289.158461) (xy 174.61172 -289.162557) (xy 174.616618 -289.16376) (xy 174.621952 -289.164776)
			(xy 175.954182 -289.164776) (xy 175.979836 -289.146996) (xy 175.985678 -289.13201) (xy 175.986186 -289.13074)
			(xy 176.006506 -289.084258) (xy 176.005744 -289.08375) (xy 176.016666 -289.057334) (xy 176.010062 -289.026854)
			(xy 175.998378 -289.015678) (xy 175.979077 -288.9968) (xy 175.946273 -288.953922) (xy 175.920876 -288.906283)
			(xy 175.90356 -288.855148) (xy 175.894787 -288.801879) (xy 175.894238 -288.774886) (xy 175.894748 -288.748899)
			(xy 175.902878 -288.697564) (xy 175.918939 -288.648134) (xy 175.942535 -288.601824) (xy 175.973085 -288.559776)
			(xy 176.009836 -288.523025) (xy 176.051884 -288.492475) (xy 176.098194 -288.468879) (xy 176.147624 -288.452818)
			(xy 176.198959 -288.444688) (xy 176.250933 -288.444688) (xy 176.302268 -288.452818) (xy 176.351698 -288.468879)
			(xy 176.398008 -288.492475) (xy 176.440056 -288.523025) (xy 176.476807 -288.559776) (xy 176.507357 -288.601824)
			(xy 176.530953 -288.648134) (xy 176.547014 -288.697564) (xy 176.555144 -288.748899) (xy 176.555654 -288.774886)
			(xy 176.555033 -288.803686) (xy 176.545062 -288.860416) (xy 176.525418 -288.914562) (xy 176.496695 -288.964489)
			(xy 176.478692 -288.986976) (xy 176.473104 -288.993834) (xy 176.465484 -289.013646) (xy 176.463905 -289.018115)
			(xy 176.462253 -289.027448) (xy 176.462182 -289.032188) (xy 176.462436 -289.04057) (xy 176.46238 -289.045716)
			(xy 176.460455 -289.055825) (xy 176.458626 -289.060636) (xy 176.454562 -289.070034) (xy 176.451125 -289.079528)
			(xy 176.451252 -289.099703) (xy 176.454816 -289.10915) (xy 176.458626 -289.118548) (xy 176.461643 -289.125032)
			(xy 176.470676 -289.136111) (xy 176.476406 -289.140392) (xy 176.476406 -289.140646) (xy 176.49825 -289.155632)
			(xy 176.502426 -289.158459) (xy 176.511641 -289.162552) (xy 176.516538 -289.16376) (xy 176.521872 -289.164776)
			(xy 176.904142 -289.164776) (xy 176.929796 -289.146996) (xy 176.935638 -289.13201) (xy 176.936146 -289.13074)
			(xy 176.956466 -289.084258) (xy 176.955704 -289.08375) (xy 176.966626 -289.057334) (xy 176.960022 -289.026854)
			(xy 176.948338 -289.015678) (xy 176.929039 -288.996799) (xy 176.896239 -288.95392) (xy 176.870845 -288.90628)
			(xy 176.853532 -288.855146) (xy 176.84476 -288.801879) (xy 176.844198 -288.774886) (xy 176.844708 -288.748899)
			(xy 176.852838 -288.697564) (xy 176.868899 -288.648134) (xy 176.892495 -288.601824) (xy 176.923045 -288.559776)
			(xy 176.959796 -288.523025) (xy 177.001844 -288.492475) (xy 177.048154 -288.468879) (xy 177.097584 -288.452818)
			(xy 177.148919 -288.444688) (xy 177.200893 -288.444688) (xy 177.252228 -288.452818) (xy 177.301658 -288.468879)
			(xy 177.347968 -288.492475) (xy 177.390016 -288.523025) (xy 177.426767 -288.559776) (xy 177.457317 -288.601824)
			(xy 177.480913 -288.648134) (xy 177.496974 -288.697564) (xy 177.505104 -288.748899) (xy 177.505614 -288.774886)
			(xy 177.504993 -288.803685) (xy 177.49502 -288.860414) (xy 177.475375 -288.914559) (xy 177.446649 -288.964484)
			(xy 177.428652 -288.986976) (xy 177.423064 -288.993834) (xy 177.415444 -289.013646) (xy 177.413864 -289.018115)
			(xy 177.41221 -289.027448) (xy 177.412142 -289.032188) (xy 177.412396 -289.04057) (xy 177.412349 -289.045717)
			(xy 177.410421 -289.055827) (xy 177.408586 -289.060636) (xy 177.404522 -289.070034) (xy 177.401087 -289.079529)
			(xy 177.401214 -289.099703) (xy 177.404776 -289.10915) (xy 177.408586 -289.118548) (xy 177.411601 -289.125034)
			(xy 177.42063 -289.136118) (xy 177.426366 -289.140392) (xy 177.426366 -289.140646) (xy 177.44821 -289.155632)
			(xy 177.452385 -289.158462) (xy 177.461599 -289.162562) (xy 177.466498 -289.16376) (xy 177.471832 -289.164776)
			(xy 177.854102 -289.164776) (xy 177.879756 -289.146996) (xy 177.885598 -289.13201) (xy 177.886106 -289.13074)
			(xy 177.906426 -289.084258) (xy 177.905664 -289.08375) (xy 177.916586 -289.057334) (xy 177.909982 -289.026854)
			(xy 177.898298 -289.015678) (xy 177.878996 -288.9968) (xy 177.846191 -288.953923) (xy 177.820792 -288.906284)
			(xy 177.803475 -288.855149) (xy 177.794701 -288.80188) (xy 177.794158 -288.774886) (xy 177.794668 -288.748899)
			(xy 177.802798 -288.697564) (xy 177.818859 -288.648134) (xy 177.842455 -288.601824) (xy 177.873005 -288.559776)
			(xy 177.909756 -288.523025) (xy 177.951804 -288.492475) (xy 177.998114 -288.468879) (xy 178.047544 -288.452818)
			(xy 178.098879 -288.444688) (xy 178.150853 -288.444688) (xy 178.202188 -288.452818) (xy 178.251618 -288.468879)
			(xy 178.297928 -288.492475) (xy 178.339976 -288.523025) (xy 178.376727 -288.559776) (xy 178.407277 -288.601824)
			(xy 178.430873 -288.648134) (xy 178.446934 -288.697564) (xy 178.455064 -288.748899) (xy 178.455574 -288.774886)
			(xy 178.454953 -288.803686) (xy 178.444983 -288.860416) (xy 178.42534 -288.914563) (xy 178.396618 -288.964491)
			(xy 178.378612 -288.986976) (xy 178.373024 -288.993834) (xy 178.365404 -289.013646) (xy 178.363824 -289.018115)
			(xy 178.362172 -289.027448) (xy 178.362102 -289.032188) (xy 178.362356 -289.04057) (xy 178.362308 -289.045717)
			(xy 178.36038 -289.055826) (xy 178.358546 -289.060636) (xy 178.354482 -289.070034) (xy 178.351044 -289.079528)
			(xy 178.351171 -289.099703) (xy 178.354736 -289.10915) (xy 178.358546 -289.118548) (xy 178.361564 -289.125031)
			(xy 178.370599 -289.136107) (xy 178.376326 -289.140392) (xy 178.376326 -289.140646) (xy 178.39817 -289.155632)
			(xy 178.402347 -289.158458) (xy 178.411563 -289.162547) (xy 178.416458 -289.16376) (xy 178.421792 -289.164776)
			(xy 178.804316 -289.164776) (xy 178.82997 -289.146996) (xy 178.835812 -289.13201) (xy 178.83632 -289.13074)
			(xy 178.85664 -289.084258) (xy 178.855878 -289.08375) (xy 178.8668 -289.057334) (xy 178.860196 -289.026854)
			(xy 178.848512 -289.015678) (xy 178.829209 -288.996801) (xy 178.796403 -288.953924) (xy 178.771003 -288.906285)
			(xy 178.753685 -288.85515) (xy 178.744911 -288.80188) (xy 178.744372 -288.774886) (xy 178.744882 -288.748899)
			(xy 178.753012 -288.697564) (xy 178.769073 -288.648134) (xy 178.792669 -288.601824) (xy 178.823219 -288.559776)
			(xy 178.85997 -288.523025) (xy 178.902018 -288.492475) (xy 178.948328 -288.468879) (xy 178.997758 -288.452818)
			(xy 179.049093 -288.444688) (xy 179.101067 -288.444688) (xy 179.152402 -288.452818) (xy 179.201832 -288.468879)
			(xy 179.248142 -288.492475) (xy 179.29019 -288.523025) (xy 179.326941 -288.559776) (xy 179.357491 -288.601824)
			(xy 179.381087 -288.648134) (xy 179.397148 -288.697564) (xy 179.405278 -288.748899) (xy 179.405788 -288.774886)
			(xy 179.405167 -288.803685) (xy 179.395194 -288.860414) (xy 179.375547 -288.914558) (xy 179.34682 -288.964481)
			(xy 179.328826 -288.986976) (xy 179.323238 -288.993834) (xy 179.315618 -289.013646) (xy 179.314038 -289.018115)
			(xy 179.312386 -289.027448) (xy 179.312316 -289.032188) (xy 179.31257 -289.04057) (xy 179.312522 -289.045717)
			(xy 179.310594 -289.055826) (xy 179.30876 -289.060636) (xy 179.304696 -289.070034) (xy 179.301257 -289.079528)
			(xy 179.301384 -289.099703) (xy 179.30495 -289.10915) (xy 179.30876 -289.118548) (xy 179.311773 -289.125036)
			(xy 179.3208 -289.136124) (xy 179.32654 -289.140392) (xy 179.32654 -289.140646) (xy 179.348384 -289.155632)
			(xy 179.352561 -289.158457) (xy 179.361778 -289.162543) (xy 179.366672 -289.16376) (xy 179.372006 -289.164776)
			(xy 179.754276 -289.164776) (xy 179.77993 -289.146996) (xy 179.785772 -289.13201) (xy 179.78628 -289.13074)
			(xy 179.8066 -289.084258) (xy 179.805838 -289.08375) (xy 179.81676 -289.057334) (xy 179.810156 -289.026854)
			(xy 179.798472 -289.015678) (xy 179.779171 -288.9968) (xy 179.746368 -288.953922) (xy 179.720971 -288.906282)
			(xy 179.703656 -288.855148) (xy 179.694883 -288.801879) (xy 179.694332 -288.774886) (xy 179.694842 -288.748899)
			(xy 179.702972 -288.697564) (xy 179.719033 -288.648134) (xy 179.742629 -288.601824) (xy 179.773179 -288.559776)
			(xy 179.80993 -288.523025) (xy 179.851978 -288.492475) (xy 179.898288 -288.468879) (xy 179.947718 -288.452818)
			(xy 179.999053 -288.444688) (xy 180.051027 -288.444688) (xy 180.102362 -288.452818) (xy 180.151792 -288.468879)
			(xy 180.198102 -288.492475) (xy 180.24015 -288.523025) (xy 180.276901 -288.559776) (xy 180.307451 -288.601824)
			(xy 180.331047 -288.648134) (xy 180.347108 -288.697564) (xy 180.355238 -288.748899) (xy 180.355748 -288.774886)
			(xy 180.355127 -288.803686) (xy 180.345155 -288.860415) (xy 180.325511 -288.914561) (xy 180.296788 -288.964488)
			(xy 180.278786 -288.986976) (xy 180.273198 -288.993834) (xy 180.265578 -289.013646) (xy 180.263997 -289.018115)
			(xy 180.262342 -289.027448) (xy 180.262276 -289.032188) (xy 180.26253 -289.04057) (xy 180.262474 -289.045716)
			(xy 180.260548 -289.055825) (xy 180.25872 -289.060636) (xy 180.254656 -289.070034) (xy 180.251219 -289.079528)
			(xy 180.251346 -289.099703) (xy 180.25491 -289.10915) (xy 180.25872 -289.118548) (xy 180.261736 -289.125033)
			(xy 180.270769 -289.136112) (xy 180.2765 -289.140392) (xy 180.2765 -289.140646) (xy 180.298344 -289.155632)
			(xy 180.30252 -289.15846) (xy 180.311735 -289.162554) (xy 180.316632 -289.16376) (xy 180.321966 -289.164776)
			(xy 180.704236 -289.164776) (xy 180.72989 -289.146996) (xy 180.735732 -289.13201) (xy 180.73624 -289.13074)
			(xy 180.75656 -289.084258) (xy 180.755798 -289.08375) (xy 180.76672 -289.057334) (xy 180.760116 -289.026854)
			(xy 180.748432 -289.015678) (xy 180.729128 -288.996801) (xy 180.69632 -288.953925) (xy 180.670918 -288.906286)
			(xy 180.6536 -288.855151) (xy 180.644825 -288.80188) (xy 180.644292 -288.774886) (xy 180.644802 -288.748899)
			(xy 180.652932 -288.697564) (xy 180.668993 -288.648134) (xy 180.692589 -288.601824) (xy 180.723139 -288.559776)
			(xy 180.75989 -288.523025) (xy 180.801938 -288.492475) (xy 180.848248 -288.468879) (xy 180.897678 -288.452818)
			(xy 180.949013 -288.444688) (xy 181.000987 -288.444688) (xy 181.052322 -288.452818) (xy 181.101752 -288.468879)
			(xy 181.148062 -288.492475) (xy 181.19011 -288.523025) (xy 181.226861 -288.559776) (xy 181.257411 -288.601824)
			(xy 181.281007 -288.648134) (xy 181.297068 -288.697564) (xy 181.305198 -288.748899) (xy 181.305708 -288.774886)
			(xy 181.305087 -288.803685) (xy 181.295114 -288.860414) (xy 181.275468 -288.914559) (xy 181.246742 -288.964484)
			(xy 181.228746 -288.986976) (xy 181.223158 -288.993834) (xy 181.215538 -289.013646) (xy 181.213958 -289.018115)
			(xy 181.212304 -289.027448) (xy 181.212236 -289.032188) (xy 181.21249 -289.04057) (xy 181.212442 -289.045717)
			(xy 181.210515 -289.055827) (xy 181.20868 -289.060636) (xy 181.204616 -289.070034) (xy 181.201181 -289.079529)
			(xy 181.201308 -289.099703) (xy 181.20487 -289.10915) (xy 181.20868 -289.118548) (xy 181.211695 -289.125034)
			(xy 181.220723 -289.136119) (xy 181.22646 -289.140392) (xy 181.22646 -289.140646) (xy 181.248304 -289.155632)
			(xy 181.252479 -289.158463) (xy 181.261692 -289.162564) (xy 181.266592 -289.16376) (xy 181.271926 -289.164776)
			(xy 181.654196 -289.164776) (xy 181.67985 -289.146996) (xy 181.685692 -289.13201) (xy 181.6862 -289.13074)
			(xy 181.70652 -289.084258) (xy 181.705758 -289.08375) (xy 181.71668 -289.057334) (xy 181.710076 -289.026854)
			(xy 181.698392 -289.015678) (xy 181.67909 -288.9968) (xy 181.646286 -288.953923) (xy 181.620887 -288.906283)
			(xy 181.603571 -288.855149) (xy 181.594797 -288.80188) (xy 181.594252 -288.774886) (xy 181.594762 -288.748899)
			(xy 181.602892 -288.697564) (xy 181.618953 -288.648134) (xy 181.642549 -288.601824) (xy 181.673099 -288.559776)
			(xy 181.70985 -288.523025) (xy 181.751898 -288.492475) (xy 181.798208 -288.468879) (xy 181.847638 -288.452818)
			(xy 181.898973 -288.444688) (xy 181.950947 -288.444688) (xy 182.002282 -288.452818) (xy 182.051712 -288.468879)
			(xy 182.098022 -288.492475) (xy 182.14007 -288.523025) (xy 182.176821 -288.559776) (xy 182.207371 -288.601824)
			(xy 182.230967 -288.648134) (xy 182.247028 -288.697564) (xy 182.255158 -288.748899) (xy 182.255668 -288.774886)
			(xy 182.255047 -288.803686) (xy 182.245076 -288.860416) (xy 182.225433 -288.914563) (xy 182.196711 -288.96449)
			(xy 182.178706 -288.986976) (xy 182.173118 -288.993834) (xy 182.165498 -289.013646) (xy 182.163919 -289.018115)
			(xy 182.162266 -289.027448) (xy 182.162196 -289.032188) (xy 182.16245 -289.04057) (xy 182.162402 -289.045717)
			(xy 182.160473 -289.055826) (xy 182.15864 -289.060636) (xy 182.154576 -289.070034) (xy 182.151138 -289.079528)
			(xy 182.151265 -289.099703) (xy 182.15483 -289.10915) (xy 182.15864 -289.118548) (xy 182.161657 -289.125032)
			(xy 182.170692 -289.136108) (xy 182.17642 -289.140392) (xy 182.17642 -289.140646) (xy 182.198264 -289.155632)
			(xy 182.202441 -289.158458) (xy 182.211656 -289.162548) (xy 182.216552 -289.16376) (xy 182.221886 -289.164776)
			(xy 182.604156 -289.164776) (xy 182.62981 -289.146996) (xy 182.635652 -289.13201) (xy 182.63616 -289.13074)
			(xy 182.65648 -289.084258) (xy 182.655718 -289.08375) (xy 182.66664 -289.057334) (xy 182.660036 -289.026854)
			(xy 182.648352 -289.015678) (xy 182.629052 -288.996799) (xy 182.596251 -288.953921) (xy 182.570856 -288.906281)
			(xy 182.553542 -288.855147) (xy 182.544769 -288.801879) (xy 182.544212 -288.774886) (xy 182.544722 -288.748899)
			(xy 182.552852 -288.697564) (xy 182.568913 -288.648134) (xy 182.592509 -288.601824) (xy 182.623059 -288.559776)
			(xy 182.65981 -288.523025) (xy 182.701858 -288.492475) (xy 182.748168 -288.468879) (xy 182.797598 -288.452818)
			(xy 182.848933 -288.444688) (xy 182.900907 -288.444688) (xy 182.952242 -288.452818) (xy 183.001672 -288.468879)
			(xy 183.047982 -288.492475) (xy 183.09003 -288.523025) (xy 183.126781 -288.559776) (xy 183.157331 -288.601824)
			(xy 183.180927 -288.648134) (xy 183.196988 -288.697564) (xy 183.205118 -288.748899) (xy 183.205628 -288.774886)
			(xy 183.205007 -288.803686) (xy 183.195035 -288.860415) (xy 183.17539 -288.91456) (xy 183.146665 -288.964486)
			(xy 183.128666 -288.986976) (xy 183.123078 -288.993834) (xy 183.115458 -289.013646) (xy 183.113877 -289.018115)
			(xy 183.112223 -289.027448) (xy 183.112156 -289.032188) (xy 183.11241 -289.04057) (xy 183.112363 -289.045717)
			(xy 183.110436 -289.055827) (xy 183.1086 -289.060636) (xy 183.104536 -289.070034) (xy 183.1011 -289.079528)
			(xy 183.101227 -289.099703) (xy 183.10479 -289.10915) (xy 183.1086 -289.118548) (xy 183.111615 -289.125033)
			(xy 183.120646 -289.136116) (xy 183.12638 -289.140392) (xy 183.12638 -289.140646) (xy 183.148224 -289.155632)
			(xy 183.152399 -289.158461) (xy 183.161614 -289.162559) (xy 183.166512 -289.16376) (xy 183.171846 -289.164776)
			(xy 183.554116 -289.164776) (xy 183.57977 -289.146996) (xy 183.585612 -289.13201) (xy 183.58612 -289.13074)
			(xy 183.60644 -289.084258) (xy 183.605678 -289.08375) (xy 183.6166 -289.057334) (xy 183.609996 -289.026854)
			(xy 183.598312 -289.015678) (xy 183.579009 -288.996801) (xy 183.546203 -288.953924) (xy 183.520803 -288.906285)
			(xy 183.503485 -288.85515) (xy 183.494711 -288.80188) (xy 183.494172 -288.774886) (xy 183.494682 -288.748899)
			(xy 183.502812 -288.697564) (xy 183.518873 -288.648134) (xy 183.542469 -288.601824) (xy 183.573019 -288.559776)
			(xy 183.60977 -288.523025) (xy 183.651818 -288.492475) (xy 183.698128 -288.468879) (xy 183.747558 -288.452818)
			(xy 183.798893 -288.444688) (xy 183.850867 -288.444688) (xy 183.902202 -288.452818) (xy 183.951632 -288.468879)
			(xy 183.997942 -288.492475) (xy 184.03999 -288.523025) (xy 184.076741 -288.559776) (xy 184.107291 -288.601824)
			(xy 184.130887 -288.648134) (xy 184.146948 -288.697564) (xy 184.155078 -288.748899) (xy 184.155588 -288.774886)
			(xy 184.469036 -288.774886) (xy 184.472996 -288.725832) (xy 184.484773 -288.678048) (xy 184.504064 -288.632772)
			(xy 184.530367 -288.591176) (xy 184.563002 -288.554339) (xy 184.601123 -288.523214) (xy 184.643744 -288.498607)
			(xy 184.68976 -288.481155) (xy 184.737979 -288.471311) (xy 184.787154 -288.46933) (xy 184.836009 -288.475262)
			(xy 184.88328 -288.488954) (xy 184.927742 -288.510052) (xy 184.968245 -288.538008) (xy 185.003738 -288.5721)
			(xy 185.033303 -288.611444) (xy 185.056174 -288.655021) (xy 185.071758 -288.701702) (xy 185.079653 -288.750279)
			(xy 185.080148 -288.774886) (xy 185.41925 -288.774886) (xy 185.42321 -288.725832) (xy 185.434987 -288.678048)
			(xy 185.454278 -288.632772) (xy 185.480581 -288.591176) (xy 185.513216 -288.554339) (xy 185.551337 -288.523214)
			(xy 185.593958 -288.498607) (xy 185.639974 -288.481155) (xy 185.688193 -288.471311) (xy 185.737368 -288.46933)
			(xy 185.786223 -288.475262) (xy 185.833494 -288.488954) (xy 185.877956 -288.510052) (xy 185.918459 -288.538008)
			(xy 185.953952 -288.5721) (xy 185.983517 -288.611444) (xy 186.006388 -288.655021) (xy 186.021972 -288.701702)
			(xy 186.029867 -288.750279) (xy 186.030362 -288.774886) (xy 186.36921 -288.774886) (xy 186.37317 -288.725832)
			(xy 186.384947 -288.678048) (xy 186.404238 -288.632772) (xy 186.430541 -288.591176) (xy 186.463176 -288.554339)
			(xy 186.501297 -288.523214) (xy 186.543918 -288.498607) (xy 186.589934 -288.481155) (xy 186.638153 -288.471311)
			(xy 186.687328 -288.46933) (xy 186.736183 -288.475262) (xy 186.783454 -288.488954) (xy 186.827916 -288.510052)
			(xy 186.868419 -288.538008) (xy 186.903912 -288.5721) (xy 186.933477 -288.611444) (xy 186.956348 -288.655021)
			(xy 186.971932 -288.701702) (xy 186.979827 -288.750279) (xy 186.980322 -288.774886) (xy 187.31917 -288.774886)
			(xy 187.32313 -288.725832) (xy 187.334907 -288.678048) (xy 187.354198 -288.632772) (xy 187.380501 -288.591176)
			(xy 187.413136 -288.554339) (xy 187.451257 -288.523214) (xy 187.493878 -288.498607) (xy 187.539894 -288.481155)
			(xy 187.588113 -288.471311) (xy 187.637288 -288.46933) (xy 187.686143 -288.475262) (xy 187.733414 -288.488954)
			(xy 187.777876 -288.510052) (xy 187.818379 -288.538008) (xy 187.853872 -288.5721) (xy 187.883437 -288.611444)
			(xy 187.906308 -288.655021) (xy 187.921892 -288.701702) (xy 187.929787 -288.750279) (xy 187.930282 -288.774886)
			(xy 188.26913 -288.774886) (xy 188.27309 -288.725832) (xy 188.284867 -288.678048) (xy 188.304158 -288.632772)
			(xy 188.330461 -288.591176) (xy 188.363096 -288.554339) (xy 188.401217 -288.523214) (xy 188.443838 -288.498607)
			(xy 188.489854 -288.481155) (xy 188.538073 -288.471311) (xy 188.587248 -288.46933) (xy 188.636103 -288.475262)
			(xy 188.683374 -288.488954) (xy 188.727836 -288.510052) (xy 188.768339 -288.538008) (xy 188.803832 -288.5721)
			(xy 188.833397 -288.611444) (xy 188.856268 -288.655021) (xy 188.871852 -288.701702) (xy 188.879747 -288.750279)
			(xy 188.880242 -288.774886) (xy 188.879747 -288.799493) (xy 188.871852 -288.84807) (xy 188.856268 -288.894751)
			(xy 188.833397 -288.938328) (xy 188.803832 -288.977672) (xy 188.768339 -289.011764) (xy 188.727836 -289.03972)
			(xy 188.683374 -289.060818) (xy 188.636103 -289.07451) (xy 188.587248 -289.080442) (xy 188.538073 -289.078461)
			(xy 188.489854 -289.068617) (xy 188.443838 -289.051165) (xy 188.401217 -289.026558) (xy 188.363096 -288.995433)
			(xy 188.330461 -288.958596) (xy 188.304158 -288.917) (xy 188.284867 -288.871724) (xy 188.27309 -288.82394)
			(xy 188.26913 -288.774886) (xy 187.930282 -288.774886) (xy 187.929787 -288.799493) (xy 187.921892 -288.84807)
			(xy 187.906308 -288.894751) (xy 187.883437 -288.938328) (xy 187.853872 -288.977672) (xy 187.818379 -289.011764)
			(xy 187.777876 -289.03972) (xy 187.733414 -289.060818) (xy 187.686143 -289.07451) (xy 187.637288 -289.080442)
			(xy 187.588113 -289.078461) (xy 187.539894 -289.068617) (xy 187.493878 -289.051165) (xy 187.451257 -289.026558)
			(xy 187.413136 -288.995433) (xy 187.380501 -288.958596) (xy 187.354198 -288.917) (xy 187.334907 -288.871724)
			(xy 187.32313 -288.82394) (xy 187.31917 -288.774886) (xy 186.980322 -288.774886) (xy 186.979827 -288.799493)
			(xy 186.971932 -288.84807) (xy 186.956348 -288.894751) (xy 186.933477 -288.938328) (xy 186.903912 -288.977672)
			(xy 186.868419 -289.011764) (xy 186.827916 -289.03972) (xy 186.783454 -289.060818) (xy 186.736183 -289.07451)
			(xy 186.687328 -289.080442) (xy 186.638153 -289.078461) (xy 186.589934 -289.068617) (xy 186.543918 -289.051165)
			(xy 186.501297 -289.026558) (xy 186.463176 -288.995433) (xy 186.430541 -288.958596) (xy 186.404238 -288.917)
			(xy 186.384947 -288.871724) (xy 186.37317 -288.82394) (xy 186.36921 -288.774886) (xy 186.030362 -288.774886)
			(xy 186.029867 -288.799493) (xy 186.021972 -288.84807) (xy 186.006388 -288.894751) (xy 185.983517 -288.938328)
			(xy 185.953952 -288.977672) (xy 185.918459 -289.011764) (xy 185.877956 -289.03972) (xy 185.833494 -289.060818)
			(xy 185.786223 -289.07451) (xy 185.737368 -289.080442) (xy 185.688193 -289.078461) (xy 185.639974 -289.068617)
			(xy 185.593958 -289.051165) (xy 185.551337 -289.026558) (xy 185.513216 -288.995433) (xy 185.480581 -288.958596)
			(xy 185.454278 -288.917) (xy 185.434987 -288.871724) (xy 185.42321 -288.82394) (xy 185.41925 -288.774886)
			(xy 185.080148 -288.774886) (xy 185.079653 -288.799493) (xy 185.071758 -288.84807) (xy 185.056174 -288.894751)
			(xy 185.033303 -288.938328) (xy 185.003738 -288.977672) (xy 184.968245 -289.011764) (xy 184.927742 -289.03972)
			(xy 184.88328 -289.060818) (xy 184.836009 -289.07451) (xy 184.787154 -289.080442) (xy 184.737979 -289.078461)
			(xy 184.68976 -289.068617) (xy 184.643744 -289.051165) (xy 184.601123 -289.026558) (xy 184.563002 -288.995433)
			(xy 184.530367 -288.958596) (xy 184.504064 -288.917) (xy 184.484773 -288.871724) (xy 184.472996 -288.82394)
			(xy 184.469036 -288.774886) (xy 184.155588 -288.774886) (xy 184.154967 -288.803685) (xy 184.144994 -288.860414)
			(xy 184.125347 -288.914558) (xy 184.09662 -288.964481) (xy 184.078626 -288.986976) (xy 184.073038 -288.993834)
			(xy 184.065418 -289.013646) (xy 184.063838 -289.018115) (xy 184.062186 -289.027448) (xy 184.062116 -289.032188)
			(xy 184.06237 -289.04057) (xy 184.062322 -289.045717) (xy 184.060394 -289.055826) (xy 184.05856 -289.060636)
			(xy 184.054496 -289.070034) (xy 184.051057 -289.079528) (xy 184.051184 -289.099703) (xy 184.05475 -289.10915)
			(xy 184.05856 -289.118548) (xy 184.061573 -289.125036) (xy 184.0706 -289.136124) (xy 184.07634 -289.140392)
			(xy 184.07634 -289.140646) (xy 184.098184 -289.155632) (xy 184.102361 -289.158457) (xy 184.111578 -289.162543)
			(xy 184.116472 -289.16376) (xy 184.121806 -289.164776) (xy 184.520078 -289.164776) (xy 184.52084 -289.164776)
			(xy 184.522872 -289.16503) (xy 184.625488 -289.16503) (xy 184.635559 -289.165452) (xy 184.654163 -289.173166)
			(xy 184.661556 -289.180016) (xy 184.731914 -289.250374) (xy 184.732676 -289.250882) (xy 184.735978 -289.254184)
			(xy 184.797446 -289.315652) (xy 184.797446 -289.315906) (xy 184.983882 -289.502342) (xy 184.984644 -289.50285)
			(xy 184.996328 -289.514534) (xy 184.996836 -289.515296) (xy 185.247534 -289.765994) (xy 185.252861 -289.770952)
			(xy 185.265627 -289.77792) (xy 185.27268 -289.77971) (xy 185.27987 -289.78105) (xy 185.294453 -289.780018)
			(xy 185.301382 -289.777678) (xy 185.373518 -289.7505) (xy 185.380028 -289.747879) (xy 185.391375 -289.739633)
			(xy 185.39587 -289.734244) (xy 185.396124 -289.73399) (xy 185.415936 -289.707574) (xy 185.421016 -289.694874)
			(xy 185.421778 -289.68827) (xy 185.425216 -289.664026) (xy 185.438804 -289.616986) (xy 185.459718 -289.572714)
			(xy 185.487422 -289.532342) (xy 185.521207 -289.496902) (xy 185.56021 -289.467302) (xy 185.603433 -289.444298)
			(xy 185.649771 -289.428479) (xy 185.698038 -289.420249) (xy 185.722514 -289.419538) (xy 185.725054 -289.419538)
			(xy 185.749048 -289.419981) (xy 185.796447 -289.427482) (xy 185.842087 -289.442307) (xy 185.884847 -289.464091)
			(xy 185.923671 -289.492296) (xy 185.957604 -289.526229) (xy 185.985809 -289.565053) (xy 186.007593 -289.607813)
			(xy 186.022418 -289.653453) (xy 186.029919 -289.700852) (xy 186.030362 -289.724846) (xy 186.36921 -289.724846)
			(xy 186.37317 -289.675792) (xy 186.384947 -289.628008) (xy 186.404238 -289.582732) (xy 186.430541 -289.541136)
			(xy 186.463176 -289.504299) (xy 186.501297 -289.473174) (xy 186.543918 -289.448567) (xy 186.589934 -289.431115)
			(xy 186.638153 -289.421271) (xy 186.687328 -289.41929) (xy 186.736183 -289.425222) (xy 186.783454 -289.438914)
			(xy 186.827916 -289.460012) (xy 186.868419 -289.487968) (xy 186.903912 -289.52206) (xy 186.933477 -289.561404)
			(xy 186.956348 -289.604981) (xy 186.971932 -289.651662) (xy 186.979827 -289.700239) (xy 186.980322 -289.724846)
			(xy 187.31917 -289.724846) (xy 187.32313 -289.675792) (xy 187.334907 -289.628008) (xy 187.354198 -289.582732)
			(xy 187.380501 -289.541136) (xy 187.413136 -289.504299) (xy 187.451257 -289.473174) (xy 187.493878 -289.448567)
			(xy 187.539894 -289.431115) (xy 187.588113 -289.421271) (xy 187.637288 -289.41929) (xy 187.686143 -289.425222)
			(xy 187.733414 -289.438914) (xy 187.777876 -289.460012) (xy 187.818379 -289.487968) (xy 187.853872 -289.52206)
			(xy 187.883437 -289.561404) (xy 187.906308 -289.604981) (xy 187.921892 -289.651662) (xy 187.929787 -289.700239)
			(xy 187.930282 -289.724846) (xy 188.26913 -289.724846) (xy 188.27309 -289.675792) (xy 188.284867 -289.628008)
			(xy 188.304158 -289.582732) (xy 188.330461 -289.541136) (xy 188.363096 -289.504299) (xy 188.401217 -289.473174)
			(xy 188.443838 -289.448567) (xy 188.489854 -289.431115) (xy 188.538073 -289.421271) (xy 188.587248 -289.41929)
			(xy 188.636103 -289.425222) (xy 188.683374 -289.438914) (xy 188.727836 -289.460012) (xy 188.768339 -289.487968)
			(xy 188.803832 -289.52206) (xy 188.833397 -289.561404) (xy 188.856268 -289.604981) (xy 188.871852 -289.651662)
			(xy 188.879747 -289.700239) (xy 188.880074 -289.716508) (xy 189.219227 -289.716508) (xy 189.224595 -289.667167)
			(xy 189.237875 -289.619344) (xy 189.258716 -289.574299) (xy 189.28657 -289.53322) (xy 189.320702 -289.497187)
			(xy 189.360214 -289.467151) (xy 189.404065 -289.443903) (xy 189.451099 -289.428054) (xy 189.500078 -289.420024)
			(xy 189.524894 -289.419538) (xy 189.539077 -289.419715) (xy 189.567317 -289.422387) (xy 189.581282 -289.424872)
			(xy 189.593728 -289.427158) (xy 189.61735 -289.419792) (xy 189.69482 -289.342322) (xy 189.702186 -289.3187)
			(xy 189.6999 -289.306254) (xy 189.697421 -289.292289) (xy 189.694751 -289.264049) (xy 189.694566 -289.249866)
			(xy 189.695088 -289.224611) (xy 189.703401 -289.174789) (xy 189.719802 -289.127015) (xy 189.743843 -289.082592)
			(xy 189.774867 -289.042732) (xy 189.812029 -289.008522) (xy 189.854315 -288.980896) (xy 189.900571 -288.960606)
			(xy 189.949536 -288.948206) (xy 189.999874 -288.944035) (xy 190.050212 -288.948206) (xy 190.099177 -288.960606)
			(xy 190.145433 -288.980896) (xy 190.187719 -289.008522) (xy 190.224881 -289.042732) (xy 190.255905 -289.082592)
			(xy 190.279946 -289.127015) (xy 190.296347 -289.174789) (xy 190.30466 -289.224611) (xy 190.305182 -289.249866)
			(xy 190.305001 -289.264049) (xy 190.302332 -289.292289) (xy 190.299848 -289.306254) (xy 190.297562 -289.3187)
			(xy 190.304928 -289.342576) (xy 190.382144 -289.419792) (xy 190.406274 -289.427158) (xy 190.418466 -289.424872)
			(xy 190.432494 -289.422381) (xy 190.460862 -289.419713) (xy 190.475108 -289.419538) (xy 190.499927 -289.419986)
			(xy 190.548912 -289.428018) (xy 190.595952 -289.443868) (xy 190.639808 -289.46712) (xy 190.679325 -289.49716)
			(xy 190.713461 -289.533197) (xy 190.741318 -289.574282) (xy 190.762162 -289.619332) (xy 190.775442 -289.667161)
			(xy 190.780811 -289.716509) (xy 190.780359 -289.724846) (xy 192.069224 -289.724846) (xy 192.073184 -289.675792)
			(xy 192.084961 -289.628008) (xy 192.104252 -289.582732) (xy 192.130555 -289.541136) (xy 192.16319 -289.504299)
			(xy 192.201311 -289.473174) (xy 192.243932 -289.448567) (xy 192.289948 -289.431115) (xy 192.338167 -289.421271)
			(xy 192.387342 -289.41929) (xy 192.436197 -289.425222) (xy 192.483468 -289.438914) (xy 192.52793 -289.460012)
			(xy 192.568433 -289.487968) (xy 192.603926 -289.52206) (xy 192.633491 -289.561404) (xy 192.656362 -289.604981)
			(xy 192.671946 -289.651662) (xy 192.679841 -289.700239) (xy 192.680336 -289.724846) (xy 193.019184 -289.724846)
			(xy 193.023144 -289.675792) (xy 193.034921 -289.628008) (xy 193.054212 -289.582732) (xy 193.080515 -289.541136)
			(xy 193.11315 -289.504299) (xy 193.151271 -289.473174) (xy 193.193892 -289.448567) (xy 193.239908 -289.431115)
			(xy 193.288127 -289.421271) (xy 193.337302 -289.41929) (xy 193.386157 -289.425222) (xy 193.433428 -289.438914)
			(xy 193.47789 -289.460012) (xy 193.518393 -289.487968) (xy 193.553886 -289.52206) (xy 193.583451 -289.561404)
			(xy 193.606322 -289.604981) (xy 193.621906 -289.651662) (xy 193.629801 -289.700239) (xy 193.630296 -289.724846)
			(xy 193.969144 -289.724846) (xy 193.973104 -289.675792) (xy 193.984881 -289.628008) (xy 194.004172 -289.582732)
			(xy 194.030475 -289.541136) (xy 194.06311 -289.504299) (xy 194.101231 -289.473174) (xy 194.143852 -289.448567)
			(xy 194.189868 -289.431115) (xy 194.238087 -289.421271) (xy 194.287262 -289.41929) (xy 194.336117 -289.425222)
			(xy 194.383388 -289.438914) (xy 194.42785 -289.460012) (xy 194.468353 -289.487968) (xy 194.503846 -289.52206)
			(xy 194.533411 -289.561404) (xy 194.556282 -289.604981) (xy 194.571866 -289.651662) (xy 194.579761 -289.700239)
			(xy 194.580088 -289.716499) (xy 194.919228 -289.716499) (xy 194.924597 -289.667157) (xy 194.937878 -289.619334)
			(xy 194.958721 -289.57429) (xy 194.986577 -289.533211) (xy 195.020711 -289.497179) (xy 195.060225 -289.467144)
			(xy 195.104077 -289.443897) (xy 195.151112 -289.428051) (xy 195.200092 -289.420023) (xy 195.224908 -289.419538)
			(xy 195.239091 -289.419713) (xy 195.267331 -289.422386) (xy 195.281296 -289.424872) (xy 195.293742 -289.427158)
			(xy 195.317364 -289.419792) (xy 195.394834 -289.342322) (xy 195.4022 -289.3187) (xy 195.399914 -289.306254)
			(xy 195.397435 -289.292288) (xy 195.394765 -289.264049) (xy 195.39458 -289.249866) (xy 195.395102 -289.224611)
			(xy 195.403415 -289.174789) (xy 195.419816 -289.127015) (xy 195.443857 -289.082592) (xy 195.474881 -289.042732)
			(xy 195.512043 -289.008522) (xy 195.554329 -288.980896) (xy 195.600585 -288.960606) (xy 195.64955 -288.948206)
			(xy 195.699888 -288.944035) (xy 195.750226 -288.948206) (xy 195.799191 -288.960606) (xy 195.845447 -288.980896)
			(xy 195.887733 -289.008522) (xy 195.924895 -289.042732) (xy 195.955919 -289.082592) (xy 195.957233 -289.08502)
			(xy 201.887834 -289.08502) (xy 201.891905 -289.029398) (xy 201.904031 -288.974961) (xy 201.923954 -288.92287)
			(xy 201.95125 -288.874235) (xy 201.985336 -288.830092) (xy 202.025485 -288.791383) (xy 202.070843 -288.758932)
			(xy 202.120443 -288.733431) (xy 202.173227 -288.715424) (xy 202.22807 -288.705294) (xy 202.283804 -288.703257)
			(xy 202.339241 -288.709357) (xy 202.393198 -288.723463) (xy 202.444527 -288.745275) (xy 202.492133 -288.774329)
			(xy 202.535001 -288.810004) (xy 202.553604 -288.830766) (xy 209.253072 -288.830766) (xy 209.257143 -288.775144)
			(xy 209.269269 -288.720707) (xy 209.289192 -288.668616) (xy 209.316488 -288.619981) (xy 209.350574 -288.575838)
			(xy 209.390723 -288.537129) (xy 209.436081 -288.504678) (xy 209.485681 -288.479177) (xy 209.538465 -288.46117)
			(xy 209.593308 -288.45104) (xy 209.649042 -288.449003) (xy 209.704479 -288.455103) (xy 209.758436 -288.469209)
			(xy 209.809765 -288.491021) (xy 209.857371 -288.520075) (xy 209.900239 -288.55575) (xy 209.937456 -288.597287)
			(xy 209.968229 -288.6438) (xy 209.991901 -288.694297) (xy 210.007969 -288.747704) (xy 210.016089 -288.80288)
			(xy 210.016598 -288.830766) (xy 210.016089 -288.858652) (xy 210.007969 -288.913828) (xy 209.991901 -288.967235)
			(xy 209.968229 -289.017732) (xy 209.937456 -289.064245) (xy 209.900239 -289.105782) (xy 209.857371 -289.141457)
			(xy 209.809765 -289.170511) (xy 209.758436 -289.192323) (xy 209.704479 -289.206429) (xy 209.649042 -289.212529)
			(xy 209.593308 -289.210492) (xy 209.538465 -289.200362) (xy 209.485681 -289.182355) (xy 209.436081 -289.156854)
			(xy 209.390723 -289.124403) (xy 209.350574 -289.085694) (xy 209.316488 -289.041551) (xy 209.289192 -288.992916)
			(xy 209.269269 -288.940825) (xy 209.257143 -288.886388) (xy 209.253072 -288.830766) (xy 202.553604 -288.830766)
			(xy 202.572218 -288.851541) (xy 202.602991 -288.898054) (xy 202.626663 -288.948551) (xy 202.642731 -289.001958)
			(xy 202.650851 -289.057134) (xy 202.65136 -289.08502) (xy 202.650851 -289.112906) (xy 202.642731 -289.168082)
			(xy 202.626663 -289.221489) (xy 202.602991 -289.271986) (xy 202.572218 -289.318499) (xy 202.535001 -289.360036)
			(xy 202.492133 -289.395711) (xy 202.454715 -289.418547) (xy 218.298322 -289.418547) (xy 218.298322 -289.364053)
			(xy 218.306077 -289.310115) (xy 218.321429 -289.257829) (xy 218.344065 -289.208259) (xy 218.373525 -289.162416)
			(xy 218.409209 -289.121231) (xy 218.45039 -289.085544) (xy 218.496231 -289.05608) (xy 218.545799 -289.03344)
			(xy 218.598083 -289.018084) (xy 218.652021 -289.010324) (xy 218.679268 -289.009836) (xy 218.706638 -289.010312)
			(xy 218.760817 -289.018126) (xy 218.81332 -289.033612) (xy 218.863067 -289.056452) (xy 218.909034 -289.086175)
			(xy 218.929966 -289.103816) (xy 218.937078 -289.109912) (xy 218.954096 -289.116262) (xy 219.03944 -289.116262)
			(xy 219.056458 -289.109912) (xy 219.06357 -289.103816) (xy 219.084505 -289.08618) (xy 219.130476 -289.056467)
			(xy 219.180223 -289.03363) (xy 219.232724 -289.018139) (xy 219.286899 -289.01031) (xy 219.314268 -289.009836)
			(xy 219.341526 -289.010209) (xy 219.395486 -289.017963) (xy 219.447794 -289.033318) (xy 219.497384 -289.055961)
			(xy 219.543246 -289.085432) (xy 219.584448 -289.12113) (xy 219.620149 -289.162328) (xy 219.649623 -289.208188)
			(xy 219.672271 -289.257776) (xy 219.68763 -289.310083) (xy 219.695389 -289.364043) (xy 219.695389 -289.418546)
			(xy 220.259722 -289.418546) (xy 220.259722 -289.364054) (xy 220.267476 -289.310116) (xy 220.282828 -289.257831)
			(xy 220.305463 -289.208263) (xy 220.334922 -289.16242) (xy 220.370604 -289.121235) (xy 220.411784 -289.085548)
			(xy 220.457624 -289.056084) (xy 220.50719 -289.033443) (xy 220.559473 -289.018086) (xy 220.61341 -289.010325)
			(xy 220.640656 -289.009836) (xy 220.670778 -289.010438) (xy 220.730273 -289.019912) (xy 220.78754 -289.038616)
			(xy 220.841158 -289.066085) (xy 220.889794 -289.101636) (xy 220.91142 -289.122612) (xy 220.918532 -289.129978)
			(xy 220.937328 -289.137598) (xy 221.029784 -289.137598) (xy 221.04858 -289.129978) (xy 221.055692 -289.122612)
			(xy 221.077299 -289.101613) (xy 221.125933 -289.066046) (xy 221.179553 -289.03857) (xy 221.236828 -289.019866)
			(xy 221.29633 -289.010401) (xy 221.326456 -289.009836) (xy 221.353714 -289.010208) (xy 221.407676 -289.017961)
			(xy 221.459985 -289.033315) (xy 221.509577 -289.055957) (xy 221.555441 -289.085428) (xy 221.596643 -289.121125)
			(xy 221.632346 -289.162324) (xy 221.661822 -289.208185) (xy 221.68447 -289.257773) (xy 221.69983 -289.310081)
			(xy 221.707589 -289.364042) (xy 221.707589 -289.418558) (xy 221.69983 -289.472519) (xy 221.68447 -289.524827)
			(xy 221.661822 -289.574415) (xy 221.632346 -289.620276) (xy 221.596643 -289.661475) (xy 221.555441 -289.697172)
			(xy 221.509577 -289.726643) (xy 221.459985 -289.749285) (xy 221.407676 -289.764639) (xy 221.353714 -289.772392)
			(xy 221.326456 -289.772852) (xy 221.296334 -289.772245) (xy 221.236839 -289.762773) (xy 221.179572 -289.74407)
			(xy 221.125954 -289.716602) (xy 221.077318 -289.681051) (xy 221.055692 -289.660076) (xy 221.04858 -289.65271)
			(xy 221.029784 -289.64509) (xy 220.937328 -289.64509) (xy 220.918532 -289.65271) (xy 220.91142 -289.660076)
			(xy 220.889806 -289.681068) (xy 220.841174 -289.716635) (xy 220.787555 -289.744114) (xy 220.730283 -289.762819)
			(xy 220.670781 -289.772286) (xy 220.640656 -289.772852) (xy 220.61341 -289.772275) (xy 220.559473 -289.764514)
			(xy 220.50719 -289.749157) (xy 220.457624 -289.726516) (xy 220.411784 -289.697052) (xy 220.370604 -289.661365)
			(xy 220.334922 -289.62018) (xy 220.305463 -289.574337) (xy 220.282828 -289.524769) (xy 220.267476 -289.472484)
			(xy 220.259722 -289.418546) (xy 219.695389 -289.418546) (xy 219.695389 -289.418557) (xy 219.68763 -289.472517)
			(xy 219.672271 -289.524824) (xy 219.649623 -289.574412) (xy 219.620149 -289.620272) (xy 219.584448 -289.66147)
			(xy 219.543246 -289.697168) (xy 219.497384 -289.726639) (xy 219.447794 -289.749282) (xy 219.395486 -289.764637)
			(xy 219.341526 -289.772391) (xy 219.314268 -289.772852) (xy 219.286897 -289.772416) (xy 219.232716 -289.764593)
			(xy 219.180212 -289.749097) (xy 219.130465 -289.726249) (xy 219.0845 -289.696517) (xy 219.06357 -289.678872)
			(xy 219.056458 -289.672776) (xy 219.03944 -289.666426) (xy 218.954096 -289.666426) (xy 218.937078 -289.672776)
			(xy 218.929966 -289.678872) (xy 218.909016 -289.696489) (xy 218.863049 -289.726205) (xy 218.813306 -289.749046)
			(xy 218.760809 -289.764542) (xy 218.706636 -289.772375) (xy 218.679268 -289.772852) (xy 218.652021 -289.772276)
			(xy 218.598083 -289.764516) (xy 218.545799 -289.74916) (xy 218.496231 -289.72652) (xy 218.45039 -289.697056)
			(xy 218.409209 -289.661369) (xy 218.373525 -289.620184) (xy 218.344065 -289.574341) (xy 218.321429 -289.524771)
			(xy 218.306077 -289.472485) (xy 218.298322 -289.418547) (xy 202.454715 -289.418547) (xy 202.444527 -289.424765)
			(xy 202.393198 -289.446577) (xy 202.339241 -289.460683) (xy 202.283804 -289.466783) (xy 202.22807 -289.464746)
			(xy 202.173227 -289.454616) (xy 202.120443 -289.436609) (xy 202.070843 -289.411108) (xy 202.025485 -289.378657)
			(xy 201.985336 -289.339948) (xy 201.95125 -289.295805) (xy 201.923954 -289.24717) (xy 201.904031 -289.195079)
			(xy 201.891905 -289.140642) (xy 201.887834 -289.08502) (xy 195.957233 -289.08502) (xy 195.97996 -289.127015)
			(xy 195.996361 -289.174789) (xy 196.004674 -289.224611) (xy 196.005196 -289.249866) (xy 196.005015 -289.264049)
			(xy 196.002346 -289.292289) (xy 195.999862 -289.306254) (xy 195.997576 -289.3187) (xy 196.004942 -289.342322)
			(xy 196.082412 -289.419792) (xy 196.106034 -289.427158) (xy 196.11848 -289.424872) (xy 196.132445 -289.422388)
			(xy 196.160685 -289.419721) (xy 196.174868 -289.419538) (xy 196.199691 -289.419943) (xy 196.248685 -289.42797)
			(xy 196.295734 -289.443817) (xy 196.3396 -289.467067) (xy 196.379126 -289.497107) (xy 196.413272 -289.533147)
			(xy 196.441138 -289.574235) (xy 196.461989 -289.619291) (xy 196.475276 -289.667126) (xy 196.48065 -289.716481)
			(xy 196.480197 -289.724846) (xy 196.819278 -289.724846) (xy 196.823238 -289.675792) (xy 196.835015 -289.628008)
			(xy 196.854306 -289.582732) (xy 196.880609 -289.541136) (xy 196.913244 -289.504299) (xy 196.951365 -289.473174)
			(xy 196.993986 -289.448567) (xy 197.040002 -289.431115) (xy 197.088221 -289.421271) (xy 197.137396 -289.41929)
			(xy 197.186251 -289.425222) (xy 197.233522 -289.438914) (xy 197.277984 -289.460012) (xy 197.318487 -289.487968)
			(xy 197.35398 -289.52206) (xy 197.383545 -289.561404) (xy 197.406416 -289.604981) (xy 197.422 -289.651662)
			(xy 197.429895 -289.700239) (xy 197.43039 -289.724846) (xy 197.769238 -289.724846) (xy 197.773198 -289.675792)
			(xy 197.784975 -289.628008) (xy 197.804266 -289.582732) (xy 197.830569 -289.541136) (xy 197.863204 -289.504299)
			(xy 197.901325 -289.473174) (xy 197.943946 -289.448567) (xy 197.989962 -289.431115) (xy 198.038181 -289.421271)
			(xy 198.087356 -289.41929) (xy 198.136211 -289.425222) (xy 198.183482 -289.438914) (xy 198.227944 -289.460012)
			(xy 198.268447 -289.487968) (xy 198.30394 -289.52206) (xy 198.333505 -289.561404) (xy 198.356376 -289.604981)
			(xy 198.37196 -289.651662) (xy 198.379855 -289.700239) (xy 198.38035 -289.724846) (xy 198.719198 -289.724846)
			(xy 198.723158 -289.675792) (xy 198.734935 -289.628008) (xy 198.754226 -289.582732) (xy 198.780529 -289.541136)
			(xy 198.813164 -289.504299) (xy 198.851285 -289.473174) (xy 198.893906 -289.448567) (xy 198.939922 -289.431115)
			(xy 198.988141 -289.421271) (xy 199.037316 -289.41929) (xy 199.086171 -289.425222) (xy 199.133442 -289.438914)
			(xy 199.177904 -289.460012) (xy 199.218407 -289.487968) (xy 199.2539 -289.52206) (xy 199.283465 -289.561404)
			(xy 199.306336 -289.604981) (xy 199.32192 -289.651662) (xy 199.329815 -289.700239) (xy 199.33031 -289.724846)
			(xy 199.329815 -289.749453) (xy 199.32192 -289.79803) (xy 199.306336 -289.844711) (xy 199.283465 -289.888288)
			(xy 199.2539 -289.927632) (xy 199.218407 -289.961724) (xy 199.177904 -289.98968) (xy 199.133442 -290.010778)
			(xy 199.086171 -290.02447) (xy 199.037316 -290.030402) (xy 198.988141 -290.028421) (xy 198.939922 -290.018577)
			(xy 198.893906 -290.001125) (xy 198.851285 -289.976518) (xy 198.813164 -289.945393) (xy 198.780529 -289.908556)
			(xy 198.754226 -289.86696) (xy 198.734935 -289.821684) (xy 198.723158 -289.7739) (xy 198.719198 -289.724846)
			(xy 198.38035 -289.724846) (xy 198.379855 -289.749453) (xy 198.37196 -289.79803) (xy 198.356376 -289.844711)
			(xy 198.333505 -289.888288) (xy 198.30394 -289.927632) (xy 198.268447 -289.961724) (xy 198.227944 -289.98968)
			(xy 198.183482 -290.010778) (xy 198.136211 -290.02447) (xy 198.087356 -290.030402) (xy 198.038181 -290.028421)
			(xy 197.989962 -290.018577) (xy 197.943946 -290.001125) (xy 197.901325 -289.976518) (xy 197.863204 -289.945393)
			(xy 197.830569 -289.908556) (xy 197.804266 -289.86696) (xy 197.784975 -289.821684) (xy 197.773198 -289.7739)
			(xy 197.769238 -289.724846) (xy 197.43039 -289.724846) (xy 197.429895 -289.749453) (xy 197.422 -289.79803)
			(xy 197.406416 -289.844711) (xy 197.383545 -289.888288) (xy 197.35398 -289.927632) (xy 197.318487 -289.961724)
			(xy 197.277984 -289.98968) (xy 197.233522 -290.010778) (xy 197.186251 -290.02447) (xy 197.137396 -290.030402)
			(xy 197.088221 -290.028421) (xy 197.040002 -290.018577) (xy 196.993986 -290.001125) (xy 196.951365 -289.976518)
			(xy 196.913244 -289.945393) (xy 196.880609 -289.908556) (xy 196.854306 -289.86696) (xy 196.835015 -289.821684)
			(xy 196.823238 -289.7739) (xy 196.819278 -289.724846) (xy 196.480197 -289.724846) (xy 196.477968 -289.766055)
			(xy 196.467301 -289.814542) (xy 196.448931 -289.860664) (xy 196.423341 -289.903207) (xy 196.391205 -289.94105)
			(xy 196.353371 -289.973195) (xy 196.310834 -289.998796) (xy 196.264716 -290.017178) (xy 196.216232 -290.027857)
			(xy 196.166659 -290.030552) (xy 196.117303 -290.025191) (xy 196.069464 -290.011916) (xy 196.024403 -289.991076)
			(xy 195.983308 -289.963221) (xy 195.94726 -289.929084) (xy 195.917209 -289.889565) (xy 195.893948 -289.845706)
			(xy 195.878089 -289.79866) (xy 195.87005 -289.749669) (xy 195.86956 -289.724846) (xy 195.869744 -289.710663)
			(xy 195.872411 -289.682423) (xy 195.874894 -289.668458) (xy 195.87718 -289.656012) (xy 195.869814 -289.63239)
			(xy 195.792344 -289.55492) (xy 195.768722 -289.547554) (xy 195.756276 -289.54984) (xy 195.74231 -289.552315)
			(xy 195.71407 -289.554988) (xy 195.699888 -289.555174) (xy 195.685705 -289.555) (xy 195.657465 -289.552326)
			(xy 195.6435 -289.54984) (xy 195.631054 -289.547554) (xy 195.607432 -289.55492) (xy 195.529962 -289.63239)
			(xy 195.522596 -289.656012) (xy 195.524882 -289.668458) (xy 195.527362 -289.682423) (xy 195.530032 -289.710663)
			(xy 195.530216 -289.724846) (xy 195.529673 -289.749662) (xy 195.521636 -289.79864) (xy 195.505781 -289.845673)
			(xy 195.482527 -289.889521) (xy 195.452485 -289.929029) (xy 195.416447 -289.963157) (xy 195.375363 -289.991005)
			(xy 195.330315 -290.01184) (xy 195.282489 -290.025113) (xy 195.233147 -290.030474) (xy 195.183587 -290.027781)
			(xy 195.135116 -290.017107) (xy 195.08901 -289.998731) (xy 195.046484 -289.973139) (xy 195.008658 -289.941004)
			(xy 194.97653 -289.903172) (xy 194.950945 -289.860642) (xy 194.932577 -289.814533) (xy 194.921911 -289.766059)
			(xy 194.919228 -289.716499) (xy 194.580088 -289.716499) (xy 194.580256 -289.724846) (xy 194.579761 -289.749453)
			(xy 194.571866 -289.79803) (xy 194.556282 -289.844711) (xy 194.533411 -289.888288) (xy 194.503846 -289.927632)
			(xy 194.468353 -289.961724) (xy 194.42785 -289.98968) (xy 194.383388 -290.010778) (xy 194.336117 -290.02447)
			(xy 194.287262 -290.030402) (xy 194.238087 -290.028421) (xy 194.189868 -290.018577) (xy 194.143852 -290.001125)
			(xy 194.101231 -289.976518) (xy 194.06311 -289.945393) (xy 194.030475 -289.908556) (xy 194.004172 -289.86696)
			(xy 193.984881 -289.821684) (xy 193.973104 -289.7739) (xy 193.969144 -289.724846) (xy 193.630296 -289.724846)
			(xy 193.629801 -289.749453) (xy 193.621906 -289.79803) (xy 193.606322 -289.844711) (xy 193.583451 -289.888288)
			(xy 193.553886 -289.927632) (xy 193.518393 -289.961724) (xy 193.47789 -289.98968) (xy 193.433428 -290.010778)
			(xy 193.386157 -290.02447) (xy 193.337302 -290.030402) (xy 193.288127 -290.028421) (xy 193.239908 -290.018577)
			(xy 193.193892 -290.001125) (xy 193.151271 -289.976518) (xy 193.11315 -289.945393) (xy 193.080515 -289.908556)
			(xy 193.054212 -289.86696) (xy 193.034921 -289.821684) (xy 193.023144 -289.7739) (xy 193.019184 -289.724846)
			(xy 192.680336 -289.724846) (xy 192.679841 -289.749453) (xy 192.671946 -289.79803) (xy 192.656362 -289.844711)
			(xy 192.633491 -289.888288) (xy 192.603926 -289.927632) (xy 192.568433 -289.961724) (xy 192.52793 -289.98968)
			(xy 192.483468 -290.010778) (xy 192.436197 -290.02447) (xy 192.387342 -290.030402) (xy 192.338167 -290.028421)
			(xy 192.289948 -290.018577) (xy 192.243932 -290.001125) (xy 192.201311 -289.976518) (xy 192.16319 -289.945393)
			(xy 192.130555 -289.908556) (xy 192.104252 -289.86696) (xy 192.084961 -289.821684) (xy 192.073184 -289.7739)
			(xy 192.069224 -289.724846) (xy 190.780359 -289.724846) (xy 190.778125 -289.766075) (xy 190.767456 -289.814553)
			(xy 190.749085 -289.860667) (xy 190.723496 -289.903202) (xy 190.691363 -289.941036) (xy 190.653532 -289.973174)
			(xy 190.611001 -289.998768) (xy 190.564889 -290.017145) (xy 190.516412 -290.02782) (xy 190.466847 -290.030512)
			(xy 190.417499 -290.025149) (xy 190.369668 -290.011875) (xy 190.324615 -289.991037) (xy 190.283527 -289.963185)
			(xy 190.247485 -289.929053) (xy 190.21744 -289.88954) (xy 190.194183 -289.845687) (xy 190.178327 -289.798649)
			(xy 190.17029 -289.749665) (xy 190.1698 -289.724846) (xy 190.169983 -289.710663) (xy 190.172651 -289.682423)
			(xy 190.175134 -289.668458) (xy 190.17742 -289.656012) (xy 190.170054 -289.632136) (xy 190.092838 -289.55492)
			(xy 190.068708 -289.547554) (xy 190.056516 -289.54984) (xy 190.042486 -289.55232) (xy 190.01412 -289.554995)
			(xy 189.999874 -289.555174) (xy 189.985691 -289.555002) (xy 189.957451 -289.552327) (xy 189.943486 -289.54984)
			(xy 189.93104 -289.547554) (xy 189.907418 -289.55492) (xy 189.829948 -289.63239) (xy 189.822582 -289.656012)
			(xy 189.824868 -289.668458) (xy 189.827348 -289.682423) (xy 189.830018 -289.710663) (xy 189.830202 -289.724846)
			(xy 189.829673 -289.749662) (xy 189.821636 -289.79864) (xy 189.805782 -289.845672) (xy 189.782528 -289.88952)
			(xy 189.752486 -289.929028) (xy 189.716449 -289.963156) (xy 189.675366 -289.991004) (xy 189.630318 -290.011839)
			(xy 189.582493 -290.025112) (xy 189.533151 -290.030474) (xy 189.483592 -290.027782) (xy 189.435121 -290.017108)
			(xy 189.389015 -289.998734) (xy 189.346489 -289.973142) (xy 189.308663 -289.941008) (xy 189.276534 -289.903179)
			(xy 189.250948 -289.860649) (xy 189.23258 -289.814541) (xy 189.221913 -289.766068) (xy 189.219227 -289.716508)
			(xy 188.880074 -289.716508) (xy 188.880242 -289.724846) (xy 188.879747 -289.749453) (xy 188.871852 -289.79803)
			(xy 188.856268 -289.844711) (xy 188.833397 -289.888288) (xy 188.803832 -289.927632) (xy 188.768339 -289.961724)
			(xy 188.727836 -289.98968) (xy 188.683374 -290.010778) (xy 188.636103 -290.02447) (xy 188.587248 -290.030402)
			(xy 188.538073 -290.028421) (xy 188.489854 -290.018577) (xy 188.443838 -290.001125) (xy 188.401217 -289.976518)
			(xy 188.363096 -289.945393) (xy 188.330461 -289.908556) (xy 188.304158 -289.86696) (xy 188.284867 -289.821684)
			(xy 188.27309 -289.7739) (xy 188.26913 -289.724846) (xy 187.930282 -289.724846) (xy 187.929787 -289.749453)
			(xy 187.921892 -289.79803) (xy 187.906308 -289.844711) (xy 187.883437 -289.888288) (xy 187.853872 -289.927632)
			(xy 187.818379 -289.961724) (xy 187.777876 -289.98968) (xy 187.733414 -290.010778) (xy 187.686143 -290.02447)
			(xy 187.637288 -290.030402) (xy 187.588113 -290.028421) (xy 187.539894 -290.018577) (xy 187.493878 -290.001125)
			(xy 187.451257 -289.976518) (xy 187.413136 -289.945393) (xy 187.380501 -289.908556) (xy 187.354198 -289.86696)
			(xy 187.334907 -289.821684) (xy 187.32313 -289.7739) (xy 187.31917 -289.724846) (xy 186.980322 -289.724846)
			(xy 186.979827 -289.749453) (xy 186.971932 -289.79803) (xy 186.956348 -289.844711) (xy 186.933477 -289.888288)
			(xy 186.903912 -289.927632) (xy 186.868419 -289.961724) (xy 186.827916 -289.98968) (xy 186.783454 -290.010778)
			(xy 186.736183 -290.02447) (xy 186.687328 -290.030402) (xy 186.638153 -290.028421) (xy 186.589934 -290.018577)
			(xy 186.543918 -290.001125) (xy 186.501297 -289.976518) (xy 186.463176 -289.945393) (xy 186.430541 -289.908556)
			(xy 186.404238 -289.86696) (xy 186.384947 -289.821684) (xy 186.37317 -289.7739) (xy 186.36921 -289.724846)
			(xy 186.030362 -289.724846) (xy 186.029897 -289.748722) (xy 186.022457 -289.795892) (xy 186.007764 -289.841328)
			(xy 185.986178 -289.883923) (xy 185.958225 -289.922639) (xy 185.924586 -289.956532) (xy 185.886081 -289.984776)
			(xy 185.843649 -290.006681) (xy 185.798324 -290.021714) (xy 185.751212 -290.029509) (xy 185.72734 -290.030154)
			(xy 185.724292 -290.030154) (xy 185.697164 -290.029566) (xy 185.64376 -290.019985) (xy 185.61812 -290.011104)
			(xy 185.606421 -290.007494) (xy 185.582148 -290.010412) (xy 185.571638 -290.016692) (xy 185.534046 -290.0426)
			(xy 185.533538 -290.0426) (xy 185.502042 -290.064698) (xy 185.495692 -290.071048) (xy 185.488326 -290.07816)
			(xy 185.480706 -290.096956) (xy 185.480706 -290.293552) (xy 185.481303 -290.305876) (xy 185.492759 -290.327698)
			(xy 185.50255 -290.335208) (xy 185.523378 -290.349686) (xy 185.57113 -290.382452) (xy 185.581624 -290.388782)
			(xy 185.605916 -290.391702) (xy 185.617612 -290.38804) (xy 185.643429 -290.379055) (xy 185.697217 -290.369341)
			(xy 185.724546 -290.368736) (xy 185.725054 -290.368736) (xy 185.750377 -290.369226) (xy 185.800333 -290.377555)
			(xy 185.848236 -290.393994) (xy 185.89278 -290.418094) (xy 185.932749 -290.449198) (xy 185.967052 -290.486456)
			(xy 185.994755 -290.528853) (xy 186.015101 -290.575232) (xy 186.027535 -290.624328) (xy 186.031718 -290.6748)
			(xy 186.031718 -290.674806) (xy 186.36921 -290.674806) (xy 186.37317 -290.625752) (xy 186.384947 -290.577968)
			(xy 186.404238 -290.532692) (xy 186.430541 -290.491096) (xy 186.463176 -290.454259) (xy 186.501297 -290.423134)
			(xy 186.543918 -290.398527) (xy 186.589934 -290.381075) (xy 186.638153 -290.371231) (xy 186.687328 -290.36925)
			(xy 186.736183 -290.375182) (xy 186.783454 -290.388874) (xy 186.827916 -290.409972) (xy 186.868419 -290.437928)
			(xy 186.903912 -290.47202) (xy 186.933477 -290.511364) (xy 186.956348 -290.554941) (xy 186.971932 -290.601622)
			(xy 186.979827 -290.650199) (xy 186.980322 -290.674806) (xy 187.31917 -290.674806) (xy 187.32313 -290.625752)
			(xy 187.334907 -290.577968) (xy 187.354198 -290.532692) (xy 187.380501 -290.491096) (xy 187.413136 -290.454259)
			(xy 187.451257 -290.423134) (xy 187.493878 -290.398527) (xy 187.539894 -290.381075) (xy 187.588113 -290.371231)
			(xy 187.637288 -290.36925) (xy 187.686143 -290.375182) (xy 187.733414 -290.388874) (xy 187.777876 -290.409972)
			(xy 187.818379 -290.437928) (xy 187.853872 -290.47202) (xy 187.883437 -290.511364) (xy 187.906308 -290.554941)
			(xy 187.921892 -290.601622) (xy 187.929787 -290.650199) (xy 187.930282 -290.674806) (xy 188.26913 -290.674806)
			(xy 188.27309 -290.625752) (xy 188.284867 -290.577968) (xy 188.304158 -290.532692) (xy 188.330461 -290.491096)
			(xy 188.363096 -290.454259) (xy 188.401217 -290.423134) (xy 188.443838 -290.398527) (xy 188.489854 -290.381075)
			(xy 188.538073 -290.371231) (xy 188.587248 -290.36925) (xy 188.636103 -290.375182) (xy 188.683374 -290.388874)
			(xy 188.727836 -290.409972) (xy 188.768339 -290.437928) (xy 188.803832 -290.47202) (xy 188.833397 -290.511364)
			(xy 188.856268 -290.554941) (xy 188.871852 -290.601622) (xy 188.879747 -290.650199) (xy 188.880242 -290.674806)
			(xy 189.21909 -290.674806) (xy 189.22305 -290.625752) (xy 189.234827 -290.577968) (xy 189.254118 -290.532692)
			(xy 189.280421 -290.491096) (xy 189.313056 -290.454259) (xy 189.351177 -290.423134) (xy 189.393798 -290.398527)
			(xy 189.439814 -290.381075) (xy 189.488033 -290.371231) (xy 189.537208 -290.36925) (xy 189.586063 -290.375182)
			(xy 189.633334 -290.388874) (xy 189.677796 -290.409972) (xy 189.718299 -290.437928) (xy 189.753792 -290.47202)
			(xy 189.783357 -290.511364) (xy 189.806228 -290.554941) (xy 189.821812 -290.601622) (xy 189.829707 -290.650199)
			(xy 189.830202 -290.674806) (xy 190.16905 -290.674806) (xy 190.17301 -290.625752) (xy 190.184787 -290.577968)
			(xy 190.204078 -290.532692) (xy 190.230381 -290.491096) (xy 190.263016 -290.454259) (xy 190.301137 -290.423134)
			(xy 190.343758 -290.398527) (xy 190.389774 -290.381075) (xy 190.437993 -290.371231) (xy 190.487168 -290.36925)
			(xy 190.536023 -290.375182) (xy 190.583294 -290.388874) (xy 190.627756 -290.409972) (xy 190.668259 -290.437928)
			(xy 190.703752 -290.47202) (xy 190.733317 -290.511364) (xy 190.756188 -290.554941) (xy 190.771772 -290.601622)
			(xy 190.779667 -290.650199) (xy 190.780162 -290.674806) (xy 191.119264 -290.674806) (xy 191.123224 -290.625752)
			(xy 191.135001 -290.577968) (xy 191.154292 -290.532692) (xy 191.180595 -290.491096) (xy 191.21323 -290.454259)
			(xy 191.251351 -290.423134) (xy 191.293972 -290.398527) (xy 191.339988 -290.381075) (xy 191.388207 -290.371231)
			(xy 191.437382 -290.36925) (xy 191.486237 -290.375182) (xy 191.533508 -290.388874) (xy 191.57797 -290.409972)
			(xy 191.618473 -290.437928) (xy 191.653966 -290.47202) (xy 191.683531 -290.511364) (xy 191.706402 -290.554941)
			(xy 191.721986 -290.601622) (xy 191.729881 -290.650199) (xy 191.730376 -290.674806) (xy 192.069224 -290.674806)
			(xy 192.073184 -290.625752) (xy 192.084961 -290.577968) (xy 192.104252 -290.532692) (xy 192.130555 -290.491096)
			(xy 192.16319 -290.454259) (xy 192.201311 -290.423134) (xy 192.243932 -290.398527) (xy 192.289948 -290.381075)
			(xy 192.338167 -290.371231) (xy 192.387342 -290.36925) (xy 192.436197 -290.375182) (xy 192.483468 -290.388874)
			(xy 192.52793 -290.409972) (xy 192.568433 -290.437928) (xy 192.603926 -290.47202) (xy 192.633491 -290.511364)
			(xy 192.656362 -290.554941) (xy 192.671946 -290.601622) (xy 192.679841 -290.650199) (xy 192.680336 -290.674806)
			(xy 193.019184 -290.674806) (xy 193.023144 -290.625752) (xy 193.034921 -290.577968) (xy 193.054212 -290.532692)
			(xy 193.080515 -290.491096) (xy 193.11315 -290.454259) (xy 193.151271 -290.423134) (xy 193.193892 -290.398527)
			(xy 193.239908 -290.381075) (xy 193.288127 -290.371231) (xy 193.337302 -290.36925) (xy 193.386157 -290.375182)
			(xy 193.433428 -290.388874) (xy 193.47789 -290.409972) (xy 193.518393 -290.437928) (xy 193.553886 -290.47202)
			(xy 193.583451 -290.511364) (xy 193.606322 -290.554941) (xy 193.621906 -290.601622) (xy 193.629801 -290.650199)
			(xy 193.630296 -290.674806) (xy 193.969144 -290.674806) (xy 193.973104 -290.625752) (xy 193.984881 -290.577968)
			(xy 194.004172 -290.532692) (xy 194.030475 -290.491096) (xy 194.06311 -290.454259) (xy 194.101231 -290.423134)
			(xy 194.143852 -290.398527) (xy 194.189868 -290.381075) (xy 194.238087 -290.371231) (xy 194.287262 -290.36925)
			(xy 194.336117 -290.375182) (xy 194.383388 -290.388874) (xy 194.42785 -290.409972) (xy 194.468353 -290.437928)
			(xy 194.503846 -290.47202) (xy 194.533411 -290.511364) (xy 194.556282 -290.554941) (xy 194.571866 -290.601622)
			(xy 194.579761 -290.650199) (xy 194.580256 -290.674806) (xy 194.919104 -290.674806) (xy 194.923064 -290.625752)
			(xy 194.934841 -290.577968) (xy 194.954132 -290.532692) (xy 194.980435 -290.491096) (xy 195.01307 -290.454259)
			(xy 195.051191 -290.423134) (xy 195.093812 -290.398527) (xy 195.139828 -290.381075) (xy 195.188047 -290.371231)
			(xy 195.237222 -290.36925) (xy 195.286077 -290.375182) (xy 195.333348 -290.388874) (xy 195.37781 -290.409972)
			(xy 195.418313 -290.437928) (xy 195.453806 -290.47202) (xy 195.483371 -290.511364) (xy 195.506242 -290.554941)
			(xy 195.521826 -290.601622) (xy 195.529721 -290.650199) (xy 195.530216 -290.674806) (xy 195.869064 -290.674806)
			(xy 195.873024 -290.625752) (xy 195.884801 -290.577968) (xy 195.904092 -290.532692) (xy 195.930395 -290.491096)
			(xy 195.96303 -290.454259) (xy 196.001151 -290.423134) (xy 196.043772 -290.398527) (xy 196.089788 -290.381075)
			(xy 196.138007 -290.371231) (xy 196.187182 -290.36925) (xy 196.236037 -290.375182) (xy 196.283308 -290.388874)
			(xy 196.32777 -290.409972) (xy 196.368273 -290.437928) (xy 196.403766 -290.47202) (xy 196.433331 -290.511364)
			(xy 196.456202 -290.554941) (xy 196.471786 -290.601622) (xy 196.479681 -290.650199) (xy 196.480176 -290.674806)
			(xy 196.819278 -290.674806) (xy 196.823238 -290.625752) (xy 196.835015 -290.577968) (xy 196.854306 -290.532692)
			(xy 196.880609 -290.491096) (xy 196.913244 -290.454259) (xy 196.951365 -290.423134) (xy 196.993986 -290.398527)
			(xy 197.040002 -290.381075) (xy 197.088221 -290.371231) (xy 197.137396 -290.36925) (xy 197.186251 -290.375182)
			(xy 197.233522 -290.388874) (xy 197.277984 -290.409972) (xy 197.318487 -290.437928) (xy 197.35398 -290.47202)
			(xy 197.383545 -290.511364) (xy 197.406416 -290.554941) (xy 197.422 -290.601622) (xy 197.429895 -290.650199)
			(xy 197.43039 -290.674806) (xy 197.769238 -290.674806) (xy 197.773198 -290.625752) (xy 197.784975 -290.577968)
			(xy 197.804266 -290.532692) (xy 197.830569 -290.491096) (xy 197.863204 -290.454259) (xy 197.901325 -290.423134)
			(xy 197.943946 -290.398527) (xy 197.989962 -290.381075) (xy 198.038181 -290.371231) (xy 198.087356 -290.36925)
			(xy 198.136211 -290.375182) (xy 198.183482 -290.388874) (xy 198.227944 -290.409972) (xy 198.268447 -290.437928)
			(xy 198.30394 -290.47202) (xy 198.333505 -290.511364) (xy 198.356376 -290.554941) (xy 198.37196 -290.601622)
			(xy 198.379855 -290.650199) (xy 198.38035 -290.674806) (xy 198.719198 -290.674806) (xy 198.723158 -290.625752)
			(xy 198.734935 -290.577968) (xy 198.754226 -290.532692) (xy 198.780529 -290.491096) (xy 198.813164 -290.454259)
			(xy 198.851285 -290.423134) (xy 198.893906 -290.398527) (xy 198.939922 -290.381075) (xy 198.988141 -290.371231)
			(xy 199.037316 -290.36925) (xy 199.086171 -290.375182) (xy 199.133442 -290.388874) (xy 199.177904 -290.409972)
			(xy 199.19176 -290.419536) (xy 201.25385 -290.419536) (xy 201.257921 -290.363914) (xy 201.270047 -290.309477)
			(xy 201.28997 -290.257386) (xy 201.317266 -290.208751) (xy 201.351352 -290.164608) (xy 201.391501 -290.125899)
			(xy 201.436859 -290.093448) (xy 201.486459 -290.067947) (xy 201.539243 -290.04994) (xy 201.594086 -290.03981)
			(xy 201.64982 -290.037773) (xy 201.705257 -290.043873) (xy 201.759214 -290.057979) (xy 201.810543 -290.079791)
			(xy 201.858149 -290.108845) (xy 201.901017 -290.14452) (xy 201.938234 -290.186057) (xy 201.969007 -290.23257)
			(xy 201.971161 -290.237164) (xy 205.26451 -290.237164) (xy 205.268581 -290.181542) (xy 205.280707 -290.127105)
			(xy 205.30063 -290.075014) (xy 205.327926 -290.026379) (xy 205.362012 -289.982236) (xy 205.402161 -289.943527)
			(xy 205.447519 -289.911076) (xy 205.497119 -289.885575) (xy 205.549903 -289.867568) (xy 205.604746 -289.857438)
			(xy 205.66048 -289.855401) (xy 205.715917 -289.861501) (xy 205.769874 -289.875607) (xy 205.821203 -289.897419)
			(xy 205.868809 -289.926473) (xy 205.911677 -289.962148) (xy 205.948894 -290.003685) (xy 205.979667 -290.050198)
			(xy 206.003339 -290.100695) (xy 206.019407 -290.154102) (xy 206.027527 -290.209278) (xy 206.028036 -290.237164)
			(xy 206.027527 -290.26505) (xy 206.019407 -290.320226) (xy 206.003339 -290.373633) (xy 205.979667 -290.42413)
			(xy 205.948894 -290.470643) (xy 205.911677 -290.51218) (xy 205.868809 -290.547855) (xy 205.821203 -290.576909)
			(xy 205.769874 -290.598721) (xy 205.715917 -290.612827) (xy 205.66048 -290.618927) (xy 205.604746 -290.61689)
			(xy 205.549903 -290.60676) (xy 205.497119 -290.588753) (xy 205.447519 -290.563252) (xy 205.402161 -290.530801)
			(xy 205.362012 -290.492092) (xy 205.327926 -290.447949) (xy 205.30063 -290.399314) (xy 205.280707 -290.347223)
			(xy 205.268581 -290.292786) (xy 205.26451 -290.237164) (xy 201.971161 -290.237164) (xy 201.992679 -290.283067)
			(xy 202.008747 -290.336474) (xy 202.016867 -290.39165) (xy 202.017376 -290.419536) (xy 202.016867 -290.447422)
			(xy 202.008747 -290.502598) (xy 201.992679 -290.556005) (xy 201.969007 -290.606502) (xy 201.938234 -290.653015)
			(xy 201.901017 -290.694552) (xy 201.858149 -290.730227) (xy 201.810543 -290.759281) (xy 201.759214 -290.781093)
			(xy 201.705257 -290.795199) (xy 201.64982 -290.801299) (xy 201.594086 -290.799262) (xy 201.539243 -290.789132)
			(xy 201.486459 -290.771125) (xy 201.436859 -290.745624) (xy 201.391501 -290.713173) (xy 201.351352 -290.674464)
			(xy 201.317266 -290.630321) (xy 201.28997 -290.581686) (xy 201.270047 -290.529595) (xy 201.257921 -290.475158)
			(xy 201.25385 -290.419536) (xy 199.19176 -290.419536) (xy 199.218407 -290.437928) (xy 199.2539 -290.47202)
			(xy 199.283465 -290.511364) (xy 199.306336 -290.554941) (xy 199.32192 -290.601622) (xy 199.329815 -290.650199)
			(xy 199.33031 -290.674806) (xy 199.329815 -290.699413) (xy 199.32192 -290.74799) (xy 199.306336 -290.794671)
			(xy 199.283465 -290.838248) (xy 199.2539 -290.877592) (xy 199.218407 -290.911684) (xy 199.177904 -290.93964)
			(xy 199.133442 -290.960738) (xy 199.086171 -290.97443) (xy 199.037316 -290.980362) (xy 198.988141 -290.978381)
			(xy 198.939922 -290.968537) (xy 198.893906 -290.951085) (xy 198.851285 -290.926478) (xy 198.813164 -290.895353)
			(xy 198.780529 -290.858516) (xy 198.754226 -290.81692) (xy 198.734935 -290.771644) (xy 198.723158 -290.72386)
			(xy 198.719198 -290.674806) (xy 198.38035 -290.674806) (xy 198.379855 -290.699413) (xy 198.37196 -290.74799)
			(xy 198.356376 -290.794671) (xy 198.333505 -290.838248) (xy 198.30394 -290.877592) (xy 198.268447 -290.911684)
			(xy 198.227944 -290.93964) (xy 198.183482 -290.960738) (xy 198.136211 -290.97443) (xy 198.087356 -290.980362)
			(xy 198.038181 -290.978381) (xy 197.989962 -290.968537) (xy 197.943946 -290.951085) (xy 197.901325 -290.926478)
			(xy 197.863204 -290.895353) (xy 197.830569 -290.858516) (xy 197.804266 -290.81692) (xy 197.784975 -290.771644)
			(xy 197.773198 -290.72386) (xy 197.769238 -290.674806) (xy 197.43039 -290.674806) (xy 197.429895 -290.699413)
			(xy 197.422 -290.74799) (xy 197.406416 -290.794671) (xy 197.383545 -290.838248) (xy 197.35398 -290.877592)
			(xy 197.318487 -290.911684) (xy 197.277984 -290.93964) (xy 197.233522 -290.960738) (xy 197.186251 -290.97443)
			(xy 197.137396 -290.980362) (xy 197.088221 -290.978381) (xy 197.040002 -290.968537) (xy 196.993986 -290.951085)
			(xy 196.951365 -290.926478) (xy 196.913244 -290.895353) (xy 196.880609 -290.858516) (xy 196.854306 -290.81692)
			(xy 196.835015 -290.771644) (xy 196.823238 -290.72386) (xy 196.819278 -290.674806) (xy 196.480176 -290.674806)
			(xy 196.479681 -290.699413) (xy 196.471786 -290.74799) (xy 196.456202 -290.794671) (xy 196.433331 -290.838248)
			(xy 196.403766 -290.877592) (xy 196.368273 -290.911684) (xy 196.32777 -290.93964) (xy 196.283308 -290.960738)
			(xy 196.236037 -290.97443) (xy 196.187182 -290.980362) (xy 196.138007 -290.978381) (xy 196.089788 -290.968537)
			(xy 196.043772 -290.951085) (xy 196.001151 -290.926478) (xy 195.96303 -290.895353) (xy 195.930395 -290.858516)
			(xy 195.904092 -290.81692) (xy 195.884801 -290.771644) (xy 195.873024 -290.72386) (xy 195.869064 -290.674806)
			(xy 195.530216 -290.674806) (xy 195.529721 -290.699413) (xy 195.521826 -290.74799) (xy 195.506242 -290.794671)
			(xy 195.483371 -290.838248) (xy 195.453806 -290.877592) (xy 195.418313 -290.911684) (xy 195.37781 -290.93964)
			(xy 195.333348 -290.960738) (xy 195.286077 -290.97443) (xy 195.237222 -290.980362) (xy 195.188047 -290.978381)
			(xy 195.139828 -290.968537) (xy 195.093812 -290.951085) (xy 195.051191 -290.926478) (xy 195.01307 -290.895353)
			(xy 194.980435 -290.858516) (xy 194.954132 -290.81692) (xy 194.934841 -290.771644) (xy 194.923064 -290.72386)
			(xy 194.919104 -290.674806) (xy 194.580256 -290.674806) (xy 194.579761 -290.699413) (xy 194.571866 -290.74799)
			(xy 194.556282 -290.794671) (xy 194.533411 -290.838248) (xy 194.503846 -290.877592) (xy 194.468353 -290.911684)
			(xy 194.42785 -290.93964) (xy 194.383388 -290.960738) (xy 194.336117 -290.97443) (xy 194.287262 -290.980362)
			(xy 194.238087 -290.978381) (xy 194.189868 -290.968537) (xy 194.143852 -290.951085) (xy 194.101231 -290.926478)
			(xy 194.06311 -290.895353) (xy 194.030475 -290.858516) (xy 194.004172 -290.81692) (xy 193.984881 -290.771644)
			(xy 193.973104 -290.72386) (xy 193.969144 -290.674806) (xy 193.630296 -290.674806) (xy 193.629801 -290.699413)
			(xy 193.621906 -290.74799) (xy 193.606322 -290.794671) (xy 193.583451 -290.838248) (xy 193.553886 -290.877592)
			(xy 193.518393 -290.911684) (xy 193.47789 -290.93964) (xy 193.433428 -290.960738) (xy 193.386157 -290.97443)
			(xy 193.337302 -290.980362) (xy 193.288127 -290.978381) (xy 193.239908 -290.968537) (xy 193.193892 -290.951085)
			(xy 193.151271 -290.926478) (xy 193.11315 -290.895353) (xy 193.080515 -290.858516) (xy 193.054212 -290.81692)
			(xy 193.034921 -290.771644) (xy 193.023144 -290.72386) (xy 193.019184 -290.674806) (xy 192.680336 -290.674806)
			(xy 192.679841 -290.699413) (xy 192.671946 -290.74799) (xy 192.656362 -290.794671) (xy 192.633491 -290.838248)
			(xy 192.603926 -290.877592) (xy 192.568433 -290.911684) (xy 192.52793 -290.93964) (xy 192.483468 -290.960738)
			(xy 192.436197 -290.97443) (xy 192.387342 -290.980362) (xy 192.338167 -290.978381) (xy 192.289948 -290.968537)
			(xy 192.243932 -290.951085) (xy 192.201311 -290.926478) (xy 192.16319 -290.895353) (xy 192.130555 -290.858516)
			(xy 192.104252 -290.81692) (xy 192.084961 -290.771644) (xy 192.073184 -290.72386) (xy 192.069224 -290.674806)
			(xy 191.730376 -290.674806) (xy 191.729881 -290.699413) (xy 191.721986 -290.74799) (xy 191.706402 -290.794671)
			(xy 191.683531 -290.838248) (xy 191.653966 -290.877592) (xy 191.618473 -290.911684) (xy 191.57797 -290.93964)
			(xy 191.533508 -290.960738) (xy 191.486237 -290.97443) (xy 191.437382 -290.980362) (xy 191.388207 -290.978381)
			(xy 191.339988 -290.968537) (xy 191.293972 -290.951085) (xy 191.251351 -290.926478) (xy 191.21323 -290.895353)
			(xy 191.180595 -290.858516) (xy 191.154292 -290.81692) (xy 191.135001 -290.771644) (xy 191.123224 -290.72386)
			(xy 191.119264 -290.674806) (xy 190.780162 -290.674806) (xy 190.779667 -290.699413) (xy 190.771772 -290.74799)
			(xy 190.756188 -290.794671) (xy 190.733317 -290.838248) (xy 190.703752 -290.877592) (xy 190.668259 -290.911684)
			(xy 190.627756 -290.93964) (xy 190.583294 -290.960738) (xy 190.536023 -290.97443) (xy 190.487168 -290.980362)
			(xy 190.437993 -290.978381) (xy 190.389774 -290.968537) (xy 190.343758 -290.951085) (xy 190.301137 -290.926478)
			(xy 190.263016 -290.895353) (xy 190.230381 -290.858516) (xy 190.204078 -290.81692) (xy 190.184787 -290.771644)
			(xy 190.17301 -290.72386) (xy 190.16905 -290.674806) (xy 189.830202 -290.674806) (xy 189.829707 -290.699413)
			(xy 189.821812 -290.74799) (xy 189.806228 -290.794671) (xy 189.783357 -290.838248) (xy 189.753792 -290.877592)
			(xy 189.718299 -290.911684) (xy 189.677796 -290.93964) (xy 189.633334 -290.960738) (xy 189.586063 -290.97443)
			(xy 189.537208 -290.980362) (xy 189.488033 -290.978381) (xy 189.439814 -290.968537) (xy 189.393798 -290.951085)
			(xy 189.351177 -290.926478) (xy 189.313056 -290.895353) (xy 189.280421 -290.858516) (xy 189.254118 -290.81692)
			(xy 189.234827 -290.771644) (xy 189.22305 -290.72386) (xy 189.21909 -290.674806) (xy 188.880242 -290.674806)
			(xy 188.879747 -290.699413) (xy 188.871852 -290.74799) (xy 188.856268 -290.794671) (xy 188.833397 -290.838248)
			(xy 188.803832 -290.877592) (xy 188.768339 -290.911684) (xy 188.727836 -290.93964) (xy 188.683374 -290.960738)
			(xy 188.636103 -290.97443) (xy 188.587248 -290.980362) (xy 188.538073 -290.978381) (xy 188.489854 -290.968537)
			(xy 188.443838 -290.951085) (xy 188.401217 -290.926478) (xy 188.363096 -290.895353) (xy 188.330461 -290.858516)
			(xy 188.304158 -290.81692) (xy 188.284867 -290.771644) (xy 188.27309 -290.72386) (xy 188.26913 -290.674806)
			(xy 187.930282 -290.674806) (xy 187.929787 -290.699413) (xy 187.921892 -290.74799) (xy 187.906308 -290.794671)
			(xy 187.883437 -290.838248) (xy 187.853872 -290.877592) (xy 187.818379 -290.911684) (xy 187.777876 -290.93964)
			(xy 187.733414 -290.960738) (xy 187.686143 -290.97443) (xy 187.637288 -290.980362) (xy 187.588113 -290.978381)
			(xy 187.539894 -290.968537) (xy 187.493878 -290.951085) (xy 187.451257 -290.926478) (xy 187.413136 -290.895353)
			(xy 187.380501 -290.858516) (xy 187.354198 -290.81692) (xy 187.334907 -290.771644) (xy 187.32313 -290.72386)
			(xy 187.31917 -290.674806) (xy 186.980322 -290.674806) (xy 186.979827 -290.699413) (xy 186.971932 -290.74799)
			(xy 186.956348 -290.794671) (xy 186.933477 -290.838248) (xy 186.903912 -290.877592) (xy 186.868419 -290.911684)
			(xy 186.827916 -290.93964) (xy 186.783454 -290.960738) (xy 186.736183 -290.97443) (xy 186.687328 -290.980362)
			(xy 186.638153 -290.978381) (xy 186.589934 -290.968537) (xy 186.543918 -290.951085) (xy 186.501297 -290.926478)
			(xy 186.463176 -290.895353) (xy 186.430541 -290.858516) (xy 186.404238 -290.81692) (xy 186.384947 -290.771644)
			(xy 186.37317 -290.72386) (xy 186.36921 -290.674806) (xy 186.031718 -290.674806) (xy 186.027535 -290.725272)
			(xy 186.015101 -290.774368) (xy 185.994755 -290.820747) (xy 185.967052 -290.863144) (xy 185.932749 -290.900402)
			(xy 185.89278 -290.931506) (xy 185.848236 -290.955606) (xy 185.800333 -290.972045) (xy 185.750377 -290.980374)
			(xy 185.725054 -290.980876) (xy 185.724546 -290.980876) (xy 185.697216 -290.980276) (xy 185.643427 -290.970565)
			(xy 185.617612 -290.961572) (xy 185.611862 -290.959594) (xy 185.599788 -290.958189) (xy 185.593736 -290.958778)
			(xy 185.58129 -290.960302) (xy 185.523632 -290.999926) (xy 185.523124 -290.999926) (xy 185.50255 -291.014404)
			(xy 185.49287 -291.022011) (xy 185.481435 -291.043772) (xy 185.480706 -291.05606) (xy 185.480706 -291.238686)
			(xy 202.096622 -291.238686) (xy 202.100693 -291.183064) (xy 202.112819 -291.128627) (xy 202.132742 -291.076536)
			(xy 202.160038 -291.027901) (xy 202.194124 -290.983758) (xy 202.234273 -290.945049) (xy 202.279631 -290.912598)
			(xy 202.329231 -290.887097) (xy 202.382015 -290.86909) (xy 202.436858 -290.85896) (xy 202.492592 -290.856923)
			(xy 202.548029 -290.863023) (xy 202.601986 -290.877129) (xy 202.653315 -290.898941) (xy 202.700921 -290.927995)
			(xy 202.743789 -290.96367) (xy 202.781006 -291.005207) (xy 202.811779 -291.05172) (xy 202.835451 -291.102217)
			(xy 202.851519 -291.155624) (xy 202.859639 -291.2108) (xy 202.860148 -291.238686) (xy 202.859639 -291.266572)
			(xy 202.851519 -291.321748) (xy 202.835451 -291.375155) (xy 202.811779 -291.425652) (xy 202.781006 -291.472165)
			(xy 202.743789 -291.513702) (xy 202.700921 -291.549377) (xy 202.653315 -291.578431) (xy 202.621384 -291.592)
			(xy 204.54188 -291.592) (xy 204.545951 -291.536378) (xy 204.558077 -291.481941) (xy 204.578 -291.42985)
			(xy 204.605296 -291.381215) (xy 204.639382 -291.337072) (xy 204.679531 -291.298363) (xy 204.724889 -291.265912)
			(xy 204.774489 -291.240411) (xy 204.827273 -291.222404) (xy 204.882116 -291.212274) (xy 204.93785 -291.210237)
			(xy 204.993287 -291.216337) (xy 205.047244 -291.230443) (xy 205.098573 -291.252255) (xy 205.146179 -291.281309)
			(xy 205.189047 -291.316984) (xy 205.226264 -291.358521) (xy 205.257037 -291.405034) (xy 205.280709 -291.455531)
			(xy 205.296777 -291.508938) (xy 205.304897 -291.564114) (xy 205.305406 -291.592) (xy 205.304897 -291.619886)
			(xy 205.296777 -291.675062) (xy 205.280709 -291.728469) (xy 205.257037 -291.778966) (xy 205.226264 -291.825479)
			(xy 205.189047 -291.867016) (xy 205.146179 -291.902691) (xy 205.098573 -291.931745) (xy 205.047244 -291.953557)
			(xy 204.993287 -291.967663) (xy 204.93785 -291.973763) (xy 204.882116 -291.971726) (xy 204.827273 -291.961596)
			(xy 204.774489 -291.943589) (xy 204.724889 -291.918088) (xy 204.679531 -291.885637) (xy 204.639382 -291.846928)
			(xy 204.605296 -291.802785) (xy 204.578 -291.75415) (xy 204.558077 -291.702059) (xy 204.545951 -291.647622)
			(xy 204.54188 -291.592) (xy 202.621384 -291.592) (xy 202.601986 -291.600243) (xy 202.548029 -291.614349)
			(xy 202.492592 -291.620449) (xy 202.436858 -291.618412) (xy 202.382015 -291.608282) (xy 202.329231 -291.590275)
			(xy 202.279631 -291.564774) (xy 202.234273 -291.532323) (xy 202.194124 -291.493614) (xy 202.160038 -291.449471)
			(xy 202.132742 -291.400836) (xy 202.112819 -291.348745) (xy 202.100693 -291.294308) (xy 202.096622 -291.238686)
			(xy 185.480706 -291.238686) (xy 185.480706 -291.243512) (xy 185.481295 -291.255841) (xy 185.492741 -291.277677)
			(xy 185.50255 -291.285168) (xy 185.523378 -291.299646) (xy 185.57113 -291.332412) (xy 185.581625 -291.338737)
			(xy 185.605915 -291.341653) (xy 185.617612 -291.338) (xy 185.643428 -291.329013) (xy 185.697217 -291.319297)
			(xy 185.724546 -291.318696) (xy 185.725054 -291.318696) (xy 185.75038 -291.319186) (xy 185.800342 -291.327517)
			(xy 185.848252 -291.343958) (xy 185.892801 -291.368061) (xy 185.932776 -291.399168) (xy 185.967084 -291.436432)
			(xy 185.99479 -291.478834) (xy 186.015139 -291.525219) (xy 186.027574 -291.574321) (xy 186.031755 -291.624766)
			(xy 186.36921 -291.624766) (xy 186.37317 -291.575712) (xy 186.384947 -291.527928) (xy 186.404238 -291.482652)
			(xy 186.430541 -291.441056) (xy 186.463176 -291.404219) (xy 186.501297 -291.373094) (xy 186.543918 -291.348487)
			(xy 186.589934 -291.331035) (xy 186.638153 -291.321191) (xy 186.687328 -291.31921) (xy 186.736183 -291.325142)
			(xy 186.783454 -291.338834) (xy 186.827916 -291.359932) (xy 186.868419 -291.387888) (xy 186.903912 -291.42198)
			(xy 186.933477 -291.461324) (xy 186.956348 -291.504901) (xy 186.971932 -291.551582) (xy 186.979827 -291.600159)
			(xy 186.980322 -291.624766) (xy 187.31917 -291.624766) (xy 187.32313 -291.575712) (xy 187.334907 -291.527928)
			(xy 187.354198 -291.482652) (xy 187.380501 -291.441056) (xy 187.413136 -291.404219) (xy 187.451257 -291.373094)
			(xy 187.493878 -291.348487) (xy 187.539894 -291.331035) (xy 187.588113 -291.321191) (xy 187.637288 -291.31921)
			(xy 187.686143 -291.325142) (xy 187.733414 -291.338834) (xy 187.777876 -291.359932) (xy 187.818379 -291.387888)
			(xy 187.853872 -291.42198) (xy 187.883437 -291.461324) (xy 187.906308 -291.504901) (xy 187.921892 -291.551582)
			(xy 187.929787 -291.600159) (xy 187.930282 -291.624766) (xy 188.26913 -291.624766) (xy 188.27309 -291.575712)
			(xy 188.284867 -291.527928) (xy 188.304158 -291.482652) (xy 188.330461 -291.441056) (xy 188.363096 -291.404219)
			(xy 188.401217 -291.373094) (xy 188.443838 -291.348487) (xy 188.489854 -291.331035) (xy 188.538073 -291.321191)
			(xy 188.587248 -291.31921) (xy 188.636103 -291.325142) (xy 188.683374 -291.338834) (xy 188.727836 -291.359932)
			(xy 188.768339 -291.387888) (xy 188.803832 -291.42198) (xy 188.833397 -291.461324) (xy 188.856268 -291.504901)
			(xy 188.871852 -291.551582) (xy 188.879747 -291.600159) (xy 188.880242 -291.624766) (xy 189.21909 -291.624766)
			(xy 189.22305 -291.575712) (xy 189.234827 -291.527928) (xy 189.254118 -291.482652) (xy 189.280421 -291.441056)
			(xy 189.313056 -291.404219) (xy 189.351177 -291.373094) (xy 189.393798 -291.348487) (xy 189.439814 -291.331035)
			(xy 189.488033 -291.321191) (xy 189.537208 -291.31921) (xy 189.586063 -291.325142) (xy 189.633334 -291.338834)
			(xy 189.677796 -291.359932) (xy 189.718299 -291.387888) (xy 189.753792 -291.42198) (xy 189.783357 -291.461324)
			(xy 189.806228 -291.504901) (xy 189.821812 -291.551582) (xy 189.829707 -291.600159) (xy 189.830202 -291.624766)
			(xy 190.169304 -291.624766) (xy 190.173264 -291.575712) (xy 190.185041 -291.527928) (xy 190.204332 -291.482652)
			(xy 190.230635 -291.441056) (xy 190.26327 -291.404219) (xy 190.301391 -291.373094) (xy 190.344012 -291.348487)
			(xy 190.390028 -291.331035) (xy 190.438247 -291.321191) (xy 190.487422 -291.31921) (xy 190.536277 -291.325142)
			(xy 190.583548 -291.338834) (xy 190.62801 -291.359932) (xy 190.668513 -291.387888) (xy 190.704006 -291.42198)
			(xy 190.733571 -291.461324) (xy 190.756442 -291.504901) (xy 190.772026 -291.551582) (xy 190.779921 -291.600159)
			(xy 190.780416 -291.624766) (xy 192.069224 -291.624766) (xy 192.073184 -291.575712) (xy 192.084961 -291.527928)
			(xy 192.104252 -291.482652) (xy 192.130555 -291.441056) (xy 192.16319 -291.404219) (xy 192.201311 -291.373094)
			(xy 192.243932 -291.348487) (xy 192.289948 -291.331035) (xy 192.338167 -291.321191) (xy 192.387342 -291.31921)
			(xy 192.436197 -291.325142) (xy 192.483468 -291.338834) (xy 192.52793 -291.359932) (xy 192.568433 -291.387888)
			(xy 192.603926 -291.42198) (xy 192.633491 -291.461324) (xy 192.656362 -291.504901) (xy 192.671946 -291.551582)
			(xy 192.679841 -291.600159) (xy 192.680336 -291.624766) (xy 193.019184 -291.624766) (xy 193.023144 -291.575712)
			(xy 193.034921 -291.527928) (xy 193.054212 -291.482652) (xy 193.080515 -291.441056) (xy 193.11315 -291.404219)
			(xy 193.151271 -291.373094) (xy 193.193892 -291.348487) (xy 193.239908 -291.331035) (xy 193.288127 -291.321191)
			(xy 193.337302 -291.31921) (xy 193.386157 -291.325142) (xy 193.433428 -291.338834) (xy 193.47789 -291.359932)
			(xy 193.518393 -291.387888) (xy 193.553886 -291.42198) (xy 193.583451 -291.461324) (xy 193.606322 -291.504901)
			(xy 193.621906 -291.551582) (xy 193.629801 -291.600159) (xy 193.630296 -291.624766) (xy 193.969144 -291.624766)
			(xy 193.973104 -291.575712) (xy 193.984881 -291.527928) (xy 194.004172 -291.482652) (xy 194.030475 -291.441056)
			(xy 194.06311 -291.404219) (xy 194.101231 -291.373094) (xy 194.143852 -291.348487) (xy 194.189868 -291.331035)
			(xy 194.238087 -291.321191) (xy 194.287262 -291.31921) (xy 194.336117 -291.325142) (xy 194.383388 -291.338834)
			(xy 194.42785 -291.359932) (xy 194.468353 -291.387888) (xy 194.503846 -291.42198) (xy 194.533411 -291.461324)
			(xy 194.556282 -291.504901) (xy 194.571866 -291.551582) (xy 194.579761 -291.600159) (xy 194.580256 -291.624766)
			(xy 194.919104 -291.624766) (xy 194.923064 -291.575712) (xy 194.934841 -291.527928) (xy 194.954132 -291.482652)
			(xy 194.980435 -291.441056) (xy 195.01307 -291.404219) (xy 195.051191 -291.373094) (xy 195.093812 -291.348487)
			(xy 195.139828 -291.331035) (xy 195.188047 -291.321191) (xy 195.237222 -291.31921) (xy 195.286077 -291.325142)
			(xy 195.333348 -291.338834) (xy 195.37781 -291.359932) (xy 195.418313 -291.387888) (xy 195.453806 -291.42198)
			(xy 195.483371 -291.461324) (xy 195.506242 -291.504901) (xy 195.521826 -291.551582) (xy 195.529721 -291.600159)
			(xy 195.530216 -291.624766) (xy 195.869064 -291.624766) (xy 195.873024 -291.575712) (xy 195.884801 -291.527928)
			(xy 195.904092 -291.482652) (xy 195.930395 -291.441056) (xy 195.96303 -291.404219) (xy 196.001151 -291.373094)
			(xy 196.043772 -291.348487) (xy 196.089788 -291.331035) (xy 196.138007 -291.321191) (xy 196.187182 -291.31921)
			(xy 196.236037 -291.325142) (xy 196.283308 -291.338834) (xy 196.32777 -291.359932) (xy 196.368273 -291.387888)
			(xy 196.403766 -291.42198) (xy 196.433331 -291.461324) (xy 196.456202 -291.504901) (xy 196.471786 -291.551582)
			(xy 196.479681 -291.600159) (xy 196.480176 -291.624766) (xy 196.819278 -291.624766) (xy 196.823238 -291.575712)
			(xy 196.835015 -291.527928) (xy 196.854306 -291.482652) (xy 196.880609 -291.441056) (xy 196.913244 -291.404219)
			(xy 196.951365 -291.373094) (xy 196.993986 -291.348487) (xy 197.040002 -291.331035) (xy 197.088221 -291.321191)
			(xy 197.137396 -291.31921) (xy 197.186251 -291.325142) (xy 197.233522 -291.338834) (xy 197.277984 -291.359932)
			(xy 197.318487 -291.387888) (xy 197.35398 -291.42198) (xy 197.383545 -291.461324) (xy 197.406416 -291.504901)
			(xy 197.422 -291.551582) (xy 197.429895 -291.600159) (xy 197.43039 -291.624766) (xy 197.769238 -291.624766)
			(xy 197.773198 -291.575712) (xy 197.784975 -291.527928) (xy 197.804266 -291.482652) (xy 197.830569 -291.441056)
			(xy 197.863204 -291.404219) (xy 197.901325 -291.373094) (xy 197.943946 -291.348487) (xy 197.989962 -291.331035)
			(xy 198.038181 -291.321191) (xy 198.087356 -291.31921) (xy 198.136211 -291.325142) (xy 198.183482 -291.338834)
			(xy 198.227944 -291.359932) (xy 198.268447 -291.387888) (xy 198.30394 -291.42198) (xy 198.333505 -291.461324)
			(xy 198.356376 -291.504901) (xy 198.37196 -291.551582) (xy 198.379855 -291.600159) (xy 198.38035 -291.624766)
			(xy 198.719198 -291.624766) (xy 198.723158 -291.575712) (xy 198.734935 -291.527928) (xy 198.754226 -291.482652)
			(xy 198.780529 -291.441056) (xy 198.813164 -291.404219) (xy 198.851285 -291.373094) (xy 198.893906 -291.348487)
			(xy 198.939922 -291.331035) (xy 198.988141 -291.321191) (xy 199.037316 -291.31921) (xy 199.086171 -291.325142)
			(xy 199.133442 -291.338834) (xy 199.177904 -291.359932) (xy 199.218407 -291.387888) (xy 199.2539 -291.42198)
			(xy 199.283465 -291.461324) (xy 199.306336 -291.504901) (xy 199.32192 -291.551582) (xy 199.329815 -291.600159)
			(xy 199.33031 -291.624766) (xy 199.329815 -291.649373) (xy 199.32192 -291.69795) (xy 199.306336 -291.744631)
			(xy 199.283465 -291.788208) (xy 199.2539 -291.827552) (xy 199.218407 -291.861644) (xy 199.177904 -291.8896)
			(xy 199.133442 -291.910698) (xy 199.086171 -291.92439) (xy 199.037316 -291.930322) (xy 198.988141 -291.928341)
			(xy 198.939922 -291.918497) (xy 198.893906 -291.901045) (xy 198.851285 -291.876438) (xy 198.813164 -291.845313)
			(xy 198.780529 -291.808476) (xy 198.754226 -291.76688) (xy 198.734935 -291.721604) (xy 198.723158 -291.67382)
			(xy 198.719198 -291.624766) (xy 198.38035 -291.624766) (xy 198.379855 -291.649373) (xy 198.37196 -291.69795)
			(xy 198.356376 -291.744631) (xy 198.333505 -291.788208) (xy 198.30394 -291.827552) (xy 198.268447 -291.861644)
			(xy 198.227944 -291.8896) (xy 198.183482 -291.910698) (xy 198.136211 -291.92439) (xy 198.087356 -291.930322)
			(xy 198.038181 -291.928341) (xy 197.989962 -291.918497) (xy 197.943946 -291.901045) (xy 197.901325 -291.876438)
			(xy 197.863204 -291.845313) (xy 197.830569 -291.808476) (xy 197.804266 -291.76688) (xy 197.784975 -291.721604)
			(xy 197.773198 -291.67382) (xy 197.769238 -291.624766) (xy 197.43039 -291.624766) (xy 197.429895 -291.649373)
			(xy 197.422 -291.69795) (xy 197.406416 -291.744631) (xy 197.383545 -291.788208) (xy 197.35398 -291.827552)
			(xy 197.318487 -291.861644) (xy 197.277984 -291.8896) (xy 197.233522 -291.910698) (xy 197.186251 -291.92439)
			(xy 197.137396 -291.930322) (xy 197.088221 -291.928341) (xy 197.040002 -291.918497) (xy 196.993986 -291.901045)
			(xy 196.951365 -291.876438) (xy 196.913244 -291.845313) (xy 196.880609 -291.808476) (xy 196.854306 -291.76688)
			(xy 196.835015 -291.721604) (xy 196.823238 -291.67382) (xy 196.819278 -291.624766) (xy 196.480176 -291.624766)
			(xy 196.479681 -291.649373) (xy 196.471786 -291.69795) (xy 196.456202 -291.744631) (xy 196.433331 -291.788208)
			(xy 196.403766 -291.827552) (xy 196.368273 -291.861644) (xy 196.32777 -291.8896) (xy 196.283308 -291.910698)
			(xy 196.236037 -291.92439) (xy 196.187182 -291.930322) (xy 196.138007 -291.928341) (xy 196.089788 -291.918497)
			(xy 196.043772 -291.901045) (xy 196.001151 -291.876438) (xy 195.96303 -291.845313) (xy 195.930395 -291.808476)
			(xy 195.904092 -291.76688) (xy 195.884801 -291.721604) (xy 195.873024 -291.67382) (xy 195.869064 -291.624766)
			(xy 195.530216 -291.624766) (xy 195.529721 -291.649373) (xy 195.521826 -291.69795) (xy 195.506242 -291.744631)
			(xy 195.483371 -291.788208) (xy 195.453806 -291.827552) (xy 195.418313 -291.861644) (xy 195.37781 -291.8896)
			(xy 195.333348 -291.910698) (xy 195.286077 -291.92439) (xy 195.237222 -291.930322) (xy 195.188047 -291.928341)
			(xy 195.139828 -291.918497) (xy 195.093812 -291.901045) (xy 195.051191 -291.876438) (xy 195.01307 -291.845313)
			(xy 194.980435 -291.808476) (xy 194.954132 -291.76688) (xy 194.934841 -291.721604) (xy 194.923064 -291.67382)
			(xy 194.919104 -291.624766) (xy 194.580256 -291.624766) (xy 194.579761 -291.649373) (xy 194.571866 -291.69795)
			(xy 194.556282 -291.744631) (xy 194.533411 -291.788208) (xy 194.503846 -291.827552) (xy 194.468353 -291.861644)
			(xy 194.42785 -291.8896) (xy 194.383388 -291.910698) (xy 194.336117 -291.92439) (xy 194.287262 -291.930322)
			(xy 194.238087 -291.928341) (xy 194.189868 -291.918497) (xy 194.143852 -291.901045) (xy 194.101231 -291.876438)
			(xy 194.06311 -291.845313) (xy 194.030475 -291.808476) (xy 194.004172 -291.76688) (xy 193.984881 -291.721604)
			(xy 193.973104 -291.67382) (xy 193.969144 -291.624766) (xy 193.630296 -291.624766) (xy 193.629801 -291.649373)
			(xy 193.621906 -291.69795) (xy 193.606322 -291.744631) (xy 193.583451 -291.788208) (xy 193.553886 -291.827552)
			(xy 193.518393 -291.861644) (xy 193.47789 -291.8896) (xy 193.433428 -291.910698) (xy 193.386157 -291.92439)
			(xy 193.337302 -291.930322) (xy 193.288127 -291.928341) (xy 193.239908 -291.918497) (xy 193.193892 -291.901045)
			(xy 193.151271 -291.876438) (xy 193.11315 -291.845313) (xy 193.080515 -291.808476) (xy 193.054212 -291.76688)
			(xy 193.034921 -291.721604) (xy 193.023144 -291.67382) (xy 193.019184 -291.624766) (xy 192.680336 -291.624766)
			(xy 192.679841 -291.649373) (xy 192.671946 -291.69795) (xy 192.656362 -291.744631) (xy 192.633491 -291.788208)
			(xy 192.603926 -291.827552) (xy 192.568433 -291.861644) (xy 192.52793 -291.8896) (xy 192.483468 -291.910698)
			(xy 192.436197 -291.92439) (xy 192.387342 -291.930322) (xy 192.338167 -291.928341) (xy 192.289948 -291.918497)
			(xy 192.243932 -291.901045) (xy 192.201311 -291.876438) (xy 192.16319 -291.845313) (xy 192.130555 -291.808476)
			(xy 192.104252 -291.76688) (xy 192.084961 -291.721604) (xy 192.073184 -291.67382) (xy 192.069224 -291.624766)
			(xy 190.780416 -291.624766) (xy 190.779921 -291.649373) (xy 190.772026 -291.69795) (xy 190.756442 -291.744631)
			(xy 190.733571 -291.788208) (xy 190.704006 -291.827552) (xy 190.668513 -291.861644) (xy 190.62801 -291.8896)
			(xy 190.583548 -291.910698) (xy 190.536277 -291.92439) (xy 190.487422 -291.930322) (xy 190.438247 -291.928341)
			(xy 190.390028 -291.918497) (xy 190.344012 -291.901045) (xy 190.301391 -291.876438) (xy 190.26327 -291.845313)
			(xy 190.230635 -291.808476) (xy 190.204332 -291.76688) (xy 190.185041 -291.721604) (xy 190.173264 -291.67382)
			(xy 190.169304 -291.624766) (xy 189.830202 -291.624766) (xy 189.829707 -291.649373) (xy 189.821812 -291.69795)
			(xy 189.806228 -291.744631) (xy 189.783357 -291.788208) (xy 189.753792 -291.827552) (xy 189.718299 -291.861644)
			(xy 189.677796 -291.8896) (xy 189.633334 -291.910698) (xy 189.586063 -291.92439) (xy 189.537208 -291.930322)
			(xy 189.488033 -291.928341) (xy 189.439814 -291.918497) (xy 189.393798 -291.901045) (xy 189.351177 -291.876438)
			(xy 189.313056 -291.845313) (xy 189.280421 -291.808476) (xy 189.254118 -291.76688) (xy 189.234827 -291.721604)
			(xy 189.22305 -291.67382) (xy 189.21909 -291.624766) (xy 188.880242 -291.624766) (xy 188.879747 -291.649373)
			(xy 188.871852 -291.69795) (xy 188.856268 -291.744631) (xy 188.833397 -291.788208) (xy 188.803832 -291.827552)
			(xy 188.768339 -291.861644) (xy 188.727836 -291.8896) (xy 188.683374 -291.910698) (xy 188.636103 -291.92439)
			(xy 188.587248 -291.930322) (xy 188.538073 -291.928341) (xy 188.489854 -291.918497) (xy 188.443838 -291.901045)
			(xy 188.401217 -291.876438) (xy 188.363096 -291.845313) (xy 188.330461 -291.808476) (xy 188.304158 -291.76688)
			(xy 188.284867 -291.721604) (xy 188.27309 -291.67382) (xy 188.26913 -291.624766) (xy 187.930282 -291.624766)
			(xy 187.929787 -291.649373) (xy 187.921892 -291.69795) (xy 187.906308 -291.744631) (xy 187.883437 -291.788208)
			(xy 187.853872 -291.827552) (xy 187.818379 -291.861644) (xy 187.777876 -291.8896) (xy 187.733414 -291.910698)
			(xy 187.686143 -291.92439) (xy 187.637288 -291.930322) (xy 187.588113 -291.928341) (xy 187.539894 -291.918497)
			(xy 187.493878 -291.901045) (xy 187.451257 -291.876438) (xy 187.413136 -291.845313) (xy 187.380501 -291.808476)
			(xy 187.354198 -291.76688) (xy 187.334907 -291.721604) (xy 187.32313 -291.67382) (xy 187.31917 -291.624766)
			(xy 186.980322 -291.624766) (xy 186.979827 -291.649373) (xy 186.971932 -291.69795) (xy 186.956348 -291.744631)
			(xy 186.933477 -291.788208) (xy 186.903912 -291.827552) (xy 186.868419 -291.861644) (xy 186.827916 -291.8896)
			(xy 186.783454 -291.910698) (xy 186.736183 -291.92439) (xy 186.687328 -291.930322) (xy 186.638153 -291.928341)
			(xy 186.589934 -291.918497) (xy 186.543918 -291.901045) (xy 186.501297 -291.876438) (xy 186.463176 -291.845313)
			(xy 186.430541 -291.808476) (xy 186.404238 -291.76688) (xy 186.384947 -291.721604) (xy 186.37317 -291.67382)
			(xy 186.36921 -291.624766) (xy 186.031755 -291.624766) (xy 186.031758 -291.6248) (xy 186.027574 -291.675279)
			(xy 186.015139 -291.724381) (xy 185.99479 -291.770766) (xy 185.967084 -291.813168) (xy 185.932776 -291.850432)
			(xy 185.892801 -291.881539) (xy 185.848252 -291.905642) (xy 185.800342 -291.922083) (xy 185.75038 -291.930414)
			(xy 185.725054 -291.930836) (xy 185.724546 -291.930836) (xy 185.697216 -291.930236) (xy 185.643426 -291.920527)
			(xy 185.617612 -291.911532) (xy 185.611862 -291.909555) (xy 185.599788 -291.908152) (xy 185.593736 -291.908738)
			(xy 185.58129 -291.910262) (xy 185.523632 -291.949886) (xy 185.523124 -291.949886) (xy 185.50255 -291.964364)
			(xy 185.492879 -291.971975) (xy 185.48147 -291.993737) (xy 185.480706 -292.00602) (xy 185.480706 -292.122098)
			(xy 209.357468 -292.122098) (xy 209.357886 -292.095493) (xy 209.365269 -292.042797) (xy 209.379907 -291.991639)
			(xy 209.401514 -291.943013) (xy 209.429671 -291.897863) (xy 209.463831 -291.857065) (xy 209.503331 -291.821413)
			(xy 209.525108 -291.806122) (xy 209.536541 -291.797728) (xy 209.554741 -291.775997) (xy 209.56626 -291.750097)
			(xy 209.570205 -291.722027) (xy 209.566274 -291.693955) (xy 209.55477 -291.668049) (xy 209.536581 -291.646309)
			(xy 209.525108 -291.637974) (xy 209.50331 -291.622718) (xy 209.463833 -291.587044) (xy 209.429693 -291.546233)
			(xy 209.401551 -291.501076) (xy 209.379953 -291.452449) (xy 209.365318 -291.401294) (xy 209.357929 -291.348602)
			(xy 209.357468 -291.321998) (xy 209.357954 -291.294747) (xy 209.36571 -291.240799) (xy 209.381065 -291.188504)
			(xy 209.403707 -291.138927) (xy 209.433173 -291.093077) (xy 209.468864 -291.051886) (xy 209.510055 -291.016195)
			(xy 209.555905 -290.986729) (xy 209.605482 -290.964087) (xy 209.657777 -290.948732) (xy 209.711725 -290.940976)
			(xy 209.766227 -290.940976) (xy 209.820175 -290.948732) (xy 209.87247 -290.964087) (xy 209.922047 -290.986729)
			(xy 209.967897 -291.016195) (xy 210.009088 -291.051886) (xy 210.044779 -291.093077) (xy 210.074245 -291.138927)
			(xy 210.096887 -291.188504) (xy 210.112242 -291.240799) (xy 210.119998 -291.294747) (xy 210.120484 -291.321998)
			(xy 210.120041 -291.348602) (xy 210.112659 -291.401296) (xy 210.098024 -291.452452) (xy 210.076421 -291.501077)
			(xy 210.048268 -291.546227) (xy 210.014113 -291.587026) (xy 209.974619 -291.622681) (xy 209.952844 -291.637974)
			(xy 209.950643 -291.639553) (xy 218.343175 -291.639553) (xy 218.343175 -291.585047) (xy 218.350933 -291.531097)
			(xy 218.366289 -291.4788) (xy 218.388932 -291.429221) (xy 218.418401 -291.383369) (xy 218.454096 -291.342177)
			(xy 218.495289 -291.306486) (xy 218.541143 -291.27702) (xy 218.590724 -291.25438) (xy 218.643022 -291.239027)
			(xy 218.696973 -291.231274) (xy 218.724226 -291.230812) (xy 218.751597 -291.23126) (xy 218.805777 -291.239082)
			(xy 218.85828 -291.254575) (xy 218.908027 -291.277421) (xy 218.953993 -291.307149) (xy 218.974924 -291.324792)
			(xy 218.982036 -291.330888) (xy 218.999054 -291.337238) (xy 219.084398 -291.337238) (xy 219.101416 -291.330888)
			(xy 219.108528 -291.324792) (xy 219.129475 -291.307172) (xy 219.175444 -291.277458) (xy 219.225188 -291.254618)
			(xy 219.277685 -291.239122) (xy 219.331858 -291.231289) (xy 219.359226 -291.230812) (xy 219.386477 -291.23126)
			(xy 219.440425 -291.23902) (xy 219.49272 -291.254378) (xy 219.542296 -291.277022) (xy 219.588146 -291.30649)
			(xy 219.629335 -291.342183) (xy 219.665026 -291.383375) (xy 219.694491 -291.429227) (xy 219.717131 -291.478805)
			(xy 219.732486 -291.5311) (xy 219.740242 -291.585049) (xy 219.740242 -291.639549) (xy 220.096598 -291.639549)
			(xy 220.096598 -291.585051) (xy 220.104354 -291.531107) (xy 220.119708 -291.478816) (xy 220.142347 -291.429242)
			(xy 220.17181 -291.383395) (xy 220.207499 -291.342207) (xy 220.248685 -291.306518) (xy 220.294532 -291.277052)
			(xy 220.344105 -291.254412) (xy 220.396395 -291.239057) (xy 220.450339 -291.231299) (xy 220.477588 -291.230812)
			(xy 220.504958 -291.231282) (xy 220.559137 -291.239099) (xy 220.61164 -291.254587) (xy 220.661387 -291.277427)
			(xy 220.707354 -291.307151) (xy 220.728286 -291.324792) (xy 220.735398 -291.330888) (xy 220.752416 -291.337238)
			(xy 220.83776 -291.337238) (xy 220.854778 -291.330888) (xy 220.86189 -291.324792) (xy 220.882814 -291.307143)
			(xy 220.928789 -291.277433) (xy 220.978539 -291.254599) (xy 221.031041 -291.23911) (xy 221.085218 -291.231285)
			(xy 221.112588 -291.230812) (xy 221.139843 -291.231234) (xy 221.193798 -291.23899) (xy 221.2461 -291.254346)
			(xy 221.295684 -291.276989) (xy 221.341541 -291.306458) (xy 221.382738 -291.342154) (xy 221.418435 -291.383349)
			(xy 221.447905 -291.429205) (xy 221.47055 -291.478789) (xy 221.485907 -291.53109) (xy 221.493665 -291.585045)
			(xy 221.493665 -291.639555) (xy 221.485907 -291.69351) (xy 221.47055 -291.745811) (xy 221.447905 -291.795395)
			(xy 221.418435 -291.841251) (xy 221.382738 -291.882446) (xy 221.341541 -291.918142) (xy 221.295684 -291.947611)
			(xy 221.2461 -291.970254) (xy 221.193798 -291.98561) (xy 221.139843 -291.993366) (xy 221.112588 -291.993828)
			(xy 221.085217 -291.993387) (xy 221.031036 -291.985565) (xy 220.978532 -291.970072) (xy 220.928785 -291.947224)
			(xy 220.88282 -291.917493) (xy 220.86189 -291.899848) (xy 220.854778 -291.893752) (xy 220.83776 -291.887402)
			(xy 220.752416 -291.887402) (xy 220.735398 -291.893752) (xy 220.728286 -291.899848) (xy 220.707326 -291.917452)
			(xy 220.661361 -291.947171) (xy 220.611621 -291.970015) (xy 220.559126 -291.985514) (xy 220.504955 -291.99335)
			(xy 220.477588 -291.993828) (xy 220.450339 -291.993301) (xy 220.396395 -291.985543) (xy 220.344105 -291.970188)
			(xy 220.294532 -291.947548) (xy 220.248685 -291.918082) (xy 220.207499 -291.882393) (xy 220.17181 -291.841205)
			(xy 220.142347 -291.795358) (xy 220.119708 -291.745784) (xy 220.104354 -291.693493) (xy 220.096598 -291.639549)
			(xy 219.740242 -291.639549) (xy 219.740242 -291.639551) (xy 219.732486 -291.6935) (xy 219.717131 -291.745795)
			(xy 219.694491 -291.795373) (xy 219.665026 -291.841225) (xy 219.629335 -291.882417) (xy 219.588146 -291.91811)
			(xy 219.542296 -291.947578) (xy 219.49272 -291.970222) (xy 219.440425 -291.98558) (xy 219.386477 -291.99334)
			(xy 219.359226 -291.993828) (xy 219.331855 -291.993364) (xy 219.277676 -291.985549) (xy 219.225172 -291.97006)
			(xy 219.175425 -291.947217) (xy 219.129459 -291.917491) (xy 219.108528 -291.899848) (xy 219.101416 -291.893752)
			(xy 219.084398 -291.887402) (xy 218.999054 -291.887402) (xy 218.982036 -291.893752) (xy 218.974924 -291.899848)
			(xy 218.953987 -291.917481) (xy 218.908016 -291.947196) (xy 218.85827 -291.970034) (xy 218.80577 -291.985526)
			(xy 218.751595 -291.993354) (xy 218.724226 -291.993828) (xy 218.696973 -291.993326) (xy 218.643022 -291.985573)
			(xy 218.590724 -291.97022) (xy 218.541143 -291.94758) (xy 218.495289 -291.918114) (xy 218.454096 -291.882423)
			(xy 218.418401 -291.841231) (xy 218.388932 -291.795379) (xy 218.366289 -291.7458) (xy 218.350933 -291.693503)
			(xy 218.343175 -291.639553) (xy 209.950643 -291.639553) (xy 209.941313 -291.646246) (xy 209.9231 -291.668001)
			(xy 209.911581 -291.693929) (xy 209.907644 -291.722027) (xy 209.911595 -291.750123) (xy 209.923129 -291.776045)
			(xy 209.941353 -291.79779) (xy 209.952844 -291.806122) (xy 209.97463 -291.821396) (xy 210.014109 -291.857065)
			(xy 210.048252 -291.897872) (xy 210.076396 -291.943026) (xy 210.097996 -291.991651) (xy 210.112633 -292.042804)
			(xy 210.120023 -292.095495) (xy 210.120484 -292.122098) (xy 210.119998 -292.149349) (xy 210.112242 -292.203297)
			(xy 210.096887 -292.255592) (xy 210.074245 -292.305169) (xy 210.044779 -292.351019) (xy 210.009088 -292.39221)
			(xy 209.967897 -292.427901) (xy 209.922047 -292.457367) (xy 209.87247 -292.480009) (xy 209.820175 -292.495364)
			(xy 209.766227 -292.50312) (xy 209.711725 -292.50312) (xy 209.657777 -292.495364) (xy 209.605482 -292.480009)
			(xy 209.555905 -292.457367) (xy 209.510055 -292.427901) (xy 209.468864 -292.39221) (xy 209.433173 -292.351019)
			(xy 209.403707 -292.305169) (xy 209.381065 -292.255592) (xy 209.36571 -292.203297) (xy 209.357954 -292.149349)
			(xy 209.357468 -292.122098) (xy 185.480706 -292.122098) (xy 185.480706 -292.193472) (xy 185.481308 -292.205793)
			(xy 185.492768 -292.227608) (xy 185.50255 -292.235128) (xy 185.523378 -292.249606) (xy 185.57113 -292.282372)
			(xy 185.581624 -292.288701) (xy 185.605916 -292.291619) (xy 185.617612 -292.28796) (xy 185.643429 -292.278974)
			(xy 185.697217 -292.26926) (xy 185.724546 -292.268656) (xy 185.725054 -292.268656) (xy 185.750375 -292.269146)
			(xy 185.800328 -292.277475) (xy 185.848228 -292.293913) (xy 185.892769 -292.318011) (xy 185.932735 -292.349112)
			(xy 185.967037 -292.386369) (xy 185.994738 -292.428763) (xy 186.015082 -292.475139) (xy 186.027515 -292.524231)
			(xy 186.031698 -292.5747) (xy 186.031675 -292.57498) (xy 186.36921 -292.57498) (xy 186.37317 -292.525926)
			(xy 186.384947 -292.478142) (xy 186.404238 -292.432866) (xy 186.430541 -292.39127) (xy 186.463176 -292.354433)
			(xy 186.501297 -292.323308) (xy 186.543918 -292.298701) (xy 186.589934 -292.281249) (xy 186.638153 -292.271405)
			(xy 186.687328 -292.269424) (xy 186.736183 -292.275356) (xy 186.783454 -292.289048) (xy 186.827916 -292.310146)
			(xy 186.868419 -292.338102) (xy 186.903912 -292.372194) (xy 186.933477 -292.411538) (xy 186.956348 -292.455115)
			(xy 186.971932 -292.501796) (xy 186.979827 -292.550373) (xy 186.980317 -292.574726) (xy 187.31917 -292.574726)
			(xy 187.32313 -292.525672) (xy 187.334907 -292.477888) (xy 187.354198 -292.432612) (xy 187.380501 -292.391016)
			(xy 187.413136 -292.354179) (xy 187.451257 -292.323054) (xy 187.493878 -292.298447) (xy 187.539894 -292.280995)
			(xy 187.588113 -292.271151) (xy 187.637288 -292.26917) (xy 187.686143 -292.275102) (xy 187.733414 -292.288794)
			(xy 187.777876 -292.309892) (xy 187.818379 -292.337848) (xy 187.853872 -292.37194) (xy 187.883437 -292.411284)
			(xy 187.906308 -292.454861) (xy 187.921892 -292.501542) (xy 187.929787 -292.550119) (xy 187.930282 -292.574726)
			(xy 188.26913 -292.574726) (xy 188.27309 -292.525672) (xy 188.284867 -292.477888) (xy 188.304158 -292.432612)
			(xy 188.330461 -292.391016) (xy 188.363096 -292.354179) (xy 188.401217 -292.323054) (xy 188.443838 -292.298447)
			(xy 188.489854 -292.280995) (xy 188.538073 -292.271151) (xy 188.587248 -292.26917) (xy 188.636103 -292.275102)
			(xy 188.683374 -292.288794) (xy 188.727836 -292.309892) (xy 188.768339 -292.337848) (xy 188.803832 -292.37194)
			(xy 188.833397 -292.411284) (xy 188.856268 -292.454861) (xy 188.871852 -292.501542) (xy 188.879747 -292.550119)
			(xy 188.880242 -292.574726) (xy 189.21909 -292.574726) (xy 189.22305 -292.525672) (xy 189.234827 -292.477888)
			(xy 189.254118 -292.432612) (xy 189.280421 -292.391016) (xy 189.313056 -292.354179) (xy 189.351177 -292.323054)
			(xy 189.393798 -292.298447) (xy 189.439814 -292.280995) (xy 189.488033 -292.271151) (xy 189.537208 -292.26917)
			(xy 189.586063 -292.275102) (xy 189.633334 -292.288794) (xy 189.677796 -292.309892) (xy 189.718299 -292.337848)
			(xy 189.753792 -292.37194) (xy 189.783357 -292.411284) (xy 189.806228 -292.454861) (xy 189.821812 -292.501542)
			(xy 189.829707 -292.550119) (xy 189.830202 -292.574726) (xy 190.16905 -292.574726) (xy 190.17301 -292.525672)
			(xy 190.184787 -292.477888) (xy 190.204078 -292.432612) (xy 190.230381 -292.391016) (xy 190.263016 -292.354179)
			(xy 190.301137 -292.323054) (xy 190.343758 -292.298447) (xy 190.389774 -292.280995) (xy 190.437993 -292.271151)
			(xy 190.487168 -292.26917) (xy 190.536023 -292.275102) (xy 190.583294 -292.288794) (xy 190.627756 -292.309892)
			(xy 190.668259 -292.337848) (xy 190.703752 -292.37194) (xy 190.733317 -292.411284) (xy 190.756188 -292.454861)
			(xy 190.771772 -292.501542) (xy 190.779667 -292.550119) (xy 190.780162 -292.574726) (xy 191.119264 -292.574726)
			(xy 191.123224 -292.525672) (xy 191.135001 -292.477888) (xy 191.154292 -292.432612) (xy 191.180595 -292.391016)
			(xy 191.21323 -292.354179) (xy 191.251351 -292.323054) (xy 191.293972 -292.298447) (xy 191.339988 -292.280995)
			(xy 191.388207 -292.271151) (xy 191.437382 -292.26917) (xy 191.486237 -292.275102) (xy 191.533508 -292.288794)
			(xy 191.57797 -292.309892) (xy 191.618473 -292.337848) (xy 191.653966 -292.37194) (xy 191.683531 -292.411284)
			(xy 191.706402 -292.454861) (xy 191.721986 -292.501542) (xy 191.729881 -292.550119) (xy 191.730376 -292.574726)
			(xy 192.069224 -292.574726) (xy 192.073184 -292.525672) (xy 192.084961 -292.477888) (xy 192.104252 -292.432612)
			(xy 192.130555 -292.391016) (xy 192.16319 -292.354179) (xy 192.201311 -292.323054) (xy 192.243932 -292.298447)
			(xy 192.289948 -292.280995) (xy 192.338167 -292.271151) (xy 192.387342 -292.26917) (xy 192.436197 -292.275102)
			(xy 192.483468 -292.288794) (xy 192.52793 -292.309892) (xy 192.568433 -292.337848) (xy 192.603926 -292.37194)
			(xy 192.633491 -292.411284) (xy 192.656362 -292.454861) (xy 192.671946 -292.501542) (xy 192.679841 -292.550119)
			(xy 192.680336 -292.574726) (xy 193.019184 -292.574726) (xy 193.023144 -292.525672) (xy 193.034921 -292.477888)
			(xy 193.054212 -292.432612) (xy 193.080515 -292.391016) (xy 193.11315 -292.354179) (xy 193.151271 -292.323054)
			(xy 193.193892 -292.298447) (xy 193.239908 -292.280995) (xy 193.288127 -292.271151) (xy 193.337302 -292.26917)
			(xy 193.386157 -292.275102) (xy 193.433428 -292.288794) (xy 193.47789 -292.309892) (xy 193.518393 -292.337848)
			(xy 193.553886 -292.37194) (xy 193.583451 -292.411284) (xy 193.606322 -292.454861) (xy 193.621906 -292.501542)
			(xy 193.629801 -292.550119) (xy 193.630296 -292.574726) (xy 193.969144 -292.574726) (xy 193.973104 -292.525672)
			(xy 193.984881 -292.477888) (xy 194.004172 -292.432612) (xy 194.030475 -292.391016) (xy 194.06311 -292.354179)
			(xy 194.101231 -292.323054) (xy 194.143852 -292.298447) (xy 194.189868 -292.280995) (xy 194.238087 -292.271151)
			(xy 194.287262 -292.26917) (xy 194.336117 -292.275102) (xy 194.383388 -292.288794) (xy 194.42785 -292.309892)
			(xy 194.468353 -292.337848) (xy 194.503846 -292.37194) (xy 194.533411 -292.411284) (xy 194.556282 -292.454861)
			(xy 194.571866 -292.501542) (xy 194.579761 -292.550119) (xy 194.580256 -292.574726) (xy 194.919104 -292.574726)
			(xy 194.923064 -292.525672) (xy 194.934841 -292.477888) (xy 194.954132 -292.432612) (xy 194.980435 -292.391016)
			(xy 195.01307 -292.354179) (xy 195.051191 -292.323054) (xy 195.093812 -292.298447) (xy 195.139828 -292.280995)
			(xy 195.188047 -292.271151) (xy 195.237222 -292.26917) (xy 195.286077 -292.275102) (xy 195.333348 -292.288794)
			(xy 195.37781 -292.309892) (xy 195.418313 -292.337848) (xy 195.453806 -292.37194) (xy 195.483371 -292.411284)
			(xy 195.506242 -292.454861) (xy 195.521826 -292.501542) (xy 195.529721 -292.550119) (xy 195.530216 -292.574726)
			(xy 195.869064 -292.574726) (xy 195.873024 -292.525672) (xy 195.884801 -292.477888) (xy 195.904092 -292.432612)
			(xy 195.930395 -292.391016) (xy 195.96303 -292.354179) (xy 196.001151 -292.323054) (xy 196.043772 -292.298447)
			(xy 196.089788 -292.280995) (xy 196.138007 -292.271151) (xy 196.187182 -292.26917) (xy 196.236037 -292.275102)
			(xy 196.283308 -292.288794) (xy 196.32777 -292.309892) (xy 196.368273 -292.337848) (xy 196.403766 -292.37194)
			(xy 196.433331 -292.411284) (xy 196.456202 -292.454861) (xy 196.471786 -292.501542) (xy 196.479681 -292.550119)
			(xy 196.480176 -292.574726) (xy 196.819278 -292.574726) (xy 196.823238 -292.525672) (xy 196.835015 -292.477888)
			(xy 196.854306 -292.432612) (xy 196.880609 -292.391016) (xy 196.913244 -292.354179) (xy 196.951365 -292.323054)
			(xy 196.993986 -292.298447) (xy 197.040002 -292.280995) (xy 197.088221 -292.271151) (xy 197.137396 -292.26917)
			(xy 197.186251 -292.275102) (xy 197.233522 -292.288794) (xy 197.277984 -292.309892) (xy 197.318487 -292.337848)
			(xy 197.35398 -292.37194) (xy 197.383545 -292.411284) (xy 197.406416 -292.454861) (xy 197.422 -292.501542)
			(xy 197.429895 -292.550119) (xy 197.43039 -292.574726) (xy 197.430385 -292.57498) (xy 197.769238 -292.57498)
			(xy 197.773198 -292.525926) (xy 197.784975 -292.478142) (xy 197.804266 -292.432866) (xy 197.830569 -292.39127)
			(xy 197.863204 -292.354433) (xy 197.901325 -292.323308) (xy 197.943946 -292.298701) (xy 197.989962 -292.281249)
			(xy 198.038181 -292.271405) (xy 198.087356 -292.269424) (xy 198.136211 -292.275356) (xy 198.183482 -292.289048)
			(xy 198.227944 -292.310146) (xy 198.268447 -292.338102) (xy 198.30394 -292.372194) (xy 198.333505 -292.411538)
			(xy 198.356376 -292.455115) (xy 198.37196 -292.501796) (xy 198.379855 -292.550373) (xy 198.38035 -292.57498)
			(xy 198.719198 -292.57498) (xy 198.723158 -292.525926) (xy 198.734935 -292.478142) (xy 198.754226 -292.432866)
			(xy 198.780529 -292.39127) (xy 198.813164 -292.354433) (xy 198.851285 -292.323308) (xy 198.893906 -292.298701)
			(xy 198.939922 -292.281249) (xy 198.988141 -292.271405) (xy 199.037316 -292.269424) (xy 199.086171 -292.275356)
			(xy 199.133442 -292.289048) (xy 199.177904 -292.310146) (xy 199.218407 -292.338102) (xy 199.2539 -292.372194)
			(xy 199.283465 -292.411538) (xy 199.306336 -292.455115) (xy 199.32192 -292.501796) (xy 199.329815 -292.550373)
			(xy 199.33031 -292.57498) (xy 199.329815 -292.599587) (xy 199.32192 -292.648164) (xy 199.306336 -292.694845)
			(xy 199.283465 -292.738422) (xy 199.2539 -292.777766) (xy 199.218407 -292.811858) (xy 199.177904 -292.839814)
			(xy 199.133442 -292.860912) (xy 199.086171 -292.874604) (xy 199.037316 -292.880536) (xy 198.988141 -292.878555)
			(xy 198.939922 -292.868711) (xy 198.893906 -292.851259) (xy 198.851285 -292.826652) (xy 198.813164 -292.795527)
			(xy 198.780529 -292.75869) (xy 198.754226 -292.717094) (xy 198.734935 -292.671818) (xy 198.723158 -292.624034)
			(xy 198.719198 -292.57498) (xy 198.38035 -292.57498) (xy 198.379855 -292.599587) (xy 198.37196 -292.648164)
			(xy 198.356376 -292.694845) (xy 198.333505 -292.738422) (xy 198.30394 -292.777766) (xy 198.268447 -292.811858)
			(xy 198.227944 -292.839814) (xy 198.183482 -292.860912) (xy 198.136211 -292.874604) (xy 198.087356 -292.880536)
			(xy 198.038181 -292.878555) (xy 197.989962 -292.868711) (xy 197.943946 -292.851259) (xy 197.901325 -292.826652)
			(xy 197.863204 -292.795527) (xy 197.830569 -292.75869) (xy 197.804266 -292.717094) (xy 197.784975 -292.671818)
			(xy 197.773198 -292.624034) (xy 197.769238 -292.57498) (xy 197.430385 -292.57498) (xy 197.429895 -292.599333)
			(xy 197.422 -292.64791) (xy 197.406416 -292.694591) (xy 197.383545 -292.738168) (xy 197.35398 -292.777512)
			(xy 197.318487 -292.811604) (xy 197.277984 -292.83956) (xy 197.233522 -292.860658) (xy 197.186251 -292.87435)
			(xy 197.137396 -292.880282) (xy 197.088221 -292.878301) (xy 197.040002 -292.868457) (xy 196.993986 -292.851005)
			(xy 196.951365 -292.826398) (xy 196.913244 -292.795273) (xy 196.880609 -292.758436) (xy 196.854306 -292.71684)
			(xy 196.835015 -292.671564) (xy 196.823238 -292.62378) (xy 196.819278 -292.574726) (xy 196.480176 -292.574726)
			(xy 196.479681 -292.599333) (xy 196.471786 -292.64791) (xy 196.456202 -292.694591) (xy 196.433331 -292.738168)
			(xy 196.403766 -292.777512) (xy 196.368273 -292.811604) (xy 196.32777 -292.83956) (xy 196.283308 -292.860658)
			(xy 196.236037 -292.87435) (xy 196.187182 -292.880282) (xy 196.138007 -292.878301) (xy 196.089788 -292.868457)
			(xy 196.043772 -292.851005) (xy 196.001151 -292.826398) (xy 195.96303 -292.795273) (xy 195.930395 -292.758436)
			(xy 195.904092 -292.71684) (xy 195.884801 -292.671564) (xy 195.873024 -292.62378) (xy 195.869064 -292.574726)
			(xy 195.530216 -292.574726) (xy 195.529721 -292.599333) (xy 195.521826 -292.64791) (xy 195.506242 -292.694591)
			(xy 195.483371 -292.738168) (xy 195.453806 -292.777512) (xy 195.418313 -292.811604) (xy 195.37781 -292.83956)
			(xy 195.333348 -292.860658) (xy 195.286077 -292.87435) (xy 195.237222 -292.880282) (xy 195.188047 -292.878301)
			(xy 195.139828 -292.868457) (xy 195.093812 -292.851005) (xy 195.051191 -292.826398) (xy 195.01307 -292.795273)
			(xy 194.980435 -292.758436) (xy 194.954132 -292.71684) (xy 194.934841 -292.671564) (xy 194.923064 -292.62378)
			(xy 194.919104 -292.574726) (xy 194.580256 -292.574726) (xy 194.579761 -292.599333) (xy 194.571866 -292.64791)
			(xy 194.556282 -292.694591) (xy 194.533411 -292.738168) (xy 194.503846 -292.777512) (xy 194.468353 -292.811604)
			(xy 194.42785 -292.83956) (xy 194.383388 -292.860658) (xy 194.336117 -292.87435) (xy 194.287262 -292.880282)
			(xy 194.238087 -292.878301) (xy 194.189868 -292.868457) (xy 194.143852 -292.851005) (xy 194.101231 -292.826398)
			(xy 194.06311 -292.795273) (xy 194.030475 -292.758436) (xy 194.004172 -292.71684) (xy 193.984881 -292.671564)
			(xy 193.973104 -292.62378) (xy 193.969144 -292.574726) (xy 193.630296 -292.574726) (xy 193.629801 -292.599333)
			(xy 193.621906 -292.64791) (xy 193.606322 -292.694591) (xy 193.583451 -292.738168) (xy 193.553886 -292.777512)
			(xy 193.518393 -292.811604) (xy 193.47789 -292.83956) (xy 193.433428 -292.860658) (xy 193.386157 -292.87435)
			(xy 193.337302 -292.880282) (xy 193.288127 -292.878301) (xy 193.239908 -292.868457) (xy 193.193892 -292.851005)
			(xy 193.151271 -292.826398) (xy 193.11315 -292.795273) (xy 193.080515 -292.758436) (xy 193.054212 -292.71684)
			(xy 193.034921 -292.671564) (xy 193.023144 -292.62378) (xy 193.019184 -292.574726) (xy 192.680336 -292.574726)
			(xy 192.679841 -292.599333) (xy 192.671946 -292.64791) (xy 192.656362 -292.694591) (xy 192.633491 -292.738168)
			(xy 192.603926 -292.777512) (xy 192.568433 -292.811604) (xy 192.52793 -292.83956) (xy 192.483468 -292.860658)
			(xy 192.436197 -292.87435) (xy 192.387342 -292.880282) (xy 192.338167 -292.878301) (xy 192.289948 -292.868457)
			(xy 192.243932 -292.851005) (xy 192.201311 -292.826398) (xy 192.16319 -292.795273) (xy 192.130555 -292.758436)
			(xy 192.104252 -292.71684) (xy 192.084961 -292.671564) (xy 192.073184 -292.62378) (xy 192.069224 -292.574726)
			(xy 191.730376 -292.574726) (xy 191.729881 -292.599333) (xy 191.721986 -292.64791) (xy 191.706402 -292.694591)
			(xy 191.683531 -292.738168) (xy 191.653966 -292.777512) (xy 191.618473 -292.811604) (xy 191.57797 -292.83956)
			(xy 191.533508 -292.860658) (xy 191.486237 -292.87435) (xy 191.437382 -292.880282) (xy 191.388207 -292.878301)
			(xy 191.339988 -292.868457) (xy 191.293972 -292.851005) (xy 191.251351 -292.826398) (xy 191.21323 -292.795273)
			(xy 191.180595 -292.758436) (xy 191.154292 -292.71684) (xy 191.135001 -292.671564) (xy 191.123224 -292.62378)
			(xy 191.119264 -292.574726) (xy 190.780162 -292.574726) (xy 190.779667 -292.599333) (xy 190.771772 -292.64791)
			(xy 190.756188 -292.694591) (xy 190.733317 -292.738168) (xy 190.703752 -292.777512) (xy 190.668259 -292.811604)
			(xy 190.627756 -292.83956) (xy 190.583294 -292.860658) (xy 190.536023 -292.87435) (xy 190.487168 -292.880282)
			(xy 190.437993 -292.878301) (xy 190.389774 -292.868457) (xy 190.343758 -292.851005) (xy 190.301137 -292.826398)
			(xy 190.263016 -292.795273) (xy 190.230381 -292.758436) (xy 190.204078 -292.71684) (xy 190.184787 -292.671564)
			(xy 190.17301 -292.62378) (xy 190.16905 -292.574726) (xy 189.830202 -292.574726) (xy 189.829707 -292.599333)
			(xy 189.821812 -292.64791) (xy 189.806228 -292.694591) (xy 189.783357 -292.738168) (xy 189.753792 -292.777512)
			(xy 189.718299 -292.811604) (xy 189.677796 -292.83956) (xy 189.633334 -292.860658) (xy 189.586063 -292.87435)
			(xy 189.537208 -292.880282) (xy 189.488033 -292.878301) (xy 189.439814 -292.868457) (xy 189.393798 -292.851005)
			(xy 189.351177 -292.826398) (xy 189.313056 -292.795273) (xy 189.280421 -292.758436) (xy 189.254118 -292.71684)
			(xy 189.234827 -292.671564) (xy 189.22305 -292.62378) (xy 189.21909 -292.574726) (xy 188.880242 -292.574726)
			(xy 188.879747 -292.599333) (xy 188.871852 -292.64791) (xy 188.856268 -292.694591) (xy 188.833397 -292.738168)
			(xy 188.803832 -292.777512) (xy 188.768339 -292.811604) (xy 188.727836 -292.83956) (xy 188.683374 -292.860658)
			(xy 188.636103 -292.87435) (xy 188.587248 -292.880282) (xy 188.538073 -292.878301) (xy 188.489854 -292.868457)
			(xy 188.443838 -292.851005) (xy 188.401217 -292.826398) (xy 188.363096 -292.795273) (xy 188.330461 -292.758436)
			(xy 188.304158 -292.71684) (xy 188.284867 -292.671564) (xy 188.27309 -292.62378) (xy 188.26913 -292.574726)
			(xy 187.930282 -292.574726) (xy 187.929787 -292.599333) (xy 187.921892 -292.64791) (xy 187.906308 -292.694591)
			(xy 187.883437 -292.738168) (xy 187.853872 -292.777512) (xy 187.818379 -292.811604) (xy 187.777876 -292.83956)
			(xy 187.733414 -292.860658) (xy 187.686143 -292.87435) (xy 187.637288 -292.880282) (xy 187.588113 -292.878301)
			(xy 187.539894 -292.868457) (xy 187.493878 -292.851005) (xy 187.451257 -292.826398) (xy 187.413136 -292.795273)
			(xy 187.380501 -292.758436) (xy 187.354198 -292.71684) (xy 187.334907 -292.671564) (xy 187.32313 -292.62378)
			(xy 187.31917 -292.574726) (xy 186.980317 -292.574726) (xy 186.980322 -292.57498) (xy 186.979827 -292.599587)
			(xy 186.971932 -292.648164) (xy 186.956348 -292.694845) (xy 186.933477 -292.738422) (xy 186.903912 -292.777766)
			(xy 186.868419 -292.811858) (xy 186.827916 -292.839814) (xy 186.783454 -292.860912) (xy 186.736183 -292.874604)
			(xy 186.687328 -292.880536) (xy 186.638153 -292.878555) (xy 186.589934 -292.868711) (xy 186.543918 -292.851259)
			(xy 186.501297 -292.826652) (xy 186.463176 -292.795527) (xy 186.430541 -292.75869) (xy 186.404238 -292.717094)
			(xy 186.384947 -292.671818) (xy 186.37317 -292.624034) (xy 186.36921 -292.57498) (xy 186.031675 -292.57498)
			(xy 186.027515 -292.625169) (xy 186.015082 -292.674261) (xy 185.994738 -292.720637) (xy 185.967037 -292.763031)
			(xy 185.932735 -292.800288) (xy 185.892769 -292.831389) (xy 185.848228 -292.855487) (xy 185.800328 -292.871925)
			(xy 185.750375 -292.880254) (xy 185.725054 -292.880796) (xy 185.724546 -292.880796) (xy 185.697216 -292.880196)
			(xy 185.643426 -292.870486) (xy 185.617612 -292.861492) (xy 185.611863 -292.859513) (xy 185.599788 -292.858108)
			(xy 185.593736 -292.858698) (xy 185.58129 -292.860222) (xy 185.523632 -292.899846) (xy 185.523124 -292.899846)
			(xy 185.50255 -292.914324) (xy 185.492873 -292.921933) (xy 185.481447 -292.943694) (xy 185.480706 -292.95598)
			(xy 185.480706 -293.143686) (xy 185.481289 -293.156018) (xy 185.492729 -293.177864) (xy 185.50255 -293.185342)
			(xy 185.523378 -293.19982) (xy 185.57113 -293.232586) (xy 185.581625 -293.238913) (xy 185.605916 -293.241831)
			(xy 185.617612 -293.238174) (xy 185.643429 -293.229188) (xy 185.697217 -293.219473) (xy 185.724546 -293.21887)
			(xy 185.725054 -293.21887) (xy 185.750374 -293.219361) (xy 185.800324 -293.227689) (xy 185.848222 -293.244126)
			(xy 185.892761 -293.268223) (xy 185.932725 -293.299323) (xy 185.967025 -293.336578) (xy 185.994725 -293.37897)
			(xy 186.015068 -293.425343) (xy 186.027501 -293.474433) (xy 186.031683 -293.5249) (xy 186.03168 -293.52494)
			(xy 187.31917 -293.52494) (xy 187.32313 -293.475886) (xy 187.334907 -293.428102) (xy 187.354198 -293.382826)
			(xy 187.380501 -293.34123) (xy 187.413136 -293.304393) (xy 187.451257 -293.273268) (xy 187.493878 -293.248661)
			(xy 187.539894 -293.231209) (xy 187.588113 -293.221365) (xy 187.637288 -293.219384) (xy 187.686143 -293.225316)
			(xy 187.733414 -293.239008) (xy 187.777876 -293.260106) (xy 187.818379 -293.288062) (xy 187.853872 -293.322154)
			(xy 187.883437 -293.361498) (xy 187.906308 -293.405075) (xy 187.921892 -293.451756) (xy 187.929787 -293.500333)
			(xy 187.930282 -293.52494) (xy 188.26913 -293.52494) (xy 188.27309 -293.475886) (xy 188.284867 -293.428102)
			(xy 188.304158 -293.382826) (xy 188.330461 -293.34123) (xy 188.363096 -293.304393) (xy 188.401217 -293.273268)
			(xy 188.443838 -293.248661) (xy 188.489854 -293.231209) (xy 188.538073 -293.221365) (xy 188.587248 -293.219384)
			(xy 188.636103 -293.225316) (xy 188.683374 -293.239008) (xy 188.727836 -293.260106) (xy 188.768339 -293.288062)
			(xy 188.803832 -293.322154) (xy 188.833397 -293.361498) (xy 188.856268 -293.405075) (xy 188.871852 -293.451756)
			(xy 188.879747 -293.500333) (xy 188.880242 -293.52494) (xy 189.21909 -293.52494) (xy 189.22305 -293.475886)
			(xy 189.234827 -293.428102) (xy 189.254118 -293.382826) (xy 189.280421 -293.34123) (xy 189.313056 -293.304393)
			(xy 189.351177 -293.273268) (xy 189.393798 -293.248661) (xy 189.439814 -293.231209) (xy 189.488033 -293.221365)
			(xy 189.537208 -293.219384) (xy 189.586063 -293.225316) (xy 189.633334 -293.239008) (xy 189.677796 -293.260106)
			(xy 189.718299 -293.288062) (xy 189.753792 -293.322154) (xy 189.783357 -293.361498) (xy 189.806228 -293.405075)
			(xy 189.821812 -293.451756) (xy 189.829707 -293.500333) (xy 189.830202 -293.52494) (xy 190.169304 -293.52494)
			(xy 190.173264 -293.475886) (xy 190.185041 -293.428102) (xy 190.204332 -293.382826) (xy 190.230635 -293.34123)
			(xy 190.26327 -293.304393) (xy 190.301391 -293.273268) (xy 190.344012 -293.248661) (xy 190.390028 -293.231209)
			(xy 190.438247 -293.221365) (xy 190.487422 -293.219384) (xy 190.536277 -293.225316) (xy 190.583548 -293.239008)
			(xy 190.62801 -293.260106) (xy 190.668513 -293.288062) (xy 190.704006 -293.322154) (xy 190.733571 -293.361498)
			(xy 190.756442 -293.405075) (xy 190.772026 -293.451756) (xy 190.779921 -293.500333) (xy 190.780416 -293.52494)
			(xy 191.119264 -293.52494) (xy 191.123224 -293.475886) (xy 191.135001 -293.428102) (xy 191.154292 -293.382826)
			(xy 191.180595 -293.34123) (xy 191.21323 -293.304393) (xy 191.251351 -293.273268) (xy 191.293972 -293.248661)
			(xy 191.339988 -293.231209) (xy 191.388207 -293.221365) (xy 191.437382 -293.219384) (xy 191.486237 -293.225316)
			(xy 191.533508 -293.239008) (xy 191.57797 -293.260106) (xy 191.618473 -293.288062) (xy 191.653966 -293.322154)
			(xy 191.683531 -293.361498) (xy 191.706402 -293.405075) (xy 191.721986 -293.451756) (xy 191.729881 -293.500333)
			(xy 191.730376 -293.52494) (xy 192.069224 -293.52494) (xy 192.073184 -293.475886) (xy 192.084961 -293.428102)
			(xy 192.104252 -293.382826) (xy 192.130555 -293.34123) (xy 192.16319 -293.304393) (xy 192.201311 -293.273268)
			(xy 192.243932 -293.248661) (xy 192.289948 -293.231209) (xy 192.338167 -293.221365) (xy 192.387342 -293.219384)
			(xy 192.436197 -293.225316) (xy 192.483468 -293.239008) (xy 192.52793 -293.260106) (xy 192.568433 -293.288062)
			(xy 192.603926 -293.322154) (xy 192.633491 -293.361498) (xy 192.656362 -293.405075) (xy 192.671946 -293.451756)
			(xy 192.679841 -293.500333) (xy 192.680336 -293.52494) (xy 193.019184 -293.52494) (xy 193.023144 -293.475886)
			(xy 193.034921 -293.428102) (xy 193.054212 -293.382826) (xy 193.080515 -293.34123) (xy 193.11315 -293.304393)
			(xy 193.151271 -293.273268) (xy 193.193892 -293.248661) (xy 193.239908 -293.231209) (xy 193.288127 -293.221365)
			(xy 193.337302 -293.219384) (xy 193.386157 -293.225316) (xy 193.433428 -293.239008) (xy 193.47789 -293.260106)
			(xy 193.518393 -293.288062) (xy 193.553886 -293.322154) (xy 193.583451 -293.361498) (xy 193.606322 -293.405075)
			(xy 193.621906 -293.451756) (xy 193.629801 -293.500333) (xy 193.630296 -293.52494) (xy 193.969144 -293.52494)
			(xy 193.973104 -293.475886) (xy 193.984881 -293.428102) (xy 194.004172 -293.382826) (xy 194.030475 -293.34123)
			(xy 194.06311 -293.304393) (xy 194.101231 -293.273268) (xy 194.143852 -293.248661) (xy 194.189868 -293.231209)
			(xy 194.238087 -293.221365) (xy 194.287262 -293.219384) (xy 194.336117 -293.225316) (xy 194.383388 -293.239008)
			(xy 194.42785 -293.260106) (xy 194.468353 -293.288062) (xy 194.503846 -293.322154) (xy 194.533411 -293.361498)
			(xy 194.556282 -293.405075) (xy 194.571866 -293.451756) (xy 194.579761 -293.500333) (xy 194.580256 -293.52494)
			(xy 194.919104 -293.52494) (xy 194.923064 -293.475886) (xy 194.934841 -293.428102) (xy 194.954132 -293.382826)
			(xy 194.980435 -293.34123) (xy 195.01307 -293.304393) (xy 195.051191 -293.273268) (xy 195.093812 -293.248661)
			(xy 195.139828 -293.231209) (xy 195.188047 -293.221365) (xy 195.237222 -293.219384) (xy 195.286077 -293.225316)
			(xy 195.333348 -293.239008) (xy 195.37781 -293.260106) (xy 195.418313 -293.288062) (xy 195.453806 -293.322154)
			(xy 195.483371 -293.361498) (xy 195.506242 -293.405075) (xy 195.521826 -293.451756) (xy 195.529721 -293.500333)
			(xy 195.530216 -293.52494) (xy 195.869064 -293.52494) (xy 195.873024 -293.475886) (xy 195.884801 -293.428102)
			(xy 195.904092 -293.382826) (xy 195.930395 -293.34123) (xy 195.96303 -293.304393) (xy 196.001151 -293.273268)
			(xy 196.043772 -293.248661) (xy 196.089788 -293.231209) (xy 196.138007 -293.221365) (xy 196.187182 -293.219384)
			(xy 196.236037 -293.225316) (xy 196.283308 -293.239008) (xy 196.32777 -293.260106) (xy 196.368273 -293.288062)
			(xy 196.403766 -293.322154) (xy 196.433331 -293.361498) (xy 196.456202 -293.405075) (xy 196.471786 -293.451756)
			(xy 196.479681 -293.500333) (xy 196.480176 -293.52494) (xy 196.819278 -293.52494) (xy 196.823238 -293.475886)
			(xy 196.835015 -293.428102) (xy 196.854306 -293.382826) (xy 196.880609 -293.34123) (xy 196.913244 -293.304393)
			(xy 196.951365 -293.273268) (xy 196.993986 -293.248661) (xy 197.040002 -293.231209) (xy 197.088221 -293.221365)
			(xy 197.137396 -293.219384) (xy 197.186251 -293.225316) (xy 197.233522 -293.239008) (xy 197.277984 -293.260106)
			(xy 197.318487 -293.288062) (xy 197.35398 -293.322154) (xy 197.383545 -293.361498) (xy 197.406416 -293.405075)
			(xy 197.422 -293.451756) (xy 197.429895 -293.500333) (xy 197.43039 -293.52494) (xy 197.769238 -293.52494)
			(xy 197.773198 -293.475886) (xy 197.784975 -293.428102) (xy 197.804266 -293.382826) (xy 197.830569 -293.34123)
			(xy 197.863204 -293.304393) (xy 197.901325 -293.273268) (xy 197.943946 -293.248661) (xy 197.989962 -293.231209)
			(xy 198.038181 -293.221365) (xy 198.087356 -293.219384) (xy 198.136211 -293.225316) (xy 198.183482 -293.239008)
			(xy 198.227944 -293.260106) (xy 198.268447 -293.288062) (xy 198.30394 -293.322154) (xy 198.333505 -293.361498)
			(xy 198.356376 -293.405075) (xy 198.37196 -293.451756) (xy 198.379855 -293.500333) (xy 198.38035 -293.52494)
			(xy 198.719198 -293.52494) (xy 198.723158 -293.475886) (xy 198.734935 -293.428102) (xy 198.754226 -293.382826)
			(xy 198.780529 -293.34123) (xy 198.813164 -293.304393) (xy 198.851285 -293.273268) (xy 198.893906 -293.248661)
			(xy 198.939922 -293.231209) (xy 198.988141 -293.221365) (xy 199.037316 -293.219384) (xy 199.086171 -293.225316)
			(xy 199.133442 -293.239008) (xy 199.177904 -293.260106) (xy 199.218407 -293.288062) (xy 199.2539 -293.322154)
			(xy 199.283465 -293.361498) (xy 199.306336 -293.405075) (xy 199.32192 -293.451756) (xy 199.329815 -293.500333)
			(xy 199.33031 -293.52494) (xy 199.329815 -293.549547) (xy 199.32192 -293.598124) (xy 199.306336 -293.644805)
			(xy 199.283465 -293.688382) (xy 199.2539 -293.727726) (xy 199.218407 -293.761818) (xy 199.177904 -293.789774)
			(xy 199.133442 -293.810872) (xy 199.086171 -293.824564) (xy 199.037316 -293.830496) (xy 198.988141 -293.828515)
			(xy 198.939922 -293.818671) (xy 198.893906 -293.801219) (xy 198.851285 -293.776612) (xy 198.813164 -293.745487)
			(xy 198.780529 -293.70865) (xy 198.754226 -293.667054) (xy 198.734935 -293.621778) (xy 198.723158 -293.573994)
			(xy 198.719198 -293.52494) (xy 198.38035 -293.52494) (xy 198.379855 -293.549547) (xy 198.37196 -293.598124)
			(xy 198.356376 -293.644805) (xy 198.333505 -293.688382) (xy 198.30394 -293.727726) (xy 198.268447 -293.761818)
			(xy 198.227944 -293.789774) (xy 198.183482 -293.810872) (xy 198.136211 -293.824564) (xy 198.087356 -293.830496)
			(xy 198.038181 -293.828515) (xy 197.989962 -293.818671) (xy 197.943946 -293.801219) (xy 197.901325 -293.776612)
			(xy 197.863204 -293.745487) (xy 197.830569 -293.70865) (xy 197.804266 -293.667054) (xy 197.784975 -293.621778)
			(xy 197.773198 -293.573994) (xy 197.769238 -293.52494) (xy 197.43039 -293.52494) (xy 197.429895 -293.549547)
			(xy 197.422 -293.598124) (xy 197.406416 -293.644805) (xy 197.383545 -293.688382) (xy 197.35398 -293.727726)
			(xy 197.318487 -293.761818) (xy 197.277984 -293.789774) (xy 197.233522 -293.810872) (xy 197.186251 -293.824564)
			(xy 197.137396 -293.830496) (xy 197.088221 -293.828515) (xy 197.040002 -293.818671) (xy 196.993986 -293.801219)
			(xy 196.951365 -293.776612) (xy 196.913244 -293.745487) (xy 196.880609 -293.70865) (xy 196.854306 -293.667054)
			(xy 196.835015 -293.621778) (xy 196.823238 -293.573994) (xy 196.819278 -293.52494) (xy 196.480176 -293.52494)
			(xy 196.479681 -293.549547) (xy 196.471786 -293.598124) (xy 196.456202 -293.644805) (xy 196.433331 -293.688382)
			(xy 196.403766 -293.727726) (xy 196.368273 -293.761818) (xy 196.32777 -293.789774) (xy 196.283308 -293.810872)
			(xy 196.236037 -293.824564) (xy 196.187182 -293.830496) (xy 196.138007 -293.828515) (xy 196.089788 -293.818671)
			(xy 196.043772 -293.801219) (xy 196.001151 -293.776612) (xy 195.96303 -293.745487) (xy 195.930395 -293.70865)
			(xy 195.904092 -293.667054) (xy 195.884801 -293.621778) (xy 195.873024 -293.573994) (xy 195.869064 -293.52494)
			(xy 195.530216 -293.52494) (xy 195.529721 -293.549547) (xy 195.521826 -293.598124) (xy 195.506242 -293.644805)
			(xy 195.483371 -293.688382) (xy 195.453806 -293.727726) (xy 195.418313 -293.761818) (xy 195.37781 -293.789774)
			(xy 195.333348 -293.810872) (xy 195.286077 -293.824564) (xy 195.237222 -293.830496) (xy 195.188047 -293.828515)
			(xy 195.139828 -293.818671) (xy 195.093812 -293.801219) (xy 195.051191 -293.776612) (xy 195.01307 -293.745487)
			(xy 194.980435 -293.70865) (xy 194.954132 -293.667054) (xy 194.934841 -293.621778) (xy 194.923064 -293.573994)
			(xy 194.919104 -293.52494) (xy 194.580256 -293.52494) (xy 194.579761 -293.549547) (xy 194.571866 -293.598124)
			(xy 194.556282 -293.644805) (xy 194.533411 -293.688382) (xy 194.503846 -293.727726) (xy 194.468353 -293.761818)
			(xy 194.42785 -293.789774) (xy 194.383388 -293.810872) (xy 194.336117 -293.824564) (xy 194.287262 -293.830496)
			(xy 194.238087 -293.828515) (xy 194.189868 -293.818671) (xy 194.143852 -293.801219) (xy 194.101231 -293.776612)
			(xy 194.06311 -293.745487) (xy 194.030475 -293.70865) (xy 194.004172 -293.667054) (xy 193.984881 -293.621778)
			(xy 193.973104 -293.573994) (xy 193.969144 -293.52494) (xy 193.630296 -293.52494) (xy 193.629801 -293.549547)
			(xy 193.621906 -293.598124) (xy 193.606322 -293.644805) (xy 193.583451 -293.688382) (xy 193.553886 -293.727726)
			(xy 193.518393 -293.761818) (xy 193.47789 -293.789774) (xy 193.433428 -293.810872) (xy 193.386157 -293.824564)
			(xy 193.337302 -293.830496) (xy 193.288127 -293.828515) (xy 193.239908 -293.818671) (xy 193.193892 -293.801219)
			(xy 193.151271 -293.776612) (xy 193.11315 -293.745487) (xy 193.080515 -293.70865) (xy 193.054212 -293.667054)
			(xy 193.034921 -293.621778) (xy 193.023144 -293.573994) (xy 193.019184 -293.52494) (xy 192.680336 -293.52494)
			(xy 192.679841 -293.549547) (xy 192.671946 -293.598124) (xy 192.656362 -293.644805) (xy 192.633491 -293.688382)
			(xy 192.603926 -293.727726) (xy 192.568433 -293.761818) (xy 192.52793 -293.789774) (xy 192.483468 -293.810872)
			(xy 192.436197 -293.824564) (xy 192.387342 -293.830496) (xy 192.338167 -293.828515) (xy 192.289948 -293.818671)
			(xy 192.243932 -293.801219) (xy 192.201311 -293.776612) (xy 192.16319 -293.745487) (xy 192.130555 -293.70865)
			(xy 192.104252 -293.667054) (xy 192.084961 -293.621778) (xy 192.073184 -293.573994) (xy 192.069224 -293.52494)
			(xy 191.730376 -293.52494) (xy 191.729881 -293.549547) (xy 191.721986 -293.598124) (xy 191.706402 -293.644805)
			(xy 191.683531 -293.688382) (xy 191.653966 -293.727726) (xy 191.618473 -293.761818) (xy 191.57797 -293.789774)
			(xy 191.533508 -293.810872) (xy 191.486237 -293.824564) (xy 191.437382 -293.830496) (xy 191.388207 -293.828515)
			(xy 191.339988 -293.818671) (xy 191.293972 -293.801219) (xy 191.251351 -293.776612) (xy 191.21323 -293.745487)
			(xy 191.180595 -293.70865) (xy 191.154292 -293.667054) (xy 191.135001 -293.621778) (xy 191.123224 -293.573994)
			(xy 191.119264 -293.52494) (xy 190.780416 -293.52494) (xy 190.779921 -293.549547) (xy 190.772026 -293.598124)
			(xy 190.756442 -293.644805) (xy 190.733571 -293.688382) (xy 190.704006 -293.727726) (xy 190.668513 -293.761818)
			(xy 190.62801 -293.789774) (xy 190.583548 -293.810872) (xy 190.536277 -293.824564) (xy 190.487422 -293.830496)
			(xy 190.438247 -293.828515) (xy 190.390028 -293.818671) (xy 190.344012 -293.801219) (xy 190.301391 -293.776612)
			(xy 190.26327 -293.745487) (xy 190.230635 -293.70865) (xy 190.204332 -293.667054) (xy 190.185041 -293.621778)
			(xy 190.173264 -293.573994) (xy 190.169304 -293.52494) (xy 189.830202 -293.52494) (xy 189.829707 -293.549547)
			(xy 189.821812 -293.598124) (xy 189.806228 -293.644805) (xy 189.783357 -293.688382) (xy 189.753792 -293.727726)
			(xy 189.718299 -293.761818) (xy 189.677796 -293.789774) (xy 189.633334 -293.810872) (xy 189.586063 -293.824564)
			(xy 189.537208 -293.830496) (xy 189.488033 -293.828515) (xy 189.439814 -293.818671) (xy 189.393798 -293.801219)
			(xy 189.351177 -293.776612) (xy 189.313056 -293.745487) (xy 189.280421 -293.70865) (xy 189.254118 -293.667054)
			(xy 189.234827 -293.621778) (xy 189.22305 -293.573994) (xy 189.21909 -293.52494) (xy 188.880242 -293.52494)
			(xy 188.879747 -293.549547) (xy 188.871852 -293.598124) (xy 188.856268 -293.644805) (xy 188.833397 -293.688382)
			(xy 188.803832 -293.727726) (xy 188.768339 -293.761818) (xy 188.727836 -293.789774) (xy 188.683374 -293.810872)
			(xy 188.636103 -293.824564) (xy 188.587248 -293.830496) (xy 188.538073 -293.828515) (xy 188.489854 -293.818671)
			(xy 188.443838 -293.801219) (xy 188.401217 -293.776612) (xy 188.363096 -293.745487) (xy 188.330461 -293.70865)
			(xy 188.304158 -293.667054) (xy 188.284867 -293.621778) (xy 188.27309 -293.573994) (xy 188.26913 -293.52494)
			(xy 187.930282 -293.52494) (xy 187.929787 -293.549547) (xy 187.921892 -293.598124) (xy 187.906308 -293.644805)
			(xy 187.883437 -293.688382) (xy 187.853872 -293.727726) (xy 187.818379 -293.761818) (xy 187.777876 -293.789774)
			(xy 187.733414 -293.810872) (xy 187.686143 -293.824564) (xy 187.637288 -293.830496) (xy 187.588113 -293.828515)
			(xy 187.539894 -293.818671) (xy 187.493878 -293.801219) (xy 187.451257 -293.776612) (xy 187.413136 -293.745487)
			(xy 187.380501 -293.70865) (xy 187.354198 -293.667054) (xy 187.334907 -293.621778) (xy 187.32313 -293.573994)
			(xy 187.31917 -293.52494) (xy 186.03168 -293.52494) (xy 186.027501 -293.575367) (xy 186.015068 -293.624457)
			(xy 185.994725 -293.67083) (xy 185.967025 -293.713222) (xy 185.932725 -293.750477) (xy 185.892761 -293.781577)
			(xy 185.848222 -293.805674) (xy 185.800324 -293.822111) (xy 185.750374 -293.830439) (xy 185.725054 -293.83101)
			(xy 185.724546 -293.83101) (xy 185.697216 -293.83041) (xy 185.643426 -293.8207) (xy 185.617612 -293.811706)
			(xy 185.611862 -293.80973) (xy 185.599788 -293.808327) (xy 185.593736 -293.808912) (xy 185.58129 -293.810436)
			(xy 185.523632 -293.85006) (xy 185.523124 -293.85006) (xy 185.50255 -293.864538) (xy 185.492875 -293.872147)
			(xy 185.481455 -293.893909) (xy 185.480706 -293.906194) (xy 185.480706 -294.093646) (xy 185.481302 -294.10597)
			(xy 185.492756 -294.127795) (xy 185.50255 -294.135302) (xy 185.523378 -294.14978) (xy 185.57113 -294.182546)
			(xy 185.581624 -294.188877) (xy 185.605917 -294.191797) (xy 185.617612 -294.188134) (xy 185.643429 -294.179149)
			(xy 185.697217 -294.169435) (xy 185.724546 -294.16883) (xy 185.725054 -294.16883) (xy 185.750377 -294.16932)
			(xy 185.800334 -294.17765) (xy 185.848238 -294.194089) (xy 185.892783 -294.218189) (xy 185.932753 -294.249293)
			(xy 185.967057 -294.286553) (xy 185.99476 -294.328951) (xy 186.015107 -294.37533) (xy 186.027541 -294.424427)
			(xy 186.031724 -294.4749) (xy 187.31917 -294.4749) (xy 187.32313 -294.425846) (xy 187.334907 -294.378062)
			(xy 187.354198 -294.332786) (xy 187.380501 -294.29119) (xy 187.413136 -294.254353) (xy 187.451257 -294.223228)
			(xy 187.493878 -294.198621) (xy 187.539894 -294.181169) (xy 187.588113 -294.171325) (xy 187.637288 -294.169344)
			(xy 187.686143 -294.175276) (xy 187.733414 -294.188968) (xy 187.777876 -294.210066) (xy 187.818379 -294.238022)
			(xy 187.853872 -294.272114) (xy 187.883437 -294.311458) (xy 187.906308 -294.355035) (xy 187.921892 -294.401716)
			(xy 187.929787 -294.450293) (xy 187.930282 -294.4749) (xy 188.26913 -294.4749) (xy 188.27309 -294.425846)
			(xy 188.284867 -294.378062) (xy 188.304158 -294.332786) (xy 188.330461 -294.29119) (xy 188.363096 -294.254353)
			(xy 188.401217 -294.223228) (xy 188.443838 -294.198621) (xy 188.489854 -294.181169) (xy 188.538073 -294.171325)
			(xy 188.587248 -294.169344) (xy 188.636103 -294.175276) (xy 188.683374 -294.188968) (xy 188.727836 -294.210066)
			(xy 188.768339 -294.238022) (xy 188.803832 -294.272114) (xy 188.833397 -294.311458) (xy 188.856268 -294.355035)
			(xy 188.871852 -294.401716) (xy 188.879747 -294.450293) (xy 188.880242 -294.4749) (xy 189.21909 -294.4749)
			(xy 189.22305 -294.425846) (xy 189.234827 -294.378062) (xy 189.254118 -294.332786) (xy 189.280421 -294.29119)
			(xy 189.313056 -294.254353) (xy 189.351177 -294.223228) (xy 189.393798 -294.198621) (xy 189.439814 -294.181169)
			(xy 189.488033 -294.171325) (xy 189.537208 -294.169344) (xy 189.586063 -294.175276) (xy 189.633334 -294.188968)
			(xy 189.677796 -294.210066) (xy 189.718299 -294.238022) (xy 189.753792 -294.272114) (xy 189.783357 -294.311458)
			(xy 189.806228 -294.355035) (xy 189.821812 -294.401716) (xy 189.829707 -294.450293) (xy 189.830202 -294.4749)
			(xy 190.16905 -294.4749) (xy 190.17301 -294.425846) (xy 190.184787 -294.378062) (xy 190.204078 -294.332786)
			(xy 190.230381 -294.29119) (xy 190.263016 -294.254353) (xy 190.301137 -294.223228) (xy 190.343758 -294.198621)
			(xy 190.389774 -294.181169) (xy 190.437993 -294.171325) (xy 190.487168 -294.169344) (xy 190.536023 -294.175276)
			(xy 190.583294 -294.188968) (xy 190.627756 -294.210066) (xy 190.668259 -294.238022) (xy 190.703752 -294.272114)
			(xy 190.733317 -294.311458) (xy 190.756188 -294.355035) (xy 190.771772 -294.401716) (xy 190.779667 -294.450293)
			(xy 190.780162 -294.4749) (xy 191.119264 -294.4749) (xy 191.123224 -294.425846) (xy 191.135001 -294.378062)
			(xy 191.154292 -294.332786) (xy 191.180595 -294.29119) (xy 191.21323 -294.254353) (xy 191.251351 -294.223228)
			(xy 191.293972 -294.198621) (xy 191.339988 -294.181169) (xy 191.388207 -294.171325) (xy 191.437382 -294.169344)
			(xy 191.486237 -294.175276) (xy 191.533508 -294.188968) (xy 191.57797 -294.210066) (xy 191.618473 -294.238022)
			(xy 191.653966 -294.272114) (xy 191.683531 -294.311458) (xy 191.706402 -294.355035) (xy 191.721986 -294.401716)
			(xy 191.729881 -294.450293) (xy 191.730376 -294.4749) (xy 192.069224 -294.4749) (xy 192.073184 -294.425846)
			(xy 192.084961 -294.378062) (xy 192.104252 -294.332786) (xy 192.130555 -294.29119) (xy 192.16319 -294.254353)
			(xy 192.201311 -294.223228) (xy 192.243932 -294.198621) (xy 192.289948 -294.181169) (xy 192.338167 -294.171325)
			(xy 192.387342 -294.169344) (xy 192.436197 -294.175276) (xy 192.483468 -294.188968) (xy 192.52793 -294.210066)
			(xy 192.568433 -294.238022) (xy 192.603926 -294.272114) (xy 192.633491 -294.311458) (xy 192.656362 -294.355035)
			(xy 192.671946 -294.401716) (xy 192.679841 -294.450293) (xy 192.680336 -294.4749) (xy 193.969144 -294.4749)
			(xy 193.973104 -294.425846) (xy 193.984881 -294.378062) (xy 194.004172 -294.332786) (xy 194.030475 -294.29119)
			(xy 194.06311 -294.254353) (xy 194.101231 -294.223228) (xy 194.143852 -294.198621) (xy 194.189868 -294.181169)
			(xy 194.238087 -294.171325) (xy 194.287262 -294.169344) (xy 194.336117 -294.175276) (xy 194.383388 -294.188968)
			(xy 194.42785 -294.210066) (xy 194.468353 -294.238022) (xy 194.503846 -294.272114) (xy 194.533411 -294.311458)
			(xy 194.556282 -294.355035) (xy 194.571866 -294.401716) (xy 194.579761 -294.450293) (xy 194.580256 -294.4749)
			(xy 194.919104 -294.4749) (xy 194.923064 -294.425846) (xy 194.934841 -294.378062) (xy 194.954132 -294.332786)
			(xy 194.980435 -294.29119) (xy 195.01307 -294.254353) (xy 195.051191 -294.223228) (xy 195.093812 -294.198621)
			(xy 195.139828 -294.181169) (xy 195.188047 -294.171325) (xy 195.237222 -294.169344) (xy 195.286077 -294.175276)
			(xy 195.333348 -294.188968) (xy 195.37781 -294.210066) (xy 195.418313 -294.238022) (xy 195.453806 -294.272114)
			(xy 195.483371 -294.311458) (xy 195.506242 -294.355035) (xy 195.521826 -294.401716) (xy 195.529721 -294.450293)
			(xy 195.530216 -294.4749) (xy 195.869064 -294.4749) (xy 195.873024 -294.425846) (xy 195.884801 -294.378062)
			(xy 195.904092 -294.332786) (xy 195.930395 -294.29119) (xy 195.96303 -294.254353) (xy 196.001151 -294.223228)
			(xy 196.043772 -294.198621) (xy 196.089788 -294.181169) (xy 196.138007 -294.171325) (xy 196.187182 -294.169344)
			(xy 196.236037 -294.175276) (xy 196.283308 -294.188968) (xy 196.32777 -294.210066) (xy 196.368273 -294.238022)
			(xy 196.403766 -294.272114) (xy 196.433331 -294.311458) (xy 196.456202 -294.355035) (xy 196.471786 -294.401716)
			(xy 196.479681 -294.450293) (xy 196.480176 -294.4749) (xy 196.819278 -294.4749) (xy 196.823238 -294.425846)
			(xy 196.835015 -294.378062) (xy 196.854306 -294.332786) (xy 196.880609 -294.29119) (xy 196.913244 -294.254353)
			(xy 196.951365 -294.223228) (xy 196.993986 -294.198621) (xy 197.040002 -294.181169) (xy 197.088221 -294.171325)
			(xy 197.137396 -294.169344) (xy 197.186251 -294.175276) (xy 197.233522 -294.188968) (xy 197.277984 -294.210066)
			(xy 197.318487 -294.238022) (xy 197.35398 -294.272114) (xy 197.383545 -294.311458) (xy 197.406416 -294.355035)
			(xy 197.422 -294.401716) (xy 197.429895 -294.450293) (xy 197.43039 -294.4749) (xy 197.769238 -294.4749)
			(xy 197.773198 -294.425846) (xy 197.784975 -294.378062) (xy 197.804266 -294.332786) (xy 197.830569 -294.29119)
			(xy 197.863204 -294.254353) (xy 197.901325 -294.223228) (xy 197.943946 -294.198621) (xy 197.989962 -294.181169)
			(xy 198.038181 -294.171325) (xy 198.087356 -294.169344) (xy 198.136211 -294.175276) (xy 198.183482 -294.188968)
			(xy 198.227944 -294.210066) (xy 198.268447 -294.238022) (xy 198.30394 -294.272114) (xy 198.333505 -294.311458)
			(xy 198.356376 -294.355035) (xy 198.37196 -294.401716) (xy 198.379855 -294.450293) (xy 198.38035 -294.4749)
			(xy 198.719198 -294.4749) (xy 198.723158 -294.425846) (xy 198.734935 -294.378062) (xy 198.754226 -294.332786)
			(xy 198.780529 -294.29119) (xy 198.813164 -294.254353) (xy 198.851285 -294.223228) (xy 198.893906 -294.198621)
			(xy 198.939922 -294.181169) (xy 198.988141 -294.171325) (xy 199.037316 -294.169344) (xy 199.086171 -294.175276)
			(xy 199.133442 -294.188968) (xy 199.177904 -294.210066) (xy 199.218407 -294.238022) (xy 199.2539 -294.272114)
			(xy 199.283465 -294.311458) (xy 199.306336 -294.355035) (xy 199.32192 -294.401716) (xy 199.329815 -294.450293)
			(xy 199.33031 -294.4749) (xy 199.329815 -294.499507) (xy 199.32192 -294.548084) (xy 199.306336 -294.594765)
			(xy 199.283465 -294.638342) (xy 199.2539 -294.677686) (xy 199.220324 -294.709937) (xy 205.263126 -294.709937)
			(xy 205.263128 -294.655425) (xy 205.270889 -294.601469) (xy 205.28625 -294.549166) (xy 205.308898 -294.499582)
			(xy 205.338373 -294.453725) (xy 205.374074 -294.412531) (xy 205.415274 -294.376837) (xy 205.461135 -294.347369)
			(xy 205.510723 -294.324729) (xy 205.563028 -294.309376) (xy 205.616986 -294.301624) (xy 205.644242 -294.301164)
			(xy 205.669642 -294.301926) (xy 205.684375 -294.302413) (xy 205.713104 -294.29587) (xy 205.738771 -294.281399)
			(xy 205.759238 -294.260201) (xy 205.772802 -294.234043) (xy 205.778333 -294.205102) (xy 205.775372 -294.175786)
			(xy 205.770226 -294.161972) (xy 205.761062 -294.13877) (xy 205.748173 -294.090579) (xy 205.741674 -294.041119)
			(xy 205.74127 -294.016176) (xy 205.741804 -293.988927) (xy 205.749563 -293.934983) (xy 205.764921 -293.882692)
			(xy 205.787563 -293.83312) (xy 205.817031 -293.787274) (xy 205.852722 -293.746089) (xy 205.893912 -293.710402)
			(xy 205.939761 -293.680941) (xy 205.989337 -293.658304) (xy 206.041629 -293.642953) (xy 206.095574 -293.635201)
			(xy 206.150073 -293.635204) (xy 206.204017 -293.642963) (xy 206.256307 -293.65832) (xy 206.30588 -293.680963)
			(xy 206.351725 -293.71043) (xy 206.392911 -293.746122) (xy 206.428597 -293.787312) (xy 206.458059 -293.833161)
			(xy 206.480696 -293.882736) (xy 206.496047 -293.935028) (xy 206.502598 -293.980616) (xy 207.380838 -293.980616)
			(xy 207.384909 -293.924994) (xy 207.397035 -293.870557) (xy 207.416958 -293.818466) (xy 207.444254 -293.769831)
			(xy 207.47834 -293.725688) (xy 207.518489 -293.686979) (xy 207.563847 -293.654528) (xy 207.613447 -293.629027)
			(xy 207.666231 -293.61102) (xy 207.721074 -293.60089) (xy 207.776808 -293.598853) (xy 207.832245 -293.604953)
			(xy 207.886202 -293.619059) (xy 207.937531 -293.640871) (xy 207.985137 -293.669925) (xy 208.028005 -293.7056)
			(xy 208.065222 -293.747137) (xy 208.095995 -293.79365) (xy 208.119667 -293.844147) (xy 208.135735 -293.897554)
			(xy 208.143855 -293.95273) (xy 208.144364 -293.980616) (xy 208.143855 -294.008502) (xy 208.135735 -294.063678)
			(xy 208.119667 -294.117085) (xy 208.095995 -294.167582) (xy 208.065222 -294.214095) (xy 208.028005 -294.255632)
			(xy 207.985137 -294.291307) (xy 207.937531 -294.320361) (xy 207.886202 -294.342173) (xy 207.832245 -294.356279)
			(xy 207.776808 -294.362379) (xy 207.721074 -294.360342) (xy 207.666231 -294.350212) (xy 207.613447 -294.332205)
			(xy 207.563847 -294.306704) (xy 207.518489 -294.274253) (xy 207.47834 -294.235544) (xy 207.444254 -294.191401)
			(xy 207.416958 -294.142766) (xy 207.397035 -294.090675) (xy 207.384909 -294.036238) (xy 207.380838 -293.980616)
			(xy 206.502598 -293.980616) (xy 206.503799 -293.988973) (xy 206.503796 -294.043472) (xy 206.496037 -294.097416)
			(xy 206.48068 -294.149706) (xy 206.458037 -294.199279) (xy 206.42857 -294.245125) (xy 206.392878 -294.28631)
			(xy 206.351689 -294.321997) (xy 206.30584 -294.351459) (xy 206.256264 -294.374095) (xy 206.203972 -294.389446)
			(xy 206.150027 -294.397199) (xy 206.122778 -294.397684) (xy 206.097378 -294.396922) (xy 206.082647 -294.396524)
			(xy 206.05393 -294.403057) (xy 206.028272 -294.417516) (xy 206.00781 -294.438698) (xy 205.994245 -294.464839)
			(xy 205.988707 -294.493764) (xy 205.989493 -294.50157) (xy 206.636618 -294.50157) (xy 206.640689 -294.445948)
			(xy 206.652815 -294.391511) (xy 206.672738 -294.33942) (xy 206.700034 -294.290785) (xy 206.73412 -294.246642)
			(xy 206.774269 -294.207933) (xy 206.819627 -294.175482) (xy 206.869227 -294.149981) (xy 206.922011 -294.131974)
			(xy 206.976854 -294.121844) (xy 207.032588 -294.119807) (xy 207.088025 -294.125907) (xy 207.141982 -294.140013)
			(xy 207.193311 -294.161825) (xy 207.240917 -294.190879) (xy 207.283785 -294.226554) (xy 207.321002 -294.268091)
			(xy 207.351775 -294.314604) (xy 207.375447 -294.365101) (xy 207.391515 -294.418508) (xy 207.399635 -294.473684)
			(xy 207.400144 -294.50157) (xy 207.399635 -294.529456) (xy 207.391515 -294.584632) (xy 207.375447 -294.638039)
			(xy 207.351775 -294.688536) (xy 207.321002 -294.735049) (xy 207.283785 -294.776586) (xy 207.240917 -294.812261)
			(xy 207.193311 -294.841315) (xy 207.141982 -294.863127) (xy 207.088025 -294.877233) (xy 207.032588 -294.883333)
			(xy 206.976854 -294.881296) (xy 206.922011 -294.871166) (xy 206.869227 -294.853159) (xy 206.819627 -294.827658)
			(xy 206.774269 -294.795207) (xy 206.73412 -294.756498) (xy 206.700034 -294.712355) (xy 206.672738 -294.66372)
			(xy 206.652815 -294.611629) (xy 206.640689 -294.557192) (xy 206.636618 -294.50157) (xy 205.989493 -294.50157)
			(xy 205.991656 -294.523067) (xy 205.996794 -294.536876) (xy 206.005943 -294.560083) (xy 206.018838 -294.608272)
			(xy 206.025342 -294.65773) (xy 206.02575 -294.682672) (xy 206.025275 -294.709928) (xy 206.017521 -294.763886)
			(xy 206.002166 -294.81619) (xy 205.979524 -294.865777) (xy 205.950055 -294.911637) (xy 205.914359 -294.952836)
			(xy 205.873163 -294.988535) (xy 205.827306 -295.018008) (xy 205.777721 -295.040655) (xy 205.725418 -295.056014)
			(xy 205.671461 -295.063773) (xy 205.616949 -295.063773) (xy 205.562992 -295.056016) (xy 205.510688 -295.040658)
			(xy 205.461102 -295.018013) (xy 205.415244 -294.988541) (xy 205.374047 -294.952843) (xy 205.338351 -294.911645)
			(xy 205.30888 -294.865786) (xy 205.286237 -294.816199) (xy 205.270881 -294.763895) (xy 205.263126 -294.709937)
			(xy 199.220324 -294.709937) (xy 199.218407 -294.711778) (xy 199.177904 -294.739734) (xy 199.133442 -294.760832)
			(xy 199.086171 -294.774524) (xy 199.037316 -294.780456) (xy 198.988141 -294.778475) (xy 198.939922 -294.768631)
			(xy 198.893906 -294.751179) (xy 198.851285 -294.726572) (xy 198.813164 -294.695447) (xy 198.780529 -294.65861)
			(xy 198.754226 -294.617014) (xy 198.734935 -294.571738) (xy 198.723158 -294.523954) (xy 198.719198 -294.4749)
			(xy 198.38035 -294.4749) (xy 198.379855 -294.499507) (xy 198.37196 -294.548084) (xy 198.356376 -294.594765)
			(xy 198.333505 -294.638342) (xy 198.30394 -294.677686) (xy 198.268447 -294.711778) (xy 198.227944 -294.739734)
			(xy 198.183482 -294.760832) (xy 198.136211 -294.774524) (xy 198.087356 -294.780456) (xy 198.038181 -294.778475)
			(xy 197.989962 -294.768631) (xy 197.943946 -294.751179) (xy 197.901325 -294.726572) (xy 197.863204 -294.695447)
			(xy 197.830569 -294.65861) (xy 197.804266 -294.617014) (xy 197.784975 -294.571738) (xy 197.773198 -294.523954)
			(xy 197.769238 -294.4749) (xy 197.43039 -294.4749) (xy 197.429895 -294.499507) (xy 197.422 -294.548084)
			(xy 197.406416 -294.594765) (xy 197.383545 -294.638342) (xy 197.35398 -294.677686) (xy 197.318487 -294.711778)
			(xy 197.277984 -294.739734) (xy 197.233522 -294.760832) (xy 197.186251 -294.774524) (xy 197.137396 -294.780456)
			(xy 197.088221 -294.778475) (xy 197.040002 -294.768631) (xy 196.993986 -294.751179) (xy 196.951365 -294.726572)
			(xy 196.913244 -294.695447) (xy 196.880609 -294.65861) (xy 196.854306 -294.617014) (xy 196.835015 -294.571738)
			(xy 196.823238 -294.523954) (xy 196.819278 -294.4749) (xy 196.480176 -294.4749) (xy 196.479681 -294.499507)
			(xy 196.471786 -294.548084) (xy 196.456202 -294.594765) (xy 196.433331 -294.638342) (xy 196.403766 -294.677686)
			(xy 196.368273 -294.711778) (xy 196.32777 -294.739734) (xy 196.283308 -294.760832) (xy 196.236037 -294.774524)
			(xy 196.187182 -294.780456) (xy 196.138007 -294.778475) (xy 196.089788 -294.768631) (xy 196.043772 -294.751179)
			(xy 196.001151 -294.726572) (xy 195.96303 -294.695447) (xy 195.930395 -294.65861) (xy 195.904092 -294.617014)
			(xy 195.884801 -294.571738) (xy 195.873024 -294.523954) (xy 195.869064 -294.4749) (xy 195.530216 -294.4749)
			(xy 195.529721 -294.499507) (xy 195.521826 -294.548084) (xy 195.506242 -294.594765) (xy 195.483371 -294.638342)
			(xy 195.453806 -294.677686) (xy 195.418313 -294.711778) (xy 195.37781 -294.739734) (xy 195.333348 -294.760832)
			(xy 195.286077 -294.774524) (xy 195.237222 -294.780456) (xy 195.188047 -294.778475) (xy 195.139828 -294.768631)
			(xy 195.093812 -294.751179) (xy 195.051191 -294.726572) (xy 195.01307 -294.695447) (xy 194.980435 -294.65861)
			(xy 194.954132 -294.617014) (xy 194.934841 -294.571738) (xy 194.923064 -294.523954) (xy 194.919104 -294.4749)
			(xy 194.580256 -294.4749) (xy 194.579761 -294.499507) (xy 194.571866 -294.548084) (xy 194.556282 -294.594765)
			(xy 194.533411 -294.638342) (xy 194.503846 -294.677686) (xy 194.468353 -294.711778) (xy 194.42785 -294.739734)
			(xy 194.383388 -294.760832) (xy 194.336117 -294.774524) (xy 194.287262 -294.780456) (xy 194.238087 -294.778475)
			(xy 194.189868 -294.768631) (xy 194.143852 -294.751179) (xy 194.101231 -294.726572) (xy 194.06311 -294.695447)
			(xy 194.030475 -294.65861) (xy 194.004172 -294.617014) (xy 193.984881 -294.571738) (xy 193.973104 -294.523954)
			(xy 193.969144 -294.4749) (xy 192.680336 -294.4749) (xy 192.679841 -294.499507) (xy 192.671946 -294.548084)
			(xy 192.656362 -294.594765) (xy 192.633491 -294.638342) (xy 192.603926 -294.677686) (xy 192.568433 -294.711778)
			(xy 192.52793 -294.739734) (xy 192.483468 -294.760832) (xy 192.436197 -294.774524) (xy 192.387342 -294.780456)
			(xy 192.338167 -294.778475) (xy 192.289948 -294.768631) (xy 192.243932 -294.751179) (xy 192.201311 -294.726572)
			(xy 192.16319 -294.695447) (xy 192.130555 -294.65861) (xy 192.104252 -294.617014) (xy 192.084961 -294.571738)
			(xy 192.073184 -294.523954) (xy 192.069224 -294.4749) (xy 191.730376 -294.4749) (xy 191.729881 -294.499507)
			(xy 191.721986 -294.548084) (xy 191.706402 -294.594765) (xy 191.683531 -294.638342) (xy 191.653966 -294.677686)
			(xy 191.618473 -294.711778) (xy 191.57797 -294.739734) (xy 191.533508 -294.760832) (xy 191.486237 -294.774524)
			(xy 191.437382 -294.780456) (xy 191.388207 -294.778475) (xy 191.339988 -294.768631) (xy 191.293972 -294.751179)
			(xy 191.251351 -294.726572) (xy 191.21323 -294.695447) (xy 191.180595 -294.65861) (xy 191.154292 -294.617014)
			(xy 191.135001 -294.571738) (xy 191.123224 -294.523954) (xy 191.119264 -294.4749) (xy 190.780162 -294.4749)
			(xy 190.779667 -294.499507) (xy 190.771772 -294.548084) (xy 190.756188 -294.594765) (xy 190.733317 -294.638342)
			(xy 190.703752 -294.677686) (xy 190.668259 -294.711778) (xy 190.627756 -294.739734) (xy 190.583294 -294.760832)
			(xy 190.536023 -294.774524) (xy 190.487168 -294.780456) (xy 190.437993 -294.778475) (xy 190.389774 -294.768631)
			(xy 190.343758 -294.751179) (xy 190.301137 -294.726572) (xy 190.263016 -294.695447) (xy 190.230381 -294.65861)
			(xy 190.204078 -294.617014) (xy 190.184787 -294.571738) (xy 190.17301 -294.523954) (xy 190.16905 -294.4749)
			(xy 189.830202 -294.4749) (xy 189.829707 -294.499507) (xy 189.821812 -294.548084) (xy 189.806228 -294.594765)
			(xy 189.783357 -294.638342) (xy 189.753792 -294.677686) (xy 189.718299 -294.711778) (xy 189.677796 -294.739734)
			(xy 189.633334 -294.760832) (xy 189.586063 -294.774524) (xy 189.537208 -294.780456) (xy 189.488033 -294.778475)
			(xy 189.439814 -294.768631) (xy 189.393798 -294.751179) (xy 189.351177 -294.726572) (xy 189.313056 -294.695447)
			(xy 189.280421 -294.65861) (xy 189.254118 -294.617014) (xy 189.234827 -294.571738) (xy 189.22305 -294.523954)
			(xy 189.21909 -294.4749) (xy 188.880242 -294.4749) (xy 188.879747 -294.499507) (xy 188.871852 -294.548084)
			(xy 188.856268 -294.594765) (xy 188.833397 -294.638342) (xy 188.803832 -294.677686) (xy 188.768339 -294.711778)
			(xy 188.727836 -294.739734) (xy 188.683374 -294.760832) (xy 188.636103 -294.774524) (xy 188.587248 -294.780456)
			(xy 188.538073 -294.778475) (xy 188.489854 -294.768631) (xy 188.443838 -294.751179) (xy 188.401217 -294.726572)
			(xy 188.363096 -294.695447) (xy 188.330461 -294.65861) (xy 188.304158 -294.617014) (xy 188.284867 -294.571738)
			(xy 188.27309 -294.523954) (xy 188.26913 -294.4749) (xy 187.930282 -294.4749) (xy 187.929787 -294.499507)
			(xy 187.921892 -294.548084) (xy 187.906308 -294.594765) (xy 187.883437 -294.638342) (xy 187.853872 -294.677686)
			(xy 187.818379 -294.711778) (xy 187.777876 -294.739734) (xy 187.733414 -294.760832) (xy 187.686143 -294.774524)
			(xy 187.637288 -294.780456) (xy 187.588113 -294.778475) (xy 187.539894 -294.768631) (xy 187.493878 -294.751179)
			(xy 187.451257 -294.726572) (xy 187.413136 -294.695447) (xy 187.380501 -294.65861) (xy 187.354198 -294.617014)
			(xy 187.334907 -294.571738) (xy 187.32313 -294.523954) (xy 187.31917 -294.4749) (xy 186.031724 -294.4749)
			(xy 186.027541 -294.525373) (xy 186.015107 -294.57447) (xy 185.99476 -294.620849) (xy 185.967057 -294.663247)
			(xy 185.932753 -294.700507) (xy 185.892783 -294.731611) (xy 185.848238 -294.755711) (xy 185.800334 -294.77215)
			(xy 185.750377 -294.78048) (xy 185.725054 -294.78097) (xy 185.724546 -294.78097) (xy 185.697216 -294.780369)
			(xy 185.643427 -294.770659) (xy 185.617612 -294.761666) (xy 185.611862 -294.759688) (xy 185.599788 -294.758283)
			(xy 185.593736 -294.758872) (xy 185.58129 -294.760396) (xy 185.523632 -294.80002) (xy 185.523124 -294.80002)
			(xy 185.50255 -294.814498) (xy 185.492868 -294.822105) (xy 185.481431 -294.843866) (xy 185.480706 -294.856154)
			(xy 185.480706 -295.355518) (xy 208.715862 -295.355518) (xy 208.719933 -295.299896) (xy 208.732059 -295.245459)
			(xy 208.751982 -295.193368) (xy 208.779278 -295.144733) (xy 208.813364 -295.10059) (xy 208.853513 -295.061881)
			(xy 208.898871 -295.02943) (xy 208.948471 -295.003929) (xy 209.001255 -294.985922) (xy 209.056098 -294.975792)
			(xy 209.111832 -294.973755) (xy 209.167269 -294.979855) (xy 209.221226 -294.993961) (xy 209.272555 -295.015773)
			(xy 209.320161 -295.044827) (xy 209.363029 -295.080502) (xy 209.400246 -295.122039) (xy 209.431019 -295.168552)
			(xy 209.454691 -295.219049) (xy 209.470759 -295.272456) (xy 209.478879 -295.327632) (xy 209.479388 -295.355518)
			(xy 209.478879 -295.383404) (xy 209.470759 -295.43858) (xy 209.454691 -295.491987) (xy 209.431019 -295.542484)
			(xy 209.400246 -295.588997) (xy 209.363029 -295.630534) (xy 209.320161 -295.666209) (xy 209.272555 -295.695263)
			(xy 209.221226 -295.717075) (xy 209.167269 -295.731181) (xy 209.111832 -295.737281) (xy 209.056098 -295.735244)
			(xy 209.001255 -295.725114) (xy 208.948471 -295.707107) (xy 208.898871 -295.681606) (xy 208.853513 -295.649155)
			(xy 208.813364 -295.610446) (xy 208.779278 -295.566303) (xy 208.751982 -295.517668) (xy 208.732059 -295.465577)
			(xy 208.719933 -295.41114) (xy 208.715862 -295.355518) (xy 185.480706 -295.355518) (xy 185.480706 -295.993566)
			(xy 185.481306 -296.005888) (xy 185.492766 -296.027705) (xy 185.50255 -296.035222) (xy 185.523378 -296.0497)
			(xy 185.57113 -296.082466) (xy 185.581624 -296.088795) (xy 185.605916 -296.091714) (xy 185.617612 -296.088054)
			(xy 185.643429 -296.079068) (xy 185.697217 -296.069354) (xy 185.724546 -296.06875) (xy 185.725054 -296.06875)
			(xy 185.750376 -296.06924) (xy 185.800329 -296.077569) (xy 185.84823 -296.094007) (xy 185.892772 -296.118106)
			(xy 185.932739 -296.149208) (xy 185.967041 -296.186465) (xy 185.994743 -296.22886) (xy 186.015088 -296.275237)
			(xy 186.027521 -296.32433) (xy 186.031704 -296.3748) (xy 186.031702 -296.37482) (xy 187.31917 -296.37482)
			(xy 187.32313 -296.325766) (xy 187.334907 -296.277982) (xy 187.354198 -296.232706) (xy 187.380501 -296.19111)
			(xy 187.413136 -296.154273) (xy 187.451257 -296.123148) (xy 187.493878 -296.098541) (xy 187.539894 -296.081089)
			(xy 187.588113 -296.071245) (xy 187.637288 -296.069264) (xy 187.686143 -296.075196) (xy 187.733414 -296.088888)
			(xy 187.777876 -296.109986) (xy 187.818379 -296.137942) (xy 187.853872 -296.172034) (xy 187.883437 -296.211378)
			(xy 187.906308 -296.254955) (xy 187.921892 -296.301636) (xy 187.929787 -296.350213) (xy 187.930282 -296.37482)
			(xy 188.26913 -296.37482) (xy 188.27309 -296.325766) (xy 188.284867 -296.277982) (xy 188.304158 -296.232706)
			(xy 188.330461 -296.19111) (xy 188.363096 -296.154273) (xy 188.401217 -296.123148) (xy 188.443838 -296.098541)
			(xy 188.489854 -296.081089) (xy 188.538073 -296.071245) (xy 188.587248 -296.069264) (xy 188.636103 -296.075196)
			(xy 188.683374 -296.088888) (xy 188.727836 -296.109986) (xy 188.768339 -296.137942) (xy 188.803832 -296.172034)
			(xy 188.833397 -296.211378) (xy 188.856268 -296.254955) (xy 188.871852 -296.301636) (xy 188.879747 -296.350213)
			(xy 188.880242 -296.37482) (xy 189.21909 -296.37482) (xy 189.22305 -296.325766) (xy 189.234827 -296.277982)
			(xy 189.254118 -296.232706) (xy 189.280421 -296.19111) (xy 189.313056 -296.154273) (xy 189.351177 -296.123148)
			(xy 189.393798 -296.098541) (xy 189.439814 -296.081089) (xy 189.488033 -296.071245) (xy 189.537208 -296.069264)
			(xy 189.586063 -296.075196) (xy 189.633334 -296.088888) (xy 189.677796 -296.109986) (xy 189.718299 -296.137942)
			(xy 189.753792 -296.172034) (xy 189.783357 -296.211378) (xy 189.806228 -296.254955) (xy 189.821812 -296.301636)
			(xy 189.829707 -296.350213) (xy 189.830202 -296.37482) (xy 190.16905 -296.37482) (xy 190.17301 -296.325766)
			(xy 190.184787 -296.277982) (xy 190.204078 -296.232706) (xy 190.230381 -296.19111) (xy 190.263016 -296.154273)
			(xy 190.301137 -296.123148) (xy 190.343758 -296.098541) (xy 190.389774 -296.081089) (xy 190.437993 -296.071245)
			(xy 190.487168 -296.069264) (xy 190.536023 -296.075196) (xy 190.583294 -296.088888) (xy 190.627756 -296.109986)
			(xy 190.668259 -296.137942) (xy 190.703752 -296.172034) (xy 190.733317 -296.211378) (xy 190.756188 -296.254955)
			(xy 190.771772 -296.301636) (xy 190.779667 -296.350213) (xy 190.780162 -296.37482) (xy 191.119264 -296.37482)
			(xy 191.123224 -296.325766) (xy 191.135001 -296.277982) (xy 191.154292 -296.232706) (xy 191.180595 -296.19111)
			(xy 191.21323 -296.154273) (xy 191.251351 -296.123148) (xy 191.293972 -296.098541) (xy 191.339988 -296.081089)
			(xy 191.388207 -296.071245) (xy 191.437382 -296.069264) (xy 191.486237 -296.075196) (xy 191.533508 -296.088888)
			(xy 191.57797 -296.109986) (xy 191.618473 -296.137942) (xy 191.653966 -296.172034) (xy 191.683531 -296.211378)
			(xy 191.706402 -296.254955) (xy 191.721986 -296.301636) (xy 191.729881 -296.350213) (xy 191.730376 -296.37482)
			(xy 192.069224 -296.37482) (xy 192.073184 -296.325766) (xy 192.084961 -296.277982) (xy 192.104252 -296.232706)
			(xy 192.130555 -296.19111) (xy 192.16319 -296.154273) (xy 192.201311 -296.123148) (xy 192.243932 -296.098541)
			(xy 192.289948 -296.081089) (xy 192.338167 -296.071245) (xy 192.387342 -296.069264) (xy 192.436197 -296.075196)
			(xy 192.483468 -296.088888) (xy 192.52793 -296.109986) (xy 192.568433 -296.137942) (xy 192.603926 -296.172034)
			(xy 192.633491 -296.211378) (xy 192.656362 -296.254955) (xy 192.671946 -296.301636) (xy 192.679841 -296.350213)
			(xy 192.680336 -296.37482) (xy 194.919104 -296.37482) (xy 194.923064 -296.325766) (xy 194.934841 -296.277982)
			(xy 194.954132 -296.232706) (xy 194.980435 -296.19111) (xy 195.01307 -296.154273) (xy 195.051191 -296.123148)
			(xy 195.093812 -296.098541) (xy 195.139828 -296.081089) (xy 195.188047 -296.071245) (xy 195.237222 -296.069264)
			(xy 195.286077 -296.075196) (xy 195.333348 -296.088888) (xy 195.37781 -296.109986) (xy 195.418313 -296.137942)
			(xy 195.453806 -296.172034) (xy 195.483371 -296.211378) (xy 195.506242 -296.254955) (xy 195.521826 -296.301636)
			(xy 195.529721 -296.350213) (xy 195.530216 -296.37482) (xy 195.869064 -296.37482) (xy 195.873024 -296.325766)
			(xy 195.884801 -296.277982) (xy 195.904092 -296.232706) (xy 195.930395 -296.19111) (xy 195.96303 -296.154273)
			(xy 196.001151 -296.123148) (xy 196.043772 -296.098541) (xy 196.089788 -296.081089) (xy 196.138007 -296.071245)
			(xy 196.187182 -296.069264) (xy 196.236037 -296.075196) (xy 196.283308 -296.088888) (xy 196.32777 -296.109986)
			(xy 196.368273 -296.137942) (xy 196.403766 -296.172034) (xy 196.433331 -296.211378) (xy 196.456202 -296.254955)
			(xy 196.471786 -296.301636) (xy 196.479681 -296.350213) (xy 196.480176 -296.37482) (xy 196.819278 -296.37482)
			(xy 196.823238 -296.325766) (xy 196.835015 -296.277982) (xy 196.854306 -296.232706) (xy 196.880609 -296.19111)
			(xy 196.913244 -296.154273) (xy 196.951365 -296.123148) (xy 196.993986 -296.098541) (xy 197.040002 -296.081089)
			(xy 197.088221 -296.071245) (xy 197.137396 -296.069264) (xy 197.186251 -296.075196) (xy 197.233522 -296.088888)
			(xy 197.277984 -296.109986) (xy 197.318487 -296.137942) (xy 197.35398 -296.172034) (xy 197.383545 -296.211378)
			(xy 197.406416 -296.254955) (xy 197.422 -296.301636) (xy 197.429895 -296.350213) (xy 197.43039 -296.37482)
			(xy 197.769238 -296.37482) (xy 197.773198 -296.325766) (xy 197.784975 -296.277982) (xy 197.804266 -296.232706)
			(xy 197.830569 -296.19111) (xy 197.863204 -296.154273) (xy 197.901325 -296.123148) (xy 197.943946 -296.098541)
			(xy 197.989962 -296.081089) (xy 198.038181 -296.071245) (xy 198.087356 -296.069264) (xy 198.136211 -296.075196)
			(xy 198.183482 -296.088888) (xy 198.227944 -296.109986) (xy 198.268447 -296.137942) (xy 198.30394 -296.172034)
			(xy 198.333505 -296.211378) (xy 198.356376 -296.254955) (xy 198.37196 -296.301636) (xy 198.379855 -296.350213)
			(xy 198.38035 -296.37482) (xy 198.719198 -296.37482) (xy 198.723158 -296.325766) (xy 198.734935 -296.277982)
			(xy 198.754226 -296.232706) (xy 198.780529 -296.19111) (xy 198.813164 -296.154273) (xy 198.851285 -296.123148)
			(xy 198.893906 -296.098541) (xy 198.939922 -296.081089) (xy 198.988141 -296.071245) (xy 199.037316 -296.069264)
			(xy 199.086171 -296.075196) (xy 199.133442 -296.088888) (xy 199.177904 -296.109986) (xy 199.218407 -296.137942)
			(xy 199.2539 -296.172034) (xy 199.283465 -296.211378) (xy 199.306336 -296.254955) (xy 199.32192 -296.301636)
			(xy 199.329815 -296.350213) (xy 199.33031 -296.37482) (xy 199.329815 -296.399427) (xy 199.32192 -296.448004)
			(xy 199.306336 -296.494685) (xy 199.283465 -296.538262) (xy 199.2539 -296.577606) (xy 199.218407 -296.611698)
			(xy 199.216416 -296.613072) (xy 205.362554 -296.613072) (xy 205.366625 -296.55745) (xy 205.378751 -296.503013)
			(xy 205.398674 -296.450922) (xy 205.42597 -296.402287) (xy 205.460056 -296.358144) (xy 205.500205 -296.319435)
			(xy 205.545563 -296.286984) (xy 205.595163 -296.261483) (xy 205.647947 -296.243476) (xy 205.70279 -296.233346)
			(xy 205.758524 -296.231309) (xy 205.813961 -296.237409) (xy 205.867918 -296.251515) (xy 205.919247 -296.273327)
			(xy 205.966853 -296.302381) (xy 206.009721 -296.338056) (xy 206.046938 -296.379593) (xy 206.077711 -296.426106)
			(xy 206.101383 -296.476603) (xy 206.117451 -296.53001) (xy 206.125571 -296.585186) (xy 206.12608 -296.613072)
			(xy 206.63738 -296.613072) (xy 206.641451 -296.55745) (xy 206.653577 -296.503013) (xy 206.6735 -296.450922)
			(xy 206.700796 -296.402287) (xy 206.734882 -296.358144) (xy 206.775031 -296.319435) (xy 206.820389 -296.286984)
			(xy 206.869989 -296.261483) (xy 206.922773 -296.243476) (xy 206.977616 -296.233346) (xy 207.03335 -296.231309)
			(xy 207.088787 -296.237409) (xy 207.142744 -296.251515) (xy 207.194073 -296.273327) (xy 207.241679 -296.302381)
			(xy 207.284547 -296.338056) (xy 207.321764 -296.379593) (xy 207.352537 -296.426106) (xy 207.376209 -296.476603)
			(xy 207.392277 -296.53001) (xy 207.400397 -296.585186) (xy 207.400906 -296.613072) (xy 207.400397 -296.640958)
			(xy 207.392277 -296.696134) (xy 207.376209 -296.749541) (xy 207.352537 -296.800038) (xy 207.321764 -296.846551)
			(xy 207.284547 -296.888088) (xy 207.241679 -296.923763) (xy 207.194073 -296.952817) (xy 207.142744 -296.974629)
			(xy 207.088787 -296.988735) (xy 207.03335 -296.994835) (xy 206.977616 -296.992798) (xy 206.922773 -296.982668)
			(xy 206.869989 -296.964661) (xy 206.820389 -296.93916) (xy 206.775031 -296.906709) (xy 206.734882 -296.868)
			(xy 206.700796 -296.823857) (xy 206.6735 -296.775222) (xy 206.653577 -296.723131) (xy 206.641451 -296.668694)
			(xy 206.63738 -296.613072) (xy 206.12608 -296.613072) (xy 206.125571 -296.640958) (xy 206.117451 -296.696134)
			(xy 206.101383 -296.749541) (xy 206.077711 -296.800038) (xy 206.046938 -296.846551) (xy 206.009721 -296.888088)
			(xy 205.966853 -296.923763) (xy 205.919247 -296.952817) (xy 205.867918 -296.974629) (xy 205.813961 -296.988735)
			(xy 205.758524 -296.994835) (xy 205.70279 -296.992798) (xy 205.647947 -296.982668) (xy 205.595163 -296.964661)
			(xy 205.545563 -296.93916) (xy 205.500205 -296.906709) (xy 205.460056 -296.868) (xy 205.42597 -296.823857)
			(xy 205.398674 -296.775222) (xy 205.378751 -296.723131) (xy 205.366625 -296.668694) (xy 205.362554 -296.613072)
			(xy 199.216416 -296.613072) (xy 199.177904 -296.639654) (xy 199.133442 -296.660752) (xy 199.086171 -296.674444)
			(xy 199.037316 -296.680376) (xy 198.988141 -296.678395) (xy 198.939922 -296.668551) (xy 198.893906 -296.651099)
			(xy 198.851285 -296.626492) (xy 198.813164 -296.595367) (xy 198.780529 -296.55853) (xy 198.754226 -296.516934)
			(xy 198.734935 -296.471658) (xy 198.723158 -296.423874) (xy 198.719198 -296.37482) (xy 198.38035 -296.37482)
			(xy 198.379855 -296.399427) (xy 198.37196 -296.448004) (xy 198.356376 -296.494685) (xy 198.333505 -296.538262)
			(xy 198.30394 -296.577606) (xy 198.268447 -296.611698) (xy 198.227944 -296.639654) (xy 198.183482 -296.660752)
			(xy 198.136211 -296.674444) (xy 198.087356 -296.680376) (xy 198.038181 -296.678395) (xy 197.989962 -296.668551)
			(xy 197.943946 -296.651099) (xy 197.901325 -296.626492) (xy 197.863204 -296.595367) (xy 197.830569 -296.55853)
			(xy 197.804266 -296.516934) (xy 197.784975 -296.471658) (xy 197.773198 -296.423874) (xy 197.769238 -296.37482)
			(xy 197.43039 -296.37482) (xy 197.429895 -296.399427) (xy 197.422 -296.448004) (xy 197.406416 -296.494685)
			(xy 197.383545 -296.538262) (xy 197.35398 -296.577606) (xy 197.318487 -296.611698) (xy 197.277984 -296.639654)
			(xy 197.233522 -296.660752) (xy 197.186251 -296.674444) (xy 197.137396 -296.680376) (xy 197.088221 -296.678395)
			(xy 197.040002 -296.668551) (xy 196.993986 -296.651099) (xy 196.951365 -296.626492) (xy 196.913244 -296.595367)
			(xy 196.880609 -296.55853) (xy 196.854306 -296.516934) (xy 196.835015 -296.471658) (xy 196.823238 -296.423874)
			(xy 196.819278 -296.37482) (xy 196.480176 -296.37482) (xy 196.479681 -296.399427) (xy 196.471786 -296.448004)
			(xy 196.456202 -296.494685) (xy 196.433331 -296.538262) (xy 196.403766 -296.577606) (xy 196.368273 -296.611698)
			(xy 196.32777 -296.639654) (xy 196.283308 -296.660752) (xy 196.236037 -296.674444) (xy 196.187182 -296.680376)
			(xy 196.138007 -296.678395) (xy 196.089788 -296.668551) (xy 196.043772 -296.651099) (xy 196.001151 -296.626492)
			(xy 195.96303 -296.595367) (xy 195.930395 -296.55853) (xy 195.904092 -296.516934) (xy 195.884801 -296.471658)
			(xy 195.873024 -296.423874) (xy 195.869064 -296.37482) (xy 195.530216 -296.37482) (xy 195.529721 -296.399427)
			(xy 195.521826 -296.448004) (xy 195.506242 -296.494685) (xy 195.483371 -296.538262) (xy 195.453806 -296.577606)
			(xy 195.418313 -296.611698) (xy 195.37781 -296.639654) (xy 195.333348 -296.660752) (xy 195.286077 -296.674444)
			(xy 195.237222 -296.680376) (xy 195.188047 -296.678395) (xy 195.139828 -296.668551) (xy 195.093812 -296.651099)
			(xy 195.051191 -296.626492) (xy 195.01307 -296.595367) (xy 194.980435 -296.55853) (xy 194.954132 -296.516934)
			(xy 194.934841 -296.471658) (xy 194.923064 -296.423874) (xy 194.919104 -296.37482) (xy 192.680336 -296.37482)
			(xy 192.679841 -296.399427) (xy 192.671946 -296.448004) (xy 192.656362 -296.494685) (xy 192.633491 -296.538262)
			(xy 192.603926 -296.577606) (xy 192.568433 -296.611698) (xy 192.52793 -296.639654) (xy 192.483468 -296.660752)
			(xy 192.436197 -296.674444) (xy 192.387342 -296.680376) (xy 192.338167 -296.678395) (xy 192.289948 -296.668551)
			(xy 192.243932 -296.651099) (xy 192.201311 -296.626492) (xy 192.16319 -296.595367) (xy 192.130555 -296.55853)
			(xy 192.104252 -296.516934) (xy 192.084961 -296.471658) (xy 192.073184 -296.423874) (xy 192.069224 -296.37482)
			(xy 191.730376 -296.37482) (xy 191.729881 -296.399427) (xy 191.721986 -296.448004) (xy 191.706402 -296.494685)
			(xy 191.683531 -296.538262) (xy 191.653966 -296.577606) (xy 191.618473 -296.611698) (xy 191.57797 -296.639654)
			(xy 191.533508 -296.660752) (xy 191.486237 -296.674444) (xy 191.437382 -296.680376) (xy 191.388207 -296.678395)
			(xy 191.339988 -296.668551) (xy 191.293972 -296.651099) (xy 191.251351 -296.626492) (xy 191.21323 -296.595367)
			(xy 191.180595 -296.55853) (xy 191.154292 -296.516934) (xy 191.135001 -296.471658) (xy 191.123224 -296.423874)
			(xy 191.119264 -296.37482) (xy 190.780162 -296.37482) (xy 190.779667 -296.399427) (xy 190.771772 -296.448004)
			(xy 190.756188 -296.494685) (xy 190.733317 -296.538262) (xy 190.703752 -296.577606) (xy 190.668259 -296.611698)
			(xy 190.627756 -296.639654) (xy 190.583294 -296.660752) (xy 190.536023 -296.674444) (xy 190.487168 -296.680376)
			(xy 190.437993 -296.678395) (xy 190.389774 -296.668551) (xy 190.343758 -296.651099) (xy 190.301137 -296.626492)
			(xy 190.263016 -296.595367) (xy 190.230381 -296.55853) (xy 190.204078 -296.516934) (xy 190.184787 -296.471658)
			(xy 190.17301 -296.423874) (xy 190.16905 -296.37482) (xy 189.830202 -296.37482) (xy 189.829707 -296.399427)
			(xy 189.821812 -296.448004) (xy 189.806228 -296.494685) (xy 189.783357 -296.538262) (xy 189.753792 -296.577606)
			(xy 189.718299 -296.611698) (xy 189.677796 -296.639654) (xy 189.633334 -296.660752) (xy 189.586063 -296.674444)
			(xy 189.537208 -296.680376) (xy 189.488033 -296.678395) (xy 189.439814 -296.668551) (xy 189.393798 -296.651099)
			(xy 189.351177 -296.626492) (xy 189.313056 -296.595367) (xy 189.280421 -296.55853) (xy 189.254118 -296.516934)
			(xy 189.234827 -296.471658) (xy 189.22305 -296.423874) (xy 189.21909 -296.37482) (xy 188.880242 -296.37482)
			(xy 188.879747 -296.399427) (xy 188.871852 -296.448004) (xy 188.856268 -296.494685) (xy 188.833397 -296.538262)
			(xy 188.803832 -296.577606) (xy 188.768339 -296.611698) (xy 188.727836 -296.639654) (xy 188.683374 -296.660752)
			(xy 188.636103 -296.674444) (xy 188.587248 -296.680376) (xy 188.538073 -296.678395) (xy 188.489854 -296.668551)
			(xy 188.443838 -296.651099) (xy 188.401217 -296.626492) (xy 188.363096 -296.595367) (xy 188.330461 -296.55853)
			(xy 188.304158 -296.516934) (xy 188.284867 -296.471658) (xy 188.27309 -296.423874) (xy 188.26913 -296.37482)
			(xy 187.930282 -296.37482) (xy 187.929787 -296.399427) (xy 187.921892 -296.448004) (xy 187.906308 -296.494685)
			(xy 187.883437 -296.538262) (xy 187.853872 -296.577606) (xy 187.818379 -296.611698) (xy 187.777876 -296.639654)
			(xy 187.733414 -296.660752) (xy 187.686143 -296.674444) (xy 187.637288 -296.680376) (xy 187.588113 -296.678395)
			(xy 187.539894 -296.668551) (xy 187.493878 -296.651099) (xy 187.451257 -296.626492) (xy 187.413136 -296.595367)
			(xy 187.380501 -296.55853) (xy 187.354198 -296.516934) (xy 187.334907 -296.471658) (xy 187.32313 -296.423874)
			(xy 187.31917 -296.37482) (xy 186.031702 -296.37482) (xy 186.027521 -296.42527) (xy 186.015088 -296.474363)
			(xy 185.994743 -296.52074) (xy 185.967041 -296.563135) (xy 185.932739 -296.600392) (xy 185.892772 -296.631494)
			(xy 185.84823 -296.655593) (xy 185.800329 -296.672031) (xy 185.750376 -296.68036) (xy 185.725054 -296.68089)
			(xy 185.724546 -296.68089) (xy 185.697216 -296.68029) (xy 185.643426 -296.67058) (xy 185.617612 -296.661586)
			(xy 185.611863 -296.659607) (xy 185.599788 -296.658202) (xy 185.593736 -296.658792) (xy 185.58129 -296.660316)
			(xy 185.523632 -296.69994) (xy 185.523124 -296.69994) (xy 185.50255 -296.714418) (xy 185.492872 -296.722026)
			(xy 185.481443 -296.743787) (xy 185.480706 -296.756074) (xy 185.480706 -296.943526) (xy 185.481298 -296.955853)
			(xy 185.492747 -296.977685) (xy 185.50255 -296.985182) (xy 185.523378 -296.99966) (xy 185.57113 -297.032426)
			(xy 185.581623 -297.038759) (xy 185.605917 -297.04168) (xy 185.617612 -297.038014) (xy 185.643428 -297.029027)
			(xy 185.697217 -297.01931) (xy 185.724546 -297.01871) (xy 185.725054 -297.01871) (xy 185.750379 -297.0192)
			(xy 185.800339 -297.02753) (xy 185.848246 -297.04397) (xy 185.892794 -297.068072) (xy 185.932766 -297.099179)
			(xy 185.967073 -297.13644) (xy 185.994778 -297.178841) (xy 186.015126 -297.225224) (xy 186.02756 -297.274323)
			(xy 186.031742 -297.32478) (xy 187.31917 -297.32478) (xy 187.32313 -297.275726) (xy 187.334907 -297.227942)
			(xy 187.354198 -297.182666) (xy 187.380501 -297.14107) (xy 187.413136 -297.104233) (xy 187.451257 -297.073108)
			(xy 187.493878 -297.048501) (xy 187.539894 -297.031049) (xy 187.588113 -297.021205) (xy 187.637288 -297.019224)
			(xy 187.686143 -297.025156) (xy 187.733414 -297.038848) (xy 187.777876 -297.059946) (xy 187.818379 -297.087902)
			(xy 187.853872 -297.121994) (xy 187.883437 -297.161338) (xy 187.906308 -297.204915) (xy 187.921892 -297.251596)
			(xy 187.929787 -297.300173) (xy 187.930282 -297.32478) (xy 188.26913 -297.32478) (xy 188.27309 -297.275726)
			(xy 188.284867 -297.227942) (xy 188.304158 -297.182666) (xy 188.330461 -297.14107) (xy 188.363096 -297.104233)
			(xy 188.401217 -297.073108) (xy 188.443838 -297.048501) (xy 188.489854 -297.031049) (xy 188.538073 -297.021205)
			(xy 188.587248 -297.019224) (xy 188.636103 -297.025156) (xy 188.683374 -297.038848) (xy 188.727836 -297.059946)
			(xy 188.768339 -297.087902) (xy 188.803832 -297.121994) (xy 188.833397 -297.161338) (xy 188.856268 -297.204915)
			(xy 188.871852 -297.251596) (xy 188.879747 -297.300173) (xy 188.880242 -297.32478) (xy 189.21909 -297.32478)
			(xy 189.22305 -297.275726) (xy 189.234827 -297.227942) (xy 189.254118 -297.182666) (xy 189.280421 -297.14107)
			(xy 189.313056 -297.104233) (xy 189.351177 -297.073108) (xy 189.393798 -297.048501) (xy 189.439814 -297.031049)
			(xy 189.488033 -297.021205) (xy 189.537208 -297.019224) (xy 189.586063 -297.025156) (xy 189.633334 -297.038848)
			(xy 189.677796 -297.059946) (xy 189.718299 -297.087902) (xy 189.753792 -297.121994) (xy 189.783357 -297.161338)
			(xy 189.806228 -297.204915) (xy 189.821812 -297.251596) (xy 189.829707 -297.300173) (xy 189.830202 -297.32478)
			(xy 190.169304 -297.32478) (xy 190.173264 -297.275726) (xy 190.185041 -297.227942) (xy 190.204332 -297.182666)
			(xy 190.230635 -297.14107) (xy 190.26327 -297.104233) (xy 190.301391 -297.073108) (xy 190.344012 -297.048501)
			(xy 190.390028 -297.031049) (xy 190.438247 -297.021205) (xy 190.487422 -297.019224) (xy 190.536277 -297.025156)
			(xy 190.583548 -297.038848) (xy 190.62801 -297.059946) (xy 190.668513 -297.087902) (xy 190.704006 -297.121994)
			(xy 190.733571 -297.161338) (xy 190.756442 -297.204915) (xy 190.772026 -297.251596) (xy 190.779921 -297.300173)
			(xy 190.780416 -297.32478) (xy 191.119264 -297.32478) (xy 191.123224 -297.275726) (xy 191.135001 -297.227942)
			(xy 191.154292 -297.182666) (xy 191.180595 -297.14107) (xy 191.21323 -297.104233) (xy 191.251351 -297.073108)
			(xy 191.293972 -297.048501) (xy 191.339988 -297.031049) (xy 191.388207 -297.021205) (xy 191.437382 -297.019224)
			(xy 191.486237 -297.025156) (xy 191.533508 -297.038848) (xy 191.57797 -297.059946) (xy 191.618473 -297.087902)
			(xy 191.653966 -297.121994) (xy 191.683531 -297.161338) (xy 191.706402 -297.204915) (xy 191.721986 -297.251596)
			(xy 191.729881 -297.300173) (xy 191.730376 -297.32478) (xy 192.069224 -297.32478) (xy 192.073184 -297.275726)
			(xy 192.084961 -297.227942) (xy 192.104252 -297.182666) (xy 192.130555 -297.14107) (xy 192.16319 -297.104233)
			(xy 192.201311 -297.073108) (xy 192.243932 -297.048501) (xy 192.289948 -297.031049) (xy 192.338167 -297.021205)
			(xy 192.387342 -297.019224) (xy 192.436197 -297.025156) (xy 192.483468 -297.038848) (xy 192.52793 -297.059946)
			(xy 192.568433 -297.087902) (xy 192.603926 -297.121994) (xy 192.633491 -297.161338) (xy 192.656362 -297.204915)
			(xy 192.671946 -297.251596) (xy 192.679841 -297.300173) (xy 192.680336 -297.32478) (xy 193.019184 -297.32478)
			(xy 193.023144 -297.275726) (xy 193.034921 -297.227942) (xy 193.054212 -297.182666) (xy 193.080515 -297.14107)
			(xy 193.11315 -297.104233) (xy 193.151271 -297.073108) (xy 193.193892 -297.048501) (xy 193.239908 -297.031049)
			(xy 193.288127 -297.021205) (xy 193.337302 -297.019224) (xy 193.386157 -297.025156) (xy 193.433428 -297.038848)
			(xy 193.47789 -297.059946) (xy 193.518393 -297.087902) (xy 193.553886 -297.121994) (xy 193.583451 -297.161338)
			(xy 193.606322 -297.204915) (xy 193.621906 -297.251596) (xy 193.629801 -297.300173) (xy 193.630296 -297.32478)
			(xy 193.969144 -297.32478) (xy 193.973104 -297.275726) (xy 193.984881 -297.227942) (xy 194.004172 -297.182666)
			(xy 194.030475 -297.14107) (xy 194.06311 -297.104233) (xy 194.101231 -297.073108) (xy 194.143852 -297.048501)
			(xy 194.189868 -297.031049) (xy 194.238087 -297.021205) (xy 194.287262 -297.019224) (xy 194.336117 -297.025156)
			(xy 194.383388 -297.038848) (xy 194.42785 -297.059946) (xy 194.468353 -297.087902) (xy 194.503846 -297.121994)
			(xy 194.533411 -297.161338) (xy 194.556282 -297.204915) (xy 194.571866 -297.251596) (xy 194.579761 -297.300173)
			(xy 194.580256 -297.32478) (xy 194.919104 -297.32478) (xy 194.923064 -297.275726) (xy 194.934841 -297.227942)
			(xy 194.954132 -297.182666) (xy 194.980435 -297.14107) (xy 195.01307 -297.104233) (xy 195.051191 -297.073108)
			(xy 195.093812 -297.048501) (xy 195.139828 -297.031049) (xy 195.188047 -297.021205) (xy 195.237222 -297.019224)
			(xy 195.286077 -297.025156) (xy 195.333348 -297.038848) (xy 195.37781 -297.059946) (xy 195.418313 -297.087902)
			(xy 195.453806 -297.121994) (xy 195.483371 -297.161338) (xy 195.506242 -297.204915) (xy 195.521826 -297.251596)
			(xy 195.529721 -297.300173) (xy 195.530216 -297.32478) (xy 195.869064 -297.32478) (xy 195.873024 -297.275726)
			(xy 195.884801 -297.227942) (xy 195.904092 -297.182666) (xy 195.930395 -297.14107) (xy 195.96303 -297.104233)
			(xy 196.001151 -297.073108) (xy 196.043772 -297.048501) (xy 196.089788 -297.031049) (xy 196.138007 -297.021205)
			(xy 196.187182 -297.019224) (xy 196.236037 -297.025156) (xy 196.283308 -297.038848) (xy 196.32777 -297.059946)
			(xy 196.368273 -297.087902) (xy 196.403766 -297.121994) (xy 196.433331 -297.161338) (xy 196.456202 -297.204915)
			(xy 196.471786 -297.251596) (xy 196.479681 -297.300173) (xy 196.480176 -297.32478) (xy 196.819278 -297.32478)
			(xy 196.823238 -297.275726) (xy 196.835015 -297.227942) (xy 196.854306 -297.182666) (xy 196.880609 -297.14107)
			(xy 196.913244 -297.104233) (xy 196.951365 -297.073108) (xy 196.993986 -297.048501) (xy 197.040002 -297.031049)
			(xy 197.088221 -297.021205) (xy 197.137396 -297.019224) (xy 197.186251 -297.025156) (xy 197.233522 -297.038848)
			(xy 197.277984 -297.059946) (xy 197.318487 -297.087902) (xy 197.35398 -297.121994) (xy 197.383545 -297.161338)
			(xy 197.406416 -297.204915) (xy 197.422 -297.251596) (xy 197.429895 -297.300173) (xy 197.43039 -297.32478)
			(xy 197.769238 -297.32478) (xy 197.773198 -297.275726) (xy 197.784975 -297.227942) (xy 197.804266 -297.182666)
			(xy 197.830569 -297.14107) (xy 197.863204 -297.104233) (xy 197.901325 -297.073108) (xy 197.943946 -297.048501)
			(xy 197.989962 -297.031049) (xy 198.038181 -297.021205) (xy 198.087356 -297.019224) (xy 198.136211 -297.025156)
			(xy 198.183482 -297.038848) (xy 198.227944 -297.059946) (xy 198.268447 -297.087902) (xy 198.30394 -297.121994)
			(xy 198.333505 -297.161338) (xy 198.356376 -297.204915) (xy 198.37196 -297.251596) (xy 198.379855 -297.300173)
			(xy 198.38035 -297.32478) (xy 198.719198 -297.32478) (xy 198.723158 -297.275726) (xy 198.734935 -297.227942)
			(xy 198.754226 -297.182666) (xy 198.780529 -297.14107) (xy 198.813164 -297.104233) (xy 198.851285 -297.073108)
			(xy 198.893906 -297.048501) (xy 198.939922 -297.031049) (xy 198.988141 -297.021205) (xy 199.037316 -297.019224)
			(xy 199.086171 -297.025156) (xy 199.133442 -297.038848) (xy 199.177904 -297.059946) (xy 199.218407 -297.087902)
			(xy 199.2539 -297.121994) (xy 199.283465 -297.161338) (xy 199.306336 -297.204915) (xy 199.32192 -297.251596)
			(xy 199.329815 -297.300173) (xy 199.33031 -297.32478) (xy 199.329815 -297.349387) (xy 199.32192 -297.397964)
			(xy 199.306336 -297.444645) (xy 199.283465 -297.488222) (xy 199.2539 -297.527566) (xy 199.218407 -297.561658)
			(xy 199.177904 -297.589614) (xy 199.133442 -297.610712) (xy 199.086171 -297.624404) (xy 199.037316 -297.630336)
			(xy 198.988141 -297.628355) (xy 198.939922 -297.618511) (xy 198.893906 -297.601059) (xy 198.851285 -297.576452)
			(xy 198.813164 -297.545327) (xy 198.780529 -297.50849) (xy 198.754226 -297.466894) (xy 198.734935 -297.421618)
			(xy 198.723158 -297.373834) (xy 198.719198 -297.32478) (xy 198.38035 -297.32478) (xy 198.379855 -297.349387)
			(xy 198.37196 -297.397964) (xy 198.356376 -297.444645) (xy 198.333505 -297.488222) (xy 198.30394 -297.527566)
			(xy 198.268447 -297.561658) (xy 198.227944 -297.589614) (xy 198.183482 -297.610712) (xy 198.136211 -297.624404)
			(xy 198.087356 -297.630336) (xy 198.038181 -297.628355) (xy 197.989962 -297.618511) (xy 197.943946 -297.601059)
			(xy 197.901325 -297.576452) (xy 197.863204 -297.545327) (xy 197.830569 -297.50849) (xy 197.804266 -297.466894)
			(xy 197.784975 -297.421618) (xy 197.773198 -297.373834) (xy 197.769238 -297.32478) (xy 197.43039 -297.32478)
			(xy 197.429895 -297.349387) (xy 197.422 -297.397964) (xy 197.406416 -297.444645) (xy 197.383545 -297.488222)
			(xy 197.35398 -297.527566) (xy 197.318487 -297.561658) (xy 197.277984 -297.589614) (xy 197.233522 -297.610712)
			(xy 197.186251 -297.624404) (xy 197.137396 -297.630336) (xy 197.088221 -297.628355) (xy 197.040002 -297.618511)
			(xy 196.993986 -297.601059) (xy 196.951365 -297.576452) (xy 196.913244 -297.545327) (xy 196.880609 -297.50849)
			(xy 196.854306 -297.466894) (xy 196.835015 -297.421618) (xy 196.823238 -297.373834) (xy 196.819278 -297.32478)
			(xy 196.480176 -297.32478) (xy 196.479681 -297.349387) (xy 196.471786 -297.397964) (xy 196.456202 -297.444645)
			(xy 196.433331 -297.488222) (xy 196.403766 -297.527566) (xy 196.368273 -297.561658) (xy 196.32777 -297.589614)
			(xy 196.283308 -297.610712) (xy 196.236037 -297.624404) (xy 196.187182 -297.630336) (xy 196.138007 -297.628355)
			(xy 196.089788 -297.618511) (xy 196.043772 -297.601059) (xy 196.001151 -297.576452) (xy 195.96303 -297.545327)
			(xy 195.930395 -297.50849) (xy 195.904092 -297.466894) (xy 195.884801 -297.421618) (xy 195.873024 -297.373834)
			(xy 195.869064 -297.32478) (xy 195.530216 -297.32478) (xy 195.529721 -297.349387) (xy 195.521826 -297.397964)
			(xy 195.506242 -297.444645) (xy 195.483371 -297.488222) (xy 195.453806 -297.527566) (xy 195.418313 -297.561658)
			(xy 195.37781 -297.589614) (xy 195.333348 -297.610712) (xy 195.286077 -297.624404) (xy 195.237222 -297.630336)
			(xy 195.188047 -297.628355) (xy 195.139828 -297.618511) (xy 195.093812 -297.601059) (xy 195.051191 -297.576452)
			(xy 195.01307 -297.545327) (xy 194.980435 -297.50849) (xy 194.954132 -297.466894) (xy 194.934841 -297.421618)
			(xy 194.923064 -297.373834) (xy 194.919104 -297.32478) (xy 194.580256 -297.32478) (xy 194.579761 -297.349387)
			(xy 194.571866 -297.397964) (xy 194.556282 -297.444645) (xy 194.533411 -297.488222) (xy 194.503846 -297.527566)
			(xy 194.468353 -297.561658) (xy 194.42785 -297.589614) (xy 194.383388 -297.610712) (xy 194.336117 -297.624404)
			(xy 194.287262 -297.630336) (xy 194.238087 -297.628355) (xy 194.189868 -297.618511) (xy 194.143852 -297.601059)
			(xy 194.101231 -297.576452) (xy 194.06311 -297.545327) (xy 194.030475 -297.50849) (xy 194.004172 -297.466894)
			(xy 193.984881 -297.421618) (xy 193.973104 -297.373834) (xy 193.969144 -297.32478) (xy 193.630296 -297.32478)
			(xy 193.629801 -297.349387) (xy 193.621906 -297.397964) (xy 193.606322 -297.444645) (xy 193.583451 -297.488222)
			(xy 193.553886 -297.527566) (xy 193.518393 -297.561658) (xy 193.47789 -297.589614) (xy 193.433428 -297.610712)
			(xy 193.386157 -297.624404) (xy 193.337302 -297.630336) (xy 193.288127 -297.628355) (xy 193.239908 -297.618511)
			(xy 193.193892 -297.601059) (xy 193.151271 -297.576452) (xy 193.11315 -297.545327) (xy 193.080515 -297.50849)
			(xy 193.054212 -297.466894) (xy 193.034921 -297.421618) (xy 193.023144 -297.373834) (xy 193.019184 -297.32478)
			(xy 192.680336 -297.32478) (xy 192.679841 -297.349387) (xy 192.671946 -297.397964) (xy 192.656362 -297.444645)
			(xy 192.633491 -297.488222) (xy 192.603926 -297.527566) (xy 192.568433 -297.561658) (xy 192.52793 -297.589614)
			(xy 192.483468 -297.610712) (xy 192.436197 -297.624404) (xy 192.387342 -297.630336) (xy 192.338167 -297.628355)
			(xy 192.289948 -297.618511) (xy 192.243932 -297.601059) (xy 192.201311 -297.576452) (xy 192.16319 -297.545327)
			(xy 192.130555 -297.50849) (xy 192.104252 -297.466894) (xy 192.084961 -297.421618) (xy 192.073184 -297.373834)
			(xy 192.069224 -297.32478) (xy 191.730376 -297.32478) (xy 191.729881 -297.349387) (xy 191.721986 -297.397964)
			(xy 191.706402 -297.444645) (xy 191.683531 -297.488222) (xy 191.653966 -297.527566) (xy 191.618473 -297.561658)
			(xy 191.57797 -297.589614) (xy 191.533508 -297.610712) (xy 191.486237 -297.624404) (xy 191.437382 -297.630336)
			(xy 191.388207 -297.628355) (xy 191.339988 -297.618511) (xy 191.293972 -297.601059) (xy 191.251351 -297.576452)
			(xy 191.21323 -297.545327) (xy 191.180595 -297.50849) (xy 191.154292 -297.466894) (xy 191.135001 -297.421618)
			(xy 191.123224 -297.373834) (xy 191.119264 -297.32478) (xy 190.780416 -297.32478) (xy 190.779921 -297.349387)
			(xy 190.772026 -297.397964) (xy 190.756442 -297.444645) (xy 190.733571 -297.488222) (xy 190.704006 -297.527566)
			(xy 190.668513 -297.561658) (xy 190.62801 -297.589614) (xy 190.583548 -297.610712) (xy 190.536277 -297.624404)
			(xy 190.487422 -297.630336) (xy 190.438247 -297.628355) (xy 190.390028 -297.618511) (xy 190.344012 -297.601059)
			(xy 190.301391 -297.576452) (xy 190.26327 -297.545327) (xy 190.230635 -297.50849) (xy 190.204332 -297.466894)
			(xy 190.185041 -297.421618) (xy 190.173264 -297.373834) (xy 190.169304 -297.32478) (xy 189.830202 -297.32478)
			(xy 189.829707 -297.349387) (xy 189.821812 -297.397964) (xy 189.806228 -297.444645) (xy 189.783357 -297.488222)
			(xy 189.753792 -297.527566) (xy 189.718299 -297.561658) (xy 189.677796 -297.589614) (xy 189.633334 -297.610712)
			(xy 189.586063 -297.624404) (xy 189.537208 -297.630336) (xy 189.488033 -297.628355) (xy 189.439814 -297.618511)
			(xy 189.393798 -297.601059) (xy 189.351177 -297.576452) (xy 189.313056 -297.545327) (xy 189.280421 -297.50849)
			(xy 189.254118 -297.466894) (xy 189.234827 -297.421618) (xy 189.22305 -297.373834) (xy 189.21909 -297.32478)
			(xy 188.880242 -297.32478) (xy 188.879747 -297.349387) (xy 188.871852 -297.397964) (xy 188.856268 -297.444645)
			(xy 188.833397 -297.488222) (xy 188.803832 -297.527566) (xy 188.768339 -297.561658) (xy 188.727836 -297.589614)
			(xy 188.683374 -297.610712) (xy 188.636103 -297.624404) (xy 188.587248 -297.630336) (xy 188.538073 -297.628355)
			(xy 188.489854 -297.618511) (xy 188.443838 -297.601059) (xy 188.401217 -297.576452) (xy 188.363096 -297.545327)
			(xy 188.330461 -297.50849) (xy 188.304158 -297.466894) (xy 188.284867 -297.421618) (xy 188.27309 -297.373834)
			(xy 188.26913 -297.32478) (xy 187.930282 -297.32478) (xy 187.929787 -297.349387) (xy 187.921892 -297.397964)
			(xy 187.906308 -297.444645) (xy 187.883437 -297.488222) (xy 187.853872 -297.527566) (xy 187.818379 -297.561658)
			(xy 187.777876 -297.589614) (xy 187.733414 -297.610712) (xy 187.686143 -297.624404) (xy 187.637288 -297.630336)
			(xy 187.588113 -297.628355) (xy 187.539894 -297.618511) (xy 187.493878 -297.601059) (xy 187.451257 -297.576452)
			(xy 187.413136 -297.545327) (xy 187.380501 -297.50849) (xy 187.354198 -297.466894) (xy 187.334907 -297.421618)
			(xy 187.32313 -297.373834) (xy 187.31917 -297.32478) (xy 186.031742 -297.32478) (xy 186.031744 -297.3248)
			(xy 186.02756 -297.375277) (xy 186.015126 -297.424376) (xy 185.994778 -297.470759) (xy 185.967073 -297.51316)
			(xy 185.932766 -297.550421) (xy 185.892794 -297.581528) (xy 185.848246 -297.60563) (xy 185.800339 -297.62207)
			(xy 185.750379 -297.6304) (xy 185.725054 -297.63085) (xy 185.724546 -297.63085) (xy 185.697216 -297.630249)
			(xy 185.643427 -297.620538) (xy 185.617612 -297.611546) (xy 185.611862 -297.609569) (xy 185.599788 -297.608165)
			(xy 185.593736 -297.608752) (xy 185.58129 -297.610276) (xy 185.523632 -297.6499) (xy 185.523124 -297.6499)
			(xy 185.50255 -297.664378) (xy 185.492882 -297.67199) (xy 185.481478 -297.693752) (xy 185.480706 -297.706034)
			(xy 185.480706 -297.893486) (xy 185.481289 -297.905818) (xy 185.492729 -297.927664) (xy 185.50255 -297.935142)
			(xy 185.523378 -297.94962) (xy 185.57113 -297.982386) (xy 185.581625 -297.988713) (xy 185.605916 -297.991631)
			(xy 185.617612 -297.987974) (xy 185.643429 -297.978988) (xy 185.697217 -297.969273) (xy 185.724546 -297.96867)
			(xy 185.725054 -297.96867) (xy 185.750374 -297.969161) (xy 185.800324 -297.977489) (xy 185.848222 -297.993926)
			(xy 185.892761 -298.018023) (xy 185.932725 -298.049123) (xy 185.967025 -298.086378) (xy 185.994725 -298.12877)
			(xy 186.015068 -298.175143) (xy 186.027501 -298.224233) (xy 186.031683 -298.2747) (xy 186.03168 -298.27474)
			(xy 187.31917 -298.27474) (xy 187.32313 -298.225686) (xy 187.334907 -298.177902) (xy 187.354198 -298.132626)
			(xy 187.380501 -298.09103) (xy 187.413136 -298.054193) (xy 187.451257 -298.023068) (xy 187.493878 -297.998461)
			(xy 187.539894 -297.981009) (xy 187.588113 -297.971165) (xy 187.637288 -297.969184) (xy 187.686143 -297.975116)
			(xy 187.733414 -297.988808) (xy 187.777876 -298.009906) (xy 187.818379 -298.037862) (xy 187.853872 -298.071954)
			(xy 187.883437 -298.111298) (xy 187.906308 -298.154875) (xy 187.921892 -298.201556) (xy 187.929787 -298.250133)
			(xy 187.930282 -298.27474) (xy 188.26913 -298.27474) (xy 188.27309 -298.225686) (xy 188.284867 -298.177902)
			(xy 188.304158 -298.132626) (xy 188.330461 -298.09103) (xy 188.363096 -298.054193) (xy 188.401217 -298.023068)
			(xy 188.443838 -297.998461) (xy 188.489854 -297.981009) (xy 188.538073 -297.971165) (xy 188.587248 -297.969184)
			(xy 188.636103 -297.975116) (xy 188.683374 -297.988808) (xy 188.727836 -298.009906) (xy 188.768339 -298.037862)
			(xy 188.803832 -298.071954) (xy 188.833397 -298.111298) (xy 188.856268 -298.154875) (xy 188.871852 -298.201556)
			(xy 188.879747 -298.250133) (xy 188.880242 -298.27474) (xy 189.21909 -298.27474) (xy 189.22305 -298.225686)
			(xy 189.234827 -298.177902) (xy 189.254118 -298.132626) (xy 189.280421 -298.09103) (xy 189.313056 -298.054193)
			(xy 189.351177 -298.023068) (xy 189.393798 -297.998461) (xy 189.439814 -297.981009) (xy 189.488033 -297.971165)
			(xy 189.537208 -297.969184) (xy 189.586063 -297.975116) (xy 189.633334 -297.988808) (xy 189.677796 -298.009906)
			(xy 189.718299 -298.037862) (xy 189.753792 -298.071954) (xy 189.783357 -298.111298) (xy 189.806228 -298.154875)
			(xy 189.821812 -298.201556) (xy 189.829707 -298.250133) (xy 189.830202 -298.27474) (xy 190.16905 -298.27474)
			(xy 190.17301 -298.225686) (xy 190.184787 -298.177902) (xy 190.204078 -298.132626) (xy 190.230381 -298.09103)
			(xy 190.263016 -298.054193) (xy 190.301137 -298.023068) (xy 190.343758 -297.998461) (xy 190.389774 -297.981009)
			(xy 190.437993 -297.971165) (xy 190.487168 -297.969184) (xy 190.536023 -297.975116) (xy 190.583294 -297.988808)
			(xy 190.627756 -298.009906) (xy 190.668259 -298.037862) (xy 190.703752 -298.071954) (xy 190.733317 -298.111298)
			(xy 190.756188 -298.154875) (xy 190.771772 -298.201556) (xy 190.779667 -298.250133) (xy 190.780162 -298.27474)
			(xy 191.119264 -298.27474) (xy 191.123224 -298.225686) (xy 191.135001 -298.177902) (xy 191.154292 -298.132626)
			(xy 191.180595 -298.09103) (xy 191.21323 -298.054193) (xy 191.251351 -298.023068) (xy 191.293972 -297.998461)
			(xy 191.339988 -297.981009) (xy 191.388207 -297.971165) (xy 191.437382 -297.969184) (xy 191.486237 -297.975116)
			(xy 191.533508 -297.988808) (xy 191.57797 -298.009906) (xy 191.618473 -298.037862) (xy 191.653966 -298.071954)
			(xy 191.683531 -298.111298) (xy 191.706402 -298.154875) (xy 191.721986 -298.201556) (xy 191.729881 -298.250133)
			(xy 191.730376 -298.27474) (xy 192.069224 -298.27474) (xy 192.073184 -298.225686) (xy 192.084961 -298.177902)
			(xy 192.104252 -298.132626) (xy 192.130555 -298.09103) (xy 192.16319 -298.054193) (xy 192.201311 -298.023068)
			(xy 192.243932 -297.998461) (xy 192.289948 -297.981009) (xy 192.338167 -297.971165) (xy 192.387342 -297.969184)
			(xy 192.436197 -297.975116) (xy 192.483468 -297.988808) (xy 192.52793 -298.009906) (xy 192.568433 -298.037862)
			(xy 192.603926 -298.071954) (xy 192.633491 -298.111298) (xy 192.656362 -298.154875) (xy 192.671946 -298.201556)
			(xy 192.679841 -298.250133) (xy 192.680336 -298.27474) (xy 193.019184 -298.27474) (xy 193.023144 -298.225686)
			(xy 193.034921 -298.177902) (xy 193.054212 -298.132626) (xy 193.080515 -298.09103) (xy 193.11315 -298.054193)
			(xy 193.151271 -298.023068) (xy 193.193892 -297.998461) (xy 193.239908 -297.981009) (xy 193.288127 -297.971165)
			(xy 193.337302 -297.969184) (xy 193.386157 -297.975116) (xy 193.433428 -297.988808) (xy 193.47789 -298.009906)
			(xy 193.518393 -298.037862) (xy 193.553886 -298.071954) (xy 193.583451 -298.111298) (xy 193.606322 -298.154875)
			(xy 193.621906 -298.201556) (xy 193.629801 -298.250133) (xy 193.630296 -298.27474) (xy 193.969144 -298.27474)
			(xy 193.973104 -298.225686) (xy 193.984881 -298.177902) (xy 194.004172 -298.132626) (xy 194.030475 -298.09103)
			(xy 194.06311 -298.054193) (xy 194.101231 -298.023068) (xy 194.143852 -297.998461) (xy 194.189868 -297.981009)
			(xy 194.238087 -297.971165) (xy 194.287262 -297.969184) (xy 194.336117 -297.975116) (xy 194.383388 -297.988808)
			(xy 194.42785 -298.009906) (xy 194.468353 -298.037862) (xy 194.503846 -298.071954) (xy 194.533411 -298.111298)
			(xy 194.556282 -298.154875) (xy 194.571866 -298.201556) (xy 194.579761 -298.250133) (xy 194.580256 -298.27474)
			(xy 194.919104 -298.27474) (xy 194.923064 -298.225686) (xy 194.934841 -298.177902) (xy 194.954132 -298.132626)
			(xy 194.980435 -298.09103) (xy 195.01307 -298.054193) (xy 195.051191 -298.023068) (xy 195.093812 -297.998461)
			(xy 195.139828 -297.981009) (xy 195.188047 -297.971165) (xy 195.237222 -297.969184) (xy 195.286077 -297.975116)
			(xy 195.333348 -297.988808) (xy 195.37781 -298.009906) (xy 195.418313 -298.037862) (xy 195.453806 -298.071954)
			(xy 195.483371 -298.111298) (xy 195.506242 -298.154875) (xy 195.521826 -298.201556) (xy 195.529721 -298.250133)
			(xy 195.530216 -298.27474) (xy 195.869064 -298.27474) (xy 195.873024 -298.225686) (xy 195.884801 -298.177902)
			(xy 195.904092 -298.132626) (xy 195.930395 -298.09103) (xy 195.96303 -298.054193) (xy 196.001151 -298.023068)
			(xy 196.043772 -297.998461) (xy 196.089788 -297.981009) (xy 196.138007 -297.971165) (xy 196.187182 -297.969184)
			(xy 196.236037 -297.975116) (xy 196.283308 -297.988808) (xy 196.32777 -298.009906) (xy 196.368273 -298.037862)
			(xy 196.403766 -298.071954) (xy 196.433331 -298.111298) (xy 196.456202 -298.154875) (xy 196.471786 -298.201556)
			(xy 196.479681 -298.250133) (xy 196.480176 -298.27474) (xy 196.819278 -298.27474) (xy 196.823238 -298.225686)
			(xy 196.835015 -298.177902) (xy 196.854306 -298.132626) (xy 196.880609 -298.09103) (xy 196.913244 -298.054193)
			(xy 196.951365 -298.023068) (xy 196.993986 -297.998461) (xy 197.040002 -297.981009) (xy 197.088221 -297.971165)
			(xy 197.137396 -297.969184) (xy 197.186251 -297.975116) (xy 197.233522 -297.988808) (xy 197.277984 -298.009906)
			(xy 197.318487 -298.037862) (xy 197.35398 -298.071954) (xy 197.383545 -298.111298) (xy 197.406416 -298.154875)
			(xy 197.422 -298.201556) (xy 197.429895 -298.250133) (xy 197.43039 -298.27474) (xy 197.769238 -298.27474)
			(xy 197.773198 -298.225686) (xy 197.784975 -298.177902) (xy 197.804266 -298.132626) (xy 197.830569 -298.09103)
			(xy 197.863204 -298.054193) (xy 197.901325 -298.023068) (xy 197.943946 -297.998461) (xy 197.989962 -297.981009)
			(xy 198.038181 -297.971165) (xy 198.087356 -297.969184) (xy 198.136211 -297.975116) (xy 198.183482 -297.988808)
			(xy 198.227944 -298.009906) (xy 198.268447 -298.037862) (xy 198.30394 -298.071954) (xy 198.333505 -298.111298)
			(xy 198.356376 -298.154875) (xy 198.37196 -298.201556) (xy 198.379855 -298.250133) (xy 198.38035 -298.27474)
			(xy 198.719198 -298.27474) (xy 198.723158 -298.225686) (xy 198.734935 -298.177902) (xy 198.754226 -298.132626)
			(xy 198.780529 -298.09103) (xy 198.813164 -298.054193) (xy 198.851285 -298.023068) (xy 198.893906 -297.998461)
			(xy 198.939922 -297.981009) (xy 198.988141 -297.971165) (xy 199.037316 -297.969184) (xy 199.086171 -297.975116)
			(xy 199.133442 -297.988808) (xy 199.177904 -298.009906) (xy 199.218407 -298.037862) (xy 199.2539 -298.071954)
			(xy 199.283465 -298.111298) (xy 199.306336 -298.154875) (xy 199.32192 -298.201556) (xy 199.329815 -298.250133)
			(xy 199.33031 -298.27474) (xy 199.329815 -298.299347) (xy 199.32192 -298.347924) (xy 199.321344 -298.349649)
			(xy 199.767688 -298.349649) (xy 199.767688 -298.296351) (xy 199.775631 -298.243647) (xy 199.791341 -298.192717)
			(xy 199.814467 -298.144696) (xy 199.844491 -298.100659) (xy 199.880743 -298.061588) (xy 199.922414 -298.028357)
			(xy 199.968572 -298.001708) (xy 200.018186 -297.982236) (xy 200.070148 -297.970376) (xy 200.123298 -297.966393)
			(xy 200.176448 -297.970376) (xy 200.22841 -297.982236) (xy 200.235858 -297.985159) (xy 200.882748 -297.985159)
			(xy 200.882748 -297.931861) (xy 200.890691 -297.879157) (xy 200.906401 -297.828227) (xy 200.929527 -297.780206)
			(xy 200.959551 -297.736169) (xy 200.995803 -297.697098) (xy 201.037474 -297.663867) (xy 201.083632 -297.637218)
			(xy 201.133246 -297.617746) (xy 201.185208 -297.605886) (xy 201.238358 -297.601903) (xy 201.291508 -297.605886)
			(xy 201.34347 -297.617746) (xy 201.393084 -297.637218) (xy 201.439242 -297.663867) (xy 201.473008 -297.690794)
			(xy 202.399644 -297.690794) (xy 202.403715 -297.635172) (xy 202.415841 -297.580735) (xy 202.435764 -297.528644)
			(xy 202.46306 -297.480009) (xy 202.497146 -297.435866) (xy 202.537295 -297.397157) (xy 202.582653 -297.364706)
			(xy 202.632253 -297.339205) (xy 202.685037 -297.321198) (xy 202.73988 -297.311068) (xy 202.795614 -297.309031)
			(xy 202.851051 -297.315131) (xy 202.905008 -297.329237) (xy 202.956337 -297.351049) (xy 202.995283 -297.374818)
			(xy 208.715862 -297.374818) (xy 208.719933 -297.319196) (xy 208.732059 -297.264759) (xy 208.751982 -297.212668)
			(xy 208.779278 -297.164033) (xy 208.813364 -297.11989) (xy 208.853513 -297.081181) (xy 208.898871 -297.04873)
			(xy 208.948471 -297.023229) (xy 209.001255 -297.005222) (xy 209.056098 -296.995092) (xy 209.111832 -296.993055)
			(xy 209.167269 -296.999155) (xy 209.221226 -297.013261) (xy 209.272555 -297.035073) (xy 209.320161 -297.064127)
			(xy 209.363029 -297.099802) (xy 209.400246 -297.141339) (xy 209.431019 -297.187852) (xy 209.454691 -297.238349)
			(xy 209.470759 -297.291756) (xy 209.478879 -297.346932) (xy 209.479388 -297.374818) (xy 209.478879 -297.402704)
			(xy 209.470759 -297.45788) (xy 209.454691 -297.511287) (xy 209.431019 -297.561784) (xy 209.400246 -297.608297)
			(xy 209.363029 -297.649834) (xy 209.320161 -297.685509) (xy 209.272555 -297.714563) (xy 209.221226 -297.736375)
			(xy 209.167269 -297.750481) (xy 209.111832 -297.756581) (xy 209.056098 -297.754544) (xy 209.001255 -297.744414)
			(xy 208.948471 -297.726407) (xy 208.898871 -297.700906) (xy 208.853513 -297.668455) (xy 208.813364 -297.629746)
			(xy 208.779278 -297.585603) (xy 208.751982 -297.536968) (xy 208.732059 -297.484877) (xy 208.719933 -297.43044)
			(xy 208.715862 -297.374818) (xy 202.995283 -297.374818) (xy 203.003943 -297.380103) (xy 203.046811 -297.415778)
			(xy 203.084028 -297.457315) (xy 203.114801 -297.503828) (xy 203.138473 -297.554325) (xy 203.154541 -297.607732)
			(xy 203.162661 -297.662908) (xy 203.16317 -297.690794) (xy 203.162661 -297.71868) (xy 203.154541 -297.773856)
			(xy 203.138473 -297.827263) (xy 203.114801 -297.87776) (xy 203.084028 -297.924273) (xy 203.046811 -297.96581)
			(xy 203.003943 -298.001485) (xy 202.956337 -298.030539) (xy 202.905008 -298.052351) (xy 202.851051 -298.066457)
			(xy 202.795614 -298.072557) (xy 202.73988 -298.07052) (xy 202.685037 -298.06039) (xy 202.632253 -298.042383)
			(xy 202.582653 -298.016882) (xy 202.537295 -297.984431) (xy 202.497146 -297.945722) (xy 202.46306 -297.901579)
			(xy 202.435764 -297.852944) (xy 202.415841 -297.800853) (xy 202.403715 -297.746416) (xy 202.399644 -297.690794)
			(xy 201.473008 -297.690794) (xy 201.480913 -297.697098) (xy 201.517165 -297.736169) (xy 201.547189 -297.780206)
			(xy 201.570315 -297.828227) (xy 201.586025 -297.879157) (xy 201.593968 -297.931861) (xy 201.594466 -297.95851)
			(xy 201.593968 -297.985159) (xy 201.586025 -298.037863) (xy 201.570315 -298.088793) (xy 201.547189 -298.136814)
			(xy 201.517165 -298.180851) (xy 201.480913 -298.219922) (xy 201.439242 -298.253153) (xy 201.393084 -298.279802)
			(xy 201.34347 -298.299274) (xy 201.291508 -298.311134) (xy 201.238358 -298.315118) (xy 201.185208 -298.311134)
			(xy 201.133246 -298.299274) (xy 201.083632 -298.279802) (xy 201.037474 -298.253153) (xy 200.995803 -298.219922)
			(xy 200.959551 -298.180851) (xy 200.929527 -298.136814) (xy 200.906401 -298.088793) (xy 200.890691 -298.037863)
			(xy 200.882748 -297.985159) (xy 200.235858 -297.985159) (xy 200.278024 -298.001708) (xy 200.324182 -298.028357)
			(xy 200.365853 -298.061588) (xy 200.402105 -298.100659) (xy 200.432129 -298.144696) (xy 200.455255 -298.192717)
			(xy 200.470965 -298.243647) (xy 200.478908 -298.296351) (xy 200.479406 -298.323) (xy 200.478908 -298.349649)
			(xy 200.470965 -298.402353) (xy 200.455255 -298.453283) (xy 200.432129 -298.501304) (xy 200.402105 -298.545341)
			(xy 200.365853 -298.584412) (xy 200.324182 -298.617643) (xy 200.278024 -298.644292) (xy 200.22841 -298.663764)
			(xy 200.176448 -298.675624) (xy 200.123298 -298.679608) (xy 200.070148 -298.675624) (xy 200.018186 -298.663764)
			(xy 199.968572 -298.644292) (xy 199.922414 -298.617643) (xy 199.880743 -298.584412) (xy 199.844491 -298.545341)
			(xy 199.814467 -298.501304) (xy 199.791341 -298.453283) (xy 199.775631 -298.402353) (xy 199.767688 -298.349649)
			(xy 199.321344 -298.349649) (xy 199.306336 -298.394605) (xy 199.283465 -298.438182) (xy 199.2539 -298.477526)
			(xy 199.218407 -298.511618) (xy 199.177904 -298.539574) (xy 199.133442 -298.560672) (xy 199.086171 -298.574364)
			(xy 199.037316 -298.580296) (xy 198.988141 -298.578315) (xy 198.939922 -298.568471) (xy 198.893906 -298.551019)
			(xy 198.851285 -298.526412) (xy 198.813164 -298.495287) (xy 198.780529 -298.45845) (xy 198.754226 -298.416854)
			(xy 198.734935 -298.371578) (xy 198.723158 -298.323794) (xy 198.719198 -298.27474) (xy 198.38035 -298.27474)
			(xy 198.379855 -298.299347) (xy 198.37196 -298.347924) (xy 198.356376 -298.394605) (xy 198.333505 -298.438182)
			(xy 198.30394 -298.477526) (xy 198.268447 -298.511618) (xy 198.227944 -298.539574) (xy 198.183482 -298.560672)
			(xy 198.136211 -298.574364) (xy 198.087356 -298.580296) (xy 198.038181 -298.578315) (xy 197.989962 -298.568471)
			(xy 197.943946 -298.551019) (xy 197.901325 -298.526412) (xy 197.863204 -298.495287) (xy 197.830569 -298.45845)
			(xy 197.804266 -298.416854) (xy 197.784975 -298.371578) (xy 197.773198 -298.323794) (xy 197.769238 -298.27474)
			(xy 197.43039 -298.27474) (xy 197.429895 -298.299347) (xy 197.422 -298.347924) (xy 197.406416 -298.394605)
			(xy 197.383545 -298.438182) (xy 197.35398 -298.477526) (xy 197.318487 -298.511618) (xy 197.277984 -298.539574)
			(xy 197.233522 -298.560672) (xy 197.186251 -298.574364) (xy 197.137396 -298.580296) (xy 197.088221 -298.578315)
			(xy 197.040002 -298.568471) (xy 196.993986 -298.551019) (xy 196.951365 -298.526412) (xy 196.913244 -298.495287)
			(xy 196.880609 -298.45845) (xy 196.854306 -298.416854) (xy 196.835015 -298.371578) (xy 196.823238 -298.323794)
			(xy 196.819278 -298.27474) (xy 196.480176 -298.27474) (xy 196.479681 -298.299347) (xy 196.471786 -298.347924)
			(xy 196.456202 -298.394605) (xy 196.433331 -298.438182) (xy 196.403766 -298.477526) (xy 196.368273 -298.511618)
			(xy 196.32777 -298.539574) (xy 196.283308 -298.560672) (xy 196.236037 -298.574364) (xy 196.187182 -298.580296)
			(xy 196.138007 -298.578315) (xy 196.089788 -298.568471) (xy 196.043772 -298.551019) (xy 196.001151 -298.526412)
			(xy 195.96303 -298.495287) (xy 195.930395 -298.45845) (xy 195.904092 -298.416854) (xy 195.884801 -298.371578)
			(xy 195.873024 -298.323794) (xy 195.869064 -298.27474) (xy 195.530216 -298.27474) (xy 195.529721 -298.299347)
			(xy 195.521826 -298.347924) (xy 195.506242 -298.394605) (xy 195.483371 -298.438182) (xy 195.453806 -298.477526)
			(xy 195.418313 -298.511618) (xy 195.37781 -298.539574) (xy 195.333348 -298.560672) (xy 195.286077 -298.574364)
			(xy 195.237222 -298.580296) (xy 195.188047 -298.578315) (xy 195.139828 -298.568471) (xy 195.093812 -298.551019)
			(xy 195.051191 -298.526412) (xy 195.01307 -298.495287) (xy 194.980435 -298.45845) (xy 194.954132 -298.416854)
			(xy 194.934841 -298.371578) (xy 194.923064 -298.323794) (xy 194.919104 -298.27474) (xy 194.580256 -298.27474)
			(xy 194.579761 -298.299347) (xy 194.571866 -298.347924) (xy 194.556282 -298.394605) (xy 194.533411 -298.438182)
			(xy 194.503846 -298.477526) (xy 194.468353 -298.511618) (xy 194.42785 -298.539574) (xy 194.383388 -298.560672)
			(xy 194.336117 -298.574364) (xy 194.287262 -298.580296) (xy 194.238087 -298.578315) (xy 194.189868 -298.568471)
			(xy 194.143852 -298.551019) (xy 194.101231 -298.526412) (xy 194.06311 -298.495287) (xy 194.030475 -298.45845)
			(xy 194.004172 -298.416854) (xy 193.984881 -298.371578) (xy 193.973104 -298.323794) (xy 193.969144 -298.27474)
			(xy 193.630296 -298.27474) (xy 193.629801 -298.299347) (xy 193.621906 -298.347924) (xy 193.606322 -298.394605)
			(xy 193.583451 -298.438182) (xy 193.553886 -298.477526) (xy 193.518393 -298.511618) (xy 193.47789 -298.539574)
			(xy 193.433428 -298.560672) (xy 193.386157 -298.574364) (xy 193.337302 -298.580296) (xy 193.288127 -298.578315)
			(xy 193.239908 -298.568471) (xy 193.193892 -298.551019) (xy 193.151271 -298.526412) (xy 193.11315 -298.495287)
			(xy 193.080515 -298.45845) (xy 193.054212 -298.416854) (xy 193.034921 -298.371578) (xy 193.023144 -298.323794)
			(xy 193.019184 -298.27474) (xy 192.680336 -298.27474) (xy 192.679841 -298.299347) (xy 192.671946 -298.347924)
			(xy 192.656362 -298.394605) (xy 192.633491 -298.438182) (xy 192.603926 -298.477526) (xy 192.568433 -298.511618)
			(xy 192.52793 -298.539574) (xy 192.483468 -298.560672) (xy 192.436197 -298.574364) (xy 192.387342 -298.580296)
			(xy 192.338167 -298.578315) (xy 192.289948 -298.568471) (xy 192.243932 -298.551019) (xy 192.201311 -298.526412)
			(xy 192.16319 -298.495287) (xy 192.130555 -298.45845) (xy 192.104252 -298.416854) (xy 192.084961 -298.371578)
			(xy 192.073184 -298.323794) (xy 192.069224 -298.27474) (xy 191.730376 -298.27474) (xy 191.729881 -298.299347)
			(xy 191.721986 -298.347924) (xy 191.706402 -298.394605) (xy 191.683531 -298.438182) (xy 191.653966 -298.477526)
			(xy 191.618473 -298.511618) (xy 191.57797 -298.539574) (xy 191.533508 -298.560672) (xy 191.486237 -298.574364)
			(xy 191.437382 -298.580296) (xy 191.388207 -298.578315) (xy 191.339988 -298.568471) (xy 191.293972 -298.551019)
			(xy 191.251351 -298.526412) (xy 191.21323 -298.495287) (xy 191.180595 -298.45845) (xy 191.154292 -298.416854)
			(xy 191.135001 -298.371578) (xy 191.123224 -298.323794) (xy 191.119264 -298.27474) (xy 190.780162 -298.27474)
			(xy 190.779667 -298.299347) (xy 190.771772 -298.347924) (xy 190.756188 -298.394605) (xy 190.733317 -298.438182)
			(xy 190.703752 -298.477526) (xy 190.668259 -298.511618) (xy 190.627756 -298.539574) (xy 190.583294 -298.560672)
			(xy 190.536023 -298.574364) (xy 190.487168 -298.580296) (xy 190.437993 -298.578315) (xy 190.389774 -298.568471)
			(xy 190.343758 -298.551019) (xy 190.301137 -298.526412) (xy 190.263016 -298.495287) (xy 190.230381 -298.45845)
			(xy 190.204078 -298.416854) (xy 190.184787 -298.371578) (xy 190.17301 -298.323794) (xy 190.16905 -298.27474)
			(xy 189.830202 -298.27474) (xy 189.829707 -298.299347) (xy 189.821812 -298.347924) (xy 189.806228 -298.394605)
			(xy 189.783357 -298.438182) (xy 189.753792 -298.477526) (xy 189.718299 -298.511618) (xy 189.677796 -298.539574)
			(xy 189.633334 -298.560672) (xy 189.586063 -298.574364) (xy 189.537208 -298.580296) (xy 189.488033 -298.578315)
			(xy 189.439814 -298.568471) (xy 189.393798 -298.551019) (xy 189.351177 -298.526412) (xy 189.313056 -298.495287)
			(xy 189.280421 -298.45845) (xy 189.254118 -298.416854) (xy 189.234827 -298.371578) (xy 189.22305 -298.323794)
			(xy 189.21909 -298.27474) (xy 188.880242 -298.27474) (xy 188.879747 -298.299347) (xy 188.871852 -298.347924)
			(xy 188.856268 -298.394605) (xy 188.833397 -298.438182) (xy 188.803832 -298.477526) (xy 188.768339 -298.511618)
			(xy 188.727836 -298.539574) (xy 188.683374 -298.560672) (xy 188.636103 -298.574364) (xy 188.587248 -298.580296)
			(xy 188.538073 -298.578315) (xy 188.489854 -298.568471) (xy 188.443838 -298.551019) (xy 188.401217 -298.526412)
			(xy 188.363096 -298.495287) (xy 188.330461 -298.45845) (xy 188.304158 -298.416854) (xy 188.284867 -298.371578)
			(xy 188.27309 -298.323794) (xy 188.26913 -298.27474) (xy 187.930282 -298.27474) (xy 187.929787 -298.299347)
			(xy 187.921892 -298.347924) (xy 187.906308 -298.394605) (xy 187.883437 -298.438182) (xy 187.853872 -298.477526)
			(xy 187.818379 -298.511618) (xy 187.777876 -298.539574) (xy 187.733414 -298.560672) (xy 187.686143 -298.574364)
			(xy 187.637288 -298.580296) (xy 187.588113 -298.578315) (xy 187.539894 -298.568471) (xy 187.493878 -298.551019)
			(xy 187.451257 -298.526412) (xy 187.413136 -298.495287) (xy 187.380501 -298.45845) (xy 187.354198 -298.416854)
			(xy 187.334907 -298.371578) (xy 187.32313 -298.323794) (xy 187.31917 -298.27474) (xy 186.03168 -298.27474)
			(xy 186.027501 -298.325167) (xy 186.015068 -298.374257) (xy 185.994725 -298.42063) (xy 185.967025 -298.463022)
			(xy 185.932725 -298.500277) (xy 185.892761 -298.531377) (xy 185.848222 -298.555474) (xy 185.800324 -298.571911)
			(xy 185.750374 -298.580239) (xy 185.725054 -298.58081) (xy 185.699144 -298.580272) (xy 185.648061 -298.571562)
			(xy 185.599172 -298.55438) (xy 185.553872 -298.529216) (xy 185.513452 -298.496789) (xy 185.479064 -298.458023)
			(xy 185.464958 -298.436284) (xy 185.46445 -298.435776) (xy 185.462418 -298.431712) (xy 185.453782 -298.422822)
			(xy 185.447573 -298.416921) (xy 185.432255 -298.409275) (xy 185.42381 -298.407836) (xy 185.34888 -298.398438)
			(xy 185.342276 -298.39793) (xy 185.340498 -298.39793) (xy 185.330429 -298.398354) (xy 185.311827 -298.406072)
			(xy 185.30443 -298.412916) (xy 185.019696 -298.69765) (xy 202.569062 -298.69765) (xy 202.573133 -298.642028)
			(xy 202.585259 -298.587591) (xy 202.605182 -298.5355) (xy 202.632478 -298.486865) (xy 202.666564 -298.442722)
			(xy 202.706713 -298.404013) (xy 202.752071 -298.371562) (xy 202.801671 -298.346061) (xy 202.854455 -298.328054)
			(xy 202.909298 -298.317924) (xy 202.965032 -298.315887) (xy 203.020469 -298.321987) (xy 203.074426 -298.336093)
			(xy 203.125755 -298.357905) (xy 203.173361 -298.386959) (xy 203.216229 -298.422634) (xy 203.253446 -298.464171)
			(xy 203.284219 -298.510684) (xy 203.307891 -298.561181) (xy 203.323959 -298.614588) (xy 203.332079 -298.669764)
			(xy 203.332588 -298.69765) (xy 203.332079 -298.725536) (xy 203.323959 -298.780712) (xy 203.307891 -298.834119)
			(xy 203.284219 -298.884616) (xy 203.253446 -298.931129) (xy 203.216229 -298.972666) (xy 203.173361 -299.008341)
			(xy 203.125755 -299.037395) (xy 203.074426 -299.059207) (xy 203.020469 -299.073313) (xy 202.965032 -299.079413)
			(xy 202.909298 -299.077376) (xy 202.854455 -299.067246) (xy 202.801671 -299.049239) (xy 202.752071 -299.023738)
			(xy 202.706713 -298.991287) (xy 202.666564 -298.952578) (xy 202.632478 -298.908435) (xy 202.605182 -298.8598)
			(xy 202.585259 -298.807709) (xy 202.573133 -298.753272) (xy 202.569062 -298.69765) (xy 185.019696 -298.69765)
			(xy 184.912762 -298.804584) (xy 184.904925 -298.813254) (xy 184.897383 -298.835349) (xy 184.898284 -298.847002)
			(xy 184.900824 -298.867068) (xy 184.900824 -298.867576) (xy 184.907682 -298.925488) (xy 184.907936 -298.927774)
			(xy 184.910315 -298.93862) (xy 184.922817 -298.95694) (xy 184.932066 -298.96308) (xy 184.954264 -298.977063)
			(xy 184.993942 -299.011379) (xy 185.027178 -299.051966) (xy 185.052997 -299.097631) (xy 185.070639 -299.147034)
			(xy 185.079587 -299.198724) (xy 185.080148 -299.224954) (xy 185.41925 -299.224954) (xy 185.42321 -299.1759)
			(xy 185.434987 -299.128116) (xy 185.454278 -299.08284) (xy 185.480581 -299.041244) (xy 185.513216 -299.004407)
			(xy 185.551337 -298.973282) (xy 185.593958 -298.948675) (xy 185.639974 -298.931223) (xy 185.688193 -298.921379)
			(xy 185.737368 -298.919398) (xy 185.786223 -298.92533) (xy 185.833494 -298.939022) (xy 185.877956 -298.96012)
			(xy 185.918459 -298.988076) (xy 185.953952 -299.022168) (xy 185.983517 -299.061512) (xy 186.006388 -299.105089)
			(xy 186.021972 -299.15177) (xy 186.029867 -299.200347) (xy 186.030362 -299.224954) (xy 186.36921 -299.224954)
			(xy 186.37317 -299.1759) (xy 186.384947 -299.128116) (xy 186.404238 -299.08284) (xy 186.430541 -299.041244)
			(xy 186.463176 -299.004407) (xy 186.501297 -298.973282) (xy 186.543918 -298.948675) (xy 186.589934 -298.931223)
			(xy 186.638153 -298.921379) (xy 186.687328 -298.919398) (xy 186.736183 -298.92533) (xy 186.783454 -298.939022)
			(xy 186.827916 -298.96012) (xy 186.868419 -298.988076) (xy 186.903912 -299.022168) (xy 186.933477 -299.061512)
			(xy 186.956348 -299.105089) (xy 186.971932 -299.15177) (xy 186.979827 -299.200347) (xy 186.980322 -299.224954)
			(xy 187.31917 -299.224954) (xy 187.32313 -299.1759) (xy 187.334907 -299.128116) (xy 187.354198 -299.08284)
			(xy 187.380501 -299.041244) (xy 187.413136 -299.004407) (xy 187.451257 -298.973282) (xy 187.493878 -298.948675)
			(xy 187.539894 -298.931223) (xy 187.588113 -298.921379) (xy 187.637288 -298.919398) (xy 187.686143 -298.92533)
			(xy 187.733414 -298.939022) (xy 187.777876 -298.96012) (xy 187.818379 -298.988076) (xy 187.853872 -299.022168)
			(xy 187.883437 -299.061512) (xy 187.906308 -299.105089) (xy 187.921892 -299.15177) (xy 187.929787 -299.200347)
			(xy 187.930282 -299.224954) (xy 188.26913 -299.224954) (xy 188.27309 -299.1759) (xy 188.284867 -299.128116)
			(xy 188.304158 -299.08284) (xy 188.330461 -299.041244) (xy 188.363096 -299.004407) (xy 188.401217 -298.973282)
			(xy 188.443838 -298.948675) (xy 188.489854 -298.931223) (xy 188.538073 -298.921379) (xy 188.587248 -298.919398)
			(xy 188.636103 -298.92533) (xy 188.683374 -298.939022) (xy 188.727836 -298.96012) (xy 188.768339 -298.988076)
			(xy 188.803832 -299.022168) (xy 188.833397 -299.061512) (xy 188.856268 -299.105089) (xy 188.871852 -299.15177)
			(xy 188.879747 -299.200347) (xy 188.880242 -299.224954) (xy 189.21909 -299.224954) (xy 189.22305 -299.1759)
			(xy 189.234827 -299.128116) (xy 189.254118 -299.08284) (xy 189.280421 -299.041244) (xy 189.313056 -299.004407)
			(xy 189.351177 -298.973282) (xy 189.393798 -298.948675) (xy 189.439814 -298.931223) (xy 189.488033 -298.921379)
			(xy 189.537208 -298.919398) (xy 189.586063 -298.92533) (xy 189.633334 -298.939022) (xy 189.677796 -298.96012)
			(xy 189.718299 -298.988076) (xy 189.753792 -299.022168) (xy 189.783357 -299.061512) (xy 189.806228 -299.105089)
			(xy 189.821812 -299.15177) (xy 189.829707 -299.200347) (xy 189.830202 -299.224954) (xy 192.069224 -299.224954)
			(xy 192.073184 -299.1759) (xy 192.084961 -299.128116) (xy 192.104252 -299.08284) (xy 192.130555 -299.041244)
			(xy 192.16319 -299.004407) (xy 192.201311 -298.973282) (xy 192.243932 -298.948675) (xy 192.289948 -298.931223)
			(xy 192.338167 -298.921379) (xy 192.387342 -298.919398) (xy 192.436197 -298.92533) (xy 192.483468 -298.939022)
			(xy 192.52793 -298.96012) (xy 192.568433 -298.988076) (xy 192.603926 -299.022168) (xy 192.633491 -299.061512)
			(xy 192.656362 -299.105089) (xy 192.671946 -299.15177) (xy 192.679841 -299.200347) (xy 192.680336 -299.224954)
			(xy 193.019184 -299.224954) (xy 193.023144 -299.1759) (xy 193.034921 -299.128116) (xy 193.054212 -299.08284)
			(xy 193.080515 -299.041244) (xy 193.11315 -299.004407) (xy 193.151271 -298.973282) (xy 193.193892 -298.948675)
			(xy 193.239908 -298.931223) (xy 193.288127 -298.921379) (xy 193.337302 -298.919398) (xy 193.386157 -298.92533)
			(xy 193.433428 -298.939022) (xy 193.47789 -298.96012) (xy 193.518393 -298.988076) (xy 193.553886 -299.022168)
			(xy 193.583451 -299.061512) (xy 193.606322 -299.105089) (xy 193.621906 -299.15177) (xy 193.629801 -299.200347)
			(xy 193.630296 -299.224954) (xy 193.969144 -299.224954) (xy 193.973104 -299.1759) (xy 193.984881 -299.128116)
			(xy 194.004172 -299.08284) (xy 194.030475 -299.041244) (xy 194.06311 -299.004407) (xy 194.101231 -298.973282)
			(xy 194.143852 -298.948675) (xy 194.189868 -298.931223) (xy 194.238087 -298.921379) (xy 194.287262 -298.919398)
			(xy 194.336117 -298.92533) (xy 194.383388 -298.939022) (xy 194.42785 -298.96012) (xy 194.468353 -298.988076)
			(xy 194.503846 -299.022168) (xy 194.533411 -299.061512) (xy 194.556282 -299.105089) (xy 194.571866 -299.15177)
			(xy 194.579761 -299.200347) (xy 194.580256 -299.224954) (xy 194.919104 -299.224954) (xy 194.923064 -299.1759)
			(xy 194.934841 -299.128116) (xy 194.954132 -299.08284) (xy 194.980435 -299.041244) (xy 195.01307 -299.004407)
			(xy 195.051191 -298.973282) (xy 195.093812 -298.948675) (xy 195.139828 -298.931223) (xy 195.188047 -298.921379)
			(xy 195.237222 -298.919398) (xy 195.286077 -298.92533) (xy 195.333348 -298.939022) (xy 195.37781 -298.96012)
			(xy 195.418313 -298.988076) (xy 195.453806 -299.022168) (xy 195.483371 -299.061512) (xy 195.506242 -299.105089)
			(xy 195.521826 -299.15177) (xy 195.529721 -299.200347) (xy 195.530216 -299.224954) (xy 195.869064 -299.224954)
			(xy 195.873024 -299.1759) (xy 195.884801 -299.128116) (xy 195.904092 -299.08284) (xy 195.930395 -299.041244)
			(xy 195.96303 -299.004407) (xy 196.001151 -298.973282) (xy 196.043772 -298.948675) (xy 196.089788 -298.931223)
			(xy 196.138007 -298.921379) (xy 196.187182 -298.919398) (xy 196.236037 -298.92533) (xy 196.283308 -298.939022)
			(xy 196.32777 -298.96012) (xy 196.368273 -298.988076) (xy 196.403766 -299.022168) (xy 196.433331 -299.061512)
			(xy 196.456202 -299.105089) (xy 196.471786 -299.15177) (xy 196.479681 -299.200347) (xy 196.480176 -299.224954)
			(xy 196.819278 -299.224954) (xy 196.823238 -299.1759) (xy 196.835015 -299.128116) (xy 196.854306 -299.08284)
			(xy 196.880609 -299.041244) (xy 196.913244 -299.004407) (xy 196.951365 -298.973282) (xy 196.993986 -298.948675)
			(xy 197.040002 -298.931223) (xy 197.088221 -298.921379) (xy 197.137396 -298.919398) (xy 197.186251 -298.92533)
			(xy 197.233522 -298.939022) (xy 197.277984 -298.96012) (xy 197.318487 -298.988076) (xy 197.35398 -299.022168)
			(xy 197.383545 -299.061512) (xy 197.406416 -299.105089) (xy 197.422 -299.15177) (xy 197.429895 -299.200347)
			(xy 197.43039 -299.224954) (xy 197.769238 -299.224954) (xy 197.773198 -299.1759) (xy 197.784975 -299.128116)
			(xy 197.804266 -299.08284) (xy 197.830569 -299.041244) (xy 197.863204 -299.004407) (xy 197.901325 -298.973282)
			(xy 197.943946 -298.948675) (xy 197.989962 -298.931223) (xy 198.038181 -298.921379) (xy 198.087356 -298.919398)
			(xy 198.136211 -298.92533) (xy 198.183482 -298.939022) (xy 198.227944 -298.96012) (xy 198.268447 -298.988076)
			(xy 198.30394 -299.022168) (xy 198.333505 -299.061512) (xy 198.356376 -299.105089) (xy 198.37196 -299.15177)
			(xy 198.379855 -299.200347) (xy 198.38035 -299.224954) (xy 198.719198 -299.224954) (xy 198.723158 -299.1759)
			(xy 198.734935 -299.128116) (xy 198.754226 -299.08284) (xy 198.780529 -299.041244) (xy 198.813164 -299.004407)
			(xy 198.851285 -298.973282) (xy 198.893906 -298.948675) (xy 198.939922 -298.931223) (xy 198.988141 -298.921379)
			(xy 199.037316 -298.919398) (xy 199.086171 -298.92533) (xy 199.133442 -298.939022) (xy 199.177904 -298.96012)
			(xy 199.218407 -298.988076) (xy 199.2539 -299.022168) (xy 199.283465 -299.061512) (xy 199.306336 -299.105089)
			(xy 199.32192 -299.15177) (xy 199.329815 -299.200347) (xy 199.33031 -299.224954) (xy 199.329815 -299.249561)
			(xy 199.326012 -299.27296) (xy 206.414622 -299.27296) (xy 206.418693 -299.217338) (xy 206.430819 -299.162901)
			(xy 206.450742 -299.11081) (xy 206.478038 -299.062175) (xy 206.512124 -299.018032) (xy 206.552273 -298.979323)
			(xy 206.597631 -298.946872) (xy 206.647231 -298.921371) (xy 206.700015 -298.903364) (xy 206.754858 -298.893234)
			(xy 206.810592 -298.891197) (xy 206.866029 -298.897297) (xy 206.919986 -298.911403) (xy 206.971315 -298.933215)
			(xy 207.018921 -298.962269) (xy 207.061789 -298.997944) (xy 207.099006 -299.039481) (xy 207.129779 -299.085994)
			(xy 207.153451 -299.136491) (xy 207.169519 -299.189898) (xy 207.177639 -299.245074) (xy 207.178148 -299.27296)
			(xy 207.177639 -299.300846) (xy 207.169519 -299.356022) (xy 207.153451 -299.409429) (xy 207.129779 -299.459926)
			(xy 207.099006 -299.506439) (xy 207.061789 -299.547976) (xy 207.018921 -299.583651) (xy 206.971315 -299.612705)
			(xy 206.919986 -299.634517) (xy 206.866029 -299.648623) (xy 206.810592 -299.654723) (xy 206.754858 -299.652686)
			(xy 206.700015 -299.642556) (xy 206.647231 -299.624549) (xy 206.597631 -299.599048) (xy 206.552273 -299.566597)
			(xy 206.512124 -299.527888) (xy 206.478038 -299.483745) (xy 206.450742 -299.43511) (xy 206.430819 -299.383019)
			(xy 206.418693 -299.328582) (xy 206.414622 -299.27296) (xy 199.326012 -299.27296) (xy 199.32192 -299.298138)
			(xy 199.306336 -299.344819) (xy 199.283465 -299.388396) (xy 199.2539 -299.42774) (xy 199.218407 -299.461832)
			(xy 199.177904 -299.489788) (xy 199.133442 -299.510886) (xy 199.086171 -299.524578) (xy 199.037316 -299.53051)
			(xy 198.988141 -299.528529) (xy 198.939922 -299.518685) (xy 198.893906 -299.501233) (xy 198.851285 -299.476626)
			(xy 198.813164 -299.445501) (xy 198.780529 -299.408664) (xy 198.754226 -299.367068) (xy 198.734935 -299.321792)
			(xy 198.723158 -299.274008) (xy 198.719198 -299.224954) (xy 198.38035 -299.224954) (xy 198.379855 -299.249561)
			(xy 198.37196 -299.298138) (xy 198.356376 -299.344819) (xy 198.333505 -299.388396) (xy 198.30394 -299.42774)
			(xy 198.268447 -299.461832) (xy 198.227944 -299.489788) (xy 198.183482 -299.510886) (xy 198.136211 -299.524578)
			(xy 198.087356 -299.53051) (xy 198.038181 -299.528529) (xy 197.989962 -299.518685) (xy 197.943946 -299.501233)
			(xy 197.901325 -299.476626) (xy 197.863204 -299.445501) (xy 197.830569 -299.408664) (xy 197.804266 -299.367068)
			(xy 197.784975 -299.321792) (xy 197.773198 -299.274008) (xy 197.769238 -299.224954) (xy 197.43039 -299.224954)
			(xy 197.429895 -299.249561) (xy 197.422 -299.298138) (xy 197.406416 -299.344819) (xy 197.383545 -299.388396)
			(xy 197.35398 -299.42774) (xy 197.318487 -299.461832) (xy 197.277984 -299.489788) (xy 197.233522 -299.510886)
			(xy 197.186251 -299.524578) (xy 197.137396 -299.53051) (xy 197.088221 -299.528529) (xy 197.040002 -299.518685)
			(xy 196.993986 -299.501233) (xy 196.951365 -299.476626) (xy 196.913244 -299.445501) (xy 196.880609 -299.408664)
			(xy 196.854306 -299.367068) (xy 196.835015 -299.321792) (xy 196.823238 -299.274008) (xy 196.819278 -299.224954)
			(xy 196.480176 -299.224954) (xy 196.479681 -299.249561) (xy 196.471786 -299.298138) (xy 196.456202 -299.344819)
			(xy 196.433331 -299.388396) (xy 196.403766 -299.42774) (xy 196.368273 -299.461832) (xy 196.32777 -299.489788)
			(xy 196.283308 -299.510886) (xy 196.236037 -299.524578) (xy 196.187182 -299.53051) (xy 196.138007 -299.528529)
			(xy 196.089788 -299.518685) (xy 196.043772 -299.501233) (xy 196.001151 -299.476626) (xy 195.96303 -299.445501)
			(xy 195.930395 -299.408664) (xy 195.904092 -299.367068) (xy 195.884801 -299.321792) (xy 195.873024 -299.274008)
			(xy 195.869064 -299.224954) (xy 195.530216 -299.224954) (xy 195.529721 -299.249561) (xy 195.521826 -299.298138)
			(xy 195.506242 -299.344819) (xy 195.483371 -299.388396) (xy 195.453806 -299.42774) (xy 195.418313 -299.461832)
			(xy 195.37781 -299.489788) (xy 195.333348 -299.510886) (xy 195.286077 -299.524578) (xy 195.237222 -299.53051)
			(xy 195.188047 -299.528529) (xy 195.139828 -299.518685) (xy 195.093812 -299.501233) (xy 195.051191 -299.476626)
			(xy 195.01307 -299.445501) (xy 194.980435 -299.408664) (xy 194.954132 -299.367068) (xy 194.934841 -299.321792)
			(xy 194.923064 -299.274008) (xy 194.919104 -299.224954) (xy 194.580256 -299.224954) (xy 194.579761 -299.249561)
			(xy 194.571866 -299.298138) (xy 194.556282 -299.344819) (xy 194.533411 -299.388396) (xy 194.503846 -299.42774)
			(xy 194.468353 -299.461832) (xy 194.42785 -299.489788) (xy 194.383388 -299.510886) (xy 194.336117 -299.524578)
			(xy 194.287262 -299.53051) (xy 194.238087 -299.528529) (xy 194.189868 -299.518685) (xy 194.143852 -299.501233)
			(xy 194.101231 -299.476626) (xy 194.06311 -299.445501) (xy 194.030475 -299.408664) (xy 194.004172 -299.367068)
			(xy 193.984881 -299.321792) (xy 193.973104 -299.274008) (xy 193.969144 -299.224954) (xy 193.630296 -299.224954)
			(xy 193.629801 -299.249561) (xy 193.621906 -299.298138) (xy 193.606322 -299.344819) (xy 193.583451 -299.388396)
			(xy 193.553886 -299.42774) (xy 193.518393 -299.461832) (xy 193.47789 -299.489788) (xy 193.433428 -299.510886)
			(xy 193.386157 -299.524578) (xy 193.337302 -299.53051) (xy 193.288127 -299.528529) (xy 193.239908 -299.518685)
			(xy 193.193892 -299.501233) (xy 193.151271 -299.476626) (xy 193.11315 -299.445501) (xy 193.080515 -299.408664)
			(xy 193.054212 -299.367068) (xy 193.034921 -299.321792) (xy 193.023144 -299.274008) (xy 193.019184 -299.224954)
			(xy 192.680336 -299.224954) (xy 192.679841 -299.249561) (xy 192.671946 -299.298138) (xy 192.656362 -299.344819)
			(xy 192.633491 -299.388396) (xy 192.603926 -299.42774) (xy 192.568433 -299.461832) (xy 192.52793 -299.489788)
			(xy 192.483468 -299.510886) (xy 192.436197 -299.524578) (xy 192.387342 -299.53051) (xy 192.338167 -299.528529)
			(xy 192.289948 -299.518685) (xy 192.243932 -299.501233) (xy 192.201311 -299.476626) (xy 192.16319 -299.445501)
			(xy 192.130555 -299.408664) (xy 192.104252 -299.367068) (xy 192.084961 -299.321792) (xy 192.073184 -299.274008)
			(xy 192.069224 -299.224954) (xy 189.830202 -299.224954) (xy 189.829707 -299.249561) (xy 189.821812 -299.298138)
			(xy 189.806228 -299.344819) (xy 189.783357 -299.388396) (xy 189.753792 -299.42774) (xy 189.718299 -299.461832)
			(xy 189.677796 -299.489788) (xy 189.633334 -299.510886) (xy 189.586063 -299.524578) (xy 189.537208 -299.53051)
			(xy 189.488033 -299.528529) (xy 189.439814 -299.518685) (xy 189.393798 -299.501233) (xy 189.351177 -299.476626)
			(xy 189.313056 -299.445501) (xy 189.280421 -299.408664) (xy 189.254118 -299.367068) (xy 189.234827 -299.321792)
			(xy 189.22305 -299.274008) (xy 189.21909 -299.224954) (xy 188.880242 -299.224954) (xy 188.879747 -299.249561)
			(xy 188.871852 -299.298138) (xy 188.856268 -299.344819) (xy 188.833397 -299.388396) (xy 188.803832 -299.42774)
			(xy 188.768339 -299.461832) (xy 188.727836 -299.489788) (xy 188.683374 -299.510886) (xy 188.636103 -299.524578)
			(xy 188.587248 -299.53051) (xy 188.538073 -299.528529) (xy 188.489854 -299.518685) (xy 188.443838 -299.501233)
			(xy 188.401217 -299.476626) (xy 188.363096 -299.445501) (xy 188.330461 -299.408664) (xy 188.304158 -299.367068)
			(xy 188.284867 -299.321792) (xy 188.27309 -299.274008) (xy 188.26913 -299.224954) (xy 187.930282 -299.224954)
			(xy 187.929787 -299.249561) (xy 187.921892 -299.298138) (xy 187.906308 -299.344819) (xy 187.883437 -299.388396)
			(xy 187.853872 -299.42774) (xy 187.818379 -299.461832) (xy 187.777876 -299.489788) (xy 187.733414 -299.510886)
			(xy 187.686143 -299.524578) (xy 187.637288 -299.53051) (xy 187.588113 -299.528529) (xy 187.539894 -299.518685)
			(xy 187.493878 -299.501233) (xy 187.451257 -299.476626) (xy 187.413136 -299.445501) (xy 187.380501 -299.408664)
			(xy 187.354198 -299.367068) (xy 187.334907 -299.321792) (xy 187.32313 -299.274008) (xy 187.31917 -299.224954)
			(xy 186.980322 -299.224954) (xy 186.979827 -299.249561) (xy 186.971932 -299.298138) (xy 186.956348 -299.344819)
			(xy 186.933477 -299.388396) (xy 186.903912 -299.42774) (xy 186.868419 -299.461832) (xy 186.827916 -299.489788)
			(xy 186.783454 -299.510886) (xy 186.736183 -299.524578) (xy 186.687328 -299.53051) (xy 186.638153 -299.528529)
			(xy 186.589934 -299.518685) (xy 186.543918 -299.501233) (xy 186.501297 -299.476626) (xy 186.463176 -299.445501)
			(xy 186.430541 -299.408664) (xy 186.404238 -299.367068) (xy 186.384947 -299.321792) (xy 186.37317 -299.274008)
			(xy 186.36921 -299.224954) (xy 186.030362 -299.224954) (xy 186.029867 -299.249561) (xy 186.021972 -299.298138)
			(xy 186.006388 -299.344819) (xy 185.983517 -299.388396) (xy 185.953952 -299.42774) (xy 185.918459 -299.461832)
			(xy 185.877956 -299.489788) (xy 185.833494 -299.510886) (xy 185.786223 -299.524578) (xy 185.737368 -299.53051)
			(xy 185.688193 -299.528529) (xy 185.639974 -299.518685) (xy 185.593958 -299.501233) (xy 185.551337 -299.476626)
			(xy 185.513216 -299.445501) (xy 185.480581 -299.408664) (xy 185.454278 -299.367068) (xy 185.434987 -299.321792)
			(xy 185.42321 -299.274008) (xy 185.41925 -299.224954) (xy 185.080148 -299.224954) (xy 185.079705 -299.248951)
			(xy 185.072205 -299.296354) (xy 185.057381 -299.342) (xy 185.035598 -299.384766) (xy 185.007394 -299.423597)
			(xy 184.973463 -299.457538) (xy 184.934639 -299.485753) (xy 184.89188 -299.507548) (xy 184.846238 -299.522384)
			(xy 184.798837 -299.529899) (xy 184.77484 -299.530262) (xy 184.750934 -299.529801) (xy 184.703705 -299.522356)
			(xy 184.658214 -299.507641) (xy 184.615572 -299.486015) (xy 184.576822 -299.458008) (xy 184.542911 -299.424303)
			(xy 184.514666 -299.385726) (xy 184.49278 -299.343217) (xy 184.477786 -299.297817) (xy 184.470051 -299.250635)
			(xy 184.469532 -299.226732) (xy 184.469532 -299.2247) (xy 184.469637 -299.215659) (xy 184.470782 -299.197614)
			(xy 184.471818 -299.188632) (xy 184.472072 -299.185584) (xy 184.472072 -299.181266) (xy 184.471578 -299.171265)
			(xy 184.463911 -299.15279) (xy 184.449758 -299.138654) (xy 184.431274 -299.13101) (xy 184.421272 -299.130466)
			(xy 184.416954 -299.130466) (xy 184.40781 -299.126656) (xy 184.403248 -299.124645) (xy 184.394938 -299.119142)
			(xy 184.3913 -299.115734) (xy 184.38114 -299.105574) (xy 184.373742 -299.098729) (xy 184.355143 -299.091004)
			(xy 184.345072 -299.090588) (xy 184.230772 -299.090588) (xy 184.225692 -299.090842) (xy 184.221698 -299.091327)
			(xy 184.213917 -299.09337) (xy 184.210198 -299.094906) (xy 184.199784 -299.099732) (xy 184.135268 -299.169836)
			(xy 184.12841 -299.189648) (xy 184.129172 -299.200316) (xy 184.130188 -299.224954) (xy 184.129666 -299.250209)
			(xy 184.121353 -299.300031) (xy 184.104952 -299.347805) (xy 184.080911 -299.392228) (xy 184.049887 -299.432088)
			(xy 184.012725 -299.466298) (xy 183.970439 -299.493924) (xy 183.924183 -299.514214) (xy 183.875218 -299.526614)
			(xy 183.82488 -299.530785) (xy 183.774542 -299.526614) (xy 183.725577 -299.514214) (xy 183.679321 -299.493924)
			(xy 183.637035 -299.466298) (xy 183.599873 -299.432088) (xy 183.568849 -299.392228) (xy 183.544808 -299.347805)
			(xy 183.528407 -299.300031) (xy 183.520094 -299.250209) (xy 183.519572 -299.224954) (xy 183.520588 -299.200316)
			(xy 183.52135 -299.189648) (xy 183.514492 -299.169836) (xy 183.48198 -299.13453) (xy 183.45785 -299.108622)
			(xy 183.448706 -299.100748) (xy 183.44642 -299.099224) (xy 183.440059 -299.095247) (xy 183.425723 -299.090857)
			(xy 183.418226 -299.090588) (xy 183.280812 -299.090588) (xy 183.275732 -299.090842) (xy 183.271737 -299.091324)
			(xy 183.263953 -299.093361) (xy 183.260238 -299.094906) (xy 183.249824 -299.099732) (xy 183.185308 -299.169836)
			(xy 183.17845 -299.189648) (xy 183.179212 -299.200316) (xy 183.180228 -299.224954) (xy 183.179706 -299.250209)
			(xy 183.171393 -299.300031) (xy 183.154992 -299.347805) (xy 183.130951 -299.392228) (xy 183.099927 -299.432088)
			(xy 183.062765 -299.466298) (xy 183.020479 -299.493924) (xy 182.974223 -299.514214) (xy 182.925258 -299.526614)
			(xy 182.87492 -299.530785) (xy 182.824582 -299.526614) (xy 182.775617 -299.514214) (xy 182.729361 -299.493924)
			(xy 182.687075 -299.466298) (xy 182.649913 -299.432088) (xy 182.618889 -299.392228) (xy 182.594848 -299.347805)
			(xy 182.578447 -299.300031) (xy 182.570134 -299.250209) (xy 182.569612 -299.224954) (xy 182.570628 -299.200316)
			(xy 182.57139 -299.189648) (xy 182.564532 -299.169836) (xy 182.53202 -299.13453) (xy 182.50789 -299.108622)
			(xy 182.498746 -299.100748) (xy 182.49646 -299.099224) (xy 182.4901 -299.095242) (xy 182.475764 -299.09084)
			(xy 182.468266 -299.090588) (xy 182.330852 -299.090588) (xy 182.325772 -299.090842) (xy 182.321778 -299.091328)
			(xy 182.313998 -299.093374) (xy 182.310278 -299.094906) (xy 182.299864 -299.099732) (xy 182.235348 -299.169836)
			(xy 182.22849 -299.189648) (xy 182.229252 -299.200316) (xy 182.230268 -299.224954) (xy 182.229746 -299.250209)
			(xy 182.221433 -299.300031) (xy 182.205032 -299.347805) (xy 182.180991 -299.392228) (xy 182.149967 -299.432088)
			(xy 182.112805 -299.466298) (xy 182.070519 -299.493924) (xy 182.024263 -299.514214) (xy 181.975298 -299.526614)
			(xy 181.92496 -299.530785) (xy 181.874622 -299.526614) (xy 181.825657 -299.514214) (xy 181.779401 -299.493924)
			(xy 181.737115 -299.466298) (xy 181.699953 -299.432088) (xy 181.668929 -299.392228) (xy 181.644888 -299.347805)
			(xy 181.628487 -299.300031) (xy 181.620174 -299.250209) (xy 181.619652 -299.224954) (xy 181.620668 -299.200316)
			(xy 181.62143 -299.189648) (xy 181.614572 -299.169836) (xy 181.58206 -299.13453) (xy 181.55793 -299.108622)
			(xy 181.548786 -299.100748) (xy 181.5465 -299.099224) (xy 181.540139 -299.09525) (xy 181.525802 -299.090865)
			(xy 181.518306 -299.090588) (xy 181.380892 -299.090588) (xy 181.375812 -299.090842) (xy 181.371818 -299.091326)
			(xy 181.364035 -299.093366) (xy 181.360318 -299.094906) (xy 181.349904 -299.099732) (xy 181.285388 -299.169836)
			(xy 181.27853 -299.189648) (xy 181.279292 -299.200316) (xy 181.280308 -299.224954) (xy 181.279786 -299.250209)
			(xy 181.271473 -299.300031) (xy 181.255072 -299.347805) (xy 181.231031 -299.392228) (xy 181.200007 -299.432088)
			(xy 181.162845 -299.466298) (xy 181.120559 -299.493924) (xy 181.074303 -299.514214) (xy 181.025338 -299.526614)
			(xy 180.975 -299.530785) (xy 180.924662 -299.526614) (xy 180.875697 -299.514214) (xy 180.829441 -299.493924)
			(xy 180.787155 -299.466298) (xy 180.749993 -299.432088) (xy 180.718969 -299.392228) (xy 180.694928 -299.347805)
			(xy 180.678527 -299.300031) (xy 180.670214 -299.250209) (xy 180.669692 -299.224954) (xy 180.670708 -299.200316)
			(xy 180.67147 -299.189648) (xy 180.664612 -299.169836) (xy 180.6321 -299.13453) (xy 180.60797 -299.108622)
			(xy 180.598826 -299.100748) (xy 180.59654 -299.099224) (xy 180.59018 -299.095244) (xy 180.575844 -299.090849)
			(xy 180.568346 -299.090588) (xy 180.430932 -299.090588) (xy 180.425852 -299.090842) (xy 180.421859 -299.09133)
			(xy 180.41408 -299.093378) (xy 180.410358 -299.094906) (xy 180.399944 -299.099732) (xy 180.335428 -299.169836)
			(xy 180.32857 -299.189648) (xy 180.329332 -299.200316) (xy 180.330348 -299.224954) (xy 180.329826 -299.250209)
			(xy 180.321513 -299.300031) (xy 180.305112 -299.347805) (xy 180.281071 -299.392228) (xy 180.250047 -299.432088)
			(xy 180.212885 -299.466298) (xy 180.170599 -299.493924) (xy 180.124343 -299.514214) (xy 180.075378 -299.526614)
			(xy 180.02504 -299.530785) (xy 179.974702 -299.526614) (xy 179.925737 -299.514214) (xy 179.879481 -299.493924)
			(xy 179.837195 -299.466298) (xy 179.800033 -299.432088) (xy 179.769009 -299.392228) (xy 179.744968 -299.347805)
			(xy 179.728567 -299.300031) (xy 179.720254 -299.250209) (xy 179.719732 -299.224954) (xy 179.720748 -299.200316)
			(xy 179.72151 -299.189648) (xy 179.714652 -299.169836) (xy 179.68214 -299.13453) (xy 179.65801 -299.108622)
			(xy 179.648866 -299.100748) (xy 179.64658 -299.099224) (xy 179.640221 -299.095239) (xy 179.625885 -299.090832)
			(xy 179.618386 -299.090588) (xy 179.480972 -299.090588) (xy 179.475892 -299.090842) (xy 179.471898 -299.091327)
			(xy 179.464117 -299.09337) (xy 179.460398 -299.094906) (xy 179.449984 -299.099732) (xy 179.385468 -299.169836)
			(xy 179.37861 -299.189648) (xy 179.379372 -299.200316) (xy 179.380388 -299.224954) (xy 179.379866 -299.250209)
			(xy 179.371553 -299.300031) (xy 179.355152 -299.347805) (xy 179.331111 -299.392228) (xy 179.300087 -299.432088)
			(xy 179.262925 -299.466298) (xy 179.220639 -299.493924) (xy 179.174383 -299.514214) (xy 179.125418 -299.526614)
			(xy 179.07508 -299.530785) (xy 179.024742 -299.526614) (xy 178.975777 -299.514214) (xy 178.929521 -299.493924)
			(xy 178.887235 -299.466298) (xy 178.850073 -299.432088) (xy 178.819049 -299.392228) (xy 178.795008 -299.347805)
			(xy 178.778607 -299.300031) (xy 178.770294 -299.250209) (xy 178.769772 -299.224954) (xy 178.770788 -299.200316)
			(xy 178.77155 -299.189648) (xy 178.764692 -299.169836) (xy 178.73218 -299.13453) (xy 178.70805 -299.108622)
			(xy 178.698906 -299.100748) (xy 178.69662 -299.099224) (xy 178.690259 -299.095247) (xy 178.675923 -299.090857)
			(xy 178.668426 -299.090588) (xy 178.530758 -299.090588) (xy 178.525678 -299.090842) (xy 178.521684 -299.091328)
			(xy 178.513904 -299.093373) (xy 178.510184 -299.094906) (xy 178.49977 -299.099732) (xy 178.435254 -299.169836)
			(xy 178.428396 -299.189648) (xy 178.429158 -299.200316) (xy 178.430174 -299.224954) (xy 178.429652 -299.250209)
			(xy 178.421339 -299.300031) (xy 178.404938 -299.347805) (xy 178.380897 -299.392228) (xy 178.349873 -299.432088)
			(xy 178.312711 -299.466298) (xy 178.270425 -299.493924) (xy 178.224169 -299.514214) (xy 178.175204 -299.526614)
			(xy 178.124866 -299.530785) (xy 178.074528 -299.526614) (xy 178.025563 -299.514214) (xy 177.979307 -299.493924)
			(xy 177.937021 -299.466298) (xy 177.899859 -299.432088) (xy 177.868835 -299.392228) (xy 177.844794 -299.347805)
			(xy 177.828393 -299.300031) (xy 177.82008 -299.250209) (xy 177.819558 -299.224954) (xy 177.820574 -299.200316)
			(xy 177.821336 -299.189648) (xy 177.814478 -299.169836) (xy 177.781966 -299.13453) (xy 177.757836 -299.108622)
			(xy 177.748692 -299.100748) (xy 177.746406 -299.099224) (xy 177.740045 -299.095249) (xy 177.725709 -299.090863)
			(xy 177.718212 -299.090588) (xy 177.580798 -299.090588) (xy 177.575718 -299.090842) (xy 177.571724 -299.091325)
			(xy 177.56394 -299.093364) (xy 177.560224 -299.094906) (xy 177.54981 -299.099732) (xy 177.485294 -299.169836)
			(xy 177.478436 -299.189648) (xy 177.479198 -299.200316) (xy 177.480214 -299.224954) (xy 177.479692 -299.250209)
			(xy 177.471379 -299.300031) (xy 177.454978 -299.347805) (xy 177.430937 -299.392228) (xy 177.399913 -299.432088)
			(xy 177.362751 -299.466298) (xy 177.320465 -299.493924) (xy 177.274209 -299.514214) (xy 177.225244 -299.526614)
			(xy 177.174906 -299.530785) (xy 177.124568 -299.526614) (xy 177.075603 -299.514214) (xy 177.029347 -299.493924)
			(xy 176.987061 -299.466298) (xy 176.949899 -299.432088) (xy 176.918875 -299.392228) (xy 176.894834 -299.347805)
			(xy 176.878433 -299.300031) (xy 176.87012 -299.250209) (xy 176.869598 -299.224954) (xy 176.870614 -299.200316)
			(xy 176.871376 -299.189648) (xy 176.864518 -299.169836) (xy 176.832006 -299.13453) (xy 176.807876 -299.108622)
			(xy 176.798732 -299.100748) (xy 176.796446 -299.099224) (xy 176.790086 -299.095244) (xy 176.77575 -299.090846)
			(xy 176.768252 -299.090588) (xy 176.630838 -299.090588) (xy 176.625758 -299.090842) (xy 176.621765 -299.091329)
			(xy 176.613985 -299.093377) (xy 176.610264 -299.094906) (xy 176.59985 -299.099732) (xy 176.535334 -299.169836)
			(xy 176.528476 -299.189648) (xy 176.529238 -299.200316) (xy 176.530254 -299.224954) (xy 176.529732 -299.250209)
			(xy 176.521419 -299.300031) (xy 176.505018 -299.347805) (xy 176.480977 -299.392228) (xy 176.449953 -299.432088)
			(xy 176.412791 -299.466298) (xy 176.370505 -299.493924) (xy 176.324249 -299.514214) (xy 176.275284 -299.526614)
			(xy 176.224946 -299.530785) (xy 176.174608 -299.526614) (xy 176.125643 -299.514214) (xy 176.079387 -299.493924)
			(xy 176.037101 -299.466298) (xy 175.999939 -299.432088) (xy 175.968915 -299.392228) (xy 175.944874 -299.347805)
			(xy 175.928473 -299.300031) (xy 175.92016 -299.250209) (xy 175.919638 -299.224954) (xy 175.920654 -299.200316)
			(xy 175.921416 -299.189648) (xy 175.914558 -299.169836) (xy 175.882046 -299.13453) (xy 175.857916 -299.108622)
			(xy 175.848772 -299.100748) (xy 175.846486 -299.099224) (xy 175.840124 -299.095251) (xy 175.825788 -299.090871)
			(xy 175.818292 -299.090588) (xy 174.730918 -299.090588) (xy 174.725838 -299.090842) (xy 174.721843 -299.091324)
			(xy 174.714059 -299.09336) (xy 174.710344 -299.094906) (xy 174.69993 -299.099732) (xy 174.635414 -299.169836)
			(xy 174.628556 -299.189648) (xy 174.629318 -299.200316) (xy 174.630334 -299.224954) (xy 174.629812 -299.250209)
			(xy 174.621499 -299.300031) (xy 174.605098 -299.347805) (xy 174.581057 -299.392228) (xy 174.550033 -299.432088)
			(xy 174.512871 -299.466298) (xy 174.470585 -299.493924) (xy 174.424329 -299.514214) (xy 174.375364 -299.526614)
			(xy 174.325026 -299.530785) (xy 174.274688 -299.526614) (xy 174.225723 -299.514214) (xy 174.179467 -299.493924)
			(xy 174.137181 -299.466298) (xy 174.100019 -299.432088) (xy 174.068995 -299.392228) (xy 174.044954 -299.347805)
			(xy 174.028553 -299.300031) (xy 174.02024 -299.250209) (xy 174.019718 -299.224954) (xy 174.020734 -299.200316)
			(xy 174.021496 -299.189648) (xy 174.014638 -299.169836) (xy 173.982126 -299.13453) (xy 173.957996 -299.108622)
			(xy 173.948852 -299.100748) (xy 173.946566 -299.099224) (xy 173.940207 -299.095241) (xy 173.925871 -299.090838)
			(xy 173.918372 -299.090588) (xy 173.780958 -299.090588) (xy 173.775878 -299.090842) (xy 173.771884 -299.091328)
			(xy 173.764104 -299.093373) (xy 173.760384 -299.094906) (xy 173.74997 -299.099732) (xy 173.685454 -299.169836)
			(xy 173.678596 -299.189648) (xy 173.679358 -299.200316) (xy 173.680374 -299.224954) (xy 173.679852 -299.250209)
			(xy 173.671539 -299.300031) (xy 173.655138 -299.347805) (xy 173.631097 -299.392228) (xy 173.600073 -299.432088)
			(xy 173.562911 -299.466298) (xy 173.520625 -299.493924) (xy 173.474369 -299.514214) (xy 173.425404 -299.526614)
			(xy 173.375066 -299.530785) (xy 173.324728 -299.526614) (xy 173.275763 -299.514214) (xy 173.229507 -299.493924)
			(xy 173.187221 -299.466298) (xy 173.150059 -299.432088) (xy 173.119035 -299.392228) (xy 173.094994 -299.347805)
			(xy 173.078593 -299.300031) (xy 173.07028 -299.250209) (xy 173.069758 -299.224954) (xy 173.070774 -299.200316)
			(xy 173.071536 -299.189648) (xy 173.064678 -299.169836) (xy 173.032166 -299.13453) (xy 173.008036 -299.108622)
			(xy 172.998892 -299.100748) (xy 172.996606 -299.099224) (xy 172.990245 -299.095249) (xy 172.975909 -299.090863)
			(xy 172.968412 -299.090588) (xy 172.830744 -299.090588) (xy 172.825664 -299.090842) (xy 172.821671 -299.091329)
			(xy 172.813891 -299.093376) (xy 172.81017 -299.094906) (xy 172.799756 -299.099732) (xy 172.73524 -299.169836)
			(xy 172.728382 -299.189648) (xy 172.729144 -299.200316) (xy 172.73016 -299.224954) (xy 172.729638 -299.250209)
			(xy 172.721325 -299.300031) (xy 172.704924 -299.347805) (xy 172.680883 -299.392228) (xy 172.649859 -299.432088)
			(xy 172.612697 -299.466298) (xy 172.570411 -299.493924) (xy 172.524155 -299.514214) (xy 172.47519 -299.526614)
			(xy 172.424852 -299.530785) (xy 172.374514 -299.526614) (xy 172.325549 -299.514214) (xy 172.279293 -299.493924)
			(xy 172.237007 -299.466298) (xy 172.199845 -299.432088) (xy 172.168821 -299.392228) (xy 172.14478 -299.347805)
			(xy 172.128379 -299.300031) (xy 172.120066 -299.250209) (xy 172.119544 -299.224954) (xy 172.12056 -299.200316)
			(xy 172.121322 -299.189648) (xy 172.114464 -299.169836) (xy 172.081952 -299.13453) (xy 172.057822 -299.108622)
			(xy 172.048678 -299.100748) (xy 172.046392 -299.099224) (xy 172.04003 -299.095251) (xy 172.025694 -299.090868)
			(xy 172.018198 -299.090588) (xy 171.880784 -299.090588) (xy 171.875704 -299.090842) (xy 171.87171 -299.091326)
			(xy 171.863928 -299.093367) (xy 171.86021 -299.094906) (xy 171.849796 -299.099732) (xy 171.78528 -299.169836)
			(xy 171.778422 -299.189648) (xy 171.779184 -299.200316) (xy 171.7802 -299.224954) (xy 171.779678 -299.250209)
			(xy 171.771365 -299.300031) (xy 171.754964 -299.347805) (xy 171.730923 -299.392228) (xy 171.699899 -299.432088)
			(xy 171.662737 -299.466298) (xy 171.620451 -299.493924) (xy 171.574195 -299.514214) (xy 171.52523 -299.526614)
			(xy 171.474892 -299.530785) (xy 171.424554 -299.526614) (xy 171.375589 -299.514214) (xy 171.329333 -299.493924)
			(xy 171.287047 -299.466298) (xy 171.249885 -299.432088) (xy 171.218861 -299.392228) (xy 171.19482 -299.347805)
			(xy 171.178419 -299.300031) (xy 171.170106 -299.250209) (xy 171.169584 -299.224954) (xy 171.1706 -299.200316)
			(xy 171.171362 -299.189648) (xy 171.164504 -299.169836) (xy 171.131992 -299.13453) (xy 171.107862 -299.108622)
			(xy 171.098718 -299.100748) (xy 171.096432 -299.099224) (xy 171.090072 -299.095245) (xy 171.075735 -299.090852)
			(xy 171.068238 -299.090588) (xy 170.930824 -299.090588) (xy 170.925744 -299.090842) (xy 170.921749 -299.091323)
			(xy 170.913964 -299.093359) (xy 170.91025 -299.094906) (xy 170.899836 -299.099732) (xy 170.83532 -299.169836)
			(xy 170.828462 -299.189648) (xy 170.829224 -299.200316) (xy 170.83024 -299.224954) (xy 170.829718 -299.250209)
			(xy 170.821405 -299.300031) (xy 170.805004 -299.347805) (xy 170.780963 -299.392228) (xy 170.749939 -299.432088)
			(xy 170.712777 -299.466298) (xy 170.670491 -299.493924) (xy 170.624235 -299.514214) (xy 170.57527 -299.526614)
			(xy 170.524932 -299.530785) (xy 170.474594 -299.526614) (xy 170.425629 -299.514214) (xy 170.379373 -299.493924)
			(xy 170.337087 -299.466298) (xy 170.299925 -299.432088) (xy 170.268901 -299.392228) (xy 170.24486 -299.347805)
			(xy 170.228459 -299.300031) (xy 170.220146 -299.250209) (xy 170.219624 -299.224954) (xy 170.22064 -299.200316)
			(xy 170.221402 -299.189648) (xy 170.214544 -299.169836) (xy 170.182032 -299.13453) (xy 170.157902 -299.108622)
			(xy 170.148758 -299.100748) (xy 170.146472 -299.099224) (xy 170.140113 -299.09524) (xy 170.125777 -299.090835)
			(xy 170.118278 -299.090588) (xy 169.980864 -299.090588) (xy 169.975784 -299.090842) (xy 169.97179 -299.091328)
			(xy 169.964009 -299.093372) (xy 169.96029 -299.094906) (xy 169.949876 -299.099732) (xy 169.88536 -299.169836)
			(xy 169.878502 -299.189648) (xy 169.879264 -299.200316) (xy 169.88028 -299.224954) (xy 169.879758 -299.250209)
			(xy 169.871445 -299.300031) (xy 169.855044 -299.347805) (xy 169.831003 -299.392228) (xy 169.799979 -299.432088)
			(xy 169.762817 -299.466298) (xy 169.720531 -299.493924) (xy 169.674275 -299.514214) (xy 169.62531 -299.526614)
			(xy 169.574972 -299.530785) (xy 169.524634 -299.526614) (xy 169.475669 -299.514214) (xy 169.429413 -299.493924)
			(xy 169.387127 -299.466298) (xy 169.349965 -299.432088) (xy 169.318941 -299.392228) (xy 169.2949 -299.347805)
			(xy 169.278499 -299.300031) (xy 169.270186 -299.250209) (xy 169.269664 -299.224954) (xy 169.27068 -299.200316)
			(xy 169.271442 -299.189648) (xy 169.264584 -299.169836) (xy 169.232072 -299.13453) (xy 169.207942 -299.108622)
			(xy 169.198798 -299.100748) (xy 169.196512 -299.099224) (xy 169.190151 -299.095248) (xy 169.175815 -299.09086)
			(xy 169.168318 -299.090588) (xy 169.030904 -299.090588) (xy 169.025824 -299.090842) (xy 169.021829 -299.091325)
			(xy 169.014046 -299.093363) (xy 169.01033 -299.094906) (xy 168.999916 -299.099732) (xy 168.9354 -299.169836)
			(xy 168.928542 -299.189648) (xy 168.929304 -299.200316) (xy 168.93032 -299.224954) (xy 168.929798 -299.250209)
			(xy 168.921485 -299.300031) (xy 168.905084 -299.347805) (xy 168.881043 -299.392228) (xy 168.850019 -299.432088)
			(xy 168.812857 -299.466298) (xy 168.770571 -299.493924) (xy 168.724315 -299.514214) (xy 168.67535 -299.526614)
			(xy 168.625012 -299.530785) (xy 168.574674 -299.526614) (xy 168.525709 -299.514214) (xy 168.479453 -299.493924)
			(xy 168.437167 -299.466298) (xy 168.400005 -299.432088) (xy 168.368981 -299.392228) (xy 168.34494 -299.347805)
			(xy 168.328539 -299.300031) (xy 168.320226 -299.250209) (xy 168.319704 -299.224954) (xy 168.32072 -299.200316)
			(xy 168.321482 -299.189648) (xy 168.314624 -299.169836) (xy 168.282112 -299.13453) (xy 168.257982 -299.108622)
			(xy 168.248838 -299.100748) (xy 168.246552 -299.099224) (xy 168.240192 -299.095243) (xy 168.225856 -299.090844)
			(xy 168.218358 -299.090588) (xy 168.080944 -299.090588) (xy 168.075864 -299.090842) (xy 168.071871 -299.091329)
			(xy 168.064091 -299.093376) (xy 168.06037 -299.094906) (xy 168.049956 -299.099732) (xy 167.98544 -299.169836)
			(xy 167.978582 -299.189648) (xy 167.979344 -299.200316) (xy 167.98036 -299.224954) (xy 167.979838 -299.250209)
			(xy 167.971525 -299.300031) (xy 167.955124 -299.347805) (xy 167.931083 -299.392228) (xy 167.900059 -299.432088)
			(xy 167.862897 -299.466298) (xy 167.820611 -299.493924) (xy 167.774355 -299.514214) (xy 167.72539 -299.526614)
			(xy 167.675052 -299.530785) (xy 167.624714 -299.526614) (xy 167.575749 -299.514214) (xy 167.529493 -299.493924)
			(xy 167.487207 -299.466298) (xy 167.450045 -299.432088) (xy 167.419021 -299.392228) (xy 167.39498 -299.347805)
			(xy 167.378579 -299.300031) (xy 167.370266 -299.250209) (xy 167.369744 -299.224954) (xy 167.37076 -299.200316)
			(xy 167.371522 -299.189648) (xy 167.364664 -299.169836) (xy 167.332152 -299.13453) (xy 167.308022 -299.108622)
			(xy 167.298878 -299.100748) (xy 167.296592 -299.099224) (xy 167.29023 -299.095251) (xy 167.275894 -299.090868)
			(xy 167.268398 -299.090588) (xy 167.130984 -299.090588) (xy 167.125904 -299.090842) (xy 167.12191 -299.091326)
			(xy 167.114128 -299.093367) (xy 167.11041 -299.094906) (xy 167.099996 -299.099732) (xy 167.03548 -299.169836)
			(xy 167.028622 -299.189648) (xy 167.029384 -299.200316) (xy 167.0304 -299.224954) (xy 167.029957 -299.248949)
			(xy 167.022456 -299.29635) (xy 167.007632 -299.341993) (xy 166.985849 -299.384755) (xy 166.957644 -299.423582)
			(xy 166.923711 -299.457519) (xy 166.884888 -299.485729) (xy 166.842128 -299.507517) (xy 166.796487 -299.522347)
			(xy 166.749087 -299.529854) (xy 166.725092 -299.530262) (xy 166.698174 -299.529695) (xy 166.645169 -299.52027)
			(xy 166.594632 -299.501712) (xy 166.548123 -299.474596) (xy 166.527226 -299.457618) (xy 166.526718 -299.45711)
			(xy 166.509954 -299.443394) (xy 166.502933 -299.438168) (xy 166.486442 -299.432337) (xy 166.477696 -299.431964)
			(xy 166.476172 -299.431964) (xy 166.407846 -299.43298) (xy 166.398055 -299.433627) (xy 166.38003 -299.441338)
			(xy 166.372794 -299.447966) (xy 166.3446 -299.47616) (xy 166.341552 -299.479208) (xy 166.143432 -299.677328)
			(xy 166.1384 -299.682749) (xy 166.131429 -299.695786) (xy 166.129716 -299.702982) (xy 166.128192 -299.710094)
			(xy 166.128192 -299.76445) (xy 204.14183 -299.76445) (xy 204.145901 -299.708828) (xy 204.158027 -299.654391)
			(xy 204.17795 -299.6023) (xy 204.205246 -299.553665) (xy 204.239332 -299.509522) (xy 204.279481 -299.470813)
			(xy 204.324839 -299.438362) (xy 204.374439 -299.412861) (xy 204.427223 -299.394854) (xy 204.482066 -299.384724)
			(xy 204.5378 -299.382687) (xy 204.593237 -299.388787) (xy 204.647194 -299.402893) (xy 204.698523 -299.424705)
			(xy 204.746129 -299.453759) (xy 204.788997 -299.489434) (xy 204.826214 -299.530971) (xy 204.856987 -299.577484)
			(xy 204.880659 -299.627981) (xy 204.896727 -299.681388) (xy 204.904847 -299.736564) (xy 204.905356 -299.76445)
			(xy 204.905078 -299.77969) (xy 208.738468 -299.77969) (xy 208.742539 -299.724068) (xy 208.754665 -299.669631)
			(xy 208.774588 -299.61754) (xy 208.801884 -299.568905) (xy 208.83597 -299.524762) (xy 208.876119 -299.486053)
			(xy 208.921477 -299.453602) (xy 208.971077 -299.428101) (xy 209.023861 -299.410094) (xy 209.078704 -299.399964)
			(xy 209.134438 -299.397927) (xy 209.189875 -299.404027) (xy 209.243832 -299.418133) (xy 209.295161 -299.439945)
			(xy 209.342767 -299.468999) (xy 209.385635 -299.504674) (xy 209.422852 -299.546211) (xy 209.453625 -299.592724)
			(xy 209.477297 -299.643221) (xy 209.493365 -299.696628) (xy 209.501485 -299.751804) (xy 209.501994 -299.77969)
			(xy 209.501485 -299.807576) (xy 209.493365 -299.862752) (xy 209.477297 -299.916159) (xy 209.453625 -299.966656)
			(xy 209.422852 -300.013169) (xy 209.385635 -300.054706) (xy 209.342767 -300.090381) (xy 209.295161 -300.119435)
			(xy 209.243832 -300.141247) (xy 209.189875 -300.155353) (xy 209.134438 -300.161453) (xy 209.078704 -300.159416)
			(xy 209.023861 -300.149286) (xy 208.971077 -300.131279) (xy 208.921477 -300.105778) (xy 208.876119 -300.073327)
			(xy 208.83597 -300.034618) (xy 208.801884 -299.990475) (xy 208.774588 -299.94184) (xy 208.754665 -299.889749)
			(xy 208.742539 -299.835312) (xy 208.738468 -299.77969) (xy 204.905078 -299.77969) (xy 204.904847 -299.792336)
			(xy 204.896727 -299.847512) (xy 204.880659 -299.900919) (xy 204.856987 -299.951416) (xy 204.826214 -299.997929)
			(xy 204.788997 -300.039466) (xy 204.746129 -300.075141) (xy 204.698523 -300.104195) (xy 204.647194 -300.126007)
			(xy 204.593237 -300.140113) (xy 204.5378 -300.146213) (xy 204.482066 -300.144176) (xy 204.427223 -300.134046)
			(xy 204.374439 -300.116039) (xy 204.324839 -300.090538) (xy 204.279481 -300.058087) (xy 204.239332 -300.019378)
			(xy 204.205246 -299.975235) (xy 204.17795 -299.9266) (xy 204.158027 -299.874509) (xy 204.145901 -299.820072)
			(xy 204.14183 -299.76445) (xy 166.128192 -299.76445) (xy 166.128192 -300.174914) (xy 166.419288 -300.174914)
			(xy 166.423248 -300.12586) (xy 166.435025 -300.078076) (xy 166.454316 -300.0328) (xy 166.480619 -299.991204)
			(xy 166.513254 -299.954367) (xy 166.551375 -299.923242) (xy 166.593996 -299.898635) (xy 166.640012 -299.881183)
			(xy 166.688231 -299.871339) (xy 166.737406 -299.869358) (xy 166.786261 -299.87529) (xy 166.833532 -299.888982)
			(xy 166.877994 -299.91008) (xy 166.918497 -299.938036) (xy 166.95399 -299.972128) (xy 166.983555 -300.011472)
			(xy 167.006426 -300.055049) (xy 167.02201 -300.10173) (xy 167.029905 -300.150307) (xy 167.0304 -300.174914)
			(xy 167.369248 -300.174914) (xy 167.373208 -300.12586) (xy 167.384985 -300.078076) (xy 167.404276 -300.0328)
			(xy 167.430579 -299.991204) (xy 167.463214 -299.954367) (xy 167.501335 -299.923242) (xy 167.543956 -299.898635)
			(xy 167.589972 -299.881183) (xy 167.638191 -299.871339) (xy 167.687366 -299.869358) (xy 167.736221 -299.87529)
			(xy 167.783492 -299.888982) (xy 167.827954 -299.91008) (xy 167.868457 -299.938036) (xy 167.90395 -299.972128)
			(xy 167.933515 -300.011472) (xy 167.956386 -300.055049) (xy 167.97197 -300.10173) (xy 167.979865 -300.150307)
			(xy 167.98036 -300.174914) (xy 168.319208 -300.174914) (xy 168.323168 -300.12586) (xy 168.334945 -300.078076)
			(xy 168.354236 -300.0328) (xy 168.380539 -299.991204) (xy 168.413174 -299.954367) (xy 168.451295 -299.923242)
			(xy 168.493916 -299.898635) (xy 168.539932 -299.881183) (xy 168.588151 -299.871339) (xy 168.637326 -299.869358)
			(xy 168.686181 -299.87529) (xy 168.733452 -299.888982) (xy 168.777914 -299.91008) (xy 168.818417 -299.938036)
			(xy 168.85391 -299.972128) (xy 168.883475 -300.011472) (xy 168.906346 -300.055049) (xy 168.92193 -300.10173)
			(xy 168.929825 -300.150307) (xy 168.93032 -300.174914) (xy 169.269168 -300.174914) (xy 169.273128 -300.12586)
			(xy 169.284905 -300.078076) (xy 169.304196 -300.0328) (xy 169.330499 -299.991204) (xy 169.363134 -299.954367)
			(xy 169.401255 -299.923242) (xy 169.443876 -299.898635) (xy 169.489892 -299.881183) (xy 169.538111 -299.871339)
			(xy 169.587286 -299.869358) (xy 169.636141 -299.87529) (xy 169.683412 -299.888982) (xy 169.727874 -299.91008)
			(xy 169.768377 -299.938036) (xy 169.80387 -299.972128) (xy 169.833435 -300.011472) (xy 169.856306 -300.055049)
			(xy 169.87189 -300.10173) (xy 169.879785 -300.150307) (xy 169.88028 -300.174914) (xy 170.219128 -300.174914)
			(xy 170.223088 -300.12586) (xy 170.234865 -300.078076) (xy 170.254156 -300.0328) (xy 170.280459 -299.991204)
			(xy 170.313094 -299.954367) (xy 170.351215 -299.923242) (xy 170.393836 -299.898635) (xy 170.439852 -299.881183)
			(xy 170.488071 -299.871339) (xy 170.537246 -299.869358) (xy 170.586101 -299.87529) (xy 170.633372 -299.888982)
			(xy 170.677834 -299.91008) (xy 170.718337 -299.938036) (xy 170.75383 -299.972128) (xy 170.783395 -300.011472)
			(xy 170.806266 -300.055049) (xy 170.82185 -300.10173) (xy 170.829745 -300.150307) (xy 170.83024 -300.174914)
			(xy 171.169088 -300.174914) (xy 171.173048 -300.12586) (xy 171.184825 -300.078076) (xy 171.204116 -300.0328)
			(xy 171.230419 -299.991204) (xy 171.263054 -299.954367) (xy 171.301175 -299.923242) (xy 171.343796 -299.898635)
			(xy 171.389812 -299.881183) (xy 171.438031 -299.871339) (xy 171.487206 -299.869358) (xy 171.536061 -299.87529)
			(xy 171.583332 -299.888982) (xy 171.627794 -299.91008) (xy 171.668297 -299.938036) (xy 171.70379 -299.972128)
			(xy 171.733355 -300.011472) (xy 171.756226 -300.055049) (xy 171.77181 -300.10173) (xy 171.779705 -300.150307)
			(xy 171.7802 -300.174914) (xy 172.119048 -300.174914) (xy 172.123008 -300.12586) (xy 172.134785 -300.078076)
			(xy 172.154076 -300.0328) (xy 172.180379 -299.991204) (xy 172.213014 -299.954367) (xy 172.251135 -299.923242)
			(xy 172.293756 -299.898635) (xy 172.339772 -299.881183) (xy 172.387991 -299.871339) (xy 172.437166 -299.869358)
			(xy 172.486021 -299.87529) (xy 172.533292 -299.888982) (xy 172.577754 -299.91008) (xy 172.618257 -299.938036)
			(xy 172.65375 -299.972128) (xy 172.683315 -300.011472) (xy 172.706186 -300.055049) (xy 172.72177 -300.10173)
			(xy 172.729665 -300.150307) (xy 172.73016 -300.174914) (xy 173.069262 -300.174914) (xy 173.073222 -300.12586)
			(xy 173.084999 -300.078076) (xy 173.10429 -300.0328) (xy 173.130593 -299.991204) (xy 173.163228 -299.954367)
			(xy 173.201349 -299.923242) (xy 173.24397 -299.898635) (xy 173.289986 -299.881183) (xy 173.338205 -299.871339)
			(xy 173.38738 -299.869358) (xy 173.436235 -299.87529) (xy 173.483506 -299.888982) (xy 173.527968 -299.91008)
			(xy 173.568471 -299.938036) (xy 173.603964 -299.972128) (xy 173.633529 -300.011472) (xy 173.6564 -300.055049)
			(xy 173.671984 -300.10173) (xy 173.679879 -300.150307) (xy 173.680374 -300.174914) (xy 174.019222 -300.174914)
			(xy 174.023182 -300.12586) (xy 174.034959 -300.078076) (xy 174.05425 -300.0328) (xy 174.080553 -299.991204)
			(xy 174.113188 -299.954367) (xy 174.151309 -299.923242) (xy 174.19393 -299.898635) (xy 174.239946 -299.881183)
			(xy 174.288165 -299.871339) (xy 174.33734 -299.869358) (xy 174.386195 -299.87529) (xy 174.433466 -299.888982)
			(xy 174.477928 -299.91008) (xy 174.518431 -299.938036) (xy 174.553924 -299.972128) (xy 174.583489 -300.011472)
			(xy 174.60636 -300.055049) (xy 174.621944 -300.10173) (xy 174.629839 -300.150307) (xy 174.630334 -300.174914)
			(xy 175.919142 -300.174914) (xy 175.923102 -300.12586) (xy 175.934879 -300.078076) (xy 175.95417 -300.0328)
			(xy 175.980473 -299.991204) (xy 176.013108 -299.954367) (xy 176.051229 -299.923242) (xy 176.09385 -299.898635)
			(xy 176.139866 -299.881183) (xy 176.188085 -299.871339) (xy 176.23726 -299.869358) (xy 176.286115 -299.87529)
			(xy 176.333386 -299.888982) (xy 176.377848 -299.91008) (xy 176.418351 -299.938036) (xy 176.453844 -299.972128)
			(xy 176.483409 -300.011472) (xy 176.50628 -300.055049) (xy 176.521864 -300.10173) (xy 176.529759 -300.150307)
			(xy 176.530254 -300.174914) (xy 176.869102 -300.174914) (xy 176.873062 -300.12586) (xy 176.884839 -300.078076)
			(xy 176.90413 -300.0328) (xy 176.930433 -299.991204) (xy 176.963068 -299.954367) (xy 177.001189 -299.923242)
			(xy 177.04381 -299.898635) (xy 177.089826 -299.881183) (xy 177.138045 -299.871339) (xy 177.18722 -299.869358)
			(xy 177.236075 -299.87529) (xy 177.283346 -299.888982) (xy 177.327808 -299.91008) (xy 177.368311 -299.938036)
			(xy 177.403804 -299.972128) (xy 177.433369 -300.011472) (xy 177.45624 -300.055049) (xy 177.471824 -300.10173)
			(xy 177.479719 -300.150307) (xy 177.480214 -300.174914) (xy 177.819062 -300.174914) (xy 177.823022 -300.12586)
			(xy 177.834799 -300.078076) (xy 177.85409 -300.0328) (xy 177.880393 -299.991204) (xy 177.913028 -299.954367)
			(xy 177.951149 -299.923242) (xy 177.99377 -299.898635) (xy 178.039786 -299.881183) (xy 178.088005 -299.871339)
			(xy 178.13718 -299.869358) (xy 178.186035 -299.87529) (xy 178.233306 -299.888982) (xy 178.277768 -299.91008)
			(xy 178.318271 -299.938036) (xy 178.353764 -299.972128) (xy 178.383329 -300.011472) (xy 178.4062 -300.055049)
			(xy 178.421784 -300.10173) (xy 178.429679 -300.150307) (xy 178.430174 -300.174914) (xy 178.769276 -300.174914)
			(xy 178.773236 -300.12586) (xy 178.785013 -300.078076) (xy 178.804304 -300.0328) (xy 178.830607 -299.991204)
			(xy 178.863242 -299.954367) (xy 178.901363 -299.923242) (xy 178.943984 -299.898635) (xy 178.99 -299.881183)
			(xy 179.038219 -299.871339) (xy 179.087394 -299.869358) (xy 179.136249 -299.87529) (xy 179.18352 -299.888982)
			(xy 179.227982 -299.91008) (xy 179.268485 -299.938036) (xy 179.303978 -299.972128) (xy 179.333543 -300.011472)
			(xy 179.356414 -300.055049) (xy 179.371998 -300.10173) (xy 179.379893 -300.150307) (xy 179.380388 -300.174914)
			(xy 179.719236 -300.174914) (xy 179.723196 -300.12586) (xy 179.734973 -300.078076) (xy 179.754264 -300.0328)
			(xy 179.780567 -299.991204) (xy 179.813202 -299.954367) (xy 179.851323 -299.923242) (xy 179.893944 -299.898635)
			(xy 179.93996 -299.881183) (xy 179.988179 -299.871339) (xy 180.037354 -299.869358) (xy 180.086209 -299.87529)
			(xy 180.13348 -299.888982) (xy 180.177942 -299.91008) (xy 180.218445 -299.938036) (xy 180.253938 -299.972128)
			(xy 180.283503 -300.011472) (xy 180.306374 -300.055049) (xy 180.321958 -300.10173) (xy 180.329853 -300.150307)
			(xy 180.330348 -300.174914) (xy 180.669196 -300.174914) (xy 180.673156 -300.12586) (xy 180.684933 -300.078076)
			(xy 180.704224 -300.0328) (xy 180.730527 -299.991204) (xy 180.763162 -299.954367) (xy 180.801283 -299.923242)
			(xy 180.843904 -299.898635) (xy 180.88992 -299.881183) (xy 180.938139 -299.871339) (xy 180.987314 -299.869358)
			(xy 181.036169 -299.87529) (xy 181.08344 -299.888982) (xy 181.127902 -299.91008) (xy 181.168405 -299.938036)
			(xy 181.203898 -299.972128) (xy 181.233463 -300.011472) (xy 181.256334 -300.055049) (xy 181.271918 -300.10173)
			(xy 181.279813 -300.150307) (xy 181.280308 -300.174914) (xy 181.619156 -300.174914) (xy 181.623116 -300.12586)
			(xy 181.634893 -300.078076) (xy 181.654184 -300.0328) (xy 181.680487 -299.991204) (xy 181.713122 -299.954367)
			(xy 181.751243 -299.923242) (xy 181.793864 -299.898635) (xy 181.83988 -299.881183) (xy 181.888099 -299.871339)
			(xy 181.937274 -299.869358) (xy 181.986129 -299.87529) (xy 182.0334 -299.888982) (xy 182.077862 -299.91008)
			(xy 182.118365 -299.938036) (xy 182.153858 -299.972128) (xy 182.183423 -300.011472) (xy 182.206294 -300.055049)
			(xy 182.221878 -300.10173) (xy 182.229773 -300.150307) (xy 182.230268 -300.174914) (xy 182.569116 -300.174914)
			(xy 182.573076 -300.12586) (xy 182.584853 -300.078076) (xy 182.604144 -300.0328) (xy 182.630447 -299.991204)
			(xy 182.663082 -299.954367) (xy 182.701203 -299.923242) (xy 182.743824 -299.898635) (xy 182.78984 -299.881183)
			(xy 182.838059 -299.871339) (xy 182.887234 -299.869358) (xy 182.936089 -299.87529) (xy 182.98336 -299.888982)
			(xy 183.027822 -299.91008) (xy 183.068325 -299.938036) (xy 183.103818 -299.972128) (xy 183.133383 -300.011472)
			(xy 183.156254 -300.055049) (xy 183.171838 -300.10173) (xy 183.179733 -300.150307) (xy 183.180228 -300.174914)
			(xy 183.519076 -300.174914) (xy 183.523036 -300.12586) (xy 183.534813 -300.078076) (xy 183.554104 -300.0328)
			(xy 183.580407 -299.991204) (xy 183.613042 -299.954367) (xy 183.651163 -299.923242) (xy 183.693784 -299.898635)
			(xy 183.7398 -299.881183) (xy 183.788019 -299.871339) (xy 183.837194 -299.869358) (xy 183.886049 -299.87529)
			(xy 183.93332 -299.888982) (xy 183.977782 -299.91008) (xy 184.018285 -299.938036) (xy 184.053778 -299.972128)
			(xy 184.083343 -300.011472) (xy 184.106214 -300.055049) (xy 184.121798 -300.10173) (xy 184.129693 -300.150307)
			(xy 184.130188 -300.174914) (xy 184.469036 -300.174914) (xy 184.472996 -300.12586) (xy 184.484773 -300.078076)
			(xy 184.504064 -300.0328) (xy 184.530367 -299.991204) (xy 184.563002 -299.954367) (xy 184.601123 -299.923242)
			(xy 184.643744 -299.898635) (xy 184.68976 -299.881183) (xy 184.737979 -299.871339) (xy 184.787154 -299.869358)
			(xy 184.836009 -299.87529) (xy 184.88328 -299.888982) (xy 184.927742 -299.91008) (xy 184.968245 -299.938036)
			(xy 185.003738 -299.972128) (xy 185.033303 -300.011472) (xy 185.056174 -300.055049) (xy 185.071758 -300.10173)
			(xy 185.079653 -300.150307) (xy 185.080148 -300.174914) (xy 185.41925 -300.174914) (xy 185.42321 -300.12586)
			(xy 185.434987 -300.078076) (xy 185.454278 -300.0328) (xy 185.480581 -299.991204) (xy 185.513216 -299.954367)
			(xy 185.551337 -299.923242) (xy 185.593958 -299.898635) (xy 185.639974 -299.881183) (xy 185.688193 -299.871339)
			(xy 185.737368 -299.869358) (xy 185.786223 -299.87529) (xy 185.833494 -299.888982) (xy 185.877956 -299.91008)
			(xy 185.918459 -299.938036) (xy 185.953952 -299.972128) (xy 185.983517 -300.011472) (xy 186.006388 -300.055049)
			(xy 186.021972 -300.10173) (xy 186.029867 -300.150307) (xy 186.030362 -300.174914) (xy 186.36921 -300.174914)
			(xy 186.37317 -300.12586) (xy 186.384947 -300.078076) (xy 186.404238 -300.0328) (xy 186.430541 -299.991204)
			(xy 186.463176 -299.954367) (xy 186.501297 -299.923242) (xy 186.543918 -299.898635) (xy 186.589934 -299.881183)
			(xy 186.638153 -299.871339) (xy 186.687328 -299.869358) (xy 186.736183 -299.87529) (xy 186.783454 -299.888982)
			(xy 186.827916 -299.91008) (xy 186.868419 -299.938036) (xy 186.903912 -299.972128) (xy 186.933477 -300.011472)
			(xy 186.956348 -300.055049) (xy 186.971932 -300.10173) (xy 186.979827 -300.150307) (xy 186.980322 -300.174914)
			(xy 187.31917 -300.174914) (xy 187.32313 -300.12586) (xy 187.334907 -300.078076) (xy 187.354198 -300.0328)
			(xy 187.380501 -299.991204) (xy 187.413136 -299.954367) (xy 187.451257 -299.923242) (xy 187.493878 -299.898635)
			(xy 187.539894 -299.881183) (xy 187.588113 -299.871339) (xy 187.637288 -299.869358) (xy 187.686143 -299.87529)
			(xy 187.733414 -299.888982) (xy 187.777876 -299.91008) (xy 187.818379 -299.938036) (xy 187.853872 -299.972128)
			(xy 187.883437 -300.011472) (xy 187.906308 -300.055049) (xy 187.921892 -300.10173) (xy 187.929787 -300.150307)
			(xy 187.930282 -300.174914) (xy 188.26913 -300.174914) (xy 188.27309 -300.12586) (xy 188.284867 -300.078076)
			(xy 188.304158 -300.0328) (xy 188.330461 -299.991204) (xy 188.363096 -299.954367) (xy 188.401217 -299.923242)
			(xy 188.443838 -299.898635) (xy 188.489854 -299.881183) (xy 188.538073 -299.871339) (xy 188.587248 -299.869358)
			(xy 188.636103 -299.87529) (xy 188.683374 -299.888982) (xy 188.727836 -299.91008) (xy 188.768339 -299.938036)
			(xy 188.803832 -299.972128) (xy 188.833397 -300.011472) (xy 188.856268 -300.055049) (xy 188.871852 -300.10173)
			(xy 188.879747 -300.150307) (xy 188.880242 -300.174914) (xy 189.21909 -300.174914) (xy 189.22305 -300.12586)
			(xy 189.234827 -300.078076) (xy 189.254118 -300.0328) (xy 189.280421 -299.991204) (xy 189.313056 -299.954367)
			(xy 189.351177 -299.923242) (xy 189.393798 -299.898635) (xy 189.439814 -299.881183) (xy 189.488033 -299.871339)
			(xy 189.537208 -299.869358) (xy 189.586063 -299.87529) (xy 189.633334 -299.888982) (xy 189.677796 -299.91008)
			(xy 189.718299 -299.938036) (xy 189.753792 -299.972128) (xy 189.783357 -300.011472) (xy 189.806228 -300.055049)
			(xy 189.821812 -300.10173) (xy 189.829707 -300.150307) (xy 189.830202 -300.174914) (xy 190.16905 -300.174914)
			(xy 190.17301 -300.12586) (xy 190.184787 -300.078076) (xy 190.204078 -300.0328) (xy 190.230381 -299.991204)
			(xy 190.263016 -299.954367) (xy 190.301137 -299.923242) (xy 190.343758 -299.898635) (xy 190.389774 -299.881183)
			(xy 190.437993 -299.871339) (xy 190.487168 -299.869358) (xy 190.536023 -299.87529) (xy 190.583294 -299.888982)
			(xy 190.627756 -299.91008) (xy 190.668259 -299.938036) (xy 190.703752 -299.972128) (xy 190.733317 -300.011472)
			(xy 190.756188 -300.055049) (xy 190.771772 -300.10173) (xy 190.779667 -300.150307) (xy 190.780162 -300.174914)
			(xy 191.119264 -300.174914) (xy 191.123224 -300.12586) (xy 191.135001 -300.078076) (xy 191.154292 -300.0328)
			(xy 191.180595 -299.991204) (xy 191.21323 -299.954367) (xy 191.251351 -299.923242) (xy 191.293972 -299.898635)
			(xy 191.339988 -299.881183) (xy 191.388207 -299.871339) (xy 191.437382 -299.869358) (xy 191.486237 -299.87529)
			(xy 191.533508 -299.888982) (xy 191.57797 -299.91008) (xy 191.618473 -299.938036) (xy 191.653966 -299.972128)
			(xy 191.683531 -300.011472) (xy 191.706402 -300.055049) (xy 191.721986 -300.10173) (xy 191.729881 -300.150307)
			(xy 191.730376 -300.174914) (xy 192.069224 -300.174914) (xy 192.073184 -300.12586) (xy 192.084961 -300.078076)
			(xy 192.104252 -300.0328) (xy 192.130555 -299.991204) (xy 192.16319 -299.954367) (xy 192.201311 -299.923242)
			(xy 192.243932 -299.898635) (xy 192.289948 -299.881183) (xy 192.338167 -299.871339) (xy 192.387342 -299.869358)
			(xy 192.436197 -299.87529) (xy 192.483468 -299.888982) (xy 192.52793 -299.91008) (xy 192.568433 -299.938036)
			(xy 192.603926 -299.972128) (xy 192.633491 -300.011472) (xy 192.656362 -300.055049) (xy 192.671946 -300.10173)
			(xy 192.679841 -300.150307) (xy 192.680336 -300.174914) (xy 193.019184 -300.174914) (xy 193.023144 -300.12586)
			(xy 193.034921 -300.078076) (xy 193.054212 -300.0328) (xy 193.080515 -299.991204) (xy 193.11315 -299.954367)
			(xy 193.151271 -299.923242) (xy 193.193892 -299.898635) (xy 193.239908 -299.881183) (xy 193.288127 -299.871339)
			(xy 193.337302 -299.869358) (xy 193.386157 -299.87529) (xy 193.433428 -299.888982) (xy 193.47789 -299.91008)
			(xy 193.518393 -299.938036) (xy 193.553886 -299.972128) (xy 193.583451 -300.011472) (xy 193.606322 -300.055049)
			(xy 193.621906 -300.10173) (xy 193.629801 -300.150307) (xy 193.630296 -300.174914) (xy 193.969144 -300.174914)
			(xy 193.973104 -300.12586) (xy 193.984881 -300.078076) (xy 194.004172 -300.0328) (xy 194.030475 -299.991204)
			(xy 194.06311 -299.954367) (xy 194.101231 -299.923242) (xy 194.143852 -299.898635) (xy 194.189868 -299.881183)
			(xy 194.238087 -299.871339) (xy 194.287262 -299.869358) (xy 194.336117 -299.87529) (xy 194.383388 -299.888982)
			(xy 194.42785 -299.91008) (xy 194.468353 -299.938036) (xy 194.503846 -299.972128) (xy 194.533411 -300.011472)
			(xy 194.556282 -300.055049) (xy 194.571866 -300.10173) (xy 194.579761 -300.150307) (xy 194.580256 -300.174914)
			(xy 194.919104 -300.174914) (xy 194.923064 -300.12586) (xy 194.934841 -300.078076) (xy 194.954132 -300.0328)
			(xy 194.980435 -299.991204) (xy 195.01307 -299.954367) (xy 195.051191 -299.923242) (xy 195.093812 -299.898635)
			(xy 195.139828 -299.881183) (xy 195.188047 -299.871339) (xy 195.237222 -299.869358) (xy 195.286077 -299.87529)
			(xy 195.333348 -299.888982) (xy 195.37781 -299.91008) (xy 195.418313 -299.938036) (xy 195.453806 -299.972128)
			(xy 195.483371 -300.011472) (xy 195.506242 -300.055049) (xy 195.521826 -300.10173) (xy 195.529721 -300.150307)
			(xy 195.530216 -300.174914) (xy 195.869064 -300.174914) (xy 195.873024 -300.12586) (xy 195.884801 -300.078076)
			(xy 195.904092 -300.0328) (xy 195.930395 -299.991204) (xy 195.96303 -299.954367) (xy 196.001151 -299.923242)
			(xy 196.043772 -299.898635) (xy 196.089788 -299.881183) (xy 196.138007 -299.871339) (xy 196.187182 -299.869358)
			(xy 196.236037 -299.87529) (xy 196.283308 -299.888982) (xy 196.32777 -299.91008) (xy 196.368273 -299.938036)
			(xy 196.403766 -299.972128) (xy 196.433331 -300.011472) (xy 196.456202 -300.055049) (xy 196.471786 -300.10173)
			(xy 196.479681 -300.150307) (xy 196.480176 -300.174914) (xy 196.819278 -300.174914) (xy 196.823238 -300.12586)
			(xy 196.835015 -300.078076) (xy 196.854306 -300.0328) (xy 196.880609 -299.991204) (xy 196.913244 -299.954367)
			(xy 196.951365 -299.923242) (xy 196.993986 -299.898635) (xy 197.040002 -299.881183) (xy 197.088221 -299.871339)
			(xy 197.137396 -299.869358) (xy 197.186251 -299.87529) (xy 197.233522 -299.888982) (xy 197.277984 -299.91008)
			(xy 197.318487 -299.938036) (xy 197.35398 -299.972128) (xy 197.383545 -300.011472) (xy 197.406416 -300.055049)
			(xy 197.422 -300.10173) (xy 197.429895 -300.150307) (xy 197.43039 -300.174914) (xy 197.769238 -300.174914)
			(xy 197.773198 -300.12586) (xy 197.784975 -300.078076) (xy 197.804266 -300.0328) (xy 197.830569 -299.991204)
			(xy 197.863204 -299.954367) (xy 197.901325 -299.923242) (xy 197.943946 -299.898635) (xy 197.989962 -299.881183)
			(xy 198.038181 -299.871339) (xy 198.087356 -299.869358) (xy 198.136211 -299.87529) (xy 198.183482 -299.888982)
			(xy 198.227944 -299.91008) (xy 198.268447 -299.938036) (xy 198.30394 -299.972128) (xy 198.333505 -300.011472)
			(xy 198.356376 -300.055049) (xy 198.37196 -300.10173) (xy 198.379855 -300.150307) (xy 198.38035 -300.174914)
			(xy 198.719198 -300.174914) (xy 198.723158 -300.12586) (xy 198.734935 -300.078076) (xy 198.754226 -300.0328)
			(xy 198.780529 -299.991204) (xy 198.813164 -299.954367) (xy 198.851285 -299.923242) (xy 198.893906 -299.898635)
			(xy 198.939922 -299.881183) (xy 198.988141 -299.871339) (xy 199.037316 -299.869358) (xy 199.086171 -299.87529)
			(xy 199.133442 -299.888982) (xy 199.177904 -299.91008) (xy 199.218407 -299.938036) (xy 199.2539 -299.972128)
			(xy 199.283465 -300.011472) (xy 199.306336 -300.055049) (xy 199.32192 -300.10173) (xy 199.329815 -300.150307)
			(xy 199.33031 -300.174914) (xy 199.329815 -300.199521) (xy 199.32192 -300.248098) (xy 199.306336 -300.294779)
			(xy 199.283465 -300.338356) (xy 199.2539 -300.3777) (xy 199.218407 -300.411792) (xy 199.177904 -300.439748)
			(xy 199.133442 -300.460846) (xy 199.086171 -300.474538) (xy 199.037316 -300.48047) (xy 198.988141 -300.478489)
			(xy 198.939922 -300.468645) (xy 198.893906 -300.451193) (xy 198.851285 -300.426586) (xy 198.813164 -300.395461)
			(xy 198.780529 -300.358624) (xy 198.754226 -300.317028) (xy 198.734935 -300.271752) (xy 198.723158 -300.223968)
			(xy 198.719198 -300.174914) (xy 198.38035 -300.174914) (xy 198.379855 -300.199521) (xy 198.37196 -300.248098)
			(xy 198.356376 -300.294779) (xy 198.333505 -300.338356) (xy 198.30394 -300.3777) (xy 198.268447 -300.411792)
			(xy 198.227944 -300.439748) (xy 198.183482 -300.460846) (xy 198.136211 -300.474538) (xy 198.087356 -300.48047)
			(xy 198.038181 -300.478489) (xy 197.989962 -300.468645) (xy 197.943946 -300.451193) (xy 197.901325 -300.426586)
			(xy 197.863204 -300.395461) (xy 197.830569 -300.358624) (xy 197.804266 -300.317028) (xy 197.784975 -300.271752)
			(xy 197.773198 -300.223968) (xy 197.769238 -300.174914) (xy 197.43039 -300.174914) (xy 197.429895 -300.199521)
			(xy 197.422 -300.248098) (xy 197.406416 -300.294779) (xy 197.383545 -300.338356) (xy 197.35398 -300.3777)
			(xy 197.318487 -300.411792) (xy 197.277984 -300.439748) (xy 197.233522 -300.460846) (xy 197.186251 -300.474538)
			(xy 197.137396 -300.48047) (xy 197.088221 -300.478489) (xy 197.040002 -300.468645) (xy 196.993986 -300.451193)
			(xy 196.951365 -300.426586) (xy 196.913244 -300.395461) (xy 196.880609 -300.358624) (xy 196.854306 -300.317028)
			(xy 196.835015 -300.271752) (xy 196.823238 -300.223968) (xy 196.819278 -300.174914) (xy 196.480176 -300.174914)
			(xy 196.479681 -300.199521) (xy 196.471786 -300.248098) (xy 196.456202 -300.294779) (xy 196.433331 -300.338356)
			(xy 196.403766 -300.3777) (xy 196.368273 -300.411792) (xy 196.32777 -300.439748) (xy 196.283308 -300.460846)
			(xy 196.236037 -300.474538) (xy 196.187182 -300.48047) (xy 196.138007 -300.478489) (xy 196.089788 -300.468645)
			(xy 196.043772 -300.451193) (xy 196.001151 -300.426586) (xy 195.96303 -300.395461) (xy 195.930395 -300.358624)
			(xy 195.904092 -300.317028) (xy 195.884801 -300.271752) (xy 195.873024 -300.223968) (xy 195.869064 -300.174914)
			(xy 195.530216 -300.174914) (xy 195.529721 -300.199521) (xy 195.521826 -300.248098) (xy 195.506242 -300.294779)
			(xy 195.483371 -300.338356) (xy 195.453806 -300.3777) (xy 195.418313 -300.411792) (xy 195.37781 -300.439748)
			(xy 195.333348 -300.460846) (xy 195.286077 -300.474538) (xy 195.237222 -300.48047) (xy 195.188047 -300.478489)
			(xy 195.139828 -300.468645) (xy 195.093812 -300.451193) (xy 195.051191 -300.426586) (xy 195.01307 -300.395461)
			(xy 194.980435 -300.358624) (xy 194.954132 -300.317028) (xy 194.934841 -300.271752) (xy 194.923064 -300.223968)
			(xy 194.919104 -300.174914) (xy 194.580256 -300.174914) (xy 194.579761 -300.199521) (xy 194.571866 -300.248098)
			(xy 194.556282 -300.294779) (xy 194.533411 -300.338356) (xy 194.503846 -300.3777) (xy 194.468353 -300.411792)
			(xy 194.42785 -300.439748) (xy 194.383388 -300.460846) (xy 194.336117 -300.474538) (xy 194.287262 -300.48047)
			(xy 194.238087 -300.478489) (xy 194.189868 -300.468645) (xy 194.143852 -300.451193) (xy 194.101231 -300.426586)
			(xy 194.06311 -300.395461) (xy 194.030475 -300.358624) (xy 194.004172 -300.317028) (xy 193.984881 -300.271752)
			(xy 193.973104 -300.223968) (xy 193.969144 -300.174914) (xy 193.630296 -300.174914) (xy 193.629801 -300.199521)
			(xy 193.621906 -300.248098) (xy 193.606322 -300.294779) (xy 193.583451 -300.338356) (xy 193.553886 -300.3777)
			(xy 193.518393 -300.411792) (xy 193.47789 -300.439748) (xy 193.433428 -300.460846) (xy 193.386157 -300.474538)
			(xy 193.337302 -300.48047) (xy 193.288127 -300.478489) (xy 193.239908 -300.468645) (xy 193.193892 -300.451193)
			(xy 193.151271 -300.426586) (xy 193.11315 -300.395461) (xy 193.080515 -300.358624) (xy 193.054212 -300.317028)
			(xy 193.034921 -300.271752) (xy 193.023144 -300.223968) (xy 193.019184 -300.174914) (xy 192.680336 -300.174914)
			(xy 192.679841 -300.199521) (xy 192.671946 -300.248098) (xy 192.656362 -300.294779) (xy 192.633491 -300.338356)
			(xy 192.603926 -300.3777) (xy 192.568433 -300.411792) (xy 192.52793 -300.439748) (xy 192.483468 -300.460846)
			(xy 192.436197 -300.474538) (xy 192.387342 -300.48047) (xy 192.338167 -300.478489) (xy 192.289948 -300.468645)
			(xy 192.243932 -300.451193) (xy 192.201311 -300.426586) (xy 192.16319 -300.395461) (xy 192.130555 -300.358624)
			(xy 192.104252 -300.317028) (xy 192.084961 -300.271752) (xy 192.073184 -300.223968) (xy 192.069224 -300.174914)
			(xy 191.730376 -300.174914) (xy 191.729881 -300.199521) (xy 191.721986 -300.248098) (xy 191.706402 -300.294779)
			(xy 191.683531 -300.338356) (xy 191.653966 -300.3777) (xy 191.618473 -300.411792) (xy 191.57797 -300.439748)
			(xy 191.533508 -300.460846) (xy 191.486237 -300.474538) (xy 191.437382 -300.48047) (xy 191.388207 -300.478489)
			(xy 191.339988 -300.468645) (xy 191.293972 -300.451193) (xy 191.251351 -300.426586) (xy 191.21323 -300.395461)
			(xy 191.180595 -300.358624) (xy 191.154292 -300.317028) (xy 191.135001 -300.271752) (xy 191.123224 -300.223968)
			(xy 191.119264 -300.174914) (xy 190.780162 -300.174914) (xy 190.779667 -300.199521) (xy 190.771772 -300.248098)
			(xy 190.756188 -300.294779) (xy 190.733317 -300.338356) (xy 190.703752 -300.3777) (xy 190.668259 -300.411792)
			(xy 190.627756 -300.439748) (xy 190.583294 -300.460846) (xy 190.536023 -300.474538) (xy 190.487168 -300.48047)
			(xy 190.437993 -300.478489) (xy 190.389774 -300.468645) (xy 190.343758 -300.451193) (xy 190.301137 -300.426586)
			(xy 190.263016 -300.395461) (xy 190.230381 -300.358624) (xy 190.204078 -300.317028) (xy 190.184787 -300.271752)
			(xy 190.17301 -300.223968) (xy 190.16905 -300.174914) (xy 189.830202 -300.174914) (xy 189.829707 -300.199521)
			(xy 189.821812 -300.248098) (xy 189.806228 -300.294779) (xy 189.783357 -300.338356) (xy 189.753792 -300.3777)
			(xy 189.718299 -300.411792) (xy 189.677796 -300.439748) (xy 189.633334 -300.460846) (xy 189.586063 -300.474538)
			(xy 189.537208 -300.48047) (xy 189.488033 -300.478489) (xy 189.439814 -300.468645) (xy 189.393798 -300.451193)
			(xy 189.351177 -300.426586) (xy 189.313056 -300.395461) (xy 189.280421 -300.358624) (xy 189.254118 -300.317028)
			(xy 189.234827 -300.271752) (xy 189.22305 -300.223968) (xy 189.21909 -300.174914) (xy 188.880242 -300.174914)
			(xy 188.879747 -300.199521) (xy 188.871852 -300.248098) (xy 188.856268 -300.294779) (xy 188.833397 -300.338356)
			(xy 188.803832 -300.3777) (xy 188.768339 -300.411792) (xy 188.727836 -300.439748) (xy 188.683374 -300.460846)
			(xy 188.636103 -300.474538) (xy 188.587248 -300.48047) (xy 188.538073 -300.478489) (xy 188.489854 -300.468645)
			(xy 188.443838 -300.451193) (xy 188.401217 -300.426586) (xy 188.363096 -300.395461) (xy 188.330461 -300.358624)
			(xy 188.304158 -300.317028) (xy 188.284867 -300.271752) (xy 188.27309 -300.223968) (xy 188.26913 -300.174914)
			(xy 187.930282 -300.174914) (xy 187.929787 -300.199521) (xy 187.921892 -300.248098) (xy 187.906308 -300.294779)
			(xy 187.883437 -300.338356) (xy 187.853872 -300.3777) (xy 187.818379 -300.411792) (xy 187.777876 -300.439748)
			(xy 187.733414 -300.460846) (xy 187.686143 -300.474538) (xy 187.637288 -300.48047) (xy 187.588113 -300.478489)
			(xy 187.539894 -300.468645) (xy 187.493878 -300.451193) (xy 187.451257 -300.426586) (xy 187.413136 -300.395461)
			(xy 187.380501 -300.358624) (xy 187.354198 -300.317028) (xy 187.334907 -300.271752) (xy 187.32313 -300.223968)
			(xy 187.31917 -300.174914) (xy 186.980322 -300.174914) (xy 186.979827 -300.199521) (xy 186.971932 -300.248098)
			(xy 186.956348 -300.294779) (xy 186.933477 -300.338356) (xy 186.903912 -300.3777) (xy 186.868419 -300.411792)
			(xy 186.827916 -300.439748) (xy 186.783454 -300.460846) (xy 186.736183 -300.474538) (xy 186.687328 -300.48047)
			(xy 186.638153 -300.478489) (xy 186.589934 -300.468645) (xy 186.543918 -300.451193) (xy 186.501297 -300.426586)
			(xy 186.463176 -300.395461) (xy 186.430541 -300.358624) (xy 186.404238 -300.317028) (xy 186.384947 -300.271752)
			(xy 186.37317 -300.223968) (xy 186.36921 -300.174914) (xy 186.030362 -300.174914) (xy 186.029867 -300.199521)
			(xy 186.021972 -300.248098) (xy 186.006388 -300.294779) (xy 185.983517 -300.338356) (xy 185.953952 -300.3777)
			(xy 185.918459 -300.411792) (xy 185.877956 -300.439748) (xy 185.833494 -300.460846) (xy 185.786223 -300.474538)
			(xy 185.737368 -300.48047) (xy 185.688193 -300.478489) (xy 185.639974 -300.468645) (xy 185.593958 -300.451193)
			(xy 185.551337 -300.426586) (xy 185.513216 -300.395461) (xy 185.480581 -300.358624) (xy 185.454278 -300.317028)
			(xy 185.434987 -300.271752) (xy 185.42321 -300.223968) (xy 185.41925 -300.174914) (xy 185.080148 -300.174914)
			(xy 185.079653 -300.199521) (xy 185.071758 -300.248098) (xy 185.056174 -300.294779) (xy 185.033303 -300.338356)
			(xy 185.003738 -300.3777) (xy 184.968245 -300.411792) (xy 184.927742 -300.439748) (xy 184.88328 -300.460846)
			(xy 184.836009 -300.474538) (xy 184.787154 -300.48047) (xy 184.737979 -300.478489) (xy 184.68976 -300.468645)
			(xy 184.643744 -300.451193) (xy 184.601123 -300.426586) (xy 184.563002 -300.395461) (xy 184.530367 -300.358624)
			(xy 184.504064 -300.317028) (xy 184.484773 -300.271752) (xy 184.472996 -300.223968) (xy 184.469036 -300.174914)
			(xy 184.130188 -300.174914) (xy 184.129693 -300.199521) (xy 184.121798 -300.248098) (xy 184.106214 -300.294779)
			(xy 184.083343 -300.338356) (xy 184.053778 -300.3777) (xy 184.018285 -300.411792) (xy 183.977782 -300.439748)
			(xy 183.93332 -300.460846) (xy 183.886049 -300.474538) (xy 183.837194 -300.48047) (xy 183.788019 -300.478489)
			(xy 183.7398 -300.468645) (xy 183.693784 -300.451193) (xy 183.651163 -300.426586) (xy 183.613042 -300.395461)
			(xy 183.580407 -300.358624) (xy 183.554104 -300.317028) (xy 183.534813 -300.271752) (xy 183.523036 -300.223968)
			(xy 183.519076 -300.174914) (xy 183.180228 -300.174914) (xy 183.179733 -300.199521) (xy 183.171838 -300.248098)
			(xy 183.156254 -300.294779) (xy 183.133383 -300.338356) (xy 183.103818 -300.3777) (xy 183.068325 -300.411792)
			(xy 183.027822 -300.439748) (xy 182.98336 -300.460846) (xy 182.936089 -300.474538) (xy 182.887234 -300.48047)
			(xy 182.838059 -300.478489) (xy 182.78984 -300.468645) (xy 182.743824 -300.451193) (xy 182.701203 -300.426586)
			(xy 182.663082 -300.395461) (xy 182.630447 -300.358624) (xy 182.604144 -300.317028) (xy 182.584853 -300.271752)
			(xy 182.573076 -300.223968) (xy 182.569116 -300.174914) (xy 182.230268 -300.174914) (xy 182.229773 -300.199521)
			(xy 182.221878 -300.248098) (xy 182.206294 -300.294779) (xy 182.183423 -300.338356) (xy 182.153858 -300.3777)
			(xy 182.118365 -300.411792) (xy 182.077862 -300.439748) (xy 182.0334 -300.460846) (xy 181.986129 -300.474538)
			(xy 181.937274 -300.48047) (xy 181.888099 -300.478489) (xy 181.83988 -300.468645) (xy 181.793864 -300.451193)
			(xy 181.751243 -300.426586) (xy 181.713122 -300.395461) (xy 181.680487 -300.358624) (xy 181.654184 -300.317028)
			(xy 181.634893 -300.271752) (xy 181.623116 -300.223968) (xy 181.619156 -300.174914) (xy 181.280308 -300.174914)
			(xy 181.279813 -300.199521) (xy 181.271918 -300.248098) (xy 181.256334 -300.294779) (xy 181.233463 -300.338356)
			(xy 181.203898 -300.3777) (xy 181.168405 -300.411792) (xy 181.127902 -300.439748) (xy 181.08344 -300.460846)
			(xy 181.036169 -300.474538) (xy 180.987314 -300.48047) (xy 180.938139 -300.478489) (xy 180.88992 -300.468645)
			(xy 180.843904 -300.451193) (xy 180.801283 -300.426586) (xy 180.763162 -300.395461) (xy 180.730527 -300.358624)
			(xy 180.704224 -300.317028) (xy 180.684933 -300.271752) (xy 180.673156 -300.223968) (xy 180.669196 -300.174914)
			(xy 180.330348 -300.174914) (xy 180.329853 -300.199521) (xy 180.321958 -300.248098) (xy 180.306374 -300.294779)
			(xy 180.283503 -300.338356) (xy 180.253938 -300.3777) (xy 180.218445 -300.411792) (xy 180.177942 -300.439748)
			(xy 180.13348 -300.460846) (xy 180.086209 -300.474538) (xy 180.037354 -300.48047) (xy 179.988179 -300.478489)
			(xy 179.93996 -300.468645) (xy 179.893944 -300.451193) (xy 179.851323 -300.426586) (xy 179.813202 -300.395461)
			(xy 179.780567 -300.358624) (xy 179.754264 -300.317028) (xy 179.734973 -300.271752) (xy 179.723196 -300.223968)
			(xy 179.719236 -300.174914) (xy 179.380388 -300.174914) (xy 179.379893 -300.199521) (xy 179.371998 -300.248098)
			(xy 179.356414 -300.294779) (xy 179.333543 -300.338356) (xy 179.303978 -300.3777) (xy 179.268485 -300.411792)
			(xy 179.227982 -300.439748) (xy 179.18352 -300.460846) (xy 179.136249 -300.474538) (xy 179.087394 -300.48047)
			(xy 179.038219 -300.478489) (xy 178.99 -300.468645) (xy 178.943984 -300.451193) (xy 178.901363 -300.426586)
			(xy 178.863242 -300.395461) (xy 178.830607 -300.358624) (xy 178.804304 -300.317028) (xy 178.785013 -300.271752)
			(xy 178.773236 -300.223968) (xy 178.769276 -300.174914) (xy 178.430174 -300.174914) (xy 178.429679 -300.199521)
			(xy 178.421784 -300.248098) (xy 178.4062 -300.294779) (xy 178.383329 -300.338356) (xy 178.353764 -300.3777)
			(xy 178.318271 -300.411792) (xy 178.277768 -300.439748) (xy 178.233306 -300.460846) (xy 178.186035 -300.474538)
			(xy 178.13718 -300.48047) (xy 178.088005 -300.478489) (xy 178.039786 -300.468645) (xy 177.99377 -300.451193)
			(xy 177.951149 -300.426586) (xy 177.913028 -300.395461) (xy 177.880393 -300.358624) (xy 177.85409 -300.317028)
			(xy 177.834799 -300.271752) (xy 177.823022 -300.223968) (xy 177.819062 -300.174914) (xy 177.480214 -300.174914)
			(xy 177.479719 -300.199521) (xy 177.471824 -300.248098) (xy 177.45624 -300.294779) (xy 177.433369 -300.338356)
			(xy 177.403804 -300.3777) (xy 177.368311 -300.411792) (xy 177.327808 -300.439748) (xy 177.283346 -300.460846)
			(xy 177.236075 -300.474538) (xy 177.18722 -300.48047) (xy 177.138045 -300.478489) (xy 177.089826 -300.468645)
			(xy 177.04381 -300.451193) (xy 177.001189 -300.426586) (xy 176.963068 -300.395461) (xy 176.930433 -300.358624)
			(xy 176.90413 -300.317028) (xy 176.884839 -300.271752) (xy 176.873062 -300.223968) (xy 176.869102 -300.174914)
			(xy 176.530254 -300.174914) (xy 176.529759 -300.199521) (xy 176.521864 -300.248098) (xy 176.50628 -300.294779)
			(xy 176.483409 -300.338356) (xy 176.453844 -300.3777) (xy 176.418351 -300.411792) (xy 176.377848 -300.439748)
			(xy 176.333386 -300.460846) (xy 176.286115 -300.474538) (xy 176.23726 -300.48047) (xy 176.188085 -300.478489)
			(xy 176.139866 -300.468645) (xy 176.09385 -300.451193) (xy 176.051229 -300.426586) (xy 176.013108 -300.395461)
			(xy 175.980473 -300.358624) (xy 175.95417 -300.317028) (xy 175.934879 -300.271752) (xy 175.923102 -300.223968)
			(xy 175.919142 -300.174914) (xy 174.630334 -300.174914) (xy 174.629839 -300.199521) (xy 174.621944 -300.248098)
			(xy 174.60636 -300.294779) (xy 174.583489 -300.338356) (xy 174.553924 -300.3777) (xy 174.518431 -300.411792)
			(xy 174.477928 -300.439748) (xy 174.433466 -300.460846) (xy 174.386195 -300.474538) (xy 174.33734 -300.48047)
			(xy 174.288165 -300.478489) (xy 174.239946 -300.468645) (xy 174.19393 -300.451193) (xy 174.151309 -300.426586)
			(xy 174.113188 -300.395461) (xy 174.080553 -300.358624) (xy 174.05425 -300.317028) (xy 174.034959 -300.271752)
			(xy 174.023182 -300.223968) (xy 174.019222 -300.174914) (xy 173.680374 -300.174914) (xy 173.679879 -300.199521)
			(xy 173.671984 -300.248098) (xy 173.6564 -300.294779) (xy 173.633529 -300.338356) (xy 173.603964 -300.3777)
			(xy 173.568471 -300.411792) (xy 173.527968 -300.439748) (xy 173.483506 -300.460846) (xy 173.436235 -300.474538)
			(xy 173.38738 -300.48047) (xy 173.338205 -300.478489) (xy 173.289986 -300.468645) (xy 173.24397 -300.451193)
			(xy 173.201349 -300.426586) (xy 173.163228 -300.395461) (xy 173.130593 -300.358624) (xy 173.10429 -300.317028)
			(xy 173.084999 -300.271752) (xy 173.073222 -300.223968) (xy 173.069262 -300.174914) (xy 172.73016 -300.174914)
			(xy 172.729665 -300.199521) (xy 172.72177 -300.248098) (xy 172.706186 -300.294779) (xy 172.683315 -300.338356)
			(xy 172.65375 -300.3777) (xy 172.618257 -300.411792) (xy 172.577754 -300.439748) (xy 172.533292 -300.460846)
			(xy 172.486021 -300.474538) (xy 172.437166 -300.48047) (xy 172.387991 -300.478489) (xy 172.339772 -300.468645)
			(xy 172.293756 -300.451193) (xy 172.251135 -300.426586) (xy 172.213014 -300.395461) (xy 172.180379 -300.358624)
			(xy 172.154076 -300.317028) (xy 172.134785 -300.271752) (xy 172.123008 -300.223968) (xy 172.119048 -300.174914)
			(xy 171.7802 -300.174914) (xy 171.779705 -300.199521) (xy 171.77181 -300.248098) (xy 171.756226 -300.294779)
			(xy 171.733355 -300.338356) (xy 171.70379 -300.3777) (xy 171.668297 -300.411792) (xy 171.627794 -300.439748)
			(xy 171.583332 -300.460846) (xy 171.536061 -300.474538) (xy 171.487206 -300.48047) (xy 171.438031 -300.478489)
			(xy 171.389812 -300.468645) (xy 171.343796 -300.451193) (xy 171.301175 -300.426586) (xy 171.263054 -300.395461)
			(xy 171.230419 -300.358624) (xy 171.204116 -300.317028) (xy 171.184825 -300.271752) (xy 171.173048 -300.223968)
			(xy 171.169088 -300.174914) (xy 170.83024 -300.174914) (xy 170.829745 -300.199521) (xy 170.82185 -300.248098)
			(xy 170.806266 -300.294779) (xy 170.783395 -300.338356) (xy 170.75383 -300.3777) (xy 170.718337 -300.411792)
			(xy 170.677834 -300.439748) (xy 170.633372 -300.460846) (xy 170.586101 -300.474538) (xy 170.537246 -300.48047)
			(xy 170.488071 -300.478489) (xy 170.439852 -300.468645) (xy 170.393836 -300.451193) (xy 170.351215 -300.426586)
			(xy 170.313094 -300.395461) (xy 170.280459 -300.358624) (xy 170.254156 -300.317028) (xy 170.234865 -300.271752)
			(xy 170.223088 -300.223968) (xy 170.219128 -300.174914) (xy 169.88028 -300.174914) (xy 169.879785 -300.199521)
			(xy 169.87189 -300.248098) (xy 169.856306 -300.294779) (xy 169.833435 -300.338356) (xy 169.80387 -300.3777)
			(xy 169.768377 -300.411792) (xy 169.727874 -300.439748) (xy 169.683412 -300.460846) (xy 169.636141 -300.474538)
			(xy 169.587286 -300.48047) (xy 169.538111 -300.478489) (xy 169.489892 -300.468645) (xy 169.443876 -300.451193)
			(xy 169.401255 -300.426586) (xy 169.363134 -300.395461) (xy 169.330499 -300.358624) (xy 169.304196 -300.317028)
			(xy 169.284905 -300.271752) (xy 169.273128 -300.223968) (xy 169.269168 -300.174914) (xy 168.93032 -300.174914)
			(xy 168.929825 -300.199521) (xy 168.92193 -300.248098) (xy 168.906346 -300.294779) (xy 168.883475 -300.338356)
			(xy 168.85391 -300.3777) (xy 168.818417 -300.411792) (xy 168.777914 -300.439748) (xy 168.733452 -300.460846)
			(xy 168.686181 -300.474538) (xy 168.637326 -300.48047) (xy 168.588151 -300.478489) (xy 168.539932 -300.468645)
			(xy 168.493916 -300.451193) (xy 168.451295 -300.426586) (xy 168.413174 -300.395461) (xy 168.380539 -300.358624)
			(xy 168.354236 -300.317028) (xy 168.334945 -300.271752) (xy 168.323168 -300.223968) (xy 168.319208 -300.174914)
			(xy 167.98036 -300.174914) (xy 167.979865 -300.199521) (xy 167.97197 -300.248098) (xy 167.956386 -300.294779)
			(xy 167.933515 -300.338356) (xy 167.90395 -300.3777) (xy 167.868457 -300.411792) (xy 167.827954 -300.439748)
			(xy 167.783492 -300.460846) (xy 167.736221 -300.474538) (xy 167.687366 -300.48047) (xy 167.638191 -300.478489)
			(xy 167.589972 -300.468645) (xy 167.543956 -300.451193) (xy 167.501335 -300.426586) (xy 167.463214 -300.395461)
			(xy 167.430579 -300.358624) (xy 167.404276 -300.317028) (xy 167.384985 -300.271752) (xy 167.373208 -300.223968)
			(xy 167.369248 -300.174914) (xy 167.0304 -300.174914) (xy 167.029905 -300.199521) (xy 167.02201 -300.248098)
			(xy 167.006426 -300.294779) (xy 166.983555 -300.338356) (xy 166.95399 -300.3777) (xy 166.918497 -300.411792)
			(xy 166.877994 -300.439748) (xy 166.833532 -300.460846) (xy 166.786261 -300.474538) (xy 166.737406 -300.48047)
			(xy 166.688231 -300.478489) (xy 166.640012 -300.468645) (xy 166.593996 -300.451193) (xy 166.551375 -300.426586)
			(xy 166.513254 -300.395461) (xy 166.480619 -300.358624) (xy 166.454316 -300.317028) (xy 166.435025 -300.271752)
			(xy 166.423248 -300.223968) (xy 166.419288 -300.174914) (xy 166.128192 -300.174914) (xy 166.128192 -300.746668)
			(xy 166.127938 -300.75759) (xy 166.127938 -301.124874) (xy 166.419288 -301.124874) (xy 166.423248 -301.07582)
			(xy 166.435025 -301.028036) (xy 166.454316 -300.98276) (xy 166.480619 -300.941164) (xy 166.513254 -300.904327)
			(xy 166.551375 -300.873202) (xy 166.593996 -300.848595) (xy 166.640012 -300.831143) (xy 166.688231 -300.821299)
			(xy 166.737406 -300.819318) (xy 166.786261 -300.82525) (xy 166.833532 -300.838942) (xy 166.877994 -300.86004)
			(xy 166.918497 -300.887996) (xy 166.95399 -300.922088) (xy 166.983555 -300.961432) (xy 167.006426 -301.005009)
			(xy 167.02201 -301.05169) (xy 167.029905 -301.100267) (xy 167.0304 -301.124874) (xy 167.369248 -301.124874)
			(xy 167.373208 -301.07582) (xy 167.384985 -301.028036) (xy 167.404276 -300.98276) (xy 167.430579 -300.941164)
			(xy 167.463214 -300.904327) (xy 167.501335 -300.873202) (xy 167.543956 -300.848595) (xy 167.589972 -300.831143)
			(xy 167.638191 -300.821299) (xy 167.687366 -300.819318) (xy 167.736221 -300.82525) (xy 167.783492 -300.838942)
			(xy 167.827954 -300.86004) (xy 167.868457 -300.887996) (xy 167.90395 -300.922088) (xy 167.933515 -300.961432)
			(xy 167.956386 -301.005009) (xy 167.97197 -301.05169) (xy 167.979865 -301.100267) (xy 167.98036 -301.124874)
			(xy 168.319208 -301.124874) (xy 168.323168 -301.07582) (xy 168.334945 -301.028036) (xy 168.354236 -300.98276)
			(xy 168.380539 -300.941164) (xy 168.413174 -300.904327) (xy 168.451295 -300.873202) (xy 168.493916 -300.848595)
			(xy 168.539932 -300.831143) (xy 168.588151 -300.821299) (xy 168.637326 -300.819318) (xy 168.686181 -300.82525)
			(xy 168.733452 -300.838942) (xy 168.777914 -300.86004) (xy 168.818417 -300.887996) (xy 168.85391 -300.922088)
			(xy 168.883475 -300.961432) (xy 168.906346 -301.005009) (xy 168.92193 -301.05169) (xy 168.929825 -301.100267)
			(xy 168.93032 -301.124874) (xy 169.269168 -301.124874) (xy 169.273128 -301.07582) (xy 169.284905 -301.028036)
			(xy 169.304196 -300.98276) (xy 169.330499 -300.941164) (xy 169.363134 -300.904327) (xy 169.401255 -300.873202)
			(xy 169.443876 -300.848595) (xy 169.489892 -300.831143) (xy 169.538111 -300.821299) (xy 169.587286 -300.819318)
			(xy 169.636141 -300.82525) (xy 169.683412 -300.838942) (xy 169.727874 -300.86004) (xy 169.768377 -300.887996)
			(xy 169.80387 -300.922088) (xy 169.833435 -300.961432) (xy 169.856306 -301.005009) (xy 169.87189 -301.05169)
			(xy 169.879785 -301.100267) (xy 169.88028 -301.124874) (xy 170.219128 -301.124874) (xy 170.223088 -301.07582)
			(xy 170.234865 -301.028036) (xy 170.254156 -300.98276) (xy 170.280459 -300.941164) (xy 170.313094 -300.904327)
			(xy 170.351215 -300.873202) (xy 170.393836 -300.848595) (xy 170.439852 -300.831143) (xy 170.488071 -300.821299)
			(xy 170.537246 -300.819318) (xy 170.586101 -300.82525) (xy 170.633372 -300.838942) (xy 170.677834 -300.86004)
			(xy 170.718337 -300.887996) (xy 170.75383 -300.922088) (xy 170.783395 -300.961432) (xy 170.806266 -301.005009)
			(xy 170.82185 -301.05169) (xy 170.829745 -301.100267) (xy 170.83024 -301.124874) (xy 171.169088 -301.124874)
			(xy 171.173048 -301.07582) (xy 171.184825 -301.028036) (xy 171.204116 -300.98276) (xy 171.230419 -300.941164)
			(xy 171.263054 -300.904327) (xy 171.301175 -300.873202) (xy 171.343796 -300.848595) (xy 171.389812 -300.831143)
			(xy 171.438031 -300.821299) (xy 171.487206 -300.819318) (xy 171.536061 -300.82525) (xy 171.583332 -300.838942)
			(xy 171.627794 -300.86004) (xy 171.668297 -300.887996) (xy 171.70379 -300.922088) (xy 171.733355 -300.961432)
			(xy 171.756226 -301.005009) (xy 171.77181 -301.05169) (xy 171.779705 -301.100267) (xy 171.7802 -301.124874)
			(xy 172.119048 -301.124874) (xy 172.123008 -301.07582) (xy 172.134785 -301.028036) (xy 172.154076 -300.98276)
			(xy 172.180379 -300.941164) (xy 172.213014 -300.904327) (xy 172.251135 -300.873202) (xy 172.293756 -300.848595)
			(xy 172.339772 -300.831143) (xy 172.387991 -300.821299) (xy 172.437166 -300.819318) (xy 172.486021 -300.82525)
			(xy 172.533292 -300.838942) (xy 172.577754 -300.86004) (xy 172.618257 -300.887996) (xy 172.65375 -300.922088)
			(xy 172.683315 -300.961432) (xy 172.706186 -301.005009) (xy 172.72177 -301.05169) (xy 172.729665 -301.100267)
			(xy 172.73016 -301.124874) (xy 173.069262 -301.124874) (xy 173.073222 -301.07582) (xy 173.084999 -301.028036)
			(xy 173.10429 -300.98276) (xy 173.130593 -300.941164) (xy 173.163228 -300.904327) (xy 173.201349 -300.873202)
			(xy 173.24397 -300.848595) (xy 173.289986 -300.831143) (xy 173.338205 -300.821299) (xy 173.38738 -300.819318)
			(xy 173.436235 -300.82525) (xy 173.483506 -300.838942) (xy 173.527968 -300.86004) (xy 173.568471 -300.887996)
			(xy 173.603964 -300.922088) (xy 173.633529 -300.961432) (xy 173.6564 -301.005009) (xy 173.671984 -301.05169)
			(xy 173.679879 -301.100267) (xy 173.680374 -301.124874) (xy 174.019222 -301.124874) (xy 174.023182 -301.07582)
			(xy 174.034959 -301.028036) (xy 174.05425 -300.98276) (xy 174.080553 -300.941164) (xy 174.113188 -300.904327)
			(xy 174.151309 -300.873202) (xy 174.19393 -300.848595) (xy 174.239946 -300.831143) (xy 174.288165 -300.821299)
			(xy 174.33734 -300.819318) (xy 174.386195 -300.82525) (xy 174.433466 -300.838942) (xy 174.477928 -300.86004)
			(xy 174.518431 -300.887996) (xy 174.553924 -300.922088) (xy 174.583489 -300.961432) (xy 174.60636 -301.005009)
			(xy 174.621944 -301.05169) (xy 174.629839 -301.100267) (xy 174.630334 -301.124874) (xy 175.919142 -301.124874)
			(xy 175.923102 -301.07582) (xy 175.934879 -301.028036) (xy 175.95417 -300.98276) (xy 175.980473 -300.941164)
			(xy 176.013108 -300.904327) (xy 176.051229 -300.873202) (xy 176.09385 -300.848595) (xy 176.139866 -300.831143)
			(xy 176.188085 -300.821299) (xy 176.23726 -300.819318) (xy 176.286115 -300.82525) (xy 176.333386 -300.838942)
			(xy 176.377848 -300.86004) (xy 176.418351 -300.887996) (xy 176.453844 -300.922088) (xy 176.483409 -300.961432)
			(xy 176.50628 -301.005009) (xy 176.521864 -301.05169) (xy 176.529759 -301.100267) (xy 176.530254 -301.124874)
			(xy 176.869102 -301.124874) (xy 176.873062 -301.07582) (xy 176.884839 -301.028036) (xy 176.90413 -300.98276)
			(xy 176.930433 -300.941164) (xy 176.963068 -300.904327) (xy 177.001189 -300.873202) (xy 177.04381 -300.848595)
			(xy 177.089826 -300.831143) (xy 177.138045 -300.821299) (xy 177.18722 -300.819318) (xy 177.236075 -300.82525)
			(xy 177.283346 -300.838942) (xy 177.327808 -300.86004) (xy 177.368311 -300.887996) (xy 177.403804 -300.922088)
			(xy 177.433369 -300.961432) (xy 177.45624 -301.005009) (xy 177.471824 -301.05169) (xy 177.479719 -301.100267)
			(xy 177.480214 -301.124874) (xy 177.819062 -301.124874) (xy 177.823022 -301.07582) (xy 177.834799 -301.028036)
			(xy 177.85409 -300.98276) (xy 177.880393 -300.941164) (xy 177.913028 -300.904327) (xy 177.951149 -300.873202)
			(xy 177.99377 -300.848595) (xy 178.039786 -300.831143) (xy 178.088005 -300.821299) (xy 178.13718 -300.819318)
			(xy 178.186035 -300.82525) (xy 178.233306 -300.838942) (xy 178.277768 -300.86004) (xy 178.318271 -300.887996)
			(xy 178.353764 -300.922088) (xy 178.383329 -300.961432) (xy 178.4062 -301.005009) (xy 178.421784 -301.05169)
			(xy 178.429679 -301.100267) (xy 178.430174 -301.124874) (xy 178.769276 -301.124874) (xy 178.773236 -301.07582)
			(xy 178.785013 -301.028036) (xy 178.804304 -300.98276) (xy 178.830607 -300.941164) (xy 178.863242 -300.904327)
			(xy 178.901363 -300.873202) (xy 178.943984 -300.848595) (xy 178.99 -300.831143) (xy 179.038219 -300.821299)
			(xy 179.087394 -300.819318) (xy 179.136249 -300.82525) (xy 179.18352 -300.838942) (xy 179.227982 -300.86004)
			(xy 179.268485 -300.887996) (xy 179.303978 -300.922088) (xy 179.333543 -300.961432) (xy 179.356414 -301.005009)
			(xy 179.371998 -301.05169) (xy 179.379893 -301.100267) (xy 179.380388 -301.124874) (xy 179.719236 -301.124874)
			(xy 179.723196 -301.07582) (xy 179.734973 -301.028036) (xy 179.754264 -300.98276) (xy 179.780567 -300.941164)
			(xy 179.813202 -300.904327) (xy 179.851323 -300.873202) (xy 179.893944 -300.848595) (xy 179.93996 -300.831143)
			(xy 179.988179 -300.821299) (xy 180.037354 -300.819318) (xy 180.086209 -300.82525) (xy 180.13348 -300.838942)
			(xy 180.177942 -300.86004) (xy 180.218445 -300.887996) (xy 180.253938 -300.922088) (xy 180.283503 -300.961432)
			(xy 180.306374 -301.005009) (xy 180.321958 -301.05169) (xy 180.329853 -301.100267) (xy 180.330348 -301.124874)
			(xy 180.669196 -301.124874) (xy 180.673156 -301.07582) (xy 180.684933 -301.028036) (xy 180.704224 -300.98276)
			(xy 180.730527 -300.941164) (xy 180.763162 -300.904327) (xy 180.801283 -300.873202) (xy 180.843904 -300.848595)
			(xy 180.88992 -300.831143) (xy 180.938139 -300.821299) (xy 180.987314 -300.819318) (xy 181.036169 -300.82525)
			(xy 181.08344 -300.838942) (xy 181.127902 -300.86004) (xy 181.168405 -300.887996) (xy 181.203898 -300.922088)
			(xy 181.233463 -300.961432) (xy 181.256334 -301.005009) (xy 181.271918 -301.05169) (xy 181.279813 -301.100267)
			(xy 181.280308 -301.124874) (xy 181.619156 -301.124874) (xy 181.623116 -301.07582) (xy 181.634893 -301.028036)
			(xy 181.654184 -300.98276) (xy 181.680487 -300.941164) (xy 181.713122 -300.904327) (xy 181.751243 -300.873202)
			(xy 181.793864 -300.848595) (xy 181.83988 -300.831143) (xy 181.888099 -300.821299) (xy 181.937274 -300.819318)
			(xy 181.986129 -300.82525) (xy 182.0334 -300.838942) (xy 182.077862 -300.86004) (xy 182.118365 -300.887996)
			(xy 182.153858 -300.922088) (xy 182.183423 -300.961432) (xy 182.206294 -301.005009) (xy 182.221878 -301.05169)
			(xy 182.229773 -301.100267) (xy 182.230268 -301.124874) (xy 182.569116 -301.124874) (xy 182.573076 -301.07582)
			(xy 182.584853 -301.028036) (xy 182.604144 -300.98276) (xy 182.630447 -300.941164) (xy 182.663082 -300.904327)
			(xy 182.701203 -300.873202) (xy 182.743824 -300.848595) (xy 182.78984 -300.831143) (xy 182.838059 -300.821299)
			(xy 182.887234 -300.819318) (xy 182.936089 -300.82525) (xy 182.98336 -300.838942) (xy 183.027822 -300.86004)
			(xy 183.068325 -300.887996) (xy 183.103818 -300.922088) (xy 183.133383 -300.961432) (xy 183.156254 -301.005009)
			(xy 183.171838 -301.05169) (xy 183.179733 -301.100267) (xy 183.180228 -301.124874) (xy 183.519076 -301.124874)
			(xy 183.523036 -301.07582) (xy 183.534813 -301.028036) (xy 183.554104 -300.98276) (xy 183.580407 -300.941164)
			(xy 183.613042 -300.904327) (xy 183.651163 -300.873202) (xy 183.693784 -300.848595) (xy 183.7398 -300.831143)
			(xy 183.788019 -300.821299) (xy 183.837194 -300.819318) (xy 183.886049 -300.82525) (xy 183.93332 -300.838942)
			(xy 183.977782 -300.86004) (xy 184.018285 -300.887996) (xy 184.053778 -300.922088) (xy 184.083343 -300.961432)
			(xy 184.106214 -301.005009) (xy 184.121798 -301.05169) (xy 184.129693 -301.100267) (xy 184.130188 -301.124874)
			(xy 184.469036 -301.124874) (xy 184.472996 -301.07582) (xy 184.484773 -301.028036) (xy 184.504064 -300.98276)
			(xy 184.530367 -300.941164) (xy 184.563002 -300.904327) (xy 184.601123 -300.873202) (xy 184.643744 -300.848595)
			(xy 184.68976 -300.831143) (xy 184.737979 -300.821299) (xy 184.787154 -300.819318) (xy 184.836009 -300.82525)
			(xy 184.88328 -300.838942) (xy 184.927742 -300.86004) (xy 184.968245 -300.887996) (xy 185.003738 -300.922088)
			(xy 185.033303 -300.961432) (xy 185.056174 -301.005009) (xy 185.071758 -301.05169) (xy 185.079653 -301.100267)
			(xy 185.080148 -301.124874) (xy 185.41925 -301.124874) (xy 185.42321 -301.07582) (xy 185.434987 -301.028036)
			(xy 185.454278 -300.98276) (xy 185.480581 -300.941164) (xy 185.513216 -300.904327) (xy 185.551337 -300.873202)
			(xy 185.593958 -300.848595) (xy 185.639974 -300.831143) (xy 185.688193 -300.821299) (xy 185.737368 -300.819318)
			(xy 185.786223 -300.82525) (xy 185.833494 -300.838942) (xy 185.877956 -300.86004) (xy 185.918459 -300.887996)
			(xy 185.953952 -300.922088) (xy 185.983517 -300.961432) (xy 186.006388 -301.005009) (xy 186.021972 -301.05169)
			(xy 186.029867 -301.100267) (xy 186.030362 -301.124874) (xy 186.36921 -301.124874) (xy 186.37317 -301.07582)
			(xy 186.384947 -301.028036) (xy 186.404238 -300.98276) (xy 186.430541 -300.941164) (xy 186.463176 -300.904327)
			(xy 186.501297 -300.873202) (xy 186.543918 -300.848595) (xy 186.589934 -300.831143) (xy 186.638153 -300.821299)
			(xy 186.687328 -300.819318) (xy 186.736183 -300.82525) (xy 186.783454 -300.838942) (xy 186.827916 -300.86004)
			(xy 186.868419 -300.887996) (xy 186.903912 -300.922088) (xy 186.933477 -300.961432) (xy 186.956348 -301.005009)
			(xy 186.971932 -301.05169) (xy 186.979827 -301.100267) (xy 186.980322 -301.124874) (xy 187.31917 -301.124874)
			(xy 187.32313 -301.07582) (xy 187.334907 -301.028036) (xy 187.354198 -300.98276) (xy 187.380501 -300.941164)
			(xy 187.413136 -300.904327) (xy 187.451257 -300.873202) (xy 187.493878 -300.848595) (xy 187.539894 -300.831143)
			(xy 187.588113 -300.821299) (xy 187.637288 -300.819318) (xy 187.686143 -300.82525) (xy 187.733414 -300.838942)
			(xy 187.777876 -300.86004) (xy 187.818379 -300.887996) (xy 187.853872 -300.922088) (xy 187.883437 -300.961432)
			(xy 187.906308 -301.005009) (xy 187.921892 -301.05169) (xy 187.929787 -301.100267) (xy 187.930282 -301.124874)
			(xy 188.26913 -301.124874) (xy 188.27309 -301.07582) (xy 188.284867 -301.028036) (xy 188.304158 -300.98276)
			(xy 188.330461 -300.941164) (xy 188.363096 -300.904327) (xy 188.401217 -300.873202) (xy 188.443838 -300.848595)
			(xy 188.489854 -300.831143) (xy 188.538073 -300.821299) (xy 188.587248 -300.819318) (xy 188.636103 -300.82525)
			(xy 188.683374 -300.838942) (xy 188.727836 -300.86004) (xy 188.768339 -300.887996) (xy 188.803832 -300.922088)
			(xy 188.833397 -300.961432) (xy 188.856268 -301.005009) (xy 188.871852 -301.05169) (xy 188.879747 -301.100267)
			(xy 188.880242 -301.124874) (xy 189.21909 -301.124874) (xy 189.22305 -301.07582) (xy 189.234827 -301.028036)
			(xy 189.254118 -300.98276) (xy 189.280421 -300.941164) (xy 189.313056 -300.904327) (xy 189.351177 -300.873202)
			(xy 189.393798 -300.848595) (xy 189.439814 -300.831143) (xy 189.488033 -300.821299) (xy 189.537208 -300.819318)
			(xy 189.586063 -300.82525) (xy 189.633334 -300.838942) (xy 189.677796 -300.86004) (xy 189.718299 -300.887996)
			(xy 189.753792 -300.922088) (xy 189.783357 -300.961432) (xy 189.806228 -301.005009) (xy 189.821812 -301.05169)
			(xy 189.829707 -301.100267) (xy 189.830202 -301.124874) (xy 189.829707 -301.149481) (xy 189.821812 -301.198058)
			(xy 189.806228 -301.244739) (xy 189.783357 -301.288316) (xy 189.753792 -301.32766) (xy 189.718299 -301.361752)
			(xy 189.677796 -301.389708) (xy 189.633334 -301.410806) (xy 189.586063 -301.424498) (xy 189.537208 -301.43043)
			(xy 189.488033 -301.428449) (xy 189.439814 -301.418605) (xy 189.393798 -301.401153) (xy 189.351177 -301.376546)
			(xy 189.313056 -301.345421) (xy 189.280421 -301.308584) (xy 189.254118 -301.266988) (xy 189.234827 -301.221712)
			(xy 189.22305 -301.173928) (xy 189.21909 -301.124874) (xy 188.880242 -301.124874) (xy 188.879747 -301.149481)
			(xy 188.871852 -301.198058) (xy 188.856268 -301.244739) (xy 188.833397 -301.288316) (xy 188.803832 -301.32766)
			(xy 188.768339 -301.361752) (xy 188.727836 -301.389708) (xy 188.683374 -301.410806) (xy 188.636103 -301.424498)
			(xy 188.587248 -301.43043) (xy 188.538073 -301.428449) (xy 188.489854 -301.418605) (xy 188.443838 -301.401153)
			(xy 188.401217 -301.376546) (xy 188.363096 -301.345421) (xy 188.330461 -301.308584) (xy 188.304158 -301.266988)
			(xy 188.284867 -301.221712) (xy 188.27309 -301.173928) (xy 188.26913 -301.124874) (xy 187.930282 -301.124874)
			(xy 187.929787 -301.149481) (xy 187.921892 -301.198058) (xy 187.906308 -301.244739) (xy 187.883437 -301.288316)
			(xy 187.853872 -301.32766) (xy 187.818379 -301.361752) (xy 187.777876 -301.389708) (xy 187.733414 -301.410806)
			(xy 187.686143 -301.424498) (xy 187.637288 -301.43043) (xy 187.588113 -301.428449) (xy 187.539894 -301.418605)
			(xy 187.493878 -301.401153) (xy 187.451257 -301.376546) (xy 187.413136 -301.345421) (xy 187.380501 -301.308584)
			(xy 187.354198 -301.266988) (xy 187.334907 -301.221712) (xy 187.32313 -301.173928) (xy 187.31917 -301.124874)
			(xy 186.980322 -301.124874) (xy 186.979827 -301.149481) (xy 186.971932 -301.198058) (xy 186.956348 -301.244739)
			(xy 186.933477 -301.288316) (xy 186.903912 -301.32766) (xy 186.868419 -301.361752) (xy 186.827916 -301.389708)
			(xy 186.783454 -301.410806) (xy 186.736183 -301.424498) (xy 186.687328 -301.43043) (xy 186.638153 -301.428449)
			(xy 186.589934 -301.418605) (xy 186.543918 -301.401153) (xy 186.501297 -301.376546) (xy 186.463176 -301.345421)
			(xy 186.430541 -301.308584) (xy 186.404238 -301.266988) (xy 186.384947 -301.221712) (xy 186.37317 -301.173928)
			(xy 186.36921 -301.124874) (xy 186.030362 -301.124874) (xy 186.029867 -301.149481) (xy 186.021972 -301.198058)
			(xy 186.006388 -301.244739) (xy 185.983517 -301.288316) (xy 185.953952 -301.32766) (xy 185.918459 -301.361752)
			(xy 185.877956 -301.389708) (xy 185.833494 -301.410806) (xy 185.786223 -301.424498) (xy 185.737368 -301.43043)
			(xy 185.688193 -301.428449) (xy 185.639974 -301.418605) (xy 185.593958 -301.401153) (xy 185.551337 -301.376546)
			(xy 185.513216 -301.345421) (xy 185.480581 -301.308584) (xy 185.454278 -301.266988) (xy 185.434987 -301.221712)
			(xy 185.42321 -301.173928) (xy 185.41925 -301.124874) (xy 185.080148 -301.124874) (xy 185.079653 -301.149481)
			(xy 185.071758 -301.198058) (xy 185.056174 -301.244739) (xy 185.033303 -301.288316) (xy 185.003738 -301.32766)
			(xy 184.968245 -301.361752) (xy 184.927742 -301.389708) (xy 184.88328 -301.410806) (xy 184.836009 -301.424498)
			(xy 184.787154 -301.43043) (xy 184.737979 -301.428449) (xy 184.68976 -301.418605) (xy 184.643744 -301.401153)
			(xy 184.601123 -301.376546) (xy 184.563002 -301.345421) (xy 184.530367 -301.308584) (xy 184.504064 -301.266988)
			(xy 184.484773 -301.221712) (xy 184.472996 -301.173928) (xy 184.469036 -301.124874) (xy 184.130188 -301.124874)
			(xy 184.129693 -301.149481) (xy 184.121798 -301.198058) (xy 184.106214 -301.244739) (xy 184.083343 -301.288316)
			(xy 184.053778 -301.32766) (xy 184.018285 -301.361752) (xy 183.977782 -301.389708) (xy 183.93332 -301.410806)
			(xy 183.886049 -301.424498) (xy 183.837194 -301.43043) (xy 183.788019 -301.428449) (xy 183.7398 -301.418605)
			(xy 183.693784 -301.401153) (xy 183.651163 -301.376546) (xy 183.613042 -301.345421) (xy 183.580407 -301.308584)
			(xy 183.554104 -301.266988) (xy 183.534813 -301.221712) (xy 183.523036 -301.173928) (xy 183.519076 -301.124874)
			(xy 183.180228 -301.124874) (xy 183.179733 -301.149481) (xy 183.171838 -301.198058) (xy 183.156254 -301.244739)
			(xy 183.133383 -301.288316) (xy 183.103818 -301.32766) (xy 183.068325 -301.361752) (xy 183.027822 -301.389708)
			(xy 182.98336 -301.410806) (xy 182.936089 -301.424498) (xy 182.887234 -301.43043) (xy 182.838059 -301.428449)
			(xy 182.78984 -301.418605) (xy 182.743824 -301.401153) (xy 182.701203 -301.376546) (xy 182.663082 -301.345421)
			(xy 182.630447 -301.308584) (xy 182.604144 -301.266988) (xy 182.584853 -301.221712) (xy 182.573076 -301.173928)
			(xy 182.569116 -301.124874) (xy 182.230268 -301.124874) (xy 182.229773 -301.149481) (xy 182.221878 -301.198058)
			(xy 182.206294 -301.244739) (xy 182.183423 -301.288316) (xy 182.153858 -301.32766) (xy 182.118365 -301.361752)
			(xy 182.077862 -301.389708) (xy 182.0334 -301.410806) (xy 181.986129 -301.424498) (xy 181.937274 -301.43043)
			(xy 181.888099 -301.428449) (xy 181.83988 -301.418605) (xy 181.793864 -301.401153) (xy 181.751243 -301.376546)
			(xy 181.713122 -301.345421) (xy 181.680487 -301.308584) (xy 181.654184 -301.266988) (xy 181.634893 -301.221712)
			(xy 181.623116 -301.173928) (xy 181.619156 -301.124874) (xy 181.280308 -301.124874) (xy 181.279813 -301.149481)
			(xy 181.271918 -301.198058) (xy 181.256334 -301.244739) (xy 181.233463 -301.288316) (xy 181.203898 -301.32766)
			(xy 181.168405 -301.361752) (xy 181.127902 -301.389708) (xy 181.08344 -301.410806) (xy 181.036169 -301.424498)
			(xy 180.987314 -301.43043) (xy 180.938139 -301.428449) (xy 180.88992 -301.418605) (xy 180.843904 -301.401153)
			(xy 180.801283 -301.376546) (xy 180.763162 -301.345421) (xy 180.730527 -301.308584) (xy 180.704224 -301.266988)
			(xy 180.684933 -301.221712) (xy 180.673156 -301.173928) (xy 180.669196 -301.124874) (xy 180.330348 -301.124874)
			(xy 180.329853 -301.149481) (xy 180.321958 -301.198058) (xy 180.306374 -301.244739) (xy 180.283503 -301.288316)
			(xy 180.253938 -301.32766) (xy 180.218445 -301.361752) (xy 180.177942 -301.389708) (xy 180.13348 -301.410806)
			(xy 180.086209 -301.424498) (xy 180.037354 -301.43043) (xy 179.988179 -301.428449) (xy 179.93996 -301.418605)
			(xy 179.893944 -301.401153) (xy 179.851323 -301.376546) (xy 179.813202 -301.345421) (xy 179.780567 -301.308584)
			(xy 179.754264 -301.266988) (xy 179.734973 -301.221712) (xy 179.723196 -301.173928) (xy 179.719236 -301.124874)
			(xy 179.380388 -301.124874) (xy 179.379893 -301.149481) (xy 179.371998 -301.198058) (xy 179.356414 -301.244739)
			(xy 179.333543 -301.288316) (xy 179.303978 -301.32766) (xy 179.268485 -301.361752) (xy 179.227982 -301.389708)
			(xy 179.18352 -301.410806) (xy 179.136249 -301.424498) (xy 179.087394 -301.43043) (xy 179.038219 -301.428449)
			(xy 178.99 -301.418605) (xy 178.943984 -301.401153) (xy 178.901363 -301.376546) (xy 178.863242 -301.345421)
			(xy 178.830607 -301.308584) (xy 178.804304 -301.266988) (xy 178.785013 -301.221712) (xy 178.773236 -301.173928)
			(xy 178.769276 -301.124874) (xy 178.430174 -301.124874) (xy 178.429679 -301.149481) (xy 178.421784 -301.198058)
			(xy 178.4062 -301.244739) (xy 178.383329 -301.288316) (xy 178.353764 -301.32766) (xy 178.318271 -301.361752)
			(xy 178.277768 -301.389708) (xy 178.233306 -301.410806) (xy 178.186035 -301.424498) (xy 178.13718 -301.43043)
			(xy 178.088005 -301.428449) (xy 178.039786 -301.418605) (xy 177.99377 -301.401153) (xy 177.951149 -301.376546)
			(xy 177.913028 -301.345421) (xy 177.880393 -301.308584) (xy 177.85409 -301.266988) (xy 177.834799 -301.221712)
			(xy 177.823022 -301.173928) (xy 177.819062 -301.124874) (xy 177.480214 -301.124874) (xy 177.479719 -301.149481)
			(xy 177.471824 -301.198058) (xy 177.45624 -301.244739) (xy 177.433369 -301.288316) (xy 177.403804 -301.32766)
			(xy 177.368311 -301.361752) (xy 177.327808 -301.389708) (xy 177.283346 -301.410806) (xy 177.236075 -301.424498)
			(xy 177.18722 -301.43043) (xy 177.138045 -301.428449) (xy 177.089826 -301.418605) (xy 177.04381 -301.401153)
			(xy 177.001189 -301.376546) (xy 176.963068 -301.345421) (xy 176.930433 -301.308584) (xy 176.90413 -301.266988)
			(xy 176.884839 -301.221712) (xy 176.873062 -301.173928) (xy 176.869102 -301.124874) (xy 176.530254 -301.124874)
			(xy 176.529759 -301.149481) (xy 176.521864 -301.198058) (xy 176.50628 -301.244739) (xy 176.483409 -301.288316)
			(xy 176.453844 -301.32766) (xy 176.418351 -301.361752) (xy 176.377848 -301.389708) (xy 176.333386 -301.410806)
			(xy 176.286115 -301.424498) (xy 176.23726 -301.43043) (xy 176.188085 -301.428449) (xy 176.139866 -301.418605)
			(xy 176.09385 -301.401153) (xy 176.051229 -301.376546) (xy 176.013108 -301.345421) (xy 175.980473 -301.308584)
			(xy 175.95417 -301.266988) (xy 175.934879 -301.221712) (xy 175.923102 -301.173928) (xy 175.919142 -301.124874)
			(xy 174.630334 -301.124874) (xy 174.629839 -301.149481) (xy 174.621944 -301.198058) (xy 174.60636 -301.244739)
			(xy 174.583489 -301.288316) (xy 174.553924 -301.32766) (xy 174.518431 -301.361752) (xy 174.477928 -301.389708)
			(xy 174.433466 -301.410806) (xy 174.386195 -301.424498) (xy 174.33734 -301.43043) (xy 174.288165 -301.428449)
			(xy 174.239946 -301.418605) (xy 174.19393 -301.401153) (xy 174.151309 -301.376546) (xy 174.113188 -301.345421)
			(xy 174.080553 -301.308584) (xy 174.05425 -301.266988) (xy 174.034959 -301.221712) (xy 174.023182 -301.173928)
			(xy 174.019222 -301.124874) (xy 173.680374 -301.124874) (xy 173.679879 -301.149481) (xy 173.671984 -301.198058)
			(xy 173.6564 -301.244739) (xy 173.633529 -301.288316) (xy 173.603964 -301.32766) (xy 173.568471 -301.361752)
			(xy 173.527968 -301.389708) (xy 173.483506 -301.410806) (xy 173.436235 -301.424498) (xy 173.38738 -301.43043)
			(xy 173.338205 -301.428449) (xy 173.289986 -301.418605) (xy 173.24397 -301.401153) (xy 173.201349 -301.376546)
			(xy 173.163228 -301.345421) (xy 173.130593 -301.308584) (xy 173.10429 -301.266988) (xy 173.084999 -301.221712)
			(xy 173.073222 -301.173928) (xy 173.069262 -301.124874) (xy 172.73016 -301.124874) (xy 172.729665 -301.149481)
			(xy 172.72177 -301.198058) (xy 172.706186 -301.244739) (xy 172.683315 -301.288316) (xy 172.65375 -301.32766)
			(xy 172.618257 -301.361752) (xy 172.577754 -301.389708) (xy 172.533292 -301.410806) (xy 172.486021 -301.424498)
			(xy 172.437166 -301.43043) (xy 172.387991 -301.428449) (xy 172.339772 -301.418605) (xy 172.293756 -301.401153)
			(xy 172.251135 -301.376546) (xy 172.213014 -301.345421) (xy 172.180379 -301.308584) (xy 172.154076 -301.266988)
			(xy 172.134785 -301.221712) (xy 172.123008 -301.173928) (xy 172.119048 -301.124874) (xy 171.7802 -301.124874)
			(xy 171.779705 -301.149481) (xy 171.77181 -301.198058) (xy 171.756226 -301.244739) (xy 171.733355 -301.288316)
			(xy 171.70379 -301.32766) (xy 171.668297 -301.361752) (xy 171.627794 -301.389708) (xy 171.583332 -301.410806)
			(xy 171.536061 -301.424498) (xy 171.487206 -301.43043) (xy 171.438031 -301.428449) (xy 171.389812 -301.418605)
			(xy 171.343796 -301.401153) (xy 171.301175 -301.376546) (xy 171.263054 -301.345421) (xy 171.230419 -301.308584)
			(xy 171.204116 -301.266988) (xy 171.184825 -301.221712) (xy 171.173048 -301.173928) (xy 171.169088 -301.124874)
			(xy 170.83024 -301.124874) (xy 170.829745 -301.149481) (xy 170.82185 -301.198058) (xy 170.806266 -301.244739)
			(xy 170.783395 -301.288316) (xy 170.75383 -301.32766) (xy 170.718337 -301.361752) (xy 170.677834 -301.389708)
			(xy 170.633372 -301.410806) (xy 170.586101 -301.424498) (xy 170.537246 -301.43043) (xy 170.488071 -301.428449)
			(xy 170.439852 -301.418605) (xy 170.393836 -301.401153) (xy 170.351215 -301.376546) (xy 170.313094 -301.345421)
			(xy 170.280459 -301.308584) (xy 170.254156 -301.266988) (xy 170.234865 -301.221712) (xy 170.223088 -301.173928)
			(xy 170.219128 -301.124874) (xy 169.88028 -301.124874) (xy 169.879785 -301.149481) (xy 169.87189 -301.198058)
			(xy 169.856306 -301.244739) (xy 169.833435 -301.288316) (xy 169.80387 -301.32766) (xy 169.768377 -301.361752)
			(xy 169.727874 -301.389708) (xy 169.683412 -301.410806) (xy 169.636141 -301.424498) (xy 169.587286 -301.43043)
			(xy 169.538111 -301.428449) (xy 169.489892 -301.418605) (xy 169.443876 -301.401153) (xy 169.401255 -301.376546)
			(xy 169.363134 -301.345421) (xy 169.330499 -301.308584) (xy 169.304196 -301.266988) (xy 169.284905 -301.221712)
			(xy 169.273128 -301.173928) (xy 169.269168 -301.124874) (xy 168.93032 -301.124874) (xy 168.929825 -301.149481)
			(xy 168.92193 -301.198058) (xy 168.906346 -301.244739) (xy 168.883475 -301.288316) (xy 168.85391 -301.32766)
			(xy 168.818417 -301.361752) (xy 168.777914 -301.389708) (xy 168.733452 -301.410806) (xy 168.686181 -301.424498)
			(xy 168.637326 -301.43043) (xy 168.588151 -301.428449) (xy 168.539932 -301.418605) (xy 168.493916 -301.401153)
			(xy 168.451295 -301.376546) (xy 168.413174 -301.345421) (xy 168.380539 -301.308584) (xy 168.354236 -301.266988)
			(xy 168.334945 -301.221712) (xy 168.323168 -301.173928) (xy 168.319208 -301.124874) (xy 167.98036 -301.124874)
			(xy 167.979865 -301.149481) (xy 167.97197 -301.198058) (xy 167.956386 -301.244739) (xy 167.933515 -301.288316)
			(xy 167.90395 -301.32766) (xy 167.868457 -301.361752) (xy 167.827954 -301.389708) (xy 167.783492 -301.410806)
			(xy 167.736221 -301.424498) (xy 167.687366 -301.43043) (xy 167.638191 -301.428449) (xy 167.589972 -301.418605)
			(xy 167.543956 -301.401153) (xy 167.501335 -301.376546) (xy 167.463214 -301.345421) (xy 167.430579 -301.308584)
			(xy 167.404276 -301.266988) (xy 167.384985 -301.221712) (xy 167.373208 -301.173928) (xy 167.369248 -301.124874)
			(xy 167.0304 -301.124874) (xy 167.029905 -301.149481) (xy 167.02201 -301.198058) (xy 167.006426 -301.244739)
			(xy 166.983555 -301.288316) (xy 166.95399 -301.32766) (xy 166.918497 -301.361752) (xy 166.877994 -301.389708)
			(xy 166.833532 -301.410806) (xy 166.786261 -301.424498) (xy 166.737406 -301.43043) (xy 166.688231 -301.428449)
			(xy 166.640012 -301.418605) (xy 166.593996 -301.401153) (xy 166.551375 -301.376546) (xy 166.513254 -301.345421)
			(xy 166.480619 -301.308584) (xy 166.454316 -301.266988) (xy 166.435025 -301.221712) (xy 166.423248 -301.173928)
			(xy 166.419288 -301.124874) (xy 166.127938 -301.124874) (xy 166.127938 -301.492158) (xy 166.128192 -301.503334)
			(xy 166.128192 -301.696628) (xy 166.127938 -301.70755) (xy 166.127938 -302.074834) (xy 166.419288 -302.074834)
			(xy 166.423248 -302.02578) (xy 166.435025 -301.977996) (xy 166.454316 -301.93272) (xy 166.480619 -301.891124)
			(xy 166.513254 -301.854287) (xy 166.551375 -301.823162) (xy 166.593996 -301.798555) (xy 166.640012 -301.781103)
			(xy 166.688231 -301.771259) (xy 166.737406 -301.769278) (xy 166.786261 -301.77521) (xy 166.833532 -301.788902)
			(xy 166.877994 -301.81) (xy 166.918497 -301.837956) (xy 166.95399 -301.872048) (xy 166.983555 -301.911392)
			(xy 167.006426 -301.954969) (xy 167.02201 -302.00165) (xy 167.029905 -302.050227) (xy 167.0304 -302.074834)
			(xy 167.369248 -302.074834) (xy 167.373208 -302.02578) (xy 167.384985 -301.977996) (xy 167.404276 -301.93272)
			(xy 167.430579 -301.891124) (xy 167.463214 -301.854287) (xy 167.501335 -301.823162) (xy 167.543956 -301.798555)
			(xy 167.589972 -301.781103) (xy 167.638191 -301.771259) (xy 167.687366 -301.769278) (xy 167.736221 -301.77521)
			(xy 167.783492 -301.788902) (xy 167.827954 -301.81) (xy 167.868457 -301.837956) (xy 167.90395 -301.872048)
			(xy 167.933515 -301.911392) (xy 167.956386 -301.954969) (xy 167.97197 -302.00165) (xy 167.979865 -302.050227)
			(xy 167.98036 -302.074834) (xy 168.319208 -302.074834) (xy 168.323168 -302.02578) (xy 168.334945 -301.977996)
			(xy 168.354236 -301.93272) (xy 168.380539 -301.891124) (xy 168.413174 -301.854287) (xy 168.451295 -301.823162)
			(xy 168.493916 -301.798555) (xy 168.539932 -301.781103) (xy 168.588151 -301.771259) (xy 168.637326 -301.769278)
			(xy 168.686181 -301.77521) (xy 168.733452 -301.788902) (xy 168.777914 -301.81) (xy 168.818417 -301.837956)
			(xy 168.85391 -301.872048) (xy 168.883475 -301.911392) (xy 168.906346 -301.954969) (xy 168.92193 -302.00165)
			(xy 168.929825 -302.050227) (xy 168.93032 -302.074834) (xy 169.269168 -302.074834) (xy 169.273128 -302.02578)
			(xy 169.284905 -301.977996) (xy 169.304196 -301.93272) (xy 169.330499 -301.891124) (xy 169.363134 -301.854287)
			(xy 169.401255 -301.823162) (xy 169.443876 -301.798555) (xy 169.489892 -301.781103) (xy 169.538111 -301.771259)
			(xy 169.587286 -301.769278) (xy 169.636141 -301.77521) (xy 169.683412 -301.788902) (xy 169.727874 -301.81)
			(xy 169.768377 -301.837956) (xy 169.80387 -301.872048) (xy 169.833435 -301.911392) (xy 169.856306 -301.954969)
			(xy 169.87189 -302.00165) (xy 169.879785 -302.050227) (xy 169.88028 -302.074834) (xy 170.219128 -302.074834)
			(xy 170.223088 -302.02578) (xy 170.234865 -301.977996) (xy 170.254156 -301.93272) (xy 170.280459 -301.891124)
			(xy 170.313094 -301.854287) (xy 170.351215 -301.823162) (xy 170.393836 -301.798555) (xy 170.439852 -301.781103)
			(xy 170.488071 -301.771259) (xy 170.537246 -301.769278) (xy 170.586101 -301.77521) (xy 170.633372 -301.788902)
			(xy 170.677834 -301.81) (xy 170.718337 -301.837956) (xy 170.75383 -301.872048) (xy 170.783395 -301.911392)
			(xy 170.806266 -301.954969) (xy 170.82185 -302.00165) (xy 170.829745 -302.050227) (xy 170.83024 -302.074834)
			(xy 171.169088 -302.074834) (xy 171.173048 -302.02578) (xy 171.184825 -301.977996) (xy 171.204116 -301.93272)
			(xy 171.230419 -301.891124) (xy 171.263054 -301.854287) (xy 171.301175 -301.823162) (xy 171.343796 -301.798555)
			(xy 171.389812 -301.781103) (xy 171.438031 -301.771259) (xy 171.487206 -301.769278) (xy 171.536061 -301.77521)
			(xy 171.583332 -301.788902) (xy 171.627794 -301.81) (xy 171.668297 -301.837956) (xy 171.70379 -301.872048)
			(xy 171.733355 -301.911392) (xy 171.756226 -301.954969) (xy 171.77181 -302.00165) (xy 171.779705 -302.050227)
			(xy 171.7802 -302.074834) (xy 172.119048 -302.074834) (xy 172.123008 -302.02578) (xy 172.134785 -301.977996)
			(xy 172.154076 -301.93272) (xy 172.180379 -301.891124) (xy 172.213014 -301.854287) (xy 172.251135 -301.823162)
			(xy 172.293756 -301.798555) (xy 172.339772 -301.781103) (xy 172.387991 -301.771259) (xy 172.437166 -301.769278)
			(xy 172.486021 -301.77521) (xy 172.533292 -301.788902) (xy 172.577754 -301.81) (xy 172.618257 -301.837956)
			(xy 172.65375 -301.872048) (xy 172.683315 -301.911392) (xy 172.706186 -301.954969) (xy 172.72177 -302.00165)
			(xy 172.729665 -302.050227) (xy 172.73016 -302.074834) (xy 173.069262 -302.074834) (xy 173.073222 -302.02578)
			(xy 173.084999 -301.977996) (xy 173.10429 -301.93272) (xy 173.130593 -301.891124) (xy 173.163228 -301.854287)
			(xy 173.201349 -301.823162) (xy 173.24397 -301.798555) (xy 173.289986 -301.781103) (xy 173.338205 -301.771259)
			(xy 173.38738 -301.769278) (xy 173.436235 -301.77521) (xy 173.483506 -301.788902) (xy 173.527968 -301.81)
			(xy 173.568471 -301.837956) (xy 173.603964 -301.872048) (xy 173.633529 -301.911392) (xy 173.6564 -301.954969)
			(xy 173.671984 -302.00165) (xy 173.679879 -302.050227) (xy 173.680374 -302.074834) (xy 174.019222 -302.074834)
			(xy 174.023182 -302.02578) (xy 174.034959 -301.977996) (xy 174.05425 -301.93272) (xy 174.080553 -301.891124)
			(xy 174.113188 -301.854287) (xy 174.151309 -301.823162) (xy 174.19393 -301.798555) (xy 174.239946 -301.781103)
			(xy 174.288165 -301.771259) (xy 174.33734 -301.769278) (xy 174.386195 -301.77521) (xy 174.433466 -301.788902)
			(xy 174.477928 -301.81) (xy 174.518431 -301.837956) (xy 174.553924 -301.872048) (xy 174.583489 -301.911392)
			(xy 174.60636 -301.954969) (xy 174.621944 -302.00165) (xy 174.629839 -302.050227) (xy 174.630334 -302.074834)
			(xy 175.919142 -302.074834) (xy 175.923102 -302.02578) (xy 175.934879 -301.977996) (xy 175.95417 -301.93272)
			(xy 175.980473 -301.891124) (xy 176.013108 -301.854287) (xy 176.051229 -301.823162) (xy 176.09385 -301.798555)
			(xy 176.139866 -301.781103) (xy 176.188085 -301.771259) (xy 176.23726 -301.769278) (xy 176.286115 -301.77521)
			(xy 176.333386 -301.788902) (xy 176.377848 -301.81) (xy 176.418351 -301.837956) (xy 176.453844 -301.872048)
			(xy 176.483409 -301.911392) (xy 176.50628 -301.954969) (xy 176.521864 -302.00165) (xy 176.529759 -302.050227)
			(xy 176.530254 -302.074834) (xy 176.869102 -302.074834) (xy 176.873062 -302.02578) (xy 176.884839 -301.977996)
			(xy 176.90413 -301.93272) (xy 176.930433 -301.891124) (xy 176.963068 -301.854287) (xy 177.001189 -301.823162)
			(xy 177.04381 -301.798555) (xy 177.089826 -301.781103) (xy 177.138045 -301.771259) (xy 177.18722 -301.769278)
			(xy 177.236075 -301.77521) (xy 177.283346 -301.788902) (xy 177.327808 -301.81) (xy 177.368311 -301.837956)
			(xy 177.403804 -301.872048) (xy 177.433369 -301.911392) (xy 177.45624 -301.954969) (xy 177.471824 -302.00165)
			(xy 177.479719 -302.050227) (xy 177.480214 -302.074834) (xy 177.819062 -302.074834) (xy 177.823022 -302.02578)
			(xy 177.834799 -301.977996) (xy 177.85409 -301.93272) (xy 177.880393 -301.891124) (xy 177.913028 -301.854287)
			(xy 177.951149 -301.823162) (xy 177.99377 -301.798555) (xy 178.039786 -301.781103) (xy 178.088005 -301.771259)
			(xy 178.13718 -301.769278) (xy 178.186035 -301.77521) (xy 178.233306 -301.788902) (xy 178.277768 -301.81)
			(xy 178.318271 -301.837956) (xy 178.353764 -301.872048) (xy 178.383329 -301.911392) (xy 178.4062 -301.954969)
			(xy 178.421784 -302.00165) (xy 178.429679 -302.050227) (xy 178.430174 -302.074834) (xy 178.769276 -302.074834)
			(xy 178.773236 -302.02578) (xy 178.785013 -301.977996) (xy 178.804304 -301.93272) (xy 178.830607 -301.891124)
			(xy 178.863242 -301.854287) (xy 178.901363 -301.823162) (xy 178.943984 -301.798555) (xy 178.99 -301.781103)
			(xy 179.038219 -301.771259) (xy 179.087394 -301.769278) (xy 179.136249 -301.77521) (xy 179.18352 -301.788902)
			(xy 179.227982 -301.81) (xy 179.268485 -301.837956) (xy 179.303978 -301.872048) (xy 179.333543 -301.911392)
			(xy 179.356414 -301.954969) (xy 179.371998 -302.00165) (xy 179.379893 -302.050227) (xy 179.380388 -302.074834)
			(xy 179.719236 -302.074834) (xy 179.723196 -302.02578) (xy 179.734973 -301.977996) (xy 179.754264 -301.93272)
			(xy 179.780567 -301.891124) (xy 179.813202 -301.854287) (xy 179.851323 -301.823162) (xy 179.893944 -301.798555)
			(xy 179.93996 -301.781103) (xy 179.988179 -301.771259) (xy 180.037354 -301.769278) (xy 180.086209 -301.77521)
			(xy 180.13348 -301.788902) (xy 180.177942 -301.81) (xy 180.218445 -301.837956) (xy 180.253938 -301.872048)
			(xy 180.283503 -301.911392) (xy 180.306374 -301.954969) (xy 180.321958 -302.00165) (xy 180.329853 -302.050227)
			(xy 180.330348 -302.074834) (xy 180.669196 -302.074834) (xy 180.673156 -302.02578) (xy 180.684933 -301.977996)
			(xy 180.704224 -301.93272) (xy 180.730527 -301.891124) (xy 180.763162 -301.854287) (xy 180.801283 -301.823162)
			(xy 180.843904 -301.798555) (xy 180.88992 -301.781103) (xy 180.938139 -301.771259) (xy 180.987314 -301.769278)
			(xy 181.036169 -301.77521) (xy 181.08344 -301.788902) (xy 181.127902 -301.81) (xy 181.168405 -301.837956)
			(xy 181.203898 -301.872048) (xy 181.233463 -301.911392) (xy 181.256334 -301.954969) (xy 181.271918 -302.00165)
			(xy 181.279813 -302.050227) (xy 181.280308 -302.074834) (xy 181.619156 -302.074834) (xy 181.623116 -302.02578)
			(xy 181.634893 -301.977996) (xy 181.654184 -301.93272) (xy 181.680487 -301.891124) (xy 181.713122 -301.854287)
			(xy 181.751243 -301.823162) (xy 181.793864 -301.798555) (xy 181.83988 -301.781103) (xy 181.888099 -301.771259)
			(xy 181.937274 -301.769278) (xy 181.986129 -301.77521) (xy 182.0334 -301.788902) (xy 182.077862 -301.81)
			(xy 182.118365 -301.837956) (xy 182.153858 -301.872048) (xy 182.183423 -301.911392) (xy 182.206294 -301.954969)
			(xy 182.221878 -302.00165) (xy 182.229773 -302.050227) (xy 182.230268 -302.074834) (xy 182.569116 -302.074834)
			(xy 182.573076 -302.02578) (xy 182.584853 -301.977996) (xy 182.604144 -301.93272) (xy 182.630447 -301.891124)
			(xy 182.663082 -301.854287) (xy 182.701203 -301.823162) (xy 182.743824 -301.798555) (xy 182.78984 -301.781103)
			(xy 182.838059 -301.771259) (xy 182.887234 -301.769278) (xy 182.936089 -301.77521) (xy 182.98336 -301.788902)
			(xy 183.027822 -301.81) (xy 183.068325 -301.837956) (xy 183.103818 -301.872048) (xy 183.133383 -301.911392)
			(xy 183.156254 -301.954969) (xy 183.171838 -302.00165) (xy 183.179733 -302.050227) (xy 183.180228 -302.074834)
			(xy 183.519076 -302.074834) (xy 183.523036 -302.02578) (xy 183.534813 -301.977996) (xy 183.554104 -301.93272)
			(xy 183.580407 -301.891124) (xy 183.613042 -301.854287) (xy 183.651163 -301.823162) (xy 183.693784 -301.798555)
			(xy 183.7398 -301.781103) (xy 183.788019 -301.771259) (xy 183.837194 -301.769278) (xy 183.886049 -301.77521)
			(xy 183.93332 -301.788902) (xy 183.977782 -301.81) (xy 184.018285 -301.837956) (xy 184.053778 -301.872048)
			(xy 184.083343 -301.911392) (xy 184.106214 -301.954969) (xy 184.121798 -302.00165) (xy 184.129693 -302.050227)
			(xy 184.130188 -302.074834) (xy 184.469036 -302.074834) (xy 184.472996 -302.02578) (xy 184.484773 -301.977996)
			(xy 184.504064 -301.93272) (xy 184.530367 -301.891124) (xy 184.563002 -301.854287) (xy 184.601123 -301.823162)
			(xy 184.643744 -301.798555) (xy 184.68976 -301.781103) (xy 184.737979 -301.771259) (xy 184.787154 -301.769278)
			(xy 184.836009 -301.77521) (xy 184.88328 -301.788902) (xy 184.927742 -301.81) (xy 184.968245 -301.837956)
			(xy 185.003738 -301.872048) (xy 185.033303 -301.911392) (xy 185.056174 -301.954969) (xy 185.071758 -302.00165)
			(xy 185.079653 -302.050227) (xy 185.080148 -302.074834) (xy 185.41925 -302.074834) (xy 185.42321 -302.02578)
			(xy 185.434987 -301.977996) (xy 185.454278 -301.93272) (xy 185.480581 -301.891124) (xy 185.513216 -301.854287)
			(xy 185.551337 -301.823162) (xy 185.593958 -301.798555) (xy 185.639974 -301.781103) (xy 185.688193 -301.771259)
			(xy 185.737368 -301.769278) (xy 185.786223 -301.77521) (xy 185.833494 -301.788902) (xy 185.877956 -301.81)
			(xy 185.918459 -301.837956) (xy 185.953952 -301.872048) (xy 185.983517 -301.911392) (xy 186.006388 -301.954969)
			(xy 186.021972 -302.00165) (xy 186.029867 -302.050227) (xy 186.030362 -302.074834) (xy 186.36921 -302.074834)
			(xy 186.37317 -302.02578) (xy 186.384947 -301.977996) (xy 186.404238 -301.93272) (xy 186.430541 -301.891124)
			(xy 186.463176 -301.854287) (xy 186.501297 -301.823162) (xy 186.543918 -301.798555) (xy 186.589934 -301.781103)
			(xy 186.638153 -301.771259) (xy 186.687328 -301.769278) (xy 186.736183 -301.77521) (xy 186.783454 -301.788902)
			(xy 186.827916 -301.81) (xy 186.868419 -301.837956) (xy 186.903912 -301.872048) (xy 186.933477 -301.911392)
			(xy 186.956348 -301.954969) (xy 186.971932 -302.00165) (xy 186.979827 -302.050227) (xy 186.980322 -302.074834)
			(xy 187.31917 -302.074834) (xy 187.32313 -302.02578) (xy 187.334907 -301.977996) (xy 187.354198 -301.93272)
			(xy 187.380501 -301.891124) (xy 187.413136 -301.854287) (xy 187.451257 -301.823162) (xy 187.493878 -301.798555)
			(xy 187.539894 -301.781103) (xy 187.588113 -301.771259) (xy 187.637288 -301.769278) (xy 187.686143 -301.77521)
			(xy 187.733414 -301.788902) (xy 187.777876 -301.81) (xy 187.818379 -301.837956) (xy 187.853872 -301.872048)
			(xy 187.883437 -301.911392) (xy 187.906308 -301.954969) (xy 187.921892 -302.00165) (xy 187.929787 -302.050227)
			(xy 187.930282 -302.074834) (xy 188.26913 -302.074834) (xy 188.27309 -302.02578) (xy 188.284867 -301.977996)
			(xy 188.304158 -301.93272) (xy 188.330461 -301.891124) (xy 188.363096 -301.854287) (xy 188.401217 -301.823162)
			(xy 188.443838 -301.798555) (xy 188.489854 -301.781103) (xy 188.538073 -301.771259) (xy 188.587248 -301.769278)
			(xy 188.636103 -301.77521) (xy 188.683374 -301.788902) (xy 188.727836 -301.81) (xy 188.768339 -301.837956)
			(xy 188.803832 -301.872048) (xy 188.833397 -301.911392) (xy 188.856268 -301.954969) (xy 188.871852 -302.00165)
			(xy 188.879747 -302.050227) (xy 188.880242 -302.074834) (xy 188.880076 -302.083066) (xy 189.219187 -302.083066)
			(xy 189.221877 -302.033498) (xy 189.232551 -301.985017) (xy 189.250928 -301.938902) (xy 189.276523 -301.896368)
			(xy 189.308663 -301.858535) (xy 189.3465 -301.8264) (xy 189.389038 -301.80081) (xy 189.435155 -301.782439)
			(xy 189.483637 -301.771771) (xy 189.533206 -301.769088) (xy 189.582557 -301.774459) (xy 189.630388 -301.787744)
			(xy 189.67544 -301.808592) (xy 189.716525 -301.836454) (xy 189.752561 -301.870596) (xy 189.782599 -301.910118)
			(xy 189.805847 -301.95398) (xy 189.821693 -302.001024) (xy 189.829719 -302.050013) (xy 189.83004 -302.06653)
			(xy 191.119415 -302.06653) (xy 191.124779 -302.017186) (xy 191.138056 -301.969361) (xy 191.158894 -301.924313)
			(xy 191.186745 -301.88323) (xy 191.220876 -301.847194) (xy 191.260387 -301.817154) (xy 191.304237 -301.793901)
			(xy 191.351272 -301.778049) (xy 191.400251 -301.770014) (xy 191.425068 -301.769526) (xy 191.439251 -301.769707)
			(xy 191.467491 -301.772376) (xy 191.481456 -301.77486) (xy 191.493902 -301.777146) (xy 191.517524 -301.76978)
			(xy 191.594994 -301.69231) (xy 191.60236 -301.668688) (xy 191.600074 -301.656242) (xy 191.597593 -301.642277)
			(xy 191.594924 -301.614037) (xy 191.59474 -301.599854) (xy 191.595096 -301.575857) (xy 191.602611 -301.528456)
			(xy 191.617449 -301.482813) (xy 191.639244 -301.440054) (xy 191.66746 -301.40123) (xy 191.701402 -301.367299)
			(xy 191.740234 -301.339095) (xy 191.783 -301.317313) (xy 191.828647 -301.302489) (xy 191.876051 -301.294989)
			(xy 191.900048 -301.294546) (xy 191.914231 -301.294731) (xy 191.942471 -301.297397) (xy 191.956436 -301.29988)
			(xy 191.968882 -301.302166) (xy 191.992504 -301.2948) (xy 192.069974 -301.21733) (xy 192.07734 -301.193708)
			(xy 192.075054 -301.181262) (xy 192.072577 -301.167296) (xy 192.069905 -301.139057) (xy 192.06972 -301.124874)
			(xy 192.070206 -301.100056) (xy 192.07824 -301.051075) (xy 192.094092 -301.004039) (xy 192.117345 -300.960187)
			(xy 192.147385 -300.920674) (xy 192.183422 -300.886542) (xy 192.224507 -300.858689) (xy 192.269556 -300.837849)
			(xy 192.317382 -300.824572) (xy 192.366727 -300.819207) (xy 192.41629 -300.821895) (xy 192.464765 -300.832566)
			(xy 192.510875 -300.850939) (xy 192.553406 -300.876529) (xy 192.591236 -300.908663) (xy 192.62337 -300.946493)
			(xy 192.64896 -300.989023) (xy 192.667333 -301.035133) (xy 192.678004 -301.083608) (xy 192.680243 -301.124874)
			(xy 193.019184 -301.124874) (xy 193.023144 -301.07582) (xy 193.034921 -301.028036) (xy 193.054212 -300.98276)
			(xy 193.080515 -300.941164) (xy 193.11315 -300.904327) (xy 193.151271 -300.873202) (xy 193.193892 -300.848595)
			(xy 193.239908 -300.831143) (xy 193.288127 -300.821299) (xy 193.337302 -300.819318) (xy 193.386157 -300.82525)
			(xy 193.433428 -300.838942) (xy 193.47789 -300.86004) (xy 193.518393 -300.887996) (xy 193.553886 -300.922088)
			(xy 193.583451 -300.961432) (xy 193.606322 -301.005009) (xy 193.621906 -301.05169) (xy 193.629801 -301.100267)
			(xy 193.630296 -301.124874) (xy 193.969144 -301.124874) (xy 193.973104 -301.07582) (xy 193.984881 -301.028036)
			(xy 194.004172 -300.98276) (xy 194.030475 -300.941164) (xy 194.06311 -300.904327) (xy 194.101231 -300.873202)
			(xy 194.143852 -300.848595) (xy 194.189868 -300.831143) (xy 194.238087 -300.821299) (xy 194.287262 -300.819318)
			(xy 194.336117 -300.82525) (xy 194.383388 -300.838942) (xy 194.42785 -300.86004) (xy 194.468353 -300.887996)
			(xy 194.503846 -300.922088) (xy 194.533411 -300.961432) (xy 194.556282 -301.005009) (xy 194.571866 -301.05169)
			(xy 194.579761 -301.100267) (xy 194.580256 -301.124874) (xy 194.919104 -301.124874) (xy 194.923064 -301.07582)
			(xy 194.934841 -301.028036) (xy 194.954132 -300.98276) (xy 194.980435 -300.941164) (xy 195.01307 -300.904327)
			(xy 195.051191 -300.873202) (xy 195.093812 -300.848595) (xy 195.139828 -300.831143) (xy 195.188047 -300.821299)
			(xy 195.237222 -300.819318) (xy 195.286077 -300.82525) (xy 195.333348 -300.838942) (xy 195.37781 -300.86004)
			(xy 195.418313 -300.887996) (xy 195.453806 -300.922088) (xy 195.483371 -300.961432) (xy 195.506242 -301.005009)
			(xy 195.521826 -301.05169) (xy 195.529721 -301.100267) (xy 195.530216 -301.124874) (xy 195.869064 -301.124874)
			(xy 195.873024 -301.07582) (xy 195.884801 -301.028036) (xy 195.904092 -300.98276) (xy 195.930395 -300.941164)
			(xy 195.96303 -300.904327) (xy 196.001151 -300.873202) (xy 196.043772 -300.848595) (xy 196.089788 -300.831143)
			(xy 196.138007 -300.821299) (xy 196.187182 -300.819318) (xy 196.236037 -300.82525) (xy 196.283308 -300.838942)
			(xy 196.32777 -300.86004) (xy 196.368273 -300.887996) (xy 196.403766 -300.922088) (xy 196.433331 -300.961432)
			(xy 196.456202 -301.005009) (xy 196.471786 -301.05169) (xy 196.479681 -301.100267) (xy 196.480176 -301.124874)
			(xy 196.819278 -301.124874) (xy 196.823238 -301.07582) (xy 196.835015 -301.028036) (xy 196.854306 -300.98276)
			(xy 196.880609 -300.941164) (xy 196.913244 -300.904327) (xy 196.951365 -300.873202) (xy 196.993986 -300.848595)
			(xy 197.040002 -300.831143) (xy 197.088221 -300.821299) (xy 197.137396 -300.819318) (xy 197.186251 -300.82525)
			(xy 197.233522 -300.838942) (xy 197.277984 -300.86004) (xy 197.318487 -300.887996) (xy 197.35398 -300.922088)
			(xy 197.383545 -300.961432) (xy 197.406416 -301.005009) (xy 197.422 -301.05169) (xy 197.429895 -301.100267)
			(xy 197.43039 -301.124874) (xy 197.769238 -301.124874) (xy 197.773198 -301.07582) (xy 197.784975 -301.028036)
			(xy 197.804266 -300.98276) (xy 197.830569 -300.941164) (xy 197.863204 -300.904327) (xy 197.901325 -300.873202)
			(xy 197.943946 -300.848595) (xy 197.989962 -300.831143) (xy 198.038181 -300.821299) (xy 198.087356 -300.819318)
			(xy 198.136211 -300.82525) (xy 198.183482 -300.838942) (xy 198.227944 -300.86004) (xy 198.268447 -300.887996)
			(xy 198.30394 -300.922088) (xy 198.333505 -300.961432) (xy 198.356376 -301.005009) (xy 198.37196 -301.05169)
			(xy 198.379855 -301.100267) (xy 198.38035 -301.124874) (xy 198.719198 -301.124874) (xy 198.723158 -301.07582)
			(xy 198.734935 -301.028036) (xy 198.754226 -300.98276) (xy 198.780529 -300.941164) (xy 198.813164 -300.904327)
			(xy 198.851285 -300.873202) (xy 198.893906 -300.848595) (xy 198.939922 -300.831143) (xy 198.988141 -300.821299)
			(xy 199.037316 -300.819318) (xy 199.086171 -300.82525) (xy 199.133442 -300.838942) (xy 199.177904 -300.86004)
			(xy 199.218407 -300.887996) (xy 199.2539 -300.922088) (xy 199.283465 -300.961432) (xy 199.306336 -301.005009)
			(xy 199.32192 -301.05169) (xy 199.329815 -301.100267) (xy 199.33031 -301.124874) (xy 199.329815 -301.149481)
			(xy 199.32192 -301.198058) (xy 199.306336 -301.244739) (xy 199.297259 -301.262034) (xy 201.475846 -301.262034)
			(xy 201.479917 -301.206412) (xy 201.492043 -301.151975) (xy 201.511966 -301.099884) (xy 201.539262 -301.051249)
			(xy 201.573348 -301.007106) (xy 201.613497 -300.968397) (xy 201.658855 -300.935946) (xy 201.708455 -300.910445)
			(xy 201.761239 -300.892438) (xy 201.816082 -300.882308) (xy 201.871816 -300.880271) (xy 201.927253 -300.886371)
			(xy 201.98121 -300.900477) (xy 202.032539 -300.922289) (xy 202.080145 -300.951343) (xy 202.123013 -300.987018)
			(xy 202.16023 -301.028555) (xy 202.169172 -301.04207) (xy 206.417162 -301.04207) (xy 206.421233 -300.986448)
			(xy 206.433359 -300.932011) (xy 206.453282 -300.87992) (xy 206.480578 -300.831285) (xy 206.514664 -300.787142)
			(xy 206.554813 -300.748433) (xy 206.600171 -300.715982) (xy 206.649771 -300.690481) (xy 206.702555 -300.672474)
			(xy 206.757398 -300.662344) (xy 206.813132 -300.660307) (xy 206.868569 -300.666407) (xy 206.922526 -300.680513)
			(xy 206.973855 -300.702325) (xy 207.021461 -300.731379) (xy 207.064329 -300.767054) (xy 207.101546 -300.808591)
			(xy 207.132319 -300.855104) (xy 207.155991 -300.905601) (xy 207.172059 -300.959008) (xy 207.180179 -301.014184)
			(xy 207.180688 -301.04207) (xy 207.180535 -301.050452) (xy 208.791046 -301.050452) (xy 208.795117 -300.99483)
			(xy 208.807243 -300.940393) (xy 208.827166 -300.888302) (xy 208.854462 -300.839667) (xy 208.888548 -300.795524)
			(xy 208.928697 -300.756815) (xy 208.974055 -300.724364) (xy 209.023655 -300.698863) (xy 209.076439 -300.680856)
			(xy 209.131282 -300.670726) (xy 209.187016 -300.668689) (xy 209.242453 -300.674789) (xy 209.29641 -300.688895)
			(xy 209.347739 -300.710707) (xy 209.395345 -300.739761) (xy 209.438213 -300.775436) (xy 209.47543 -300.816973)
			(xy 209.506203 -300.863486) (xy 209.529875 -300.913983) (xy 209.545943 -300.96739) (xy 209.554063 -301.022566)
			(xy 209.554572 -301.050452) (xy 209.554063 -301.078338) (xy 209.545943 -301.133514) (xy 209.529875 -301.186921)
			(xy 209.506203 -301.237418) (xy 209.47543 -301.283931) (xy 209.438213 -301.325468) (xy 209.395345 -301.361143)
			(xy 209.347739 -301.390197) (xy 209.29641 -301.412009) (xy 209.242453 -301.426115) (xy 209.187016 -301.432215)
			(xy 209.131282 -301.430178) (xy 209.076439 -301.420048) (xy 209.023655 -301.402041) (xy 208.974055 -301.37654)
			(xy 208.928697 -301.344089) (xy 208.888548 -301.30538) (xy 208.854462 -301.261237) (xy 208.827166 -301.212602)
			(xy 208.807243 -301.160511) (xy 208.795117 -301.106074) (xy 208.791046 -301.050452) (xy 207.180535 -301.050452)
			(xy 207.180179 -301.069956) (xy 207.172059 -301.125132) (xy 207.155991 -301.178539) (xy 207.132319 -301.229036)
			(xy 207.101546 -301.275549) (xy 207.064329 -301.317086) (xy 207.021461 -301.352761) (xy 206.973855 -301.381815)
			(xy 206.922526 -301.403627) (xy 206.868569 -301.417733) (xy 206.813132 -301.423833) (xy 206.757398 -301.421796)
			(xy 206.702555 -301.411666) (xy 206.649771 -301.393659) (xy 206.600171 -301.368158) (xy 206.554813 -301.335707)
			(xy 206.514664 -301.296998) (xy 206.480578 -301.252855) (xy 206.453282 -301.20422) (xy 206.433359 -301.152129)
			(xy 206.421233 -301.097692) (xy 206.417162 -301.04207) (xy 202.169172 -301.04207) (xy 202.191003 -301.075068)
			(xy 202.214675 -301.125565) (xy 202.230743 -301.178972) (xy 202.238863 -301.234148) (xy 202.239372 -301.262034)
			(xy 202.238863 -301.28992) (xy 202.230743 -301.345096) (xy 202.214675 -301.398503) (xy 202.191003 -301.449)
			(xy 202.16023 -301.495513) (xy 202.123013 -301.53705) (xy 202.080145 -301.572725) (xy 202.032539 -301.601779)
			(xy 201.98121 -301.623591) (xy 201.927253 -301.637697) (xy 201.871816 -301.643797) (xy 201.816082 -301.64176)
			(xy 201.761239 -301.63163) (xy 201.708455 -301.613623) (xy 201.658855 -301.588122) (xy 201.613497 -301.555671)
			(xy 201.573348 -301.516962) (xy 201.539262 -301.472819) (xy 201.511966 -301.424184) (xy 201.492043 -301.372093)
			(xy 201.479917 -301.317656) (xy 201.475846 -301.262034) (xy 199.297259 -301.262034) (xy 199.283465 -301.288316)
			(xy 199.2539 -301.32766) (xy 199.218407 -301.361752) (xy 199.177904 -301.389708) (xy 199.133442 -301.410806)
			(xy 199.086171 -301.424498) (xy 199.037316 -301.43043) (xy 198.988141 -301.428449) (xy 198.939922 -301.418605)
			(xy 198.893906 -301.401153) (xy 198.851285 -301.376546) (xy 198.813164 -301.345421) (xy 198.780529 -301.308584)
			(xy 198.754226 -301.266988) (xy 198.734935 -301.221712) (xy 198.723158 -301.173928) (xy 198.719198 -301.124874)
			(xy 198.38035 -301.124874) (xy 198.379855 -301.149481) (xy 198.37196 -301.198058) (xy 198.356376 -301.244739)
			(xy 198.333505 -301.288316) (xy 198.30394 -301.32766) (xy 198.268447 -301.361752) (xy 198.227944 -301.389708)
			(xy 198.183482 -301.410806) (xy 198.136211 -301.424498) (xy 198.087356 -301.43043) (xy 198.038181 -301.428449)
			(xy 197.989962 -301.418605) (xy 197.943946 -301.401153) (xy 197.901325 -301.376546) (xy 197.863204 -301.345421)
			(xy 197.830569 -301.308584) (xy 197.804266 -301.266988) (xy 197.784975 -301.221712) (xy 197.773198 -301.173928)
			(xy 197.769238 -301.124874) (xy 197.43039 -301.124874) (xy 197.429895 -301.149481) (xy 197.422 -301.198058)
			(xy 197.406416 -301.244739) (xy 197.383545 -301.288316) (xy 197.35398 -301.32766) (xy 197.318487 -301.361752)
			(xy 197.277984 -301.389708) (xy 197.233522 -301.410806) (xy 197.186251 -301.424498) (xy 197.137396 -301.43043)
			(xy 197.088221 -301.428449) (xy 197.040002 -301.418605) (xy 196.993986 -301.401153) (xy 196.951365 -301.376546)
			(xy 196.913244 -301.345421) (xy 196.880609 -301.308584) (xy 196.854306 -301.266988) (xy 196.835015 -301.221712)
			(xy 196.823238 -301.173928) (xy 196.819278 -301.124874) (xy 196.480176 -301.124874) (xy 196.479681 -301.149481)
			(xy 196.471786 -301.198058) (xy 196.456202 -301.244739) (xy 196.433331 -301.288316) (xy 196.403766 -301.32766)
			(xy 196.368273 -301.361752) (xy 196.32777 -301.389708) (xy 196.283308 -301.410806) (xy 196.236037 -301.424498)
			(xy 196.187182 -301.43043) (xy 196.138007 -301.428449) (xy 196.089788 -301.418605) (xy 196.043772 -301.401153)
			(xy 196.001151 -301.376546) (xy 195.96303 -301.345421) (xy 195.930395 -301.308584) (xy 195.904092 -301.266988)
			(xy 195.884801 -301.221712) (xy 195.873024 -301.173928) (xy 195.869064 -301.124874) (xy 195.530216 -301.124874)
			(xy 195.529721 -301.149481) (xy 195.521826 -301.198058) (xy 195.506242 -301.244739) (xy 195.483371 -301.288316)
			(xy 195.453806 -301.32766) (xy 195.418313 -301.361752) (xy 195.37781 -301.389708) (xy 195.333348 -301.410806)
			(xy 195.286077 -301.424498) (xy 195.237222 -301.43043) (xy 195.188047 -301.428449) (xy 195.139828 -301.418605)
			(xy 195.093812 -301.401153) (xy 195.051191 -301.376546) (xy 195.01307 -301.345421) (xy 194.980435 -301.308584)
			(xy 194.954132 -301.266988) (xy 194.934841 -301.221712) (xy 194.923064 -301.173928) (xy 194.919104 -301.124874)
			(xy 194.580256 -301.124874) (xy 194.579761 -301.149481) (xy 194.571866 -301.198058) (xy 194.556282 -301.244739)
			(xy 194.533411 -301.288316) (xy 194.503846 -301.32766) (xy 194.468353 -301.361752) (xy 194.42785 -301.389708)
			(xy 194.383388 -301.410806) (xy 194.336117 -301.424498) (xy 194.287262 -301.43043) (xy 194.238087 -301.428449)
			(xy 194.189868 -301.418605) (xy 194.143852 -301.401153) (xy 194.101231 -301.376546) (xy 194.06311 -301.345421)
			(xy 194.030475 -301.308584) (xy 194.004172 -301.266988) (xy 193.984881 -301.221712) (xy 193.973104 -301.173928)
			(xy 193.969144 -301.124874) (xy 193.630296 -301.124874) (xy 193.629801 -301.149481) (xy 193.621906 -301.198058)
			(xy 193.606322 -301.244739) (xy 193.583451 -301.288316) (xy 193.553886 -301.32766) (xy 193.518393 -301.361752)
			(xy 193.47789 -301.389708) (xy 193.433428 -301.410806) (xy 193.386157 -301.424498) (xy 193.337302 -301.43043)
			(xy 193.288127 -301.428449) (xy 193.239908 -301.418605) (xy 193.193892 -301.401153) (xy 193.151271 -301.376546)
			(xy 193.11315 -301.345421) (xy 193.080515 -301.308584) (xy 193.054212 -301.266988) (xy 193.034921 -301.221712)
			(xy 193.023144 -301.173928) (xy 193.019184 -301.124874) (xy 192.680243 -301.124874) (xy 192.680693 -301.133171)
			(xy 192.675328 -301.182516) (xy 192.662052 -301.230343) (xy 192.641212 -301.275392) (xy 192.61336 -301.316476)
			(xy 192.579227 -301.352513) (xy 192.539715 -301.382554) (xy 192.495863 -301.405807) (xy 192.448827 -301.42166)
			(xy 192.399846 -301.429694) (xy 192.375028 -301.430182) (xy 192.360845 -301.430002) (xy 192.332605 -301.427332)
			(xy 192.31864 -301.424848) (xy 192.306194 -301.422562) (xy 192.282572 -301.429928) (xy 192.205102 -301.507398)
			(xy 192.197736 -301.53102) (xy 192.200022 -301.543466) (xy 192.202504 -301.557431) (xy 192.205172 -301.585671)
			(xy 192.205356 -301.599854) (xy 192.204795 -301.623842) (xy 192.197297 -301.671227) (xy 192.182479 -301.716856)
			(xy 192.160706 -301.759606) (xy 192.132512 -301.798423) (xy 192.098594 -301.832351) (xy 192.059786 -301.860556)
			(xy 192.017043 -301.882343) (xy 191.971419 -301.897175) (xy 191.924035 -301.904688) (xy 191.900048 -301.905162)
			(xy 191.885865 -301.904979) (xy 191.857625 -301.902311) (xy 191.84366 -301.899828) (xy 191.831214 -301.897542)
			(xy 191.807592 -301.904908) (xy 191.730122 -301.982378) (xy 191.722756 -302.006) (xy 191.725042 -302.018446)
			(xy 191.72752 -302.032412) (xy 191.730191 -302.060651) (xy 191.730376 -302.074834) (xy 191.729886 -302.099651)
			(xy 191.721851 -302.14863) (xy 191.705998 -302.195664) (xy 191.682745 -302.239514) (xy 191.652705 -302.279025)
			(xy 191.616668 -302.313156) (xy 191.575585 -302.341007) (xy 191.530537 -302.361845) (xy 191.482712 -302.375121)
			(xy 191.433368 -302.380485) (xy 191.383807 -302.377796) (xy 191.335334 -302.367125) (xy 191.289226 -302.348753)
			(xy 191.246697 -302.323163) (xy 191.208868 -302.29103) (xy 191.176736 -302.253201) (xy 191.151147 -302.210672)
			(xy 191.132774 -302.164564) (xy 191.122103 -302.116091) (xy 191.119415 -302.06653) (xy 189.83004 -302.06653)
			(xy 189.830202 -302.074834) (xy 189.83003 -302.089017) (xy 189.827355 -302.117257) (xy 189.824868 -302.131222)
			(xy 189.822699 -302.145186) (xy 189.825283 -302.173317) (xy 189.835476 -302.199663) (xy 189.852496 -302.222208)
			(xy 189.875043 -302.239227) (xy 189.90139 -302.249418) (xy 189.92952 -302.252001) (xy 189.943486 -302.24984)
			(xy 189.957453 -302.24737) (xy 189.985692 -302.244694) (xy 189.999874 -302.244506) (xy 190.024697 -302.24495)
			(xy 190.07369 -302.252978) (xy 190.120739 -302.268826) (xy 190.164604 -302.292077) (xy 190.20413 -302.322119)
			(xy 190.238274 -302.358159) (xy 190.266138 -302.399249) (xy 190.286988 -302.444305) (xy 190.300273 -302.492141)
			(xy 190.305644 -302.541495) (xy 190.305194 -302.549814) (xy 192.544204 -302.549814) (xy 192.548164 -302.50076)
			(xy 192.559941 -302.452976) (xy 192.579232 -302.4077) (xy 192.605535 -302.366104) (xy 192.63817 -302.329267)
			(xy 192.676291 -302.298142) (xy 192.718912 -302.273535) (xy 192.764928 -302.256083) (xy 192.813147 -302.246239)
			(xy 192.862322 -302.244258) (xy 192.911177 -302.25019) (xy 192.958448 -302.263882) (xy 193.00291 -302.28498)
			(xy 193.043413 -302.312936) (xy 193.078906 -302.347028) (xy 193.108471 -302.386372) (xy 193.131342 -302.429949)
			(xy 193.146926 -302.47663) (xy 193.154821 -302.525207) (xy 193.155149 -302.541536) (xy 193.494295 -302.541536)
			(xy 193.499659 -302.492188) (xy 193.512935 -302.444359) (xy 193.533774 -302.399308) (xy 193.561628 -302.358221)
			(xy 193.595761 -302.322181) (xy 193.635274 -302.292138) (xy 193.679128 -302.268884) (xy 193.726166 -302.25303)
			(xy 193.775149 -302.244994) (xy 193.799968 -302.244506) (xy 193.814151 -302.244687) (xy 193.842391 -302.247356)
			(xy 193.856356 -302.24984) (xy 193.870331 -302.251931) (xy 193.898454 -302.249363) (xy 193.924796 -302.239185)
			(xy 193.94734 -302.222177) (xy 193.964359 -302.199642) (xy 193.974551 -302.173305) (xy 193.977134 -302.145183)
			(xy 193.974974 -302.131222) (xy 193.972491 -302.117257) (xy 193.969823 -302.089017) (xy 193.96964 -302.074834)
			(xy 193.970041 -302.050011) (xy 193.978068 -302.001017) (xy 193.993915 -301.953967) (xy 194.017164 -301.910101)
			(xy 194.047205 -301.870574) (xy 194.083244 -301.836428) (xy 194.124333 -301.808562) (xy 194.169388 -301.78771)
			(xy 194.217224 -301.774422) (xy 194.266579 -301.769048) (xy 194.316153 -301.77173) (xy 194.36464 -301.782396)
			(xy 194.410763 -301.800766) (xy 194.453307 -301.826356) (xy 194.49115 -301.858492) (xy 194.523296 -301.896326)
			(xy 194.548897 -301.938863) (xy 194.56728 -301.984981) (xy 194.577959 -302.033466) (xy 194.580208 -302.074834)
			(xy 195.869064 -302.074834) (xy 195.873024 -302.02578) (xy 195.884801 -301.977996) (xy 195.904092 -301.93272)
			(xy 195.930395 -301.891124) (xy 195.96303 -301.854287) (xy 196.001151 -301.823162) (xy 196.043772 -301.798555)
			(xy 196.089788 -301.781103) (xy 196.138007 -301.771259) (xy 196.187182 -301.769278) (xy 196.236037 -301.77521)
			(xy 196.283308 -301.788902) (xy 196.32777 -301.81) (xy 196.368273 -301.837956) (xy 196.403766 -301.872048)
			(xy 196.433331 -301.911392) (xy 196.456202 -301.954969) (xy 196.471786 -302.00165) (xy 196.479681 -302.050227)
			(xy 196.480176 -302.074834) (xy 197.769238 -302.074834) (xy 197.773198 -302.02578) (xy 197.784975 -301.977996)
			(xy 197.804266 -301.93272) (xy 197.830569 -301.891124) (xy 197.863204 -301.854287) (xy 197.901325 -301.823162)
			(xy 197.943946 -301.798555) (xy 197.989962 -301.781103) (xy 198.038181 -301.771259) (xy 198.087356 -301.769278)
			(xy 198.136211 -301.77521) (xy 198.183482 -301.788902) (xy 198.227944 -301.81) (xy 198.268447 -301.837956)
			(xy 198.30394 -301.872048) (xy 198.333505 -301.911392) (xy 198.356376 -301.954969) (xy 198.37196 -302.00165)
			(xy 198.379855 -302.050227) (xy 198.38035 -302.074834) (xy 198.719198 -302.074834) (xy 198.723158 -302.02578)
			(xy 198.734935 -301.977996) (xy 198.754226 -301.93272) (xy 198.780529 -301.891124) (xy 198.813164 -301.854287)
			(xy 198.851285 -301.823162) (xy 198.893906 -301.798555) (xy 198.939922 -301.781103) (xy 198.988141 -301.771259)
			(xy 199.037316 -301.769278) (xy 199.086171 -301.77521) (xy 199.133442 -301.788902) (xy 199.177904 -301.81)
			(xy 199.218407 -301.837956) (xy 199.22015 -301.83963) (xy 202.44765 -301.83963) (xy 202.451721 -301.784008)
			(xy 202.463847 -301.729571) (xy 202.48377 -301.67748) (xy 202.511066 -301.628845) (xy 202.545152 -301.584702)
			(xy 202.585301 -301.545993) (xy 202.630659 -301.513542) (xy 202.680259 -301.488041) (xy 202.733043 -301.470034)
			(xy 202.787886 -301.459904) (xy 202.84362 -301.457867) (xy 202.899057 -301.463967) (xy 202.953014 -301.478073)
			(xy 203.004343 -301.499885) (xy 203.051949 -301.528939) (xy 203.080393 -301.55261) (xy 204.219808 -301.55261)
			(xy 204.223879 -301.496988) (xy 204.236005 -301.442551) (xy 204.255928 -301.39046) (xy 204.283224 -301.341825)
			(xy 204.31731 -301.297682) (xy 204.357459 -301.258973) (xy 204.402817 -301.226522) (xy 204.452417 -301.201021)
			(xy 204.505201 -301.183014) (xy 204.560044 -301.172884) (xy 204.615778 -301.170847) (xy 204.671215 -301.176947)
			(xy 204.725172 -301.191053) (xy 204.776501 -301.212865) (xy 204.824107 -301.241919) (xy 204.866975 -301.277594)
			(xy 204.904192 -301.319131) (xy 204.934965 -301.365644) (xy 204.958637 -301.416141) (xy 204.974705 -301.469548)
			(xy 204.982825 -301.524724) (xy 204.983334 -301.55261) (xy 204.983162 -301.562008) (xy 205.203804 -301.562008)
			(xy 205.207875 -301.506386) (xy 205.220001 -301.451949) (xy 205.239924 -301.399858) (xy 205.26722 -301.351223)
			(xy 205.301306 -301.30708) (xy 205.341455 -301.268371) (xy 205.386813 -301.23592) (xy 205.436413 -301.210419)
			(xy 205.489197 -301.192412) (xy 205.54404 -301.182282) (xy 205.599774 -301.180245) (xy 205.655211 -301.186345)
			(xy 205.709168 -301.200451) (xy 205.760497 -301.222263) (xy 205.808103 -301.251317) (xy 205.850971 -301.286992)
			(xy 205.888188 -301.328529) (xy 205.918961 -301.375042) (xy 205.942633 -301.425539) (xy 205.958701 -301.478946)
			(xy 205.966821 -301.534122) (xy 205.96733 -301.562008) (xy 205.967061 -301.57674) (xy 207.613248 -301.57674)
			(xy 207.617319 -301.521118) (xy 207.629445 -301.466681) (xy 207.649368 -301.41459) (xy 207.676664 -301.365955)
			(xy 207.71075 -301.321812) (xy 207.750899 -301.283103) (xy 207.796257 -301.250652) (xy 207.845857 -301.225151)
			(xy 207.898641 -301.207144) (xy 207.953484 -301.197014) (xy 208.009218 -301.194977) (xy 208.064655 -301.201077)
			(xy 208.118612 -301.215183) (xy 208.169941 -301.236995) (xy 208.217547 -301.266049) (xy 208.260415 -301.301724)
			(xy 208.297632 -301.343261) (xy 208.328405 -301.389774) (xy 208.352077 -301.440271) (xy 208.368145 -301.493678)
			(xy 208.376265 -301.548854) (xy 208.376774 -301.57674) (xy 208.376265 -301.604626) (xy 208.368145 -301.659802)
			(xy 208.352077 -301.713209) (xy 208.328405 -301.763706) (xy 208.297632 -301.810219) (xy 208.260415 -301.851756)
			(xy 208.217547 -301.887431) (xy 208.169941 -301.916485) (xy 208.118612 -301.938297) (xy 208.064655 -301.952403)
			(xy 208.009218 -301.958503) (xy 207.953484 -301.956466) (xy 207.898641 -301.946336) (xy 207.845857 -301.928329)
			(xy 207.796257 -301.902828) (xy 207.750899 -301.870377) (xy 207.71075 -301.831668) (xy 207.676664 -301.787525)
			(xy 207.649368 -301.73889) (xy 207.629445 -301.686799) (xy 207.617319 -301.632362) (xy 207.613248 -301.57674)
			(xy 205.967061 -301.57674) (xy 205.966821 -301.589894) (xy 205.958701 -301.64507) (xy 205.942633 -301.698477)
			(xy 205.918961 -301.748974) (xy 205.888188 -301.795487) (xy 205.850971 -301.837024) (xy 205.808103 -301.872699)
			(xy 205.760497 -301.901753) (xy 205.709168 -301.923565) (xy 205.655211 -301.937671) (xy 205.599774 -301.943771)
			(xy 205.54404 -301.941734) (xy 205.489197 -301.931604) (xy 205.436413 -301.913597) (xy 205.386813 -301.888096)
			(xy 205.341455 -301.855645) (xy 205.301306 -301.816936) (xy 205.26722 -301.772793) (xy 205.239924 -301.724158)
			(xy 205.220001 -301.672067) (xy 205.207875 -301.61763) (xy 205.203804 -301.562008) (xy 204.983162 -301.562008)
			(xy 204.982825 -301.580496) (xy 204.974705 -301.635672) (xy 204.958637 -301.689079) (xy 204.934965 -301.739576)
			(xy 204.904192 -301.786089) (xy 204.866975 -301.827626) (xy 204.824107 -301.863301) (xy 204.776501 -301.892355)
			(xy 204.725172 -301.914167) (xy 204.671215 -301.928273) (xy 204.615778 -301.934373) (xy 204.560044 -301.932336)
			(xy 204.505201 -301.922206) (xy 204.452417 -301.904199) (xy 204.402817 -301.878698) (xy 204.357459 -301.846247)
			(xy 204.31731 -301.807538) (xy 204.283224 -301.763395) (xy 204.255928 -301.71476) (xy 204.236005 -301.662669)
			(xy 204.223879 -301.608232) (xy 204.219808 -301.55261) (xy 203.080393 -301.55261) (xy 203.094817 -301.564614)
			(xy 203.132034 -301.606151) (xy 203.162807 -301.652664) (xy 203.186479 -301.703161) (xy 203.202547 -301.756568)
			(xy 203.210667 -301.811744) (xy 203.211176 -301.83963) (xy 203.210667 -301.867516) (xy 203.202547 -301.922692)
			(xy 203.186479 -301.976099) (xy 203.162807 -302.026596) (xy 203.132034 -302.073109) (xy 203.094817 -302.114646)
			(xy 203.051949 -302.150321) (xy 203.004343 -302.179375) (xy 202.953014 -302.201187) (xy 202.899057 -302.215293)
			(xy 202.84362 -302.221393) (xy 202.787886 -302.219356) (xy 202.733043 -302.209226) (xy 202.680259 -302.191219)
			(xy 202.630659 -302.165718) (xy 202.585301 -302.133267) (xy 202.545152 -302.094558) (xy 202.511066 -302.050415)
			(xy 202.48377 -302.00178) (xy 202.463847 -301.949689) (xy 202.451721 -301.895252) (xy 202.44765 -301.83963)
			(xy 199.22015 -301.83963) (xy 199.2539 -301.872048) (xy 199.283465 -301.911392) (xy 199.306336 -301.954969)
			(xy 199.32192 -302.00165) (xy 199.329815 -302.050227) (xy 199.33031 -302.074834) (xy 199.329815 -302.099441)
			(xy 199.32192 -302.148018) (xy 199.306336 -302.194699) (xy 199.283465 -302.238276) (xy 199.2539 -302.27762)
			(xy 199.218407 -302.311712) (xy 199.177904 -302.339668) (xy 199.133442 -302.360766) (xy 199.086171 -302.374458)
			(xy 199.037316 -302.38039) (xy 198.988141 -302.378409) (xy 198.939922 -302.368565) (xy 198.893906 -302.351113)
			(xy 198.851285 -302.326506) (xy 198.813164 -302.295381) (xy 198.780529 -302.258544) (xy 198.754226 -302.216948)
			(xy 198.734935 -302.171672) (xy 198.723158 -302.123888) (xy 198.719198 -302.074834) (xy 198.38035 -302.074834)
			(xy 198.379855 -302.099441) (xy 198.37196 -302.148018) (xy 198.356376 -302.194699) (xy 198.333505 -302.238276)
			(xy 198.30394 -302.27762) (xy 198.268447 -302.311712) (xy 198.227944 -302.339668) (xy 198.183482 -302.360766)
			(xy 198.136211 -302.374458) (xy 198.087356 -302.38039) (xy 198.038181 -302.378409) (xy 197.989962 -302.368565)
			(xy 197.943946 -302.351113) (xy 197.901325 -302.326506) (xy 197.863204 -302.295381) (xy 197.830569 -302.258544)
			(xy 197.804266 -302.216948) (xy 197.784975 -302.171672) (xy 197.773198 -302.123888) (xy 197.769238 -302.074834)
			(xy 196.480176 -302.074834) (xy 196.479681 -302.099441) (xy 196.471786 -302.148018) (xy 196.456202 -302.194699)
			(xy 196.433331 -302.238276) (xy 196.403766 -302.27762) (xy 196.368273 -302.311712) (xy 196.32777 -302.339668)
			(xy 196.283308 -302.360766) (xy 196.236037 -302.374458) (xy 196.187182 -302.38039) (xy 196.138007 -302.378409)
			(xy 196.089788 -302.368565) (xy 196.043772 -302.351113) (xy 196.001151 -302.326506) (xy 195.96303 -302.295381)
			(xy 195.930395 -302.258544) (xy 195.904092 -302.216948) (xy 195.884801 -302.171672) (xy 195.873024 -302.123888)
			(xy 195.869064 -302.074834) (xy 194.580208 -302.074834) (xy 194.580654 -302.083039) (xy 194.575293 -302.132396)
			(xy 194.562018 -302.180235) (xy 194.541179 -302.225296) (xy 194.513324 -302.266392) (xy 194.479187 -302.30244)
			(xy 194.439668 -302.332491) (xy 194.395808 -302.355753) (xy 194.348763 -302.371613) (xy 194.299771 -302.379652)
			(xy 194.274948 -302.380142) (xy 194.260765 -302.379958) (xy 194.232525 -302.377291) (xy 194.21856 -302.374808)
			(xy 194.204603 -302.372573) (xy 194.176462 -302.375162) (xy 194.150108 -302.385363) (xy 194.127558 -302.402395)
			(xy 194.110537 -302.424954) (xy 194.10035 -302.451314) (xy 194.097776 -302.479456) (xy 194.099942 -302.493426)
			(xy 194.102418 -302.507392) (xy 194.10509 -302.535632) (xy 194.105276 -302.549814) (xy 194.104807 -302.574633)
			(xy 194.096775 -302.623617) (xy 194.080923 -302.670655) (xy 194.060431 -302.709305) (xy 200.909418 -302.709305)
			(xy 200.909418 -302.656007) (xy 200.917361 -302.603303) (xy 200.933071 -302.552373) (xy 200.956197 -302.504352)
			(xy 200.986221 -302.460315) (xy 201.022473 -302.421244) (xy 201.064144 -302.388013) (xy 201.110302 -302.361364)
			(xy 201.159916 -302.341892) (xy 201.211878 -302.330032) (xy 201.265028 -302.326049) (xy 201.318178 -302.330032)
			(xy 201.37014 -302.341892) (xy 201.419754 -302.361364) (xy 201.465912 -302.388013) (xy 201.507583 -302.421244)
			(xy 201.543835 -302.460315) (xy 201.573859 -302.504352) (xy 201.596985 -302.552373) (xy 201.612695 -302.603303)
			(xy 201.620638 -302.656007) (xy 201.621136 -302.682656) (xy 201.620638 -302.709305) (xy 201.612695 -302.762009)
			(xy 201.596985 -302.812939) (xy 201.573859 -302.86096) (xy 201.543835 -302.904997) (xy 201.507583 -302.944068)
			(xy 201.465912 -302.977299) (xy 201.419754 -303.003948) (xy 201.37014 -303.02342) (xy 201.318178 -303.03528)
			(xy 201.265028 -303.039264) (xy 201.211878 -303.03528) (xy 201.159916 -303.02342) (xy 201.110302 -303.003948)
			(xy 201.064144 -302.977299) (xy 201.022473 -302.944068) (xy 200.986221 -302.904997) (xy 200.956197 -302.86096)
			(xy 200.933071 -302.812939) (xy 200.917361 -302.762009) (xy 200.909418 -302.709305) (xy 194.060431 -302.709305)
			(xy 194.057671 -302.71451) (xy 194.027631 -302.754026) (xy 193.991593 -302.788161) (xy 193.950508 -302.816017)
			(xy 193.905458 -302.836859) (xy 193.857629 -302.850138) (xy 193.808282 -302.855505) (xy 193.758717 -302.852818)
			(xy 193.71024 -302.842148) (xy 193.664127 -302.823776) (xy 193.621594 -302.798185) (xy 193.583761 -302.766052)
			(xy 193.551625 -302.728221) (xy 193.526032 -302.685689) (xy 193.507658 -302.639577) (xy 193.496985 -302.591101)
			(xy 193.494295 -302.541536) (xy 193.155149 -302.541536) (xy 193.155316 -302.549814) (xy 193.154821 -302.574421)
			(xy 193.146926 -302.622998) (xy 193.131342 -302.669679) (xy 193.108471 -302.713256) (xy 193.078906 -302.7526)
			(xy 193.043413 -302.786692) (xy 193.00291 -302.814648) (xy 192.958448 -302.835746) (xy 192.911177 -302.849438)
			(xy 192.862322 -302.85537) (xy 192.813147 -302.853389) (xy 192.764928 -302.843545) (xy 192.718912 -302.826093)
			(xy 192.676291 -302.801486) (xy 192.63817 -302.770361) (xy 192.605535 -302.733524) (xy 192.579232 -302.691928)
			(xy 192.559941 -302.646652) (xy 192.548164 -302.598868) (xy 192.544204 -302.549814) (xy 190.305194 -302.549814)
			(xy 190.30296 -302.591069) (xy 190.292291 -302.639556) (xy 190.273918 -302.685677) (xy 190.248326 -302.728219)
			(xy 190.216188 -302.766059) (xy 190.178351 -302.798202) (xy 190.135813 -302.8238) (xy 190.089694 -302.842179)
			(xy 190.041209 -302.852855) (xy 189.991636 -302.855545) (xy 189.94228 -302.85018) (xy 189.894442 -302.836901)
			(xy 189.849383 -302.816058) (xy 189.80829 -302.788199) (xy 189.772245 -302.754059) (xy 189.742199 -302.714538)
			(xy 189.718942 -302.670676) (xy 189.703087 -302.623629) (xy 189.695053 -302.574637) (xy 189.694566 -302.549814)
			(xy 189.694745 -302.535631) (xy 189.697416 -302.507391) (xy 189.6999 -302.493426) (xy 189.702057 -302.479458)
			(xy 189.699484 -302.451325) (xy 189.689298 -302.424975) (xy 189.672279 -302.402426) (xy 189.649731 -302.385406)
			(xy 189.623381 -302.375218) (xy 189.595248 -302.372643) (xy 189.581282 -302.374808) (xy 189.567316 -302.377283)
			(xy 189.539076 -302.379956) (xy 189.524894 -302.380142) (xy 189.500073 -302.379616) (xy 189.451086 -302.371583)
			(xy 189.404043 -302.355731) (xy 189.360185 -302.332478) (xy 189.320666 -302.302434) (xy 189.286529 -302.266394)
			(xy 189.258672 -302.225305) (xy 189.23783 -302.18025) (xy 189.224552 -302.132417) (xy 189.219187 -302.083066)
			(xy 188.880076 -302.083066) (xy 188.879747 -302.099441) (xy 188.871852 -302.148018) (xy 188.856268 -302.194699)
			(xy 188.833397 -302.238276) (xy 188.803832 -302.27762) (xy 188.768339 -302.311712) (xy 188.727836 -302.339668)
			(xy 188.683374 -302.360766) (xy 188.636103 -302.374458) (xy 188.587248 -302.38039) (xy 188.538073 -302.378409)
			(xy 188.489854 -302.368565) (xy 188.443838 -302.351113) (xy 188.401217 -302.326506) (xy 188.363096 -302.295381)
			(xy 188.330461 -302.258544) (xy 188.304158 -302.216948) (xy 188.284867 -302.171672) (xy 188.27309 -302.123888)
			(xy 188.26913 -302.074834) (xy 187.930282 -302.074834) (xy 187.929787 -302.099441) (xy 187.921892 -302.148018)
			(xy 187.906308 -302.194699) (xy 187.883437 -302.238276) (xy 187.853872 -302.27762) (xy 187.818379 -302.311712)
			(xy 187.777876 -302.339668) (xy 187.733414 -302.360766) (xy 187.686143 -302.374458) (xy 187.637288 -302.38039)
			(xy 187.588113 -302.378409) (xy 187.539894 -302.368565) (xy 187.493878 -302.351113) (xy 187.451257 -302.326506)
			(xy 187.413136 -302.295381) (xy 187.380501 -302.258544) (xy 187.354198 -302.216948) (xy 187.334907 -302.171672)
			(xy 187.32313 -302.123888) (xy 187.31917 -302.074834) (xy 186.980322 -302.074834) (xy 186.979827 -302.099441)
			(xy 186.971932 -302.148018) (xy 186.956348 -302.194699) (xy 186.933477 -302.238276) (xy 186.903912 -302.27762)
			(xy 186.868419 -302.311712) (xy 186.827916 -302.339668) (xy 186.783454 -302.360766) (xy 186.736183 -302.374458)
			(xy 186.687328 -302.38039) (xy 186.638153 -302.378409) (xy 186.589934 -302.368565) (xy 186.543918 -302.351113)
			(xy 186.501297 -302.326506) (xy 186.463176 -302.295381) (xy 186.430541 -302.258544) (xy 186.404238 -302.216948)
			(xy 186.384947 -302.171672) (xy 186.37317 -302.123888) (xy 186.36921 -302.074834) (xy 186.030362 -302.074834)
			(xy 186.029867 -302.099441) (xy 186.021972 -302.148018) (xy 186.006388 -302.194699) (xy 185.983517 -302.238276)
			(xy 185.953952 -302.27762) (xy 185.918459 -302.311712) (xy 185.877956 -302.339668) (xy 185.833494 -302.360766)
			(xy 185.786223 -302.374458) (xy 185.737368 -302.38039) (xy 185.688193 -302.378409) (xy 185.639974 -302.368565)
			(xy 185.593958 -302.351113) (xy 185.551337 -302.326506) (xy 185.513216 -302.295381) (xy 185.480581 -302.258544)
			(xy 185.454278 -302.216948) (xy 185.434987 -302.171672) (xy 185.42321 -302.123888) (xy 185.41925 -302.074834)
			(xy 185.080148 -302.074834) (xy 185.079653 -302.099441) (xy 185.071758 -302.148018) (xy 185.056174 -302.194699)
			(xy 185.033303 -302.238276) (xy 185.003738 -302.27762) (xy 184.968245 -302.311712) (xy 184.927742 -302.339668)
			(xy 184.88328 -302.360766) (xy 184.836009 -302.374458) (xy 184.787154 -302.38039) (xy 184.737979 -302.378409)
			(xy 184.68976 -302.368565) (xy 184.643744 -302.351113) (xy 184.601123 -302.326506) (xy 184.563002 -302.295381)
			(xy 184.530367 -302.258544) (xy 184.504064 -302.216948) (xy 184.484773 -302.171672) (xy 184.472996 -302.123888)
			(xy 184.469036 -302.074834) (xy 184.130188 -302.074834) (xy 184.129693 -302.099441) (xy 184.121798 -302.148018)
			(xy 184.106214 -302.194699) (xy 184.083343 -302.238276) (xy 184.053778 -302.27762) (xy 184.018285 -302.311712)
			(xy 183.977782 -302.339668) (xy 183.93332 -302.360766) (xy 183.886049 -302.374458) (xy 183.837194 -302.38039)
			(xy 183.788019 -302.378409) (xy 183.7398 -302.368565) (xy 183.693784 -302.351113) (xy 183.651163 -302.326506)
			(xy 183.613042 -302.295381) (xy 183.580407 -302.258544) (xy 183.554104 -302.216948) (xy 183.534813 -302.171672)
			(xy 183.523036 -302.123888) (xy 183.519076 -302.074834) (xy 183.180228 -302.074834) (xy 183.179733 -302.099441)
			(xy 183.171838 -302.148018) (xy 183.156254 -302.194699) (xy 183.133383 -302.238276) (xy 183.103818 -302.27762)
			(xy 183.068325 -302.311712) (xy 183.027822 -302.339668) (xy 182.98336 -302.360766) (xy 182.936089 -302.374458)
			(xy 182.887234 -302.38039) (xy 182.838059 -302.378409) (xy 182.78984 -302.368565) (xy 182.743824 -302.351113)
			(xy 182.701203 -302.326506) (xy 182.663082 -302.295381) (xy 182.630447 -302.258544) (xy 182.604144 -302.216948)
			(xy 182.584853 -302.171672) (xy 182.573076 -302.123888) (xy 182.569116 -302.074834) (xy 182.230268 -302.074834)
			(xy 182.229773 -302.099441) (xy 182.221878 -302.148018) (xy 182.206294 -302.194699) (xy 182.183423 -302.238276)
			(xy 182.153858 -302.27762) (xy 182.118365 -302.311712) (xy 182.077862 -302.339668) (xy 182.0334 -302.360766)
			(xy 181.986129 -302.374458) (xy 181.937274 -302.38039) (xy 181.888099 -302.378409) (xy 181.83988 -302.368565)
			(xy 181.793864 -302.351113) (xy 181.751243 -302.326506) (xy 181.713122 -302.295381) (xy 181.680487 -302.258544)
			(xy 181.654184 -302.216948) (xy 181.634893 -302.171672) (xy 181.623116 -302.123888) (xy 181.619156 -302.074834)
			(xy 181.280308 -302.074834) (xy 181.279813 -302.099441) (xy 181.271918 -302.148018) (xy 181.256334 -302.194699)
			(xy 181.233463 -302.238276) (xy 181.203898 -302.27762) (xy 181.168405 -302.311712) (xy 181.127902 -302.339668)
			(xy 181.08344 -302.360766) (xy 181.036169 -302.374458) (xy 180.987314 -302.38039) (xy 180.938139 -302.378409)
			(xy 180.88992 -302.368565) (xy 180.843904 -302.351113) (xy 180.801283 -302.326506) (xy 180.763162 -302.295381)
			(xy 180.730527 -302.258544) (xy 180.704224 -302.216948) (xy 180.684933 -302.171672) (xy 180.673156 -302.123888)
			(xy 180.669196 -302.074834) (xy 180.330348 -302.074834) (xy 180.329853 -302.099441) (xy 180.321958 -302.148018)
			(xy 180.306374 -302.194699) (xy 180.283503 -302.238276) (xy 180.253938 -302.27762) (xy 180.218445 -302.311712)
			(xy 180.177942 -302.339668) (xy 180.13348 -302.360766) (xy 180.086209 -302.374458) (xy 180.037354 -302.38039)
			(xy 179.988179 -302.378409) (xy 179.93996 -302.368565) (xy 179.893944 -302.351113) (xy 179.851323 -302.326506)
			(xy 179.813202 -302.295381) (xy 179.780567 -302.258544) (xy 179.754264 -302.216948) (xy 179.734973 -302.171672)
			(xy 179.723196 -302.123888) (xy 179.719236 -302.074834) (xy 179.380388 -302.074834) (xy 179.379893 -302.099441)
			(xy 179.371998 -302.148018) (xy 179.356414 -302.194699) (xy 179.333543 -302.238276) (xy 179.303978 -302.27762)
			(xy 179.268485 -302.311712) (xy 179.227982 -302.339668) (xy 179.18352 -302.360766) (xy 179.136249 -302.374458)
			(xy 179.087394 -302.38039) (xy 179.038219 -302.378409) (xy 178.99 -302.368565) (xy 178.943984 -302.351113)
			(xy 178.901363 -302.326506) (xy 178.863242 -302.295381) (xy 178.830607 -302.258544) (xy 178.804304 -302.216948)
			(xy 178.785013 -302.171672) (xy 178.773236 -302.123888) (xy 178.769276 -302.074834) (xy 178.430174 -302.074834)
			(xy 178.429679 -302.099441) (xy 178.421784 -302.148018) (xy 178.4062 -302.194699) (xy 178.383329 -302.238276)
			(xy 178.353764 -302.27762) (xy 178.318271 -302.311712) (xy 178.277768 -302.339668) (xy 178.233306 -302.360766)
			(xy 178.186035 -302.374458) (xy 178.13718 -302.38039) (xy 178.088005 -302.378409) (xy 178.039786 -302.368565)
			(xy 177.99377 -302.351113) (xy 177.951149 -302.326506) (xy 177.913028 -302.295381) (xy 177.880393 -302.258544)
			(xy 177.85409 -302.216948) (xy 177.834799 -302.171672) (xy 177.823022 -302.123888) (xy 177.819062 -302.074834)
			(xy 177.480214 -302.074834) (xy 177.479719 -302.099441) (xy 177.471824 -302.148018) (xy 177.45624 -302.194699)
			(xy 177.433369 -302.238276) (xy 177.403804 -302.27762) (xy 177.368311 -302.311712) (xy 177.327808 -302.339668)
			(xy 177.283346 -302.360766) (xy 177.236075 -302.374458) (xy 177.18722 -302.38039) (xy 177.138045 -302.378409)
			(xy 177.089826 -302.368565) (xy 177.04381 -302.351113) (xy 177.001189 -302.326506) (xy 176.963068 -302.295381)
			(xy 176.930433 -302.258544) (xy 176.90413 -302.216948) (xy 176.884839 -302.171672) (xy 176.873062 -302.123888)
			(xy 176.869102 -302.074834) (xy 176.530254 -302.074834) (xy 176.529759 -302.099441) (xy 176.521864 -302.148018)
			(xy 176.50628 -302.194699) (xy 176.483409 -302.238276) (xy 176.453844 -302.27762) (xy 176.418351 -302.311712)
			(xy 176.377848 -302.339668) (xy 176.333386 -302.360766) (xy 176.286115 -302.374458) (xy 176.23726 -302.38039)
			(xy 176.188085 -302.378409) (xy 176.139866 -302.368565) (xy 176.09385 -302.351113) (xy 176.051229 -302.326506)
			(xy 176.013108 -302.295381) (xy 175.980473 -302.258544) (xy 175.95417 -302.216948) (xy 175.934879 -302.171672)
			(xy 175.923102 -302.123888) (xy 175.919142 -302.074834) (xy 174.630334 -302.074834) (xy 174.629839 -302.099441)
			(xy 174.621944 -302.148018) (xy 174.60636 -302.194699) (xy 174.583489 -302.238276) (xy 174.553924 -302.27762)
			(xy 174.518431 -302.311712) (xy 174.477928 -302.339668) (xy 174.433466 -302.360766) (xy 174.386195 -302.374458)
			(xy 174.33734 -302.38039) (xy 174.288165 -302.378409) (xy 174.239946 -302.368565) (xy 174.19393 -302.351113)
			(xy 174.151309 -302.326506) (xy 174.113188 -302.295381) (xy 174.080553 -302.258544) (xy 174.05425 -302.216948)
			(xy 174.034959 -302.171672) (xy 174.023182 -302.123888) (xy 174.019222 -302.074834) (xy 173.680374 -302.074834)
			(xy 173.679879 -302.099441) (xy 173.671984 -302.148018) (xy 173.6564 -302.194699) (xy 173.633529 -302.238276)
			(xy 173.603964 -302.27762) (xy 173.568471 -302.311712) (xy 173.527968 -302.339668) (xy 173.483506 -302.360766)
			(xy 173.436235 -302.374458) (xy 173.38738 -302.38039) (xy 173.338205 -302.378409) (xy 173.289986 -302.368565)
			(xy 173.24397 -302.351113) (xy 173.201349 -302.326506) (xy 173.163228 -302.295381) (xy 173.130593 -302.258544)
			(xy 173.10429 -302.216948) (xy 173.084999 -302.171672) (xy 173.073222 -302.123888) (xy 173.069262 -302.074834)
			(xy 172.73016 -302.074834) (xy 172.729665 -302.099441) (xy 172.72177 -302.148018) (xy 172.706186 -302.194699)
			(xy 172.683315 -302.238276) (xy 172.65375 -302.27762) (xy 172.618257 -302.311712) (xy 172.577754 -302.339668)
			(xy 172.533292 -302.360766) (xy 172.486021 -302.374458) (xy 172.437166 -302.38039) (xy 172.387991 -302.378409)
			(xy 172.339772 -302.368565) (xy 172.293756 -302.351113) (xy 172.251135 -302.326506) (xy 172.213014 -302.295381)
			(xy 172.180379 -302.258544) (xy 172.154076 -302.216948) (xy 172.134785 -302.171672) (xy 172.123008 -302.123888)
			(xy 172.119048 -302.074834) (xy 171.7802 -302.074834) (xy 171.779705 -302.099441) (xy 171.77181 -302.148018)
			(xy 171.756226 -302.194699) (xy 171.733355 -302.238276) (xy 171.70379 -302.27762) (xy 171.668297 -302.311712)
			(xy 171.627794 -302.339668) (xy 171.583332 -302.360766) (xy 171.536061 -302.374458) (xy 171.487206 -302.38039)
			(xy 171.438031 -302.378409) (xy 171.389812 -302.368565) (xy 171.343796 -302.351113) (xy 171.301175 -302.326506)
			(xy 171.263054 -302.295381) (xy 171.230419 -302.258544) (xy 171.204116 -302.216948) (xy 171.184825 -302.171672)
			(xy 171.173048 -302.123888) (xy 171.169088 -302.074834) (xy 170.83024 -302.074834) (xy 170.829745 -302.099441)
			(xy 170.82185 -302.148018) (xy 170.806266 -302.194699) (xy 170.783395 -302.238276) (xy 170.75383 -302.27762)
			(xy 170.718337 -302.311712) (xy 170.677834 -302.339668) (xy 170.633372 -302.360766) (xy 170.586101 -302.374458)
			(xy 170.537246 -302.38039) (xy 170.488071 -302.378409) (xy 170.439852 -302.368565) (xy 170.393836 -302.351113)
			(xy 170.351215 -302.326506) (xy 170.313094 -302.295381) (xy 170.280459 -302.258544) (xy 170.254156 -302.216948)
			(xy 170.234865 -302.171672) (xy 170.223088 -302.123888) (xy 170.219128 -302.074834) (xy 169.88028 -302.074834)
			(xy 169.879785 -302.099441) (xy 169.87189 -302.148018) (xy 169.856306 -302.194699) (xy 169.833435 -302.238276)
			(xy 169.80387 -302.27762) (xy 169.768377 -302.311712) (xy 169.727874 -302.339668) (xy 169.683412 -302.360766)
			(xy 169.636141 -302.374458) (xy 169.587286 -302.38039) (xy 169.538111 -302.378409) (xy 169.489892 -302.368565)
			(xy 169.443876 -302.351113) (xy 169.401255 -302.326506) (xy 169.363134 -302.295381) (xy 169.330499 -302.258544)
			(xy 169.304196 -302.216948) (xy 169.284905 -302.171672) (xy 169.273128 -302.123888) (xy 169.269168 -302.074834)
			(xy 168.93032 -302.074834) (xy 168.929825 -302.099441) (xy 168.92193 -302.148018) (xy 168.906346 -302.194699)
			(xy 168.883475 -302.238276) (xy 168.85391 -302.27762) (xy 168.818417 -302.311712) (xy 168.777914 -302.339668)
			(xy 168.733452 -302.360766) (xy 168.686181 -302.374458) (xy 168.637326 -302.38039) (xy 168.588151 -302.378409)
			(xy 168.539932 -302.368565) (xy 168.493916 -302.351113) (xy 168.451295 -302.326506) (xy 168.413174 -302.295381)
			(xy 168.380539 -302.258544) (xy 168.354236 -302.216948) (xy 168.334945 -302.171672) (xy 168.323168 -302.123888)
			(xy 168.319208 -302.074834) (xy 167.98036 -302.074834) (xy 167.979865 -302.099441) (xy 167.97197 -302.148018)
			(xy 167.956386 -302.194699) (xy 167.933515 -302.238276) (xy 167.90395 -302.27762) (xy 167.868457 -302.311712)
			(xy 167.827954 -302.339668) (xy 167.783492 -302.360766) (xy 167.736221 -302.374458) (xy 167.687366 -302.38039)
			(xy 167.638191 -302.378409) (xy 167.589972 -302.368565) (xy 167.543956 -302.351113) (xy 167.501335 -302.326506)
			(xy 167.463214 -302.295381) (xy 167.430579 -302.258544) (xy 167.404276 -302.216948) (xy 167.384985 -302.171672)
			(xy 167.373208 -302.123888) (xy 167.369248 -302.074834) (xy 167.0304 -302.074834) (xy 167.029905 -302.099441)
			(xy 167.02201 -302.148018) (xy 167.006426 -302.194699) (xy 166.983555 -302.238276) (xy 166.95399 -302.27762)
			(xy 166.918497 -302.311712) (xy 166.877994 -302.339668) (xy 166.833532 -302.360766) (xy 166.786261 -302.374458)
			(xy 166.737406 -302.38039) (xy 166.688231 -302.378409) (xy 166.640012 -302.368565) (xy 166.593996 -302.351113)
			(xy 166.551375 -302.326506) (xy 166.513254 -302.295381) (xy 166.480619 -302.258544) (xy 166.454316 -302.216948)
			(xy 166.435025 -302.171672) (xy 166.423248 -302.123888) (xy 166.419288 -302.074834) (xy 166.127938 -302.074834)
			(xy 166.127938 -302.837088) (xy 166.127821 -302.842043) (xy 166.125905 -302.851766) (xy 166.124128 -302.856392)
			(xy 166.12108 -302.863758) (xy 166.119301 -302.868385) (xy 166.117372 -302.878107) (xy 166.11727 -302.883062)
			(xy 166.11727 -303.024794) (xy 184.469036 -303.024794) (xy 184.472996 -302.97574) (xy 184.484773 -302.927956)
			(xy 184.504064 -302.88268) (xy 184.530367 -302.841084) (xy 184.563002 -302.804247) (xy 184.601123 -302.773122)
			(xy 184.643744 -302.748515) (xy 184.68976 -302.731063) (xy 184.737979 -302.721219) (xy 184.787154 -302.719238)
			(xy 184.836009 -302.72517) (xy 184.88328 -302.738862) (xy 184.927742 -302.75996) (xy 184.968245 -302.787916)
			(xy 185.003738 -302.822008) (xy 185.033303 -302.861352) (xy 185.056174 -302.904929) (xy 185.071758 -302.95161)
			(xy 185.079653 -303.000187) (xy 185.080148 -303.024794) (xy 185.41925 -303.024794) (xy 185.42321 -302.97574)
			(xy 185.434987 -302.927956) (xy 185.454278 -302.88268) (xy 185.480581 -302.841084) (xy 185.513216 -302.804247)
			(xy 185.551337 -302.773122) (xy 185.593958 -302.748515) (xy 185.639974 -302.731063) (xy 185.688193 -302.721219)
			(xy 185.737368 -302.719238) (xy 185.786223 -302.72517) (xy 185.833494 -302.738862) (xy 185.877956 -302.75996)
			(xy 185.918459 -302.787916) (xy 185.953952 -302.822008) (xy 185.983517 -302.861352) (xy 186.006388 -302.904929)
			(xy 186.021972 -302.95161) (xy 186.029867 -303.000187) (xy 186.030362 -303.024794) (xy 186.36921 -303.024794)
			(xy 186.37317 -302.97574) (xy 186.384947 -302.927956) (xy 186.404238 -302.88268) (xy 186.430541 -302.841084)
			(xy 186.463176 -302.804247) (xy 186.501297 -302.773122) (xy 186.543918 -302.748515) (xy 186.589934 -302.731063)
			(xy 186.638153 -302.721219) (xy 186.687328 -302.719238) (xy 186.736183 -302.72517) (xy 186.783454 -302.738862)
			(xy 186.827916 -302.75996) (xy 186.868419 -302.787916) (xy 186.903912 -302.822008) (xy 186.933477 -302.861352)
			(xy 186.956348 -302.904929) (xy 186.971932 -302.95161) (xy 186.979827 -303.000187) (xy 186.980322 -303.024794)
			(xy 187.31917 -303.024794) (xy 187.32313 -302.97574) (xy 187.334907 -302.927956) (xy 187.354198 -302.88268)
			(xy 187.380501 -302.841084) (xy 187.413136 -302.804247) (xy 187.451257 -302.773122) (xy 187.493878 -302.748515)
			(xy 187.539894 -302.731063) (xy 187.588113 -302.721219) (xy 187.637288 -302.719238) (xy 187.686143 -302.72517)
			(xy 187.733414 -302.738862) (xy 187.777876 -302.75996) (xy 187.818379 -302.787916) (xy 187.853872 -302.822008)
			(xy 187.883437 -302.861352) (xy 187.906308 -302.904929) (xy 187.921892 -302.95161) (xy 187.929787 -303.000187)
			(xy 187.930282 -303.024794) (xy 188.26913 -303.024794) (xy 188.27309 -302.97574) (xy 188.284867 -302.927956)
			(xy 188.304158 -302.88268) (xy 188.330461 -302.841084) (xy 188.363096 -302.804247) (xy 188.401217 -302.773122)
			(xy 188.443838 -302.748515) (xy 188.489854 -302.731063) (xy 188.538073 -302.721219) (xy 188.587248 -302.719238)
			(xy 188.636103 -302.72517) (xy 188.683374 -302.738862) (xy 188.727836 -302.75996) (xy 188.768339 -302.787916)
			(xy 188.803832 -302.822008) (xy 188.833397 -302.861352) (xy 188.856268 -302.904929) (xy 188.871852 -302.95161)
			(xy 188.879747 -303.000187) (xy 188.880242 -303.024794) (xy 188.879747 -303.049401) (xy 188.871852 -303.097978)
			(xy 188.856268 -303.144659) (xy 188.833397 -303.188236) (xy 188.803832 -303.22758) (xy 188.768339 -303.261672)
			(xy 188.727836 -303.289628) (xy 188.683374 -303.310726) (xy 188.636103 -303.324418) (xy 188.587248 -303.33035)
			(xy 188.538073 -303.328369) (xy 188.489854 -303.318525) (xy 188.443838 -303.301073) (xy 188.401217 -303.276466)
			(xy 188.363096 -303.245341) (xy 188.330461 -303.208504) (xy 188.304158 -303.166908) (xy 188.284867 -303.121632)
			(xy 188.27309 -303.073848) (xy 188.26913 -303.024794) (xy 187.930282 -303.024794) (xy 187.929787 -303.049401)
			(xy 187.921892 -303.097978) (xy 187.906308 -303.144659) (xy 187.883437 -303.188236) (xy 187.853872 -303.22758)
			(xy 187.818379 -303.261672) (xy 187.777876 -303.289628) (xy 187.733414 -303.310726) (xy 187.686143 -303.324418)
			(xy 187.637288 -303.33035) (xy 187.588113 -303.328369) (xy 187.539894 -303.318525) (xy 187.493878 -303.301073)
			(xy 187.451257 -303.276466) (xy 187.413136 -303.245341) (xy 187.380501 -303.208504) (xy 187.354198 -303.166908)
			(xy 187.334907 -303.121632) (xy 187.32313 -303.073848) (xy 187.31917 -303.024794) (xy 186.980322 -303.024794)
			(xy 186.979827 -303.049401) (xy 186.971932 -303.097978) (xy 186.956348 -303.144659) (xy 186.933477 -303.188236)
			(xy 186.903912 -303.22758) (xy 186.868419 -303.261672) (xy 186.827916 -303.289628) (xy 186.783454 -303.310726)
			(xy 186.736183 -303.324418) (xy 186.687328 -303.33035) (xy 186.638153 -303.328369) (xy 186.589934 -303.318525)
			(xy 186.543918 -303.301073) (xy 186.501297 -303.276466) (xy 186.463176 -303.245341) (xy 186.430541 -303.208504)
			(xy 186.404238 -303.166908) (xy 186.384947 -303.121632) (xy 186.37317 -303.073848) (xy 186.36921 -303.024794)
			(xy 186.030362 -303.024794) (xy 186.029867 -303.049401) (xy 186.021972 -303.097978) (xy 186.006388 -303.144659)
			(xy 185.983517 -303.188236) (xy 185.953952 -303.22758) (xy 185.918459 -303.261672) (xy 185.877956 -303.289628)
			(xy 185.833494 -303.310726) (xy 185.786223 -303.324418) (xy 185.737368 -303.33035) (xy 185.688193 -303.328369)
			(xy 185.639974 -303.318525) (xy 185.593958 -303.301073) (xy 185.551337 -303.276466) (xy 185.513216 -303.245341)
			(xy 185.480581 -303.208504) (xy 185.454278 -303.166908) (xy 185.434987 -303.121632) (xy 185.42321 -303.073848)
			(xy 185.41925 -303.024794) (xy 185.080148 -303.024794) (xy 185.079653 -303.049401) (xy 185.071758 -303.097978)
			(xy 185.056174 -303.144659) (xy 185.033303 -303.188236) (xy 185.003738 -303.22758) (xy 184.968245 -303.261672)
			(xy 184.927742 -303.289628) (xy 184.88328 -303.310726) (xy 184.836009 -303.324418) (xy 184.787154 -303.33035)
			(xy 184.737979 -303.328369) (xy 184.68976 -303.318525) (xy 184.643744 -303.301073) (xy 184.601123 -303.276466)
			(xy 184.563002 -303.245341) (xy 184.530367 -303.208504) (xy 184.504064 -303.166908) (xy 184.484773 -303.121632)
			(xy 184.472996 -303.073848) (xy 184.469036 -303.024794) (xy 166.11727 -303.024794) (xy 166.11727 -303.499774)
			(xy 189.69407 -303.499774) (xy 189.69803 -303.45072) (xy 189.709807 -303.402936) (xy 189.729098 -303.35766)
			(xy 189.755401 -303.316064) (xy 189.788036 -303.279227) (xy 189.826157 -303.248102) (xy 189.868778 -303.223495)
			(xy 189.914794 -303.206043) (xy 189.963013 -303.196199) (xy 190.012188 -303.194218) (xy 190.061043 -303.20015)
			(xy 190.108314 -303.213842) (xy 190.152776 -303.23494) (xy 190.193279 -303.262896) (xy 190.228772 -303.296988)
			(xy 190.258337 -303.336332) (xy 190.281208 -303.379909) (xy 190.296792 -303.42659) (xy 190.304687 -303.475167)
			(xy 190.305182 -303.499774) (xy 190.644284 -303.499774) (xy 190.648244 -303.45072) (xy 190.660021 -303.402936)
			(xy 190.679312 -303.35766) (xy 190.705615 -303.316064) (xy 190.73825 -303.279227) (xy 190.776371 -303.248102)
			(xy 190.818992 -303.223495) (xy 190.865008 -303.206043) (xy 190.913227 -303.196199) (xy 190.962402 -303.194218)
			(xy 191.011257 -303.20015) (xy 191.058528 -303.213842) (xy 191.10299 -303.23494) (xy 191.143493 -303.262896)
			(xy 191.178986 -303.296988) (xy 191.208551 -303.336332) (xy 191.231422 -303.379909) (xy 191.247006 -303.42659)
			(xy 191.254901 -303.475167) (xy 191.255396 -303.499774) (xy 191.594244 -303.499774) (xy 191.598204 -303.45072)
			(xy 191.609981 -303.402936) (xy 191.629272 -303.35766) (xy 191.655575 -303.316064) (xy 191.68821 -303.279227)
			(xy 191.726331 -303.248102) (xy 191.768952 -303.223495) (xy 191.814968 -303.206043) (xy 191.863187 -303.196199)
			(xy 191.912362 -303.194218) (xy 191.961217 -303.20015) (xy 192.008488 -303.213842) (xy 192.05295 -303.23494)
			(xy 192.093453 -303.262896) (xy 192.128946 -303.296988) (xy 192.158511 -303.336332) (xy 192.181382 -303.379909)
			(xy 192.196966 -303.42659) (xy 192.204861 -303.475167) (xy 192.20519 -303.491507) (xy 194.444155 -303.491507)
			(xy 194.449525 -303.442151) (xy 194.462809 -303.394313) (xy 194.483658 -303.349255) (xy 194.511522 -303.308164)
			(xy 194.545667 -303.272122) (xy 194.585193 -303.242079) (xy 194.629059 -303.218827) (xy 194.67611 -303.202978)
			(xy 194.725104 -303.19495) (xy 194.749928 -303.194466) (xy 194.764111 -303.194639) (xy 194.792351 -303.197314)
			(xy 194.806316 -303.1998) (xy 194.820277 -303.202001) (xy 194.848414 -303.199417) (xy 194.874766 -303.189222)
			(xy 194.897316 -303.172196) (xy 194.914336 -303.149642) (xy 194.924524 -303.123288) (xy 194.927099 -303.09515)
			(xy 194.924934 -303.081182) (xy 194.922459 -303.067216) (xy 194.919786 -303.038976) (xy 194.9196 -303.024794)
			(xy 194.920084 -302.999974) (xy 194.928116 -302.950988) (xy 194.943967 -302.903946) (xy 194.96722 -302.860089)
			(xy 194.997261 -302.820571) (xy 195.0333 -302.786434) (xy 195.074387 -302.758577) (xy 195.11944 -302.737734)
			(xy 195.167271 -302.724454) (xy 195.21662 -302.719087) (xy 195.266187 -302.721775) (xy 195.314667 -302.732446)
			(xy 195.360782 -302.75082) (xy 195.403316 -302.776412) (xy 195.44115 -302.808548) (xy 195.473287 -302.846382)
			(xy 195.498879 -302.888917) (xy 195.517253 -302.935031) (xy 195.527925 -302.983511) (xy 195.530164 -303.024794)
			(xy 195.869064 -303.024794) (xy 195.873024 -302.97574) (xy 195.884801 -302.927956) (xy 195.904092 -302.88268)
			(xy 195.930395 -302.841084) (xy 195.96303 -302.804247) (xy 196.001151 -302.773122) (xy 196.043772 -302.748515)
			(xy 196.089788 -302.731063) (xy 196.138007 -302.721219) (xy 196.187182 -302.719238) (xy 196.236037 -302.72517)
			(xy 196.283308 -302.738862) (xy 196.32777 -302.75996) (xy 196.368273 -302.787916) (xy 196.403766 -302.822008)
			(xy 196.433331 -302.861352) (xy 196.456202 -302.904929) (xy 196.471786 -302.95161) (xy 196.479681 -303.000187)
			(xy 196.480176 -303.024794) (xy 196.819278 -303.024794) (xy 196.823238 -302.97574) (xy 196.835015 -302.927956)
			(xy 196.854306 -302.88268) (xy 196.880609 -302.841084) (xy 196.913244 -302.804247) (xy 196.951365 -302.773122)
			(xy 196.993986 -302.748515) (xy 197.040002 -302.731063) (xy 197.088221 -302.721219) (xy 197.137396 -302.719238)
			(xy 197.186251 -302.72517) (xy 197.233522 -302.738862) (xy 197.277984 -302.75996) (xy 197.318487 -302.787916)
			(xy 197.35398 -302.822008) (xy 197.383545 -302.861352) (xy 197.406416 -302.904929) (xy 197.422 -302.95161)
			(xy 197.429895 -303.000187) (xy 197.43039 -303.024794) (xy 197.769238 -303.024794) (xy 197.773198 -302.97574)
			(xy 197.784975 -302.927956) (xy 197.804266 -302.88268) (xy 197.830569 -302.841084) (xy 197.863204 -302.804247)
			(xy 197.901325 -302.773122) (xy 197.943946 -302.748515) (xy 197.989962 -302.731063) (xy 198.038181 -302.721219)
			(xy 198.087356 -302.719238) (xy 198.136211 -302.72517) (xy 198.183482 -302.738862) (xy 198.227944 -302.75996)
			(xy 198.268447 -302.787916) (xy 198.30394 -302.822008) (xy 198.333505 -302.861352) (xy 198.356376 -302.904929)
			(xy 198.37196 -302.95161) (xy 198.379855 -303.000187) (xy 198.38035 -303.024794) (xy 198.703958 -303.024794)
			(xy 198.707918 -302.97574) (xy 198.719695 -302.927956) (xy 198.738986 -302.88268) (xy 198.765289 -302.841084)
			(xy 198.797924 -302.804247) (xy 198.836045 -302.773122) (xy 198.878666 -302.748515) (xy 198.924682 -302.731063)
			(xy 198.972901 -302.721219) (xy 199.022076 -302.719238) (xy 199.070931 -302.72517) (xy 199.118202 -302.738862)
			(xy 199.162664 -302.75996) (xy 199.203167 -302.787916) (xy 199.23866 -302.822008) (xy 199.268225 -302.861352)
			(xy 199.291096 -302.904929) (xy 199.30668 -302.95161) (xy 199.314575 -303.000187) (xy 199.31507 -303.024794)
			(xy 199.314575 -303.049401) (xy 199.309984 -303.077651) (xy 203.951303 -303.077651) (xy 203.951303 -303.023149)
			(xy 203.95906 -302.969202) (xy 203.974416 -302.916908) (xy 203.997058 -302.867332) (xy 204.026525 -302.821483)
			(xy 204.062218 -302.780295) (xy 204.103409 -302.744606) (xy 204.14926 -302.715142) (xy 204.198838 -302.692505)
			(xy 204.251133 -302.677153) (xy 204.305081 -302.669401) (xy 204.332332 -302.66894) (xy 204.360674 -302.669466)
			(xy 204.416737 -302.677839) (xy 204.470941 -302.694424) (xy 204.522089 -302.718857) (xy 204.569054 -302.750597)
			(xy 204.610798 -302.788944) (xy 204.629004 -302.810672) (xy 204.637791 -302.820791) (xy 204.659494 -302.836494)
			(xy 204.684534 -302.846013) (xy 204.711188 -302.848695) (xy 204.737622 -302.844356) (xy 204.762019 -302.833292)
			(xy 204.782701 -302.816266) (xy 204.790802 -302.805592) (xy 204.806246 -302.784717) (xy 204.841816 -302.746889)
			(xy 204.882188 -302.714234) (xy 204.926614 -302.687356) (xy 204.974275 -302.66675) (xy 205.02429 -302.652797)
			(xy 205.075736 -302.645755) (xy 205.101698 -302.645318) (xy 205.128953 -302.645729) (xy 205.182908 -302.653486)
			(xy 205.235209 -302.668843) (xy 205.284793 -302.691487) (xy 205.33065 -302.720957) (xy 205.371846 -302.756653)
			(xy 205.407542 -302.797849) (xy 205.437012 -302.843705) (xy 205.459656 -302.893289) (xy 205.475014 -302.94559)
			(xy 205.482771 -302.999545) (xy 205.482771 -303.026826) (xy 205.73568 -303.026826) (xy 205.739751 -302.971204)
			(xy 205.751877 -302.916767) (xy 205.7718 -302.864676) (xy 205.799096 -302.816041) (xy 205.833182 -302.771898)
			(xy 205.873331 -302.733189) (xy 205.918689 -302.700738) (xy 205.968289 -302.675237) (xy 206.021073 -302.65723)
			(xy 206.075916 -302.6471) (xy 206.13165 -302.645063) (xy 206.187087 -302.651163) (xy 206.241044 -302.665269)
			(xy 206.292373 -302.687081) (xy 206.339979 -302.716135) (xy 206.382847 -302.75181) (xy 206.420064 -302.793347)
			(xy 206.450837 -302.83986) (xy 206.474509 -302.890357) (xy 206.490577 -302.943764) (xy 206.498697 -302.99894)
			(xy 206.499206 -303.026826) (xy 206.75168 -303.026826) (xy 206.755751 -302.971204) (xy 206.767877 -302.916767)
			(xy 206.7878 -302.864676) (xy 206.815096 -302.816041) (xy 206.849182 -302.771898) (xy 206.889331 -302.733189)
			(xy 206.934689 -302.700738) (xy 206.984289 -302.675237) (xy 207.037073 -302.65723) (xy 207.091916 -302.6471)
			(xy 207.14765 -302.645063) (xy 207.203087 -302.651163) (xy 207.257044 -302.665269) (xy 207.308373 -302.687081)
			(xy 207.355979 -302.716135) (xy 207.398847 -302.75181) (xy 207.436064 -302.793347) (xy 207.466837 -302.83986)
			(xy 207.490509 -302.890357) (xy 207.506577 -302.943764) (xy 207.514697 -302.99894) (xy 207.515206 -303.026826)
			(xy 207.76768 -303.026826) (xy 207.771751 -302.971204) (xy 207.783877 -302.916767) (xy 207.8038 -302.864676)
			(xy 207.831096 -302.816041) (xy 207.865182 -302.771898) (xy 207.905331 -302.733189) (xy 207.950689 -302.700738)
			(xy 208.000289 -302.675237) (xy 208.053073 -302.65723) (xy 208.107916 -302.6471) (xy 208.16365 -302.645063)
			(xy 208.219087 -302.651163) (xy 208.273044 -302.665269) (xy 208.324373 -302.687081) (xy 208.371979 -302.716135)
			(xy 208.414847 -302.75181) (xy 208.452064 -302.793347) (xy 208.482837 -302.83986) (xy 208.506509 -302.890357)
			(xy 208.522577 -302.943764) (xy 208.530697 -302.99894) (xy 208.531206 -303.026826) (xy 208.78368 -303.026826)
			(xy 208.787751 -302.971204) (xy 208.799877 -302.916767) (xy 208.8198 -302.864676) (xy 208.847096 -302.816041)
			(xy 208.881182 -302.771898) (xy 208.921331 -302.733189) (xy 208.966689 -302.700738) (xy 209.016289 -302.675237)
			(xy 209.069073 -302.65723) (xy 209.123916 -302.6471) (xy 209.17965 -302.645063) (xy 209.235087 -302.651163)
			(xy 209.289044 -302.665269) (xy 209.340373 -302.687081) (xy 209.387979 -302.716135) (xy 209.430847 -302.75181)
			(xy 209.468064 -302.793347) (xy 209.498837 -302.83986) (xy 209.522509 -302.890357) (xy 209.538577 -302.943764)
			(xy 209.546697 -302.99894) (xy 209.547206 -303.026826) (xy 209.546697 -303.054712) (xy 209.538577 -303.109888)
			(xy 209.522509 -303.163295) (xy 209.498837 -303.213792) (xy 209.468064 -303.260305) (xy 209.430847 -303.301842)
			(xy 209.387979 -303.337517) (xy 209.340373 -303.366571) (xy 209.289044 -303.388383) (xy 209.235087 -303.402489)
			(xy 209.17965 -303.408589) (xy 209.123916 -303.406552) (xy 209.069073 -303.396422) (xy 209.016289 -303.378415)
			(xy 208.966689 -303.352914) (xy 208.921331 -303.320463) (xy 208.881182 -303.281754) (xy 208.847096 -303.237611)
			(xy 208.8198 -303.188976) (xy 208.799877 -303.136885) (xy 208.787751 -303.082448) (xy 208.78368 -303.026826)
			(xy 208.531206 -303.026826) (xy 208.530697 -303.054712) (xy 208.522577 -303.109888) (xy 208.506509 -303.163295)
			(xy 208.482837 -303.213792) (xy 208.452064 -303.260305) (xy 208.414847 -303.301842) (xy 208.371979 -303.337517)
			(xy 208.324373 -303.366571) (xy 208.273044 -303.388383) (xy 208.219087 -303.402489) (xy 208.16365 -303.408589)
			(xy 208.107916 -303.406552) (xy 208.053073 -303.396422) (xy 208.000289 -303.378415) (xy 207.950689 -303.352914)
			(xy 207.905331 -303.320463) (xy 207.865182 -303.281754) (xy 207.831096 -303.237611) (xy 207.8038 -303.188976)
			(xy 207.783877 -303.136885) (xy 207.771751 -303.082448) (xy 207.76768 -303.026826) (xy 207.515206 -303.026826)
			(xy 207.514697 -303.054712) (xy 207.506577 -303.109888) (xy 207.490509 -303.163295) (xy 207.466837 -303.213792)
			(xy 207.436064 -303.260305) (xy 207.398847 -303.301842) (xy 207.355979 -303.337517) (xy 207.308373 -303.366571)
			(xy 207.257044 -303.388383) (xy 207.203087 -303.402489) (xy 207.14765 -303.408589) (xy 207.091916 -303.406552)
			(xy 207.037073 -303.396422) (xy 206.984289 -303.378415) (xy 206.934689 -303.352914) (xy 206.889331 -303.320463)
			(xy 206.849182 -303.281754) (xy 206.815096 -303.237611) (xy 206.7878 -303.188976) (xy 206.767877 -303.136885)
			(xy 206.755751 -303.082448) (xy 206.75168 -303.026826) (xy 206.499206 -303.026826) (xy 206.498697 -303.054712)
			(xy 206.490577 -303.109888) (xy 206.474509 -303.163295) (xy 206.450837 -303.213792) (xy 206.420064 -303.260305)
			(xy 206.382847 -303.301842) (xy 206.339979 -303.337517) (xy 206.292373 -303.366571) (xy 206.241044 -303.388383)
			(xy 206.187087 -303.402489) (xy 206.13165 -303.408589) (xy 206.075916 -303.406552) (xy 206.021073 -303.396422)
			(xy 205.968289 -303.378415) (xy 205.918689 -303.352914) (xy 205.873331 -303.320463) (xy 205.833182 -303.281754)
			(xy 205.799096 -303.237611) (xy 205.7718 -303.188976) (xy 205.751877 -303.136885) (xy 205.739751 -303.082448)
			(xy 205.73568 -303.026826) (xy 205.482771 -303.026826) (xy 205.482771 -303.054055) (xy 205.475014 -303.10801)
			(xy 205.459656 -303.160311) (xy 205.437012 -303.209895) (xy 205.407542 -303.255751) (xy 205.371846 -303.296947)
			(xy 205.33065 -303.332643) (xy 205.284793 -303.362113) (xy 205.235209 -303.384757) (xy 205.182908 -303.400114)
			(xy 205.128953 -303.407871) (xy 205.101698 -303.408334) (xy 205.073355 -303.40783) (xy 205.017293 -303.399449)
			(xy 204.96309 -303.382857) (xy 204.911942 -303.358421) (xy 204.864978 -303.326678) (xy 204.823233 -303.28833)
			(xy 204.805026 -303.266602) (xy 204.796314 -303.256414) (xy 204.774592 -303.240716) (xy 204.749535 -303.231205)
			(xy 204.722868 -303.228533) (xy 204.696422 -303.232885) (xy 204.672017 -303.243962) (xy 204.65133 -303.261001)
			(xy 204.643228 -303.271682) (xy 204.627819 -303.292584) (xy 204.592244 -303.330412) (xy 204.551867 -303.363066)
			(xy 204.507434 -303.389942) (xy 204.459767 -303.410543) (xy 204.409746 -303.42449) (xy 204.358296 -303.431523)
			(xy 204.332332 -303.431956) (xy 204.305081 -303.431399) (xy 204.251133 -303.423647) (xy 204.198838 -303.408295)
			(xy 204.14926 -303.385658) (xy 204.103409 -303.356194) (xy 204.062218 -303.320505) (xy 204.026525 -303.279317)
			(xy 203.997058 -303.233468) (xy 203.974416 -303.183892) (xy 203.95906 -303.131598) (xy 203.951303 -303.077651)
			(xy 199.309984 -303.077651) (xy 199.30668 -303.097978) (xy 199.291096 -303.144659) (xy 199.268225 -303.188236)
			(xy 199.23866 -303.22758) (xy 199.203167 -303.261672) (xy 199.162664 -303.289628) (xy 199.118202 -303.310726)
			(xy 199.070931 -303.324418) (xy 199.022076 -303.33035) (xy 198.972901 -303.328369) (xy 198.924682 -303.318525)
			(xy 198.878666 -303.301073) (xy 198.836045 -303.276466) (xy 198.797924 -303.245341) (xy 198.765289 -303.208504)
			(xy 198.738986 -303.166908) (xy 198.719695 -303.121632) (xy 198.707918 -303.073848) (xy 198.703958 -303.024794)
			(xy 198.38035 -303.024794) (xy 198.379855 -303.049401) (xy 198.37196 -303.097978) (xy 198.356376 -303.144659)
			(xy 198.333505 -303.188236) (xy 198.30394 -303.22758) (xy 198.268447 -303.261672) (xy 198.227944 -303.289628)
			(xy 198.183482 -303.310726) (xy 198.136211 -303.324418) (xy 198.087356 -303.33035) (xy 198.038181 -303.328369)
			(xy 197.989962 -303.318525) (xy 197.943946 -303.301073) (xy 197.901325 -303.276466) (xy 197.863204 -303.245341)
			(xy 197.830569 -303.208504) (xy 197.804266 -303.166908) (xy 197.784975 -303.121632) (xy 197.773198 -303.073848)
			(xy 197.769238 -303.024794) (xy 197.43039 -303.024794) (xy 197.429895 -303.049401) (xy 197.422 -303.097978)
			(xy 197.406416 -303.144659) (xy 197.383545 -303.188236) (xy 197.35398 -303.22758) (xy 197.318487 -303.261672)
			(xy 197.277984 -303.289628) (xy 197.233522 -303.310726) (xy 197.186251 -303.324418) (xy 197.137396 -303.33035)
			(xy 197.088221 -303.328369) (xy 197.040002 -303.318525) (xy 196.993986 -303.301073) (xy 196.951365 -303.276466)
			(xy 196.913244 -303.245341) (xy 196.880609 -303.208504) (xy 196.854306 -303.166908) (xy 196.835015 -303.121632)
			(xy 196.823238 -303.073848) (xy 196.819278 -303.024794) (xy 196.480176 -303.024794) (xy 196.479681 -303.049401)
			(xy 196.471786 -303.097978) (xy 196.456202 -303.144659) (xy 196.433331 -303.188236) (xy 196.403766 -303.22758)
			(xy 196.368273 -303.261672) (xy 196.32777 -303.289628) (xy 196.283308 -303.310726) (xy 196.236037 -303.324418)
			(xy 196.187182 -303.33035) (xy 196.138007 -303.328369) (xy 196.089788 -303.318525) (xy 196.043772 -303.301073)
			(xy 196.001151 -303.276466) (xy 195.96303 -303.245341) (xy 195.930395 -303.208504) (xy 195.904092 -303.166908)
			(xy 195.884801 -303.121632) (xy 195.873024 -303.073848) (xy 195.869064 -303.024794) (xy 195.530164 -303.024794)
			(xy 195.530613 -303.033078) (xy 195.525246 -303.082427) (xy 195.511967 -303.130259) (xy 195.491124 -303.175311)
			(xy 195.463267 -303.216398) (xy 195.429131 -303.252437) (xy 195.389613 -303.282479) (xy 195.345756 -303.305732)
			(xy 195.298714 -303.321583) (xy 195.249728 -303.329616) (xy 195.224908 -303.330102) (xy 195.210725 -303.329924)
			(xy 195.182485 -303.327253) (xy 195.16852 -303.324768) (xy 195.15455 -303.322643) (xy 195.126423 -303.325217)
			(xy 195.100078 -303.335401) (xy 195.077533 -303.352414) (xy 195.060514 -303.374955) (xy 195.050323 -303.401296)
			(xy 195.047741 -303.429423) (xy 195.049902 -303.443386) (xy 195.052373 -303.457353) (xy 195.055048 -303.485592)
			(xy 195.055236 -303.499774) (xy 195.05475 -303.524598) (xy 195.046722 -303.573592) (xy 195.030873 -303.620642)
			(xy 195.00762 -303.664508) (xy 194.977577 -303.704034) (xy 194.941535 -303.738179) (xy 194.900443 -303.766043)
			(xy 194.855385 -303.786891) (xy 194.807547 -303.800175) (xy 194.758191 -303.805545) (xy 194.708616 -303.802858)
			(xy 194.660128 -303.792186) (xy 194.614007 -303.77381) (xy 194.571465 -303.748214) (xy 194.533626 -303.716073)
			(xy 194.501485 -303.678233) (xy 194.475889 -303.635692) (xy 194.457513 -303.58957) (xy 194.446842 -303.541082)
			(xy 194.444155 -303.491507) (xy 192.20519 -303.491507) (xy 192.205356 -303.499774) (xy 192.204861 -303.524381)
			(xy 192.196966 -303.572958) (xy 192.181382 -303.619639) (xy 192.158511 -303.663216) (xy 192.128946 -303.70256)
			(xy 192.093453 -303.736652) (xy 192.05295 -303.764608) (xy 192.008488 -303.785706) (xy 191.961217 -303.799398)
			(xy 191.912362 -303.80533) (xy 191.863187 -303.803349) (xy 191.814968 -303.793505) (xy 191.768952 -303.776053)
			(xy 191.726331 -303.751446) (xy 191.68821 -303.720321) (xy 191.655575 -303.683484) (xy 191.629272 -303.641888)
			(xy 191.609981 -303.596612) (xy 191.598204 -303.548828) (xy 191.594244 -303.499774) (xy 191.255396 -303.499774)
			(xy 191.254901 -303.524381) (xy 191.247006 -303.572958) (xy 191.231422 -303.619639) (xy 191.208551 -303.663216)
			(xy 191.178986 -303.70256) (xy 191.143493 -303.736652) (xy 191.10299 -303.764608) (xy 191.058528 -303.785706)
			(xy 191.011257 -303.799398) (xy 190.962402 -303.80533) (xy 190.913227 -303.803349) (xy 190.865008 -303.793505)
			(xy 190.818992 -303.776053) (xy 190.776371 -303.751446) (xy 190.73825 -303.720321) (xy 190.705615 -303.683484)
			(xy 190.679312 -303.641888) (xy 190.660021 -303.596612) (xy 190.648244 -303.548828) (xy 190.644284 -303.499774)
			(xy 190.305182 -303.499774) (xy 190.304687 -303.524381) (xy 190.296792 -303.572958) (xy 190.281208 -303.619639)
			(xy 190.258337 -303.663216) (xy 190.228772 -303.70256) (xy 190.193279 -303.736652) (xy 190.152776 -303.764608)
			(xy 190.108314 -303.785706) (xy 190.061043 -303.799398) (xy 190.012188 -303.80533) (xy 189.963013 -303.803349)
			(xy 189.914794 -303.793505) (xy 189.868778 -303.776053) (xy 189.826157 -303.751446) (xy 189.788036 -303.720321)
			(xy 189.755401 -303.683484) (xy 189.729098 -303.641888) (xy 189.709807 -303.596612) (xy 189.69803 -303.548828)
			(xy 189.69407 -303.499774) (xy 166.11727 -303.499774) (xy 166.11727 -303.974754) (xy 166.419288 -303.974754)
			(xy 166.423248 -303.9257) (xy 166.435025 -303.877916) (xy 166.454316 -303.83264) (xy 166.480619 -303.791044)
			(xy 166.513254 -303.754207) (xy 166.551375 -303.723082) (xy 166.593996 -303.698475) (xy 166.640012 -303.681023)
			(xy 166.688231 -303.671179) (xy 166.737406 -303.669198) (xy 166.786261 -303.67513) (xy 166.833532 -303.688822)
			(xy 166.877994 -303.70992) (xy 166.918497 -303.737876) (xy 166.95399 -303.771968) (xy 166.983555 -303.811312)
			(xy 167.006426 -303.854889) (xy 167.02201 -303.90157) (xy 167.029905 -303.950147) (xy 167.0304 -303.974754)
			(xy 167.369248 -303.974754) (xy 167.373208 -303.9257) (xy 167.384985 -303.877916) (xy 167.404276 -303.83264)
			(xy 167.430579 -303.791044) (xy 167.463214 -303.754207) (xy 167.501335 -303.723082) (xy 167.543956 -303.698475)
			(xy 167.589972 -303.681023) (xy 167.638191 -303.671179) (xy 167.687366 -303.669198) (xy 167.736221 -303.67513)
			(xy 167.783492 -303.688822) (xy 167.827954 -303.70992) (xy 167.868457 -303.737876) (xy 167.90395 -303.771968)
			(xy 167.933515 -303.811312) (xy 167.956386 -303.854889) (xy 167.97197 -303.90157) (xy 167.979865 -303.950147)
			(xy 167.98036 -303.974754) (xy 168.319208 -303.974754) (xy 168.323168 -303.9257) (xy 168.334945 -303.877916)
			(xy 168.354236 -303.83264) (xy 168.380539 -303.791044) (xy 168.413174 -303.754207) (xy 168.451295 -303.723082)
			(xy 168.493916 -303.698475) (xy 168.539932 -303.681023) (xy 168.588151 -303.671179) (xy 168.637326 -303.669198)
			(xy 168.686181 -303.67513) (xy 168.733452 -303.688822) (xy 168.777914 -303.70992) (xy 168.818417 -303.737876)
			(xy 168.85391 -303.771968) (xy 168.883475 -303.811312) (xy 168.906346 -303.854889) (xy 168.92193 -303.90157)
			(xy 168.929825 -303.950147) (xy 168.93032 -303.974754) (xy 169.269168 -303.974754) (xy 169.273128 -303.9257)
			(xy 169.284905 -303.877916) (xy 169.304196 -303.83264) (xy 169.330499 -303.791044) (xy 169.363134 -303.754207)
			(xy 169.401255 -303.723082) (xy 169.443876 -303.698475) (xy 169.489892 -303.681023) (xy 169.538111 -303.671179)
			(xy 169.587286 -303.669198) (xy 169.636141 -303.67513) (xy 169.683412 -303.688822) (xy 169.727874 -303.70992)
			(xy 169.768377 -303.737876) (xy 169.80387 -303.771968) (xy 169.833435 -303.811312) (xy 169.856306 -303.854889)
			(xy 169.87189 -303.90157) (xy 169.879785 -303.950147) (xy 169.88028 -303.974754) (xy 170.219128 -303.974754)
			(xy 170.223088 -303.9257) (xy 170.234865 -303.877916) (xy 170.254156 -303.83264) (xy 170.280459 -303.791044)
			(xy 170.313094 -303.754207) (xy 170.351215 -303.723082) (xy 170.393836 -303.698475) (xy 170.439852 -303.681023)
			(xy 170.488071 -303.671179) (xy 170.537246 -303.669198) (xy 170.586101 -303.67513) (xy 170.633372 -303.688822)
			(xy 170.677834 -303.70992) (xy 170.718337 -303.737876) (xy 170.75383 -303.771968) (xy 170.783395 -303.811312)
			(xy 170.806266 -303.854889) (xy 170.82185 -303.90157) (xy 170.829745 -303.950147) (xy 170.83024 -303.974754)
			(xy 171.169088 -303.974754) (xy 171.173048 -303.9257) (xy 171.184825 -303.877916) (xy 171.204116 -303.83264)
			(xy 171.230419 -303.791044) (xy 171.263054 -303.754207) (xy 171.301175 -303.723082) (xy 171.343796 -303.698475)
			(xy 171.389812 -303.681023) (xy 171.438031 -303.671179) (xy 171.487206 -303.669198) (xy 171.536061 -303.67513)
			(xy 171.583332 -303.688822) (xy 171.627794 -303.70992) (xy 171.668297 -303.737876) (xy 171.70379 -303.771968)
			(xy 171.733355 -303.811312) (xy 171.756226 -303.854889) (xy 171.77181 -303.90157) (xy 171.779705 -303.950147)
			(xy 171.7802 -303.974754) (xy 172.119048 -303.974754) (xy 172.123008 -303.9257) (xy 172.134785 -303.877916)
			(xy 172.154076 -303.83264) (xy 172.180379 -303.791044) (xy 172.213014 -303.754207) (xy 172.251135 -303.723082)
			(xy 172.293756 -303.698475) (xy 172.339772 -303.681023) (xy 172.387991 -303.671179) (xy 172.437166 -303.669198)
			(xy 172.486021 -303.67513) (xy 172.533292 -303.688822) (xy 172.577754 -303.70992) (xy 172.618257 -303.737876)
			(xy 172.65375 -303.771968) (xy 172.683315 -303.811312) (xy 172.706186 -303.854889) (xy 172.72177 -303.90157)
			(xy 172.729665 -303.950147) (xy 172.73016 -303.974754) (xy 173.069262 -303.974754) (xy 173.073222 -303.9257)
			(xy 173.084999 -303.877916) (xy 173.10429 -303.83264) (xy 173.130593 -303.791044) (xy 173.163228 -303.754207)
			(xy 173.201349 -303.723082) (xy 173.24397 -303.698475) (xy 173.289986 -303.681023) (xy 173.338205 -303.671179)
			(xy 173.38738 -303.669198) (xy 173.436235 -303.67513) (xy 173.483506 -303.688822) (xy 173.527968 -303.70992)
			(xy 173.568471 -303.737876) (xy 173.603964 -303.771968) (xy 173.633529 -303.811312) (xy 173.6564 -303.854889)
			(xy 173.671984 -303.90157) (xy 173.679879 -303.950147) (xy 173.680374 -303.974754) (xy 174.019222 -303.974754)
			(xy 174.023182 -303.9257) (xy 174.034959 -303.877916) (xy 174.05425 -303.83264) (xy 174.080553 -303.791044)
			(xy 174.113188 -303.754207) (xy 174.151309 -303.723082) (xy 174.19393 -303.698475) (xy 174.239946 -303.681023)
			(xy 174.288165 -303.671179) (xy 174.33734 -303.669198) (xy 174.386195 -303.67513) (xy 174.433466 -303.688822)
			(xy 174.477928 -303.70992) (xy 174.518431 -303.737876) (xy 174.553924 -303.771968) (xy 174.583489 -303.811312)
			(xy 174.60636 -303.854889) (xy 174.621944 -303.90157) (xy 174.629839 -303.950147) (xy 174.630334 -303.974754)
			(xy 175.919142 -303.974754) (xy 175.923102 -303.9257) (xy 175.934879 -303.877916) (xy 175.95417 -303.83264)
			(xy 175.980473 -303.791044) (xy 176.013108 -303.754207) (xy 176.051229 -303.723082) (xy 176.09385 -303.698475)
			(xy 176.139866 -303.681023) (xy 176.188085 -303.671179) (xy 176.23726 -303.669198) (xy 176.286115 -303.67513)
			(xy 176.333386 -303.688822) (xy 176.377848 -303.70992) (xy 176.418351 -303.737876) (xy 176.453844 -303.771968)
			(xy 176.483409 -303.811312) (xy 176.50628 -303.854889) (xy 176.521864 -303.90157) (xy 176.529759 -303.950147)
			(xy 176.530254 -303.974754) (xy 176.869102 -303.974754) (xy 176.873062 -303.9257) (xy 176.884839 -303.877916)
			(xy 176.90413 -303.83264) (xy 176.930433 -303.791044) (xy 176.963068 -303.754207) (xy 177.001189 -303.723082)
			(xy 177.04381 -303.698475) (xy 177.089826 -303.681023) (xy 177.138045 -303.671179) (xy 177.18722 -303.669198)
			(xy 177.236075 -303.67513) (xy 177.283346 -303.688822) (xy 177.327808 -303.70992) (xy 177.368311 -303.737876)
			(xy 177.403804 -303.771968) (xy 177.433369 -303.811312) (xy 177.45624 -303.854889) (xy 177.471824 -303.90157)
			(xy 177.479719 -303.950147) (xy 177.480214 -303.974754) (xy 177.819062 -303.974754) (xy 177.823022 -303.9257)
			(xy 177.834799 -303.877916) (xy 177.85409 -303.83264) (xy 177.880393 -303.791044) (xy 177.913028 -303.754207)
			(xy 177.951149 -303.723082) (xy 177.99377 -303.698475) (xy 178.039786 -303.681023) (xy 178.088005 -303.671179)
			(xy 178.13718 -303.669198) (xy 178.186035 -303.67513) (xy 178.233306 -303.688822) (xy 178.277768 -303.70992)
			(xy 178.318271 -303.737876) (xy 178.353764 -303.771968) (xy 178.383329 -303.811312) (xy 178.4062 -303.854889)
			(xy 178.421784 -303.90157) (xy 178.429679 -303.950147) (xy 178.430174 -303.974754) (xy 178.769276 -303.974754)
			(xy 178.773236 -303.9257) (xy 178.785013 -303.877916) (xy 178.804304 -303.83264) (xy 178.830607 -303.791044)
			(xy 178.863242 -303.754207) (xy 178.901363 -303.723082) (xy 178.943984 -303.698475) (xy 178.99 -303.681023)
			(xy 179.038219 -303.671179) (xy 179.087394 -303.669198) (xy 179.136249 -303.67513) (xy 179.18352 -303.688822)
			(xy 179.227982 -303.70992) (xy 179.268485 -303.737876) (xy 179.303978 -303.771968) (xy 179.333543 -303.811312)
			(xy 179.356414 -303.854889) (xy 179.371998 -303.90157) (xy 179.379893 -303.950147) (xy 179.380388 -303.974754)
			(xy 179.719236 -303.974754) (xy 179.723196 -303.9257) (xy 179.734973 -303.877916) (xy 179.754264 -303.83264)
			(xy 179.780567 -303.791044) (xy 179.813202 -303.754207) (xy 179.851323 -303.723082) (xy 179.893944 -303.698475)
			(xy 179.93996 -303.681023) (xy 179.988179 -303.671179) (xy 180.037354 -303.669198) (xy 180.086209 -303.67513)
			(xy 180.13348 -303.688822) (xy 180.177942 -303.70992) (xy 180.218445 -303.737876) (xy 180.253938 -303.771968)
			(xy 180.283503 -303.811312) (xy 180.306374 -303.854889) (xy 180.321958 -303.90157) (xy 180.329853 -303.950147)
			(xy 180.330348 -303.974754) (xy 180.669196 -303.974754) (xy 180.673156 -303.9257) (xy 180.684933 -303.877916)
			(xy 180.704224 -303.83264) (xy 180.730527 -303.791044) (xy 180.763162 -303.754207) (xy 180.801283 -303.723082)
			(xy 180.843904 -303.698475) (xy 180.88992 -303.681023) (xy 180.938139 -303.671179) (xy 180.987314 -303.669198)
			(xy 181.036169 -303.67513) (xy 181.08344 -303.688822) (xy 181.127902 -303.70992) (xy 181.168405 -303.737876)
			(xy 181.203898 -303.771968) (xy 181.233463 -303.811312) (xy 181.256334 -303.854889) (xy 181.271918 -303.90157)
			(xy 181.279813 -303.950147) (xy 181.280308 -303.974754) (xy 181.619156 -303.974754) (xy 181.623116 -303.9257)
			(xy 181.634893 -303.877916) (xy 181.654184 -303.83264) (xy 181.680487 -303.791044) (xy 181.713122 -303.754207)
			(xy 181.751243 -303.723082) (xy 181.793864 -303.698475) (xy 181.83988 -303.681023) (xy 181.888099 -303.671179)
			(xy 181.937274 -303.669198) (xy 181.986129 -303.67513) (xy 182.0334 -303.688822) (xy 182.077862 -303.70992)
			(xy 182.118365 -303.737876) (xy 182.153858 -303.771968) (xy 182.183423 -303.811312) (xy 182.206294 -303.854889)
			(xy 182.221878 -303.90157) (xy 182.229773 -303.950147) (xy 182.230268 -303.974754) (xy 182.569116 -303.974754)
			(xy 182.573076 -303.9257) (xy 182.584853 -303.877916) (xy 182.604144 -303.83264) (xy 182.630447 -303.791044)
			(xy 182.663082 -303.754207) (xy 182.701203 -303.723082) (xy 182.743824 -303.698475) (xy 182.78984 -303.681023)
			(xy 182.838059 -303.671179) (xy 182.887234 -303.669198) (xy 182.936089 -303.67513) (xy 182.98336 -303.688822)
			(xy 183.027822 -303.70992) (xy 183.068325 -303.737876) (xy 183.103818 -303.771968) (xy 183.133383 -303.811312)
			(xy 183.156254 -303.854889) (xy 183.171838 -303.90157) (xy 183.179733 -303.950147) (xy 183.180228 -303.974754)
			(xy 183.519076 -303.974754) (xy 183.523036 -303.9257) (xy 183.534813 -303.877916) (xy 183.554104 -303.83264)
			(xy 183.580407 -303.791044) (xy 183.613042 -303.754207) (xy 183.651163 -303.723082) (xy 183.693784 -303.698475)
			(xy 183.7398 -303.681023) (xy 183.788019 -303.671179) (xy 183.837194 -303.669198) (xy 183.886049 -303.67513)
			(xy 183.93332 -303.688822) (xy 183.977782 -303.70992) (xy 184.018285 -303.737876) (xy 184.053778 -303.771968)
			(xy 184.083343 -303.811312) (xy 184.106214 -303.854889) (xy 184.121798 -303.90157) (xy 184.129693 -303.950147)
			(xy 184.130091 -303.969928) (xy 184.474116 -303.969928) (xy 184.478076 -303.920874) (xy 184.489853 -303.87309)
			(xy 184.509144 -303.827814) (xy 184.535447 -303.786218) (xy 184.568082 -303.749381) (xy 184.606203 -303.718256)
			(xy 184.648824 -303.693649) (xy 184.69484 -303.676197) (xy 184.743059 -303.666353) (xy 184.792234 -303.664372)
			(xy 184.841089 -303.670304) (xy 184.88836 -303.683996) (xy 184.932822 -303.705094) (xy 184.973325 -303.73305)
			(xy 185.008818 -303.767142) (xy 185.038383 -303.806486) (xy 185.061254 -303.850063) (xy 185.076838 -303.896744)
			(xy 185.084733 -303.945321) (xy 185.085228 -303.969928) (xy 185.085131 -303.974754) (xy 185.41925 -303.974754)
			(xy 185.42321 -303.9257) (xy 185.434987 -303.877916) (xy 185.454278 -303.83264) (xy 185.480581 -303.791044)
			(xy 185.513216 -303.754207) (xy 185.551337 -303.723082) (xy 185.593958 -303.698475) (xy 185.639974 -303.681023)
			(xy 185.688193 -303.671179) (xy 185.737368 -303.669198) (xy 185.786223 -303.67513) (xy 185.833494 -303.688822)
			(xy 185.877956 -303.70992) (xy 185.918459 -303.737876) (xy 185.953952 -303.771968) (xy 185.983517 -303.811312)
			(xy 186.006388 -303.854889) (xy 186.021972 -303.90157) (xy 186.029867 -303.950147) (xy 186.030362 -303.974754)
			(xy 186.36921 -303.974754) (xy 186.37317 -303.9257) (xy 186.384947 -303.877916) (xy 186.404238 -303.83264)
			(xy 186.430541 -303.791044) (xy 186.463176 -303.754207) (xy 186.501297 -303.723082) (xy 186.543918 -303.698475)
			(xy 186.589934 -303.681023) (xy 186.638153 -303.671179) (xy 186.687328 -303.669198) (xy 186.736183 -303.67513)
			(xy 186.783454 -303.688822) (xy 186.827916 -303.70992) (xy 186.868419 -303.737876) (xy 186.903912 -303.771968)
			(xy 186.933477 -303.811312) (xy 186.956348 -303.854889) (xy 186.971932 -303.90157) (xy 186.979827 -303.950147)
			(xy 186.980322 -303.974754) (xy 187.31917 -303.974754) (xy 187.32313 -303.9257) (xy 187.334907 -303.877916)
			(xy 187.354198 -303.83264) (xy 187.380501 -303.791044) (xy 187.413136 -303.754207) (xy 187.451257 -303.723082)
			(xy 187.493878 -303.698475) (xy 187.539894 -303.681023) (xy 187.588113 -303.671179) (xy 187.637288 -303.669198)
			(xy 187.686143 -303.67513) (xy 187.733414 -303.688822) (xy 187.777876 -303.70992) (xy 187.818379 -303.737876)
			(xy 187.853872 -303.771968) (xy 187.883437 -303.811312) (xy 187.906308 -303.854889) (xy 187.921892 -303.90157)
			(xy 187.929787 -303.950147) (xy 187.930282 -303.974754) (xy 188.26913 -303.974754) (xy 188.27309 -303.9257)
			(xy 188.284867 -303.877916) (xy 188.304158 -303.83264) (xy 188.330461 -303.791044) (xy 188.363096 -303.754207)
			(xy 188.401217 -303.723082) (xy 188.443838 -303.698475) (xy 188.489854 -303.681023) (xy 188.538073 -303.671179)
			(xy 188.587248 -303.669198) (xy 188.636103 -303.67513) (xy 188.683374 -303.688822) (xy 188.727836 -303.70992)
			(xy 188.768339 -303.737876) (xy 188.803832 -303.771968) (xy 188.833397 -303.811312) (xy 188.856268 -303.854889)
			(xy 188.871852 -303.90157) (xy 188.879747 -303.950147) (xy 188.880242 -303.974754) (xy 188.879747 -303.999361)
			(xy 188.871852 -304.047938) (xy 188.856268 -304.094619) (xy 188.833397 -304.138196) (xy 188.803832 -304.17754)
			(xy 188.768339 -304.211632) (xy 188.727836 -304.239588) (xy 188.683374 -304.260686) (xy 188.636103 -304.274378)
			(xy 188.587248 -304.28031) (xy 188.538073 -304.278329) (xy 188.489854 -304.268485) (xy 188.443838 -304.251033)
			(xy 188.401217 -304.226426) (xy 188.363096 -304.195301) (xy 188.330461 -304.158464) (xy 188.304158 -304.116868)
			(xy 188.284867 -304.071592) (xy 188.27309 -304.023808) (xy 188.26913 -303.974754) (xy 187.930282 -303.974754)
			(xy 187.929787 -303.999361) (xy 187.921892 -304.047938) (xy 187.906308 -304.094619) (xy 187.883437 -304.138196)
			(xy 187.853872 -304.17754) (xy 187.818379 -304.211632) (xy 187.777876 -304.239588) (xy 187.733414 -304.260686)
			(xy 187.686143 -304.274378) (xy 187.637288 -304.28031) (xy 187.588113 -304.278329) (xy 187.539894 -304.268485)
			(xy 187.493878 -304.251033) (xy 187.451257 -304.226426) (xy 187.413136 -304.195301) (xy 187.380501 -304.158464)
			(xy 187.354198 -304.116868) (xy 187.334907 -304.071592) (xy 187.32313 -304.023808) (xy 187.31917 -303.974754)
			(xy 186.980322 -303.974754) (xy 186.979827 -303.999361) (xy 186.971932 -304.047938) (xy 186.956348 -304.094619)
			(xy 186.933477 -304.138196) (xy 186.903912 -304.17754) (xy 186.868419 -304.211632) (xy 186.827916 -304.239588)
			(xy 186.783454 -304.260686) (xy 186.736183 -304.274378) (xy 186.687328 -304.28031) (xy 186.638153 -304.278329)
			(xy 186.589934 -304.268485) (xy 186.543918 -304.251033) (xy 186.501297 -304.226426) (xy 186.463176 -304.195301)
			(xy 186.430541 -304.158464) (xy 186.404238 -304.116868) (xy 186.384947 -304.071592) (xy 186.37317 -304.023808)
			(xy 186.36921 -303.974754) (xy 186.030362 -303.974754) (xy 186.029867 -303.999361) (xy 186.021972 -304.047938)
			(xy 186.006388 -304.094619) (xy 185.983517 -304.138196) (xy 185.953952 -304.17754) (xy 185.918459 -304.211632)
			(xy 185.877956 -304.239588) (xy 185.833494 -304.260686) (xy 185.786223 -304.274378) (xy 185.737368 -304.28031)
			(xy 185.688193 -304.278329) (xy 185.639974 -304.268485) (xy 185.593958 -304.251033) (xy 185.551337 -304.226426)
			(xy 185.513216 -304.195301) (xy 185.480581 -304.158464) (xy 185.454278 -304.116868) (xy 185.434987 -304.071592)
			(xy 185.42321 -304.023808) (xy 185.41925 -303.974754) (xy 185.085131 -303.974754) (xy 185.084733 -303.994535)
			(xy 185.076838 -304.043112) (xy 185.061254 -304.089793) (xy 185.038383 -304.13337) (xy 185.008818 -304.172714)
			(xy 184.973325 -304.206806) (xy 184.932822 -304.234762) (xy 184.88836 -304.25586) (xy 184.841089 -304.269552)
			(xy 184.792234 -304.275484) (xy 184.743059 -304.273503) (xy 184.69484 -304.263659) (xy 184.648824 -304.246207)
			(xy 184.606203 -304.2216) (xy 184.568082 -304.190475) (xy 184.535447 -304.153638) (xy 184.509144 -304.112042)
			(xy 184.489853 -304.066766) (xy 184.478076 -304.018982) (xy 184.474116 -303.969928) (xy 184.130091 -303.969928)
			(xy 184.130188 -303.974754) (xy 184.129693 -303.999361) (xy 184.121798 -304.047938) (xy 184.106214 -304.094619)
			(xy 184.083343 -304.138196) (xy 184.053778 -304.17754) (xy 184.018285 -304.211632) (xy 183.977782 -304.239588)
			(xy 183.93332 -304.260686) (xy 183.886049 -304.274378) (xy 183.837194 -304.28031) (xy 183.788019 -304.278329)
			(xy 183.7398 -304.268485) (xy 183.693784 -304.251033) (xy 183.651163 -304.226426) (xy 183.613042 -304.195301)
			(xy 183.580407 -304.158464) (xy 183.554104 -304.116868) (xy 183.534813 -304.071592) (xy 183.523036 -304.023808)
			(xy 183.519076 -303.974754) (xy 183.180228 -303.974754) (xy 183.179733 -303.999361) (xy 183.171838 -304.047938)
			(xy 183.156254 -304.094619) (xy 183.133383 -304.138196) (xy 183.103818 -304.17754) (xy 183.068325 -304.211632)
			(xy 183.027822 -304.239588) (xy 182.98336 -304.260686) (xy 182.936089 -304.274378) (xy 182.887234 -304.28031)
			(xy 182.838059 -304.278329) (xy 182.78984 -304.268485) (xy 182.743824 -304.251033) (xy 182.701203 -304.226426)
			(xy 182.663082 -304.195301) (xy 182.630447 -304.158464) (xy 182.604144 -304.116868) (xy 182.584853 -304.071592)
			(xy 182.573076 -304.023808) (xy 182.569116 -303.974754) (xy 182.230268 -303.974754) (xy 182.229773 -303.999361)
			(xy 182.221878 -304.047938) (xy 182.206294 -304.094619) (xy 182.183423 -304.138196) (xy 182.153858 -304.17754)
			(xy 182.118365 -304.211632) (xy 182.077862 -304.239588) (xy 182.0334 -304.260686) (xy 181.986129 -304.274378)
			(xy 181.937274 -304.28031) (xy 181.888099 -304.278329) (xy 181.83988 -304.268485) (xy 181.793864 -304.251033)
			(xy 181.751243 -304.226426) (xy 181.713122 -304.195301) (xy 181.680487 -304.158464) (xy 181.654184 -304.116868)
			(xy 181.634893 -304.071592) (xy 181.623116 -304.023808) (xy 181.619156 -303.974754) (xy 181.280308 -303.974754)
			(xy 181.279813 -303.999361) (xy 181.271918 -304.047938) (xy 181.256334 -304.094619) (xy 181.233463 -304.138196)
			(xy 181.203898 -304.17754) (xy 181.168405 -304.211632) (xy 181.127902 -304.239588) (xy 181.08344 -304.260686)
			(xy 181.036169 -304.274378) (xy 180.987314 -304.28031) (xy 180.938139 -304.278329) (xy 180.88992 -304.268485)
			(xy 180.843904 -304.251033) (xy 180.801283 -304.226426) (xy 180.763162 -304.195301) (xy 180.730527 -304.158464)
			(xy 180.704224 -304.116868) (xy 180.684933 -304.071592) (xy 180.673156 -304.023808) (xy 180.669196 -303.974754)
			(xy 180.330348 -303.974754) (xy 180.329853 -303.999361) (xy 180.321958 -304.047938) (xy 180.306374 -304.094619)
			(xy 180.283503 -304.138196) (xy 180.253938 -304.17754) (xy 180.218445 -304.211632) (xy 180.177942 -304.239588)
			(xy 180.13348 -304.260686) (xy 180.086209 -304.274378) (xy 180.037354 -304.28031) (xy 179.988179 -304.278329)
			(xy 179.93996 -304.268485) (xy 179.893944 -304.251033) (xy 179.851323 -304.226426) (xy 179.813202 -304.195301)
			(xy 179.780567 -304.158464) (xy 179.754264 -304.116868) (xy 179.734973 -304.071592) (xy 179.723196 -304.023808)
			(xy 179.719236 -303.974754) (xy 179.380388 -303.974754) (xy 179.379893 -303.999361) (xy 179.371998 -304.047938)
			(xy 179.356414 -304.094619) (xy 179.333543 -304.138196) (xy 179.303978 -304.17754) (xy 179.268485 -304.211632)
			(xy 179.227982 -304.239588) (xy 179.18352 -304.260686) (xy 179.136249 -304.274378) (xy 179.087394 -304.28031)
			(xy 179.038219 -304.278329) (xy 178.99 -304.268485) (xy 178.943984 -304.251033) (xy 178.901363 -304.226426)
			(xy 178.863242 -304.195301) (xy 178.830607 -304.158464) (xy 178.804304 -304.116868) (xy 178.785013 -304.071592)
			(xy 178.773236 -304.023808) (xy 178.769276 -303.974754) (xy 178.430174 -303.974754) (xy 178.429679 -303.999361)
			(xy 178.421784 -304.047938) (xy 178.4062 -304.094619) (xy 178.383329 -304.138196) (xy 178.353764 -304.17754)
			(xy 178.318271 -304.211632) (xy 178.277768 -304.239588) (xy 178.233306 -304.260686) (xy 178.186035 -304.274378)
			(xy 178.13718 -304.28031) (xy 178.088005 -304.278329) (xy 178.039786 -304.268485) (xy 177.99377 -304.251033)
			(xy 177.951149 -304.226426) (xy 177.913028 -304.195301) (xy 177.880393 -304.158464) (xy 177.85409 -304.116868)
			(xy 177.834799 -304.071592) (xy 177.823022 -304.023808) (xy 177.819062 -303.974754) (xy 177.480214 -303.974754)
			(xy 177.479719 -303.999361) (xy 177.471824 -304.047938) (xy 177.45624 -304.094619) (xy 177.433369 -304.138196)
			(xy 177.403804 -304.17754) (xy 177.368311 -304.211632) (xy 177.327808 -304.239588) (xy 177.283346 -304.260686)
			(xy 177.236075 -304.274378) (xy 177.18722 -304.28031) (xy 177.138045 -304.278329) (xy 177.089826 -304.268485)
			(xy 177.04381 -304.251033) (xy 177.001189 -304.226426) (xy 176.963068 -304.195301) (xy 176.930433 -304.158464)
			(xy 176.90413 -304.116868) (xy 176.884839 -304.071592) (xy 176.873062 -304.023808) (xy 176.869102 -303.974754)
			(xy 176.530254 -303.974754) (xy 176.529759 -303.999361) (xy 176.521864 -304.047938) (xy 176.50628 -304.094619)
			(xy 176.483409 -304.138196) (xy 176.453844 -304.17754) (xy 176.418351 -304.211632) (xy 176.377848 -304.239588)
			(xy 176.333386 -304.260686) (xy 176.286115 -304.274378) (xy 176.23726 -304.28031) (xy 176.188085 -304.278329)
			(xy 176.139866 -304.268485) (xy 176.09385 -304.251033) (xy 176.051229 -304.226426) (xy 176.013108 -304.195301)
			(xy 175.980473 -304.158464) (xy 175.95417 -304.116868) (xy 175.934879 -304.071592) (xy 175.923102 -304.023808)
			(xy 175.919142 -303.974754) (xy 174.630334 -303.974754) (xy 174.629839 -303.999361) (xy 174.621944 -304.047938)
			(xy 174.60636 -304.094619) (xy 174.583489 -304.138196) (xy 174.553924 -304.17754) (xy 174.518431 -304.211632)
			(xy 174.477928 -304.239588) (xy 174.433466 -304.260686) (xy 174.386195 -304.274378) (xy 174.33734 -304.28031)
			(xy 174.288165 -304.278329) (xy 174.239946 -304.268485) (xy 174.19393 -304.251033) (xy 174.151309 -304.226426)
			(xy 174.113188 -304.195301) (xy 174.080553 -304.158464) (xy 174.05425 -304.116868) (xy 174.034959 -304.071592)
			(xy 174.023182 -304.023808) (xy 174.019222 -303.974754) (xy 173.680374 -303.974754) (xy 173.679879 -303.999361)
			(xy 173.671984 -304.047938) (xy 173.6564 -304.094619) (xy 173.633529 -304.138196) (xy 173.603964 -304.17754)
			(xy 173.568471 -304.211632) (xy 173.527968 -304.239588) (xy 173.483506 -304.260686) (xy 173.436235 -304.274378)
			(xy 173.38738 -304.28031) (xy 173.338205 -304.278329) (xy 173.289986 -304.268485) (xy 173.24397 -304.251033)
			(xy 173.201349 -304.226426) (xy 173.163228 -304.195301) (xy 173.130593 -304.158464) (xy 173.10429 -304.116868)
			(xy 173.084999 -304.071592) (xy 173.073222 -304.023808) (xy 173.069262 -303.974754) (xy 172.73016 -303.974754)
			(xy 172.729665 -303.999361) (xy 172.72177 -304.047938) (xy 172.706186 -304.094619) (xy 172.683315 -304.138196)
			(xy 172.65375 -304.17754) (xy 172.618257 -304.211632) (xy 172.577754 -304.239588) (xy 172.533292 -304.260686)
			(xy 172.486021 -304.274378) (xy 172.437166 -304.28031) (xy 172.387991 -304.278329) (xy 172.339772 -304.268485)
			(xy 172.293756 -304.251033) (xy 172.251135 -304.226426) (xy 172.213014 -304.195301) (xy 172.180379 -304.158464)
			(xy 172.154076 -304.116868) (xy 172.134785 -304.071592) (xy 172.123008 -304.023808) (xy 172.119048 -303.974754)
			(xy 171.7802 -303.974754) (xy 171.779705 -303.999361) (xy 171.77181 -304.047938) (xy 171.756226 -304.094619)
			(xy 171.733355 -304.138196) (xy 171.70379 -304.17754) (xy 171.668297 -304.211632) (xy 171.627794 -304.239588)
			(xy 171.583332 -304.260686) (xy 171.536061 -304.274378) (xy 171.487206 -304.28031) (xy 171.438031 -304.278329)
			(xy 171.389812 -304.268485) (xy 171.343796 -304.251033) (xy 171.301175 -304.226426) (xy 171.263054 -304.195301)
			(xy 171.230419 -304.158464) (xy 171.204116 -304.116868) (xy 171.184825 -304.071592) (xy 171.173048 -304.023808)
			(xy 171.169088 -303.974754) (xy 170.83024 -303.974754) (xy 170.829745 -303.999361) (xy 170.82185 -304.047938)
			(xy 170.806266 -304.094619) (xy 170.783395 -304.138196) (xy 170.75383 -304.17754) (xy 170.718337 -304.211632)
			(xy 170.677834 -304.239588) (xy 170.633372 -304.260686) (xy 170.586101 -304.274378) (xy 170.537246 -304.28031)
			(xy 170.488071 -304.278329) (xy 170.439852 -304.268485) (xy 170.393836 -304.251033) (xy 170.351215 -304.226426)
			(xy 170.313094 -304.195301) (xy 170.280459 -304.158464) (xy 170.254156 -304.116868) (xy 170.234865 -304.071592)
			(xy 170.223088 -304.023808) (xy 170.219128 -303.974754) (xy 169.88028 -303.974754) (xy 169.879785 -303.999361)
			(xy 169.87189 -304.047938) (xy 169.856306 -304.094619) (xy 169.833435 -304.138196) (xy 169.80387 -304.17754)
			(xy 169.768377 -304.211632) (xy 169.727874 -304.239588) (xy 169.683412 -304.260686) (xy 169.636141 -304.274378)
			(xy 169.587286 -304.28031) (xy 169.538111 -304.278329) (xy 169.489892 -304.268485) (xy 169.443876 -304.251033)
			(xy 169.401255 -304.226426) (xy 169.363134 -304.195301) (xy 169.330499 -304.158464) (xy 169.304196 -304.116868)
			(xy 169.284905 -304.071592) (xy 169.273128 -304.023808) (xy 169.269168 -303.974754) (xy 168.93032 -303.974754)
			(xy 168.929825 -303.999361) (xy 168.92193 -304.047938) (xy 168.906346 -304.094619) (xy 168.883475 -304.138196)
			(xy 168.85391 -304.17754) (xy 168.818417 -304.211632) (xy 168.777914 -304.239588) (xy 168.733452 -304.260686)
			(xy 168.686181 -304.274378) (xy 168.637326 -304.28031) (xy 168.588151 -304.278329) (xy 168.539932 -304.268485)
			(xy 168.493916 -304.251033) (xy 168.451295 -304.226426) (xy 168.413174 -304.195301) (xy 168.380539 -304.158464)
			(xy 168.354236 -304.116868) (xy 168.334945 -304.071592) (xy 168.323168 -304.023808) (xy 168.319208 -303.974754)
			(xy 167.98036 -303.974754) (xy 167.979865 -303.999361) (xy 167.97197 -304.047938) (xy 167.956386 -304.094619)
			(xy 167.933515 -304.138196) (xy 167.90395 -304.17754) (xy 167.868457 -304.211632) (xy 167.827954 -304.239588)
			(xy 167.783492 -304.260686) (xy 167.736221 -304.274378) (xy 167.687366 -304.28031) (xy 167.638191 -304.278329)
			(xy 167.589972 -304.268485) (xy 167.543956 -304.251033) (xy 167.501335 -304.226426) (xy 167.463214 -304.195301)
			(xy 167.430579 -304.158464) (xy 167.404276 -304.116868) (xy 167.384985 -304.071592) (xy 167.373208 -304.023808)
			(xy 167.369248 -303.974754) (xy 167.0304 -303.974754) (xy 167.029905 -303.999361) (xy 167.02201 -304.047938)
			(xy 167.006426 -304.094619) (xy 166.983555 -304.138196) (xy 166.95399 -304.17754) (xy 166.918497 -304.211632)
			(xy 166.877994 -304.239588) (xy 166.833532 -304.260686) (xy 166.786261 -304.274378) (xy 166.737406 -304.28031)
			(xy 166.688231 -304.278329) (xy 166.640012 -304.268485) (xy 166.593996 -304.251033) (xy 166.551375 -304.226426)
			(xy 166.513254 -304.195301) (xy 166.480619 -304.158464) (xy 166.454316 -304.116868) (xy 166.435025 -304.071592)
			(xy 166.423248 -304.023808) (xy 166.419288 -303.974754) (xy 166.11727 -303.974754) (xy 166.11727 -304.449734)
			(xy 189.69407 -304.449734) (xy 189.69803 -304.40068) (xy 189.709807 -304.352896) (xy 189.729098 -304.30762)
			(xy 189.755401 -304.266024) (xy 189.788036 -304.229187) (xy 189.826157 -304.198062) (xy 189.868778 -304.173455)
			(xy 189.914794 -304.156003) (xy 189.963013 -304.146159) (xy 190.012188 -304.144178) (xy 190.061043 -304.15011)
			(xy 190.108314 -304.163802) (xy 190.152776 -304.1849) (xy 190.193279 -304.212856) (xy 190.228772 -304.246948)
			(xy 190.258337 -304.286292) (xy 190.281208 -304.329869) (xy 190.296792 -304.37655) (xy 190.304687 -304.425127)
			(xy 190.305182 -304.449734) (xy 190.304687 -304.474341) (xy 190.304508 -304.475442) (xy 190.62344 -304.475442)
			(xy 190.62344 -304.424026) (xy 190.631483 -304.373244) (xy 190.647371 -304.324345) (xy 190.670714 -304.278533)
			(xy 190.700935 -304.236937) (xy 190.737291 -304.200581) (xy 190.778887 -304.17036) (xy 190.824699 -304.147017)
			(xy 190.873598 -304.131129) (xy 190.92438 -304.123086) (xy 190.975796 -304.123086) (xy 191.026578 -304.131129)
			(xy 191.075477 -304.147017) (xy 191.121289 -304.17036) (xy 191.162885 -304.200581) (xy 191.199241 -304.236937)
			(xy 191.229462 -304.278533) (xy 191.252805 -304.324345) (xy 191.268693 -304.373244) (xy 191.276736 -304.424026)
			(xy 191.27724 -304.449734) (xy 191.276736 -304.475442) (xy 191.5734 -304.475442) (xy 191.5734 -304.424026)
			(xy 191.581443 -304.373244) (xy 191.597331 -304.324345) (xy 191.620674 -304.278533) (xy 191.650895 -304.236937)
			(xy 191.687251 -304.200581) (xy 191.728847 -304.17036) (xy 191.774659 -304.147017) (xy 191.823558 -304.131129)
			(xy 191.87434 -304.123086) (xy 191.925756 -304.123086) (xy 191.976538 -304.131129) (xy 192.025437 -304.147017)
			(xy 192.071249 -304.17036) (xy 192.112845 -304.200581) (xy 192.149201 -304.236937) (xy 192.179422 -304.278533)
			(xy 192.202765 -304.324345) (xy 192.218653 -304.373244) (xy 192.226696 -304.424026) (xy 192.2272 -304.449734)
			(xy 192.544204 -304.449734) (xy 192.548164 -304.40068) (xy 192.559941 -304.352896) (xy 192.579232 -304.30762)
			(xy 192.605535 -304.266024) (xy 192.63817 -304.229187) (xy 192.676291 -304.198062) (xy 192.718912 -304.173455)
			(xy 192.764928 -304.156003) (xy 192.813147 -304.146159) (xy 192.862322 -304.144178) (xy 192.911177 -304.15011)
			(xy 192.958448 -304.163802) (xy 193.00291 -304.1849) (xy 193.043413 -304.212856) (xy 193.078906 -304.246948)
			(xy 193.108471 -304.286292) (xy 193.131342 -304.329869) (xy 193.146926 -304.37655) (xy 193.154821 -304.425127)
			(xy 193.155316 -304.449734) (xy 193.494164 -304.449734) (xy 193.498124 -304.40068) (xy 193.509901 -304.352896)
			(xy 193.529192 -304.30762) (xy 193.555495 -304.266024) (xy 193.58813 -304.229187) (xy 193.626251 -304.198062)
			(xy 193.668872 -304.173455) (xy 193.714888 -304.156003) (xy 193.763107 -304.146159) (xy 193.812282 -304.144178)
			(xy 193.861137 -304.15011) (xy 193.908408 -304.163802) (xy 193.95287 -304.1849) (xy 193.993373 -304.212856)
			(xy 194.028866 -304.246948) (xy 194.058431 -304.286292) (xy 194.081302 -304.329869) (xy 194.096886 -304.37655)
			(xy 194.104781 -304.425127) (xy 194.105276 -304.449734) (xy 194.444124 -304.449734) (xy 194.448084 -304.40068)
			(xy 194.459861 -304.352896) (xy 194.479152 -304.30762) (xy 194.505455 -304.266024) (xy 194.53809 -304.229187)
			(xy 194.576211 -304.198062) (xy 194.618832 -304.173455) (xy 194.664848 -304.156003) (xy 194.713067 -304.146159)
			(xy 194.762242 -304.144178) (xy 194.811097 -304.15011) (xy 194.858368 -304.163802) (xy 194.90283 -304.1849)
			(xy 194.943333 -304.212856) (xy 194.978826 -304.246948) (xy 195.008391 -304.286292) (xy 195.031262 -304.329869)
			(xy 195.046846 -304.37655) (xy 195.054741 -304.425127) (xy 195.055069 -304.441416) (xy 195.394215 -304.441416)
			(xy 195.399582 -304.392073) (xy 195.412861 -304.344247) (xy 195.433702 -304.2992) (xy 195.461556 -304.258118)
			(xy 195.495689 -304.222083) (xy 195.535202 -304.192044) (xy 195.579054 -304.168794) (xy 195.62609 -304.152944)
			(xy 195.675071 -304.144913) (xy 195.699888 -304.144426) (xy 195.714071 -304.144604) (xy 195.742311 -304.147275)
			(xy 195.756276 -304.14976) (xy 195.768722 -304.152046) (xy 195.792344 -304.14468) (xy 195.869814 -304.06721)
			(xy 195.87718 -304.043588) (xy 195.874894 -304.031142) (xy 195.872413 -304.017177) (xy 195.869744 -303.988937)
			(xy 195.86956 -303.974754) (xy 195.870082 -303.949499) (xy 195.878395 -303.899677) (xy 195.894796 -303.851903)
			(xy 195.918837 -303.80748) (xy 195.949861 -303.76762) (xy 195.987023 -303.73341) (xy 196.029309 -303.705784)
			(xy 196.075565 -303.685494) (xy 196.12453 -303.673094) (xy 196.174868 -303.668923) (xy 196.225206 -303.673094)
			(xy 196.274171 -303.685494) (xy 196.320427 -303.705784) (xy 196.362713 -303.73341) (xy 196.399875 -303.76762)
			(xy 196.430899 -303.80748) (xy 196.45494 -303.851903) (xy 196.471341 -303.899677) (xy 196.479654 -303.949499)
			(xy 196.480176 -303.974754) (xy 196.479993 -303.988937) (xy 196.477325 -304.017177) (xy 196.474842 -304.031142)
			(xy 196.472556 -304.043588) (xy 196.479922 -304.06721) (xy 196.557392 -304.14468) (xy 196.581014 -304.152046)
			(xy 196.59346 -304.14976) (xy 196.607425 -304.14728) (xy 196.635665 -304.14461) (xy 196.649848 -304.144426)
			(xy 196.664095 -304.144588) (xy 196.692463 -304.147261) (xy 196.70649 -304.14976) (xy 196.718682 -304.152046)
			(xy 196.742812 -304.14468) (xy 196.820028 -304.067464) (xy 196.827394 -304.043588) (xy 196.825108 -304.031142)
			(xy 196.822628 -304.017177) (xy 196.819958 -303.988937) (xy 196.819774 -303.974754) (xy 196.820296 -303.949499)
			(xy 196.828609 -303.899677) (xy 196.84501 -303.851903) (xy 196.869051 -303.80748) (xy 196.900075 -303.76762)
			(xy 196.937237 -303.73341) (xy 196.979523 -303.705784) (xy 197.025779 -303.685494) (xy 197.074744 -303.673094)
			(xy 197.125082 -303.668923) (xy 197.17542 -303.673094) (xy 197.224385 -303.685494) (xy 197.270641 -303.705784)
			(xy 197.299387 -303.724564) (xy 201.429364 -303.724564) (xy 201.433435 -303.668942) (xy 201.445561 -303.614505)
			(xy 201.465484 -303.562414) (xy 201.49278 -303.513779) (xy 201.526866 -303.469636) (xy 201.567015 -303.430927)
			(xy 201.612373 -303.398476) (xy 201.661973 -303.372975) (xy 201.714757 -303.354968) (xy 201.7696 -303.344838)
			(xy 201.825334 -303.342801) (xy 201.880771 -303.348901) (xy 201.934728 -303.363007) (xy 201.986057 -303.384819)
			(xy 202.033663 -303.413873) (xy 202.076531 -303.449548) (xy 202.113748 -303.491085) (xy 202.144521 -303.537598)
			(xy 202.168193 -303.588095) (xy 202.184261 -303.641502) (xy 202.192381 -303.696678) (xy 202.19289 -303.724564)
			(xy 202.192381 -303.75245) (xy 202.184261 -303.807626) (xy 202.168193 -303.861033) (xy 202.144521 -303.91153)
			(xy 202.113748 -303.958043) (xy 202.076531 -303.99958) (xy 202.033663 -304.035255) (xy 201.986057 -304.064309)
			(xy 201.934728 -304.086121) (xy 201.880771 -304.100227) (xy 201.825334 -304.106327) (xy 201.7696 -304.10429)
			(xy 201.714757 -304.09416) (xy 201.661973 -304.076153) (xy 201.612373 -304.050652) (xy 201.567015 -304.018201)
			(xy 201.526866 -303.979492) (xy 201.49278 -303.935349) (xy 201.465484 -303.886714) (xy 201.445561 -303.834623)
			(xy 201.433435 -303.780186) (xy 201.429364 -303.724564) (xy 197.299387 -303.724564) (xy 197.312927 -303.73341)
			(xy 197.350089 -303.76762) (xy 197.381113 -303.80748) (xy 197.405154 -303.851903) (xy 197.421555 -303.899677)
			(xy 197.429868 -303.949499) (xy 197.43039 -303.974754) (xy 197.430313 -303.984625) (xy 197.429045 -304.004326)
			(xy 197.42785 -304.014124) (xy 197.426326 -304.026062) (xy 197.4342 -304.048668) (xy 197.510654 -304.122328)
			(xy 197.533514 -304.129186) (xy 197.545452 -304.127408) (xy 197.559002 -304.125256) (xy 197.586343 -304.122965)
			(xy 197.600062 -304.122836) (xy 197.625755 -304.123238) (xy 197.676509 -304.131271) (xy 197.725382 -304.147145)
			(xy 197.771169 -304.170468) (xy 197.812745 -304.200667) (xy 197.849084 -304.236998) (xy 197.879293 -304.278567)
			(xy 197.902627 -304.324349) (xy 197.918511 -304.373218) (xy 197.926556 -304.42397) (xy 197.926561 -304.475356)
			(xy 197.926547 -304.475442) (xy 198.223374 -304.475442) (xy 198.223374 -304.424026) (xy 198.231417 -304.373244)
			(xy 198.247305 -304.324345) (xy 198.270648 -304.278533) (xy 198.300869 -304.236937) (xy 198.337225 -304.200581)
			(xy 198.378821 -304.17036) (xy 198.424633 -304.147017) (xy 198.473532 -304.131129) (xy 198.524314 -304.123086)
			(xy 198.57573 -304.123086) (xy 198.626512 -304.131129) (xy 198.675411 -304.147017) (xy 198.721223 -304.17036)
			(xy 198.762819 -304.200581) (xy 198.799175 -304.236937) (xy 198.829396 -304.278533) (xy 198.852739 -304.324345)
			(xy 198.868627 -304.373244) (xy 198.87667 -304.424026) (xy 198.877174 -304.449734) (xy 199.194432 -304.449734)
			(xy 199.198392 -304.40068) (xy 199.210169 -304.352896) (xy 199.22946 -304.30762) (xy 199.255763 -304.266024)
			(xy 199.288398 -304.229187) (xy 199.326519 -304.198062) (xy 199.36914 -304.173455) (xy 199.415156 -304.156003)
			(xy 199.463375 -304.146159) (xy 199.51255 -304.144178) (xy 199.561405 -304.15011) (xy 199.608676 -304.163802)
			(xy 199.653138 -304.1849) (xy 199.693641 -304.212856) (xy 199.729134 -304.246948) (xy 199.758699 -304.286292)
			(xy 199.78157 -304.329869) (xy 199.797154 -304.37655) (xy 199.805049 -304.425127) (xy 199.805544 -304.449734)
			(xy 199.805049 -304.474341) (xy 199.797154 -304.522918) (xy 199.78157 -304.569599) (xy 199.758699 -304.613176)
			(xy 199.729134 -304.65252) (xy 199.693641 -304.686612) (xy 199.653138 -304.714568) (xy 199.608676 -304.735666)
			(xy 199.561405 -304.749358) (xy 199.51255 -304.75529) (xy 199.463375 -304.753309) (xy 199.415156 -304.743465)
			(xy 199.36914 -304.726013) (xy 199.326519 -304.701406) (xy 199.288398 -304.670281) (xy 199.255763 -304.633444)
			(xy 199.22946 -304.591848) (xy 199.210169 -304.546572) (xy 199.198392 -304.498788) (xy 199.194432 -304.449734)
			(xy 198.877174 -304.449734) (xy 198.87667 -304.475442) (xy 198.868627 -304.526224) (xy 198.852739 -304.575123)
			(xy 198.829396 -304.620935) (xy 198.799175 -304.662531) (xy 198.762819 -304.698887) (xy 198.721223 -304.729108)
			(xy 198.675411 -304.752451) (xy 198.626512 -304.768339) (xy 198.57573 -304.776382) (xy 198.524314 -304.776382)
			(xy 198.473532 -304.768339) (xy 198.424633 -304.752451) (xy 198.378821 -304.729108) (xy 198.337225 -304.698887)
			(xy 198.300869 -304.662531) (xy 198.270648 -304.620935) (xy 198.247305 -304.575123) (xy 198.231417 -304.526224)
			(xy 198.223374 -304.475442) (xy 197.926547 -304.475442) (xy 197.918529 -304.52611) (xy 197.902655 -304.574983)
			(xy 197.879331 -304.620771) (xy 197.849132 -304.662346) (xy 197.812801 -304.698685) (xy 197.771232 -304.728894)
			(xy 197.72545 -304.752227) (xy 197.67658 -304.768112) (xy 197.625828 -304.776156) (xy 197.574442 -304.776161)
			(xy 197.523688 -304.768128) (xy 197.474816 -304.752254) (xy 197.429028 -304.728931) (xy 197.387453 -304.698731)
			(xy 197.351114 -304.6624) (xy 197.320906 -304.620831) (xy 197.297572 -304.575048) (xy 197.281688 -304.526179)
			(xy 197.273644 -304.475427) (xy 197.273164 -304.449734) (xy 197.273303 -304.436016) (xy 197.275596 -304.408675)
			(xy 197.277736 -304.395124) (xy 197.279514 -304.383186) (xy 197.272656 -304.360326) (xy 197.198996 -304.283872)
			(xy 197.17639 -304.275998) (xy 197.164452 -304.277522) (xy 197.154653 -304.27871) (xy 197.134953 -304.279981)
			(xy 197.125082 -304.280062) (xy 197.110835 -304.279896) (xy 197.082467 -304.277226) (xy 197.06844 -304.274728)
			(xy 197.056248 -304.272442) (xy 197.032118 -304.279808) (xy 196.954902 -304.357024) (xy 196.947536 -304.3809)
			(xy 196.949822 -304.393346) (xy 196.952301 -304.407311) (xy 196.954971 -304.435551) (xy 196.955156 -304.449734)
			(xy 196.954634 -304.474989) (xy 196.946321 -304.524811) (xy 196.92992 -304.572585) (xy 196.905879 -304.617008)
			(xy 196.874855 -304.656868) (xy 196.837693 -304.691078) (xy 196.795407 -304.718704) (xy 196.749151 -304.738994)
			(xy 196.700186 -304.751394) (xy 196.649848 -304.755565) (xy 196.59951 -304.751394) (xy 196.550545 -304.738994)
			(xy 196.504289 -304.718704) (xy 196.462003 -304.691078) (xy 196.424841 -304.656868) (xy 196.393817 -304.617008)
			(xy 196.369776 -304.572585) (xy 196.353375 -304.524811) (xy 196.345062 -304.474989) (xy 196.34454 -304.449734)
			(xy 196.344721 -304.435551) (xy 196.34739 -304.407311) (xy 196.349874 -304.393346) (xy 196.35216 -304.3809)
			(xy 196.344794 -304.357278) (xy 196.267324 -304.279808) (xy 196.243702 -304.272442) (xy 196.231256 -304.274728)
			(xy 196.217291 -304.277207) (xy 196.189051 -304.279877) (xy 196.174868 -304.280062) (xy 196.160685 -304.279891)
			(xy 196.132445 -304.277215) (xy 196.11848 -304.274728) (xy 196.106034 -304.272442) (xy 196.082412 -304.279808)
			(xy 196.004942 -304.357278) (xy 195.997576 -304.3809) (xy 195.999862 -304.393346) (xy 196.00234 -304.407312)
			(xy 196.005011 -304.435551) (xy 196.005196 -304.449734) (xy 196.004686 -304.474551) (xy 195.99665 -304.523531)
			(xy 195.980797 -304.570566) (xy 195.957544 -304.614416) (xy 195.927503 -304.653928) (xy 195.891465 -304.688058)
			(xy 195.850381 -304.715909) (xy 195.805332 -304.736747) (xy 195.757506 -304.750022) (xy 195.708162 -304.755385)
			(xy 195.6586 -304.752695) (xy 195.610127 -304.742023) (xy 195.564018 -304.723649) (xy 195.521489 -304.698058)
			(xy 195.483661 -304.665923) (xy 195.45153 -304.628093) (xy 195.425941 -304.585562) (xy 195.407571 -304.539452)
			(xy 195.396902 -304.490978) (xy 195.394215 -304.441416) (xy 195.055069 -304.441416) (xy 195.055236 -304.449734)
			(xy 195.054741 -304.474341) (xy 195.046846 -304.522918) (xy 195.031262 -304.569599) (xy 195.008391 -304.613176)
			(xy 194.978826 -304.65252) (xy 194.943333 -304.686612) (xy 194.90283 -304.714568) (xy 194.858368 -304.735666)
			(xy 194.811097 -304.749358) (xy 194.762242 -304.75529) (xy 194.713067 -304.753309) (xy 194.664848 -304.743465)
			(xy 194.618832 -304.726013) (xy 194.576211 -304.701406) (xy 194.53809 -304.670281) (xy 194.505455 -304.633444)
			(xy 194.479152 -304.591848) (xy 194.459861 -304.546572) (xy 194.448084 -304.498788) (xy 194.444124 -304.449734)
			(xy 194.105276 -304.449734) (xy 194.104781 -304.474341) (xy 194.096886 -304.522918) (xy 194.081302 -304.569599)
			(xy 194.058431 -304.613176) (xy 194.028866 -304.65252) (xy 193.993373 -304.686612) (xy 193.95287 -304.714568)
			(xy 193.908408 -304.735666) (xy 193.861137 -304.749358) (xy 193.812282 -304.75529) (xy 193.763107 -304.753309)
			(xy 193.714888 -304.743465) (xy 193.668872 -304.726013) (xy 193.626251 -304.701406) (xy 193.58813 -304.670281)
			(xy 193.555495 -304.633444) (xy 193.529192 -304.591848) (xy 193.509901 -304.546572) (xy 193.498124 -304.498788)
			(xy 193.494164 -304.449734) (xy 193.155316 -304.449734) (xy 193.154821 -304.474341) (xy 193.146926 -304.522918)
			(xy 193.131342 -304.569599) (xy 193.108471 -304.613176) (xy 193.078906 -304.65252) (xy 193.043413 -304.686612)
			(xy 193.00291 -304.714568) (xy 192.958448 -304.735666) (xy 192.911177 -304.749358) (xy 192.862322 -304.75529)
			(xy 192.813147 -304.753309) (xy 192.764928 -304.743465) (xy 192.718912 -304.726013) (xy 192.676291 -304.701406)
			(xy 192.63817 -304.670281) (xy 192.605535 -304.633444) (xy 192.579232 -304.591848) (xy 192.559941 -304.546572)
			(xy 192.548164 -304.498788) (xy 192.544204 -304.449734) (xy 192.2272 -304.449734) (xy 192.226696 -304.475442)
			(xy 192.218653 -304.526224) (xy 192.202765 -304.575123) (xy 192.179422 -304.620935) (xy 192.149201 -304.662531)
			(xy 192.112845 -304.698887) (xy 192.071249 -304.729108) (xy 192.025437 -304.752451) (xy 191.976538 -304.768339)
			(xy 191.925756 -304.776382) (xy 191.87434 -304.776382) (xy 191.823558 -304.768339) (xy 191.774659 -304.752451)
			(xy 191.728847 -304.729108) (xy 191.687251 -304.698887) (xy 191.650895 -304.662531) (xy 191.620674 -304.620935)
			(xy 191.597331 -304.575123) (xy 191.581443 -304.526224) (xy 191.5734 -304.475442) (xy 191.276736 -304.475442)
			(xy 191.268693 -304.526224) (xy 191.252805 -304.575123) (xy 191.229462 -304.620935) (xy 191.199241 -304.662531)
			(xy 191.162885 -304.698887) (xy 191.121289 -304.729108) (xy 191.075477 -304.752451) (xy 191.026578 -304.768339)
			(xy 190.975796 -304.776382) (xy 190.92438 -304.776382) (xy 190.873598 -304.768339) (xy 190.824699 -304.752451)
			(xy 190.778887 -304.729108) (xy 190.737291 -304.698887) (xy 190.700935 -304.662531) (xy 190.670714 -304.620935)
			(xy 190.647371 -304.575123) (xy 190.631483 -304.526224) (xy 190.62344 -304.475442) (xy 190.304508 -304.475442)
			(xy 190.296792 -304.522918) (xy 190.281208 -304.569599) (xy 190.258337 -304.613176) (xy 190.228772 -304.65252)
			(xy 190.193279 -304.686612) (xy 190.152776 -304.714568) (xy 190.108314 -304.735666) (xy 190.061043 -304.749358)
			(xy 190.012188 -304.75529) (xy 189.963013 -304.753309) (xy 189.914794 -304.743465) (xy 189.868778 -304.726013)
			(xy 189.826157 -304.701406) (xy 189.788036 -304.670281) (xy 189.755401 -304.633444) (xy 189.729098 -304.591848)
			(xy 189.709807 -304.546572) (xy 189.69803 -304.498788) (xy 189.69407 -304.449734) (xy 166.11727 -304.449734)
			(xy 166.11727 -304.924714) (xy 166.419288 -304.924714) (xy 166.423248 -304.87566) (xy 166.435025 -304.827876)
			(xy 166.454316 -304.7826) (xy 166.480619 -304.741004) (xy 166.513254 -304.704167) (xy 166.551375 -304.673042)
			(xy 166.593996 -304.648435) (xy 166.640012 -304.630983) (xy 166.688231 -304.621139) (xy 166.737406 -304.619158)
			(xy 166.786261 -304.62509) (xy 166.833532 -304.638782) (xy 166.877994 -304.65988) (xy 166.918497 -304.687836)
			(xy 166.95399 -304.721928) (xy 166.983555 -304.761272) (xy 167.006426 -304.804849) (xy 167.02201 -304.85153)
			(xy 167.029905 -304.900107) (xy 167.0304 -304.924714) (xy 167.369248 -304.924714) (xy 167.373208 -304.87566)
			(xy 167.384985 -304.827876) (xy 167.404276 -304.7826) (xy 167.430579 -304.741004) (xy 167.463214 -304.704167)
			(xy 167.501335 -304.673042) (xy 167.543956 -304.648435) (xy 167.589972 -304.630983) (xy 167.638191 -304.621139)
			(xy 167.687366 -304.619158) (xy 167.736221 -304.62509) (xy 167.783492 -304.638782) (xy 167.827954 -304.65988)
			(xy 167.868457 -304.687836) (xy 167.90395 -304.721928) (xy 167.933515 -304.761272) (xy 167.956386 -304.804849)
			(xy 167.97197 -304.85153) (xy 167.979865 -304.900107) (xy 167.98036 -304.924714) (xy 168.319208 -304.924714)
			(xy 168.323168 -304.87566) (xy 168.334945 -304.827876) (xy 168.354236 -304.7826) (xy 168.380539 -304.741004)
			(xy 168.413174 -304.704167) (xy 168.451295 -304.673042) (xy 168.493916 -304.648435) (xy 168.539932 -304.630983)
			(xy 168.588151 -304.621139) (xy 168.637326 -304.619158) (xy 168.686181 -304.62509) (xy 168.733452 -304.638782)
			(xy 168.777914 -304.65988) (xy 168.818417 -304.687836) (xy 168.85391 -304.721928) (xy 168.883475 -304.761272)
			(xy 168.906346 -304.804849) (xy 168.92193 -304.85153) (xy 168.929825 -304.900107) (xy 168.93032 -304.924714)
			(xy 169.269168 -304.924714) (xy 169.273128 -304.87566) (xy 169.284905 -304.827876) (xy 169.304196 -304.7826)
			(xy 169.330499 -304.741004) (xy 169.363134 -304.704167) (xy 169.401255 -304.673042) (xy 169.443876 -304.648435)
			(xy 169.489892 -304.630983) (xy 169.538111 -304.621139) (xy 169.587286 -304.619158) (xy 169.636141 -304.62509)
			(xy 169.683412 -304.638782) (xy 169.727874 -304.65988) (xy 169.768377 -304.687836) (xy 169.80387 -304.721928)
			(xy 169.833435 -304.761272) (xy 169.856306 -304.804849) (xy 169.87189 -304.85153) (xy 169.879785 -304.900107)
			(xy 169.88028 -304.924714) (xy 170.219128 -304.924714) (xy 170.223088 -304.87566) (xy 170.234865 -304.827876)
			(xy 170.254156 -304.7826) (xy 170.280459 -304.741004) (xy 170.313094 -304.704167) (xy 170.351215 -304.673042)
			(xy 170.393836 -304.648435) (xy 170.439852 -304.630983) (xy 170.488071 -304.621139) (xy 170.537246 -304.619158)
			(xy 170.586101 -304.62509) (xy 170.633372 -304.638782) (xy 170.677834 -304.65988) (xy 170.718337 -304.687836)
			(xy 170.75383 -304.721928) (xy 170.783395 -304.761272) (xy 170.806266 -304.804849) (xy 170.82185 -304.85153)
			(xy 170.829745 -304.900107) (xy 170.83024 -304.924714) (xy 171.169088 -304.924714) (xy 171.173048 -304.87566)
			(xy 171.184825 -304.827876) (xy 171.204116 -304.7826) (xy 171.230419 -304.741004) (xy 171.263054 -304.704167)
			(xy 171.301175 -304.673042) (xy 171.343796 -304.648435) (xy 171.389812 -304.630983) (xy 171.438031 -304.621139)
			(xy 171.487206 -304.619158) (xy 171.536061 -304.62509) (xy 171.583332 -304.638782) (xy 171.627794 -304.65988)
			(xy 171.668297 -304.687836) (xy 171.70379 -304.721928) (xy 171.733355 -304.761272) (xy 171.756226 -304.804849)
			(xy 171.77181 -304.85153) (xy 171.779705 -304.900107) (xy 171.7802 -304.924714) (xy 172.119048 -304.924714)
			(xy 172.123008 -304.87566) (xy 172.134785 -304.827876) (xy 172.154076 -304.7826) (xy 172.180379 -304.741004)
			(xy 172.213014 -304.704167) (xy 172.251135 -304.673042) (xy 172.293756 -304.648435) (xy 172.339772 -304.630983)
			(xy 172.387991 -304.621139) (xy 172.437166 -304.619158) (xy 172.486021 -304.62509) (xy 172.533292 -304.638782)
			(xy 172.577754 -304.65988) (xy 172.618257 -304.687836) (xy 172.65375 -304.721928) (xy 172.683315 -304.761272)
			(xy 172.706186 -304.804849) (xy 172.72177 -304.85153) (xy 172.729665 -304.900107) (xy 172.73016 -304.924714)
			(xy 173.069262 -304.924714) (xy 173.073222 -304.87566) (xy 173.084999 -304.827876) (xy 173.10429 -304.7826)
			(xy 173.130593 -304.741004) (xy 173.163228 -304.704167) (xy 173.201349 -304.673042) (xy 173.24397 -304.648435)
			(xy 173.289986 -304.630983) (xy 173.338205 -304.621139) (xy 173.38738 -304.619158) (xy 173.436235 -304.62509)
			(xy 173.483506 -304.638782) (xy 173.527968 -304.65988) (xy 173.568471 -304.687836) (xy 173.603964 -304.721928)
			(xy 173.633529 -304.761272) (xy 173.6564 -304.804849) (xy 173.671984 -304.85153) (xy 173.679879 -304.900107)
			(xy 173.680374 -304.924714) (xy 174.019222 -304.924714) (xy 174.023182 -304.87566) (xy 174.034959 -304.827876)
			(xy 174.05425 -304.7826) (xy 174.080553 -304.741004) (xy 174.113188 -304.704167) (xy 174.151309 -304.673042)
			(xy 174.19393 -304.648435) (xy 174.239946 -304.630983) (xy 174.288165 -304.621139) (xy 174.33734 -304.619158)
			(xy 174.386195 -304.62509) (xy 174.433466 -304.638782) (xy 174.477928 -304.65988) (xy 174.518431 -304.687836)
			(xy 174.553924 -304.721928) (xy 174.583489 -304.761272) (xy 174.60636 -304.804849) (xy 174.621944 -304.85153)
			(xy 174.629839 -304.900107) (xy 174.630334 -304.924714) (xy 175.919142 -304.924714) (xy 175.923102 -304.87566)
			(xy 175.934879 -304.827876) (xy 175.95417 -304.7826) (xy 175.980473 -304.741004) (xy 176.013108 -304.704167)
			(xy 176.051229 -304.673042) (xy 176.09385 -304.648435) (xy 176.139866 -304.630983) (xy 176.188085 -304.621139)
			(xy 176.23726 -304.619158) (xy 176.286115 -304.62509) (xy 176.333386 -304.638782) (xy 176.377848 -304.65988)
			(xy 176.418351 -304.687836) (xy 176.453844 -304.721928) (xy 176.483409 -304.761272) (xy 176.50628 -304.804849)
			(xy 176.521864 -304.85153) (xy 176.529759 -304.900107) (xy 176.530254 -304.924714) (xy 176.869102 -304.924714)
			(xy 176.873062 -304.87566) (xy 176.884839 -304.827876) (xy 176.90413 -304.7826) (xy 176.930433 -304.741004)
			(xy 176.963068 -304.704167) (xy 177.001189 -304.673042) (xy 177.04381 -304.648435) (xy 177.089826 -304.630983)
			(xy 177.138045 -304.621139) (xy 177.18722 -304.619158) (xy 177.236075 -304.62509) (xy 177.283346 -304.638782)
			(xy 177.327808 -304.65988) (xy 177.368311 -304.687836) (xy 177.403804 -304.721928) (xy 177.433369 -304.761272)
			(xy 177.45624 -304.804849) (xy 177.471824 -304.85153) (xy 177.479719 -304.900107) (xy 177.480214 -304.924714)
			(xy 177.819062 -304.924714) (xy 177.823022 -304.87566) (xy 177.834799 -304.827876) (xy 177.85409 -304.7826)
			(xy 177.880393 -304.741004) (xy 177.913028 -304.704167) (xy 177.951149 -304.673042) (xy 177.99377 -304.648435)
			(xy 178.039786 -304.630983) (xy 178.088005 -304.621139) (xy 178.13718 -304.619158) (xy 178.186035 -304.62509)
			(xy 178.233306 -304.638782) (xy 178.277768 -304.65988) (xy 178.318271 -304.687836) (xy 178.353764 -304.721928)
			(xy 178.383329 -304.761272) (xy 178.4062 -304.804849) (xy 178.421784 -304.85153) (xy 178.429679 -304.900107)
			(xy 178.430174 -304.924714) (xy 178.769276 -304.924714) (xy 178.773236 -304.87566) (xy 178.785013 -304.827876)
			(xy 178.804304 -304.7826) (xy 178.830607 -304.741004) (xy 178.863242 -304.704167) (xy 178.901363 -304.673042)
			(xy 178.943984 -304.648435) (xy 178.99 -304.630983) (xy 179.038219 -304.621139) (xy 179.087394 -304.619158)
			(xy 179.136249 -304.62509) (xy 179.18352 -304.638782) (xy 179.227982 -304.65988) (xy 179.268485 -304.687836)
			(xy 179.303978 -304.721928) (xy 179.333543 -304.761272) (xy 179.356414 -304.804849) (xy 179.371998 -304.85153)
			(xy 179.379893 -304.900107) (xy 179.380388 -304.924714) (xy 179.719236 -304.924714) (xy 179.723196 -304.87566)
			(xy 179.734973 -304.827876) (xy 179.754264 -304.7826) (xy 179.780567 -304.741004) (xy 179.813202 -304.704167)
			(xy 179.851323 -304.673042) (xy 179.893944 -304.648435) (xy 179.93996 -304.630983) (xy 179.988179 -304.621139)
			(xy 180.037354 -304.619158) (xy 180.086209 -304.62509) (xy 180.13348 -304.638782) (xy 180.177942 -304.65988)
			(xy 180.218445 -304.687836) (xy 180.253938 -304.721928) (xy 180.283503 -304.761272) (xy 180.306374 -304.804849)
			(xy 180.321958 -304.85153) (xy 180.329853 -304.900107) (xy 180.330348 -304.924714) (xy 180.669196 -304.924714)
			(xy 180.673156 -304.87566) (xy 180.684933 -304.827876) (xy 180.704224 -304.7826) (xy 180.730527 -304.741004)
			(xy 180.763162 -304.704167) (xy 180.801283 -304.673042) (xy 180.843904 -304.648435) (xy 180.88992 -304.630983)
			(xy 180.938139 -304.621139) (xy 180.987314 -304.619158) (xy 181.036169 -304.62509) (xy 181.08344 -304.638782)
			(xy 181.127902 -304.65988) (xy 181.168405 -304.687836) (xy 181.203898 -304.721928) (xy 181.233463 -304.761272)
			(xy 181.256334 -304.804849) (xy 181.271918 -304.85153) (xy 181.279813 -304.900107) (xy 181.280308 -304.924714)
			(xy 181.619156 -304.924714) (xy 181.623116 -304.87566) (xy 181.634893 -304.827876) (xy 181.654184 -304.7826)
			(xy 181.680487 -304.741004) (xy 181.713122 -304.704167) (xy 181.751243 -304.673042) (xy 181.793864 -304.648435)
			(xy 181.83988 -304.630983) (xy 181.888099 -304.621139) (xy 181.937274 -304.619158) (xy 181.986129 -304.62509)
			(xy 182.0334 -304.638782) (xy 182.077862 -304.65988) (xy 182.118365 -304.687836) (xy 182.153858 -304.721928)
			(xy 182.183423 -304.761272) (xy 182.206294 -304.804849) (xy 182.221878 -304.85153) (xy 182.229773 -304.900107)
			(xy 182.230268 -304.924714) (xy 182.569116 -304.924714) (xy 182.573076 -304.87566) (xy 182.584853 -304.827876)
			(xy 182.604144 -304.7826) (xy 182.630447 -304.741004) (xy 182.663082 -304.704167) (xy 182.701203 -304.673042)
			(xy 182.743824 -304.648435) (xy 182.78984 -304.630983) (xy 182.838059 -304.621139) (xy 182.887234 -304.619158)
			(xy 182.936089 -304.62509) (xy 182.98336 -304.638782) (xy 183.027822 -304.65988) (xy 183.068325 -304.687836)
			(xy 183.103818 -304.721928) (xy 183.133383 -304.761272) (xy 183.156254 -304.804849) (xy 183.171838 -304.85153)
			(xy 183.179733 -304.900107) (xy 183.180228 -304.924714) (xy 183.519076 -304.924714) (xy 183.523036 -304.87566)
			(xy 183.534813 -304.827876) (xy 183.554104 -304.7826) (xy 183.580407 -304.741004) (xy 183.613042 -304.704167)
			(xy 183.651163 -304.673042) (xy 183.693784 -304.648435) (xy 183.7398 -304.630983) (xy 183.788019 -304.621139)
			(xy 183.837194 -304.619158) (xy 183.886049 -304.62509) (xy 183.93332 -304.638782) (xy 183.977782 -304.65988)
			(xy 184.018285 -304.687836) (xy 184.053778 -304.721928) (xy 184.083343 -304.761272) (xy 184.106214 -304.804849)
			(xy 184.121798 -304.85153) (xy 184.129693 -304.900107) (xy 184.130188 -304.924714) (xy 184.469036 -304.924714)
			(xy 184.472996 -304.87566) (xy 184.484773 -304.827876) (xy 184.504064 -304.7826) (xy 184.530367 -304.741004)
			(xy 184.563002 -304.704167) (xy 184.601123 -304.673042) (xy 184.643744 -304.648435) (xy 184.68976 -304.630983)
			(xy 184.737979 -304.621139) (xy 184.787154 -304.619158) (xy 184.836009 -304.62509) (xy 184.88328 -304.638782)
			(xy 184.927742 -304.65988) (xy 184.968245 -304.687836) (xy 185.003738 -304.721928) (xy 185.033303 -304.761272)
			(xy 185.056174 -304.804849) (xy 185.071758 -304.85153) (xy 185.079653 -304.900107) (xy 185.080148 -304.924714)
			(xy 185.41925 -304.924714) (xy 185.42321 -304.87566) (xy 185.434987 -304.827876) (xy 185.454278 -304.7826)
			(xy 185.480581 -304.741004) (xy 185.513216 -304.704167) (xy 185.551337 -304.673042) (xy 185.593958 -304.648435)
			(xy 185.639974 -304.630983) (xy 185.688193 -304.621139) (xy 185.737368 -304.619158) (xy 185.786223 -304.62509)
			(xy 185.833494 -304.638782) (xy 185.877956 -304.65988) (xy 185.918459 -304.687836) (xy 185.953952 -304.721928)
			(xy 185.983517 -304.761272) (xy 186.006388 -304.804849) (xy 186.021972 -304.85153) (xy 186.029867 -304.900107)
			(xy 186.030362 -304.924714) (xy 186.36921 -304.924714) (xy 186.37317 -304.87566) (xy 186.384947 -304.827876)
			(xy 186.404238 -304.7826) (xy 186.430541 -304.741004) (xy 186.463176 -304.704167) (xy 186.501297 -304.673042)
			(xy 186.543918 -304.648435) (xy 186.589934 -304.630983) (xy 186.638153 -304.621139) (xy 186.687328 -304.619158)
			(xy 186.736183 -304.62509) (xy 186.783454 -304.638782) (xy 186.827916 -304.65988) (xy 186.868419 -304.687836)
			(xy 186.903912 -304.721928) (xy 186.933477 -304.761272) (xy 186.956348 -304.804849) (xy 186.971932 -304.85153)
			(xy 186.979827 -304.900107) (xy 186.980322 -304.924714) (xy 187.31917 -304.924714) (xy 187.32313 -304.87566)
			(xy 187.334907 -304.827876) (xy 187.354198 -304.7826) (xy 187.380501 -304.741004) (xy 187.413136 -304.704167)
			(xy 187.451257 -304.673042) (xy 187.493878 -304.648435) (xy 187.539894 -304.630983) (xy 187.588113 -304.621139)
			(xy 187.637288 -304.619158) (xy 187.686143 -304.62509) (xy 187.733414 -304.638782) (xy 187.777876 -304.65988)
			(xy 187.818379 -304.687836) (xy 187.853872 -304.721928) (xy 187.883437 -304.761272) (xy 187.906308 -304.804849)
			(xy 187.921892 -304.85153) (xy 187.929787 -304.900107) (xy 187.930282 -304.924714) (xy 188.26913 -304.924714)
			(xy 188.27309 -304.87566) (xy 188.284867 -304.827876) (xy 188.304158 -304.7826) (xy 188.330461 -304.741004)
			(xy 188.363096 -304.704167) (xy 188.401217 -304.673042) (xy 188.443838 -304.648435) (xy 188.489854 -304.630983)
			(xy 188.538073 -304.621139) (xy 188.587248 -304.619158) (xy 188.636103 -304.62509) (xy 188.683374 -304.638782)
			(xy 188.727836 -304.65988) (xy 188.768339 -304.687836) (xy 188.803832 -304.721928) (xy 188.833397 -304.761272)
			(xy 188.843256 -304.780056) (xy 203.949711 -304.780056) (xy 203.949711 -304.725544) (xy 203.957469 -304.671586)
			(xy 203.972827 -304.619281) (xy 203.995473 -304.569695) (xy 204.024945 -304.523836) (xy 204.060644 -304.482638)
			(xy 204.101842 -304.44694) (xy 204.147702 -304.417469) (xy 204.197289 -304.394824) (xy 204.249594 -304.379467)
			(xy 204.303552 -304.37171) (xy 204.330808 -304.371248) (xy 204.357952 -304.371727) (xy 204.411695 -304.379403)
			(xy 204.463805 -304.394627) (xy 204.513227 -304.417092) (xy 204.558962 -304.446341) (xy 204.600084 -304.481785)
			(xy 204.63576 -304.522705) (xy 204.665269 -304.568273) (xy 204.688013 -304.617567) (xy 204.703533 -304.669589)
			(xy 204.707998 -304.696368) (xy 204.710733 -304.711218) (xy 204.723778 -304.738439) (xy 204.744199 -304.760668)
			(xy 204.770219 -304.775969) (xy 204.799571 -304.783011) (xy 204.829701 -304.78118) (xy 204.857985 -304.770637)
			(xy 204.870304 -304.7619) (xy 204.89035 -304.747071) (xy 204.933571 -304.722205) (xy 204.979661 -304.703176)
			(xy 205.027835 -304.690307) (xy 205.077274 -304.683818) (xy 205.102206 -304.683414) (xy 205.129459 -304.683856)
			(xy 205.183409 -304.691614) (xy 205.235706 -304.70697) (xy 205.285285 -304.729613) (xy 205.331137 -304.759081)
			(xy 205.372329 -304.794775) (xy 205.408022 -304.835967) (xy 205.43749 -304.88182) (xy 205.460132 -304.9314)
			(xy 205.475487 -304.983697) (xy 205.483244 -305.037647) (xy 205.483244 -305.064922) (xy 205.735172 -305.064922)
			(xy 205.739243 -305.0093) (xy 205.751369 -304.954863) (xy 205.771292 -304.902772) (xy 205.798588 -304.854137)
			(xy 205.832674 -304.809994) (xy 205.872823 -304.771285) (xy 205.918181 -304.738834) (xy 205.967781 -304.713333)
			(xy 206.020565 -304.695326) (xy 206.075408 -304.685196) (xy 206.131142 -304.683159) (xy 206.186579 -304.689259)
			(xy 206.240536 -304.703365) (xy 206.291865 -304.725177) (xy 206.339471 -304.754231) (xy 206.382339 -304.789906)
			(xy 206.419556 -304.831443) (xy 206.450329 -304.877956) (xy 206.474001 -304.928453) (xy 206.490069 -304.98186)
			(xy 206.498189 -305.037036) (xy 206.498698 -305.064922) (xy 206.743552 -305.064922) (xy 206.747623 -305.0093)
			(xy 206.759749 -304.954863) (xy 206.779672 -304.902772) (xy 206.806968 -304.854137) (xy 206.841054 -304.809994)
			(xy 206.881203 -304.771285) (xy 206.926561 -304.738834) (xy 206.976161 -304.713333) (xy 207.028945 -304.695326)
			(xy 207.083788 -304.685196) (xy 207.139522 -304.683159) (xy 207.194959 -304.689259) (xy 207.248916 -304.703365)
			(xy 207.300245 -304.725177) (xy 207.347851 -304.754231) (xy 207.390719 -304.789906) (xy 207.427936 -304.831443)
			(xy 207.458709 -304.877956) (xy 207.482381 -304.928453) (xy 207.498449 -304.98186) (xy 207.506569 -305.037036)
			(xy 207.507059 -305.063906) (xy 207.768188 -305.063906) (xy 207.772259 -305.008284) (xy 207.784385 -304.953847)
			(xy 207.804308 -304.901756) (xy 207.831604 -304.853121) (xy 207.86569 -304.808978) (xy 207.905839 -304.770269)
			(xy 207.951197 -304.737818) (xy 208.000797 -304.712317) (xy 208.053581 -304.69431) (xy 208.108424 -304.68418)
			(xy 208.164158 -304.682143) (xy 208.219595 -304.688243) (xy 208.273552 -304.702349) (xy 208.324881 -304.724161)
			(xy 208.372487 -304.753215) (xy 208.415355 -304.78889) (xy 208.452572 -304.830427) (xy 208.483345 -304.87694)
			(xy 208.507017 -304.927437) (xy 208.523085 -304.980844) (xy 208.531205 -305.03602) (xy 208.531389 -305.046126)
			(xy 208.784188 -305.046126) (xy 208.788259 -304.990504) (xy 208.800385 -304.936067) (xy 208.820308 -304.883976)
			(xy 208.847604 -304.835341) (xy 208.88169 -304.791198) (xy 208.921839 -304.752489) (xy 208.967197 -304.720038)
			(xy 209.016797 -304.694537) (xy 209.069581 -304.67653) (xy 209.124424 -304.6664) (xy 209.180158 -304.664363)
			(xy 209.235595 -304.670463) (xy 209.289552 -304.684569) (xy 209.340881 -304.706381) (xy 209.388487 -304.735435)
			(xy 209.431355 -304.77111) (xy 209.468572 -304.812647) (xy 209.499345 -304.85916) (xy 209.523017 -304.909657)
			(xy 209.539085 -304.963064) (xy 209.547205 -305.01824) (xy 209.547714 -305.046126) (xy 209.547205 -305.074012)
			(xy 209.539085 -305.129188) (xy 209.523017 -305.182595) (xy 209.499345 -305.233092) (xy 209.468572 -305.279605)
			(xy 209.431355 -305.321142) (xy 209.388487 -305.356817) (xy 209.340881 -305.385871) (xy 209.289552 -305.407683)
			(xy 209.235595 -305.421789) (xy 209.180158 -305.427889) (xy 209.124424 -305.425852) (xy 209.069581 -305.415722)
			(xy 209.016797 -305.397715) (xy 208.967197 -305.372214) (xy 208.921839 -305.339763) (xy 208.88169 -305.301054)
			(xy 208.847604 -305.256911) (xy 208.820308 -305.208276) (xy 208.800385 -305.156185) (xy 208.788259 -305.101748)
			(xy 208.784188 -305.046126) (xy 208.531389 -305.046126) (xy 208.531714 -305.063906) (xy 208.531205 -305.091792)
			(xy 208.523085 -305.146968) (xy 208.507017 -305.200375) (xy 208.483345 -305.250872) (xy 208.452572 -305.297385)
			(xy 208.415355 -305.338922) (xy 208.372487 -305.374597) (xy 208.324881 -305.403651) (xy 208.273552 -305.425463)
			(xy 208.219595 -305.439569) (xy 208.164158 -305.445669) (xy 208.108424 -305.443632) (xy 208.053581 -305.433502)
			(xy 208.000797 -305.415495) (xy 207.951197 -305.389994) (xy 207.905839 -305.357543) (xy 207.86569 -305.318834)
			(xy 207.831604 -305.274691) (xy 207.804308 -305.226056) (xy 207.784385 -305.173965) (xy 207.772259 -305.119528)
			(xy 207.768188 -305.063906) (xy 207.507059 -305.063906) (xy 207.507078 -305.064922) (xy 207.506569 -305.092808)
			(xy 207.498449 -305.147984) (xy 207.482381 -305.201391) (xy 207.458709 -305.251888) (xy 207.427936 -305.298401)
			(xy 207.390719 -305.339938) (xy 207.347851 -305.375613) (xy 207.300245 -305.404667) (xy 207.248916 -305.426479)
			(xy 207.194959 -305.440585) (xy 207.139522 -305.446685) (xy 207.083788 -305.444648) (xy 207.028945 -305.434518)
			(xy 206.976161 -305.416511) (xy 206.926561 -305.39101) (xy 206.881203 -305.358559) (xy 206.841054 -305.31985)
			(xy 206.806968 -305.275707) (xy 206.779672 -305.227072) (xy 206.759749 -305.174981) (xy 206.747623 -305.120544)
			(xy 206.743552 -305.064922) (xy 206.498698 -305.064922) (xy 206.498189 -305.092808) (xy 206.490069 -305.147984)
			(xy 206.474001 -305.201391) (xy 206.450329 -305.251888) (xy 206.419556 -305.298401) (xy 206.382339 -305.339938)
			(xy 206.339471 -305.375613) (xy 206.291865 -305.404667) (xy 206.240536 -305.426479) (xy 206.186579 -305.440585)
			(xy 206.131142 -305.446685) (xy 206.075408 -305.444648) (xy 206.020565 -305.434518) (xy 205.967781 -305.416511)
			(xy 205.918181 -305.39101) (xy 205.872823 -305.358559) (xy 205.832674 -305.31985) (xy 205.798588 -305.275707)
			(xy 205.771292 -305.227072) (xy 205.751369 -305.174981) (xy 205.739243 -305.120544) (xy 205.735172 -305.064922)
			(xy 205.483244 -305.064922) (xy 205.483244 -305.092153) (xy 205.475487 -305.146103) (xy 205.460132 -305.1984)
			(xy 205.43749 -305.24798) (xy 205.408022 -305.293833) (xy 205.372329 -305.335025) (xy 205.331137 -305.370719)
			(xy 205.285285 -305.400187) (xy 205.235706 -305.42283) (xy 205.183409 -305.438186) (xy 205.129459 -305.445944)
			(xy 205.102206 -305.44643) (xy 205.075061 -305.445957) (xy 205.021317 -305.438282) (xy 204.969206 -305.423059)
			(xy 204.919783 -305.400594) (xy 204.874047 -305.371344) (xy 204.832925 -305.3359) (xy 204.797249 -305.294979)
			(xy 204.767741 -305.249409) (xy 204.744997 -305.200114) (xy 204.72948 -305.148089) (xy 204.725016 -305.12131)
			(xy 204.722271 -305.106463) (xy 204.709224 -305.079247) (xy 204.688803 -305.057023) (xy 204.662787 -305.041723)
			(xy 204.633438 -305.034681) (xy 204.603312 -305.036508) (xy 204.575029 -305.047045) (xy 204.56271 -305.055778)
			(xy 204.542667 -305.070611) (xy 204.499445 -305.095475) (xy 204.453354 -305.114502) (xy 204.405179 -305.12737)
			(xy 204.35574 -305.13386) (xy 204.330808 -305.134264) (xy 204.303552 -305.13389) (xy 204.249594 -305.126133)
			(xy 204.197289 -305.110776) (xy 204.147702 -305.088131) (xy 204.101842 -305.05866) (xy 204.060644 -305.022962)
			(xy 204.024945 -304.981764) (xy 203.995473 -304.935905) (xy 203.972827 -304.886319) (xy 203.957469 -304.834014)
			(xy 203.949711 -304.780056) (xy 188.843256 -304.780056) (xy 188.856268 -304.804849) (xy 188.871852 -304.85153)
			(xy 188.879747 -304.900107) (xy 188.880242 -304.924714) (xy 188.879747 -304.949321) (xy 188.871852 -304.997898)
			(xy 188.856268 -305.044579) (xy 188.833397 -305.088156) (xy 188.803832 -305.1275) (xy 188.768339 -305.161592)
			(xy 188.727836 -305.189548) (xy 188.683374 -305.210646) (xy 188.636103 -305.224338) (xy 188.587248 -305.23027)
			(xy 188.538073 -305.228289) (xy 188.489854 -305.218445) (xy 188.443838 -305.200993) (xy 188.401217 -305.176386)
			(xy 188.363096 -305.145261) (xy 188.330461 -305.108424) (xy 188.304158 -305.066828) (xy 188.284867 -305.021552)
			(xy 188.27309 -304.973768) (xy 188.26913 -304.924714) (xy 187.930282 -304.924714) (xy 187.929787 -304.949321)
			(xy 187.921892 -304.997898) (xy 187.906308 -305.044579) (xy 187.883437 -305.088156) (xy 187.853872 -305.1275)
			(xy 187.818379 -305.161592) (xy 187.777876 -305.189548) (xy 187.733414 -305.210646) (xy 187.686143 -305.224338)
			(xy 187.637288 -305.23027) (xy 187.588113 -305.228289) (xy 187.539894 -305.218445) (xy 187.493878 -305.200993)
			(xy 187.451257 -305.176386) (xy 187.413136 -305.145261) (xy 187.380501 -305.108424) (xy 187.354198 -305.066828)
			(xy 187.334907 -305.021552) (xy 187.32313 -304.973768) (xy 187.31917 -304.924714) (xy 186.980322 -304.924714)
			(xy 186.979827 -304.949321) (xy 186.971932 -304.997898) (xy 186.956348 -305.044579) (xy 186.933477 -305.088156)
			(xy 186.903912 -305.1275) (xy 186.868419 -305.161592) (xy 186.827916 -305.189548) (xy 186.783454 -305.210646)
			(xy 186.736183 -305.224338) (xy 186.687328 -305.23027) (xy 186.638153 -305.228289) (xy 186.589934 -305.218445)
			(xy 186.543918 -305.200993) (xy 186.501297 -305.176386) (xy 186.463176 -305.145261) (xy 186.430541 -305.108424)
			(xy 186.404238 -305.066828) (xy 186.384947 -305.021552) (xy 186.37317 -304.973768) (xy 186.36921 -304.924714)
			(xy 186.030362 -304.924714) (xy 186.029867 -304.949321) (xy 186.021972 -304.997898) (xy 186.006388 -305.044579)
			(xy 185.983517 -305.088156) (xy 185.953952 -305.1275) (xy 185.918459 -305.161592) (xy 185.877956 -305.189548)
			(xy 185.833494 -305.210646) (xy 185.786223 -305.224338) (xy 185.737368 -305.23027) (xy 185.688193 -305.228289)
			(xy 185.639974 -305.218445) (xy 185.593958 -305.200993) (xy 185.551337 -305.176386) (xy 185.513216 -305.145261)
			(xy 185.480581 -305.108424) (xy 185.454278 -305.066828) (xy 185.434987 -305.021552) (xy 185.42321 -304.973768)
			(xy 185.41925 -304.924714) (xy 185.080148 -304.924714) (xy 185.079653 -304.949321) (xy 185.071758 -304.997898)
			(xy 185.056174 -305.044579) (xy 185.033303 -305.088156) (xy 185.003738 -305.1275) (xy 184.968245 -305.161592)
			(xy 184.927742 -305.189548) (xy 184.88328 -305.210646) (xy 184.836009 -305.224338) (xy 184.787154 -305.23027)
			(xy 184.737979 -305.228289) (xy 184.68976 -305.218445) (xy 184.643744 -305.200993) (xy 184.601123 -305.176386)
			(xy 184.563002 -305.145261) (xy 184.530367 -305.108424) (xy 184.504064 -305.066828) (xy 184.484773 -305.021552)
			(xy 184.472996 -304.973768) (xy 184.469036 -304.924714) (xy 184.130188 -304.924714) (xy 184.129693 -304.949321)
			(xy 184.121798 -304.997898) (xy 184.106214 -305.044579) (xy 184.083343 -305.088156) (xy 184.053778 -305.1275)
			(xy 184.018285 -305.161592) (xy 183.977782 -305.189548) (xy 183.93332 -305.210646) (xy 183.886049 -305.224338)
			(xy 183.837194 -305.23027) (xy 183.788019 -305.228289) (xy 183.7398 -305.218445) (xy 183.693784 -305.200993)
			(xy 183.651163 -305.176386) (xy 183.613042 -305.145261) (xy 183.580407 -305.108424) (xy 183.554104 -305.066828)
			(xy 183.534813 -305.021552) (xy 183.523036 -304.973768) (xy 183.519076 -304.924714) (xy 183.180228 -304.924714)
			(xy 183.179733 -304.949321) (xy 183.171838 -304.997898) (xy 183.156254 -305.044579) (xy 183.133383 -305.088156)
			(xy 183.103818 -305.1275) (xy 183.068325 -305.161592) (xy 183.027822 -305.189548) (xy 182.98336 -305.210646)
			(xy 182.936089 -305.224338) (xy 182.887234 -305.23027) (xy 182.838059 -305.228289) (xy 182.78984 -305.218445)
			(xy 182.743824 -305.200993) (xy 182.701203 -305.176386) (xy 182.663082 -305.145261) (xy 182.630447 -305.108424)
			(xy 182.604144 -305.066828) (xy 182.584853 -305.021552) (xy 182.573076 -304.973768) (xy 182.569116 -304.924714)
			(xy 182.230268 -304.924714) (xy 182.229773 -304.949321) (xy 182.221878 -304.997898) (xy 182.206294 -305.044579)
			(xy 182.183423 -305.088156) (xy 182.153858 -305.1275) (xy 182.118365 -305.161592) (xy 182.077862 -305.189548)
			(xy 182.0334 -305.210646) (xy 181.986129 -305.224338) (xy 181.937274 -305.23027) (xy 181.888099 -305.228289)
			(xy 181.83988 -305.218445) (xy 181.793864 -305.200993) (xy 181.751243 -305.176386) (xy 181.713122 -305.145261)
			(xy 181.680487 -305.108424) (xy 181.654184 -305.066828) (xy 181.634893 -305.021552) (xy 181.623116 -304.973768)
			(xy 181.619156 -304.924714) (xy 181.280308 -304.924714) (xy 181.279813 -304.949321) (xy 181.271918 -304.997898)
			(xy 181.256334 -305.044579) (xy 181.233463 -305.088156) (xy 181.203898 -305.1275) (xy 181.168405 -305.161592)
			(xy 181.127902 -305.189548) (xy 181.08344 -305.210646) (xy 181.036169 -305.224338) (xy 180.987314 -305.23027)
			(xy 180.938139 -305.228289) (xy 180.88992 -305.218445) (xy 180.843904 -305.200993) (xy 180.801283 -305.176386)
			(xy 180.763162 -305.145261) (xy 180.730527 -305.108424) (xy 180.704224 -305.066828) (xy 180.684933 -305.021552)
			(xy 180.673156 -304.973768) (xy 180.669196 -304.924714) (xy 180.330348 -304.924714) (xy 180.329853 -304.949321)
			(xy 180.321958 -304.997898) (xy 180.306374 -305.044579) (xy 180.283503 -305.088156) (xy 180.253938 -305.1275)
			(xy 180.218445 -305.161592) (xy 180.177942 -305.189548) (xy 180.13348 -305.210646) (xy 180.086209 -305.224338)
			(xy 180.037354 -305.23027) (xy 179.988179 -305.228289) (xy 179.93996 -305.218445) (xy 179.893944 -305.200993)
			(xy 179.851323 -305.176386) (xy 179.813202 -305.145261) (xy 179.780567 -305.108424) (xy 179.754264 -305.066828)
			(xy 179.734973 -305.021552) (xy 179.723196 -304.973768) (xy 179.719236 -304.924714) (xy 179.380388 -304.924714)
			(xy 179.379893 -304.949321) (xy 179.371998 -304.997898) (xy 179.356414 -305.044579) (xy 179.333543 -305.088156)
			(xy 179.303978 -305.1275) (xy 179.268485 -305.161592) (xy 179.227982 -305.189548) (xy 179.18352 -305.210646)
			(xy 179.136249 -305.224338) (xy 179.087394 -305.23027) (xy 179.038219 -305.228289) (xy 178.99 -305.218445)
			(xy 178.943984 -305.200993) (xy 178.901363 -305.176386) (xy 178.863242 -305.145261) (xy 178.830607 -305.108424)
			(xy 178.804304 -305.066828) (xy 178.785013 -305.021552) (xy 178.773236 -304.973768) (xy 178.769276 -304.924714)
			(xy 178.430174 -304.924714) (xy 178.429679 -304.949321) (xy 178.421784 -304.997898) (xy 178.4062 -305.044579)
			(xy 178.383329 -305.088156) (xy 178.353764 -305.1275) (xy 178.318271 -305.161592) (xy 178.277768 -305.189548)
			(xy 178.233306 -305.210646) (xy 178.186035 -305.224338) (xy 178.13718 -305.23027) (xy 178.088005 -305.228289)
			(xy 178.039786 -305.218445) (xy 177.99377 -305.200993) (xy 177.951149 -305.176386) (xy 177.913028 -305.145261)
			(xy 177.880393 -305.108424) (xy 177.85409 -305.066828) (xy 177.834799 -305.021552) (xy 177.823022 -304.973768)
			(xy 177.819062 -304.924714) (xy 177.480214 -304.924714) (xy 177.479719 -304.949321) (xy 177.471824 -304.997898)
			(xy 177.45624 -305.044579) (xy 177.433369 -305.088156) (xy 177.403804 -305.1275) (xy 177.368311 -305.161592)
			(xy 177.327808 -305.189548) (xy 177.283346 -305.210646) (xy 177.236075 -305.224338) (xy 177.18722 -305.23027)
			(xy 177.138045 -305.228289) (xy 177.089826 -305.218445) (xy 177.04381 -305.200993) (xy 177.001189 -305.176386)
			(xy 176.963068 -305.145261) (xy 176.930433 -305.108424) (xy 176.90413 -305.066828) (xy 176.884839 -305.021552)
			(xy 176.873062 -304.973768) (xy 176.869102 -304.924714) (xy 176.530254 -304.924714) (xy 176.529759 -304.949321)
			(xy 176.521864 -304.997898) (xy 176.50628 -305.044579) (xy 176.483409 -305.088156) (xy 176.453844 -305.1275)
			(xy 176.418351 -305.161592) (xy 176.377848 -305.189548) (xy 176.333386 -305.210646) (xy 176.286115 -305.224338)
			(xy 176.23726 -305.23027) (xy 176.188085 -305.228289) (xy 176.139866 -305.218445) (xy 176.09385 -305.200993)
			(xy 176.051229 -305.176386) (xy 176.013108 -305.145261) (xy 175.980473 -305.108424) (xy 175.95417 -305.066828)
			(xy 175.934879 -305.021552) (xy 175.923102 -304.973768) (xy 175.919142 -304.924714) (xy 174.630334 -304.924714)
			(xy 174.629839 -304.949321) (xy 174.621944 -304.997898) (xy 174.60636 -305.044579) (xy 174.583489 -305.088156)
			(xy 174.553924 -305.1275) (xy 174.518431 -305.161592) (xy 174.477928 -305.189548) (xy 174.433466 -305.210646)
			(xy 174.386195 -305.224338) (xy 174.33734 -305.23027) (xy 174.288165 -305.228289) (xy 174.239946 -305.218445)
			(xy 174.19393 -305.200993) (xy 174.151309 -305.176386) (xy 174.113188 -305.145261) (xy 174.080553 -305.108424)
			(xy 174.05425 -305.066828) (xy 174.034959 -305.021552) (xy 174.023182 -304.973768) (xy 174.019222 -304.924714)
			(xy 173.680374 -304.924714) (xy 173.679879 -304.949321) (xy 173.671984 -304.997898) (xy 173.6564 -305.044579)
			(xy 173.633529 -305.088156) (xy 173.603964 -305.1275) (xy 173.568471 -305.161592) (xy 173.527968 -305.189548)
			(xy 173.483506 -305.210646) (xy 173.436235 -305.224338) (xy 173.38738 -305.23027) (xy 173.338205 -305.228289)
			(xy 173.289986 -305.218445) (xy 173.24397 -305.200993) (xy 173.201349 -305.176386) (xy 173.163228 -305.145261)
			(xy 173.130593 -305.108424) (xy 173.10429 -305.066828) (xy 173.084999 -305.021552) (xy 173.073222 -304.973768)
			(xy 173.069262 -304.924714) (xy 172.73016 -304.924714) (xy 172.729665 -304.949321) (xy 172.72177 -304.997898)
			(xy 172.706186 -305.044579) (xy 172.683315 -305.088156) (xy 172.65375 -305.1275) (xy 172.618257 -305.161592)
			(xy 172.577754 -305.189548) (xy 172.533292 -305.210646) (xy 172.486021 -305.224338) (xy 172.437166 -305.23027)
			(xy 172.387991 -305.228289) (xy 172.339772 -305.218445) (xy 172.293756 -305.200993) (xy 172.251135 -305.176386)
			(xy 172.213014 -305.145261) (xy 172.180379 -305.108424) (xy 172.154076 -305.066828) (xy 172.134785 -305.021552)
			(xy 172.123008 -304.973768) (xy 172.119048 -304.924714) (xy 171.7802 -304.924714) (xy 171.779705 -304.949321)
			(xy 171.77181 -304.997898) (xy 171.756226 -305.044579) (xy 171.733355 -305.088156) (xy 171.70379 -305.1275)
			(xy 171.668297 -305.161592) (xy 171.627794 -305.189548) (xy 171.583332 -305.210646) (xy 171.536061 -305.224338)
			(xy 171.487206 -305.23027) (xy 171.438031 -305.228289) (xy 171.389812 -305.218445) (xy 171.343796 -305.200993)
			(xy 171.301175 -305.176386) (xy 171.263054 -305.145261) (xy 171.230419 -305.108424) (xy 171.204116 -305.066828)
			(xy 171.184825 -305.021552) (xy 171.173048 -304.973768) (xy 171.169088 -304.924714) (xy 170.83024 -304.924714)
			(xy 170.829745 -304.949321) (xy 170.82185 -304.997898) (xy 170.806266 -305.044579) (xy 170.783395 -305.088156)
			(xy 170.75383 -305.1275) (xy 170.718337 -305.161592) (xy 170.677834 -305.189548) (xy 170.633372 -305.210646)
			(xy 170.586101 -305.224338) (xy 170.537246 -305.23027) (xy 170.488071 -305.228289) (xy 170.439852 -305.218445)
			(xy 170.393836 -305.200993) (xy 170.351215 -305.176386) (xy 170.313094 -305.145261) (xy 170.280459 -305.108424)
			(xy 170.254156 -305.066828) (xy 170.234865 -305.021552) (xy 170.223088 -304.973768) (xy 170.219128 -304.924714)
			(xy 169.88028 -304.924714) (xy 169.879785 -304.949321) (xy 169.87189 -304.997898) (xy 169.856306 -305.044579)
			(xy 169.833435 -305.088156) (xy 169.80387 -305.1275) (xy 169.768377 -305.161592) (xy 169.727874 -305.189548)
			(xy 169.683412 -305.210646) (xy 169.636141 -305.224338) (xy 169.587286 -305.23027) (xy 169.538111 -305.228289)
			(xy 169.489892 -305.218445) (xy 169.443876 -305.200993) (xy 169.401255 -305.176386) (xy 169.363134 -305.145261)
			(xy 169.330499 -305.108424) (xy 169.304196 -305.066828) (xy 169.284905 -305.021552) (xy 169.273128 -304.973768)
			(xy 169.269168 -304.924714) (xy 168.93032 -304.924714) (xy 168.929825 -304.949321) (xy 168.92193 -304.997898)
			(xy 168.906346 -305.044579) (xy 168.883475 -305.088156) (xy 168.85391 -305.1275) (xy 168.818417 -305.161592)
			(xy 168.777914 -305.189548) (xy 168.733452 -305.210646) (xy 168.686181 -305.224338) (xy 168.637326 -305.23027)
			(xy 168.588151 -305.228289) (xy 168.539932 -305.218445) (xy 168.493916 -305.200993) (xy 168.451295 -305.176386)
			(xy 168.413174 -305.145261) (xy 168.380539 -305.108424) (xy 168.354236 -305.066828) (xy 168.334945 -305.021552)
			(xy 168.323168 -304.973768) (xy 168.319208 -304.924714) (xy 167.98036 -304.924714) (xy 167.979865 -304.949321)
			(xy 167.97197 -304.997898) (xy 167.956386 -305.044579) (xy 167.933515 -305.088156) (xy 167.90395 -305.1275)
			(xy 167.868457 -305.161592) (xy 167.827954 -305.189548) (xy 167.783492 -305.210646) (xy 167.736221 -305.224338)
			(xy 167.687366 -305.23027) (xy 167.638191 -305.228289) (xy 167.589972 -305.218445) (xy 167.543956 -305.200993)
			(xy 167.501335 -305.176386) (xy 167.463214 -305.145261) (xy 167.430579 -305.108424) (xy 167.404276 -305.066828)
			(xy 167.384985 -305.021552) (xy 167.373208 -304.973768) (xy 167.369248 -304.924714) (xy 167.0304 -304.924714)
			(xy 167.029905 -304.949321) (xy 167.02201 -304.997898) (xy 167.006426 -305.044579) (xy 166.983555 -305.088156)
			(xy 166.95399 -305.1275) (xy 166.918497 -305.161592) (xy 166.877994 -305.189548) (xy 166.833532 -305.210646)
			(xy 166.786261 -305.224338) (xy 166.737406 -305.23027) (xy 166.688231 -305.228289) (xy 166.640012 -305.218445)
			(xy 166.593996 -305.200993) (xy 166.551375 -305.176386) (xy 166.513254 -305.145261) (xy 166.480619 -305.108424)
			(xy 166.454316 -305.066828) (xy 166.435025 -305.021552) (xy 166.423248 -304.973768) (xy 166.419288 -304.924714)
			(xy 166.11727 -304.924714) (xy 166.11727 -305.399948) (xy 189.69407 -305.399948) (xy 189.69803 -305.350894)
			(xy 189.709807 -305.30311) (xy 189.729098 -305.257834) (xy 189.755401 -305.216238) (xy 189.788036 -305.179401)
			(xy 189.826157 -305.148276) (xy 189.868778 -305.123669) (xy 189.914794 -305.106217) (xy 189.963013 -305.096373)
			(xy 190.012188 -305.094392) (xy 190.061043 -305.100324) (xy 190.108314 -305.114016) (xy 190.152776 -305.135114)
			(xy 190.193279 -305.16307) (xy 190.228772 -305.197162) (xy 190.258337 -305.236506) (xy 190.281208 -305.280083)
			(xy 190.296792 -305.326764) (xy 190.304687 -305.375341) (xy 190.305182 -305.399948) (xy 190.644284 -305.399948)
			(xy 190.648244 -305.350894) (xy 190.660021 -305.30311) (xy 190.679312 -305.257834) (xy 190.705615 -305.216238)
			(xy 190.73825 -305.179401) (xy 190.776371 -305.148276) (xy 190.818992 -305.123669) (xy 190.865008 -305.106217)
			(xy 190.913227 -305.096373) (xy 190.962402 -305.094392) (xy 191.011257 -305.100324) (xy 191.058528 -305.114016)
			(xy 191.10299 -305.135114) (xy 191.143493 -305.16307) (xy 191.178986 -305.197162) (xy 191.208551 -305.236506)
			(xy 191.231422 -305.280083) (xy 191.247006 -305.326764) (xy 191.254901 -305.375341) (xy 191.255396 -305.399948)
			(xy 191.594244 -305.399948) (xy 191.598204 -305.350894) (xy 191.609981 -305.30311) (xy 191.629272 -305.257834)
			(xy 191.655575 -305.216238) (xy 191.68821 -305.179401) (xy 191.726331 -305.148276) (xy 191.768952 -305.123669)
			(xy 191.814968 -305.106217) (xy 191.863187 -305.096373) (xy 191.912362 -305.094392) (xy 191.961217 -305.100324)
			(xy 192.008488 -305.114016) (xy 192.05295 -305.135114) (xy 192.093453 -305.16307) (xy 192.128946 -305.197162)
			(xy 192.158511 -305.236506) (xy 192.181382 -305.280083) (xy 192.196966 -305.326764) (xy 192.204861 -305.375341)
			(xy 192.205356 -305.399948) (xy 192.204861 -305.424555) (xy 192.204682 -305.425656) (xy 192.52336 -305.425656)
			(xy 192.52336 -305.37424) (xy 192.531403 -305.323458) (xy 192.547291 -305.274559) (xy 192.570634 -305.228747)
			(xy 192.600855 -305.187151) (xy 192.637211 -305.150795) (xy 192.678807 -305.120574) (xy 192.724619 -305.097231)
			(xy 192.773518 -305.081343) (xy 192.8243 -305.0733) (xy 192.875716 -305.0733) (xy 192.926498 -305.081343)
			(xy 192.975397 -305.097231) (xy 193.021209 -305.120574) (xy 193.062805 -305.150795) (xy 193.099161 -305.187151)
			(xy 193.129382 -305.228747) (xy 193.152725 -305.274559) (xy 193.168613 -305.323458) (xy 193.176656 -305.37424)
			(xy 193.17716 -305.399948) (xy 193.176656 -305.425656) (xy 193.47332 -305.425656) (xy 193.47332 -305.37424)
			(xy 193.481363 -305.323458) (xy 193.497251 -305.274559) (xy 193.520594 -305.228747) (xy 193.550815 -305.187151)
			(xy 193.587171 -305.150795) (xy 193.628767 -305.120574) (xy 193.674579 -305.097231) (xy 193.723478 -305.081343)
			(xy 193.77426 -305.0733) (xy 193.825676 -305.0733) (xy 193.876458 -305.081343) (xy 193.925357 -305.097231)
			(xy 193.971169 -305.120574) (xy 194.012765 -305.150795) (xy 194.049121 -305.187151) (xy 194.079342 -305.228747)
			(xy 194.102685 -305.274559) (xy 194.118573 -305.323458) (xy 194.126616 -305.37424) (xy 194.12712 -305.399948)
			(xy 194.444124 -305.399948) (xy 194.448084 -305.350894) (xy 194.459861 -305.30311) (xy 194.479152 -305.257834)
			(xy 194.505455 -305.216238) (xy 194.53809 -305.179401) (xy 194.576211 -305.148276) (xy 194.618832 -305.123669)
			(xy 194.664848 -305.106217) (xy 194.713067 -305.096373) (xy 194.762242 -305.094392) (xy 194.811097 -305.100324)
			(xy 194.858368 -305.114016) (xy 194.90283 -305.135114) (xy 194.943333 -305.16307) (xy 194.978826 -305.197162)
			(xy 195.008391 -305.236506) (xy 195.031262 -305.280083) (xy 195.046846 -305.326764) (xy 195.054741 -305.375341)
			(xy 195.055236 -305.399948) (xy 195.054741 -305.424555) (xy 195.054562 -305.425656) (xy 195.37324 -305.425656)
			(xy 195.37324 -305.37424) (xy 195.381283 -305.323458) (xy 195.397171 -305.274559) (xy 195.420514 -305.228747)
			(xy 195.450735 -305.187151) (xy 195.487091 -305.150795) (xy 195.528687 -305.120574) (xy 195.574499 -305.097231)
			(xy 195.623398 -305.081343) (xy 195.67418 -305.0733) (xy 195.725596 -305.0733) (xy 195.776378 -305.081343)
			(xy 195.825277 -305.097231) (xy 195.871089 -305.120574) (xy 195.912685 -305.150795) (xy 195.949041 -305.187151)
			(xy 195.979262 -305.228747) (xy 196.002605 -305.274559) (xy 196.018493 -305.323458) (xy 196.026536 -305.37424)
			(xy 196.02704 -305.399948) (xy 196.026536 -305.425656) (xy 196.3232 -305.425656) (xy 196.3232 -305.37424)
			(xy 196.331243 -305.323458) (xy 196.347131 -305.274559) (xy 196.370474 -305.228747) (xy 196.400695 -305.187151)
			(xy 196.437051 -305.150795) (xy 196.478647 -305.120574) (xy 196.524459 -305.097231) (xy 196.573358 -305.081343)
			(xy 196.62414 -305.0733) (xy 196.675556 -305.0733) (xy 196.726338 -305.081343) (xy 196.775237 -305.097231)
			(xy 196.821049 -305.120574) (xy 196.862645 -305.150795) (xy 196.899001 -305.187151) (xy 196.929222 -305.228747)
			(xy 196.952565 -305.274559) (xy 196.968453 -305.323458) (xy 196.976496 -305.37424) (xy 196.977 -305.399948)
			(xy 197.294258 -305.399948) (xy 197.298218 -305.350894) (xy 197.309995 -305.30311) (xy 197.329286 -305.257834)
			(xy 197.355589 -305.216238) (xy 197.388224 -305.179401) (xy 197.426345 -305.148276) (xy 197.468966 -305.123669)
			(xy 197.514982 -305.106217) (xy 197.563201 -305.096373) (xy 197.612376 -305.094392) (xy 197.661231 -305.100324)
			(xy 197.708502 -305.114016) (xy 197.752964 -305.135114) (xy 197.793467 -305.16307) (xy 197.82896 -305.197162)
			(xy 197.858525 -305.236506) (xy 197.881396 -305.280083) (xy 197.89698 -305.326764) (xy 197.904875 -305.375341)
			(xy 197.90537 -305.399948) (xy 198.244218 -305.399948) (xy 198.248178 -305.350894) (xy 198.259955 -305.30311)
			(xy 198.279246 -305.257834) (xy 198.305549 -305.216238) (xy 198.338184 -305.179401) (xy 198.376305 -305.148276)
			(xy 198.418926 -305.123669) (xy 198.464942 -305.106217) (xy 198.513161 -305.096373) (xy 198.562336 -305.094392)
			(xy 198.611191 -305.100324) (xy 198.658462 -305.114016) (xy 198.702924 -305.135114) (xy 198.743427 -305.16307)
			(xy 198.77892 -305.197162) (xy 198.808485 -305.236506) (xy 198.831356 -305.280083) (xy 198.84694 -305.326764)
			(xy 198.854835 -305.375341) (xy 198.85533 -305.399948) (xy 198.854835 -305.424555) (xy 198.84694 -305.473132)
			(xy 198.831356 -305.519813) (xy 198.808485 -305.56339) (xy 198.77892 -305.602734) (xy 198.743427 -305.636826)
			(xy 198.702924 -305.664782) (xy 198.658462 -305.68588) (xy 198.611191 -305.699572) (xy 198.562336 -305.705504)
			(xy 198.513161 -305.703523) (xy 198.464942 -305.693679) (xy 198.418926 -305.676227) (xy 198.376305 -305.65162)
			(xy 198.338184 -305.620495) (xy 198.305549 -305.583658) (xy 198.279246 -305.542062) (xy 198.259955 -305.496786)
			(xy 198.248178 -305.449002) (xy 198.244218 -305.399948) (xy 197.90537 -305.399948) (xy 197.904875 -305.424555)
			(xy 197.89698 -305.473132) (xy 197.881396 -305.519813) (xy 197.858525 -305.56339) (xy 197.82896 -305.602734)
			(xy 197.793467 -305.636826) (xy 197.752964 -305.664782) (xy 197.708502 -305.68588) (xy 197.661231 -305.699572)
			(xy 197.612376 -305.705504) (xy 197.563201 -305.703523) (xy 197.514982 -305.693679) (xy 197.468966 -305.676227)
			(xy 197.426345 -305.65162) (xy 197.388224 -305.620495) (xy 197.355589 -305.583658) (xy 197.329286 -305.542062)
			(xy 197.309995 -305.496786) (xy 197.298218 -305.449002) (xy 197.294258 -305.399948) (xy 196.977 -305.399948)
			(xy 196.976496 -305.425656) (xy 196.968453 -305.476438) (xy 196.952565 -305.525337) (xy 196.929222 -305.571149)
			(xy 196.899001 -305.612745) (xy 196.862645 -305.649101) (xy 196.821049 -305.679322) (xy 196.775237 -305.702665)
			(xy 196.726338 -305.718553) (xy 196.675556 -305.726596) (xy 196.62414 -305.726596) (xy 196.573358 -305.718553)
			(xy 196.524459 -305.702665) (xy 196.478647 -305.679322) (xy 196.437051 -305.649101) (xy 196.400695 -305.612745)
			(xy 196.370474 -305.571149) (xy 196.347131 -305.525337) (xy 196.331243 -305.476438) (xy 196.3232 -305.425656)
			(xy 196.026536 -305.425656) (xy 196.018493 -305.476438) (xy 196.002605 -305.525337) (xy 195.979262 -305.571149)
			(xy 195.949041 -305.612745) (xy 195.912685 -305.649101) (xy 195.871089 -305.679322) (xy 195.825277 -305.702665)
			(xy 195.776378 -305.718553) (xy 195.725596 -305.726596) (xy 195.67418 -305.726596) (xy 195.623398 -305.718553)
			(xy 195.574499 -305.702665) (xy 195.528687 -305.679322) (xy 195.487091 -305.649101) (xy 195.450735 -305.612745)
			(xy 195.420514 -305.571149) (xy 195.397171 -305.525337) (xy 195.381283 -305.476438) (xy 195.37324 -305.425656)
			(xy 195.054562 -305.425656) (xy 195.046846 -305.473132) (xy 195.031262 -305.519813) (xy 195.008391 -305.56339)
			(xy 194.978826 -305.602734) (xy 194.943333 -305.636826) (xy 194.90283 -305.664782) (xy 194.858368 -305.68588)
			(xy 194.811097 -305.699572) (xy 194.762242 -305.705504) (xy 194.713067 -305.703523) (xy 194.664848 -305.693679)
			(xy 194.618832 -305.676227) (xy 194.576211 -305.65162) (xy 194.53809 -305.620495) (xy 194.505455 -305.583658)
			(xy 194.479152 -305.542062) (xy 194.459861 -305.496786) (xy 194.448084 -305.449002) (xy 194.444124 -305.399948)
			(xy 194.12712 -305.399948) (xy 194.126616 -305.425656) (xy 194.118573 -305.476438) (xy 194.102685 -305.525337)
			(xy 194.079342 -305.571149) (xy 194.049121 -305.612745) (xy 194.012765 -305.649101) (xy 193.971169 -305.679322)
			(xy 193.925357 -305.702665) (xy 193.876458 -305.718553) (xy 193.825676 -305.726596) (xy 193.77426 -305.726596)
			(xy 193.723478 -305.718553) (xy 193.674579 -305.702665) (xy 193.628767 -305.679322) (xy 193.587171 -305.649101)
			(xy 193.550815 -305.612745) (xy 193.520594 -305.571149) (xy 193.497251 -305.525337) (xy 193.481363 -305.476438)
			(xy 193.47332 -305.425656) (xy 193.176656 -305.425656) (xy 193.168613 -305.476438) (xy 193.152725 -305.525337)
			(xy 193.129382 -305.571149) (xy 193.099161 -305.612745) (xy 193.062805 -305.649101) (xy 193.021209 -305.679322)
			(xy 192.975397 -305.702665) (xy 192.926498 -305.718553) (xy 192.875716 -305.726596) (xy 192.8243 -305.726596)
			(xy 192.773518 -305.718553) (xy 192.724619 -305.702665) (xy 192.678807 -305.679322) (xy 192.637211 -305.649101)
			(xy 192.600855 -305.612745) (xy 192.570634 -305.571149) (xy 192.547291 -305.525337) (xy 192.531403 -305.476438)
			(xy 192.52336 -305.425656) (xy 192.204682 -305.425656) (xy 192.196966 -305.473132) (xy 192.181382 -305.519813)
			(xy 192.158511 -305.56339) (xy 192.128946 -305.602734) (xy 192.093453 -305.636826) (xy 192.05295 -305.664782)
			(xy 192.008488 -305.68588) (xy 191.961217 -305.699572) (xy 191.912362 -305.705504) (xy 191.863187 -305.703523)
			(xy 191.814968 -305.693679) (xy 191.768952 -305.676227) (xy 191.726331 -305.65162) (xy 191.68821 -305.620495)
			(xy 191.655575 -305.583658) (xy 191.629272 -305.542062) (xy 191.609981 -305.496786) (xy 191.598204 -305.449002)
			(xy 191.594244 -305.399948) (xy 191.255396 -305.399948) (xy 191.254901 -305.424555) (xy 191.247006 -305.473132)
			(xy 191.231422 -305.519813) (xy 191.208551 -305.56339) (xy 191.178986 -305.602734) (xy 191.143493 -305.636826)
			(xy 191.10299 -305.664782) (xy 191.058528 -305.68588) (xy 191.011257 -305.699572) (xy 190.962402 -305.705504)
			(xy 190.913227 -305.703523) (xy 190.865008 -305.693679) (xy 190.818992 -305.676227) (xy 190.776371 -305.65162)
			(xy 190.73825 -305.620495) (xy 190.705615 -305.583658) (xy 190.679312 -305.542062) (xy 190.660021 -305.496786)
			(xy 190.648244 -305.449002) (xy 190.644284 -305.399948) (xy 190.305182 -305.399948) (xy 190.304687 -305.424555)
			(xy 190.296792 -305.473132) (xy 190.281208 -305.519813) (xy 190.258337 -305.56339) (xy 190.228772 -305.602734)
			(xy 190.193279 -305.636826) (xy 190.152776 -305.664782) (xy 190.108314 -305.68588) (xy 190.061043 -305.699572)
			(xy 190.012188 -305.705504) (xy 189.963013 -305.703523) (xy 189.914794 -305.693679) (xy 189.868778 -305.676227)
			(xy 189.826157 -305.65162) (xy 189.788036 -305.620495) (xy 189.755401 -305.583658) (xy 189.729098 -305.542062)
			(xy 189.709807 -305.496786) (xy 189.69803 -305.449002) (xy 189.69407 -305.399948) (xy 166.11727 -305.399948)
			(xy 166.11727 -305.874928) (xy 166.419288 -305.874928) (xy 166.423248 -305.825874) (xy 166.435025 -305.77809)
			(xy 166.454316 -305.732814) (xy 166.480619 -305.691218) (xy 166.513254 -305.654381) (xy 166.551375 -305.623256)
			(xy 166.593996 -305.598649) (xy 166.640012 -305.581197) (xy 166.688231 -305.571353) (xy 166.737406 -305.569372)
			(xy 166.786261 -305.575304) (xy 166.833532 -305.588996) (xy 166.877994 -305.610094) (xy 166.918497 -305.63805)
			(xy 166.95399 -305.672142) (xy 166.983555 -305.711486) (xy 167.006426 -305.755063) (xy 167.02201 -305.801744)
			(xy 167.029905 -305.850321) (xy 167.0304 -305.874928) (xy 167.369248 -305.874928) (xy 167.373208 -305.825874)
			(xy 167.384985 -305.77809) (xy 167.404276 -305.732814) (xy 167.430579 -305.691218) (xy 167.463214 -305.654381)
			(xy 167.501335 -305.623256) (xy 167.543956 -305.598649) (xy 167.589972 -305.581197) (xy 167.638191 -305.571353)
			(xy 167.687366 -305.569372) (xy 167.736221 -305.575304) (xy 167.783492 -305.588996) (xy 167.827954 -305.610094)
			(xy 167.868457 -305.63805) (xy 167.90395 -305.672142) (xy 167.933515 -305.711486) (xy 167.956386 -305.755063)
			(xy 167.97197 -305.801744) (xy 167.979865 -305.850321) (xy 167.98036 -305.874928) (xy 168.319208 -305.874928)
			(xy 168.323168 -305.825874) (xy 168.334945 -305.77809) (xy 168.354236 -305.732814) (xy 168.380539 -305.691218)
			(xy 168.413174 -305.654381) (xy 168.451295 -305.623256) (xy 168.493916 -305.598649) (xy 168.539932 -305.581197)
			(xy 168.588151 -305.571353) (xy 168.637326 -305.569372) (xy 168.686181 -305.575304) (xy 168.733452 -305.588996)
			(xy 168.777914 -305.610094) (xy 168.818417 -305.63805) (xy 168.85391 -305.672142) (xy 168.883475 -305.711486)
			(xy 168.906346 -305.755063) (xy 168.92193 -305.801744) (xy 168.929825 -305.850321) (xy 168.93032 -305.874928)
			(xy 169.269168 -305.874928) (xy 169.273128 -305.825874) (xy 169.284905 -305.77809) (xy 169.304196 -305.732814)
			(xy 169.330499 -305.691218) (xy 169.363134 -305.654381) (xy 169.401255 -305.623256) (xy 169.443876 -305.598649)
			(xy 169.489892 -305.581197) (xy 169.538111 -305.571353) (xy 169.587286 -305.569372) (xy 169.636141 -305.575304)
			(xy 169.683412 -305.588996) (xy 169.727874 -305.610094) (xy 169.768377 -305.63805) (xy 169.80387 -305.672142)
			(xy 169.833435 -305.711486) (xy 169.856306 -305.755063) (xy 169.87189 -305.801744) (xy 169.879785 -305.850321)
			(xy 169.88028 -305.874928) (xy 170.219128 -305.874928) (xy 170.223088 -305.825874) (xy 170.234865 -305.77809)
			(xy 170.254156 -305.732814) (xy 170.280459 -305.691218) (xy 170.313094 -305.654381) (xy 170.351215 -305.623256)
			(xy 170.393836 -305.598649) (xy 170.439852 -305.581197) (xy 170.488071 -305.571353) (xy 170.537246 -305.569372)
			(xy 170.586101 -305.575304) (xy 170.633372 -305.588996) (xy 170.677834 -305.610094) (xy 170.718337 -305.63805)
			(xy 170.75383 -305.672142) (xy 170.783395 -305.711486) (xy 170.806266 -305.755063) (xy 170.82185 -305.801744)
			(xy 170.829745 -305.850321) (xy 170.83024 -305.874928) (xy 171.169088 -305.874928) (xy 171.173048 -305.825874)
			(xy 171.184825 -305.77809) (xy 171.204116 -305.732814) (xy 171.230419 -305.691218) (xy 171.263054 -305.654381)
			(xy 171.301175 -305.623256) (xy 171.343796 -305.598649) (xy 171.389812 -305.581197) (xy 171.438031 -305.571353)
			(xy 171.487206 -305.569372) (xy 171.536061 -305.575304) (xy 171.583332 -305.588996) (xy 171.627794 -305.610094)
			(xy 171.668297 -305.63805) (xy 171.70379 -305.672142) (xy 171.733355 -305.711486) (xy 171.756226 -305.755063)
			(xy 171.77181 -305.801744) (xy 171.779705 -305.850321) (xy 171.7802 -305.874928) (xy 172.119048 -305.874928)
			(xy 172.123008 -305.825874) (xy 172.134785 -305.77809) (xy 172.154076 -305.732814) (xy 172.180379 -305.691218)
			(xy 172.213014 -305.654381) (xy 172.251135 -305.623256) (xy 172.293756 -305.598649) (xy 172.339772 -305.581197)
			(xy 172.387991 -305.571353) (xy 172.437166 -305.569372) (xy 172.486021 -305.575304) (xy 172.533292 -305.588996)
			(xy 172.577754 -305.610094) (xy 172.618257 -305.63805) (xy 172.65375 -305.672142) (xy 172.683315 -305.711486)
			(xy 172.706186 -305.755063) (xy 172.72177 -305.801744) (xy 172.729665 -305.850321) (xy 172.73016 -305.874928)
			(xy 173.069262 -305.874928) (xy 173.073222 -305.825874) (xy 173.084999 -305.77809) (xy 173.10429 -305.732814)
			(xy 173.130593 -305.691218) (xy 173.163228 -305.654381) (xy 173.201349 -305.623256) (xy 173.24397 -305.598649)
			(xy 173.289986 -305.581197) (xy 173.338205 -305.571353) (xy 173.38738 -305.569372) (xy 173.436235 -305.575304)
			(xy 173.483506 -305.588996) (xy 173.527968 -305.610094) (xy 173.568471 -305.63805) (xy 173.603964 -305.672142)
			(xy 173.633529 -305.711486) (xy 173.6564 -305.755063) (xy 173.671984 -305.801744) (xy 173.679879 -305.850321)
			(xy 173.680374 -305.874928) (xy 174.019222 -305.874928) (xy 174.023182 -305.825874) (xy 174.034959 -305.77809)
			(xy 174.05425 -305.732814) (xy 174.080553 -305.691218) (xy 174.113188 -305.654381) (xy 174.151309 -305.623256)
			(xy 174.19393 -305.598649) (xy 174.239946 -305.581197) (xy 174.288165 -305.571353) (xy 174.33734 -305.569372)
			(xy 174.386195 -305.575304) (xy 174.433466 -305.588996) (xy 174.477928 -305.610094) (xy 174.518431 -305.63805)
			(xy 174.553924 -305.672142) (xy 174.583489 -305.711486) (xy 174.60636 -305.755063) (xy 174.621944 -305.801744)
			(xy 174.629839 -305.850321) (xy 174.630334 -305.874928) (xy 175.919142 -305.874928) (xy 175.923102 -305.825874)
			(xy 175.934879 -305.77809) (xy 175.95417 -305.732814) (xy 175.980473 -305.691218) (xy 176.013108 -305.654381)
			(xy 176.051229 -305.623256) (xy 176.09385 -305.598649) (xy 176.139866 -305.581197) (xy 176.188085 -305.571353)
			(xy 176.23726 -305.569372) (xy 176.286115 -305.575304) (xy 176.333386 -305.588996) (xy 176.377848 -305.610094)
			(xy 176.418351 -305.63805) (xy 176.453844 -305.672142) (xy 176.483409 -305.711486) (xy 176.50628 -305.755063)
			(xy 176.521864 -305.801744) (xy 176.529759 -305.850321) (xy 176.530254 -305.874928) (xy 176.869102 -305.874928)
			(xy 176.873062 -305.825874) (xy 176.884839 -305.77809) (xy 176.90413 -305.732814) (xy 176.930433 -305.691218)
			(xy 176.963068 -305.654381) (xy 177.001189 -305.623256) (xy 177.04381 -305.598649) (xy 177.089826 -305.581197)
			(xy 177.138045 -305.571353) (xy 177.18722 -305.569372) (xy 177.236075 -305.575304) (xy 177.283346 -305.588996)
			(xy 177.327808 -305.610094) (xy 177.368311 -305.63805) (xy 177.403804 -305.672142) (xy 177.433369 -305.711486)
			(xy 177.45624 -305.755063) (xy 177.471824 -305.801744) (xy 177.479719 -305.850321) (xy 177.480214 -305.874928)
			(xy 177.819062 -305.874928) (xy 177.823022 -305.825874) (xy 177.834799 -305.77809) (xy 177.85409 -305.732814)
			(xy 177.880393 -305.691218) (xy 177.913028 -305.654381) (xy 177.951149 -305.623256) (xy 177.99377 -305.598649)
			(xy 178.039786 -305.581197) (xy 178.088005 -305.571353) (xy 178.13718 -305.569372) (xy 178.186035 -305.575304)
			(xy 178.233306 -305.588996) (xy 178.277768 -305.610094) (xy 178.318271 -305.63805) (xy 178.353764 -305.672142)
			(xy 178.383329 -305.711486) (xy 178.4062 -305.755063) (xy 178.421784 -305.801744) (xy 178.429679 -305.850321)
			(xy 178.430174 -305.874928) (xy 178.769276 -305.874928) (xy 178.773236 -305.825874) (xy 178.785013 -305.77809)
			(xy 178.804304 -305.732814) (xy 178.830607 -305.691218) (xy 178.863242 -305.654381) (xy 178.901363 -305.623256)
			(xy 178.943984 -305.598649) (xy 178.99 -305.581197) (xy 179.038219 -305.571353) (xy 179.087394 -305.569372)
			(xy 179.136249 -305.575304) (xy 179.18352 -305.588996) (xy 179.227982 -305.610094) (xy 179.268485 -305.63805)
			(xy 179.303978 -305.672142) (xy 179.333543 -305.711486) (xy 179.356414 -305.755063) (xy 179.371998 -305.801744)
			(xy 179.379893 -305.850321) (xy 179.380388 -305.874928) (xy 179.719236 -305.874928) (xy 179.723196 -305.825874)
			(xy 179.734973 -305.77809) (xy 179.754264 -305.732814) (xy 179.780567 -305.691218) (xy 179.813202 -305.654381)
			(xy 179.851323 -305.623256) (xy 179.893944 -305.598649) (xy 179.93996 -305.581197) (xy 179.988179 -305.571353)
			(xy 180.037354 -305.569372) (xy 180.086209 -305.575304) (xy 180.13348 -305.588996) (xy 180.177942 -305.610094)
			(xy 180.218445 -305.63805) (xy 180.253938 -305.672142) (xy 180.283503 -305.711486) (xy 180.306374 -305.755063)
			(xy 180.321958 -305.801744) (xy 180.329853 -305.850321) (xy 180.330348 -305.874928) (xy 180.669196 -305.874928)
			(xy 180.673156 -305.825874) (xy 180.684933 -305.77809) (xy 180.704224 -305.732814) (xy 180.730527 -305.691218)
			(xy 180.763162 -305.654381) (xy 180.801283 -305.623256) (xy 180.843904 -305.598649) (xy 180.88992 -305.581197)
			(xy 180.938139 -305.571353) (xy 180.987314 -305.569372) (xy 181.036169 -305.575304) (xy 181.08344 -305.588996)
			(xy 181.127902 -305.610094) (xy 181.168405 -305.63805) (xy 181.203898 -305.672142) (xy 181.233463 -305.711486)
			(xy 181.256334 -305.755063) (xy 181.271918 -305.801744) (xy 181.279813 -305.850321) (xy 181.280308 -305.874928)
			(xy 181.619156 -305.874928) (xy 181.623116 -305.825874) (xy 181.634893 -305.77809) (xy 181.654184 -305.732814)
			(xy 181.680487 -305.691218) (xy 181.713122 -305.654381) (xy 181.751243 -305.623256) (xy 181.793864 -305.598649)
			(xy 181.83988 -305.581197) (xy 181.888099 -305.571353) (xy 181.937274 -305.569372) (xy 181.986129 -305.575304)
			(xy 182.0334 -305.588996) (xy 182.077862 -305.610094) (xy 182.118365 -305.63805) (xy 182.153858 -305.672142)
			(xy 182.183423 -305.711486) (xy 182.206294 -305.755063) (xy 182.221878 -305.801744) (xy 182.229773 -305.850321)
			(xy 182.230268 -305.874928) (xy 182.569116 -305.874928) (xy 182.573076 -305.825874) (xy 182.584853 -305.77809)
			(xy 182.604144 -305.732814) (xy 182.630447 -305.691218) (xy 182.663082 -305.654381) (xy 182.701203 -305.623256)
			(xy 182.743824 -305.598649) (xy 182.78984 -305.581197) (xy 182.838059 -305.571353) (xy 182.887234 -305.569372)
			(xy 182.936089 -305.575304) (xy 182.98336 -305.588996) (xy 183.027822 -305.610094) (xy 183.068325 -305.63805)
			(xy 183.103818 -305.672142) (xy 183.133383 -305.711486) (xy 183.156254 -305.755063) (xy 183.171838 -305.801744)
			(xy 183.179733 -305.850321) (xy 183.180228 -305.874928) (xy 183.519076 -305.874928) (xy 183.523036 -305.825874)
			(xy 183.534813 -305.77809) (xy 183.554104 -305.732814) (xy 183.580407 -305.691218) (xy 183.613042 -305.654381)
			(xy 183.651163 -305.623256) (xy 183.693784 -305.598649) (xy 183.7398 -305.581197) (xy 183.788019 -305.571353)
			(xy 183.837194 -305.569372) (xy 183.886049 -305.575304) (xy 183.93332 -305.588996) (xy 183.977782 -305.610094)
			(xy 184.018285 -305.63805) (xy 184.053778 -305.672142) (xy 184.083343 -305.711486) (xy 184.106214 -305.755063)
			(xy 184.121798 -305.801744) (xy 184.129693 -305.850321) (xy 184.130188 -305.874928) (xy 184.469036 -305.874928)
			(xy 184.472996 -305.825874) (xy 184.484773 -305.77809) (xy 184.504064 -305.732814) (xy 184.530367 -305.691218)
			(xy 184.563002 -305.654381) (xy 184.601123 -305.623256) (xy 184.643744 -305.598649) (xy 184.68976 -305.581197)
			(xy 184.737979 -305.571353) (xy 184.787154 -305.569372) (xy 184.836009 -305.575304) (xy 184.88328 -305.588996)
			(xy 184.927742 -305.610094) (xy 184.968245 -305.63805) (xy 185.003738 -305.672142) (xy 185.033303 -305.711486)
			(xy 185.056174 -305.755063) (xy 185.071758 -305.801744) (xy 185.079653 -305.850321) (xy 185.080148 -305.874928)
			(xy 185.41925 -305.874928) (xy 185.42321 -305.825874) (xy 185.434987 -305.77809) (xy 185.454278 -305.732814)
			(xy 185.480581 -305.691218) (xy 185.513216 -305.654381) (xy 185.551337 -305.623256) (xy 185.593958 -305.598649)
			(xy 185.639974 -305.581197) (xy 185.688193 -305.571353) (xy 185.737368 -305.569372) (xy 185.786223 -305.575304)
			(xy 185.833494 -305.588996) (xy 185.877956 -305.610094) (xy 185.918459 -305.63805) (xy 185.953952 -305.672142)
			(xy 185.983517 -305.711486) (xy 186.006388 -305.755063) (xy 186.021972 -305.801744) (xy 186.029867 -305.850321)
			(xy 186.030362 -305.874928) (xy 186.36921 -305.874928) (xy 186.37317 -305.825874) (xy 186.384947 -305.77809)
			(xy 186.404238 -305.732814) (xy 186.430541 -305.691218) (xy 186.463176 -305.654381) (xy 186.501297 -305.623256)
			(xy 186.543918 -305.598649) (xy 186.589934 -305.581197) (xy 186.638153 -305.571353) (xy 186.687328 -305.569372)
			(xy 186.736183 -305.575304) (xy 186.783454 -305.588996) (xy 186.827916 -305.610094) (xy 186.868419 -305.63805)
			(xy 186.903912 -305.672142) (xy 186.933477 -305.711486) (xy 186.956348 -305.755063) (xy 186.971932 -305.801744)
			(xy 186.979827 -305.850321) (xy 186.980322 -305.874928) (xy 187.31917 -305.874928) (xy 187.32313 -305.825874)
			(xy 187.334907 -305.77809) (xy 187.354198 -305.732814) (xy 187.380501 -305.691218) (xy 187.413136 -305.654381)
			(xy 187.451257 -305.623256) (xy 187.493878 -305.598649) (xy 187.539894 -305.581197) (xy 187.588113 -305.571353)
			(xy 187.637288 -305.569372) (xy 187.686143 -305.575304) (xy 187.733414 -305.588996) (xy 187.777876 -305.610094)
			(xy 187.818379 -305.63805) (xy 187.853872 -305.672142) (xy 187.883437 -305.711486) (xy 187.906308 -305.755063)
			(xy 187.921892 -305.801744) (xy 187.929787 -305.850321) (xy 187.930282 -305.874928) (xy 188.26913 -305.874928)
			(xy 188.27309 -305.825874) (xy 188.284867 -305.77809) (xy 188.304158 -305.732814) (xy 188.330461 -305.691218)
			(xy 188.363096 -305.654381) (xy 188.401217 -305.623256) (xy 188.443838 -305.598649) (xy 188.489854 -305.581197)
			(xy 188.538073 -305.571353) (xy 188.587248 -305.569372) (xy 188.636103 -305.575304) (xy 188.683374 -305.588996)
			(xy 188.727836 -305.610094) (xy 188.768339 -305.63805) (xy 188.803832 -305.672142) (xy 188.833397 -305.711486)
			(xy 188.856268 -305.755063) (xy 188.871852 -305.801744) (xy 188.879747 -305.850321) (xy 188.880242 -305.874928)
			(xy 188.879747 -305.899535) (xy 188.871852 -305.948112) (xy 188.856268 -305.994793) (xy 188.833397 -306.03837)
			(xy 188.803832 -306.077714) (xy 188.768339 -306.111806) (xy 188.727836 -306.139762) (xy 188.683374 -306.16086)
			(xy 188.636103 -306.174552) (xy 188.587248 -306.180484) (xy 188.538073 -306.178503) (xy 188.489854 -306.168659)
			(xy 188.443838 -306.151207) (xy 188.401217 -306.1266) (xy 188.363096 -306.095475) (xy 188.330461 -306.058638)
			(xy 188.304158 -306.017042) (xy 188.284867 -305.971766) (xy 188.27309 -305.923982) (xy 188.26913 -305.874928)
			(xy 187.930282 -305.874928) (xy 187.929787 -305.899535) (xy 187.921892 -305.948112) (xy 187.906308 -305.994793)
			(xy 187.883437 -306.03837) (xy 187.853872 -306.077714) (xy 187.818379 -306.111806) (xy 187.777876 -306.139762)
			(xy 187.733414 -306.16086) (xy 187.686143 -306.174552) (xy 187.637288 -306.180484) (xy 187.588113 -306.178503)
			(xy 187.539894 -306.168659) (xy 187.493878 -306.151207) (xy 187.451257 -306.1266) (xy 187.413136 -306.095475)
			(xy 187.380501 -306.058638) (xy 187.354198 -306.017042) (xy 187.334907 -305.971766) (xy 187.32313 -305.923982)
			(xy 187.31917 -305.874928) (xy 186.980322 -305.874928) (xy 186.979827 -305.899535) (xy 186.971932 -305.948112)
			(xy 186.956348 -305.994793) (xy 186.933477 -306.03837) (xy 186.903912 -306.077714) (xy 186.868419 -306.111806)
			(xy 186.827916 -306.139762) (xy 186.783454 -306.16086) (xy 186.736183 -306.174552) (xy 186.687328 -306.180484)
			(xy 186.638153 -306.178503) (xy 186.589934 -306.168659) (xy 186.543918 -306.151207) (xy 186.501297 -306.1266)
			(xy 186.463176 -306.095475) (xy 186.430541 -306.058638) (xy 186.404238 -306.017042) (xy 186.384947 -305.971766)
			(xy 186.37317 -305.923982) (xy 186.36921 -305.874928) (xy 186.030362 -305.874928) (xy 186.029867 -305.899535)
			(xy 186.021972 -305.948112) (xy 186.006388 -305.994793) (xy 185.983517 -306.03837) (xy 185.953952 -306.077714)
			(xy 185.918459 -306.111806) (xy 185.877956 -306.139762) (xy 185.833494 -306.16086) (xy 185.786223 -306.174552)
			(xy 185.737368 -306.180484) (xy 185.688193 -306.178503) (xy 185.639974 -306.168659) (xy 185.593958 -306.151207)
			(xy 185.551337 -306.1266) (xy 185.513216 -306.095475) (xy 185.480581 -306.058638) (xy 185.454278 -306.017042)
			(xy 185.434987 -305.971766) (xy 185.42321 -305.923982) (xy 185.41925 -305.874928) (xy 185.080148 -305.874928)
			(xy 185.079653 -305.899535) (xy 185.071758 -305.948112) (xy 185.056174 -305.994793) (xy 185.033303 -306.03837)
			(xy 185.003738 -306.077714) (xy 184.968245 -306.111806) (xy 184.927742 -306.139762) (xy 184.88328 -306.16086)
			(xy 184.836009 -306.174552) (xy 184.787154 -306.180484) (xy 184.737979 -306.178503) (xy 184.68976 -306.168659)
			(xy 184.643744 -306.151207) (xy 184.601123 -306.1266) (xy 184.563002 -306.095475) (xy 184.530367 -306.058638)
			(xy 184.504064 -306.017042) (xy 184.484773 -305.971766) (xy 184.472996 -305.923982) (xy 184.469036 -305.874928)
			(xy 184.130188 -305.874928) (xy 184.129693 -305.899535) (xy 184.121798 -305.948112) (xy 184.106214 -305.994793)
			(xy 184.083343 -306.03837) (xy 184.053778 -306.077714) (xy 184.018285 -306.111806) (xy 183.977782 -306.139762)
			(xy 183.93332 -306.16086) (xy 183.886049 -306.174552) (xy 183.837194 -306.180484) (xy 183.788019 -306.178503)
			(xy 183.7398 -306.168659) (xy 183.693784 -306.151207) (xy 183.651163 -306.1266) (xy 183.613042 -306.095475)
			(xy 183.580407 -306.058638) (xy 183.554104 -306.017042) (xy 183.534813 -305.971766) (xy 183.523036 -305.923982)
			(xy 183.519076 -305.874928) (xy 183.180228 -305.874928) (xy 183.179733 -305.899535) (xy 183.171838 -305.948112)
			(xy 183.156254 -305.994793) (xy 183.133383 -306.03837) (xy 183.103818 -306.077714) (xy 183.068325 -306.111806)
			(xy 183.027822 -306.139762) (xy 182.98336 -306.16086) (xy 182.936089 -306.174552) (xy 182.887234 -306.180484)
			(xy 182.838059 -306.178503) (xy 182.78984 -306.168659) (xy 182.743824 -306.151207) (xy 182.701203 -306.1266)
			(xy 182.663082 -306.095475) (xy 182.630447 -306.058638) (xy 182.604144 -306.017042) (xy 182.584853 -305.971766)
			(xy 182.573076 -305.923982) (xy 182.569116 -305.874928) (xy 182.230268 -305.874928) (xy 182.229773 -305.899535)
			(xy 182.221878 -305.948112) (xy 182.206294 -305.994793) (xy 182.183423 -306.03837) (xy 182.153858 -306.077714)
			(xy 182.118365 -306.111806) (xy 182.077862 -306.139762) (xy 182.0334 -306.16086) (xy 181.986129 -306.174552)
			(xy 181.937274 -306.180484) (xy 181.888099 -306.178503) (xy 181.83988 -306.168659) (xy 181.793864 -306.151207)
			(xy 181.751243 -306.1266) (xy 181.713122 -306.095475) (xy 181.680487 -306.058638) (xy 181.654184 -306.017042)
			(xy 181.634893 -305.971766) (xy 181.623116 -305.923982) (xy 181.619156 -305.874928) (xy 181.280308 -305.874928)
			(xy 181.279813 -305.899535) (xy 181.271918 -305.948112) (xy 181.256334 -305.994793) (xy 181.233463 -306.03837)
			(xy 181.203898 -306.077714) (xy 181.168405 -306.111806) (xy 181.127902 -306.139762) (xy 181.08344 -306.16086)
			(xy 181.036169 -306.174552) (xy 180.987314 -306.180484) (xy 180.938139 -306.178503) (xy 180.88992 -306.168659)
			(xy 180.843904 -306.151207) (xy 180.801283 -306.1266) (xy 180.763162 -306.095475) (xy 180.730527 -306.058638)
			(xy 180.704224 -306.017042) (xy 180.684933 -305.971766) (xy 180.673156 -305.923982) (xy 180.669196 -305.874928)
			(xy 180.330348 -305.874928) (xy 180.329853 -305.899535) (xy 180.321958 -305.948112) (xy 180.306374 -305.994793)
			(xy 180.283503 -306.03837) (xy 180.253938 -306.077714) (xy 180.218445 -306.111806) (xy 180.177942 -306.139762)
			(xy 180.13348 -306.16086) (xy 180.086209 -306.174552) (xy 180.037354 -306.180484) (xy 179.988179 -306.178503)
			(xy 179.93996 -306.168659) (xy 179.893944 -306.151207) (xy 179.851323 -306.1266) (xy 179.813202 -306.095475)
			(xy 179.780567 -306.058638) (xy 179.754264 -306.017042) (xy 179.734973 -305.971766) (xy 179.723196 -305.923982)
			(xy 179.719236 -305.874928) (xy 179.380388 -305.874928) (xy 179.379893 -305.899535) (xy 179.371998 -305.948112)
			(xy 179.356414 -305.994793) (xy 179.333543 -306.03837) (xy 179.303978 -306.077714) (xy 179.268485 -306.111806)
			(xy 179.227982 -306.139762) (xy 179.18352 -306.16086) (xy 179.136249 -306.174552) (xy 179.087394 -306.180484)
			(xy 179.038219 -306.178503) (xy 178.99 -306.168659) (xy 178.943984 -306.151207) (xy 178.901363 -306.1266)
			(xy 178.863242 -306.095475) (xy 178.830607 -306.058638) (xy 178.804304 -306.017042) (xy 178.785013 -305.971766)
			(xy 178.773236 -305.923982) (xy 178.769276 -305.874928) (xy 178.430174 -305.874928) (xy 178.429679 -305.899535)
			(xy 178.421784 -305.948112) (xy 178.4062 -305.994793) (xy 178.383329 -306.03837) (xy 178.353764 -306.077714)
			(xy 178.318271 -306.111806) (xy 178.277768 -306.139762) (xy 178.233306 -306.16086) (xy 178.186035 -306.174552)
			(xy 178.13718 -306.180484) (xy 178.088005 -306.178503) (xy 178.039786 -306.168659) (xy 177.99377 -306.151207)
			(xy 177.951149 -306.1266) (xy 177.913028 -306.095475) (xy 177.880393 -306.058638) (xy 177.85409 -306.017042)
			(xy 177.834799 -305.971766) (xy 177.823022 -305.923982) (xy 177.819062 -305.874928) (xy 177.480214 -305.874928)
			(xy 177.479719 -305.899535) (xy 177.471824 -305.948112) (xy 177.45624 -305.994793) (xy 177.433369 -306.03837)
			(xy 177.403804 -306.077714) (xy 177.368311 -306.111806) (xy 177.327808 -306.139762) (xy 177.283346 -306.16086)
			(xy 177.236075 -306.174552) (xy 177.18722 -306.180484) (xy 177.138045 -306.178503) (xy 177.089826 -306.168659)
			(xy 177.04381 -306.151207) (xy 177.001189 -306.1266) (xy 176.963068 -306.095475) (xy 176.930433 -306.058638)
			(xy 176.90413 -306.017042) (xy 176.884839 -305.971766) (xy 176.873062 -305.923982) (xy 176.869102 -305.874928)
			(xy 176.530254 -305.874928) (xy 176.529759 -305.899535) (xy 176.521864 -305.948112) (xy 176.50628 -305.994793)
			(xy 176.483409 -306.03837) (xy 176.453844 -306.077714) (xy 176.418351 -306.111806) (xy 176.377848 -306.139762)
			(xy 176.333386 -306.16086) (xy 176.286115 -306.174552) (xy 176.23726 -306.180484) (xy 176.188085 -306.178503)
			(xy 176.139866 -306.168659) (xy 176.09385 -306.151207) (xy 176.051229 -306.1266) (xy 176.013108 -306.095475)
			(xy 175.980473 -306.058638) (xy 175.95417 -306.017042) (xy 175.934879 -305.971766) (xy 175.923102 -305.923982)
			(xy 175.919142 -305.874928) (xy 174.630334 -305.874928) (xy 174.629839 -305.899535) (xy 174.621944 -305.948112)
			(xy 174.60636 -305.994793) (xy 174.583489 -306.03837) (xy 174.553924 -306.077714) (xy 174.518431 -306.111806)
			(xy 174.477928 -306.139762) (xy 174.433466 -306.16086) (xy 174.386195 -306.174552) (xy 174.33734 -306.180484)
			(xy 174.288165 -306.178503) (xy 174.239946 -306.168659) (xy 174.19393 -306.151207) (xy 174.151309 -306.1266)
			(xy 174.113188 -306.095475) (xy 174.080553 -306.058638) (xy 174.05425 -306.017042) (xy 174.034959 -305.971766)
			(xy 174.023182 -305.923982) (xy 174.019222 -305.874928) (xy 173.680374 -305.874928) (xy 173.679879 -305.899535)
			(xy 173.671984 -305.948112) (xy 173.6564 -305.994793) (xy 173.633529 -306.03837) (xy 173.603964 -306.077714)
			(xy 173.568471 -306.111806) (xy 173.527968 -306.139762) (xy 173.483506 -306.16086) (xy 173.436235 -306.174552)
			(xy 173.38738 -306.180484) (xy 173.338205 -306.178503) (xy 173.289986 -306.168659) (xy 173.24397 -306.151207)
			(xy 173.201349 -306.1266) (xy 173.163228 -306.095475) (xy 173.130593 -306.058638) (xy 173.10429 -306.017042)
			(xy 173.084999 -305.971766) (xy 173.073222 -305.923982) (xy 173.069262 -305.874928) (xy 172.73016 -305.874928)
			(xy 172.729665 -305.899535) (xy 172.72177 -305.948112) (xy 172.706186 -305.994793) (xy 172.683315 -306.03837)
			(xy 172.65375 -306.077714) (xy 172.618257 -306.111806) (xy 172.577754 -306.139762) (xy 172.533292 -306.16086)
			(xy 172.486021 -306.174552) (xy 172.437166 -306.180484) (xy 172.387991 -306.178503) (xy 172.339772 -306.168659)
			(xy 172.293756 -306.151207) (xy 172.251135 -306.1266) (xy 172.213014 -306.095475) (xy 172.180379 -306.058638)
			(xy 172.154076 -306.017042) (xy 172.134785 -305.971766) (xy 172.123008 -305.923982) (xy 172.119048 -305.874928)
			(xy 171.7802 -305.874928) (xy 171.779705 -305.899535) (xy 171.77181 -305.948112) (xy 171.756226 -305.994793)
			(xy 171.733355 -306.03837) (xy 171.70379 -306.077714) (xy 171.668297 -306.111806) (xy 171.627794 -306.139762)
			(xy 171.583332 -306.16086) (xy 171.536061 -306.174552) (xy 171.487206 -306.180484) (xy 171.438031 -306.178503)
			(xy 171.389812 -306.168659) (xy 171.343796 -306.151207) (xy 171.301175 -306.1266) (xy 171.263054 -306.095475)
			(xy 171.230419 -306.058638) (xy 171.204116 -306.017042) (xy 171.184825 -305.971766) (xy 171.173048 -305.923982)
			(xy 171.169088 -305.874928) (xy 170.83024 -305.874928) (xy 170.829745 -305.899535) (xy 170.82185 -305.948112)
			(xy 170.806266 -305.994793) (xy 170.783395 -306.03837) (xy 170.75383 -306.077714) (xy 170.718337 -306.111806)
			(xy 170.677834 -306.139762) (xy 170.633372 -306.16086) (xy 170.586101 -306.174552) (xy 170.537246 -306.180484)
			(xy 170.488071 -306.178503) (xy 170.439852 -306.168659) (xy 170.393836 -306.151207) (xy 170.351215 -306.1266)
			(xy 170.313094 -306.095475) (xy 170.280459 -306.058638) (xy 170.254156 -306.017042) (xy 170.234865 -305.971766)
			(xy 170.223088 -305.923982) (xy 170.219128 -305.874928) (xy 169.88028 -305.874928) (xy 169.879785 -305.899535)
			(xy 169.87189 -305.948112) (xy 169.856306 -305.994793) (xy 169.833435 -306.03837) (xy 169.80387 -306.077714)
			(xy 169.768377 -306.111806) (xy 169.727874 -306.139762) (xy 169.683412 -306.16086) (xy 169.636141 -306.174552)
			(xy 169.587286 -306.180484) (xy 169.538111 -306.178503) (xy 169.489892 -306.168659) (xy 169.443876 -306.151207)
			(xy 169.401255 -306.1266) (xy 169.363134 -306.095475) (xy 169.330499 -306.058638) (xy 169.304196 -306.017042)
			(xy 169.284905 -305.971766) (xy 169.273128 -305.923982) (xy 169.269168 -305.874928) (xy 168.93032 -305.874928)
			(xy 168.929825 -305.899535) (xy 168.92193 -305.948112) (xy 168.906346 -305.994793) (xy 168.883475 -306.03837)
			(xy 168.85391 -306.077714) (xy 168.818417 -306.111806) (xy 168.777914 -306.139762) (xy 168.733452 -306.16086)
			(xy 168.686181 -306.174552) (xy 168.637326 -306.180484) (xy 168.588151 -306.178503) (xy 168.539932 -306.168659)
			(xy 168.493916 -306.151207) (xy 168.451295 -306.1266) (xy 168.413174 -306.095475) (xy 168.380539 -306.058638)
			(xy 168.354236 -306.017042) (xy 168.334945 -305.971766) (xy 168.323168 -305.923982) (xy 168.319208 -305.874928)
			(xy 167.98036 -305.874928) (xy 167.979865 -305.899535) (xy 167.97197 -305.948112) (xy 167.956386 -305.994793)
			(xy 167.933515 -306.03837) (xy 167.90395 -306.077714) (xy 167.868457 -306.111806) (xy 167.827954 -306.139762)
			(xy 167.783492 -306.16086) (xy 167.736221 -306.174552) (xy 167.687366 -306.180484) (xy 167.638191 -306.178503)
			(xy 167.589972 -306.168659) (xy 167.543956 -306.151207) (xy 167.501335 -306.1266) (xy 167.463214 -306.095475)
			(xy 167.430579 -306.058638) (xy 167.404276 -306.017042) (xy 167.384985 -305.971766) (xy 167.373208 -305.923982)
			(xy 167.369248 -305.874928) (xy 167.0304 -305.874928) (xy 167.029905 -305.899535) (xy 167.02201 -305.948112)
			(xy 167.006426 -305.994793) (xy 166.983555 -306.03837) (xy 166.95399 -306.077714) (xy 166.918497 -306.111806)
			(xy 166.877994 -306.139762) (xy 166.833532 -306.16086) (xy 166.786261 -306.174552) (xy 166.737406 -306.180484)
			(xy 166.688231 -306.178503) (xy 166.640012 -306.168659) (xy 166.593996 -306.151207) (xy 166.551375 -306.1266)
			(xy 166.513254 -306.095475) (xy 166.480619 -306.058638) (xy 166.454316 -306.017042) (xy 166.435025 -305.971766)
			(xy 166.423248 -305.923982) (xy 166.419288 -305.874928) (xy 166.11727 -305.874928) (xy 166.11727 -306.349908)
			(xy 189.69407 -306.349908) (xy 189.69803 -306.300854) (xy 189.709807 -306.25307) (xy 189.729098 -306.207794)
			(xy 189.755401 -306.166198) (xy 189.788036 -306.129361) (xy 189.826157 -306.098236) (xy 189.868778 -306.073629)
			(xy 189.914794 -306.056177) (xy 189.963013 -306.046333) (xy 190.012188 -306.044352) (xy 190.061043 -306.050284)
			(xy 190.108314 -306.063976) (xy 190.152776 -306.085074) (xy 190.193279 -306.11303) (xy 190.228772 -306.147122)
			(xy 190.258337 -306.186466) (xy 190.281208 -306.230043) (xy 190.296792 -306.276724) (xy 190.304687 -306.325301)
			(xy 190.305182 -306.349908) (xy 190.304687 -306.374515) (xy 190.304508 -306.375616) (xy 190.62344 -306.375616)
			(xy 190.62344 -306.3242) (xy 190.631483 -306.273418) (xy 190.647371 -306.224519) (xy 190.670714 -306.178707)
			(xy 190.700935 -306.137111) (xy 190.737291 -306.100755) (xy 190.778887 -306.070534) (xy 190.824699 -306.047191)
			(xy 190.873598 -306.031303) (xy 190.92438 -306.02326) (xy 190.975796 -306.02326) (xy 191.026578 -306.031303)
			(xy 191.075477 -306.047191) (xy 191.121289 -306.070534) (xy 191.162885 -306.100755) (xy 191.199241 -306.137111)
			(xy 191.229462 -306.178707) (xy 191.252805 -306.224519) (xy 191.268693 -306.273418) (xy 191.276736 -306.3242)
			(xy 191.27724 -306.349908) (xy 191.276736 -306.375616) (xy 191.5734 -306.375616) (xy 191.5734 -306.3242)
			(xy 191.581443 -306.273418) (xy 191.597331 -306.224519) (xy 191.620674 -306.178707) (xy 191.650895 -306.137111)
			(xy 191.687251 -306.100755) (xy 191.728847 -306.070534) (xy 191.774659 -306.047191) (xy 191.823558 -306.031303)
			(xy 191.87434 -306.02326) (xy 191.925756 -306.02326) (xy 191.976538 -306.031303) (xy 192.025437 -306.047191)
			(xy 192.071249 -306.070534) (xy 192.112845 -306.100755) (xy 192.149201 -306.137111) (xy 192.179422 -306.178707)
			(xy 192.202765 -306.224519) (xy 192.218653 -306.273418) (xy 192.226696 -306.3242) (xy 192.2272 -306.349908)
			(xy 192.544204 -306.349908) (xy 192.548164 -306.300854) (xy 192.559941 -306.25307) (xy 192.579232 -306.207794)
			(xy 192.605535 -306.166198) (xy 192.63817 -306.129361) (xy 192.676291 -306.098236) (xy 192.718912 -306.073629)
			(xy 192.764928 -306.056177) (xy 192.813147 -306.046333) (xy 192.862322 -306.044352) (xy 192.911177 -306.050284)
			(xy 192.958448 -306.063976) (xy 193.00291 -306.085074) (xy 193.043413 -306.11303) (xy 193.078906 -306.147122)
			(xy 193.108471 -306.186466) (xy 193.131342 -306.230043) (xy 193.146926 -306.276724) (xy 193.154821 -306.325301)
			(xy 193.155316 -306.349908) (xy 193.494164 -306.349908) (xy 193.498124 -306.300854) (xy 193.509901 -306.25307)
			(xy 193.529192 -306.207794) (xy 193.555495 -306.166198) (xy 193.58813 -306.129361) (xy 193.626251 -306.098236)
			(xy 193.668872 -306.073629) (xy 193.714888 -306.056177) (xy 193.763107 -306.046333) (xy 193.812282 -306.044352)
			(xy 193.861137 -306.050284) (xy 193.908408 -306.063976) (xy 193.95287 -306.085074) (xy 193.993373 -306.11303)
			(xy 194.028866 -306.147122) (xy 194.058431 -306.186466) (xy 194.081302 -306.230043) (xy 194.096886 -306.276724)
			(xy 194.104781 -306.325301) (xy 194.105276 -306.349908) (xy 194.444124 -306.349908) (xy 194.448084 -306.300854)
			(xy 194.459861 -306.25307) (xy 194.479152 -306.207794) (xy 194.505455 -306.166198) (xy 194.53809 -306.129361)
			(xy 194.576211 -306.098236) (xy 194.618832 -306.073629) (xy 194.664848 -306.056177) (xy 194.713067 -306.046333)
			(xy 194.762242 -306.044352) (xy 194.811097 -306.050284) (xy 194.858368 -306.063976) (xy 194.90283 -306.085074)
			(xy 194.943333 -306.11303) (xy 194.978826 -306.147122) (xy 195.008391 -306.186466) (xy 195.031262 -306.230043)
			(xy 195.046846 -306.276724) (xy 195.054741 -306.325301) (xy 195.055236 -306.349908) (xy 195.394084 -306.349908)
			(xy 195.398044 -306.300854) (xy 195.409821 -306.25307) (xy 195.429112 -306.207794) (xy 195.455415 -306.166198)
			(xy 195.48805 -306.129361) (xy 195.526171 -306.098236) (xy 195.568792 -306.073629) (xy 195.614808 -306.056177)
			(xy 195.663027 -306.046333) (xy 195.712202 -306.044352) (xy 195.761057 -306.050284) (xy 195.808328 -306.063976)
			(xy 195.85279 -306.085074) (xy 195.893293 -306.11303) (xy 195.928786 -306.147122) (xy 195.958351 -306.186466)
			(xy 195.981222 -306.230043) (xy 195.996806 -306.276724) (xy 196.004701 -306.325301) (xy 196.005196 -306.349908)
			(xy 196.344044 -306.349908) (xy 196.348004 -306.300854) (xy 196.359781 -306.25307) (xy 196.379072 -306.207794)
			(xy 196.405375 -306.166198) (xy 196.43801 -306.129361) (xy 196.476131 -306.098236) (xy 196.518752 -306.073629)
			(xy 196.564768 -306.056177) (xy 196.612987 -306.046333) (xy 196.662162 -306.044352) (xy 196.711017 -306.050284)
			(xy 196.758288 -306.063976) (xy 196.80275 -306.085074) (xy 196.843253 -306.11303) (xy 196.878746 -306.147122)
			(xy 196.908311 -306.186466) (xy 196.931182 -306.230043) (xy 196.946766 -306.276724) (xy 196.954661 -306.325301)
			(xy 196.955156 -306.349908) (xy 196.954661 -306.374515) (xy 196.954482 -306.375616) (xy 197.273414 -306.375616)
			(xy 197.273414 -306.3242) (xy 197.281457 -306.273418) (xy 197.297345 -306.224519) (xy 197.320688 -306.178707)
			(xy 197.350909 -306.137111) (xy 197.387265 -306.100755) (xy 197.428861 -306.070534) (xy 197.474673 -306.047191)
			(xy 197.523572 -306.031303) (xy 197.574354 -306.02326) (xy 197.62577 -306.02326) (xy 197.676552 -306.031303)
			(xy 197.725451 -306.047191) (xy 197.771263 -306.070534) (xy 197.812859 -306.100755) (xy 197.849215 -306.137111)
			(xy 197.879436 -306.178707) (xy 197.902779 -306.224519) (xy 197.918667 -306.273418) (xy 197.92671 -306.3242)
			(xy 197.927214 -306.349908) (xy 197.92671 -306.375616) (xy 198.223374 -306.375616) (xy 198.223374 -306.3242)
			(xy 198.231417 -306.273418) (xy 198.247305 -306.224519) (xy 198.270648 -306.178707) (xy 198.300869 -306.137111)
			(xy 198.337225 -306.100755) (xy 198.378821 -306.070534) (xy 198.424633 -306.047191) (xy 198.473532 -306.031303)
			(xy 198.524314 -306.02326) (xy 198.57573 -306.02326) (xy 198.626512 -306.031303) (xy 198.675411 -306.047191)
			(xy 198.721223 -306.070534) (xy 198.762819 -306.100755) (xy 198.799175 -306.137111) (xy 198.829396 -306.178707)
			(xy 198.852739 -306.224519) (xy 198.868627 -306.273418) (xy 198.87667 -306.3242) (xy 198.877174 -306.349908)
			(xy 199.194432 -306.349908) (xy 199.198392 -306.300854) (xy 199.210169 -306.25307) (xy 199.22946 -306.207794)
			(xy 199.255763 -306.166198) (xy 199.288398 -306.129361) (xy 199.326519 -306.098236) (xy 199.36914 -306.073629)
			(xy 199.415156 -306.056177) (xy 199.463375 -306.046333) (xy 199.51255 -306.044352) (xy 199.561405 -306.050284)
			(xy 199.608676 -306.063976) (xy 199.653138 -306.085074) (xy 199.693641 -306.11303) (xy 199.729134 -306.147122)
			(xy 199.758699 -306.186466) (xy 199.78157 -306.230043) (xy 199.797154 -306.276724) (xy 199.805049 -306.325301)
			(xy 199.805544 -306.349908) (xy 199.805049 -306.374515) (xy 199.797154 -306.423092) (xy 199.78157 -306.469773)
			(xy 199.758699 -306.51335) (xy 199.729134 -306.552694) (xy 199.693641 -306.586786) (xy 199.653138 -306.614742)
			(xy 199.608676 -306.63584) (xy 199.561405 -306.649532) (xy 199.51255 -306.655464) (xy 199.463375 -306.653483)
			(xy 199.415156 -306.643639) (xy 199.36914 -306.626187) (xy 199.326519 -306.60158) (xy 199.288398 -306.570455)
			(xy 199.255763 -306.533618) (xy 199.22946 -306.492022) (xy 199.210169 -306.446746) (xy 199.198392 -306.398962)
			(xy 199.194432 -306.349908) (xy 198.877174 -306.349908) (xy 198.87667 -306.375616) (xy 198.868627 -306.426398)
			(xy 198.852739 -306.475297) (xy 198.829396 -306.521109) (xy 198.799175 -306.562705) (xy 198.762819 -306.599061)
			(xy 198.721223 -306.629282) (xy 198.675411 -306.652625) (xy 198.626512 -306.668513) (xy 198.57573 -306.676556)
			(xy 198.524314 -306.676556) (xy 198.473532 -306.668513) (xy 198.424633 -306.652625) (xy 198.378821 -306.629282)
			(xy 198.337225 -306.599061) (xy 198.300869 -306.562705) (xy 198.270648 -306.521109) (xy 198.247305 -306.475297)
			(xy 198.231417 -306.426398) (xy 198.223374 -306.375616) (xy 197.92671 -306.375616) (xy 197.918667 -306.426398)
			(xy 197.902779 -306.475297) (xy 197.879436 -306.521109) (xy 197.849215 -306.562705) (xy 197.812859 -306.599061)
			(xy 197.771263 -306.629282) (xy 197.725451 -306.652625) (xy 197.676552 -306.668513) (xy 197.62577 -306.676556)
			(xy 197.574354 -306.676556) (xy 197.523572 -306.668513) (xy 197.474673 -306.652625) (xy 197.428861 -306.629282)
			(xy 197.387265 -306.599061) (xy 197.350909 -306.562705) (xy 197.320688 -306.521109) (xy 197.297345 -306.475297)
			(xy 197.281457 -306.426398) (xy 197.273414 -306.375616) (xy 196.954482 -306.375616) (xy 196.946766 -306.423092)
			(xy 196.931182 -306.469773) (xy 196.908311 -306.51335) (xy 196.878746 -306.552694) (xy 196.843253 -306.586786)
			(xy 196.80275 -306.614742) (xy 196.758288 -306.63584) (xy 196.711017 -306.649532) (xy 196.662162 -306.655464)
			(xy 196.612987 -306.653483) (xy 196.564768 -306.643639) (xy 196.518752 -306.626187) (xy 196.476131 -306.60158)
			(xy 196.43801 -306.570455) (xy 196.405375 -306.533618) (xy 196.379072 -306.492022) (xy 196.359781 -306.446746)
			(xy 196.348004 -306.398962) (xy 196.344044 -306.349908) (xy 196.005196 -306.349908) (xy 196.004701 -306.374515)
			(xy 195.996806 -306.423092) (xy 195.981222 -306.469773) (xy 195.958351 -306.51335) (xy 195.928786 -306.552694)
			(xy 195.893293 -306.586786) (xy 195.85279 -306.614742) (xy 195.808328 -306.63584) (xy 195.761057 -306.649532)
			(xy 195.712202 -306.655464) (xy 195.663027 -306.653483) (xy 195.614808 -306.643639) (xy 195.568792 -306.626187)
			(xy 195.526171 -306.60158) (xy 195.48805 -306.570455) (xy 195.455415 -306.533618) (xy 195.429112 -306.492022)
			(xy 195.409821 -306.446746) (xy 195.398044 -306.398962) (xy 195.394084 -306.349908) (xy 195.055236 -306.349908)
			(xy 195.054741 -306.374515) (xy 195.046846 -306.423092) (xy 195.031262 -306.469773) (xy 195.008391 -306.51335)
			(xy 194.978826 -306.552694) (xy 194.943333 -306.586786) (xy 194.90283 -306.614742) (xy 194.858368 -306.63584)
			(xy 194.811097 -306.649532) (xy 194.762242 -306.655464) (xy 194.713067 -306.653483) (xy 194.664848 -306.643639)
			(xy 194.618832 -306.626187) (xy 194.576211 -306.60158) (xy 194.53809 -306.570455) (xy 194.505455 -306.533618)
			(xy 194.479152 -306.492022) (xy 194.459861 -306.446746) (xy 194.448084 -306.398962) (xy 194.444124 -306.349908)
			(xy 194.105276 -306.349908) (xy 194.104781 -306.374515) (xy 194.096886 -306.423092) (xy 194.081302 -306.469773)
			(xy 194.058431 -306.51335) (xy 194.028866 -306.552694) (xy 193.993373 -306.586786) (xy 193.95287 -306.614742)
			(xy 193.908408 -306.63584) (xy 193.861137 -306.649532) (xy 193.812282 -306.655464) (xy 193.763107 -306.653483)
			(xy 193.714888 -306.643639) (xy 193.668872 -306.626187) (xy 193.626251 -306.60158) (xy 193.58813 -306.570455)
			(xy 193.555495 -306.533618) (xy 193.529192 -306.492022) (xy 193.509901 -306.446746) (xy 193.498124 -306.398962)
			(xy 193.494164 -306.349908) (xy 193.155316 -306.349908) (xy 193.154821 -306.374515) (xy 193.146926 -306.423092)
			(xy 193.131342 -306.469773) (xy 193.108471 -306.51335) (xy 193.078906 -306.552694) (xy 193.043413 -306.586786)
			(xy 193.00291 -306.614742) (xy 192.958448 -306.63584) (xy 192.911177 -306.649532) (xy 192.862322 -306.655464)
			(xy 192.813147 -306.653483) (xy 192.764928 -306.643639) (xy 192.718912 -306.626187) (xy 192.676291 -306.60158)
			(xy 192.63817 -306.570455) (xy 192.605535 -306.533618) (xy 192.579232 -306.492022) (xy 192.559941 -306.446746)
			(xy 192.548164 -306.398962) (xy 192.544204 -306.349908) (xy 192.2272 -306.349908) (xy 192.226696 -306.375616)
			(xy 192.218653 -306.426398) (xy 192.202765 -306.475297) (xy 192.179422 -306.521109) (xy 192.149201 -306.562705)
			(xy 192.112845 -306.599061) (xy 192.071249 -306.629282) (xy 192.025437 -306.652625) (xy 191.976538 -306.668513)
			(xy 191.925756 -306.676556) (xy 191.87434 -306.676556) (xy 191.823558 -306.668513) (xy 191.774659 -306.652625)
			(xy 191.728847 -306.629282) (xy 191.687251 -306.599061) (xy 191.650895 -306.562705) (xy 191.620674 -306.521109)
			(xy 191.597331 -306.475297) (xy 191.581443 -306.426398) (xy 191.5734 -306.375616) (xy 191.276736 -306.375616)
			(xy 191.268693 -306.426398) (xy 191.252805 -306.475297) (xy 191.229462 -306.521109) (xy 191.199241 -306.562705)
			(xy 191.162885 -306.599061) (xy 191.121289 -306.629282) (xy 191.075477 -306.652625) (xy 191.026578 -306.668513)
			(xy 190.975796 -306.676556) (xy 190.92438 -306.676556) (xy 190.873598 -306.668513) (xy 190.824699 -306.652625)
			(xy 190.778887 -306.629282) (xy 190.737291 -306.599061) (xy 190.700935 -306.562705) (xy 190.670714 -306.521109)
			(xy 190.647371 -306.475297) (xy 190.631483 -306.426398) (xy 190.62344 -306.375616) (xy 190.304508 -306.375616)
			(xy 190.296792 -306.423092) (xy 190.281208 -306.469773) (xy 190.258337 -306.51335) (xy 190.228772 -306.552694)
			(xy 190.193279 -306.586786) (xy 190.152776 -306.614742) (xy 190.108314 -306.63584) (xy 190.061043 -306.649532)
			(xy 190.012188 -306.655464) (xy 189.963013 -306.653483) (xy 189.914794 -306.643639) (xy 189.868778 -306.626187)
			(xy 189.826157 -306.60158) (xy 189.788036 -306.570455) (xy 189.755401 -306.533618) (xy 189.729098 -306.492022)
			(xy 189.709807 -306.446746) (xy 189.69803 -306.398962) (xy 189.69407 -306.349908) (xy 166.11727 -306.349908)
			(xy 166.11727 -306.824888) (xy 166.419288 -306.824888) (xy 166.423248 -306.775834) (xy 166.435025 -306.72805)
			(xy 166.454316 -306.682774) (xy 166.480619 -306.641178) (xy 166.513254 -306.604341) (xy 166.551375 -306.573216)
			(xy 166.593996 -306.548609) (xy 166.640012 -306.531157) (xy 166.688231 -306.521313) (xy 166.737406 -306.519332)
			(xy 166.786261 -306.525264) (xy 166.833532 -306.538956) (xy 166.877994 -306.560054) (xy 166.918497 -306.58801)
			(xy 166.95399 -306.622102) (xy 166.983555 -306.661446) (xy 167.006426 -306.705023) (xy 167.02201 -306.751704)
			(xy 167.029905 -306.800281) (xy 167.0304 -306.824888) (xy 167.369248 -306.824888) (xy 167.373208 -306.775834)
			(xy 167.384985 -306.72805) (xy 167.404276 -306.682774) (xy 167.430579 -306.641178) (xy 167.463214 -306.604341)
			(xy 167.501335 -306.573216) (xy 167.543956 -306.548609) (xy 167.589972 -306.531157) (xy 167.638191 -306.521313)
			(xy 167.687366 -306.519332) (xy 167.736221 -306.525264) (xy 167.783492 -306.538956) (xy 167.827954 -306.560054)
			(xy 167.868457 -306.58801) (xy 167.90395 -306.622102) (xy 167.933515 -306.661446) (xy 167.956386 -306.705023)
			(xy 167.97197 -306.751704) (xy 167.979865 -306.800281) (xy 167.98036 -306.824888) (xy 168.319208 -306.824888)
			(xy 168.323168 -306.775834) (xy 168.334945 -306.72805) (xy 168.354236 -306.682774) (xy 168.380539 -306.641178)
			(xy 168.413174 -306.604341) (xy 168.451295 -306.573216) (xy 168.493916 -306.548609) (xy 168.539932 -306.531157)
			(xy 168.588151 -306.521313) (xy 168.637326 -306.519332) (xy 168.686181 -306.525264) (xy 168.733452 -306.538956)
			(xy 168.777914 -306.560054) (xy 168.818417 -306.58801) (xy 168.85391 -306.622102) (xy 168.883475 -306.661446)
			(xy 168.906346 -306.705023) (xy 168.92193 -306.751704) (xy 168.929825 -306.800281) (xy 168.93032 -306.824888)
			(xy 169.269168 -306.824888) (xy 169.273128 -306.775834) (xy 169.284905 -306.72805) (xy 169.304196 -306.682774)
			(xy 169.330499 -306.641178) (xy 169.363134 -306.604341) (xy 169.401255 -306.573216) (xy 169.443876 -306.548609)
			(xy 169.489892 -306.531157) (xy 169.538111 -306.521313) (xy 169.587286 -306.519332) (xy 169.636141 -306.525264)
			(xy 169.683412 -306.538956) (xy 169.727874 -306.560054) (xy 169.768377 -306.58801) (xy 169.80387 -306.622102)
			(xy 169.833435 -306.661446) (xy 169.856306 -306.705023) (xy 169.87189 -306.751704) (xy 169.879785 -306.800281)
			(xy 169.88028 -306.824888) (xy 170.219128 -306.824888) (xy 170.223088 -306.775834) (xy 170.234865 -306.72805)
			(xy 170.254156 -306.682774) (xy 170.280459 -306.641178) (xy 170.313094 -306.604341) (xy 170.351215 -306.573216)
			(xy 170.393836 -306.548609) (xy 170.439852 -306.531157) (xy 170.488071 -306.521313) (xy 170.537246 -306.519332)
			(xy 170.586101 -306.525264) (xy 170.633372 -306.538956) (xy 170.677834 -306.560054) (xy 170.718337 -306.58801)
			(xy 170.75383 -306.622102) (xy 170.783395 -306.661446) (xy 170.806266 -306.705023) (xy 170.82185 -306.751704)
			(xy 170.829745 -306.800281) (xy 170.83024 -306.824888) (xy 171.169088 -306.824888) (xy 171.173048 -306.775834)
			(xy 171.184825 -306.72805) (xy 171.204116 -306.682774) (xy 171.230419 -306.641178) (xy 171.263054 -306.604341)
			(xy 171.301175 -306.573216) (xy 171.343796 -306.548609) (xy 171.389812 -306.531157) (xy 171.438031 -306.521313)
			(xy 171.487206 -306.519332) (xy 171.536061 -306.525264) (xy 171.583332 -306.538956) (xy 171.627794 -306.560054)
			(xy 171.668297 -306.58801) (xy 171.70379 -306.622102) (xy 171.733355 -306.661446) (xy 171.756226 -306.705023)
			(xy 171.77181 -306.751704) (xy 171.779705 -306.800281) (xy 171.7802 -306.824888) (xy 172.119048 -306.824888)
			(xy 172.123008 -306.775834) (xy 172.134785 -306.72805) (xy 172.154076 -306.682774) (xy 172.180379 -306.641178)
			(xy 172.213014 -306.604341) (xy 172.251135 -306.573216) (xy 172.293756 -306.548609) (xy 172.339772 -306.531157)
			(xy 172.387991 -306.521313) (xy 172.437166 -306.519332) (xy 172.486021 -306.525264) (xy 172.533292 -306.538956)
			(xy 172.577754 -306.560054) (xy 172.618257 -306.58801) (xy 172.65375 -306.622102) (xy 172.683315 -306.661446)
			(xy 172.706186 -306.705023) (xy 172.72177 -306.751704) (xy 172.729665 -306.800281) (xy 172.73016 -306.824888)
			(xy 173.069262 -306.824888) (xy 173.073222 -306.775834) (xy 173.084999 -306.72805) (xy 173.10429 -306.682774)
			(xy 173.130593 -306.641178) (xy 173.163228 -306.604341) (xy 173.201349 -306.573216) (xy 173.24397 -306.548609)
			(xy 173.289986 -306.531157) (xy 173.338205 -306.521313) (xy 173.38738 -306.519332) (xy 173.436235 -306.525264)
			(xy 173.483506 -306.538956) (xy 173.527968 -306.560054) (xy 173.568471 -306.58801) (xy 173.603964 -306.622102)
			(xy 173.633529 -306.661446) (xy 173.6564 -306.705023) (xy 173.671984 -306.751704) (xy 173.679879 -306.800281)
			(xy 173.680374 -306.824888) (xy 174.019222 -306.824888) (xy 174.023182 -306.775834) (xy 174.034959 -306.72805)
			(xy 174.05425 -306.682774) (xy 174.080553 -306.641178) (xy 174.113188 -306.604341) (xy 174.151309 -306.573216)
			(xy 174.19393 -306.548609) (xy 174.239946 -306.531157) (xy 174.288165 -306.521313) (xy 174.33734 -306.519332)
			(xy 174.386195 -306.525264) (xy 174.433466 -306.538956) (xy 174.477928 -306.560054) (xy 174.518431 -306.58801)
			(xy 174.553924 -306.622102) (xy 174.583489 -306.661446) (xy 174.60636 -306.705023) (xy 174.621944 -306.751704)
			(xy 174.629839 -306.800281) (xy 174.630334 -306.824888) (xy 175.919142 -306.824888) (xy 175.923102 -306.775834)
			(xy 175.934879 -306.72805) (xy 175.95417 -306.682774) (xy 175.980473 -306.641178) (xy 176.013108 -306.604341)
			(xy 176.051229 -306.573216) (xy 176.09385 -306.548609) (xy 176.139866 -306.531157) (xy 176.188085 -306.521313)
			(xy 176.23726 -306.519332) (xy 176.286115 -306.525264) (xy 176.333386 -306.538956) (xy 176.377848 -306.560054)
			(xy 176.418351 -306.58801) (xy 176.453844 -306.622102) (xy 176.483409 -306.661446) (xy 176.50628 -306.705023)
			(xy 176.521864 -306.751704) (xy 176.529759 -306.800281) (xy 176.530254 -306.824888) (xy 176.869102 -306.824888)
			(xy 176.873062 -306.775834) (xy 176.884839 -306.72805) (xy 176.90413 -306.682774) (xy 176.930433 -306.641178)
			(xy 176.963068 -306.604341) (xy 177.001189 -306.573216) (xy 177.04381 -306.548609) (xy 177.089826 -306.531157)
			(xy 177.138045 -306.521313) (xy 177.18722 -306.519332) (xy 177.236075 -306.525264) (xy 177.283346 -306.538956)
			(xy 177.327808 -306.560054) (xy 177.368311 -306.58801) (xy 177.403804 -306.622102) (xy 177.433369 -306.661446)
			(xy 177.45624 -306.705023) (xy 177.471824 -306.751704) (xy 177.479719 -306.800281) (xy 177.480214 -306.824888)
			(xy 177.819062 -306.824888) (xy 177.823022 -306.775834) (xy 177.834799 -306.72805) (xy 177.85409 -306.682774)
			(xy 177.880393 -306.641178) (xy 177.913028 -306.604341) (xy 177.951149 -306.573216) (xy 177.99377 -306.548609)
			(xy 178.039786 -306.531157) (xy 178.088005 -306.521313) (xy 178.13718 -306.519332) (xy 178.186035 -306.525264)
			(xy 178.233306 -306.538956) (xy 178.277768 -306.560054) (xy 178.318271 -306.58801) (xy 178.353764 -306.622102)
			(xy 178.383329 -306.661446) (xy 178.4062 -306.705023) (xy 178.421784 -306.751704) (xy 178.429679 -306.800281)
			(xy 178.430174 -306.824888) (xy 178.769276 -306.824888) (xy 178.773236 -306.775834) (xy 178.785013 -306.72805)
			(xy 178.804304 -306.682774) (xy 178.830607 -306.641178) (xy 178.863242 -306.604341) (xy 178.901363 -306.573216)
			(xy 178.943984 -306.548609) (xy 178.99 -306.531157) (xy 179.038219 -306.521313) (xy 179.087394 -306.519332)
			(xy 179.136249 -306.525264) (xy 179.18352 -306.538956) (xy 179.227982 -306.560054) (xy 179.268485 -306.58801)
			(xy 179.303978 -306.622102) (xy 179.333543 -306.661446) (xy 179.356414 -306.705023) (xy 179.371998 -306.751704)
			(xy 179.379893 -306.800281) (xy 179.380388 -306.824888) (xy 179.719236 -306.824888) (xy 179.723196 -306.775834)
			(xy 179.734973 -306.72805) (xy 179.754264 -306.682774) (xy 179.780567 -306.641178) (xy 179.813202 -306.604341)
			(xy 179.851323 -306.573216) (xy 179.893944 -306.548609) (xy 179.93996 -306.531157) (xy 179.988179 -306.521313)
			(xy 180.037354 -306.519332) (xy 180.086209 -306.525264) (xy 180.13348 -306.538956) (xy 180.177942 -306.560054)
			(xy 180.218445 -306.58801) (xy 180.253938 -306.622102) (xy 180.283503 -306.661446) (xy 180.306374 -306.705023)
			(xy 180.321958 -306.751704) (xy 180.329853 -306.800281) (xy 180.330348 -306.824888) (xy 180.669196 -306.824888)
			(xy 180.673156 -306.775834) (xy 180.684933 -306.72805) (xy 180.704224 -306.682774) (xy 180.730527 -306.641178)
			(xy 180.763162 -306.604341) (xy 180.801283 -306.573216) (xy 180.843904 -306.548609) (xy 180.88992 -306.531157)
			(xy 180.938139 -306.521313) (xy 180.987314 -306.519332) (xy 181.036169 -306.525264) (xy 181.08344 -306.538956)
			(xy 181.127902 -306.560054) (xy 181.168405 -306.58801) (xy 181.203898 -306.622102) (xy 181.233463 -306.661446)
			(xy 181.256334 -306.705023) (xy 181.271918 -306.751704) (xy 181.279813 -306.800281) (xy 181.280308 -306.824888)
			(xy 181.619156 -306.824888) (xy 181.623116 -306.775834) (xy 181.634893 -306.72805) (xy 181.654184 -306.682774)
			(xy 181.680487 -306.641178) (xy 181.713122 -306.604341) (xy 181.751243 -306.573216) (xy 181.793864 -306.548609)
			(xy 181.83988 -306.531157) (xy 181.888099 -306.521313) (xy 181.937274 -306.519332) (xy 181.986129 -306.525264)
			(xy 182.0334 -306.538956) (xy 182.077862 -306.560054) (xy 182.118365 -306.58801) (xy 182.153858 -306.622102)
			(xy 182.183423 -306.661446) (xy 182.206294 -306.705023) (xy 182.221878 -306.751704) (xy 182.229773 -306.800281)
			(xy 182.230268 -306.824888) (xy 182.569116 -306.824888) (xy 182.573076 -306.775834) (xy 182.584853 -306.72805)
			(xy 182.604144 -306.682774) (xy 182.630447 -306.641178) (xy 182.663082 -306.604341) (xy 182.701203 -306.573216)
			(xy 182.743824 -306.548609) (xy 182.78984 -306.531157) (xy 182.838059 -306.521313) (xy 182.887234 -306.519332)
			(xy 182.936089 -306.525264) (xy 182.98336 -306.538956) (xy 183.027822 -306.560054) (xy 183.068325 -306.58801)
			(xy 183.103818 -306.622102) (xy 183.133383 -306.661446) (xy 183.156254 -306.705023) (xy 183.171838 -306.751704)
			(xy 183.179733 -306.800281) (xy 183.180228 -306.824888) (xy 183.519076 -306.824888) (xy 183.523036 -306.775834)
			(xy 183.534813 -306.72805) (xy 183.554104 -306.682774) (xy 183.580407 -306.641178) (xy 183.613042 -306.604341)
			(xy 183.651163 -306.573216) (xy 183.693784 -306.548609) (xy 183.7398 -306.531157) (xy 183.788019 -306.521313)
			(xy 183.837194 -306.519332) (xy 183.886049 -306.525264) (xy 183.93332 -306.538956) (xy 183.977782 -306.560054)
			(xy 184.018285 -306.58801) (xy 184.053778 -306.622102) (xy 184.083343 -306.661446) (xy 184.106214 -306.705023)
			(xy 184.121798 -306.751704) (xy 184.129693 -306.800281) (xy 184.130188 -306.824888) (xy 184.469036 -306.824888)
			(xy 184.472996 -306.775834) (xy 184.484773 -306.72805) (xy 184.504064 -306.682774) (xy 184.530367 -306.641178)
			(xy 184.563002 -306.604341) (xy 184.601123 -306.573216) (xy 184.643744 -306.548609) (xy 184.68976 -306.531157)
			(xy 184.737979 -306.521313) (xy 184.787154 -306.519332) (xy 184.836009 -306.525264) (xy 184.88328 -306.538956)
			(xy 184.927742 -306.560054) (xy 184.968245 -306.58801) (xy 185.003738 -306.622102) (xy 185.033303 -306.661446)
			(xy 185.056174 -306.705023) (xy 185.071758 -306.751704) (xy 185.079653 -306.800281) (xy 185.080148 -306.824888)
			(xy 185.41925 -306.824888) (xy 185.42321 -306.775834) (xy 185.434987 -306.72805) (xy 185.454278 -306.682774)
			(xy 185.480581 -306.641178) (xy 185.513216 -306.604341) (xy 185.551337 -306.573216) (xy 185.593958 -306.548609)
			(xy 185.639974 -306.531157) (xy 185.688193 -306.521313) (xy 185.737368 -306.519332) (xy 185.786223 -306.525264)
			(xy 185.833494 -306.538956) (xy 185.877956 -306.560054) (xy 185.918459 -306.58801) (xy 185.953952 -306.622102)
			(xy 185.983517 -306.661446) (xy 186.006388 -306.705023) (xy 186.021972 -306.751704) (xy 186.029867 -306.800281)
			(xy 186.030362 -306.824888) (xy 186.36921 -306.824888) (xy 186.37317 -306.775834) (xy 186.384947 -306.72805)
			(xy 186.404238 -306.682774) (xy 186.430541 -306.641178) (xy 186.463176 -306.604341) (xy 186.501297 -306.573216)
			(xy 186.543918 -306.548609) (xy 186.589934 -306.531157) (xy 186.638153 -306.521313) (xy 186.687328 -306.519332)
			(xy 186.736183 -306.525264) (xy 186.783454 -306.538956) (xy 186.827916 -306.560054) (xy 186.868419 -306.58801)
			(xy 186.903912 -306.622102) (xy 186.933477 -306.661446) (xy 186.956348 -306.705023) (xy 186.971932 -306.751704)
			(xy 186.979827 -306.800281) (xy 186.980322 -306.824888) (xy 187.31917 -306.824888) (xy 187.32313 -306.775834)
			(xy 187.334907 -306.72805) (xy 187.354198 -306.682774) (xy 187.380501 -306.641178) (xy 187.413136 -306.604341)
			(xy 187.451257 -306.573216) (xy 187.493878 -306.548609) (xy 187.539894 -306.531157) (xy 187.588113 -306.521313)
			(xy 187.637288 -306.519332) (xy 187.686143 -306.525264) (xy 187.733414 -306.538956) (xy 187.777876 -306.560054)
			(xy 187.818379 -306.58801) (xy 187.853872 -306.622102) (xy 187.883437 -306.661446) (xy 187.906308 -306.705023)
			(xy 187.921892 -306.751704) (xy 187.929787 -306.800281) (xy 187.930282 -306.824888) (xy 188.26913 -306.824888)
			(xy 188.27309 -306.775834) (xy 188.284867 -306.72805) (xy 188.304158 -306.682774) (xy 188.330461 -306.641178)
			(xy 188.363096 -306.604341) (xy 188.401217 -306.573216) (xy 188.443838 -306.548609) (xy 188.489854 -306.531157)
			(xy 188.538073 -306.521313) (xy 188.587248 -306.519332) (xy 188.636103 -306.525264) (xy 188.683374 -306.538956)
			(xy 188.727836 -306.560054) (xy 188.768339 -306.58801) (xy 188.803832 -306.622102) (xy 188.833397 -306.661446)
			(xy 188.856268 -306.705023) (xy 188.871852 -306.751704) (xy 188.879747 -306.800281) (xy 188.880242 -306.824888)
			(xy 188.879747 -306.849495) (xy 188.871852 -306.898072) (xy 188.856268 -306.944753) (xy 188.833397 -306.98833)
			(xy 188.803832 -307.027674) (xy 188.768339 -307.061766) (xy 188.727836 -307.089722) (xy 188.683374 -307.11082)
			(xy 188.636103 -307.124512) (xy 188.587248 -307.130444) (xy 188.538073 -307.128463) (xy 188.489854 -307.118619)
			(xy 188.443838 -307.101167) (xy 188.401217 -307.07656) (xy 188.363096 -307.045435) (xy 188.330461 -307.008598)
			(xy 188.304158 -306.967002) (xy 188.284867 -306.921726) (xy 188.27309 -306.873942) (xy 188.26913 -306.824888)
			(xy 187.930282 -306.824888) (xy 187.929787 -306.849495) (xy 187.921892 -306.898072) (xy 187.906308 -306.944753)
			(xy 187.883437 -306.98833) (xy 187.853872 -307.027674) (xy 187.818379 -307.061766) (xy 187.777876 -307.089722)
			(xy 187.733414 -307.11082) (xy 187.686143 -307.124512) (xy 187.637288 -307.130444) (xy 187.588113 -307.128463)
			(xy 187.539894 -307.118619) (xy 187.493878 -307.101167) (xy 187.451257 -307.07656) (xy 187.413136 -307.045435)
			(xy 187.380501 -307.008598) (xy 187.354198 -306.967002) (xy 187.334907 -306.921726) (xy 187.32313 -306.873942)
			(xy 187.31917 -306.824888) (xy 186.980322 -306.824888) (xy 186.979827 -306.849495) (xy 186.971932 -306.898072)
			(xy 186.956348 -306.944753) (xy 186.933477 -306.98833) (xy 186.903912 -307.027674) (xy 186.868419 -307.061766)
			(xy 186.827916 -307.089722) (xy 186.783454 -307.11082) (xy 186.736183 -307.124512) (xy 186.687328 -307.130444)
			(xy 186.638153 -307.128463) (xy 186.589934 -307.118619) (xy 186.543918 -307.101167) (xy 186.501297 -307.07656)
			(xy 186.463176 -307.045435) (xy 186.430541 -307.008598) (xy 186.404238 -306.967002) (xy 186.384947 -306.921726)
			(xy 186.37317 -306.873942) (xy 186.36921 -306.824888) (xy 186.030362 -306.824888) (xy 186.029867 -306.849495)
			(xy 186.021972 -306.898072) (xy 186.006388 -306.944753) (xy 185.983517 -306.98833) (xy 185.953952 -307.027674)
			(xy 185.918459 -307.061766) (xy 185.877956 -307.089722) (xy 185.833494 -307.11082) (xy 185.786223 -307.124512)
			(xy 185.737368 -307.130444) (xy 185.688193 -307.128463) (xy 185.639974 -307.118619) (xy 185.593958 -307.101167)
			(xy 185.551337 -307.07656) (xy 185.513216 -307.045435) (xy 185.480581 -307.008598) (xy 185.454278 -306.967002)
			(xy 185.434987 -306.921726) (xy 185.42321 -306.873942) (xy 185.41925 -306.824888) (xy 185.080148 -306.824888)
			(xy 185.079653 -306.849495) (xy 185.071758 -306.898072) (xy 185.056174 -306.944753) (xy 185.033303 -306.98833)
			(xy 185.003738 -307.027674) (xy 184.968245 -307.061766) (xy 184.927742 -307.089722) (xy 184.88328 -307.11082)
			(xy 184.836009 -307.124512) (xy 184.787154 -307.130444) (xy 184.737979 -307.128463) (xy 184.68976 -307.118619)
			(xy 184.643744 -307.101167) (xy 184.601123 -307.07656) (xy 184.563002 -307.045435) (xy 184.530367 -307.008598)
			(xy 184.504064 -306.967002) (xy 184.484773 -306.921726) (xy 184.472996 -306.873942) (xy 184.469036 -306.824888)
			(xy 184.130188 -306.824888) (xy 184.129693 -306.849495) (xy 184.121798 -306.898072) (xy 184.106214 -306.944753)
			(xy 184.083343 -306.98833) (xy 184.053778 -307.027674) (xy 184.018285 -307.061766) (xy 183.977782 -307.089722)
			(xy 183.93332 -307.11082) (xy 183.886049 -307.124512) (xy 183.837194 -307.130444) (xy 183.788019 -307.128463)
			(xy 183.7398 -307.118619) (xy 183.693784 -307.101167) (xy 183.651163 -307.07656) (xy 183.613042 -307.045435)
			(xy 183.580407 -307.008598) (xy 183.554104 -306.967002) (xy 183.534813 -306.921726) (xy 183.523036 -306.873942)
			(xy 183.519076 -306.824888) (xy 183.180228 -306.824888) (xy 183.179733 -306.849495) (xy 183.171838 -306.898072)
			(xy 183.156254 -306.944753) (xy 183.133383 -306.98833) (xy 183.103818 -307.027674) (xy 183.068325 -307.061766)
			(xy 183.027822 -307.089722) (xy 182.98336 -307.11082) (xy 182.936089 -307.124512) (xy 182.887234 -307.130444)
			(xy 182.838059 -307.128463) (xy 182.78984 -307.118619) (xy 182.743824 -307.101167) (xy 182.701203 -307.07656)
			(xy 182.663082 -307.045435) (xy 182.630447 -307.008598) (xy 182.604144 -306.967002) (xy 182.584853 -306.921726)
			(xy 182.573076 -306.873942) (xy 182.569116 -306.824888) (xy 182.230268 -306.824888) (xy 182.229773 -306.849495)
			(xy 182.221878 -306.898072) (xy 182.206294 -306.944753) (xy 182.183423 -306.98833) (xy 182.153858 -307.027674)
			(xy 182.118365 -307.061766) (xy 182.077862 -307.089722) (xy 182.0334 -307.11082) (xy 181.986129 -307.124512)
			(xy 181.937274 -307.130444) (xy 181.888099 -307.128463) (xy 181.83988 -307.118619) (xy 181.793864 -307.101167)
			(xy 181.751243 -307.07656) (xy 181.713122 -307.045435) (xy 181.680487 -307.008598) (xy 181.654184 -306.967002)
			(xy 181.634893 -306.921726) (xy 181.623116 -306.873942) (xy 181.619156 -306.824888) (xy 181.280308 -306.824888)
			(xy 181.279813 -306.849495) (xy 181.271918 -306.898072) (xy 181.256334 -306.944753) (xy 181.233463 -306.98833)
			(xy 181.203898 -307.027674) (xy 181.168405 -307.061766) (xy 181.127902 -307.089722) (xy 181.08344 -307.11082)
			(xy 181.036169 -307.124512) (xy 180.987314 -307.130444) (xy 180.938139 -307.128463) (xy 180.88992 -307.118619)
			(xy 180.843904 -307.101167) (xy 180.801283 -307.07656) (xy 180.763162 -307.045435) (xy 180.730527 -307.008598)
			(xy 180.704224 -306.967002) (xy 180.684933 -306.921726) (xy 180.673156 -306.873942) (xy 180.669196 -306.824888)
			(xy 180.330348 -306.824888) (xy 180.329853 -306.849495) (xy 180.321958 -306.898072) (xy 180.306374 -306.944753)
			(xy 180.283503 -306.98833) (xy 180.253938 -307.027674) (xy 180.218445 -307.061766) (xy 180.177942 -307.089722)
			(xy 180.13348 -307.11082) (xy 180.086209 -307.124512) (xy 180.037354 -307.130444) (xy 179.988179 -307.128463)
			(xy 179.93996 -307.118619) (xy 179.893944 -307.101167) (xy 179.851323 -307.07656) (xy 179.813202 -307.045435)
			(xy 179.780567 -307.008598) (xy 179.754264 -306.967002) (xy 179.734973 -306.921726) (xy 179.723196 -306.873942)
			(xy 179.719236 -306.824888) (xy 179.380388 -306.824888) (xy 179.379893 -306.849495) (xy 179.371998 -306.898072)
			(xy 179.356414 -306.944753) (xy 179.333543 -306.98833) (xy 179.303978 -307.027674) (xy 179.268485 -307.061766)
			(xy 179.227982 -307.089722) (xy 179.18352 -307.11082) (xy 179.136249 -307.124512) (xy 179.087394 -307.130444)
			(xy 179.038219 -307.128463) (xy 178.99 -307.118619) (xy 178.943984 -307.101167) (xy 178.901363 -307.07656)
			(xy 178.863242 -307.045435) (xy 178.830607 -307.008598) (xy 178.804304 -306.967002) (xy 178.785013 -306.921726)
			(xy 178.773236 -306.873942) (xy 178.769276 -306.824888) (xy 178.430174 -306.824888) (xy 178.429679 -306.849495)
			(xy 178.421784 -306.898072) (xy 178.4062 -306.944753) (xy 178.383329 -306.98833) (xy 178.353764 -307.027674)
			(xy 178.318271 -307.061766) (xy 178.277768 -307.089722) (xy 178.233306 -307.11082) (xy 178.186035 -307.124512)
			(xy 178.13718 -307.130444) (xy 178.088005 -307.128463) (xy 178.039786 -307.118619) (xy 177.99377 -307.101167)
			(xy 177.951149 -307.07656) (xy 177.913028 -307.045435) (xy 177.880393 -307.008598) (xy 177.85409 -306.967002)
			(xy 177.834799 -306.921726) (xy 177.823022 -306.873942) (xy 177.819062 -306.824888) (xy 177.480214 -306.824888)
			(xy 177.479719 -306.849495) (xy 177.471824 -306.898072) (xy 177.45624 -306.944753) (xy 177.433369 -306.98833)
			(xy 177.403804 -307.027674) (xy 177.368311 -307.061766) (xy 177.327808 -307.089722) (xy 177.283346 -307.11082)
			(xy 177.236075 -307.124512) (xy 177.18722 -307.130444) (xy 177.138045 -307.128463) (xy 177.089826 -307.118619)
			(xy 177.04381 -307.101167) (xy 177.001189 -307.07656) (xy 176.963068 -307.045435) (xy 176.930433 -307.008598)
			(xy 176.90413 -306.967002) (xy 176.884839 -306.921726) (xy 176.873062 -306.873942) (xy 176.869102 -306.824888)
			(xy 176.530254 -306.824888) (xy 176.529759 -306.849495) (xy 176.521864 -306.898072) (xy 176.50628 -306.944753)
			(xy 176.483409 -306.98833) (xy 176.453844 -307.027674) (xy 176.418351 -307.061766) (xy 176.377848 -307.089722)
			(xy 176.333386 -307.11082) (xy 176.286115 -307.124512) (xy 176.23726 -307.130444) (xy 176.188085 -307.128463)
			(xy 176.139866 -307.118619) (xy 176.09385 -307.101167) (xy 176.051229 -307.07656) (xy 176.013108 -307.045435)
			(xy 175.980473 -307.008598) (xy 175.95417 -306.967002) (xy 175.934879 -306.921726) (xy 175.923102 -306.873942)
			(xy 175.919142 -306.824888) (xy 174.630334 -306.824888) (xy 174.629839 -306.849495) (xy 174.621944 -306.898072)
			(xy 174.60636 -306.944753) (xy 174.583489 -306.98833) (xy 174.553924 -307.027674) (xy 174.518431 -307.061766)
			(xy 174.477928 -307.089722) (xy 174.433466 -307.11082) (xy 174.386195 -307.124512) (xy 174.33734 -307.130444)
			(xy 174.288165 -307.128463) (xy 174.239946 -307.118619) (xy 174.19393 -307.101167) (xy 174.151309 -307.07656)
			(xy 174.113188 -307.045435) (xy 174.080553 -307.008598) (xy 174.05425 -306.967002) (xy 174.034959 -306.921726)
			(xy 174.023182 -306.873942) (xy 174.019222 -306.824888) (xy 173.680374 -306.824888) (xy 173.679879 -306.849495)
			(xy 173.671984 -306.898072) (xy 173.6564 -306.944753) (xy 173.633529 -306.98833) (xy 173.603964 -307.027674)
			(xy 173.568471 -307.061766) (xy 173.527968 -307.089722) (xy 173.483506 -307.11082) (xy 173.436235 -307.124512)
			(xy 173.38738 -307.130444) (xy 173.338205 -307.128463) (xy 173.289986 -307.118619) (xy 173.24397 -307.101167)
			(xy 173.201349 -307.07656) (xy 173.163228 -307.045435) (xy 173.130593 -307.008598) (xy 173.10429 -306.967002)
			(xy 173.084999 -306.921726) (xy 173.073222 -306.873942) (xy 173.069262 -306.824888) (xy 172.73016 -306.824888)
			(xy 172.729665 -306.849495) (xy 172.72177 -306.898072) (xy 172.706186 -306.944753) (xy 172.683315 -306.98833)
			(xy 172.65375 -307.027674) (xy 172.618257 -307.061766) (xy 172.577754 -307.089722) (xy 172.533292 -307.11082)
			(xy 172.486021 -307.124512) (xy 172.437166 -307.130444) (xy 172.387991 -307.128463) (xy 172.339772 -307.118619)
			(xy 172.293756 -307.101167) (xy 172.251135 -307.07656) (xy 172.213014 -307.045435) (xy 172.180379 -307.008598)
			(xy 172.154076 -306.967002) (xy 172.134785 -306.921726) (xy 172.123008 -306.873942) (xy 172.119048 -306.824888)
			(xy 171.7802 -306.824888) (xy 171.779705 -306.849495) (xy 171.77181 -306.898072) (xy 171.756226 -306.944753)
			(xy 171.733355 -306.98833) (xy 171.70379 -307.027674) (xy 171.668297 -307.061766) (xy 171.627794 -307.089722)
			(xy 171.583332 -307.11082) (xy 171.536061 -307.124512) (xy 171.487206 -307.130444) (xy 171.438031 -307.128463)
			(xy 171.389812 -307.118619) (xy 171.343796 -307.101167) (xy 171.301175 -307.07656) (xy 171.263054 -307.045435)
			(xy 171.230419 -307.008598) (xy 171.204116 -306.967002) (xy 171.184825 -306.921726) (xy 171.173048 -306.873942)
			(xy 171.169088 -306.824888) (xy 170.83024 -306.824888) (xy 170.829745 -306.849495) (xy 170.82185 -306.898072)
			(xy 170.806266 -306.944753) (xy 170.783395 -306.98833) (xy 170.75383 -307.027674) (xy 170.718337 -307.061766)
			(xy 170.677834 -307.089722) (xy 170.633372 -307.11082) (xy 170.586101 -307.124512) (xy 170.537246 -307.130444)
			(xy 170.488071 -307.128463) (xy 170.439852 -307.118619) (xy 170.393836 -307.101167) (xy 170.351215 -307.07656)
			(xy 170.313094 -307.045435) (xy 170.280459 -307.008598) (xy 170.254156 -306.967002) (xy 170.234865 -306.921726)
			(xy 170.223088 -306.873942) (xy 170.219128 -306.824888) (xy 169.88028 -306.824888) (xy 169.879785 -306.849495)
			(xy 169.87189 -306.898072) (xy 169.856306 -306.944753) (xy 169.833435 -306.98833) (xy 169.80387 -307.027674)
			(xy 169.768377 -307.061766) (xy 169.727874 -307.089722) (xy 169.683412 -307.11082) (xy 169.636141 -307.124512)
			(xy 169.587286 -307.130444) (xy 169.538111 -307.128463) (xy 169.489892 -307.118619) (xy 169.443876 -307.101167)
			(xy 169.401255 -307.07656) (xy 169.363134 -307.045435) (xy 169.330499 -307.008598) (xy 169.304196 -306.967002)
			(xy 169.284905 -306.921726) (xy 169.273128 -306.873942) (xy 169.269168 -306.824888) (xy 168.93032 -306.824888)
			(xy 168.929825 -306.849495) (xy 168.92193 -306.898072) (xy 168.906346 -306.944753) (xy 168.883475 -306.98833)
			(xy 168.85391 -307.027674) (xy 168.818417 -307.061766) (xy 168.777914 -307.089722) (xy 168.733452 -307.11082)
			(xy 168.686181 -307.124512) (xy 168.637326 -307.130444) (xy 168.588151 -307.128463) (xy 168.539932 -307.118619)
			(xy 168.493916 -307.101167) (xy 168.451295 -307.07656) (xy 168.413174 -307.045435) (xy 168.380539 -307.008598)
			(xy 168.354236 -306.967002) (xy 168.334945 -306.921726) (xy 168.323168 -306.873942) (xy 168.319208 -306.824888)
			(xy 167.98036 -306.824888) (xy 167.979865 -306.849495) (xy 167.97197 -306.898072) (xy 167.956386 -306.944753)
			(xy 167.933515 -306.98833) (xy 167.90395 -307.027674) (xy 167.868457 -307.061766) (xy 167.827954 -307.089722)
			(xy 167.783492 -307.11082) (xy 167.736221 -307.124512) (xy 167.687366 -307.130444) (xy 167.638191 -307.128463)
			(xy 167.589972 -307.118619) (xy 167.543956 -307.101167) (xy 167.501335 -307.07656) (xy 167.463214 -307.045435)
			(xy 167.430579 -307.008598) (xy 167.404276 -306.967002) (xy 167.384985 -306.921726) (xy 167.373208 -306.873942)
			(xy 167.369248 -306.824888) (xy 167.0304 -306.824888) (xy 167.029905 -306.849495) (xy 167.02201 -306.898072)
			(xy 167.006426 -306.944753) (xy 166.983555 -306.98833) (xy 166.95399 -307.027674) (xy 166.918497 -307.061766)
			(xy 166.877994 -307.089722) (xy 166.833532 -307.11082) (xy 166.786261 -307.124512) (xy 166.737406 -307.130444)
			(xy 166.688231 -307.128463) (xy 166.640012 -307.118619) (xy 166.593996 -307.101167) (xy 166.551375 -307.07656)
			(xy 166.513254 -307.045435) (xy 166.480619 -307.008598) (xy 166.454316 -306.967002) (xy 166.435025 -306.921726)
			(xy 166.423248 -306.873942) (xy 166.419288 -306.824888) (xy 166.11727 -306.824888) (xy 166.11727 -307.299868)
			(xy 189.69407 -307.299868) (xy 189.69803 -307.250814) (xy 189.709807 -307.20303) (xy 189.729098 -307.157754)
			(xy 189.755401 -307.116158) (xy 189.788036 -307.079321) (xy 189.826157 -307.048196) (xy 189.868778 -307.023589)
			(xy 189.914794 -307.006137) (xy 189.963013 -306.996293) (xy 190.012188 -306.994312) (xy 190.061043 -307.000244)
			(xy 190.108314 -307.013936) (xy 190.152776 -307.035034) (xy 190.193279 -307.06299) (xy 190.228772 -307.097082)
			(xy 190.258337 -307.136426) (xy 190.281208 -307.180003) (xy 190.296792 -307.226684) (xy 190.304687 -307.275261)
			(xy 190.305182 -307.299868) (xy 190.644284 -307.299868) (xy 190.648244 -307.250814) (xy 190.660021 -307.20303)
			(xy 190.679312 -307.157754) (xy 190.705615 -307.116158) (xy 190.73825 -307.079321) (xy 190.776371 -307.048196)
			(xy 190.818992 -307.023589) (xy 190.865008 -307.006137) (xy 190.913227 -306.996293) (xy 190.962402 -306.994312)
			(xy 191.011257 -307.000244) (xy 191.058528 -307.013936) (xy 191.10299 -307.035034) (xy 191.143493 -307.06299)
			(xy 191.178986 -307.097082) (xy 191.208551 -307.136426) (xy 191.231422 -307.180003) (xy 191.247006 -307.226684)
			(xy 191.254901 -307.275261) (xy 191.255396 -307.299868) (xy 191.594244 -307.299868) (xy 191.598204 -307.250814)
			(xy 191.609981 -307.20303) (xy 191.629272 -307.157754) (xy 191.655575 -307.116158) (xy 191.68821 -307.079321)
			(xy 191.726331 -307.048196) (xy 191.768952 -307.023589) (xy 191.814968 -307.006137) (xy 191.863187 -306.996293)
			(xy 191.912362 -306.994312) (xy 191.961217 -307.000244) (xy 192.008488 -307.013936) (xy 192.05295 -307.035034)
			(xy 192.093453 -307.06299) (xy 192.128946 -307.097082) (xy 192.158511 -307.136426) (xy 192.181382 -307.180003)
			(xy 192.196966 -307.226684) (xy 192.204861 -307.275261) (xy 192.205356 -307.299868) (xy 192.204861 -307.324475)
			(xy 192.204682 -307.325576) (xy 192.52336 -307.325576) (xy 192.52336 -307.27416) (xy 192.531403 -307.223378)
			(xy 192.547291 -307.174479) (xy 192.570634 -307.128667) (xy 192.600855 -307.087071) (xy 192.637211 -307.050715)
			(xy 192.678807 -307.020494) (xy 192.724619 -306.997151) (xy 192.773518 -306.981263) (xy 192.8243 -306.97322)
			(xy 192.875716 -306.97322) (xy 192.926498 -306.981263) (xy 192.975397 -306.997151) (xy 193.021209 -307.020494)
			(xy 193.062805 -307.050715) (xy 193.099161 -307.087071) (xy 193.129382 -307.128667) (xy 193.152725 -307.174479)
			(xy 193.168613 -307.223378) (xy 193.176656 -307.27416) (xy 193.17716 -307.299868) (xy 193.176656 -307.325576)
			(xy 193.47332 -307.325576) (xy 193.47332 -307.27416) (xy 193.481363 -307.223378) (xy 193.497251 -307.174479)
			(xy 193.520594 -307.128667) (xy 193.550815 -307.087071) (xy 193.587171 -307.050715) (xy 193.628767 -307.020494)
			(xy 193.674579 -306.997151) (xy 193.723478 -306.981263) (xy 193.77426 -306.97322) (xy 193.825676 -306.97322)
			(xy 193.876458 -306.981263) (xy 193.925357 -306.997151) (xy 193.971169 -307.020494) (xy 194.012765 -307.050715)
			(xy 194.049121 -307.087071) (xy 194.079342 -307.128667) (xy 194.102685 -307.174479) (xy 194.118573 -307.223378)
			(xy 194.126616 -307.27416) (xy 194.12712 -307.299868) (xy 194.444124 -307.299868) (xy 194.448084 -307.250814)
			(xy 194.459861 -307.20303) (xy 194.479152 -307.157754) (xy 194.505455 -307.116158) (xy 194.53809 -307.079321)
			(xy 194.576211 -307.048196) (xy 194.618832 -307.023589) (xy 194.664848 -307.006137) (xy 194.713067 -306.996293)
			(xy 194.762242 -306.994312) (xy 194.811097 -307.000244) (xy 194.858368 -307.013936) (xy 194.90283 -307.035034)
			(xy 194.943333 -307.06299) (xy 194.978826 -307.097082) (xy 195.008391 -307.136426) (xy 195.031262 -307.180003)
			(xy 195.046846 -307.226684) (xy 195.054741 -307.275261) (xy 195.055236 -307.299868) (xy 195.054741 -307.324475)
			(xy 195.054562 -307.325576) (xy 195.37324 -307.325576) (xy 195.37324 -307.27416) (xy 195.381283 -307.223378)
			(xy 195.397171 -307.174479) (xy 195.420514 -307.128667) (xy 195.450735 -307.087071) (xy 195.487091 -307.050715)
			(xy 195.528687 -307.020494) (xy 195.574499 -306.997151) (xy 195.623398 -306.981263) (xy 195.67418 -306.97322)
			(xy 195.725596 -306.97322) (xy 195.776378 -306.981263) (xy 195.825277 -306.997151) (xy 195.871089 -307.020494)
			(xy 195.912685 -307.050715) (xy 195.949041 -307.087071) (xy 195.979262 -307.128667) (xy 196.002605 -307.174479)
			(xy 196.018493 -307.223378) (xy 196.026536 -307.27416) (xy 196.02704 -307.299868) (xy 196.026536 -307.325576)
			(xy 196.3232 -307.325576) (xy 196.3232 -307.27416) (xy 196.331243 -307.223378) (xy 196.347131 -307.174479)
			(xy 196.370474 -307.128667) (xy 196.400695 -307.087071) (xy 196.437051 -307.050715) (xy 196.478647 -307.020494)
			(xy 196.524459 -306.997151) (xy 196.573358 -306.981263) (xy 196.62414 -306.97322) (xy 196.675556 -306.97322)
			(xy 196.726338 -306.981263) (xy 196.775237 -306.997151) (xy 196.821049 -307.020494) (xy 196.862645 -307.050715)
			(xy 196.899001 -307.087071) (xy 196.929222 -307.128667) (xy 196.952565 -307.174479) (xy 196.968453 -307.223378)
			(xy 196.976496 -307.27416) (xy 196.977 -307.299868) (xy 197.294258 -307.299868) (xy 197.298218 -307.250814)
			(xy 197.309995 -307.20303) (xy 197.329286 -307.157754) (xy 197.355589 -307.116158) (xy 197.388224 -307.079321)
			(xy 197.426345 -307.048196) (xy 197.468966 -307.023589) (xy 197.514982 -307.006137) (xy 197.563201 -306.996293)
			(xy 197.612376 -306.994312) (xy 197.661231 -307.000244) (xy 197.708502 -307.013936) (xy 197.752964 -307.035034)
			(xy 197.793467 -307.06299) (xy 197.82896 -307.097082) (xy 197.858525 -307.136426) (xy 197.881396 -307.180003)
			(xy 197.89698 -307.226684) (xy 197.904875 -307.275261) (xy 197.90537 -307.299868) (xy 198.244218 -307.299868)
			(xy 198.248178 -307.250814) (xy 198.259955 -307.20303) (xy 198.279246 -307.157754) (xy 198.305549 -307.116158)
			(xy 198.338184 -307.079321) (xy 198.376305 -307.048196) (xy 198.418926 -307.023589) (xy 198.464942 -307.006137)
			(xy 198.513161 -306.996293) (xy 198.562336 -306.994312) (xy 198.611191 -307.000244) (xy 198.658462 -307.013936)
			(xy 198.702924 -307.035034) (xy 198.743427 -307.06299) (xy 198.77892 -307.097082) (xy 198.808485 -307.136426)
			(xy 198.831356 -307.180003) (xy 198.84694 -307.226684) (xy 198.854835 -307.275261) (xy 198.85533 -307.299868)
			(xy 198.854835 -307.324475) (xy 198.84694 -307.373052) (xy 198.841336 -307.389837) (xy 207.250293 -307.389837)
			(xy 207.250295 -307.335337) (xy 207.258053 -307.281393) (xy 207.273409 -307.229101) (xy 207.296051 -307.179527)
			(xy 207.325517 -307.133679) (xy 207.361208 -307.092492) (xy 207.402397 -307.056804) (xy 207.448246 -307.02734)
			(xy 207.497821 -307.004701) (xy 207.550114 -306.989348) (xy 207.604059 -306.981594) (xy 207.658559 -306.981595)
			(xy 207.712504 -306.989352) (xy 207.764796 -307.004708) (xy 207.81437 -307.027349) (xy 207.860218 -307.056815)
			(xy 207.891846 -307.084222) (xy 208.814414 -307.084222) (xy 208.818485 -307.0286) (xy 208.830611 -306.974163)
			(xy 208.850534 -306.922072) (xy 208.87783 -306.873437) (xy 208.911916 -306.829294) (xy 208.952065 -306.790585)
			(xy 208.997423 -306.758134) (xy 209.047023 -306.732633) (xy 209.099807 -306.714626) (xy 209.15465 -306.704496)
			(xy 209.210384 -306.702459) (xy 209.265821 -306.708559) (xy 209.319778 -306.722665) (xy 209.371107 -306.744477)
			(xy 209.418713 -306.773531) (xy 209.461581 -306.809206) (xy 209.498798 -306.850743) (xy 209.529571 -306.897256)
			(xy 209.553243 -306.947753) (xy 209.569311 -307.00116) (xy 209.577431 -307.056336) (xy 209.57794 -307.084222)
			(xy 209.577431 -307.112108) (xy 209.569311 -307.167284) (xy 209.553243 -307.220691) (xy 209.529571 -307.271188)
			(xy 209.498798 -307.317701) (xy 209.461581 -307.359238) (xy 209.418713 -307.394913) (xy 209.371107 -307.423967)
			(xy 209.319778 -307.445779) (xy 209.265821 -307.459885) (xy 209.210384 -307.465985) (xy 209.15465 -307.463948)
			(xy 209.099807 -307.453818) (xy 209.047023 -307.435811) (xy 208.997423 -307.41031) (xy 208.952065 -307.377859)
			(xy 208.911916 -307.33915) (xy 208.87783 -307.295007) (xy 208.850534 -307.246372) (xy 208.830611 -307.194281)
			(xy 208.818485 -307.139844) (xy 208.814414 -307.084222) (xy 207.891846 -307.084222) (xy 207.901405 -307.092505)
			(xy 207.937094 -307.133694) (xy 207.966558 -307.179543) (xy 207.989197 -307.229118) (xy 208.004551 -307.281411)
			(xy 208.012306 -307.335356) (xy 208.012792 -307.362606) (xy 208.011014 -307.399182) (xy 208.009998 -307.410612)
			(xy 208.017618 -307.431694) (xy 208.089246 -307.503322) (xy 208.110582 -307.510942) (xy 208.122012 -307.509926)
			(xy 208.158588 -307.508148) (xy 208.185837 -307.508689) (xy 208.23978 -307.516443) (xy 208.292071 -307.531794)
			(xy 208.341645 -307.554431) (xy 208.387494 -307.583892) (xy 208.428683 -307.619577) (xy 208.464375 -307.660761)
			(xy 208.493842 -307.706605) (xy 208.516486 -307.756176) (xy 208.531845 -307.808465) (xy 208.539607 -307.862407)
			(xy 208.540096 -307.889656) (xy 208.539739 -307.912162) (xy 208.534396 -307.956856) (xy 208.529428 -307.97881)
			(xy 208.52638 -307.992018) (xy 208.533492 -308.017164) (xy 208.613756 -308.097428) (xy 208.638902 -308.10454)
			(xy 208.65211 -308.101492) (xy 208.674064 -308.096524) (xy 208.718758 -308.091181) (xy 208.741264 -308.090824)
			(xy 208.76852 -308.091216) (xy 208.822476 -308.098969) (xy 208.874781 -308.114322) (xy 208.924368 -308.136962)
			(xy 208.970228 -308.166428) (xy 209.011428 -308.202122) (xy 209.047129 -308.243315) (xy 209.076604 -308.28917)
			(xy 209.099254 -308.338753) (xy 209.114616 -308.391054) (xy 209.122379 -308.44501) (xy 209.122384 -308.499521)
			(xy 209.114631 -308.553478) (xy 209.099278 -308.605782) (xy 209.076638 -308.655369) (xy 209.047171 -308.701229)
			(xy 209.011477 -308.742429) (xy 208.970284 -308.77813) (xy 208.924429 -308.807605) (xy 208.874846 -308.830254)
			(xy 208.822544 -308.845616) (xy 208.768589 -308.853379) (xy 208.714078 -308.853383) (xy 208.660121 -308.84563)
			(xy 208.607817 -308.830277) (xy 208.55823 -308.807637) (xy 208.51237 -308.77817) (xy 208.47117 -308.742476)
			(xy 208.435469 -308.701283) (xy 208.405994 -308.655428) (xy 208.383345 -308.605845) (xy 208.367983 -308.553543)
			(xy 208.360221 -308.499587) (xy 208.359756 -308.472332) (xy 208.36011 -308.449826) (xy 208.365455 -308.405131)
			(xy 208.370424 -308.383178) (xy 208.373472 -308.36997) (xy 208.36636 -308.344824) (xy 208.286096 -308.26456)
			(xy 208.26095 -308.257448) (xy 208.247742 -308.260496) (xy 208.225787 -308.265455) (xy 208.181094 -308.270804)
			(xy 208.158588 -308.271164) (xy 208.131333 -308.270756) (xy 208.077378 -308.262996) (xy 208.025076 -308.247637)
			(xy 207.975493 -308.224989) (xy 207.929638 -308.195516) (xy 207.888444 -308.159817) (xy 207.85275 -308.118618)
			(xy 207.823284 -308.072758) (xy 207.800644 -308.023172) (xy 207.785292 -307.970868) (xy 207.77754 -307.916911)
			(xy 207.77708 -307.889656) (xy 207.778858 -307.85308) (xy 207.779874 -307.84165) (xy 207.772254 -307.820568)
			(xy 207.700626 -307.74894) (xy 207.67929 -307.74132) (xy 207.66786 -307.742336) (xy 207.631284 -307.744114)
			(xy 207.604034 -307.743605) (xy 207.550089 -307.735846) (xy 207.497798 -307.72049) (xy 207.448224 -307.697848)
			(xy 207.402377 -307.668381) (xy 207.36119 -307.63269) (xy 207.325502 -307.5915) (xy 207.296038 -307.545651)
			(xy 207.2734 -307.496075) (xy 207.258048 -307.443783) (xy 207.250293 -307.389837) (xy 198.841336 -307.389837)
			(xy 198.831356 -307.419733) (xy 198.808485 -307.46331) (xy 198.77892 -307.502654) (xy 198.743427 -307.536746)
			(xy 198.702924 -307.564702) (xy 198.658462 -307.5858) (xy 198.611191 -307.599492) (xy 198.562336 -307.605424)
			(xy 198.513161 -307.603443) (xy 198.464942 -307.593599) (xy 198.418926 -307.576147) (xy 198.376305 -307.55154)
			(xy 198.338184 -307.520415) (xy 198.305549 -307.483578) (xy 198.279246 -307.441982) (xy 198.259955 -307.396706)
			(xy 198.248178 -307.348922) (xy 198.244218 -307.299868) (xy 197.90537 -307.299868) (xy 197.904875 -307.324475)
			(xy 197.89698 -307.373052) (xy 197.881396 -307.419733) (xy 197.858525 -307.46331) (xy 197.82896 -307.502654)
			(xy 197.793467 -307.536746) (xy 197.752964 -307.564702) (xy 197.708502 -307.5858) (xy 197.661231 -307.599492)
			(xy 197.612376 -307.605424) (xy 197.563201 -307.603443) (xy 197.514982 -307.593599) (xy 197.468966 -307.576147)
			(xy 197.426345 -307.55154) (xy 197.388224 -307.520415) (xy 197.355589 -307.483578) (xy 197.329286 -307.441982)
			(xy 197.309995 -307.396706) (xy 197.298218 -307.348922) (xy 197.294258 -307.299868) (xy 196.977 -307.299868)
			(xy 196.976496 -307.325576) (xy 196.968453 -307.376358) (xy 196.952565 -307.425257) (xy 196.929222 -307.471069)
			(xy 196.899001 -307.512665) (xy 196.862645 -307.549021) (xy 196.821049 -307.579242) (xy 196.775237 -307.602585)
			(xy 196.726338 -307.618473) (xy 196.675556 -307.626516) (xy 196.62414 -307.626516) (xy 196.573358 -307.618473)
			(xy 196.524459 -307.602585) (xy 196.478647 -307.579242) (xy 196.437051 -307.549021) (xy 196.400695 -307.512665)
			(xy 196.370474 -307.471069) (xy 196.347131 -307.425257) (xy 196.331243 -307.376358) (xy 196.3232 -307.325576)
			(xy 196.026536 -307.325576) (xy 196.018493 -307.376358) (xy 196.002605 -307.425257) (xy 195.979262 -307.471069)
			(xy 195.949041 -307.512665) (xy 195.912685 -307.549021) (xy 195.871089 -307.579242) (xy 195.825277 -307.602585)
			(xy 195.776378 -307.618473) (xy 195.725596 -307.626516) (xy 195.67418 -307.626516) (xy 195.623398 -307.618473)
			(xy 195.574499 -307.602585) (xy 195.528687 -307.579242) (xy 195.487091 -307.549021) (xy 195.450735 -307.512665)
			(xy 195.420514 -307.471069) (xy 195.397171 -307.425257) (xy 195.381283 -307.376358) (xy 195.37324 -307.325576)
			(xy 195.054562 -307.325576) (xy 195.046846 -307.373052) (xy 195.031262 -307.419733) (xy 195.008391 -307.46331)
			(xy 194.978826 -307.502654) (xy 194.943333 -307.536746) (xy 194.90283 -307.564702) (xy 194.858368 -307.5858)
			(xy 194.811097 -307.599492) (xy 194.762242 -307.605424) (xy 194.713067 -307.603443) (xy 194.664848 -307.593599)
			(xy 194.618832 -307.576147) (xy 194.576211 -307.55154) (xy 194.53809 -307.520415) (xy 194.505455 -307.483578)
			(xy 194.479152 -307.441982) (xy 194.459861 -307.396706) (xy 194.448084 -307.348922) (xy 194.444124 -307.299868)
			(xy 194.12712 -307.299868) (xy 194.126616 -307.325576) (xy 194.118573 -307.376358) (xy 194.102685 -307.425257)
			(xy 194.079342 -307.471069) (xy 194.049121 -307.512665) (xy 194.012765 -307.549021) (xy 193.971169 -307.579242)
			(xy 193.925357 -307.602585) (xy 193.876458 -307.618473) (xy 193.825676 -307.626516) (xy 193.77426 -307.626516)
			(xy 193.723478 -307.618473) (xy 193.674579 -307.602585) (xy 193.628767 -307.579242) (xy 193.587171 -307.549021)
			(xy 193.550815 -307.512665) (xy 193.520594 -307.471069) (xy 193.497251 -307.425257) (xy 193.481363 -307.376358)
			(xy 193.47332 -307.325576) (xy 193.176656 -307.325576) (xy 193.168613 -307.376358) (xy 193.152725 -307.425257)
			(xy 193.129382 -307.471069) (xy 193.099161 -307.512665) (xy 193.062805 -307.549021) (xy 193.021209 -307.579242)
			(xy 192.975397 -307.602585) (xy 192.926498 -307.618473) (xy 192.875716 -307.626516) (xy 192.8243 -307.626516)
			(xy 192.773518 -307.618473) (xy 192.724619 -307.602585) (xy 192.678807 -307.579242) (xy 192.637211 -307.549021)
			(xy 192.600855 -307.512665) (xy 192.570634 -307.471069) (xy 192.547291 -307.425257) (xy 192.531403 -307.376358)
			(xy 192.52336 -307.325576) (xy 192.204682 -307.325576) (xy 192.196966 -307.373052) (xy 192.181382 -307.419733)
			(xy 192.158511 -307.46331) (xy 192.128946 -307.502654) (xy 192.093453 -307.536746) (xy 192.05295 -307.564702)
			(xy 192.008488 -307.5858) (xy 191.961217 -307.599492) (xy 191.912362 -307.605424) (xy 191.863187 -307.603443)
			(xy 191.814968 -307.593599) (xy 191.768952 -307.576147) (xy 191.726331 -307.55154) (xy 191.68821 -307.520415)
			(xy 191.655575 -307.483578) (xy 191.629272 -307.441982) (xy 191.609981 -307.396706) (xy 191.598204 -307.348922)
			(xy 191.594244 -307.299868) (xy 191.255396 -307.299868) (xy 191.254901 -307.324475) (xy 191.247006 -307.373052)
			(xy 191.231422 -307.419733) (xy 191.208551 -307.46331) (xy 191.178986 -307.502654) (xy 191.143493 -307.536746)
			(xy 191.10299 -307.564702) (xy 191.058528 -307.5858) (xy 191.011257 -307.599492) (xy 190.962402 -307.605424)
			(xy 190.913227 -307.603443) (xy 190.865008 -307.593599) (xy 190.818992 -307.576147) (xy 190.776371 -307.55154)
			(xy 190.73825 -307.520415) (xy 190.705615 -307.483578) (xy 190.679312 -307.441982) (xy 190.660021 -307.396706)
			(xy 190.648244 -307.348922) (xy 190.644284 -307.299868) (xy 190.305182 -307.299868) (xy 190.304687 -307.324475)
			(xy 190.296792 -307.373052) (xy 190.281208 -307.419733) (xy 190.258337 -307.46331) (xy 190.228772 -307.502654)
			(xy 190.193279 -307.536746) (xy 190.152776 -307.564702) (xy 190.108314 -307.5858) (xy 190.061043 -307.599492)
			(xy 190.012188 -307.605424) (xy 189.963013 -307.603443) (xy 189.914794 -307.593599) (xy 189.868778 -307.576147)
			(xy 189.826157 -307.55154) (xy 189.788036 -307.520415) (xy 189.755401 -307.483578) (xy 189.729098 -307.441982)
			(xy 189.709807 -307.396706) (xy 189.69803 -307.348922) (xy 189.69407 -307.299868) (xy 166.11727 -307.299868)
			(xy 166.11727 -307.774848) (xy 166.419288 -307.774848) (xy 166.423248 -307.725794) (xy 166.435025 -307.67801)
			(xy 166.454316 -307.632734) (xy 166.480619 -307.591138) (xy 166.513254 -307.554301) (xy 166.551375 -307.523176)
			(xy 166.593996 -307.498569) (xy 166.640012 -307.481117) (xy 166.688231 -307.471273) (xy 166.737406 -307.469292)
			(xy 166.786261 -307.475224) (xy 166.833532 -307.488916) (xy 166.877994 -307.510014) (xy 166.918497 -307.53797)
			(xy 166.95399 -307.572062) (xy 166.983555 -307.611406) (xy 167.006426 -307.654983) (xy 167.02201 -307.701664)
			(xy 167.029905 -307.750241) (xy 167.0304 -307.774848) (xy 167.369248 -307.774848) (xy 167.373208 -307.725794)
			(xy 167.384985 -307.67801) (xy 167.404276 -307.632734) (xy 167.430579 -307.591138) (xy 167.463214 -307.554301)
			(xy 167.501335 -307.523176) (xy 167.543956 -307.498569) (xy 167.589972 -307.481117) (xy 167.638191 -307.471273)
			(xy 167.687366 -307.469292) (xy 167.736221 -307.475224) (xy 167.783492 -307.488916) (xy 167.827954 -307.510014)
			(xy 167.868457 -307.53797) (xy 167.90395 -307.572062) (xy 167.933515 -307.611406) (xy 167.956386 -307.654983)
			(xy 167.97197 -307.701664) (xy 167.979865 -307.750241) (xy 167.98036 -307.774848) (xy 168.319208 -307.774848)
			(xy 168.323168 -307.725794) (xy 168.334945 -307.67801) (xy 168.354236 -307.632734) (xy 168.380539 -307.591138)
			(xy 168.413174 -307.554301) (xy 168.451295 -307.523176) (xy 168.493916 -307.498569) (xy 168.539932 -307.481117)
			(xy 168.588151 -307.471273) (xy 168.637326 -307.469292) (xy 168.686181 -307.475224) (xy 168.733452 -307.488916)
			(xy 168.777914 -307.510014) (xy 168.818417 -307.53797) (xy 168.85391 -307.572062) (xy 168.883475 -307.611406)
			(xy 168.906346 -307.654983) (xy 168.92193 -307.701664) (xy 168.929825 -307.750241) (xy 168.93032 -307.774848)
			(xy 169.269168 -307.774848) (xy 169.273128 -307.725794) (xy 169.284905 -307.67801) (xy 169.304196 -307.632734)
			(xy 169.330499 -307.591138) (xy 169.363134 -307.554301) (xy 169.401255 -307.523176) (xy 169.443876 -307.498569)
			(xy 169.489892 -307.481117) (xy 169.538111 -307.471273) (xy 169.587286 -307.469292) (xy 169.636141 -307.475224)
			(xy 169.683412 -307.488916) (xy 169.727874 -307.510014) (xy 169.768377 -307.53797) (xy 169.80387 -307.572062)
			(xy 169.833435 -307.611406) (xy 169.856306 -307.654983) (xy 169.87189 -307.701664) (xy 169.879785 -307.750241)
			(xy 169.88028 -307.774848) (xy 170.219128 -307.774848) (xy 170.223088 -307.725794) (xy 170.234865 -307.67801)
			(xy 170.254156 -307.632734) (xy 170.280459 -307.591138) (xy 170.313094 -307.554301) (xy 170.351215 -307.523176)
			(xy 170.393836 -307.498569) (xy 170.439852 -307.481117) (xy 170.488071 -307.471273) (xy 170.537246 -307.469292)
			(xy 170.586101 -307.475224) (xy 170.633372 -307.488916) (xy 170.677834 -307.510014) (xy 170.718337 -307.53797)
			(xy 170.75383 -307.572062) (xy 170.783395 -307.611406) (xy 170.806266 -307.654983) (xy 170.82185 -307.701664)
			(xy 170.829745 -307.750241) (xy 170.83024 -307.774848) (xy 171.169088 -307.774848) (xy 171.173048 -307.725794)
			(xy 171.184825 -307.67801) (xy 171.204116 -307.632734) (xy 171.230419 -307.591138) (xy 171.263054 -307.554301)
			(xy 171.301175 -307.523176) (xy 171.343796 -307.498569) (xy 171.389812 -307.481117) (xy 171.438031 -307.471273)
			(xy 171.487206 -307.469292) (xy 171.536061 -307.475224) (xy 171.583332 -307.488916) (xy 171.627794 -307.510014)
			(xy 171.668297 -307.53797) (xy 171.70379 -307.572062) (xy 171.733355 -307.611406) (xy 171.756226 -307.654983)
			(xy 171.77181 -307.701664) (xy 171.779705 -307.750241) (xy 171.7802 -307.774848) (xy 172.119302 -307.774848)
			(xy 172.123262 -307.725794) (xy 172.135039 -307.67801) (xy 172.15433 -307.632734) (xy 172.180633 -307.591138)
			(xy 172.213268 -307.554301) (xy 172.251389 -307.523176) (xy 172.29401 -307.498569) (xy 172.340026 -307.481117)
			(xy 172.388245 -307.471273) (xy 172.43742 -307.469292) (xy 172.486275 -307.475224) (xy 172.533546 -307.488916)
			(xy 172.578008 -307.510014) (xy 172.618511 -307.53797) (xy 172.654004 -307.572062) (xy 172.683569 -307.611406)
			(xy 172.70644 -307.654983) (xy 172.722024 -307.701664) (xy 172.729919 -307.750241) (xy 172.730414 -307.774848)
			(xy 173.069262 -307.774848) (xy 173.073222 -307.725794) (xy 173.084999 -307.67801) (xy 173.10429 -307.632734)
			(xy 173.130593 -307.591138) (xy 173.163228 -307.554301) (xy 173.201349 -307.523176) (xy 173.24397 -307.498569)
			(xy 173.289986 -307.481117) (xy 173.338205 -307.471273) (xy 173.38738 -307.469292) (xy 173.436235 -307.475224)
			(xy 173.483506 -307.488916) (xy 173.527968 -307.510014) (xy 173.568471 -307.53797) (xy 173.603964 -307.572062)
			(xy 173.633529 -307.611406) (xy 173.6564 -307.654983) (xy 173.671984 -307.701664) (xy 173.679879 -307.750241)
			(xy 173.680374 -307.774848) (xy 174.019222 -307.774848) (xy 174.023182 -307.725794) (xy 174.034959 -307.67801)
			(xy 174.05425 -307.632734) (xy 174.080553 -307.591138) (xy 174.113188 -307.554301) (xy 174.151309 -307.523176)
			(xy 174.19393 -307.498569) (xy 174.239946 -307.481117) (xy 174.288165 -307.471273) (xy 174.33734 -307.469292)
			(xy 174.386195 -307.475224) (xy 174.433466 -307.488916) (xy 174.477928 -307.510014) (xy 174.518431 -307.53797)
			(xy 174.553924 -307.572062) (xy 174.583489 -307.611406) (xy 174.60636 -307.654983) (xy 174.621944 -307.701664)
			(xy 174.629839 -307.750241) (xy 174.630334 -307.774848) (xy 175.919142 -307.774848) (xy 175.923102 -307.725794)
			(xy 175.934879 -307.67801) (xy 175.95417 -307.632734) (xy 175.980473 -307.591138) (xy 176.013108 -307.554301)
			(xy 176.051229 -307.523176) (xy 176.09385 -307.498569) (xy 176.139866 -307.481117) (xy 176.188085 -307.471273)
			(xy 176.23726 -307.469292) (xy 176.286115 -307.475224) (xy 176.333386 -307.488916) (xy 176.377848 -307.510014)
			(xy 176.418351 -307.53797) (xy 176.453844 -307.572062) (xy 176.483409 -307.611406) (xy 176.50628 -307.654983)
			(xy 176.521864 -307.701664) (xy 176.529759 -307.750241) (xy 176.530254 -307.774848) (xy 176.869102 -307.774848)
			(xy 176.873062 -307.725794) (xy 176.884839 -307.67801) (xy 176.90413 -307.632734) (xy 176.930433 -307.591138)
			(xy 176.963068 -307.554301) (xy 177.001189 -307.523176) (xy 177.04381 -307.498569) (xy 177.089826 -307.481117)
			(xy 177.138045 -307.471273) (xy 177.18722 -307.469292) (xy 177.236075 -307.475224) (xy 177.283346 -307.488916)
			(xy 177.327808 -307.510014) (xy 177.368311 -307.53797) (xy 177.403804 -307.572062) (xy 177.433369 -307.611406)
			(xy 177.45624 -307.654983) (xy 177.471824 -307.701664) (xy 177.479719 -307.750241) (xy 177.480214 -307.774848)
			(xy 177.819062 -307.774848) (xy 177.823022 -307.725794) (xy 177.834799 -307.67801) (xy 177.85409 -307.632734)
			(xy 177.880393 -307.591138) (xy 177.913028 -307.554301) (xy 177.951149 -307.523176) (xy 177.99377 -307.498569)
			(xy 178.039786 -307.481117) (xy 178.088005 -307.471273) (xy 178.13718 -307.469292) (xy 178.186035 -307.475224)
			(xy 178.233306 -307.488916) (xy 178.277768 -307.510014) (xy 178.318271 -307.53797) (xy 178.353764 -307.572062)
			(xy 178.383329 -307.611406) (xy 178.4062 -307.654983) (xy 178.421784 -307.701664) (xy 178.429679 -307.750241)
			(xy 178.430169 -307.774594) (xy 178.769022 -307.774594) (xy 178.772982 -307.72554) (xy 178.784759 -307.677756)
			(xy 178.80405 -307.63248) (xy 178.830353 -307.590884) (xy 178.862988 -307.554047) (xy 178.901109 -307.522922)
			(xy 178.94373 -307.498315) (xy 178.989746 -307.480863) (xy 179.037965 -307.471019) (xy 179.08714 -307.469038)
			(xy 179.135995 -307.47497) (xy 179.183266 -307.488662) (xy 179.227728 -307.50976) (xy 179.268231 -307.537716)
			(xy 179.303724 -307.571808) (xy 179.333289 -307.611152) (xy 179.35616 -307.654729) (xy 179.371744 -307.70141)
			(xy 179.379639 -307.749987) (xy 179.380134 -307.774594) (xy 179.719236 -307.774594) (xy 179.723196 -307.72554)
			(xy 179.734973 -307.677756) (xy 179.754264 -307.63248) (xy 179.780567 -307.590884) (xy 179.813202 -307.554047)
			(xy 179.851323 -307.522922) (xy 179.893944 -307.498315) (xy 179.93996 -307.480863) (xy 179.988179 -307.471019)
			(xy 180.037354 -307.469038) (xy 180.086209 -307.47497) (xy 180.13348 -307.488662) (xy 180.177942 -307.50976)
			(xy 180.218445 -307.537716) (xy 180.253938 -307.571808) (xy 180.283503 -307.611152) (xy 180.306374 -307.654729)
			(xy 180.321958 -307.70141) (xy 180.329853 -307.749987) (xy 180.330348 -307.774594) (xy 180.330343 -307.774848)
			(xy 180.669196 -307.774848) (xy 180.673156 -307.725794) (xy 180.684933 -307.67801) (xy 180.704224 -307.632734)
			(xy 180.730527 -307.591138) (xy 180.763162 -307.554301) (xy 180.801283 -307.523176) (xy 180.843904 -307.498569)
			(xy 180.88992 -307.481117) (xy 180.938139 -307.471273) (xy 180.987314 -307.469292) (xy 181.036169 -307.475224)
			(xy 181.08344 -307.488916) (xy 181.127902 -307.510014) (xy 181.168405 -307.53797) (xy 181.203898 -307.572062)
			(xy 181.233463 -307.611406) (xy 181.256334 -307.654983) (xy 181.271918 -307.701664) (xy 181.279813 -307.750241)
			(xy 181.280308 -307.774848) (xy 181.619156 -307.774848) (xy 181.623116 -307.725794) (xy 181.634893 -307.67801)
			(xy 181.654184 -307.632734) (xy 181.680487 -307.591138) (xy 181.713122 -307.554301) (xy 181.751243 -307.523176)
			(xy 181.793864 -307.498569) (xy 181.83988 -307.481117) (xy 181.888099 -307.471273) (xy 181.937274 -307.469292)
			(xy 181.986129 -307.475224) (xy 182.0334 -307.488916) (xy 182.077862 -307.510014) (xy 182.118365 -307.53797)
			(xy 182.153858 -307.572062) (xy 182.183423 -307.611406) (xy 182.206294 -307.654983) (xy 182.221878 -307.701664)
			(xy 182.229773 -307.750241) (xy 182.230268 -307.774848) (xy 182.569116 -307.774848) (xy 182.573076 -307.725794)
			(xy 182.584853 -307.67801) (xy 182.604144 -307.632734) (xy 182.630447 -307.591138) (xy 182.663082 -307.554301)
			(xy 182.701203 -307.523176) (xy 182.743824 -307.498569) (xy 182.78984 -307.481117) (xy 182.838059 -307.471273)
			(xy 182.887234 -307.469292) (xy 182.936089 -307.475224) (xy 182.98336 -307.488916) (xy 183.027822 -307.510014)
			(xy 183.068325 -307.53797) (xy 183.103818 -307.572062) (xy 183.133383 -307.611406) (xy 183.156254 -307.654983)
			(xy 183.171838 -307.701664) (xy 183.179733 -307.750241) (xy 183.180228 -307.774848) (xy 183.519076 -307.774848)
			(xy 183.523036 -307.725794) (xy 183.534813 -307.67801) (xy 183.554104 -307.632734) (xy 183.580407 -307.591138)
			(xy 183.613042 -307.554301) (xy 183.651163 -307.523176) (xy 183.693784 -307.498569) (xy 183.7398 -307.481117)
			(xy 183.788019 -307.471273) (xy 183.837194 -307.469292) (xy 183.886049 -307.475224) (xy 183.93332 -307.488916)
			(xy 183.977782 -307.510014) (xy 184.018285 -307.53797) (xy 184.053778 -307.572062) (xy 184.083343 -307.611406)
			(xy 184.106214 -307.654983) (xy 184.121798 -307.701664) (xy 184.129693 -307.750241) (xy 184.130188 -307.774848)
			(xy 184.469036 -307.774848) (xy 184.472996 -307.725794) (xy 184.484773 -307.67801) (xy 184.504064 -307.632734)
			(xy 184.530367 -307.591138) (xy 184.563002 -307.554301) (xy 184.601123 -307.523176) (xy 184.643744 -307.498569)
			(xy 184.68976 -307.481117) (xy 184.737979 -307.471273) (xy 184.787154 -307.469292) (xy 184.836009 -307.475224)
			(xy 184.88328 -307.488916) (xy 184.927742 -307.510014) (xy 184.968245 -307.53797) (xy 185.003738 -307.572062)
			(xy 185.033303 -307.611406) (xy 185.056174 -307.654983) (xy 185.071758 -307.701664) (xy 185.079653 -307.750241)
			(xy 185.080148 -307.774848) (xy 185.41925 -307.774848) (xy 185.42321 -307.725794) (xy 185.434987 -307.67801)
			(xy 185.454278 -307.632734) (xy 185.480581 -307.591138) (xy 185.513216 -307.554301) (xy 185.551337 -307.523176)
			(xy 185.593958 -307.498569) (xy 185.639974 -307.481117) (xy 185.688193 -307.471273) (xy 185.737368 -307.469292)
			(xy 185.786223 -307.475224) (xy 185.833494 -307.488916) (xy 185.877956 -307.510014) (xy 185.918459 -307.53797)
			(xy 185.953952 -307.572062) (xy 185.983517 -307.611406) (xy 186.006388 -307.654983) (xy 186.021972 -307.701664)
			(xy 186.029867 -307.750241) (xy 186.030362 -307.774848) (xy 186.36921 -307.774848) (xy 186.37317 -307.725794)
			(xy 186.384947 -307.67801) (xy 186.404238 -307.632734) (xy 186.430541 -307.591138) (xy 186.463176 -307.554301)
			(xy 186.501297 -307.523176) (xy 186.543918 -307.498569) (xy 186.589934 -307.481117) (xy 186.638153 -307.471273)
			(xy 186.687328 -307.469292) (xy 186.736183 -307.475224) (xy 186.783454 -307.488916) (xy 186.827916 -307.510014)
			(xy 186.868419 -307.53797) (xy 186.903912 -307.572062) (xy 186.933477 -307.611406) (xy 186.956348 -307.654983)
			(xy 186.971932 -307.701664) (xy 186.979827 -307.750241) (xy 186.980322 -307.774848) (xy 187.31917 -307.774848)
			(xy 187.32313 -307.725794) (xy 187.334907 -307.67801) (xy 187.354198 -307.632734) (xy 187.380501 -307.591138)
			(xy 187.413136 -307.554301) (xy 187.451257 -307.523176) (xy 187.493878 -307.498569) (xy 187.539894 -307.481117)
			(xy 187.588113 -307.471273) (xy 187.637288 -307.469292) (xy 187.686143 -307.475224) (xy 187.733414 -307.488916)
			(xy 187.777876 -307.510014) (xy 187.818379 -307.53797) (xy 187.853872 -307.572062) (xy 187.883437 -307.611406)
			(xy 187.906308 -307.654983) (xy 187.921892 -307.701664) (xy 187.929787 -307.750241) (xy 187.930282 -307.774848)
			(xy 188.26913 -307.774848) (xy 188.27309 -307.725794) (xy 188.284867 -307.67801) (xy 188.304158 -307.632734)
			(xy 188.330461 -307.591138) (xy 188.363096 -307.554301) (xy 188.401217 -307.523176) (xy 188.443838 -307.498569)
			(xy 188.489854 -307.481117) (xy 188.538073 -307.471273) (xy 188.587248 -307.469292) (xy 188.636103 -307.475224)
			(xy 188.683374 -307.488916) (xy 188.727836 -307.510014) (xy 188.768339 -307.53797) (xy 188.803832 -307.572062)
			(xy 188.833397 -307.611406) (xy 188.856268 -307.654983) (xy 188.871852 -307.701664) (xy 188.879747 -307.750241)
			(xy 188.880242 -307.774848) (xy 188.879747 -307.799455) (xy 188.871852 -307.848032) (xy 188.856268 -307.894713)
			(xy 188.833397 -307.93829) (xy 188.803832 -307.977634) (xy 188.768339 -308.011726) (xy 188.727836 -308.039682)
			(xy 188.683374 -308.06078) (xy 188.636103 -308.074472) (xy 188.587248 -308.080404) (xy 188.538073 -308.078423)
			(xy 188.489854 -308.068579) (xy 188.443838 -308.051127) (xy 188.401217 -308.02652) (xy 188.363096 -307.995395)
			(xy 188.330461 -307.958558) (xy 188.304158 -307.916962) (xy 188.284867 -307.871686) (xy 188.27309 -307.823902)
			(xy 188.26913 -307.774848) (xy 187.930282 -307.774848) (xy 187.929787 -307.799455) (xy 187.921892 -307.848032)
			(xy 187.906308 -307.894713) (xy 187.883437 -307.93829) (xy 187.853872 -307.977634) (xy 187.818379 -308.011726)
			(xy 187.777876 -308.039682) (xy 187.733414 -308.06078) (xy 187.686143 -308.074472) (xy 187.637288 -308.080404)
			(xy 187.588113 -308.078423) (xy 187.539894 -308.068579) (xy 187.493878 -308.051127) (xy 187.451257 -308.02652)
			(xy 187.413136 -307.995395) (xy 187.380501 -307.958558) (xy 187.354198 -307.916962) (xy 187.334907 -307.871686)
			(xy 187.32313 -307.823902) (xy 187.31917 -307.774848) (xy 186.980322 -307.774848) (xy 186.979827 -307.799455)
			(xy 186.971932 -307.848032) (xy 186.956348 -307.894713) (xy 186.933477 -307.93829) (xy 186.903912 -307.977634)
			(xy 186.868419 -308.011726) (xy 186.827916 -308.039682) (xy 186.783454 -308.06078) (xy 186.736183 -308.074472)
			(xy 186.687328 -308.080404) (xy 186.638153 -308.078423) (xy 186.589934 -308.068579) (xy 186.543918 -308.051127)
			(xy 186.501297 -308.02652) (xy 186.463176 -307.995395) (xy 186.430541 -307.958558) (xy 186.404238 -307.916962)
			(xy 186.384947 -307.871686) (xy 186.37317 -307.823902) (xy 186.36921 -307.774848) (xy 186.030362 -307.774848)
			(xy 186.029867 -307.799455) (xy 186.021972 -307.848032) (xy 186.006388 -307.894713) (xy 185.983517 -307.93829)
			(xy 185.953952 -307.977634) (xy 185.918459 -308.011726) (xy 185.877956 -308.039682) (xy 185.833494 -308.06078)
			(xy 185.786223 -308.074472) (xy 185.737368 -308.080404) (xy 185.688193 -308.078423) (xy 185.639974 -308.068579)
			(xy 185.593958 -308.051127) (xy 185.551337 -308.02652) (xy 185.513216 -307.995395) (xy 185.480581 -307.958558)
			(xy 185.454278 -307.916962) (xy 185.434987 -307.871686) (xy 185.42321 -307.823902) (xy 185.41925 -307.774848)
			(xy 185.080148 -307.774848) (xy 185.079653 -307.799455) (xy 185.071758 -307.848032) (xy 185.056174 -307.894713)
			(xy 185.033303 -307.93829) (xy 185.003738 -307.977634) (xy 184.968245 -308.011726) (xy 184.927742 -308.039682)
			(xy 184.88328 -308.06078) (xy 184.836009 -308.074472) (xy 184.787154 -308.080404) (xy 184.737979 -308.078423)
			(xy 184.68976 -308.068579) (xy 184.643744 -308.051127) (xy 184.601123 -308.02652) (xy 184.563002 -307.995395)
			(xy 184.530367 -307.958558) (xy 184.504064 -307.916962) (xy 184.484773 -307.871686) (xy 184.472996 -307.823902)
			(xy 184.469036 -307.774848) (xy 184.130188 -307.774848) (xy 184.129693 -307.799455) (xy 184.121798 -307.848032)
			(xy 184.106214 -307.894713) (xy 184.083343 -307.93829) (xy 184.053778 -307.977634) (xy 184.018285 -308.011726)
			(xy 183.977782 -308.039682) (xy 183.93332 -308.06078) (xy 183.886049 -308.074472) (xy 183.837194 -308.080404)
			(xy 183.788019 -308.078423) (xy 183.7398 -308.068579) (xy 183.693784 -308.051127) (xy 183.651163 -308.02652)
			(xy 183.613042 -307.995395) (xy 183.580407 -307.958558) (xy 183.554104 -307.916962) (xy 183.534813 -307.871686)
			(xy 183.523036 -307.823902) (xy 183.519076 -307.774848) (xy 183.180228 -307.774848) (xy 183.179733 -307.799455)
			(xy 183.171838 -307.848032) (xy 183.156254 -307.894713) (xy 183.133383 -307.93829) (xy 183.103818 -307.977634)
			(xy 183.068325 -308.011726) (xy 183.027822 -308.039682) (xy 182.98336 -308.06078) (xy 182.936089 -308.074472)
			(xy 182.887234 -308.080404) (xy 182.838059 -308.078423) (xy 182.78984 -308.068579) (xy 182.743824 -308.051127)
			(xy 182.701203 -308.02652) (xy 182.663082 -307.995395) (xy 182.630447 -307.958558) (xy 182.604144 -307.916962)
			(xy 182.584853 -307.871686) (xy 182.573076 -307.823902) (xy 182.569116 -307.774848) (xy 182.230268 -307.774848)
			(xy 182.229773 -307.799455) (xy 182.221878 -307.848032) (xy 182.206294 -307.894713) (xy 182.183423 -307.93829)
			(xy 182.153858 -307.977634) (xy 182.118365 -308.011726) (xy 182.077862 -308.039682) (xy 182.0334 -308.06078)
			(xy 181.986129 -308.074472) (xy 181.937274 -308.080404) (xy 181.888099 -308.078423) (xy 181.83988 -308.068579)
			(xy 181.793864 -308.051127) (xy 181.751243 -308.02652) (xy 181.713122 -307.995395) (xy 181.680487 -307.958558)
			(xy 181.654184 -307.916962) (xy 181.634893 -307.871686) (xy 181.623116 -307.823902) (xy 181.619156 -307.774848)
			(xy 181.280308 -307.774848) (xy 181.279813 -307.799455) (xy 181.271918 -307.848032) (xy 181.256334 -307.894713)
			(xy 181.233463 -307.93829) (xy 181.203898 -307.977634) (xy 181.168405 -308.011726) (xy 181.127902 -308.039682)
			(xy 181.08344 -308.06078) (xy 181.036169 -308.074472) (xy 180.987314 -308.080404) (xy 180.938139 -308.078423)
			(xy 180.88992 -308.068579) (xy 180.843904 -308.051127) (xy 180.801283 -308.02652) (xy 180.763162 -307.995395)
			(xy 180.730527 -307.958558) (xy 180.704224 -307.916962) (xy 180.684933 -307.871686) (xy 180.673156 -307.823902)
			(xy 180.669196 -307.774848) (xy 180.330343 -307.774848) (xy 180.329853 -307.799201) (xy 180.321958 -307.847778)
			(xy 180.306374 -307.894459) (xy 180.283503 -307.938036) (xy 180.253938 -307.97738) (xy 180.218445 -308.011472)
			(xy 180.177942 -308.039428) (xy 180.13348 -308.060526) (xy 180.086209 -308.074218) (xy 180.037354 -308.08015)
			(xy 179.988179 -308.078169) (xy 179.93996 -308.068325) (xy 179.893944 -308.050873) (xy 179.851323 -308.026266)
			(xy 179.813202 -307.995141) (xy 179.780567 -307.958304) (xy 179.754264 -307.916708) (xy 179.734973 -307.871432)
			(xy 179.723196 -307.823648) (xy 179.719236 -307.774594) (xy 179.380134 -307.774594) (xy 179.379639 -307.799201)
			(xy 179.371744 -307.847778) (xy 179.35616 -307.894459) (xy 179.333289 -307.938036) (xy 179.303724 -307.97738)
			(xy 179.268231 -308.011472) (xy 179.227728 -308.039428) (xy 179.183266 -308.060526) (xy 179.135995 -308.074218)
			(xy 179.08714 -308.08015) (xy 179.037965 -308.078169) (xy 178.989746 -308.068325) (xy 178.94373 -308.050873)
			(xy 178.901109 -308.026266) (xy 178.862988 -307.995141) (xy 178.830353 -307.958304) (xy 178.80405 -307.916708)
			(xy 178.784759 -307.871432) (xy 178.772982 -307.823648) (xy 178.769022 -307.774594) (xy 178.430169 -307.774594)
			(xy 178.430174 -307.774848) (xy 178.429679 -307.799455) (xy 178.421784 -307.848032) (xy 178.4062 -307.894713)
			(xy 178.383329 -307.93829) (xy 178.353764 -307.977634) (xy 178.318271 -308.011726) (xy 178.277768 -308.039682)
			(xy 178.233306 -308.06078) (xy 178.186035 -308.074472) (xy 178.13718 -308.080404) (xy 178.088005 -308.078423)
			(xy 178.039786 -308.068579) (xy 177.99377 -308.051127) (xy 177.951149 -308.02652) (xy 177.913028 -307.995395)
			(xy 177.880393 -307.958558) (xy 177.85409 -307.916962) (xy 177.834799 -307.871686) (xy 177.823022 -307.823902)
			(xy 177.819062 -307.774848) (xy 177.480214 -307.774848) (xy 177.479719 -307.799455) (xy 177.471824 -307.848032)
			(xy 177.45624 -307.894713) (xy 177.433369 -307.93829) (xy 177.403804 -307.977634) (xy 177.368311 -308.011726)
			(xy 177.327808 -308.039682) (xy 177.283346 -308.06078) (xy 177.236075 -308.074472) (xy 177.18722 -308.080404)
			(xy 177.138045 -308.078423) (xy 177.089826 -308.068579) (xy 177.04381 -308.051127) (xy 177.001189 -308.02652)
			(xy 176.963068 -307.995395) (xy 176.930433 -307.958558) (xy 176.90413 -307.916962) (xy 176.884839 -307.871686)
			(xy 176.873062 -307.823902) (xy 176.869102 -307.774848) (xy 176.530254 -307.774848) (xy 176.529759 -307.799455)
			(xy 176.521864 -307.848032) (xy 176.50628 -307.894713) (xy 176.483409 -307.93829) (xy 176.453844 -307.977634)
			(xy 176.418351 -308.011726) (xy 176.377848 -308.039682) (xy 176.333386 -308.06078) (xy 176.286115 -308.074472)
			(xy 176.23726 -308.080404) (xy 176.188085 -308.078423) (xy 176.139866 -308.068579) (xy 176.09385 -308.051127)
			(xy 176.051229 -308.02652) (xy 176.013108 -307.995395) (xy 175.980473 -307.958558) (xy 175.95417 -307.916962)
			(xy 175.934879 -307.871686) (xy 175.923102 -307.823902) (xy 175.919142 -307.774848) (xy 174.630334 -307.774848)
			(xy 174.629839 -307.799455) (xy 174.621944 -307.848032) (xy 174.60636 -307.894713) (xy 174.583489 -307.93829)
			(xy 174.553924 -307.977634) (xy 174.518431 -308.011726) (xy 174.477928 -308.039682) (xy 174.433466 -308.06078)
			(xy 174.386195 -308.074472) (xy 174.33734 -308.080404) (xy 174.288165 -308.078423) (xy 174.239946 -308.068579)
			(xy 174.19393 -308.051127) (xy 174.151309 -308.02652) (xy 174.113188 -307.995395) (xy 174.080553 -307.958558)
			(xy 174.05425 -307.916962) (xy 174.034959 -307.871686) (xy 174.023182 -307.823902) (xy 174.019222 -307.774848)
			(xy 173.680374 -307.774848) (xy 173.679879 -307.799455) (xy 173.671984 -307.848032) (xy 173.6564 -307.894713)
			(xy 173.633529 -307.93829) (xy 173.603964 -307.977634) (xy 173.568471 -308.011726) (xy 173.527968 -308.039682)
			(xy 173.483506 -308.06078) (xy 173.436235 -308.074472) (xy 173.38738 -308.080404) (xy 173.338205 -308.078423)
			(xy 173.289986 -308.068579) (xy 173.24397 -308.051127) (xy 173.201349 -308.02652) (xy 173.163228 -307.995395)
			(xy 173.130593 -307.958558) (xy 173.10429 -307.916962) (xy 173.084999 -307.871686) (xy 173.073222 -307.823902)
			(xy 173.069262 -307.774848) (xy 172.730414 -307.774848) (xy 172.729919 -307.799455) (xy 172.722024 -307.848032)
			(xy 172.70644 -307.894713) (xy 172.683569 -307.93829) (xy 172.654004 -307.977634) (xy 172.618511 -308.011726)
			(xy 172.578008 -308.039682) (xy 172.533546 -308.06078) (xy 172.486275 -308.074472) (xy 172.43742 -308.080404)
			(xy 172.388245 -308.078423) (xy 172.340026 -308.068579) (xy 172.29401 -308.051127) (xy 172.251389 -308.02652)
			(xy 172.213268 -307.995395) (xy 172.180633 -307.958558) (xy 172.15433 -307.916962) (xy 172.135039 -307.871686)
			(xy 172.123262 -307.823902) (xy 172.119302 -307.774848) (xy 171.7802 -307.774848) (xy 171.779705 -307.799455)
			(xy 171.77181 -307.848032) (xy 171.756226 -307.894713) (xy 171.733355 -307.93829) (xy 171.70379 -307.977634)
			(xy 171.668297 -308.011726) (xy 171.627794 -308.039682) (xy 171.583332 -308.06078) (xy 171.536061 -308.074472)
			(xy 171.487206 -308.080404) (xy 171.438031 -308.078423) (xy 171.389812 -308.068579) (xy 171.343796 -308.051127)
			(xy 171.301175 -308.02652) (xy 171.263054 -307.995395) (xy 171.230419 -307.958558) (xy 171.204116 -307.916962)
			(xy 171.184825 -307.871686) (xy 171.173048 -307.823902) (xy 171.169088 -307.774848) (xy 170.83024 -307.774848)
			(xy 170.829745 -307.799455) (xy 170.82185 -307.848032) (xy 170.806266 -307.894713) (xy 170.783395 -307.93829)
			(xy 170.75383 -307.977634) (xy 170.718337 -308.011726) (xy 170.677834 -308.039682) (xy 170.633372 -308.06078)
			(xy 170.586101 -308.074472) (xy 170.537246 -308.080404) (xy 170.488071 -308.078423) (xy 170.439852 -308.068579)
			(xy 170.393836 -308.051127) (xy 170.351215 -308.02652) (xy 170.313094 -307.995395) (xy 170.280459 -307.958558)
			(xy 170.254156 -307.916962) (xy 170.234865 -307.871686) (xy 170.223088 -307.823902) (xy 170.219128 -307.774848)
			(xy 169.88028 -307.774848) (xy 169.879785 -307.799455) (xy 169.87189 -307.848032) (xy 169.856306 -307.894713)
			(xy 169.833435 -307.93829) (xy 169.80387 -307.977634) (xy 169.768377 -308.011726) (xy 169.727874 -308.039682)
			(xy 169.683412 -308.06078) (xy 169.636141 -308.074472) (xy 169.587286 -308.080404) (xy 169.538111 -308.078423)
			(xy 169.489892 -308.068579) (xy 169.443876 -308.051127) (xy 169.401255 -308.02652) (xy 169.363134 -307.995395)
			(xy 169.330499 -307.958558) (xy 169.304196 -307.916962) (xy 169.284905 -307.871686) (xy 169.273128 -307.823902)
			(xy 169.269168 -307.774848) (xy 168.93032 -307.774848) (xy 168.929825 -307.799455) (xy 168.92193 -307.848032)
			(xy 168.906346 -307.894713) (xy 168.883475 -307.93829) (xy 168.85391 -307.977634) (xy 168.818417 -308.011726)
			(xy 168.777914 -308.039682) (xy 168.733452 -308.06078) (xy 168.686181 -308.074472) (xy 168.637326 -308.080404)
			(xy 168.588151 -308.078423) (xy 168.539932 -308.068579) (xy 168.493916 -308.051127) (xy 168.451295 -308.02652)
			(xy 168.413174 -307.995395) (xy 168.380539 -307.958558) (xy 168.354236 -307.916962) (xy 168.334945 -307.871686)
			(xy 168.323168 -307.823902) (xy 168.319208 -307.774848) (xy 167.98036 -307.774848) (xy 167.979865 -307.799455)
			(xy 167.97197 -307.848032) (xy 167.956386 -307.894713) (xy 167.933515 -307.93829) (xy 167.90395 -307.977634)
			(xy 167.868457 -308.011726) (xy 167.827954 -308.039682) (xy 167.783492 -308.06078) (xy 167.736221 -308.074472)
			(xy 167.687366 -308.080404) (xy 167.638191 -308.078423) (xy 167.589972 -308.068579) (xy 167.543956 -308.051127)
			(xy 167.501335 -308.02652) (xy 167.463214 -307.995395) (xy 167.430579 -307.958558) (xy 167.404276 -307.916962)
			(xy 167.384985 -307.871686) (xy 167.373208 -307.823902) (xy 167.369248 -307.774848) (xy 167.0304 -307.774848)
			(xy 167.029905 -307.799455) (xy 167.02201 -307.848032) (xy 167.006426 -307.894713) (xy 166.983555 -307.93829)
			(xy 166.95399 -307.977634) (xy 166.918497 -308.011726) (xy 166.877994 -308.039682) (xy 166.833532 -308.06078)
			(xy 166.786261 -308.074472) (xy 166.737406 -308.080404) (xy 166.688231 -308.078423) (xy 166.640012 -308.068579)
			(xy 166.593996 -308.051127) (xy 166.551375 -308.02652) (xy 166.513254 -307.995395) (xy 166.480619 -307.958558)
			(xy 166.454316 -307.916962) (xy 166.435025 -307.871686) (xy 166.423248 -307.823902) (xy 166.419288 -307.774848)
			(xy 166.11727 -307.774848) (xy 166.11727 -308.249828) (xy 189.69407 -308.249828) (xy 189.69803 -308.200774)
			(xy 189.709807 -308.15299) (xy 189.729098 -308.107714) (xy 189.755401 -308.066118) (xy 189.788036 -308.029281)
			(xy 189.826157 -307.998156) (xy 189.868778 -307.973549) (xy 189.914794 -307.956097) (xy 189.963013 -307.946253)
			(xy 190.012188 -307.944272) (xy 190.061043 -307.950204) (xy 190.108314 -307.963896) (xy 190.152776 -307.984994)
			(xy 190.193279 -308.01295) (xy 190.228772 -308.047042) (xy 190.258337 -308.086386) (xy 190.281208 -308.129963)
			(xy 190.296792 -308.176644) (xy 190.304687 -308.225221) (xy 190.305182 -308.249828) (xy 190.304687 -308.274435)
			(xy 190.304508 -308.275536) (xy 190.62344 -308.275536) (xy 190.62344 -308.22412) (xy 190.631483 -308.173338)
			(xy 190.647371 -308.124439) (xy 190.670714 -308.078627) (xy 190.700935 -308.037031) (xy 190.737291 -308.000675)
			(xy 190.778887 -307.970454) (xy 190.824699 -307.947111) (xy 190.873598 -307.931223) (xy 190.92438 -307.92318)
			(xy 190.975796 -307.92318) (xy 191.026578 -307.931223) (xy 191.075477 -307.947111) (xy 191.121289 -307.970454)
			(xy 191.162885 -308.000675) (xy 191.199241 -308.037031) (xy 191.229462 -308.078627) (xy 191.252805 -308.124439)
			(xy 191.268693 -308.173338) (xy 191.276736 -308.22412) (xy 191.27724 -308.249828) (xy 191.276736 -308.275536)
			(xy 191.5734 -308.275536) (xy 191.5734 -308.22412) (xy 191.581443 -308.173338) (xy 191.597331 -308.124439)
			(xy 191.620674 -308.078627) (xy 191.650895 -308.037031) (xy 191.687251 -308.000675) (xy 191.728847 -307.970454)
			(xy 191.774659 -307.947111) (xy 191.823558 -307.931223) (xy 191.87434 -307.92318) (xy 191.925756 -307.92318)
			(xy 191.976538 -307.931223) (xy 192.025437 -307.947111) (xy 192.071249 -307.970454) (xy 192.112845 -308.000675)
			(xy 192.149201 -308.037031) (xy 192.179422 -308.078627) (xy 192.202765 -308.124439) (xy 192.218653 -308.173338)
			(xy 192.226696 -308.22412) (xy 192.2272 -308.249828) (xy 192.544204 -308.249828) (xy 192.548164 -308.200774)
			(xy 192.559941 -308.15299) (xy 192.579232 -308.107714) (xy 192.605535 -308.066118) (xy 192.63817 -308.029281)
			(xy 192.676291 -307.998156) (xy 192.718912 -307.973549) (xy 192.764928 -307.956097) (xy 192.813147 -307.946253)
			(xy 192.862322 -307.944272) (xy 192.911177 -307.950204) (xy 192.958448 -307.963896) (xy 193.00291 -307.984994)
			(xy 193.043413 -308.01295) (xy 193.078906 -308.047042) (xy 193.108471 -308.086386) (xy 193.131342 -308.129963)
			(xy 193.146926 -308.176644) (xy 193.154821 -308.225221) (xy 193.155316 -308.249828) (xy 193.494164 -308.249828)
			(xy 193.498124 -308.200774) (xy 193.509901 -308.15299) (xy 193.529192 -308.107714) (xy 193.555495 -308.066118)
			(xy 193.58813 -308.029281) (xy 193.626251 -307.998156) (xy 193.668872 -307.973549) (xy 193.714888 -307.956097)
			(xy 193.763107 -307.946253) (xy 193.812282 -307.944272) (xy 193.861137 -307.950204) (xy 193.908408 -307.963896)
			(xy 193.95287 -307.984994) (xy 193.993373 -308.01295) (xy 194.028866 -308.047042) (xy 194.058431 -308.086386)
			(xy 194.081302 -308.129963) (xy 194.096886 -308.176644) (xy 194.104781 -308.225221) (xy 194.105276 -308.249828)
			(xy 194.444124 -308.249828) (xy 194.448084 -308.200774) (xy 194.459861 -308.15299) (xy 194.479152 -308.107714)
			(xy 194.505455 -308.066118) (xy 194.53809 -308.029281) (xy 194.576211 -307.998156) (xy 194.618832 -307.973549)
			(xy 194.664848 -307.956097) (xy 194.713067 -307.946253) (xy 194.762242 -307.944272) (xy 194.811097 -307.950204)
			(xy 194.858368 -307.963896) (xy 194.90283 -307.984994) (xy 194.943333 -308.01295) (xy 194.978826 -308.047042)
			(xy 195.008391 -308.086386) (xy 195.031262 -308.129963) (xy 195.046846 -308.176644) (xy 195.054741 -308.225221)
			(xy 195.055236 -308.249828) (xy 195.394084 -308.249828) (xy 195.398044 -308.200774) (xy 195.409821 -308.15299)
			(xy 195.429112 -308.107714) (xy 195.455415 -308.066118) (xy 195.48805 -308.029281) (xy 195.526171 -307.998156)
			(xy 195.568792 -307.973549) (xy 195.614808 -307.956097) (xy 195.663027 -307.946253) (xy 195.712202 -307.944272)
			(xy 195.761057 -307.950204) (xy 195.808328 -307.963896) (xy 195.85279 -307.984994) (xy 195.893293 -308.01295)
			(xy 195.928786 -308.047042) (xy 195.958351 -308.086386) (xy 195.981222 -308.129963) (xy 195.996806 -308.176644)
			(xy 196.004701 -308.225221) (xy 196.005196 -308.249828) (xy 196.344044 -308.249828) (xy 196.348004 -308.200774)
			(xy 196.359781 -308.15299) (xy 196.379072 -308.107714) (xy 196.405375 -308.066118) (xy 196.43801 -308.029281)
			(xy 196.476131 -307.998156) (xy 196.518752 -307.973549) (xy 196.564768 -307.956097) (xy 196.612987 -307.946253)
			(xy 196.662162 -307.944272) (xy 196.711017 -307.950204) (xy 196.758288 -307.963896) (xy 196.80275 -307.984994)
			(xy 196.843253 -308.01295) (xy 196.878746 -308.047042) (xy 196.908311 -308.086386) (xy 196.931182 -308.129963)
			(xy 196.946766 -308.176644) (xy 196.954661 -308.225221) (xy 196.955156 -308.249828) (xy 196.954661 -308.274435)
			(xy 196.954482 -308.275536) (xy 197.273414 -308.275536) (xy 197.273414 -308.22412) (xy 197.281457 -308.173338)
			(xy 197.297345 -308.124439) (xy 197.320688 -308.078627) (xy 197.350909 -308.037031) (xy 197.387265 -308.000675)
			(xy 197.428861 -307.970454) (xy 197.474673 -307.947111) (xy 197.523572 -307.931223) (xy 197.574354 -307.92318)
			(xy 197.62577 -307.92318) (xy 197.676552 -307.931223) (xy 197.725451 -307.947111) (xy 197.771263 -307.970454)
			(xy 197.812859 -308.000675) (xy 197.849215 -308.037031) (xy 197.879436 -308.078627) (xy 197.902779 -308.124439)
			(xy 197.918667 -308.173338) (xy 197.92671 -308.22412) (xy 197.927214 -308.249828) (xy 197.92671 -308.275536)
			(xy 198.223374 -308.275536) (xy 198.223374 -308.22412) (xy 198.231417 -308.173338) (xy 198.247305 -308.124439)
			(xy 198.270648 -308.078627) (xy 198.300869 -308.037031) (xy 198.337225 -308.000675) (xy 198.378821 -307.970454)
			(xy 198.424633 -307.947111) (xy 198.473532 -307.931223) (xy 198.524314 -307.92318) (xy 198.57573 -307.92318)
			(xy 198.626512 -307.931223) (xy 198.675411 -307.947111) (xy 198.721223 -307.970454) (xy 198.762819 -308.000675)
			(xy 198.799175 -308.037031) (xy 198.829396 -308.078627) (xy 198.852739 -308.124439) (xy 198.868627 -308.173338)
			(xy 198.87667 -308.22412) (xy 198.877174 -308.249828) (xy 199.194432 -308.249828) (xy 199.198392 -308.200774)
			(xy 199.210169 -308.15299) (xy 199.22946 -308.107714) (xy 199.255763 -308.066118) (xy 199.288398 -308.029281)
			(xy 199.326519 -307.998156) (xy 199.36914 -307.973549) (xy 199.415156 -307.956097) (xy 199.463375 -307.946253)
			(xy 199.51255 -307.944272) (xy 199.561405 -307.950204) (xy 199.608676 -307.963896) (xy 199.653138 -307.984994)
			(xy 199.693641 -308.01295) (xy 199.729134 -308.047042) (xy 199.758699 -308.086386) (xy 199.78157 -308.129963)
			(xy 199.797154 -308.176644) (xy 199.805049 -308.225221) (xy 199.805544 -308.249828) (xy 199.805049 -308.274435)
			(xy 199.797154 -308.323012) (xy 199.78157 -308.369693) (xy 199.758699 -308.41327) (xy 199.729134 -308.452614)
			(xy 199.693641 -308.486706) (xy 199.653138 -308.514662) (xy 199.608676 -308.53576) (xy 199.561405 -308.549452)
			(xy 199.51255 -308.555384) (xy 199.463375 -308.553403) (xy 199.415156 -308.543559) (xy 199.36914 -308.526107)
			(xy 199.326519 -308.5015) (xy 199.288398 -308.470375) (xy 199.255763 -308.433538) (xy 199.22946 -308.391942)
			(xy 199.210169 -308.346666) (xy 199.198392 -308.298882) (xy 199.194432 -308.249828) (xy 198.877174 -308.249828)
			(xy 198.87667 -308.275536) (xy 198.868627 -308.326318) (xy 198.852739 -308.375217) (xy 198.829396 -308.421029)
			(xy 198.799175 -308.462625) (xy 198.762819 -308.498981) (xy 198.721223 -308.529202) (xy 198.675411 -308.552545)
			(xy 198.626512 -308.568433) (xy 198.57573 -308.576476) (xy 198.524314 -308.576476) (xy 198.473532 -308.568433)
			(xy 198.424633 -308.552545) (xy 198.378821 -308.529202) (xy 198.337225 -308.498981) (xy 198.300869 -308.462625)
			(xy 198.270648 -308.421029) (xy 198.247305 -308.375217) (xy 198.231417 -308.326318) (xy 198.223374 -308.275536)
			(xy 197.92671 -308.275536) (xy 197.918667 -308.326318) (xy 197.902779 -308.375217) (xy 197.879436 -308.421029)
			(xy 197.849215 -308.462625) (xy 197.812859 -308.498981) (xy 197.771263 -308.529202) (xy 197.725451 -308.552545)
			(xy 197.676552 -308.568433) (xy 197.62577 -308.576476) (xy 197.574354 -308.576476) (xy 197.523572 -308.568433)
			(xy 197.474673 -308.552545) (xy 197.428861 -308.529202) (xy 197.387265 -308.498981) (xy 197.350909 -308.462625)
			(xy 197.320688 -308.421029) (xy 197.297345 -308.375217) (xy 197.281457 -308.326318) (xy 197.273414 -308.275536)
			(xy 196.954482 -308.275536) (xy 196.946766 -308.323012) (xy 196.931182 -308.369693) (xy 196.908311 -308.41327)
			(xy 196.878746 -308.452614) (xy 196.843253 -308.486706) (xy 196.80275 -308.514662) (xy 196.758288 -308.53576)
			(xy 196.711017 -308.549452) (xy 196.662162 -308.555384) (xy 196.612987 -308.553403) (xy 196.564768 -308.543559)
			(xy 196.518752 -308.526107) (xy 196.476131 -308.5015) (xy 196.43801 -308.470375) (xy 196.405375 -308.433538)
			(xy 196.379072 -308.391942) (xy 196.359781 -308.346666) (xy 196.348004 -308.298882) (xy 196.344044 -308.249828)
			(xy 196.005196 -308.249828) (xy 196.004701 -308.274435) (xy 195.996806 -308.323012) (xy 195.981222 -308.369693)
			(xy 195.958351 -308.41327) (xy 195.928786 -308.452614) (xy 195.893293 -308.486706) (xy 195.85279 -308.514662)
			(xy 195.808328 -308.53576) (xy 195.761057 -308.549452) (xy 195.712202 -308.555384) (xy 195.663027 -308.553403)
			(xy 195.614808 -308.543559) (xy 195.568792 -308.526107) (xy 195.526171 -308.5015) (xy 195.48805 -308.470375)
			(xy 195.455415 -308.433538) (xy 195.429112 -308.391942) (xy 195.409821 -308.346666) (xy 195.398044 -308.298882)
			(xy 195.394084 -308.249828) (xy 195.055236 -308.249828) (xy 195.054741 -308.274435) (xy 195.046846 -308.323012)
			(xy 195.031262 -308.369693) (xy 195.008391 -308.41327) (xy 194.978826 -308.452614) (xy 194.943333 -308.486706)
			(xy 194.90283 -308.514662) (xy 194.858368 -308.53576) (xy 194.811097 -308.549452) (xy 194.762242 -308.555384)
			(xy 194.713067 -308.553403) (xy 194.664848 -308.543559) (xy 194.618832 -308.526107) (xy 194.576211 -308.5015)
			(xy 194.53809 -308.470375) (xy 194.505455 -308.433538) (xy 194.479152 -308.391942) (xy 194.459861 -308.346666)
			(xy 194.448084 -308.298882) (xy 194.444124 -308.249828) (xy 194.105276 -308.249828) (xy 194.104781 -308.274435)
			(xy 194.096886 -308.323012) (xy 194.081302 -308.369693) (xy 194.058431 -308.41327) (xy 194.028866 -308.452614)
			(xy 193.993373 -308.486706) (xy 193.95287 -308.514662) (xy 193.908408 -308.53576) (xy 193.861137 -308.549452)
			(xy 193.812282 -308.555384) (xy 193.763107 -308.553403) (xy 193.714888 -308.543559) (xy 193.668872 -308.526107)
			(xy 193.626251 -308.5015) (xy 193.58813 -308.470375) (xy 193.555495 -308.433538) (xy 193.529192 -308.391942)
			(xy 193.509901 -308.346666) (xy 193.498124 -308.298882) (xy 193.494164 -308.249828) (xy 193.155316 -308.249828)
			(xy 193.154821 -308.274435) (xy 193.146926 -308.323012) (xy 193.131342 -308.369693) (xy 193.108471 -308.41327)
			(xy 193.078906 -308.452614) (xy 193.043413 -308.486706) (xy 193.00291 -308.514662) (xy 192.958448 -308.53576)
			(xy 192.911177 -308.549452) (xy 192.862322 -308.555384) (xy 192.813147 -308.553403) (xy 192.764928 -308.543559)
			(xy 192.718912 -308.526107) (xy 192.676291 -308.5015) (xy 192.63817 -308.470375) (xy 192.605535 -308.433538)
			(xy 192.579232 -308.391942) (xy 192.559941 -308.346666) (xy 192.548164 -308.298882) (xy 192.544204 -308.249828)
			(xy 192.2272 -308.249828) (xy 192.226696 -308.275536) (xy 192.218653 -308.326318) (xy 192.202765 -308.375217)
			(xy 192.179422 -308.421029) (xy 192.149201 -308.462625) (xy 192.112845 -308.498981) (xy 192.071249 -308.529202)
			(xy 192.025437 -308.552545) (xy 191.976538 -308.568433) (xy 191.925756 -308.576476) (xy 191.87434 -308.576476)
			(xy 191.823558 -308.568433) (xy 191.774659 -308.552545) (xy 191.728847 -308.529202) (xy 191.687251 -308.498981)
			(xy 191.650895 -308.462625) (xy 191.620674 -308.421029) (xy 191.597331 -308.375217) (xy 191.581443 -308.326318)
			(xy 191.5734 -308.275536) (xy 191.276736 -308.275536) (xy 191.268693 -308.326318) (xy 191.252805 -308.375217)
			(xy 191.229462 -308.421029) (xy 191.199241 -308.462625) (xy 191.162885 -308.498981) (xy 191.121289 -308.529202)
			(xy 191.075477 -308.552545) (xy 191.026578 -308.568433) (xy 190.975796 -308.576476) (xy 190.92438 -308.576476)
			(xy 190.873598 -308.568433) (xy 190.824699 -308.552545) (xy 190.778887 -308.529202) (xy 190.737291 -308.498981)
			(xy 190.700935 -308.462625) (xy 190.670714 -308.421029) (xy 190.647371 -308.375217) (xy 190.631483 -308.326318)
			(xy 190.62344 -308.275536) (xy 190.304508 -308.275536) (xy 190.296792 -308.323012) (xy 190.281208 -308.369693)
			(xy 190.258337 -308.41327) (xy 190.228772 -308.452614) (xy 190.193279 -308.486706) (xy 190.152776 -308.514662)
			(xy 190.108314 -308.53576) (xy 190.061043 -308.549452) (xy 190.012188 -308.555384) (xy 189.963013 -308.553403)
			(xy 189.914794 -308.543559) (xy 189.868778 -308.526107) (xy 189.826157 -308.5015) (xy 189.788036 -308.470375)
			(xy 189.755401 -308.433538) (xy 189.729098 -308.391942) (xy 189.709807 -308.346666) (xy 189.69803 -308.298882)
			(xy 189.69407 -308.249828) (xy 166.11727 -308.249828) (xy 166.11727 -308.724808) (xy 166.419288 -308.724808)
			(xy 166.423248 -308.675754) (xy 166.435025 -308.62797) (xy 166.454316 -308.582694) (xy 166.480619 -308.541098)
			(xy 166.513254 -308.504261) (xy 166.551375 -308.473136) (xy 166.593996 -308.448529) (xy 166.640012 -308.431077)
			(xy 166.688231 -308.421233) (xy 166.737406 -308.419252) (xy 166.786261 -308.425184) (xy 166.833532 -308.438876)
			(xy 166.877994 -308.459974) (xy 166.918497 -308.48793) (xy 166.95399 -308.522022) (xy 166.983555 -308.561366)
			(xy 167.006426 -308.604943) (xy 167.02201 -308.651624) (xy 167.029905 -308.700201) (xy 167.0304 -308.724808)
			(xy 167.369248 -308.724808) (xy 167.373208 -308.675754) (xy 167.384985 -308.62797) (xy 167.404276 -308.582694)
			(xy 167.430579 -308.541098) (xy 167.463214 -308.504261) (xy 167.501335 -308.473136) (xy 167.543956 -308.448529)
			(xy 167.589972 -308.431077) (xy 167.638191 -308.421233) (xy 167.687366 -308.419252) (xy 167.736221 -308.425184)
			(xy 167.783492 -308.438876) (xy 167.827954 -308.459974) (xy 167.868457 -308.48793) (xy 167.90395 -308.522022)
			(xy 167.933515 -308.561366) (xy 167.956386 -308.604943) (xy 167.97197 -308.651624) (xy 167.979865 -308.700201)
			(xy 167.98036 -308.724808) (xy 168.319208 -308.724808) (xy 168.323168 -308.675754) (xy 168.334945 -308.62797)
			(xy 168.354236 -308.582694) (xy 168.380539 -308.541098) (xy 168.413174 -308.504261) (xy 168.451295 -308.473136)
			(xy 168.493916 -308.448529) (xy 168.539932 -308.431077) (xy 168.588151 -308.421233) (xy 168.637326 -308.419252)
			(xy 168.686181 -308.425184) (xy 168.733452 -308.438876) (xy 168.777914 -308.459974) (xy 168.818417 -308.48793)
			(xy 168.85391 -308.522022) (xy 168.883475 -308.561366) (xy 168.906346 -308.604943) (xy 168.92193 -308.651624)
			(xy 168.929825 -308.700201) (xy 168.93032 -308.724808) (xy 169.269168 -308.724808) (xy 169.273128 -308.675754)
			(xy 169.284905 -308.62797) (xy 169.304196 -308.582694) (xy 169.330499 -308.541098) (xy 169.363134 -308.504261)
			(xy 169.401255 -308.473136) (xy 169.443876 -308.448529) (xy 169.489892 -308.431077) (xy 169.538111 -308.421233)
			(xy 169.587286 -308.419252) (xy 169.636141 -308.425184) (xy 169.683412 -308.438876) (xy 169.727874 -308.459974)
			(xy 169.768377 -308.48793) (xy 169.80387 -308.522022) (xy 169.833435 -308.561366) (xy 169.856306 -308.604943)
			(xy 169.87189 -308.651624) (xy 169.879785 -308.700201) (xy 169.88028 -308.724808) (xy 170.219128 -308.724808)
			(xy 170.223088 -308.675754) (xy 170.234865 -308.62797) (xy 170.254156 -308.582694) (xy 170.280459 -308.541098)
			(xy 170.313094 -308.504261) (xy 170.351215 -308.473136) (xy 170.393836 -308.448529) (xy 170.439852 -308.431077)
			(xy 170.488071 -308.421233) (xy 170.537246 -308.419252) (xy 170.586101 -308.425184) (xy 170.633372 -308.438876)
			(xy 170.677834 -308.459974) (xy 170.718337 -308.48793) (xy 170.75383 -308.522022) (xy 170.783395 -308.561366)
			(xy 170.806266 -308.604943) (xy 170.82185 -308.651624) (xy 170.829745 -308.700201) (xy 170.83024 -308.724808)
			(xy 171.169088 -308.724808) (xy 171.173048 -308.675754) (xy 171.184825 -308.62797) (xy 171.204116 -308.582694)
			(xy 171.230419 -308.541098) (xy 171.263054 -308.504261) (xy 171.301175 -308.473136) (xy 171.343796 -308.448529)
			(xy 171.389812 -308.431077) (xy 171.438031 -308.421233) (xy 171.487206 -308.419252) (xy 171.536061 -308.425184)
			(xy 171.583332 -308.438876) (xy 171.627794 -308.459974) (xy 171.668297 -308.48793) (xy 171.70379 -308.522022)
			(xy 171.733355 -308.561366) (xy 171.756226 -308.604943) (xy 171.77181 -308.651624) (xy 171.779705 -308.700201)
			(xy 171.7802 -308.724808) (xy 172.119302 -308.724808) (xy 172.123262 -308.675754) (xy 172.135039 -308.62797)
			(xy 172.15433 -308.582694) (xy 172.180633 -308.541098) (xy 172.213268 -308.504261) (xy 172.251389 -308.473136)
			(xy 172.29401 -308.448529) (xy 172.340026 -308.431077) (xy 172.388245 -308.421233) (xy 172.43742 -308.419252)
			(xy 172.486275 -308.425184) (xy 172.533546 -308.438876) (xy 172.578008 -308.459974) (xy 172.618511 -308.48793)
			(xy 172.654004 -308.522022) (xy 172.683569 -308.561366) (xy 172.70644 -308.604943) (xy 172.722024 -308.651624)
			(xy 172.729919 -308.700201) (xy 172.730414 -308.724808) (xy 174.019222 -308.724808) (xy 174.023182 -308.675754)
			(xy 174.034959 -308.62797) (xy 174.05425 -308.582694) (xy 174.080553 -308.541098) (xy 174.113188 -308.504261)
			(xy 174.151309 -308.473136) (xy 174.19393 -308.448529) (xy 174.239946 -308.431077) (xy 174.288165 -308.421233)
			(xy 174.33734 -308.419252) (xy 174.386195 -308.425184) (xy 174.433466 -308.438876) (xy 174.477928 -308.459974)
			(xy 174.518431 -308.48793) (xy 174.553924 -308.522022) (xy 174.583489 -308.561366) (xy 174.60636 -308.604943)
			(xy 174.621944 -308.651624) (xy 174.629839 -308.700201) (xy 174.630334 -308.724808) (xy 174.629839 -308.749415)
			(xy 174.621944 -308.797992) (xy 174.60636 -308.844673) (xy 174.583489 -308.88825) (xy 174.553924 -308.927594)
			(xy 174.518431 -308.961686) (xy 174.477928 -308.989642) (xy 174.433466 -309.01074) (xy 174.386195 -309.024432)
			(xy 174.33734 -309.030364) (xy 174.288165 -309.028383) (xy 174.239946 -309.018539) (xy 174.19393 -309.001087)
			(xy 174.151309 -308.97648) (xy 174.113188 -308.945355) (xy 174.080553 -308.908518) (xy 174.05425 -308.866922)
			(xy 174.034959 -308.821646) (xy 174.023182 -308.773862) (xy 174.019222 -308.724808) (xy 172.730414 -308.724808)
			(xy 172.729919 -308.749415) (xy 172.722024 -308.797992) (xy 172.70644 -308.844673) (xy 172.683569 -308.88825)
			(xy 172.654004 -308.927594) (xy 172.618511 -308.961686) (xy 172.578008 -308.989642) (xy 172.533546 -309.01074)
			(xy 172.486275 -309.024432) (xy 172.43742 -309.030364) (xy 172.388245 -309.028383) (xy 172.340026 -309.018539)
			(xy 172.29401 -309.001087) (xy 172.251389 -308.97648) (xy 172.213268 -308.945355) (xy 172.180633 -308.908518)
			(xy 172.15433 -308.866922) (xy 172.135039 -308.821646) (xy 172.123262 -308.773862) (xy 172.119302 -308.724808)
			(xy 171.7802 -308.724808) (xy 171.779705 -308.749415) (xy 171.77181 -308.797992) (xy 171.756226 -308.844673)
			(xy 171.733355 -308.88825) (xy 171.70379 -308.927594) (xy 171.668297 -308.961686) (xy 171.627794 -308.989642)
			(xy 171.583332 -309.01074) (xy 171.536061 -309.024432) (xy 171.487206 -309.030364) (xy 171.438031 -309.028383)
			(xy 171.389812 -309.018539) (xy 171.343796 -309.001087) (xy 171.301175 -308.97648) (xy 171.263054 -308.945355)
			(xy 171.230419 -308.908518) (xy 171.204116 -308.866922) (xy 171.184825 -308.821646) (xy 171.173048 -308.773862)
			(xy 171.169088 -308.724808) (xy 170.83024 -308.724808) (xy 170.829745 -308.749415) (xy 170.82185 -308.797992)
			(xy 170.806266 -308.844673) (xy 170.783395 -308.88825) (xy 170.75383 -308.927594) (xy 170.718337 -308.961686)
			(xy 170.677834 -308.989642) (xy 170.633372 -309.01074) (xy 170.586101 -309.024432) (xy 170.537246 -309.030364)
			(xy 170.488071 -309.028383) (xy 170.439852 -309.018539) (xy 170.393836 -309.001087) (xy 170.351215 -308.97648)
			(xy 170.313094 -308.945355) (xy 170.280459 -308.908518) (xy 170.254156 -308.866922) (xy 170.234865 -308.821646)
			(xy 170.223088 -308.773862) (xy 170.219128 -308.724808) (xy 169.88028 -308.724808) (xy 169.879785 -308.749415)
			(xy 169.87189 -308.797992) (xy 169.856306 -308.844673) (xy 169.833435 -308.88825) (xy 169.80387 -308.927594)
			(xy 169.768377 -308.961686) (xy 169.727874 -308.989642) (xy 169.683412 -309.01074) (xy 169.636141 -309.024432)
			(xy 169.587286 -309.030364) (xy 169.538111 -309.028383) (xy 169.489892 -309.018539) (xy 169.443876 -309.001087)
			(xy 169.401255 -308.97648) (xy 169.363134 -308.945355) (xy 169.330499 -308.908518) (xy 169.304196 -308.866922)
			(xy 169.284905 -308.821646) (xy 169.273128 -308.773862) (xy 169.269168 -308.724808) (xy 168.93032 -308.724808)
			(xy 168.929825 -308.749415) (xy 168.92193 -308.797992) (xy 168.906346 -308.844673) (xy 168.883475 -308.88825)
			(xy 168.85391 -308.927594) (xy 168.818417 -308.961686) (xy 168.777914 -308.989642) (xy 168.733452 -309.01074)
			(xy 168.686181 -309.024432) (xy 168.637326 -309.030364) (xy 168.588151 -309.028383) (xy 168.539932 -309.018539)
			(xy 168.493916 -309.001087) (xy 168.451295 -308.97648) (xy 168.413174 -308.945355) (xy 168.380539 -308.908518)
			(xy 168.354236 -308.866922) (xy 168.334945 -308.821646) (xy 168.323168 -308.773862) (xy 168.319208 -308.724808)
			(xy 167.98036 -308.724808) (xy 167.979865 -308.749415) (xy 167.97197 -308.797992) (xy 167.956386 -308.844673)
			(xy 167.933515 -308.88825) (xy 167.90395 -308.927594) (xy 167.868457 -308.961686) (xy 167.827954 -308.989642)
			(xy 167.783492 -309.01074) (xy 167.736221 -309.024432) (xy 167.687366 -309.030364) (xy 167.638191 -309.028383)
			(xy 167.589972 -309.018539) (xy 167.543956 -309.001087) (xy 167.501335 -308.97648) (xy 167.463214 -308.945355)
			(xy 167.430579 -308.908518) (xy 167.404276 -308.866922) (xy 167.384985 -308.821646) (xy 167.373208 -308.773862)
			(xy 167.369248 -308.724808) (xy 167.0304 -308.724808) (xy 167.029905 -308.749415) (xy 167.02201 -308.797992)
			(xy 167.006426 -308.844673) (xy 166.983555 -308.88825) (xy 166.95399 -308.927594) (xy 166.918497 -308.961686)
			(xy 166.877994 -308.989642) (xy 166.833532 -309.01074) (xy 166.786261 -309.024432) (xy 166.737406 -309.030364)
			(xy 166.688231 -309.028383) (xy 166.640012 -309.018539) (xy 166.593996 -309.001087) (xy 166.551375 -308.97648)
			(xy 166.513254 -308.945355) (xy 166.480619 -308.908518) (xy 166.454316 -308.866922) (xy 166.435025 -308.821646)
			(xy 166.423248 -308.773862) (xy 166.419288 -308.724808) (xy 166.11727 -308.724808) (xy 166.11727 -309.74411)
			(xy 166.117826 -309.754561) (xy 166.126207 -309.773715) (xy 166.133526 -309.781194) (xy 166.19601 -309.83936)
			(xy 166.215822 -309.846218) (xy 166.22649 -309.845202) (xy 166.249858 -309.84444) (xy 166.273852 -309.844883)
			(xy 166.32125 -309.852385) (xy 166.36689 -309.86721) (xy 166.409648 -309.888994) (xy 166.448472 -309.9172)
			(xy 166.482404 -309.951133) (xy 166.510609 -309.989957) (xy 166.532392 -310.032716) (xy 166.547216 -310.078356)
			(xy 166.554717 -310.125754) (xy 166.555166 -310.149748) (xy 166.55512 -310.158785) (xy 166.554105 -310.176831)
			(xy 166.553134 -310.185816) (xy 166.55161 -310.197754) (xy 166.559484 -310.220106) (xy 166.635938 -310.293004)
			(xy 166.658544 -310.299862) (xy 166.670482 -310.298084) (xy 166.68397 -310.295955) (xy 166.711184 -310.293668)
			(xy 166.724838 -310.293512) (xy 166.738492 -310.293673) (xy 166.765705 -310.295962) (xy 166.779194 -310.298084)
			(xy 166.791386 -310.300116) (xy 166.813992 -310.293004) (xy 166.890446 -310.220106) (xy 166.89832 -310.198008)
			(xy 166.896796 -310.185816) (xy 166.895814 -310.176832) (xy 166.894797 -310.158786) (xy 166.894764 -310.149748)
			(xy 166.895286 -310.124493) (xy 166.903599 -310.074671) (xy 166.92 -310.026897) (xy 166.944041 -309.982474)
			(xy 166.975065 -309.942614) (xy 167.012227 -309.908404) (xy 167.054513 -309.880778) (xy 167.100769 -309.860488)
			(xy 167.149734 -309.848088) (xy 167.200072 -309.843917) (xy 167.25041 -309.848088) (xy 167.299375 -309.860488)
			(xy 167.345631 -309.880778) (xy 167.387917 -309.908404) (xy 167.425079 -309.942614) (xy 167.456103 -309.982474)
			(xy 167.480144 -310.026897) (xy 167.496545 -310.074671) (xy 167.504858 -310.124493) (xy 167.50538 -310.149748)
			(xy 167.505258 -310.163862) (xy 167.502714 -310.191975) (xy 167.5003 -310.205882) (xy 167.49776 -310.218328)
			(xy 167.505126 -310.24195) (xy 167.582596 -310.31942) (xy 167.606218 -310.326532) (xy 167.618664 -310.324246)
			(xy 167.646672 -310.319623) (xy 167.703432 -310.319623) (xy 167.73144 -310.324246) (xy 167.743886 -310.326532)
			(xy 167.767508 -310.31942) (xy 167.844978 -310.24195) (xy 167.852344 -310.218328) (xy 167.849804 -310.205882)
			(xy 167.847405 -310.191973) (xy 167.84486 -310.163862) (xy 167.844724 -310.149748) (xy 167.845246 -310.124493)
			(xy 167.853559 -310.074671) (xy 167.86996 -310.026897) (xy 167.894001 -309.982474) (xy 167.925025 -309.942614)
			(xy 167.962187 -309.908404) (xy 168.004473 -309.880778) (xy 168.050729 -309.860488) (xy 168.099694 -309.848088)
			(xy 168.150032 -309.843917) (xy 168.20037 -309.848088) (xy 168.249335 -309.860488) (xy 168.295591 -309.880778)
			(xy 168.337877 -309.908404) (xy 168.375039 -309.942614) (xy 168.406063 -309.982474) (xy 168.430104 -310.026897)
			(xy 168.446505 -310.074671) (xy 168.454818 -310.124493) (xy 168.45534 -310.149748) (xy 168.455299 -310.158722)
			(xy 168.454282 -310.176641) (xy 168.453308 -310.185562) (xy 168.451784 -310.197754) (xy 168.459912 -310.219852)
			(xy 168.536112 -310.29275) (xy 168.558718 -310.299862) (xy 168.570656 -310.29783) (xy 168.591484 -310.295036)
			(xy 168.596818 -310.295036) (xy 168.601644 -310.294274) (xy 168.621059 -310.293228) (xy 168.659894 -310.295143)
			(xy 168.679114 -310.298084) (xy 168.691306 -310.299862) (xy 168.713912 -310.293004) (xy 168.790366 -310.220106)
			(xy 168.79824 -310.198008) (xy 168.796716 -310.185816) (xy 168.795734 -310.176832) (xy 168.794718 -310.158786)
			(xy 168.794684 -310.149748) (xy 168.795206 -310.124493) (xy 168.803519 -310.074671) (xy 168.81992 -310.026897)
			(xy 168.843961 -309.982474) (xy 168.874985 -309.942614) (xy 168.912147 -309.908404) (xy 168.954433 -309.880778)
			(xy 169.000689 -309.860488) (xy 169.049654 -309.848088) (xy 169.099992 -309.843917) (xy 169.15033 -309.848088)
			(xy 169.199295 -309.860488) (xy 169.245551 -309.880778) (xy 169.287837 -309.908404) (xy 169.324999 -309.942614)
			(xy 169.356023 -309.982474) (xy 169.380064 -310.026897) (xy 169.396465 -310.074671) (xy 169.404778 -310.124493)
			(xy 169.4053 -310.149748) (xy 169.405178 -310.163862) (xy 169.402633 -310.191975) (xy 169.40022 -310.205882)
			(xy 169.39768 -310.218328) (xy 169.405046 -310.24195) (xy 169.482516 -310.31942) (xy 169.506138 -310.326532)
			(xy 169.518584 -310.324246) (xy 169.546592 -310.319623) (xy 169.603352 -310.319623) (xy 169.63136 -310.324246)
			(xy 169.643806 -310.326532) (xy 169.667428 -310.31942) (xy 169.744898 -310.24195) (xy 169.752264 -310.218328)
			(xy 169.749724 -310.205882) (xy 169.747325 -310.191973) (xy 169.744779 -310.163862) (xy 169.744644 -310.149748)
			(xy 169.745166 -310.124493) (xy 169.753479 -310.074671) (xy 169.76988 -310.026897) (xy 169.793921 -309.982474)
			(xy 169.824945 -309.942614) (xy 169.862107 -309.908404) (xy 169.904393 -309.880778) (xy 169.950649 -309.860488)
			(xy 169.999614 -309.848088) (xy 170.049952 -309.843917) (xy 170.10029 -309.848088) (xy 170.149255 -309.860488)
			(xy 170.195511 -309.880778) (xy 170.237797 -309.908404) (xy 170.274959 -309.942614) (xy 170.305983 -309.982474)
			(xy 170.330024 -310.026897) (xy 170.346425 -310.074671) (xy 170.354738 -310.124493) (xy 170.35526 -310.149748)
			(xy 170.355219 -310.158722) (xy 170.354202 -310.176641) (xy 170.353228 -310.185562) (xy 170.351704 -310.197754)
			(xy 170.359832 -310.219852) (xy 170.436032 -310.29275) (xy 170.458638 -310.299862) (xy 170.470576 -310.29783)
			(xy 170.491404 -310.295036) (xy 170.496738 -310.295036) (xy 170.501564 -310.294274) (xy 170.520979 -310.293223)
			(xy 170.559816 -310.295129) (xy 170.579034 -310.298084) (xy 170.591226 -310.299862) (xy 170.613832 -310.293004)
			(xy 170.690286 -310.220106) (xy 170.69816 -310.198008) (xy 170.696636 -310.185816) (xy 170.695654 -310.176832)
			(xy 170.694637 -310.158786) (xy 170.694604 -310.149748) (xy 170.695126 -310.124493) (xy 170.703439 -310.074671)
			(xy 170.71984 -310.026897) (xy 170.743881 -309.982474) (xy 170.774905 -309.942614) (xy 170.812067 -309.908404)
			(xy 170.854353 -309.880778) (xy 170.900609 -309.860488) (xy 170.949574 -309.848088) (xy 170.999912 -309.843917)
			(xy 171.05025 -309.848088) (xy 171.099215 -309.860488) (xy 171.145471 -309.880778) (xy 171.187757 -309.908404)
			(xy 171.224919 -309.942614) (xy 171.255943 -309.982474) (xy 171.279984 -310.026897) (xy 171.296385 -310.074671)
			(xy 171.304698 -310.124493) (xy 171.30522 -310.149748) (xy 171.305098 -310.163862) (xy 171.302554 -310.191975)
			(xy 171.30014 -310.205882) (xy 171.2976 -310.218328) (xy 171.304966 -310.24195) (xy 171.382436 -310.31942)
			(xy 171.406058 -310.326532) (xy 171.418504 -310.324246) (xy 171.446512 -310.319623) (xy 171.503272 -310.319623)
			(xy 171.53128 -310.324246) (xy 171.543726 -310.326532) (xy 171.567348 -310.31942) (xy 171.644818 -310.24195)
			(xy 171.652184 -310.218328) (xy 171.649644 -310.205882) (xy 171.647245 -310.191973) (xy 171.644699 -310.163862)
			(xy 171.644564 -310.149748) (xy 171.645007 -310.125752) (xy 171.652507 -310.078349) (xy 171.667331 -310.032703)
			(xy 171.689113 -309.989938) (xy 171.717318 -309.951107) (xy 171.751249 -309.917167) (xy 171.790073 -309.888953)
			(xy 171.832832 -309.86716) (xy 171.878475 -309.852325) (xy 171.925876 -309.844813) (xy 171.949872 -309.84444)
			(xy 171.964055 -309.844625) (xy 171.992294 -309.847296) (xy 172.00626 -309.849774) (xy 172.018706 -309.85206)
			(xy 172.042328 -309.844694) (xy 172.119798 -309.767224) (xy 172.127164 -309.743602) (xy 172.124878 -309.731156)
			(xy 172.122394 -309.717191) (xy 172.119724 -309.688951) (xy 172.119544 -309.674768) (xy 172.120066 -309.649513)
			(xy 172.128379 -309.599691) (xy 172.14478 -309.551917) (xy 172.168821 -309.507494) (xy 172.199845 -309.467634)
			(xy 172.237007 -309.433424) (xy 172.279293 -309.405798) (xy 172.325549 -309.385508) (xy 172.374514 -309.373108)
			(xy 172.424852 -309.368937) (xy 172.47519 -309.373108) (xy 172.524155 -309.385508) (xy 172.570411 -309.405798)
			(xy 172.612697 -309.433424) (xy 172.649859 -309.467634) (xy 172.680883 -309.507494) (xy 172.704924 -309.551917)
			(xy 172.721325 -309.599691) (xy 172.729638 -309.649513) (xy 172.73016 -309.674768) (xy 172.729975 -309.688951)
			(xy 172.727305 -309.717191) (xy 172.724826 -309.731156) (xy 172.72254 -309.743602) (xy 172.729906 -309.767478)
			(xy 172.807122 -309.844694) (xy 172.831252 -309.85206) (xy 172.843444 -309.849774) (xy 172.857471 -309.847276)
			(xy 172.885839 -309.844606) (xy 172.900086 -309.84444) (xy 172.914269 -309.844626) (xy 172.942508 -309.847298)
			(xy 172.956474 -309.849774) (xy 172.96892 -309.85206) (xy 172.992542 -309.844694) (xy 173.070012 -309.767224)
			(xy 173.077378 -309.743602) (xy 173.075092 -309.731156) (xy 173.072608 -309.717191) (xy 173.06994 -309.688951)
			(xy 173.069758 -309.674768) (xy 173.070231 -309.650777) (xy 173.077741 -309.603388) (xy 173.092571 -309.557756)
			(xy 173.114355 -309.515005) (xy 173.142559 -309.476188) (xy 173.176486 -309.44226) (xy 173.215303 -309.414056)
			(xy 173.258054 -309.392271) (xy 173.303686 -309.377441) (xy 173.351075 -309.369931) (xy 173.375066 -309.36946)
			(xy 173.399009 -309.369924) (xy 173.446309 -309.377394) (xy 173.491863 -309.392156) (xy 173.534554 -309.413849)
			(xy 173.573335 -309.44194) (xy 173.607256 -309.475741) (xy 173.635484 -309.514422) (xy 173.657328 -309.557036)
			(xy 173.672252 -309.602537) (xy 173.679889 -309.64981) (xy 173.680374 -309.673752) (xy 173.680374 -309.678324)
			(xy 173.679612 -309.700676) (xy 173.678596 -309.7149) (xy 173.691296 -309.739792) (xy 173.718474 -309.75681)
			(xy 173.718728 -309.75681) (xy 173.77791 -309.79364) (xy 173.783284 -309.796762) (xy 173.795097 -309.800614)
			(xy 173.801278 -309.80126) (xy 173.805576 -309.801451) (xy 173.814132 -309.800561) (xy 173.818296 -309.799482)
			(xy 173.82617 -309.797196) (xy 173.837854 -309.792116) (xy 173.851728 -309.784151) (xy 173.879929 -309.769036)
			(xy 173.894242 -309.76189) (xy 173.931072 -309.744364) (xy 173.940978 -309.740046) (xy 173.971712 -309.727346)
			(xy 173.977554 -309.724806) (xy 173.983396 -309.720742) (xy 173.991778 -309.715408) (xy 174.01921 -309.674768)
			(xy 174.019972 -309.660544) (xy 174.02166 -309.635017) (xy 174.032481 -309.58502) (xy 174.051482 -309.537525)
			(xy 174.078132 -309.493861) (xy 174.111686 -309.455248) (xy 174.151205 -309.422767) (xy 174.173134 -309.409592)
			(xy 174.174404 -309.409084) (xy 174.17542 -309.408322) (xy 174.198844 -309.395878) (xy 174.248912 -309.378382)
			(xy 174.274988 -309.373524) (xy 174.29607 -309.37073) (xy 174.296324 -309.37073) (xy 174.29861 -309.370476)
			(xy 174.301658 -309.370222) (xy 174.325788 -309.369206) (xy 174.345092 -309.369968) (xy 174.353982 -309.37073)
			(xy 174.378065 -309.373492) (xy 174.424987 -309.385655) (xy 174.469399 -309.405075) (xy 174.510186 -309.431267)
			(xy 174.546325 -309.463571) (xy 174.576908 -309.501177) (xy 174.601168 -309.543142) (xy 174.618495 -309.588412)
			(xy 174.628456 -309.63585) (xy 174.63008 -309.660036) (xy 174.630842 -309.67426) (xy 174.645066 -309.695596)
			(xy 174.650146 -309.702962) (xy 174.654972 -309.709566) (xy 174.664878 -309.719726) (xy 174.67072 -309.724298)
			(xy 174.677578 -309.727092) (xy 174.72179 -309.745092) (xy 174.806751 -309.788623) (xy 174.88699 -309.840344)
			(xy 174.92472 -309.869586) (xy 174.933864 -309.875428) (xy 174.956426 -309.886958) (xy 174.997702 -309.916336)
			(xy 175.033563 -309.952125) (xy 175.063025 -309.993342) (xy 175.07458 -310.01589) (xy 175.080422 -310.025288)
			(xy 175.107108 -310.059718) (xy 175.154861 -310.132582) (xy 175.195846 -310.209455) (xy 175.229732 -310.289712)
			(xy 175.25624 -310.372698) (xy 175.275155 -310.457737) (xy 175.286323 -310.544135) (xy 175.288448 -310.587644)
			(xy 175.28921 -310.608218) (xy 175.31842 -310.636412) (xy 175.829722 -310.636412)
		)
		(stroke
			(width 0)
			(type solid)
		)
		(fill yes)
		(layer "In13.Cu")
		(net "P1V25_PEX1")
	)
	(gr_poly
		(pts
			(xy 346.557346 -330.138532) (xy 346.567222 -330.138068) (xy 346.585516 -330.130621) (xy 346.592906 -330.124054)
			(xy 346.59316 -330.1238) (xy 349.956628 -326.760332) (xy 349.963471 -326.752933) (xy 349.971192 -326.734334)
			(xy 349.971614 -326.724264) (xy 349.971614 -319.04051) (xy 349.971157 -319.030358) (xy 349.963287 -319.011639)
			(xy 349.956374 -319.004188) (xy 349.89643 -318.946022) (xy 349.877888 -318.938656) (xy 349.86722 -318.93891)
			(xy 349.85706 -318.939164) (xy 349.829814 -318.938675) (xy 349.775877 -318.930915) (xy 349.723593 -318.915558)
			(xy 349.674026 -318.892917) (xy 349.628186 -318.863453) (xy 349.587006 -318.827766) (xy 349.551323 -318.786582)
			(xy 349.521864 -318.740738) (xy 349.499228 -318.69117) (xy 349.483877 -318.638884) (xy 349.476122 -318.584946)
			(xy 349.476122 -318.530454) (xy 349.483877 -318.476516) (xy 349.499228 -318.42423) (xy 349.521864 -318.374662)
			(xy 349.551323 -318.328818) (xy 349.587006 -318.287634) (xy 349.628186 -318.251947) (xy 349.674026 -318.222483)
			(xy 349.723593 -318.199842) (xy 349.775877 -318.184485) (xy 349.829814 -318.176725) (xy 349.85706 -318.176148)
			(xy 349.871208 -318.176254) (xy 349.89943 -318.178292) (xy 349.913448 -318.180212) (xy 349.917004 -318.180974)
			(xy 349.920814 -318.180974) (xy 349.930832 -318.180551) (xy 349.949339 -318.172878) (xy 349.963501 -318.158705)
			(xy 349.971159 -318.140192) (xy 349.971614 -318.130174) (xy 349.971614 -318.120522) (xy 349.971198 -318.110497)
			(xy 349.963533 -318.09197) (xy 349.94936 -318.077787) (xy 349.930839 -318.070109) (xy 349.920814 -318.069722)
			(xy 349.917004 -318.069722) (xy 349.913448 -318.070484) (xy 349.899432 -318.072418) (xy 349.871209 -318.07445)
			(xy 349.85706 -318.074548) (xy 349.829808 -318.074059) (xy 349.775859 -318.066297) (xy 349.723563 -318.050937)
			(xy 349.673986 -318.028291) (xy 349.628136 -317.998821) (xy 349.586946 -317.963126) (xy 349.551255 -317.921932)
			(xy 349.521789 -317.876079) (xy 349.499149 -317.826499) (xy 349.483794 -317.774202) (xy 349.476038 -317.720252)
			(xy 349.476038 -317.665748) (xy 349.483794 -317.611798) (xy 349.499149 -317.559501) (xy 349.521789 -317.509921)
			(xy 349.551255 -317.464068) (xy 349.586946 -317.422874) (xy 349.628136 -317.387179) (xy 349.673986 -317.357709)
			(xy 349.723563 -317.335063) (xy 349.775859 -317.319703) (xy 349.829808 -317.311941) (xy 349.85706 -317.311532)
			(xy 349.86722 -317.311786) (xy 349.877888 -317.31204) (xy 349.89643 -317.304674) (xy 349.956374 -317.246508)
			(xy 349.963325 -317.239084) (xy 349.971189 -317.220347) (xy 349.971614 -317.210186) (xy 349.971614 -316.472824)
			(xy 349.97116 -316.462671) (xy 349.963293 -316.443948) (xy 349.956374 -316.436502) (xy 349.89643 -316.378336)
			(xy 349.877888 -316.37097) (xy 349.86722 -316.371224) (xy 349.85706 -316.371478) (xy 349.829813 -316.370989)
			(xy 349.775874 -316.363229) (xy 349.723588 -316.347871) (xy 349.67402 -316.32523) (xy 349.628178 -316.295765)
			(xy 349.586996 -316.260076) (xy 349.551311 -316.21889) (xy 349.521851 -316.173045) (xy 349.499215 -316.123475)
			(xy 349.483863 -316.071187) (xy 349.476108 -316.017247) (xy 349.476108 -315.962753) (xy 349.483863 -315.908813)
			(xy 349.499215 -315.856525) (xy 349.521851 -315.806955) (xy 349.551311 -315.76111) (xy 349.586996 -315.719924)
			(xy 349.628178 -315.684235) (xy 349.67402 -315.65477) (xy 349.723588 -315.632129) (xy 349.775874 -315.616771)
			(xy 349.829813 -315.609011) (xy 349.85706 -315.608462) (xy 349.86722 -315.608716) (xy 349.877888 -315.60897)
			(xy 349.89643 -315.601604) (xy 349.956374 -315.543438) (xy 349.963329 -315.536015) (xy 349.971205 -315.517279)
			(xy 349.971614 -315.507116) (xy 349.971614 -294.228266) (xy 349.971185 -294.218198) (xy 349.963464 -294.199601)
			(xy 349.956628 -294.192198) (xy 349.75292 -293.98849) (xy 349.745522 -293.981646) (xy 349.726922 -293.973927)
			(xy 349.716852 -293.973504) (xy 348.671642 -293.973504) (xy 348.658434 -293.971726) (xy 348.655132 -293.97071)
			(xy 348.64294 -293.965884) (xy 333.427324 -293.965884) (xy 333.41726 -293.965447) (xy 333.398677 -293.957711)
			(xy 333.391256 -293.950898) (xy 332.778354 -293.337996) (xy 332.771242 -293.33063) (xy 332.752446 -293.32301)
			(xy 332.058772 -293.32301) (xy 332.053692 -293.324026) (xy 331.966849 -293.3409) (xy 331.791865 -293.36708)
			(xy 331.6158 -293.384571) (xy 331.439086 -293.39333) (xy 331.35062 -293.393876) (xy 331.350112 -293.393876)
			(xy 331.265052 -293.393378) (xy 331.095124 -293.385284) (xy 330.925775 -293.369114) (xy 330.757386 -293.344903)
			(xy 330.59034 -293.312708) (xy 330.425015 -293.272602) (xy 330.261786 -293.224674) (xy 330.101022 -293.169033)
			(xy 329.943088 -293.105806) (xy 329.788341 -293.035136) (xy 329.637132 -292.957183) (xy 329.489804 -292.872123)
			(xy 329.346689 -292.78015) (xy 329.208114 -292.681471) (xy 329.07439 -292.57631) (xy 328.945821 -292.464905)
			(xy 328.8227 -292.347509) (xy 328.705303 -292.224387) (xy 328.593898 -292.095819) (xy 328.488736 -291.962096)
			(xy 328.390057 -291.82352) (xy 328.298083 -291.680406) (xy 328.213023 -291.533078) (xy 328.135069 -291.38187)
			(xy 328.064398 -291.227123) (xy 328.001171 -291.069189) (xy 327.94553 -290.908425) (xy 327.897601 -290.745196)
			(xy 327.857494 -290.579872) (xy 327.825299 -290.412826) (xy 327.801088 -290.244437) (xy 327.784917 -290.075087)
			(xy 327.776822 -289.90516) (xy 327.776822 -289.73504) (xy 327.784917 -289.565113) (xy 327.801088 -289.395763)
			(xy 327.825299 -289.227374) (xy 327.857494 -289.060328) (xy 327.897601 -288.895004) (xy 327.94553 -288.731775)
			(xy 328.001171 -288.571011) (xy 328.064398 -288.413077) (xy 328.135069 -288.25833) (xy 328.213023 -288.107122)
			(xy 328.298083 -287.959794) (xy 328.390057 -287.81668) (xy 328.488736 -287.678104) (xy 328.593898 -287.544381)
			(xy 328.705303 -287.415813) (xy 328.8227 -287.292691) (xy 328.945821 -287.175295) (xy 329.07439 -287.06389)
			(xy 329.208114 -286.958729) (xy 329.346689 -286.86005) (xy 329.489804 -286.768077) (xy 329.637132 -286.683017)
			(xy 329.788341 -286.605064) (xy 329.943088 -286.534394) (xy 330.101022 -286.471167) (xy 330.261786 -286.415526)
			(xy 330.425015 -286.367598) (xy 330.59034 -286.327492) (xy 330.757386 -286.295297) (xy 330.925775 -286.271086)
			(xy 331.095124 -286.254916) (xy 331.265052 -286.246822) (xy 331.350112 -286.246316) (xy 331.431138 -286.247332)
			(xy 331.441552 -286.247586) (xy 331.460348 -286.24022) (xy 331.519784 -286.182054) (xy 331.526741 -286.174632)
			(xy 331.534621 -286.155895) (xy 331.535024 -286.145732) (xy 331.535024 -265.829288) (xy 331.527404 -265.810492)
			(xy 331.520038 -265.80338) (xy 331.328776 -265.612372) (xy 331.316838 -265.605768) (xy 331.30998 -265.60399)
			(xy 331.276119 -265.595285) (xy 331.210598 -265.570884) (xy 331.148452 -265.53885) (xy 331.119226 -265.519662)
			(xy 331.112761 -265.515607) (xy 331.098153 -265.511218) (xy 331.090524 -265.511026) (xy 318.327278 -265.511026)
			(xy 318.319658 -265.511273) (xy 318.305065 -265.515659) (xy 318.298576 -265.519662) (xy 318.269445 -265.538807)
			(xy 318.20751 -265.570797) (xy 318.142211 -265.595202) (xy 318.074476 -265.611675) (xy 318.005263 -265.619983)
			(xy 317.970408 -265.6205) (xy 299.024802 -265.6205) (xy 298.991926 -265.620018) (xy 298.92659 -265.61262)
			(xy 298.862492 -265.59796) (xy 298.800436 -265.576223) (xy 298.7412 -265.547681) (xy 298.685528 -265.512694)
			(xy 298.634119 -265.471699) (xy 298.610528 -265.448796) (xy 298.152566 -264.990834) (xy 298.145167 -264.983989)
			(xy 298.126569 -264.976262) (xy 298.116498 -264.975848) (xy 283.575506 -264.975848) (xy 283.565436 -264.976271)
			(xy 283.546835 -264.98399) (xy 283.539438 -264.990834) (xy 281.631898 -266.898374) (xy 281.624532 -266.905486)
			(xy 281.616912 -266.924282) (xy 281.616912 -270.89989) (xy 317.098687 -270.89989) (xy 317.102693 -270.704835)
			(xy 317.114703 -270.510109) (xy 317.134698 -270.31604) (xy 317.162643 -270.122956) (xy 317.198492 -269.931181)
			(xy 317.242184 -269.741041) (xy 317.293645 -269.552854) (xy 317.352789 -269.366939) (xy 317.419516 -269.183608)
			(xy 317.493713 -269.003172) (xy 317.575255 -268.825934) (xy 317.664006 -268.652193) (xy 317.759814 -268.482242)
			(xy 317.862519 -268.316368) (xy 317.971947 -268.15485) (xy 318.087914 -267.997961) (xy 318.210225 -267.845966)
			(xy 318.338672 -267.69912) (xy 318.47304 -267.557671) (xy 318.613102 -267.421858) (xy 318.758621 -267.291909)
			(xy 318.909353 -267.168045) (xy 319.065043 -267.050473) (xy 319.225429 -266.939393) (xy 319.39024 -266.83499)
			(xy 319.559198 -266.737442) (xy 319.732019 -266.646913) (xy 319.908411 -266.563555) (xy 320.088076 -266.487509)
			(xy 320.270711 -266.418904) (xy 320.45601 -266.357854) (xy 320.643658 -266.304464) (xy 320.83334 -266.258822)
			(xy 321.024737 -266.221006) (xy 321.217524 -266.19108) (xy 321.411377 -266.169094) (xy 321.60597 -266.155085)
			(xy 321.800973 -266.149077) (xy 321.996059 -266.15108) (xy 322.190898 -266.161091) (xy 322.385162 -266.179092)
			(xy 322.578523 -266.205054) (xy 322.770656 -266.238932) (xy 322.961235 -266.280669) (xy 323.14994 -266.330196)
			(xy 323.336453 -266.387428) (xy 323.520459 -266.452269) (xy 323.701647 -266.52461) (xy 323.879713 -266.604328)
			(xy 324.054356 -266.69129) (xy 324.225282 -266.785349) (xy 324.392201 -266.886345) (xy 324.554834 -266.99411)
			(xy 324.712905 -267.10846) (xy 324.866148 -267.229203) (xy 325.014305 -267.356137) (xy 325.157126 -267.489045)
			(xy 325.29437 -267.627705) (xy 325.425806 -267.771883) (xy 325.551211 -267.921336) (xy 325.670375 -268.07581)
			(xy 325.783096 -268.235047) (xy 325.889185 -268.398778) (xy 325.988463 -268.566725) (xy 326.080761 -268.738608)
			(xy 326.165926 -268.914134) (xy 326.243812 -269.093009) (xy 326.314289 -269.274931) (xy 326.377237 -269.459593)
			(xy 326.432552 -269.646683) (xy 326.480138 -269.835887) (xy 326.519917 -270.026884) (xy 326.551821 -270.219354)
			(xy 326.575796 -270.412972) (xy 326.591802 -270.60741) (xy 326.599811 -270.802342) (xy 326.600312 -270.89989)
			(xy 326.599811 -270.997438) (xy 326.591802 -271.19237) (xy 326.575796 -271.386808) (xy 326.551821 -271.580426)
			(xy 326.519917 -271.772896) (xy 326.480138 -271.963893) (xy 326.432552 -272.153097) (xy 326.377237 -272.340187)
			(xy 326.314289 -272.524849) (xy 326.243812 -272.706771) (xy 326.165926 -272.885646) (xy 326.080761 -273.061172)
			(xy 325.988463 -273.233055) (xy 325.889185 -273.401002) (xy 325.783096 -273.564733) (xy 325.670375 -273.72397)
			(xy 325.551211 -273.878444) (xy 325.425806 -274.027897) (xy 325.29437 -274.172075) (xy 325.157126 -274.310735)
			(xy 325.014305 -274.443643) (xy 324.866148 -274.570577) (xy 324.712905 -274.69132) (xy 324.554834 -274.80567)
			(xy 324.392201 -274.913435) (xy 324.225282 -275.014431) (xy 324.054356 -275.10849) (xy 323.879713 -275.195452)
			(xy 323.701647 -275.27517) (xy 323.520459 -275.347511) (xy 323.336453 -275.412352) (xy 323.14994 -275.469584)
			(xy 322.961235 -275.519111) (xy 322.770656 -275.560848) (xy 322.578523 -275.594726) (xy 322.385162 -275.620688)
			(xy 322.190898 -275.638689) (xy 321.996059 -275.6487) (xy 321.800973 -275.650703) (xy 321.60597 -275.644695)
			(xy 321.411377 -275.630686) (xy 321.217524 -275.6087) (xy 321.024737 -275.578774) (xy 320.83334 -275.540958)
			(xy 320.643658 -275.495316) (xy 320.45601 -275.441926) (xy 320.270711 -275.380876) (xy 320.088076 -275.312271)
			(xy 319.908411 -275.236225) (xy 319.732019 -275.152867) (xy 319.559198 -275.062338) (xy 319.39024 -274.96479)
			(xy 319.225429 -274.860387) (xy 319.065043 -274.749307) (xy 318.909353 -274.631735) (xy 318.758621 -274.507871)
			(xy 318.613102 -274.377922) (xy 318.47304 -274.242109) (xy 318.338672 -274.10066) (xy 318.210225 -273.953814)
			(xy 318.087914 -273.801819) (xy 317.971947 -273.64493) (xy 317.862519 -273.483412) (xy 317.759814 -273.317538)
			(xy 317.664006 -273.147587) (xy 317.575255 -272.973846) (xy 317.493713 -272.796608) (xy 317.419516 -272.616172)
			(xy 317.352789 -272.432841) (xy 317.293645 -272.246926) (xy 317.242184 -272.058739) (xy 317.198492 -271.868599)
			(xy 317.162643 -271.676824) (xy 317.134698 -271.48374) (xy 317.114703 -271.289671) (xy 317.102693 -271.094945)
			(xy 317.098687 -270.89989) (xy 281.616912 -270.89989) (xy 281.616912 -271.614138) (xy 281.617563 -271.626689)
			(xy 281.629427 -271.648809) (xy 281.639518 -271.656302) (xy 281.709876 -271.703292) (xy 281.720716 -271.70971)
			(xy 281.745763 -271.712099) (xy 281.757628 -271.707864) (xy 281.785665 -271.696966) (xy 281.844649 -271.685201)
			(xy 281.874722 -271.684496) (xy 281.901307 -271.685065) (xy 281.953674 -271.694264) (xy 282.003655 -271.712399)
			(xy 282.049738 -271.738919) (xy 282.090529 -271.773024) (xy 282.124793 -271.81368) (xy 282.138628 -271.836388)
			(xy 282.143581 -271.844098) (xy 282.157772 -271.855673) (xy 282.166314 -271.858994) (xy 282.196286 -271.8689)
			(xy 282.205113 -271.871473) (xy 282.223474 -271.870815) (xy 282.2321 -271.86763) (xy 282.260201 -271.856724)
			(xy 282.319313 -271.844963) (xy 282.349448 -271.844262) (xy 282.374703 -271.844787) (xy 282.424524 -271.853108)
			(xy 282.472295 -271.869515) (xy 282.516716 -271.89356) (xy 282.556573 -271.924588) (xy 282.59078 -271.961752)
			(xy 282.618404 -272.00404) (xy 282.638692 -272.050297) (xy 282.65109 -272.099262) (xy 282.655259 -272.14957)
			(xy 283.943818 -272.14957) (xy 283.947778 -272.100516) (xy 283.959555 -272.052732) (xy 283.978846 -272.007456)
			(xy 284.005149 -271.96586) (xy 284.037784 -271.929023) (xy 284.075905 -271.897898) (xy 284.118526 -271.873291)
			(xy 284.164542 -271.855839) (xy 284.212761 -271.845995) (xy 284.261936 -271.844014) (xy 284.310791 -271.849946)
			(xy 284.358062 -271.863638) (xy 284.402524 -271.884736) (xy 284.443027 -271.912692) (xy 284.47852 -271.946784)
			(xy 284.508085 -271.986128) (xy 284.530956 -272.029705) (xy 284.54654 -272.076386) (xy 284.554435 -272.124963)
			(xy 284.55493 -272.14957) (xy 285.843738 -272.14957) (xy 285.847698 -272.100516) (xy 285.859475 -272.052732)
			(xy 285.878766 -272.007456) (xy 285.905069 -271.96586) (xy 285.937704 -271.929023) (xy 285.975825 -271.897898)
			(xy 286.018446 -271.873291) (xy 286.064462 -271.855839) (xy 286.112681 -271.845995) (xy 286.161856 -271.844014)
			(xy 286.210711 -271.849946) (xy 286.257982 -271.863638) (xy 286.302444 -271.884736) (xy 286.342947 -271.912692)
			(xy 286.37844 -271.946784) (xy 286.408005 -271.986128) (xy 286.430876 -272.029705) (xy 286.44646 -272.076386)
			(xy 286.454355 -272.124963) (xy 286.45485 -272.14957) (xy 287.743658 -272.14957) (xy 287.747618 -272.100516)
			(xy 287.759395 -272.052732) (xy 287.778686 -272.007456) (xy 287.804989 -271.96586) (xy 287.837624 -271.929023)
			(xy 287.875745 -271.897898) (xy 287.918366 -271.873291) (xy 287.964382 -271.855839) (xy 288.012601 -271.845995)
			(xy 288.061776 -271.844014) (xy 288.110631 -271.849946) (xy 288.157902 -271.863638) (xy 288.202364 -271.884736)
			(xy 288.242867 -271.912692) (xy 288.27836 -271.946784) (xy 288.307925 -271.986128) (xy 288.330796 -272.029705)
			(xy 288.34638 -272.076386) (xy 288.354275 -272.124963) (xy 288.35477 -272.14957) (xy 289.643832 -272.14957)
			(xy 289.647792 -272.100516) (xy 289.659569 -272.052732) (xy 289.67886 -272.007456) (xy 289.705163 -271.96586)
			(xy 289.737798 -271.929023) (xy 289.775919 -271.897898) (xy 289.81854 -271.873291) (xy 289.864556 -271.855839)
			(xy 289.912775 -271.845995) (xy 289.96195 -271.844014) (xy 290.010805 -271.849946) (xy 290.058076 -271.863638)
			(xy 290.102538 -271.884736) (xy 290.143041 -271.912692) (xy 290.178534 -271.946784) (xy 290.208099 -271.986128)
			(xy 290.23097 -272.029705) (xy 290.246554 -272.076386) (xy 290.254449 -272.124963) (xy 290.254939 -272.149316)
			(xy 291.543752 -272.149316) (xy 291.547712 -272.100262) (xy 291.559489 -272.052478) (xy 291.57878 -272.007202)
			(xy 291.605083 -271.965606) (xy 291.637718 -271.928769) (xy 291.675839 -271.897644) (xy 291.71846 -271.873037)
			(xy 291.764476 -271.855585) (xy 291.812695 -271.845741) (xy 291.86187 -271.84376) (xy 291.910725 -271.849692)
			(xy 291.957996 -271.863384) (xy 292.002458 -271.884482) (xy 292.042961 -271.912438) (xy 292.078454 -271.94653)
			(xy 292.108019 -271.985874) (xy 292.13089 -272.029451) (xy 292.146474 -272.076132) (xy 292.154369 -272.124709)
			(xy 292.154864 -272.149316) (xy 292.154859 -272.14957) (xy 293.443672 -272.14957) (xy 293.447632 -272.100516)
			(xy 293.459409 -272.052732) (xy 293.4787 -272.007456) (xy 293.505003 -271.96586) (xy 293.537638 -271.929023)
			(xy 293.575759 -271.897898) (xy 293.61838 -271.873291) (xy 293.664396 -271.855839) (xy 293.712615 -271.845995)
			(xy 293.76179 -271.844014) (xy 293.810645 -271.849946) (xy 293.857916 -271.863638) (xy 293.902378 -271.884736)
			(xy 293.942881 -271.912692) (xy 293.978374 -271.946784) (xy 294.007939 -271.986128) (xy 294.03081 -272.029705)
			(xy 294.046394 -272.076386) (xy 294.054289 -272.124963) (xy 294.054784 -272.14957) (xy 295.343846 -272.14957)
			(xy 295.347806 -272.100516) (xy 295.359583 -272.052732) (xy 295.378874 -272.007456) (xy 295.405177 -271.96586)
			(xy 295.437812 -271.929023) (xy 295.475933 -271.897898) (xy 295.518554 -271.873291) (xy 295.56457 -271.855839)
			(xy 295.612789 -271.845995) (xy 295.661964 -271.844014) (xy 295.710819 -271.849946) (xy 295.75809 -271.863638)
			(xy 295.802552 -271.884736) (xy 295.843055 -271.912692) (xy 295.878548 -271.946784) (xy 295.908113 -271.986128)
			(xy 295.930984 -272.029705) (xy 295.946568 -272.076386) (xy 295.954463 -272.124963) (xy 295.954958 -272.14957)
			(xy 297.243766 -272.14957) (xy 297.247726 -272.100516) (xy 297.259503 -272.052732) (xy 297.278794 -272.007456)
			(xy 297.305097 -271.96586) (xy 297.337732 -271.929023) (xy 297.375853 -271.897898) (xy 297.418474 -271.873291)
			(xy 297.46449 -271.855839) (xy 297.512709 -271.845995) (xy 297.561884 -271.844014) (xy 297.610739 -271.849946)
			(xy 297.65801 -271.863638) (xy 297.702472 -271.884736) (xy 297.742975 -271.912692) (xy 297.778468 -271.946784)
			(xy 297.808033 -271.986128) (xy 297.830904 -272.029705) (xy 297.846488 -272.076386) (xy 297.854383 -272.124963)
			(xy 297.854878 -272.14957) (xy 299.143686 -272.14957) (xy 299.147646 -272.100516) (xy 299.159423 -272.052732)
			(xy 299.178714 -272.007456) (xy 299.205017 -271.96586) (xy 299.237652 -271.929023) (xy 299.275773 -271.897898)
			(xy 299.318394 -271.873291) (xy 299.36441 -271.855839) (xy 299.412629 -271.845995) (xy 299.461804 -271.844014)
			(xy 299.510659 -271.849946) (xy 299.55793 -271.863638) (xy 299.602392 -271.884736) (xy 299.642895 -271.912692)
			(xy 299.678388 -271.946784) (xy 299.707953 -271.986128) (xy 299.730824 -272.029705) (xy 299.746408 -272.076386)
			(xy 299.754303 -272.124963) (xy 299.754798 -272.14957) (xy 301.04386 -272.14957) (xy 301.04782 -272.100516)
			(xy 301.059597 -272.052732) (xy 301.078888 -272.007456) (xy 301.105191 -271.96586) (xy 301.137826 -271.929023)
			(xy 301.175947 -271.897898) (xy 301.218568 -271.873291) (xy 301.264584 -271.855839) (xy 301.312803 -271.845995)
			(xy 301.361978 -271.844014) (xy 301.410833 -271.849946) (xy 301.458104 -271.863638) (xy 301.502566 -271.884736)
			(xy 301.543069 -271.912692) (xy 301.578562 -271.946784) (xy 301.608127 -271.986128) (xy 301.630998 -272.029705)
			(xy 301.646582 -272.076386) (xy 301.654477 -272.124963) (xy 301.654972 -272.14957) (xy 302.94378 -272.14957)
			(xy 302.94774 -272.100516) (xy 302.959517 -272.052732) (xy 302.978808 -272.007456) (xy 303.005111 -271.96586)
			(xy 303.037746 -271.929023) (xy 303.075867 -271.897898) (xy 303.118488 -271.873291) (xy 303.164504 -271.855839)
			(xy 303.212723 -271.845995) (xy 303.261898 -271.844014) (xy 303.310753 -271.849946) (xy 303.358024 -271.863638)
			(xy 303.402486 -271.884736) (xy 303.442989 -271.912692) (xy 303.478482 -271.946784) (xy 303.508047 -271.986128)
			(xy 303.530918 -272.029705) (xy 303.546502 -272.076386) (xy 303.554397 -272.124963) (xy 303.554892 -272.14957)
			(xy 304.8437 -272.14957) (xy 304.84766 -272.100516) (xy 304.859437 -272.052732) (xy 304.878728 -272.007456)
			(xy 304.905031 -271.96586) (xy 304.937666 -271.929023) (xy 304.975787 -271.897898) (xy 305.018408 -271.873291)
			(xy 305.064424 -271.855839) (xy 305.112643 -271.845995) (xy 305.161818 -271.844014) (xy 305.210673 -271.849946)
			(xy 305.257944 -271.863638) (xy 305.302406 -271.884736) (xy 305.342909 -271.912692) (xy 305.378402 -271.946784)
			(xy 305.407967 -271.986128) (xy 305.430838 -272.029705) (xy 305.446422 -272.076386) (xy 305.454317 -272.124963)
			(xy 305.454812 -272.14957) (xy 306.743874 -272.14957) (xy 306.747834 -272.100516) (xy 306.759611 -272.052732)
			(xy 306.778902 -272.007456) (xy 306.805205 -271.96586) (xy 306.83784 -271.929023) (xy 306.875961 -271.897898)
			(xy 306.918582 -271.873291) (xy 306.964598 -271.855839) (xy 307.012817 -271.845995) (xy 307.061992 -271.844014)
			(xy 307.110847 -271.849946) (xy 307.158118 -271.863638) (xy 307.20258 -271.884736) (xy 307.243083 -271.912692)
			(xy 307.278576 -271.946784) (xy 307.308141 -271.986128) (xy 307.331012 -272.029705) (xy 307.346596 -272.076386)
			(xy 307.354491 -272.124963) (xy 307.354986 -272.14957) (xy 308.644048 -272.14957) (xy 308.648008 -272.100516)
			(xy 308.659785 -272.052732) (xy 308.679076 -272.007456) (xy 308.705379 -271.96586) (xy 308.738014 -271.929023)
			(xy 308.776135 -271.897898) (xy 308.818756 -271.873291) (xy 308.864772 -271.855839) (xy 308.912991 -271.845995)
			(xy 308.962166 -271.844014) (xy 309.011021 -271.849946) (xy 309.058292 -271.863638) (xy 309.102754 -271.884736)
			(xy 309.143257 -271.912692) (xy 309.17875 -271.946784) (xy 309.208315 -271.986128) (xy 309.231186 -272.029705)
			(xy 309.24677 -272.076386) (xy 309.254665 -272.124963) (xy 309.25516 -272.14957) (xy 310.543968 -272.14957)
			(xy 310.547928 -272.100516) (xy 310.559705 -272.052732) (xy 310.578996 -272.007456) (xy 310.605299 -271.96586)
			(xy 310.637934 -271.929023) (xy 310.676055 -271.897898) (xy 310.718676 -271.873291) (xy 310.764692 -271.855839)
			(xy 310.812911 -271.845995) (xy 310.862086 -271.844014) (xy 310.910941 -271.849946) (xy 310.958212 -271.863638)
			(xy 311.002674 -271.884736) (xy 311.043177 -271.912692) (xy 311.07867 -271.946784) (xy 311.108235 -271.986128)
			(xy 311.131106 -272.029705) (xy 311.14669 -272.076386) (xy 311.154585 -272.124963) (xy 311.15508 -272.14957)
			(xy 312.443888 -272.14957) (xy 312.447848 -272.100516) (xy 312.459625 -272.052732) (xy 312.478916 -272.007456)
			(xy 312.505219 -271.96586) (xy 312.537854 -271.929023) (xy 312.575975 -271.897898) (xy 312.618596 -271.873291)
			(xy 312.664612 -271.855839) (xy 312.712831 -271.845995) (xy 312.762006 -271.844014) (xy 312.810861 -271.849946)
			(xy 312.858132 -271.863638) (xy 312.902594 -271.884736) (xy 312.943097 -271.912692) (xy 312.97859 -271.946784)
			(xy 313.008155 -271.986128) (xy 313.031026 -272.029705) (xy 313.04661 -272.076386) (xy 313.054505 -272.124963)
			(xy 313.055 -272.14957) (xy 313.054505 -272.174177) (xy 313.04661 -272.222754) (xy 313.031026 -272.269435)
			(xy 313.008155 -272.313012) (xy 312.97859 -272.352356) (xy 312.943097 -272.386448) (xy 312.902594 -272.414404)
			(xy 312.858132 -272.435502) (xy 312.810861 -272.449194) (xy 312.762006 -272.455126) (xy 312.712831 -272.453145)
			(xy 312.664612 -272.443301) (xy 312.618596 -272.425849) (xy 312.575975 -272.401242) (xy 312.537854 -272.370117)
			(xy 312.505219 -272.33328) (xy 312.478916 -272.291684) (xy 312.459625 -272.246408) (xy 312.447848 -272.198624)
			(xy 312.443888 -272.14957) (xy 311.15508 -272.14957) (xy 311.154585 -272.174177) (xy 311.14669 -272.222754)
			(xy 311.131106 -272.269435) (xy 311.108235 -272.313012) (xy 311.07867 -272.352356) (xy 311.043177 -272.386448)
			(xy 311.002674 -272.414404) (xy 310.958212 -272.435502) (xy 310.910941 -272.449194) (xy 310.862086 -272.455126)
			(xy 310.812911 -272.453145) (xy 310.764692 -272.443301) (xy 310.718676 -272.425849) (xy 310.676055 -272.401242)
			(xy 310.637934 -272.370117) (xy 310.605299 -272.33328) (xy 310.578996 -272.291684) (xy 310.559705 -272.246408)
			(xy 310.547928 -272.198624) (xy 310.543968 -272.14957) (xy 309.25516 -272.14957) (xy 309.254665 -272.174177)
			(xy 309.24677 -272.222754) (xy 309.231186 -272.269435) (xy 309.208315 -272.313012) (xy 309.17875 -272.352356)
			(xy 309.143257 -272.386448) (xy 309.102754 -272.414404) (xy 309.058292 -272.435502) (xy 309.011021 -272.449194)
			(xy 308.962166 -272.455126) (xy 308.912991 -272.453145) (xy 308.864772 -272.443301) (xy 308.818756 -272.425849)
			(xy 308.776135 -272.401242) (xy 308.738014 -272.370117) (xy 308.705379 -272.33328) (xy 308.679076 -272.291684)
			(xy 308.659785 -272.246408) (xy 308.648008 -272.198624) (xy 308.644048 -272.14957) (xy 307.354986 -272.14957)
			(xy 307.354491 -272.174177) (xy 307.346596 -272.222754) (xy 307.331012 -272.269435) (xy 307.308141 -272.313012)
			(xy 307.278576 -272.352356) (xy 307.243083 -272.386448) (xy 307.20258 -272.414404) (xy 307.158118 -272.435502)
			(xy 307.110847 -272.449194) (xy 307.061992 -272.455126) (xy 307.012817 -272.453145) (xy 306.964598 -272.443301)
			(xy 306.918582 -272.425849) (xy 306.875961 -272.401242) (xy 306.83784 -272.370117) (xy 306.805205 -272.33328)
			(xy 306.778902 -272.291684) (xy 306.759611 -272.246408) (xy 306.747834 -272.198624) (xy 306.743874 -272.14957)
			(xy 305.454812 -272.14957) (xy 305.454317 -272.174177) (xy 305.446422 -272.222754) (xy 305.430838 -272.269435)
			(xy 305.407967 -272.313012) (xy 305.378402 -272.352356) (xy 305.342909 -272.386448) (xy 305.302406 -272.414404)
			(xy 305.257944 -272.435502) (xy 305.210673 -272.449194) (xy 305.161818 -272.455126) (xy 305.112643 -272.453145)
			(xy 305.064424 -272.443301) (xy 305.018408 -272.425849) (xy 304.975787 -272.401242) (xy 304.937666 -272.370117)
			(xy 304.905031 -272.33328) (xy 304.878728 -272.291684) (xy 304.859437 -272.246408) (xy 304.84766 -272.198624)
			(xy 304.8437 -272.14957) (xy 303.554892 -272.14957) (xy 303.554397 -272.174177) (xy 303.546502 -272.222754)
			(xy 303.530918 -272.269435) (xy 303.508047 -272.313012) (xy 303.478482 -272.352356) (xy 303.442989 -272.386448)
			(xy 303.402486 -272.414404) (xy 303.358024 -272.435502) (xy 303.310753 -272.449194) (xy 303.261898 -272.455126)
			(xy 303.212723 -272.453145) (xy 303.164504 -272.443301) (xy 303.118488 -272.425849) (xy 303.075867 -272.401242)
			(xy 303.037746 -272.370117) (xy 303.005111 -272.33328) (xy 302.978808 -272.291684) (xy 302.959517 -272.246408)
			(xy 302.94774 -272.198624) (xy 302.94378 -272.14957) (xy 301.654972 -272.14957) (xy 301.654477 -272.174177)
			(xy 301.646582 -272.222754) (xy 301.630998 -272.269435) (xy 301.608127 -272.313012) (xy 301.578562 -272.352356)
			(xy 301.543069 -272.386448) (xy 301.502566 -272.414404) (xy 301.458104 -272.435502) (xy 301.410833 -272.449194)
			(xy 301.361978 -272.455126) (xy 301.312803 -272.453145) (xy 301.264584 -272.443301) (xy 301.218568 -272.425849)
			(xy 301.175947 -272.401242) (xy 301.137826 -272.370117) (xy 301.105191 -272.33328) (xy 301.078888 -272.291684)
			(xy 301.059597 -272.246408) (xy 301.04782 -272.198624) (xy 301.04386 -272.14957) (xy 299.754798 -272.14957)
			(xy 299.754303 -272.174177) (xy 299.746408 -272.222754) (xy 299.730824 -272.269435) (xy 299.707953 -272.313012)
			(xy 299.678388 -272.352356) (xy 299.642895 -272.386448) (xy 299.602392 -272.414404) (xy 299.55793 -272.435502)
			(xy 299.510659 -272.449194) (xy 299.461804 -272.455126) (xy 299.412629 -272.453145) (xy 299.36441 -272.443301)
			(xy 299.318394 -272.425849) (xy 299.275773 -272.401242) (xy 299.237652 -272.370117) (xy 299.205017 -272.33328)
			(xy 299.178714 -272.291684) (xy 299.159423 -272.246408) (xy 299.147646 -272.198624) (xy 299.143686 -272.14957)
			(xy 297.854878 -272.14957) (xy 297.854383 -272.174177) (xy 297.846488 -272.222754) (xy 297.830904 -272.269435)
			(xy 297.808033 -272.313012) (xy 297.778468 -272.352356) (xy 297.742975 -272.386448) (xy 297.702472 -272.414404)
			(xy 297.65801 -272.435502) (xy 297.610739 -272.449194) (xy 297.561884 -272.455126) (xy 297.512709 -272.453145)
			(xy 297.46449 -272.443301) (xy 297.418474 -272.425849) (xy 297.375853 -272.401242) (xy 297.337732 -272.370117)
			(xy 297.305097 -272.33328) (xy 297.278794 -272.291684) (xy 297.259503 -272.246408) (xy 297.247726 -272.198624)
			(xy 297.243766 -272.14957) (xy 295.954958 -272.14957) (xy 295.954463 -272.174177) (xy 295.946568 -272.222754)
			(xy 295.930984 -272.269435) (xy 295.908113 -272.313012) (xy 295.878548 -272.352356) (xy 295.843055 -272.386448)
			(xy 295.802552 -272.414404) (xy 295.75809 -272.435502) (xy 295.710819 -272.449194) (xy 295.661964 -272.455126)
			(xy 295.612789 -272.453145) (xy 295.56457 -272.443301) (xy 295.518554 -272.425849) (xy 295.475933 -272.401242)
			(xy 295.437812 -272.370117) (xy 295.405177 -272.33328) (xy 295.378874 -272.291684) (xy 295.359583 -272.246408)
			(xy 295.347806 -272.198624) (xy 295.343846 -272.14957) (xy 294.054784 -272.14957) (xy 294.054289 -272.174177)
			(xy 294.046394 -272.222754) (xy 294.03081 -272.269435) (xy 294.007939 -272.313012) (xy 293.978374 -272.352356)
			(xy 293.942881 -272.386448) (xy 293.902378 -272.414404) (xy 293.857916 -272.435502) (xy 293.810645 -272.449194)
			(xy 293.76179 -272.455126) (xy 293.712615 -272.453145) (xy 293.664396 -272.443301) (xy 293.61838 -272.425849)
			(xy 293.575759 -272.401242) (xy 293.537638 -272.370117) (xy 293.505003 -272.33328) (xy 293.4787 -272.291684)
			(xy 293.459409 -272.246408) (xy 293.447632 -272.198624) (xy 293.443672 -272.14957) (xy 292.154859 -272.14957)
			(xy 292.154369 -272.173923) (xy 292.146474 -272.2225) (xy 292.13089 -272.269181) (xy 292.108019 -272.312758)
			(xy 292.078454 -272.352102) (xy 292.042961 -272.386194) (xy 292.002458 -272.41415) (xy 291.957996 -272.435248)
			(xy 291.910725 -272.44894) (xy 291.86187 -272.454872) (xy 291.812695 -272.452891) (xy 291.764476 -272.443047)
			(xy 291.71846 -272.425595) (xy 291.675839 -272.400988) (xy 291.637718 -272.369863) (xy 291.605083 -272.333026)
			(xy 291.57878 -272.29143) (xy 291.559489 -272.246154) (xy 291.547712 -272.19837) (xy 291.543752 -272.149316)
			(xy 290.254939 -272.149316) (xy 290.254944 -272.14957) (xy 290.254449 -272.174177) (xy 290.246554 -272.222754)
			(xy 290.23097 -272.269435) (xy 290.208099 -272.313012) (xy 290.178534 -272.352356) (xy 290.143041 -272.386448)
			(xy 290.102538 -272.414404) (xy 290.058076 -272.435502) (xy 290.010805 -272.449194) (xy 289.96195 -272.455126)
			(xy 289.912775 -272.453145) (xy 289.864556 -272.443301) (xy 289.81854 -272.425849) (xy 289.775919 -272.401242)
			(xy 289.737798 -272.370117) (xy 289.705163 -272.33328) (xy 289.67886 -272.291684) (xy 289.659569 -272.246408)
			(xy 289.647792 -272.198624) (xy 289.643832 -272.14957) (xy 288.35477 -272.14957) (xy 288.354275 -272.174177)
			(xy 288.34638 -272.222754) (xy 288.330796 -272.269435) (xy 288.307925 -272.313012) (xy 288.27836 -272.352356)
			(xy 288.242867 -272.386448) (xy 288.202364 -272.414404) (xy 288.157902 -272.435502) (xy 288.110631 -272.449194)
			(xy 288.061776 -272.455126) (xy 288.012601 -272.453145) (xy 287.964382 -272.443301) (xy 287.918366 -272.425849)
			(xy 287.875745 -272.401242) (xy 287.837624 -272.370117) (xy 287.804989 -272.33328) (xy 287.778686 -272.291684)
			(xy 287.759395 -272.246408) (xy 287.747618 -272.198624) (xy 287.743658 -272.14957) (xy 286.45485 -272.14957)
			(xy 286.454355 -272.174177) (xy 286.44646 -272.222754) (xy 286.430876 -272.269435) (xy 286.408005 -272.313012)
			(xy 286.37844 -272.352356) (xy 286.342947 -272.386448) (xy 286.302444 -272.414404) (xy 286.257982 -272.435502)
			(xy 286.210711 -272.449194) (xy 286.161856 -272.455126) (xy 286.112681 -272.453145) (xy 286.064462 -272.443301)
			(xy 286.018446 -272.425849) (xy 285.975825 -272.401242) (xy 285.937704 -272.370117) (xy 285.905069 -272.33328)
			(xy 285.878766 -272.291684) (xy 285.859475 -272.246408) (xy 285.847698 -272.198624) (xy 285.843738 -272.14957)
			(xy 284.55493 -272.14957) (xy 284.554435 -272.174177) (xy 284.54654 -272.222754) (xy 284.530956 -272.269435)
			(xy 284.508085 -272.313012) (xy 284.47852 -272.352356) (xy 284.443027 -272.386448) (xy 284.402524 -272.414404)
			(xy 284.358062 -272.435502) (xy 284.310791 -272.449194) (xy 284.261936 -272.455126) (xy 284.212761 -272.453145)
			(xy 284.164542 -272.443301) (xy 284.118526 -272.425849) (xy 284.075905 -272.401242) (xy 284.037784 -272.370117)
			(xy 284.005149 -272.33328) (xy 283.978846 -272.291684) (xy 283.959555 -272.246408) (xy 283.947778 -272.198624)
			(xy 283.943818 -272.14957) (xy 282.655259 -272.14957) (xy 282.655261 -272.1496) (xy 282.65109 -272.199938)
			(xy 282.638692 -272.248903) (xy 282.618404 -272.29516) (xy 282.59078 -272.337448) (xy 282.556573 -272.374612)
			(xy 282.516716 -272.40564) (xy 282.472295 -272.429685) (xy 282.424524 -272.446092) (xy 282.374703 -272.454413)
			(xy 282.349448 -272.454878) (xy 282.340344 -272.45478) (xy 282.322171 -272.453636) (xy 282.313126 -272.452592)
			(xy 282.301188 -272.451322) (xy 282.278836 -272.459196) (xy 282.205938 -272.53565) (xy 282.198826 -272.558256)
			(xy 282.200858 -272.570194) (xy 282.202998 -272.583745) (xy 282.205288 -272.611086) (xy 282.20543 -272.624804)
			(xy 282.20543 -272.673318) (xy 282.205894 -272.683975) (xy 282.214584 -272.703434) (xy 282.222194 -272.71091)
			(xy 282.285948 -272.768822) (xy 282.306268 -272.775426) (xy 282.31719 -272.77441) (xy 282.349702 -272.772632)
			(xy 282.375411 -272.773136) (xy 282.426196 -272.78118) (xy 282.475097 -272.797069) (xy 282.52091 -272.820413)
			(xy 282.562508 -272.850635) (xy 282.598866 -272.886993) (xy 282.629088 -272.928591) (xy 282.652431 -272.974405)
			(xy 282.66832 -273.023306) (xy 282.676364 -273.074091) (xy 282.676364 -273.099784) (xy 282.994112 -273.099784)
			(xy 282.998072 -273.05073) (xy 283.009849 -273.002946) (xy 283.02914 -272.95767) (xy 283.055443 -272.916074)
			(xy 283.088078 -272.879237) (xy 283.126199 -272.848112) (xy 283.16882 -272.823505) (xy 283.214836 -272.806053)
			(xy 283.263055 -272.796209) (xy 283.31223 -272.794228) (xy 283.361085 -272.80016) (xy 283.408356 -272.813852)
			(xy 283.452818 -272.83495) (xy 283.493321 -272.862906) (xy 283.528814 -272.896998) (xy 283.558379 -272.936342)
			(xy 283.58125 -272.979919) (xy 283.596834 -273.0266) (xy 283.604729 -273.075177) (xy 283.605224 -273.099784)
			(xy 283.604729 -273.124391) (xy 283.60455 -273.125492) (xy 283.923228 -273.125492) (xy 283.923228 -273.074076)
			(xy 283.931271 -273.023294) (xy 283.947159 -272.974395) (xy 283.970502 -272.928583) (xy 284.000723 -272.886987)
			(xy 284.037079 -272.850631) (xy 284.078675 -272.82041) (xy 284.124487 -272.797067) (xy 284.173386 -272.781179)
			(xy 284.224168 -272.773136) (xy 284.275584 -272.773136) (xy 284.326366 -272.781179) (xy 284.375265 -272.797067)
			(xy 284.421077 -272.82041) (xy 284.462673 -272.850631) (xy 284.499029 -272.886987) (xy 284.52925 -272.928583)
			(xy 284.552593 -272.974395) (xy 284.568481 -273.023294) (xy 284.576524 -273.074076) (xy 284.577028 -273.099784)
			(xy 284.894032 -273.099784) (xy 284.897992 -273.05073) (xy 284.909769 -273.002946) (xy 284.92906 -272.95767)
			(xy 284.955363 -272.916074) (xy 284.987998 -272.879237) (xy 285.026119 -272.848112) (xy 285.06874 -272.823505)
			(xy 285.114756 -272.806053) (xy 285.162975 -272.796209) (xy 285.21215 -272.794228) (xy 285.261005 -272.80016)
			(xy 285.308276 -272.813852) (xy 285.352738 -272.83495) (xy 285.393241 -272.862906) (xy 285.428734 -272.896998)
			(xy 285.458299 -272.936342) (xy 285.48117 -272.979919) (xy 285.496754 -273.0266) (xy 285.504649 -273.075177)
			(xy 285.505144 -273.099784) (xy 285.504649 -273.124391) (xy 285.50447 -273.125492) (xy 285.823148 -273.125492)
			(xy 285.823148 -273.074076) (xy 285.831191 -273.023294) (xy 285.847079 -272.974395) (xy 285.870422 -272.928583)
			(xy 285.900643 -272.886987) (xy 285.936999 -272.850631) (xy 285.978595 -272.82041) (xy 286.024407 -272.797067)
			(xy 286.073306 -272.781179) (xy 286.124088 -272.773136) (xy 286.175504 -272.773136) (xy 286.226286 -272.781179)
			(xy 286.275185 -272.797067) (xy 286.320997 -272.82041) (xy 286.362593 -272.850631) (xy 286.398949 -272.886987)
			(xy 286.42917 -272.928583) (xy 286.452513 -272.974395) (xy 286.468401 -273.023294) (xy 286.476444 -273.074076)
			(xy 286.476948 -273.099784) (xy 286.793952 -273.099784) (xy 286.797912 -273.05073) (xy 286.809689 -273.002946)
			(xy 286.82898 -272.95767) (xy 286.855283 -272.916074) (xy 286.887918 -272.879237) (xy 286.926039 -272.848112)
			(xy 286.96866 -272.823505) (xy 287.014676 -272.806053) (xy 287.062895 -272.796209) (xy 287.11207 -272.794228)
			(xy 287.160925 -272.80016) (xy 287.208196 -272.813852) (xy 287.252658 -272.83495) (xy 287.293161 -272.862906)
			(xy 287.328654 -272.896998) (xy 287.358219 -272.936342) (xy 287.38109 -272.979919) (xy 287.396674 -273.0266)
			(xy 287.404569 -273.075177) (xy 287.405064 -273.099784) (xy 287.404569 -273.124391) (xy 287.40439 -273.125492)
			(xy 287.723068 -273.125492) (xy 287.723068 -273.074076) (xy 287.731111 -273.023294) (xy 287.746999 -272.974395)
			(xy 287.770342 -272.928583) (xy 287.800563 -272.886987) (xy 287.836919 -272.850631) (xy 287.878515 -272.82041)
			(xy 287.924327 -272.797067) (xy 287.973226 -272.781179) (xy 288.024008 -272.773136) (xy 288.075424 -272.773136)
			(xy 288.126206 -272.781179) (xy 288.175105 -272.797067) (xy 288.220917 -272.82041) (xy 288.262513 -272.850631)
			(xy 288.298869 -272.886987) (xy 288.32909 -272.928583) (xy 288.352433 -272.974395) (xy 288.368321 -273.023294)
			(xy 288.376364 -273.074076) (xy 288.376868 -273.099784) (xy 288.694126 -273.099784) (xy 288.698086 -273.05073)
			(xy 288.709863 -273.002946) (xy 288.729154 -272.95767) (xy 288.755457 -272.916074) (xy 288.788092 -272.879237)
			(xy 288.826213 -272.848112) (xy 288.868834 -272.823505) (xy 288.91485 -272.806053) (xy 288.963069 -272.796209)
			(xy 289.012244 -272.794228) (xy 289.061099 -272.80016) (xy 289.10837 -272.813852) (xy 289.152832 -272.83495)
			(xy 289.193335 -272.862906) (xy 289.228828 -272.896998) (xy 289.258393 -272.936342) (xy 289.281264 -272.979919)
			(xy 289.296848 -273.0266) (xy 289.304743 -273.075177) (xy 289.305238 -273.099784) (xy 289.304743 -273.124391)
			(xy 289.304564 -273.125492) (xy 289.623242 -273.125492) (xy 289.623242 -273.074076) (xy 289.631285 -273.023294)
			(xy 289.647173 -272.974395) (xy 289.670516 -272.928583) (xy 289.700737 -272.886987) (xy 289.737093 -272.850631)
			(xy 289.778689 -272.82041) (xy 289.824501 -272.797067) (xy 289.8734 -272.781179) (xy 289.924182 -272.773136)
			(xy 289.975598 -272.773136) (xy 290.02638 -272.781179) (xy 290.075279 -272.797067) (xy 290.121091 -272.82041)
			(xy 290.162687 -272.850631) (xy 290.199043 -272.886987) (xy 290.229264 -272.928583) (xy 290.252607 -272.974395)
			(xy 290.268495 -273.023294) (xy 290.276538 -273.074076) (xy 290.277042 -273.099784) (xy 290.594046 -273.099784)
			(xy 290.598006 -273.05073) (xy 290.609783 -273.002946) (xy 290.629074 -272.95767) (xy 290.655377 -272.916074)
			(xy 290.688012 -272.879237) (xy 290.726133 -272.848112) (xy 290.768754 -272.823505) (xy 290.81477 -272.806053)
			(xy 290.862989 -272.796209) (xy 290.912164 -272.794228) (xy 290.961019 -272.80016) (xy 291.00829 -272.813852)
			(xy 291.052752 -272.83495) (xy 291.093255 -272.862906) (xy 291.128748 -272.896998) (xy 291.158313 -272.936342)
			(xy 291.181184 -272.979919) (xy 291.196768 -273.0266) (xy 291.204663 -273.075177) (xy 291.205158 -273.099784)
			(xy 291.204663 -273.124391) (xy 291.204525 -273.125238) (xy 291.522908 -273.125238) (xy 291.522908 -273.073822)
			(xy 291.530951 -273.02304) (xy 291.546839 -272.974141) (xy 291.570182 -272.928329) (xy 291.600403 -272.886733)
			(xy 291.636759 -272.850377) (xy 291.678355 -272.820156) (xy 291.724167 -272.796813) (xy 291.773066 -272.780925)
			(xy 291.823848 -272.772882) (xy 291.875264 -272.772882) (xy 291.926046 -272.780925) (xy 291.974945 -272.796813)
			(xy 292.020757 -272.820156) (xy 292.062353 -272.850377) (xy 292.098709 -272.886733) (xy 292.12893 -272.928329)
			(xy 292.152273 -272.974141) (xy 292.168161 -273.02304) (xy 292.176204 -273.073822) (xy 292.176708 -273.09953)
			(xy 292.176703 -273.099784) (xy 292.493966 -273.099784) (xy 292.497926 -273.05073) (xy 292.509703 -273.002946)
			(xy 292.528994 -272.95767) (xy 292.555297 -272.916074) (xy 292.587932 -272.879237) (xy 292.626053 -272.848112)
			(xy 292.668674 -272.823505) (xy 292.71469 -272.806053) (xy 292.762909 -272.796209) (xy 292.812084 -272.794228)
			(xy 292.860939 -272.80016) (xy 292.90821 -272.813852) (xy 292.952672 -272.83495) (xy 292.993175 -272.862906)
			(xy 293.028668 -272.896998) (xy 293.058233 -272.936342) (xy 293.081104 -272.979919) (xy 293.096688 -273.0266)
			(xy 293.104583 -273.075177) (xy 293.105078 -273.099784) (xy 293.104583 -273.124391) (xy 293.104404 -273.125492)
			(xy 293.422828 -273.125492) (xy 293.422828 -273.074076) (xy 293.430871 -273.023294) (xy 293.446759 -272.974395)
			(xy 293.470102 -272.928583) (xy 293.500323 -272.886987) (xy 293.536679 -272.850631) (xy 293.578275 -272.82041)
			(xy 293.624087 -272.797067) (xy 293.672986 -272.781179) (xy 293.723768 -272.773136) (xy 293.775184 -272.773136)
			(xy 293.825966 -272.781179) (xy 293.874865 -272.797067) (xy 293.920677 -272.82041) (xy 293.962273 -272.850631)
			(xy 293.998629 -272.886987) (xy 294.02885 -272.928583) (xy 294.052193 -272.974395) (xy 294.068081 -273.023294)
			(xy 294.076124 -273.074076) (xy 294.076628 -273.099784) (xy 294.393886 -273.099784) (xy 294.397846 -273.05073)
			(xy 294.409623 -273.002946) (xy 294.428914 -272.95767) (xy 294.455217 -272.916074) (xy 294.487852 -272.879237)
			(xy 294.525973 -272.848112) (xy 294.568594 -272.823505) (xy 294.61461 -272.806053) (xy 294.662829 -272.796209)
			(xy 294.712004 -272.794228) (xy 294.760859 -272.80016) (xy 294.80813 -272.813852) (xy 294.852592 -272.83495)
			(xy 294.893095 -272.862906) (xy 294.928588 -272.896998) (xy 294.958153 -272.936342) (xy 294.981024 -272.979919)
			(xy 294.996608 -273.0266) (xy 295.004503 -273.075177) (xy 295.004998 -273.099784) (xy 295.004503 -273.124391)
			(xy 295.004324 -273.125492) (xy 295.323002 -273.125492) (xy 295.323002 -273.074076) (xy 295.331045 -273.023294)
			(xy 295.346933 -272.974395) (xy 295.370276 -272.928583) (xy 295.400497 -272.886987) (xy 295.436853 -272.850631)
			(xy 295.478449 -272.82041) (xy 295.524261 -272.797067) (xy 295.57316 -272.781179) (xy 295.623942 -272.773136)
			(xy 295.675358 -272.773136) (xy 295.72614 -272.781179) (xy 295.775039 -272.797067) (xy 295.820851 -272.82041)
			(xy 295.862447 -272.850631) (xy 295.898803 -272.886987) (xy 295.929024 -272.928583) (xy 295.952367 -272.974395)
			(xy 295.968255 -273.023294) (xy 295.976298 -273.074076) (xy 295.976802 -273.099784) (xy 296.29406 -273.099784)
			(xy 296.29802 -273.05073) (xy 296.309797 -273.002946) (xy 296.329088 -272.95767) (xy 296.355391 -272.916074)
			(xy 296.388026 -272.879237) (xy 296.426147 -272.848112) (xy 296.468768 -272.823505) (xy 296.514784 -272.806053)
			(xy 296.563003 -272.796209) (xy 296.612178 -272.794228) (xy 296.661033 -272.80016) (xy 296.708304 -272.813852)
			(xy 296.752766 -272.83495) (xy 296.793269 -272.862906) (xy 296.828762 -272.896998) (xy 296.858327 -272.936342)
			(xy 296.881198 -272.979919) (xy 296.896782 -273.0266) (xy 296.904677 -273.075177) (xy 296.905172 -273.099784)
			(xy 296.904677 -273.124391) (xy 296.904498 -273.125492) (xy 297.222922 -273.125492) (xy 297.222922 -273.074076)
			(xy 297.230965 -273.023294) (xy 297.246853 -272.974395) (xy 297.270196 -272.928583) (xy 297.300417 -272.886987)
			(xy 297.336773 -272.850631) (xy 297.378369 -272.82041) (xy 297.424181 -272.797067) (xy 297.47308 -272.781179)
			(xy 297.523862 -272.773136) (xy 297.575278 -272.773136) (xy 297.62606 -272.781179) (xy 297.674959 -272.797067)
			(xy 297.720771 -272.82041) (xy 297.762367 -272.850631) (xy 297.798723 -272.886987) (xy 297.828944 -272.928583)
			(xy 297.852287 -272.974395) (xy 297.868175 -273.023294) (xy 297.876218 -273.074076) (xy 297.876722 -273.099784)
			(xy 298.19398 -273.099784) (xy 298.19794 -273.05073) (xy 298.209717 -273.002946) (xy 298.229008 -272.95767)
			(xy 298.255311 -272.916074) (xy 298.287946 -272.879237) (xy 298.326067 -272.848112) (xy 298.368688 -272.823505)
			(xy 298.414704 -272.806053) (xy 298.462923 -272.796209) (xy 298.512098 -272.794228) (xy 298.560953 -272.80016)
			(xy 298.608224 -272.813852) (xy 298.652686 -272.83495) (xy 298.693189 -272.862906) (xy 298.728682 -272.896998)
			(xy 298.758247 -272.936342) (xy 298.781118 -272.979919) (xy 298.796702 -273.0266) (xy 298.804597 -273.075177)
			(xy 298.805092 -273.099784) (xy 298.804597 -273.124391) (xy 298.804418 -273.125492) (xy 299.122842 -273.125492)
			(xy 299.122842 -273.074076) (xy 299.130885 -273.023294) (xy 299.146773 -272.974395) (xy 299.170116 -272.928583)
			(xy 299.200337 -272.886987) (xy 299.236693 -272.850631) (xy 299.278289 -272.82041) (xy 299.324101 -272.797067)
			(xy 299.373 -272.781179) (xy 299.423782 -272.773136) (xy 299.475198 -272.773136) (xy 299.52598 -272.781179)
			(xy 299.574879 -272.797067) (xy 299.620691 -272.82041) (xy 299.662287 -272.850631) (xy 299.698643 -272.886987)
			(xy 299.728864 -272.928583) (xy 299.752207 -272.974395) (xy 299.768095 -273.023294) (xy 299.776138 -273.074076)
			(xy 299.776642 -273.099784) (xy 300.0939 -273.099784) (xy 300.09786 -273.05073) (xy 300.109637 -273.002946)
			(xy 300.128928 -272.95767) (xy 300.155231 -272.916074) (xy 300.187866 -272.879237) (xy 300.225987 -272.848112)
			(xy 300.268608 -272.823505) (xy 300.314624 -272.806053) (xy 300.362843 -272.796209) (xy 300.412018 -272.794228)
			(xy 300.460873 -272.80016) (xy 300.508144 -272.813852) (xy 300.552606 -272.83495) (xy 300.593109 -272.862906)
			(xy 300.628602 -272.896998) (xy 300.658167 -272.936342) (xy 300.681038 -272.979919) (xy 300.696622 -273.0266)
			(xy 300.704517 -273.075177) (xy 300.705012 -273.099784) (xy 300.704517 -273.124391) (xy 300.704338 -273.125492)
			(xy 301.023016 -273.125492) (xy 301.023016 -273.074076) (xy 301.031059 -273.023294) (xy 301.046947 -272.974395)
			(xy 301.07029 -272.928583) (xy 301.100511 -272.886987) (xy 301.136867 -272.850631) (xy 301.178463 -272.82041)
			(xy 301.224275 -272.797067) (xy 301.273174 -272.781179) (xy 301.323956 -272.773136) (xy 301.375372 -272.773136)
			(xy 301.426154 -272.781179) (xy 301.475053 -272.797067) (xy 301.520865 -272.82041) (xy 301.562461 -272.850631)
			(xy 301.598817 -272.886987) (xy 301.629038 -272.928583) (xy 301.652381 -272.974395) (xy 301.668269 -273.023294)
			(xy 301.676312 -273.074076) (xy 301.676816 -273.099784) (xy 301.994074 -273.099784) (xy 301.998034 -273.05073)
			(xy 302.009811 -273.002946) (xy 302.029102 -272.95767) (xy 302.055405 -272.916074) (xy 302.08804 -272.879237)
			(xy 302.126161 -272.848112) (xy 302.168782 -272.823505) (xy 302.214798 -272.806053) (xy 302.263017 -272.796209)
			(xy 302.312192 -272.794228) (xy 302.361047 -272.80016) (xy 302.408318 -272.813852) (xy 302.45278 -272.83495)
			(xy 302.493283 -272.862906) (xy 302.528776 -272.896998) (xy 302.558341 -272.936342) (xy 302.581212 -272.979919)
			(xy 302.596796 -273.0266) (xy 302.604691 -273.075177) (xy 302.605186 -273.099784) (xy 302.604691 -273.124391)
			(xy 302.604512 -273.125492) (xy 302.922936 -273.125492) (xy 302.922936 -273.074076) (xy 302.930979 -273.023294)
			(xy 302.946867 -272.974395) (xy 302.97021 -272.928583) (xy 303.000431 -272.886987) (xy 303.036787 -272.850631)
			(xy 303.078383 -272.82041) (xy 303.124195 -272.797067) (xy 303.173094 -272.781179) (xy 303.223876 -272.773136)
			(xy 303.275292 -272.773136) (xy 303.326074 -272.781179) (xy 303.374973 -272.797067) (xy 303.420785 -272.82041)
			(xy 303.462381 -272.850631) (xy 303.498737 -272.886987) (xy 303.528958 -272.928583) (xy 303.552301 -272.974395)
			(xy 303.568189 -273.023294) (xy 303.576232 -273.074076) (xy 303.576736 -273.099784) (xy 303.893994 -273.099784)
			(xy 303.897954 -273.05073) (xy 303.909731 -273.002946) (xy 303.929022 -272.95767) (xy 303.955325 -272.916074)
			(xy 303.98796 -272.879237) (xy 304.026081 -272.848112) (xy 304.068702 -272.823505) (xy 304.114718 -272.806053)
			(xy 304.162937 -272.796209) (xy 304.212112 -272.794228) (xy 304.260967 -272.80016) (xy 304.308238 -272.813852)
			(xy 304.3527 -272.83495) (xy 304.393203 -272.862906) (xy 304.428696 -272.896998) (xy 304.458261 -272.936342)
			(xy 304.481132 -272.979919) (xy 304.496716 -273.0266) (xy 304.504611 -273.075177) (xy 304.505106 -273.099784)
			(xy 304.504611 -273.124391) (xy 304.504432 -273.125492) (xy 304.822856 -273.125492) (xy 304.822856 -273.074076)
			(xy 304.830899 -273.023294) (xy 304.846787 -272.974395) (xy 304.87013 -272.928583) (xy 304.900351 -272.886987)
			(xy 304.936707 -272.850631) (xy 304.978303 -272.82041) (xy 305.024115 -272.797067) (xy 305.073014 -272.781179)
			(xy 305.123796 -272.773136) (xy 305.175212 -272.773136) (xy 305.225994 -272.781179) (xy 305.274893 -272.797067)
			(xy 305.320705 -272.82041) (xy 305.362301 -272.850631) (xy 305.398657 -272.886987) (xy 305.428878 -272.928583)
			(xy 305.452221 -272.974395) (xy 305.468109 -273.023294) (xy 305.476152 -273.074076) (xy 305.476656 -273.099784)
			(xy 305.793914 -273.099784) (xy 305.797874 -273.05073) (xy 305.809651 -273.002946) (xy 305.828942 -272.95767)
			(xy 305.855245 -272.916074) (xy 305.88788 -272.879237) (xy 305.926001 -272.848112) (xy 305.968622 -272.823505)
			(xy 306.014638 -272.806053) (xy 306.062857 -272.796209) (xy 306.112032 -272.794228) (xy 306.160887 -272.80016)
			(xy 306.208158 -272.813852) (xy 306.25262 -272.83495) (xy 306.293123 -272.862906) (xy 306.328616 -272.896998)
			(xy 306.358181 -272.936342) (xy 306.381052 -272.979919) (xy 306.396636 -273.0266) (xy 306.404531 -273.075177)
			(xy 306.405026 -273.099784) (xy 306.404531 -273.124391) (xy 306.404352 -273.125492) (xy 306.72303 -273.125492)
			(xy 306.72303 -273.074076) (xy 306.731073 -273.023294) (xy 306.746961 -272.974395) (xy 306.770304 -272.928583)
			(xy 306.800525 -272.886987) (xy 306.836881 -272.850631) (xy 306.878477 -272.82041) (xy 306.924289 -272.797067)
			(xy 306.973188 -272.781179) (xy 307.02397 -272.773136) (xy 307.075386 -272.773136) (xy 307.126168 -272.781179)
			(xy 307.175067 -272.797067) (xy 307.220879 -272.82041) (xy 307.262475 -272.850631) (xy 307.298831 -272.886987)
			(xy 307.329052 -272.928583) (xy 307.352395 -272.974395) (xy 307.368283 -273.023294) (xy 307.376326 -273.074076)
			(xy 307.37683 -273.099784) (xy 307.694088 -273.099784) (xy 307.698048 -273.05073) (xy 307.709825 -273.002946)
			(xy 307.729116 -272.95767) (xy 307.755419 -272.916074) (xy 307.788054 -272.879237) (xy 307.826175 -272.848112)
			(xy 307.868796 -272.823505) (xy 307.914812 -272.806053) (xy 307.963031 -272.796209) (xy 308.012206 -272.794228)
			(xy 308.061061 -272.80016) (xy 308.108332 -272.813852) (xy 308.152794 -272.83495) (xy 308.193297 -272.862906)
			(xy 308.22879 -272.896998) (xy 308.258355 -272.936342) (xy 308.281226 -272.979919) (xy 308.29681 -273.0266)
			(xy 308.304705 -273.075177) (xy 308.3052 -273.099784) (xy 308.304705 -273.124391) (xy 308.304526 -273.125492)
			(xy 308.62295 -273.125492) (xy 308.62295 -273.074076) (xy 308.630993 -273.023294) (xy 308.646881 -272.974395)
			(xy 308.670224 -272.928583) (xy 308.700445 -272.886987) (xy 308.736801 -272.850631) (xy 308.778397 -272.82041)
			(xy 308.824209 -272.797067) (xy 308.873108 -272.781179) (xy 308.92389 -272.773136) (xy 308.975306 -272.773136)
			(xy 309.026088 -272.781179) (xy 309.074987 -272.797067) (xy 309.120799 -272.82041) (xy 309.162395 -272.850631)
			(xy 309.198751 -272.886987) (xy 309.228972 -272.928583) (xy 309.252315 -272.974395) (xy 309.268203 -273.023294)
			(xy 309.276246 -273.074076) (xy 309.27675 -273.099784) (xy 309.594262 -273.099784) (xy 309.598222 -273.05073)
			(xy 309.609999 -273.002946) (xy 309.62929 -272.95767) (xy 309.655593 -272.916074) (xy 309.688228 -272.879237)
			(xy 309.726349 -272.848112) (xy 309.76897 -272.823505) (xy 309.814986 -272.806053) (xy 309.863205 -272.796209)
			(xy 309.91238 -272.794228) (xy 309.961235 -272.80016) (xy 310.008506 -272.813852) (xy 310.052968 -272.83495)
			(xy 310.093471 -272.862906) (xy 310.128964 -272.896998) (xy 310.158529 -272.936342) (xy 310.1814 -272.979919)
			(xy 310.196984 -273.0266) (xy 310.204879 -273.075177) (xy 310.205374 -273.099784) (xy 310.204879 -273.124391)
			(xy 310.2047 -273.125492) (xy 310.52287 -273.125492) (xy 310.52287 -273.074076) (xy 310.530913 -273.023294)
			(xy 310.546801 -272.974395) (xy 310.570144 -272.928583) (xy 310.600365 -272.886987) (xy 310.636721 -272.850631)
			(xy 310.678317 -272.82041) (xy 310.724129 -272.797067) (xy 310.773028 -272.781179) (xy 310.82381 -272.773136)
			(xy 310.875226 -272.773136) (xy 310.926008 -272.781179) (xy 310.974907 -272.797067) (xy 311.020719 -272.82041)
			(xy 311.062315 -272.850631) (xy 311.098671 -272.886987) (xy 311.128892 -272.928583) (xy 311.152235 -272.974395)
			(xy 311.168123 -273.023294) (xy 311.176166 -273.074076) (xy 311.17667 -273.099784) (xy 311.494182 -273.099784)
			(xy 311.498142 -273.05073) (xy 311.509919 -273.002946) (xy 311.52921 -272.95767) (xy 311.555513 -272.916074)
			(xy 311.588148 -272.879237) (xy 311.626269 -272.848112) (xy 311.66889 -272.823505) (xy 311.714906 -272.806053)
			(xy 311.763125 -272.796209) (xy 311.8123 -272.794228) (xy 311.861155 -272.80016) (xy 311.908426 -272.813852)
			(xy 311.952888 -272.83495) (xy 311.993391 -272.862906) (xy 312.028884 -272.896998) (xy 312.058449 -272.936342)
			(xy 312.08132 -272.979919) (xy 312.096904 -273.0266) (xy 312.104799 -273.075177) (xy 312.105294 -273.099784)
			(xy 312.104799 -273.124391) (xy 312.10462 -273.125492) (xy 312.42279 -273.125492) (xy 312.42279 -273.074076)
			(xy 312.430833 -273.023294) (xy 312.446721 -272.974395) (xy 312.470064 -272.928583) (xy 312.500285 -272.886987)
			(xy 312.536641 -272.850631) (xy 312.578237 -272.82041) (xy 312.624049 -272.797067) (xy 312.672948 -272.781179)
			(xy 312.72373 -272.773136) (xy 312.775146 -272.773136) (xy 312.825928 -272.781179) (xy 312.874827 -272.797067)
			(xy 312.920639 -272.82041) (xy 312.962235 -272.850631) (xy 312.998591 -272.886987) (xy 313.028812 -272.928583)
			(xy 313.052155 -272.974395) (xy 313.068043 -273.023294) (xy 313.076086 -273.074076) (xy 313.07659 -273.099784)
			(xy 313.394102 -273.099784) (xy 313.398062 -273.05073) (xy 313.409839 -273.002946) (xy 313.42913 -272.95767)
			(xy 313.455433 -272.916074) (xy 313.488068 -272.879237) (xy 313.526189 -272.848112) (xy 313.56881 -272.823505)
			(xy 313.614826 -272.806053) (xy 313.663045 -272.796209) (xy 313.71222 -272.794228) (xy 313.761075 -272.80016)
			(xy 313.808346 -272.813852) (xy 313.852808 -272.83495) (xy 313.893311 -272.862906) (xy 313.928804 -272.896998)
			(xy 313.958369 -272.936342) (xy 313.98124 -272.979919) (xy 313.996824 -273.0266) (xy 314.004719 -273.075177)
			(xy 314.005214 -273.099784) (xy 314.004719 -273.124391) (xy 313.996824 -273.172968) (xy 313.98124 -273.219649)
			(xy 313.958369 -273.263226) (xy 313.928804 -273.30257) (xy 313.893311 -273.336662) (xy 313.852808 -273.364618)
			(xy 313.808346 -273.385716) (xy 313.761075 -273.399408) (xy 313.71222 -273.40534) (xy 313.663045 -273.403359)
			(xy 313.614826 -273.393515) (xy 313.56881 -273.376063) (xy 313.526189 -273.351456) (xy 313.488068 -273.320331)
			(xy 313.455433 -273.283494) (xy 313.42913 -273.241898) (xy 313.409839 -273.196622) (xy 313.398062 -273.148838)
			(xy 313.394102 -273.099784) (xy 313.07659 -273.099784) (xy 313.076086 -273.125492) (xy 313.068043 -273.176274)
			(xy 313.052155 -273.225173) (xy 313.028812 -273.270985) (xy 312.998591 -273.312581) (xy 312.962235 -273.348937)
			(xy 312.920639 -273.379158) (xy 312.874827 -273.402501) (xy 312.825928 -273.418389) (xy 312.775146 -273.426432)
			(xy 312.72373 -273.426432) (xy 312.672948 -273.418389) (xy 312.624049 -273.402501) (xy 312.578237 -273.379158)
			(xy 312.536641 -273.348937) (xy 312.500285 -273.312581) (xy 312.470064 -273.270985) (xy 312.446721 -273.225173)
			(xy 312.430833 -273.176274) (xy 312.42279 -273.125492) (xy 312.10462 -273.125492) (xy 312.096904 -273.172968)
			(xy 312.08132 -273.219649) (xy 312.058449 -273.263226) (xy 312.028884 -273.30257) (xy 311.993391 -273.336662)
			(xy 311.952888 -273.364618) (xy 311.908426 -273.385716) (xy 311.861155 -273.399408) (xy 311.8123 -273.40534)
			(xy 311.763125 -273.403359) (xy 311.714906 -273.393515) (xy 311.66889 -273.376063) (xy 311.626269 -273.351456)
			(xy 311.588148 -273.320331) (xy 311.555513 -273.283494) (xy 311.52921 -273.241898) (xy 311.509919 -273.196622)
			(xy 311.498142 -273.148838) (xy 311.494182 -273.099784) (xy 311.17667 -273.099784) (xy 311.176166 -273.125492)
			(xy 311.168123 -273.176274) (xy 311.152235 -273.225173) (xy 311.128892 -273.270985) (xy 311.098671 -273.312581)
			(xy 311.062315 -273.348937) (xy 311.020719 -273.379158) (xy 310.974907 -273.402501) (xy 310.926008 -273.418389)
			(xy 310.875226 -273.426432) (xy 310.82381 -273.426432) (xy 310.773028 -273.418389) (xy 310.724129 -273.402501)
			(xy 310.678317 -273.379158) (xy 310.636721 -273.348937) (xy 310.600365 -273.312581) (xy 310.570144 -273.270985)
			(xy 310.546801 -273.225173) (xy 310.530913 -273.176274) (xy 310.52287 -273.125492) (xy 310.2047 -273.125492)
			(xy 310.196984 -273.172968) (xy 310.1814 -273.219649) (xy 310.158529 -273.263226) (xy 310.128964 -273.30257)
			(xy 310.093471 -273.336662) (xy 310.052968 -273.364618) (xy 310.008506 -273.385716) (xy 309.961235 -273.399408)
			(xy 309.91238 -273.40534) (xy 309.863205 -273.403359) (xy 309.814986 -273.393515) (xy 309.76897 -273.376063)
			(xy 309.726349 -273.351456) (xy 309.688228 -273.320331) (xy 309.655593 -273.283494) (xy 309.62929 -273.241898)
			(xy 309.609999 -273.196622) (xy 309.598222 -273.148838) (xy 309.594262 -273.099784) (xy 309.27675 -273.099784)
			(xy 309.276246 -273.125492) (xy 309.268203 -273.176274) (xy 309.252315 -273.225173) (xy 309.228972 -273.270985)
			(xy 309.198751 -273.312581) (xy 309.162395 -273.348937) (xy 309.120799 -273.379158) (xy 309.074987 -273.402501)
			(xy 309.026088 -273.418389) (xy 308.975306 -273.426432) (xy 308.92389 -273.426432) (xy 308.873108 -273.418389)
			(xy 308.824209 -273.402501) (xy 308.778397 -273.379158) (xy 308.736801 -273.348937) (xy 308.700445 -273.312581)
			(xy 308.670224 -273.270985) (xy 308.646881 -273.225173) (xy 308.630993 -273.176274) (xy 308.62295 -273.125492)
			(xy 308.304526 -273.125492) (xy 308.29681 -273.172968) (xy 308.281226 -273.219649) (xy 308.258355 -273.263226)
			(xy 308.22879 -273.30257) (xy 308.193297 -273.336662) (xy 308.152794 -273.364618) (xy 308.108332 -273.385716)
			(xy 308.061061 -273.399408) (xy 308.012206 -273.40534) (xy 307.963031 -273.403359) (xy 307.914812 -273.393515)
			(xy 307.868796 -273.376063) (xy 307.826175 -273.351456) (xy 307.788054 -273.320331) (xy 307.755419 -273.283494)
			(xy 307.729116 -273.241898) (xy 307.709825 -273.196622) (xy 307.698048 -273.148838) (xy 307.694088 -273.099784)
			(xy 307.37683 -273.099784) (xy 307.376326 -273.125492) (xy 307.368283 -273.176274) (xy 307.352395 -273.225173)
			(xy 307.329052 -273.270985) (xy 307.298831 -273.312581) (xy 307.262475 -273.348937) (xy 307.220879 -273.379158)
			(xy 307.175067 -273.402501) (xy 307.126168 -273.418389) (xy 307.075386 -273.426432) (xy 307.02397 -273.426432)
			(xy 306.973188 -273.418389) (xy 306.924289 -273.402501) (xy 306.878477 -273.379158) (xy 306.836881 -273.348937)
			(xy 306.800525 -273.312581) (xy 306.770304 -273.270985) (xy 306.746961 -273.225173) (xy 306.731073 -273.176274)
			(xy 306.72303 -273.125492) (xy 306.404352 -273.125492) (xy 306.396636 -273.172968) (xy 306.381052 -273.219649)
			(xy 306.358181 -273.263226) (xy 306.328616 -273.30257) (xy 306.293123 -273.336662) (xy 306.25262 -273.364618)
			(xy 306.208158 -273.385716) (xy 306.160887 -273.399408) (xy 306.112032 -273.40534) (xy 306.062857 -273.403359)
			(xy 306.014638 -273.393515) (xy 305.968622 -273.376063) (xy 305.926001 -273.351456) (xy 305.88788 -273.320331)
			(xy 305.855245 -273.283494) (xy 305.828942 -273.241898) (xy 305.809651 -273.196622) (xy 305.797874 -273.148838)
			(xy 305.793914 -273.099784) (xy 305.476656 -273.099784) (xy 305.476152 -273.125492) (xy 305.468109 -273.176274)
			(xy 305.452221 -273.225173) (xy 305.428878 -273.270985) (xy 305.398657 -273.312581) (xy 305.362301 -273.348937)
			(xy 305.320705 -273.379158) (xy 305.274893 -273.402501) (xy 305.225994 -273.418389) (xy 305.175212 -273.426432)
			(xy 305.123796 -273.426432) (xy 305.073014 -273.418389) (xy 305.024115 -273.402501) (xy 304.978303 -273.379158)
			(xy 304.936707 -273.348937) (xy 304.900351 -273.312581) (xy 304.87013 -273.270985) (xy 304.846787 -273.225173)
			(xy 304.830899 -273.176274) (xy 304.822856 -273.125492) (xy 304.504432 -273.125492) (xy 304.496716 -273.172968)
			(xy 304.481132 -273.219649) (xy 304.458261 -273.263226) (xy 304.428696 -273.30257) (xy 304.393203 -273.336662)
			(xy 304.3527 -273.364618) (xy 304.308238 -273.385716) (xy 304.260967 -273.399408) (xy 304.212112 -273.40534)
			(xy 304.162937 -273.403359) (xy 304.114718 -273.393515) (xy 304.068702 -273.376063) (xy 304.026081 -273.351456)
			(xy 303.98796 -273.320331) (xy 303.955325 -273.283494) (xy 303.929022 -273.241898) (xy 303.909731 -273.196622)
			(xy 303.897954 -273.148838) (xy 303.893994 -273.099784) (xy 303.576736 -273.099784) (xy 303.576232 -273.125492)
			(xy 303.568189 -273.176274) (xy 303.552301 -273.225173) (xy 303.528958 -273.270985) (xy 303.498737 -273.312581)
			(xy 303.462381 -273.348937) (xy 303.420785 -273.379158) (xy 303.374973 -273.402501) (xy 303.326074 -273.418389)
			(xy 303.275292 -273.426432) (xy 303.223876 -273.426432) (xy 303.173094 -273.418389) (xy 303.124195 -273.402501)
			(xy 303.078383 -273.379158) (xy 303.036787 -273.348937) (xy 303.000431 -273.312581) (xy 302.97021 -273.270985)
			(xy 302.946867 -273.225173) (xy 302.930979 -273.176274) (xy 302.922936 -273.125492) (xy 302.604512 -273.125492)
			(xy 302.596796 -273.172968) (xy 302.581212 -273.219649) (xy 302.558341 -273.263226) (xy 302.528776 -273.30257)
			(xy 302.493283 -273.336662) (xy 302.45278 -273.364618) (xy 302.408318 -273.385716) (xy 302.361047 -273.399408)
			(xy 302.312192 -273.40534) (xy 302.263017 -273.403359) (xy 302.214798 -273.393515) (xy 302.168782 -273.376063)
			(xy 302.126161 -273.351456) (xy 302.08804 -273.320331) (xy 302.055405 -273.283494) (xy 302.029102 -273.241898)
			(xy 302.009811 -273.196622) (xy 301.998034 -273.148838) (xy 301.994074 -273.099784) (xy 301.676816 -273.099784)
			(xy 301.676312 -273.125492) (xy 301.668269 -273.176274) (xy 301.652381 -273.225173) (xy 301.629038 -273.270985)
			(xy 301.598817 -273.312581) (xy 301.562461 -273.348937) (xy 301.520865 -273.379158) (xy 301.475053 -273.402501)
			(xy 301.426154 -273.418389) (xy 301.375372 -273.426432) (xy 301.323956 -273.426432) (xy 301.273174 -273.418389)
			(xy 301.224275 -273.402501) (xy 301.178463 -273.379158) (xy 301.136867 -273.348937) (xy 301.100511 -273.312581)
			(xy 301.07029 -273.270985) (xy 301.046947 -273.225173) (xy 301.031059 -273.176274) (xy 301.023016 -273.125492)
			(xy 300.704338 -273.125492) (xy 300.696622 -273.172968) (xy 300.681038 -273.219649) (xy 300.658167 -273.263226)
			(xy 300.628602 -273.30257) (xy 300.593109 -273.336662) (xy 300.552606 -273.364618) (xy 300.508144 -273.385716)
			(xy 300.460873 -273.399408) (xy 300.412018 -273.40534) (xy 300.362843 -273.403359) (xy 300.314624 -273.393515)
			(xy 300.268608 -273.376063) (xy 300.225987 -273.351456) (xy 300.187866 -273.320331) (xy 300.155231 -273.283494)
			(xy 300.128928 -273.241898) (xy 300.109637 -273.196622) (xy 300.09786 -273.148838) (xy 300.0939 -273.099784)
			(xy 299.776642 -273.099784) (xy 299.776138 -273.125492) (xy 299.768095 -273.176274) (xy 299.752207 -273.225173)
			(xy 299.728864 -273.270985) (xy 299.698643 -273.312581) (xy 299.662287 -273.348937) (xy 299.620691 -273.379158)
			(xy 299.574879 -273.402501) (xy 299.52598 -273.418389) (xy 299.475198 -273.426432) (xy 299.423782 -273.426432)
			(xy 299.373 -273.418389) (xy 299.324101 -273.402501) (xy 299.278289 -273.379158) (xy 299.236693 -273.348937)
			(xy 299.200337 -273.312581) (xy 299.170116 -273.270985) (xy 299.146773 -273.225173) (xy 299.130885 -273.176274)
			(xy 299.122842 -273.125492) (xy 298.804418 -273.125492) (xy 298.796702 -273.172968) (xy 298.781118 -273.219649)
			(xy 298.758247 -273.263226) (xy 298.728682 -273.30257) (xy 298.693189 -273.336662) (xy 298.652686 -273.364618)
			(xy 298.608224 -273.385716) (xy 298.560953 -273.399408) (xy 298.512098 -273.40534) (xy 298.462923 -273.403359)
			(xy 298.414704 -273.393515) (xy 298.368688 -273.376063) (xy 298.326067 -273.351456) (xy 298.287946 -273.320331)
			(xy 298.255311 -273.283494) (xy 298.229008 -273.241898) (xy 298.209717 -273.196622) (xy 298.19794 -273.148838)
			(xy 298.19398 -273.099784) (xy 297.876722 -273.099784) (xy 297.876218 -273.125492) (xy 297.868175 -273.176274)
			(xy 297.852287 -273.225173) (xy 297.828944 -273.270985) (xy 297.798723 -273.312581) (xy 297.762367 -273.348937)
			(xy 297.720771 -273.379158) (xy 297.674959 -273.402501) (xy 297.62606 -273.418389) (xy 297.575278 -273.426432)
			(xy 297.523862 -273.426432) (xy 297.47308 -273.418389) (xy 297.424181 -273.402501) (xy 297.378369 -273.379158)
			(xy 297.336773 -273.348937) (xy 297.300417 -273.312581) (xy 297.270196 -273.270985) (xy 297.246853 -273.225173)
			(xy 297.230965 -273.176274) (xy 297.222922 -273.125492) (xy 296.904498 -273.125492) (xy 296.896782 -273.172968)
			(xy 296.881198 -273.219649) (xy 296.858327 -273.263226) (xy 296.828762 -273.30257) (xy 296.793269 -273.336662)
			(xy 296.752766 -273.364618) (xy 296.708304 -273.385716) (xy 296.661033 -273.399408) (xy 296.612178 -273.40534)
			(xy 296.563003 -273.403359) (xy 296.514784 -273.393515) (xy 296.468768 -273.376063) (xy 296.426147 -273.351456)
			(xy 296.388026 -273.320331) (xy 296.355391 -273.283494) (xy 296.329088 -273.241898) (xy 296.309797 -273.196622)
			(xy 296.29802 -273.148838) (xy 296.29406 -273.099784) (xy 295.976802 -273.099784) (xy 295.976298 -273.125492)
			(xy 295.968255 -273.176274) (xy 295.952367 -273.225173) (xy 295.929024 -273.270985) (xy 295.898803 -273.312581)
			(xy 295.862447 -273.348937) (xy 295.820851 -273.379158) (xy 295.775039 -273.402501) (xy 295.72614 -273.418389)
			(xy 295.675358 -273.426432) (xy 295.623942 -273.426432) (xy 295.57316 -273.418389) (xy 295.524261 -273.402501)
			(xy 295.478449 -273.379158) (xy 295.436853 -273.348937) (xy 295.400497 -273.312581) (xy 295.370276 -273.270985)
			(xy 295.346933 -273.225173) (xy 295.331045 -273.176274) (xy 295.323002 -273.125492) (xy 295.004324 -273.125492)
			(xy 294.996608 -273.172968) (xy 294.981024 -273.219649) (xy 294.958153 -273.263226) (xy 294.928588 -273.30257)
			(xy 294.893095 -273.336662) (xy 294.852592 -273.364618) (xy 294.80813 -273.385716) (xy 294.760859 -273.399408)
			(xy 294.712004 -273.40534) (xy 294.662829 -273.403359) (xy 294.61461 -273.393515) (xy 294.568594 -273.376063)
			(xy 294.525973 -273.351456) (xy 294.487852 -273.320331) (xy 294.455217 -273.283494) (xy 294.428914 -273.241898)
			(xy 294.409623 -273.196622) (xy 294.397846 -273.148838) (xy 294.393886 -273.099784) (xy 294.076628 -273.099784)
			(xy 294.076124 -273.125492) (xy 294.068081 -273.176274) (xy 294.052193 -273.225173) (xy 294.02885 -273.270985)
			(xy 293.998629 -273.312581) (xy 293.962273 -273.348937) (xy 293.920677 -273.379158) (xy 293.874865 -273.402501)
			(xy 293.825966 -273.418389) (xy 293.775184 -273.426432) (xy 293.723768 -273.426432) (xy 293.672986 -273.418389)
			(xy 293.624087 -273.402501) (xy 293.578275 -273.379158) (xy 293.536679 -273.348937) (xy 293.500323 -273.312581)
			(xy 293.470102 -273.270985) (xy 293.446759 -273.225173) (xy 293.430871 -273.176274) (xy 293.422828 -273.125492)
			(xy 293.104404 -273.125492) (xy 293.096688 -273.172968) (xy 293.081104 -273.219649) (xy 293.058233 -273.263226)
			(xy 293.028668 -273.30257) (xy 292.993175 -273.336662) (xy 292.952672 -273.364618) (xy 292.90821 -273.385716)
			(xy 292.860939 -273.399408) (xy 292.812084 -273.40534) (xy 292.762909 -273.403359) (xy 292.71469 -273.393515)
			(xy 292.668674 -273.376063) (xy 292.626053 -273.351456) (xy 292.587932 -273.320331) (xy 292.555297 -273.283494)
			(xy 292.528994 -273.241898) (xy 292.509703 -273.196622) (xy 292.497926 -273.148838) (xy 292.493966 -273.099784)
			(xy 292.176703 -273.099784) (xy 292.176204 -273.125238) (xy 292.168161 -273.17602) (xy 292.152273 -273.224919)
			(xy 292.12893 -273.270731) (xy 292.098709 -273.312327) (xy 292.062353 -273.348683) (xy 292.020757 -273.378904)
			(xy 291.974945 -273.402247) (xy 291.926046 -273.418135) (xy 291.875264 -273.426178) (xy 291.823848 -273.426178)
			(xy 291.773066 -273.418135) (xy 291.724167 -273.402247) (xy 291.678355 -273.378904) (xy 291.636759 -273.348683)
			(xy 291.600403 -273.312327) (xy 291.570182 -273.270731) (xy 291.546839 -273.224919) (xy 291.530951 -273.17602)
			(xy 291.522908 -273.125238) (xy 291.204525 -273.125238) (xy 291.196768 -273.172968) (xy 291.181184 -273.219649)
			(xy 291.158313 -273.263226) (xy 291.128748 -273.30257) (xy 291.093255 -273.336662) (xy 291.052752 -273.364618)
			(xy 291.00829 -273.385716) (xy 290.961019 -273.399408) (xy 290.912164 -273.40534) (xy 290.862989 -273.403359)
			(xy 290.81477 -273.393515) (xy 290.768754 -273.376063) (xy 290.726133 -273.351456) (xy 290.688012 -273.320331)
			(xy 290.655377 -273.283494) (xy 290.629074 -273.241898) (xy 290.609783 -273.196622) (xy 290.598006 -273.148838)
			(xy 290.594046 -273.099784) (xy 290.277042 -273.099784) (xy 290.276538 -273.125492) (xy 290.268495 -273.176274)
			(xy 290.252607 -273.225173) (xy 290.229264 -273.270985) (xy 290.199043 -273.312581) (xy 290.162687 -273.348937)
			(xy 290.121091 -273.379158) (xy 290.075279 -273.402501) (xy 290.02638 -273.418389) (xy 289.975598 -273.426432)
			(xy 289.924182 -273.426432) (xy 289.8734 -273.418389) (xy 289.824501 -273.402501) (xy 289.778689 -273.379158)
			(xy 289.737093 -273.348937) (xy 289.700737 -273.312581) (xy 289.670516 -273.270985) (xy 289.647173 -273.225173)
			(xy 289.631285 -273.176274) (xy 289.623242 -273.125492) (xy 289.304564 -273.125492) (xy 289.296848 -273.172968)
			(xy 289.281264 -273.219649) (xy 289.258393 -273.263226) (xy 289.228828 -273.30257) (xy 289.193335 -273.336662)
			(xy 289.152832 -273.364618) (xy 289.10837 -273.385716) (xy 289.061099 -273.399408) (xy 289.012244 -273.40534)
			(xy 288.963069 -273.403359) (xy 288.91485 -273.393515) (xy 288.868834 -273.376063) (xy 288.826213 -273.351456)
			(xy 288.788092 -273.320331) (xy 288.755457 -273.283494) (xy 288.729154 -273.241898) (xy 288.709863 -273.196622)
			(xy 288.698086 -273.148838) (xy 288.694126 -273.099784) (xy 288.376868 -273.099784) (xy 288.376364 -273.125492)
			(xy 288.368321 -273.176274) (xy 288.352433 -273.225173) (xy 288.32909 -273.270985) (xy 288.298869 -273.312581)
			(xy 288.262513 -273.348937) (xy 288.220917 -273.379158) (xy 288.175105 -273.402501) (xy 288.126206 -273.418389)
			(xy 288.075424 -273.426432) (xy 288.024008 -273.426432) (xy 287.973226 -273.418389) (xy 287.924327 -273.402501)
			(xy 287.878515 -273.379158) (xy 287.836919 -273.348937) (xy 287.800563 -273.312581) (xy 287.770342 -273.270985)
			(xy 287.746999 -273.225173) (xy 287.731111 -273.176274) (xy 287.723068 -273.125492) (xy 287.40439 -273.125492)
			(xy 287.396674 -273.172968) (xy 287.38109 -273.219649) (xy 287.358219 -273.263226) (xy 287.328654 -273.30257)
			(xy 287.293161 -273.336662) (xy 287.252658 -273.364618) (xy 287.208196 -273.385716) (xy 287.160925 -273.399408)
			(xy 287.11207 -273.40534) (xy 287.062895 -273.403359) (xy 287.014676 -273.393515) (xy 286.96866 -273.376063)
			(xy 286.926039 -273.351456) (xy 286.887918 -273.320331) (xy 286.855283 -273.283494) (xy 286.82898 -273.241898)
			(xy 286.809689 -273.196622) (xy 286.797912 -273.148838) (xy 286.793952 -273.099784) (xy 286.476948 -273.099784)
			(xy 286.476444 -273.125492) (xy 286.468401 -273.176274) (xy 286.452513 -273.225173) (xy 286.42917 -273.270985)
			(xy 286.398949 -273.312581) (xy 286.362593 -273.348937) (xy 286.320997 -273.379158) (xy 286.275185 -273.402501)
			(xy 286.226286 -273.418389) (xy 286.175504 -273.426432) (xy 286.124088 -273.426432) (xy 286.073306 -273.418389)
			(xy 286.024407 -273.402501) (xy 285.978595 -273.379158) (xy 285.936999 -273.348937) (xy 285.900643 -273.312581)
			(xy 285.870422 -273.270985) (xy 285.847079 -273.225173) (xy 285.831191 -273.176274) (xy 285.823148 -273.125492)
			(xy 285.50447 -273.125492) (xy 285.496754 -273.172968) (xy 285.48117 -273.219649) (xy 285.458299 -273.263226)
			(xy 285.428734 -273.30257) (xy 285.393241 -273.336662) (xy 285.352738 -273.364618) (xy 285.308276 -273.385716)
			(xy 285.261005 -273.399408) (xy 285.21215 -273.40534) (xy 285.162975 -273.403359) (xy 285.114756 -273.393515)
			(xy 285.06874 -273.376063) (xy 285.026119 -273.351456) (xy 284.987998 -273.320331) (xy 284.955363 -273.283494)
			(xy 284.92906 -273.241898) (xy 284.909769 -273.196622) (xy 284.897992 -273.148838) (xy 284.894032 -273.099784)
			(xy 284.577028 -273.099784) (xy 284.576524 -273.125492) (xy 284.568481 -273.176274) (xy 284.552593 -273.225173)
			(xy 284.52925 -273.270985) (xy 284.499029 -273.312581) (xy 284.462673 -273.348937) (xy 284.421077 -273.379158)
			(xy 284.375265 -273.402501) (xy 284.326366 -273.418389) (xy 284.275584 -273.426432) (xy 284.224168 -273.426432)
			(xy 284.173386 -273.418389) (xy 284.124487 -273.402501) (xy 284.078675 -273.379158) (xy 284.037079 -273.348937)
			(xy 284.000723 -273.312581) (xy 283.970502 -273.270985) (xy 283.947159 -273.225173) (xy 283.931271 -273.176274)
			(xy 283.923228 -273.125492) (xy 283.60455 -273.125492) (xy 283.596834 -273.172968) (xy 283.58125 -273.219649)
			(xy 283.558379 -273.263226) (xy 283.528814 -273.30257) (xy 283.493321 -273.336662) (xy 283.452818 -273.364618)
			(xy 283.408356 -273.385716) (xy 283.361085 -273.399408) (xy 283.31223 -273.40534) (xy 283.263055 -273.403359)
			(xy 283.214836 -273.393515) (xy 283.16882 -273.376063) (xy 283.126199 -273.351456) (xy 283.088078 -273.320331)
			(xy 283.055443 -273.283494) (xy 283.02914 -273.241898) (xy 283.009849 -273.196622) (xy 282.998072 -273.148838)
			(xy 282.994112 -273.099784) (xy 282.676364 -273.099784) (xy 282.676364 -273.125509) (xy 282.66832 -273.176294)
			(xy 282.652431 -273.225195) (xy 282.629088 -273.271009) (xy 282.598866 -273.312607) (xy 282.562508 -273.348965)
			(xy 282.52091 -273.379187) (xy 282.475097 -273.402531) (xy 282.426196 -273.41842) (xy 282.375411 -273.426464)
			(xy 282.349702 -273.426936) (xy 282.316936 -273.425158) (xy 282.306014 -273.424142) (xy 282.285948 -273.430746)
			(xy 282.22194 -273.488658) (xy 282.214424 -273.4962) (xy 282.205749 -273.515619) (xy 282.205176 -273.52625)
			(xy 282.205176 -273.574764) (xy 282.205134 -273.584118) (xy 282.20412 -273.602799) (xy 282.203144 -273.612102)
			(xy 282.20162 -273.623786) (xy 282.20924 -273.645376) (xy 282.28163 -273.718274) (xy 282.30322 -273.725894)
			(xy 282.314904 -273.724624) (xy 282.349702 -273.722592) (xy 282.375406 -273.723097) (xy 282.426182 -273.731139)
			(xy 282.475074 -273.747025) (xy 282.520879 -273.770364) (xy 282.562469 -273.800581) (xy 282.59882 -273.836933)
			(xy 282.629037 -273.878523) (xy 282.652376 -273.924328) (xy 282.668262 -273.97322) (xy 282.676304 -274.023996)
			(xy 282.676304 -274.049744) (xy 282.994112 -274.049744) (xy 282.998072 -274.00069) (xy 283.009849 -273.952906)
			(xy 283.02914 -273.90763) (xy 283.055443 -273.866034) (xy 283.088078 -273.829197) (xy 283.126199 -273.798072)
			(xy 283.16882 -273.773465) (xy 283.214836 -273.756013) (xy 283.263055 -273.746169) (xy 283.31223 -273.744188)
			(xy 283.361085 -273.75012) (xy 283.408356 -273.763812) (xy 283.452818 -273.78491) (xy 283.493321 -273.812866)
			(xy 283.528814 -273.846958) (xy 283.558379 -273.886302) (xy 283.58125 -273.929879) (xy 283.596834 -273.97656)
			(xy 283.604729 -274.025137) (xy 283.605224 -274.049744) (xy 283.604729 -274.074351) (xy 283.60455 -274.075452)
			(xy 283.923228 -274.075452) (xy 283.923228 -274.024036) (xy 283.931271 -273.973254) (xy 283.947159 -273.924355)
			(xy 283.970502 -273.878543) (xy 284.000723 -273.836947) (xy 284.037079 -273.800591) (xy 284.078675 -273.77037)
			(xy 284.124487 -273.747027) (xy 284.173386 -273.731139) (xy 284.224168 -273.723096) (xy 284.275584 -273.723096)
			(xy 284.326366 -273.731139) (xy 284.375265 -273.747027) (xy 284.421077 -273.77037) (xy 284.462673 -273.800591)
			(xy 284.499029 -273.836947) (xy 284.52925 -273.878543) (xy 284.552593 -273.924355) (xy 284.568481 -273.973254)
			(xy 284.576524 -274.024036) (xy 284.577028 -274.049744) (xy 284.894032 -274.049744) (xy 284.897992 -274.00069)
			(xy 284.909769 -273.952906) (xy 284.92906 -273.90763) (xy 284.955363 -273.866034) (xy 284.987998 -273.829197)
			(xy 285.026119 -273.798072) (xy 285.06874 -273.773465) (xy 285.114756 -273.756013) (xy 285.162975 -273.746169)
			(xy 285.21215 -273.744188) (xy 285.261005 -273.75012) (xy 285.308276 -273.763812) (xy 285.352738 -273.78491)
			(xy 285.393241 -273.812866) (xy 285.428734 -273.846958) (xy 285.458299 -273.886302) (xy 285.48117 -273.929879)
			(xy 285.496754 -273.97656) (xy 285.504649 -274.025137) (xy 285.505144 -274.049744) (xy 285.504649 -274.074351)
			(xy 285.50447 -274.075452) (xy 285.823148 -274.075452) (xy 285.823148 -274.024036) (xy 285.831191 -273.973254)
			(xy 285.847079 -273.924355) (xy 285.870422 -273.878543) (xy 285.900643 -273.836947) (xy 285.936999 -273.800591)
			(xy 285.978595 -273.77037) (xy 286.024407 -273.747027) (xy 286.073306 -273.731139) (xy 286.124088 -273.723096)
			(xy 286.175504 -273.723096) (xy 286.226286 -273.731139) (xy 286.275185 -273.747027) (xy 286.320997 -273.77037)
			(xy 286.362593 -273.800591) (xy 286.398949 -273.836947) (xy 286.42917 -273.878543) (xy 286.452513 -273.924355)
			(xy 286.468401 -273.973254) (xy 286.476444 -274.024036) (xy 286.476948 -274.049744) (xy 286.793952 -274.049744)
			(xy 286.797912 -274.00069) (xy 286.809689 -273.952906) (xy 286.82898 -273.90763) (xy 286.855283 -273.866034)
			(xy 286.887918 -273.829197) (xy 286.926039 -273.798072) (xy 286.96866 -273.773465) (xy 287.014676 -273.756013)
			(xy 287.062895 -273.746169) (xy 287.11207 -273.744188) (xy 287.160925 -273.75012) (xy 287.208196 -273.763812)
			(xy 287.252658 -273.78491) (xy 287.293161 -273.812866) (xy 287.328654 -273.846958) (xy 287.358219 -273.886302)
			(xy 287.38109 -273.929879) (xy 287.396674 -273.97656) (xy 287.404569 -274.025137) (xy 287.405064 -274.049744)
			(xy 287.404569 -274.074351) (xy 287.40439 -274.075452) (xy 287.723068 -274.075452) (xy 287.723068 -274.024036)
			(xy 287.731111 -273.973254) (xy 287.746999 -273.924355) (xy 287.770342 -273.878543) (xy 287.800563 -273.836947)
			(xy 287.836919 -273.800591) (xy 287.878515 -273.77037) (xy 287.924327 -273.747027) (xy 287.973226 -273.731139)
			(xy 288.024008 -273.723096) (xy 288.075424 -273.723096) (xy 288.126206 -273.731139) (xy 288.175105 -273.747027)
			(xy 288.220917 -273.77037) (xy 288.262513 -273.800591) (xy 288.298869 -273.836947) (xy 288.32909 -273.878543)
			(xy 288.352433 -273.924355) (xy 288.368321 -273.973254) (xy 288.376364 -274.024036) (xy 288.376868 -274.049744)
			(xy 288.694126 -274.049744) (xy 288.698086 -274.00069) (xy 288.709863 -273.952906) (xy 288.729154 -273.90763)
			(xy 288.755457 -273.866034) (xy 288.788092 -273.829197) (xy 288.826213 -273.798072) (xy 288.868834 -273.773465)
			(xy 288.91485 -273.756013) (xy 288.963069 -273.746169) (xy 289.012244 -273.744188) (xy 289.061099 -273.75012)
			(xy 289.10837 -273.763812) (xy 289.152832 -273.78491) (xy 289.193335 -273.812866) (xy 289.228828 -273.846958)
			(xy 289.258393 -273.886302) (xy 289.281264 -273.929879) (xy 289.296848 -273.97656) (xy 289.304743 -274.025137)
			(xy 289.305238 -274.049744) (xy 289.304743 -274.074351) (xy 289.304564 -274.075452) (xy 289.623242 -274.075452)
			(xy 289.623242 -274.024036) (xy 289.631285 -273.973254) (xy 289.647173 -273.924355) (xy 289.670516 -273.878543)
			(xy 289.700737 -273.836947) (xy 289.737093 -273.800591) (xy 289.778689 -273.77037) (xy 289.824501 -273.747027)
			(xy 289.8734 -273.731139) (xy 289.924182 -273.723096) (xy 289.975598 -273.723096) (xy 290.02638 -273.731139)
			(xy 290.075279 -273.747027) (xy 290.121091 -273.77037) (xy 290.162687 -273.800591) (xy 290.199043 -273.836947)
			(xy 290.229264 -273.878543) (xy 290.252607 -273.924355) (xy 290.268495 -273.973254) (xy 290.276538 -274.024036)
			(xy 290.277042 -274.049744) (xy 290.594046 -274.049744) (xy 290.598006 -274.00069) (xy 290.609783 -273.952906)
			(xy 290.629074 -273.90763) (xy 290.655377 -273.866034) (xy 290.688012 -273.829197) (xy 290.726133 -273.798072)
			(xy 290.768754 -273.773465) (xy 290.81477 -273.756013) (xy 290.862989 -273.746169) (xy 290.912164 -273.744188)
			(xy 290.961019 -273.75012) (xy 291.00829 -273.763812) (xy 291.052752 -273.78491) (xy 291.093255 -273.812866)
			(xy 291.128748 -273.846958) (xy 291.158313 -273.886302) (xy 291.181184 -273.929879) (xy 291.196768 -273.97656)
			(xy 291.204663 -274.025137) (xy 291.205158 -274.049744) (xy 291.204663 -274.074351) (xy 291.204525 -274.075198)
			(xy 291.522908 -274.075198) (xy 291.522908 -274.023782) (xy 291.530951 -273.973) (xy 291.546839 -273.924101)
			(xy 291.570182 -273.878289) (xy 291.600403 -273.836693) (xy 291.636759 -273.800337) (xy 291.678355 -273.770116)
			(xy 291.724167 -273.746773) (xy 291.773066 -273.730885) (xy 291.823848 -273.722842) (xy 291.875264 -273.722842)
			(xy 291.926046 -273.730885) (xy 291.974945 -273.746773) (xy 292.020757 -273.770116) (xy 292.062353 -273.800337)
			(xy 292.098709 -273.836693) (xy 292.12893 -273.878289) (xy 292.152273 -273.924101) (xy 292.168161 -273.973)
			(xy 292.176204 -274.023782) (xy 292.176708 -274.04949) (xy 292.176703 -274.049744) (xy 292.493966 -274.049744)
			(xy 292.497926 -274.00069) (xy 292.509703 -273.952906) (xy 292.528994 -273.90763) (xy 292.555297 -273.866034)
			(xy 292.587932 -273.829197) (xy 292.626053 -273.798072) (xy 292.668674 -273.773465) (xy 292.71469 -273.756013)
			(xy 292.762909 -273.746169) (xy 292.812084 -273.744188) (xy 292.860939 -273.75012) (xy 292.90821 -273.763812)
			(xy 292.952672 -273.78491) (xy 292.993175 -273.812866) (xy 293.028668 -273.846958) (xy 293.058233 -273.886302)
			(xy 293.081104 -273.929879) (xy 293.096688 -273.97656) (xy 293.104583 -274.025137) (xy 293.105078 -274.049744)
			(xy 293.104583 -274.074351) (xy 293.104404 -274.075452) (xy 293.422828 -274.075452) (xy 293.422828 -274.024036)
			(xy 293.430871 -273.973254) (xy 293.446759 -273.924355) (xy 293.470102 -273.878543) (xy 293.500323 -273.836947)
			(xy 293.536679 -273.800591) (xy 293.578275 -273.77037) (xy 293.624087 -273.747027) (xy 293.672986 -273.731139)
			(xy 293.723768 -273.723096) (xy 293.775184 -273.723096) (xy 293.825966 -273.731139) (xy 293.874865 -273.747027)
			(xy 293.920677 -273.77037) (xy 293.962273 -273.800591) (xy 293.998629 -273.836947) (xy 294.02885 -273.878543)
			(xy 294.052193 -273.924355) (xy 294.068081 -273.973254) (xy 294.076124 -274.024036) (xy 294.076628 -274.049744)
			(xy 294.393886 -274.049744) (xy 294.397846 -274.00069) (xy 294.409623 -273.952906) (xy 294.428914 -273.90763)
			(xy 294.455217 -273.866034) (xy 294.487852 -273.829197) (xy 294.525973 -273.798072) (xy 294.568594 -273.773465)
			(xy 294.61461 -273.756013) (xy 294.662829 -273.746169) (xy 294.712004 -273.744188) (xy 294.760859 -273.75012)
			(xy 294.80813 -273.763812) (xy 294.852592 -273.78491) (xy 294.893095 -273.812866) (xy 294.928588 -273.846958)
			(xy 294.958153 -273.886302) (xy 294.981024 -273.929879) (xy 294.996608 -273.97656) (xy 295.004503 -274.025137)
			(xy 295.004998 -274.049744) (xy 295.004503 -274.074351) (xy 295.004324 -274.075452) (xy 295.323002 -274.075452)
			(xy 295.323002 -274.024036) (xy 295.331045 -273.973254) (xy 295.346933 -273.924355) (xy 295.370276 -273.878543)
			(xy 295.400497 -273.836947) (xy 295.436853 -273.800591) (xy 295.478449 -273.77037) (xy 295.524261 -273.747027)
			(xy 295.57316 -273.731139) (xy 295.623942 -273.723096) (xy 295.675358 -273.723096) (xy 295.72614 -273.731139)
			(xy 295.775039 -273.747027) (xy 295.820851 -273.77037) (xy 295.862447 -273.800591) (xy 295.898803 -273.836947)
			(xy 295.929024 -273.878543) (xy 295.952367 -273.924355) (xy 295.968255 -273.973254) (xy 295.976298 -274.024036)
			(xy 295.976802 -274.049744) (xy 296.29406 -274.049744) (xy 296.29802 -274.00069) (xy 296.309797 -273.952906)
			(xy 296.329088 -273.90763) (xy 296.355391 -273.866034) (xy 296.388026 -273.829197) (xy 296.426147 -273.798072)
			(xy 296.468768 -273.773465) (xy 296.514784 -273.756013) (xy 296.563003 -273.746169) (xy 296.612178 -273.744188)
			(xy 296.661033 -273.75012) (xy 296.708304 -273.763812) (xy 296.752766 -273.78491) (xy 296.793269 -273.812866)
			(xy 296.828762 -273.846958) (xy 296.858327 -273.886302) (xy 296.881198 -273.929879) (xy 296.896782 -273.97656)
			(xy 296.904677 -274.025137) (xy 296.905172 -274.049744) (xy 296.904677 -274.074351) (xy 296.904498 -274.075452)
			(xy 297.222922 -274.075452) (xy 297.222922 -274.024036) (xy 297.230965 -273.973254) (xy 297.246853 -273.924355)
			(xy 297.270196 -273.878543) (xy 297.300417 -273.836947) (xy 297.336773 -273.800591) (xy 297.378369 -273.77037)
			(xy 297.424181 -273.747027) (xy 297.47308 -273.731139) (xy 297.523862 -273.723096) (xy 297.575278 -273.723096)
			(xy 297.62606 -273.731139) (xy 297.674959 -273.747027) (xy 297.720771 -273.77037) (xy 297.762367 -273.800591)
			(xy 297.798723 -273.836947) (xy 297.828944 -273.878543) (xy 297.852287 -273.924355) (xy 297.868175 -273.973254)
			(xy 297.876218 -274.024036) (xy 297.876722 -274.049744) (xy 298.19398 -274.049744) (xy 298.19794 -274.00069)
			(xy 298.209717 -273.952906) (xy 298.229008 -273.90763) (xy 298.255311 -273.866034) (xy 298.287946 -273.829197)
			(xy 298.326067 -273.798072) (xy 298.368688 -273.773465) (xy 298.414704 -273.756013) (xy 298.462923 -273.746169)
			(xy 298.512098 -273.744188) (xy 298.560953 -273.75012) (xy 298.608224 -273.763812) (xy 298.652686 -273.78491)
			(xy 298.693189 -273.812866) (xy 298.728682 -273.846958) (xy 298.758247 -273.886302) (xy 298.781118 -273.929879)
			(xy 298.796702 -273.97656) (xy 298.804597 -274.025137) (xy 298.805092 -274.049744) (xy 298.804597 -274.074351)
			(xy 298.804418 -274.075452) (xy 299.122842 -274.075452) (xy 299.122842 -274.024036) (xy 299.130885 -273.973254)
			(xy 299.146773 -273.924355) (xy 299.170116 -273.878543) (xy 299.200337 -273.836947) (xy 299.236693 -273.800591)
			(xy 299.278289 -273.77037) (xy 299.324101 -273.747027) (xy 299.373 -273.731139) (xy 299.423782 -273.723096)
			(xy 299.475198 -273.723096) (xy 299.52598 -273.731139) (xy 299.574879 -273.747027) (xy 299.620691 -273.77037)
			(xy 299.662287 -273.800591) (xy 299.698643 -273.836947) (xy 299.728864 -273.878543) (xy 299.752207 -273.924355)
			(xy 299.768095 -273.973254) (xy 299.776138 -274.024036) (xy 299.776642 -274.049744) (xy 300.0939 -274.049744)
			(xy 300.09786 -274.00069) (xy 300.109637 -273.952906) (xy 300.128928 -273.90763) (xy 300.155231 -273.866034)
			(xy 300.187866 -273.829197) (xy 300.225987 -273.798072) (xy 300.268608 -273.773465) (xy 300.314624 -273.756013)
			(xy 300.362843 -273.746169) (xy 300.412018 -273.744188) (xy 300.460873 -273.75012) (xy 300.508144 -273.763812)
			(xy 300.552606 -273.78491) (xy 300.593109 -273.812866) (xy 300.628602 -273.846958) (xy 300.658167 -273.886302)
			(xy 300.681038 -273.929879) (xy 300.696622 -273.97656) (xy 300.704517 -274.025137) (xy 300.705012 -274.049744)
			(xy 300.704517 -274.074351) (xy 300.704338 -274.075452) (xy 301.023016 -274.075452) (xy 301.023016 -274.024036)
			(xy 301.031059 -273.973254) (xy 301.046947 -273.924355) (xy 301.07029 -273.878543) (xy 301.100511 -273.836947)
			(xy 301.136867 -273.800591) (xy 301.178463 -273.77037) (xy 301.224275 -273.747027) (xy 301.273174 -273.731139)
			(xy 301.323956 -273.723096) (xy 301.375372 -273.723096) (xy 301.426154 -273.731139) (xy 301.475053 -273.747027)
			(xy 301.520865 -273.77037) (xy 301.562461 -273.800591) (xy 301.598817 -273.836947) (xy 301.629038 -273.878543)
			(xy 301.652381 -273.924355) (xy 301.668269 -273.973254) (xy 301.676312 -274.024036) (xy 301.676816 -274.049744)
			(xy 301.994074 -274.049744) (xy 301.998034 -274.00069) (xy 302.009811 -273.952906) (xy 302.029102 -273.90763)
			(xy 302.055405 -273.866034) (xy 302.08804 -273.829197) (xy 302.126161 -273.798072) (xy 302.168782 -273.773465)
			(xy 302.214798 -273.756013) (xy 302.263017 -273.746169) (xy 302.312192 -273.744188) (xy 302.361047 -273.75012)
			(xy 302.408318 -273.763812) (xy 302.45278 -273.78491) (xy 302.493283 -273.812866) (xy 302.528776 -273.846958)
			(xy 302.558341 -273.886302) (xy 302.581212 -273.929879) (xy 302.596796 -273.97656) (xy 302.604691 -274.025137)
			(xy 302.605186 -274.049744) (xy 302.604691 -274.074351) (xy 302.604512 -274.075452) (xy 302.922936 -274.075452)
			(xy 302.922936 -274.024036) (xy 302.930979 -273.973254) (xy 302.946867 -273.924355) (xy 302.97021 -273.878543)
			(xy 303.000431 -273.836947) (xy 303.036787 -273.800591) (xy 303.078383 -273.77037) (xy 303.124195 -273.747027)
			(xy 303.173094 -273.731139) (xy 303.223876 -273.723096) (xy 303.275292 -273.723096) (xy 303.326074 -273.731139)
			(xy 303.374973 -273.747027) (xy 303.420785 -273.77037) (xy 303.462381 -273.800591) (xy 303.498737 -273.836947)
			(xy 303.528958 -273.878543) (xy 303.552301 -273.924355) (xy 303.568189 -273.973254) (xy 303.576232 -274.024036)
			(xy 303.576736 -274.049744) (xy 303.893994 -274.049744) (xy 303.897954 -274.00069) (xy 303.909731 -273.952906)
			(xy 303.929022 -273.90763) (xy 303.955325 -273.866034) (xy 303.98796 -273.829197) (xy 304.026081 -273.798072)
			(xy 304.068702 -273.773465) (xy 304.114718 -273.756013) (xy 304.162937 -273.746169) (xy 304.212112 -273.744188)
			(xy 304.260967 -273.75012) (xy 304.308238 -273.763812) (xy 304.3527 -273.78491) (xy 304.393203 -273.812866)
			(xy 304.428696 -273.846958) (xy 304.458261 -273.886302) (xy 304.481132 -273.929879) (xy 304.496716 -273.97656)
			(xy 304.504611 -274.025137) (xy 304.505106 -274.049744) (xy 304.504611 -274.074351) (xy 304.504432 -274.075452)
			(xy 304.822856 -274.075452) (xy 304.822856 -274.024036) (xy 304.830899 -273.973254) (xy 304.846787 -273.924355)
			(xy 304.87013 -273.878543) (xy 304.900351 -273.836947) (xy 304.936707 -273.800591) (xy 304.978303 -273.77037)
			(xy 305.024115 -273.747027) (xy 305.073014 -273.731139) (xy 305.123796 -273.723096) (xy 305.175212 -273.723096)
			(xy 305.225994 -273.731139) (xy 305.274893 -273.747027) (xy 305.320705 -273.77037) (xy 305.362301 -273.800591)
			(xy 305.398657 -273.836947) (xy 305.428878 -273.878543) (xy 305.452221 -273.924355) (xy 305.468109 -273.973254)
			(xy 305.476152 -274.024036) (xy 305.476656 -274.049744) (xy 305.793914 -274.049744) (xy 305.797874 -274.00069)
			(xy 305.809651 -273.952906) (xy 305.828942 -273.90763) (xy 305.855245 -273.866034) (xy 305.88788 -273.829197)
			(xy 305.926001 -273.798072) (xy 305.968622 -273.773465) (xy 306.014638 -273.756013) (xy 306.062857 -273.746169)
			(xy 306.112032 -273.744188) (xy 306.160887 -273.75012) (xy 306.208158 -273.763812) (xy 306.25262 -273.78491)
			(xy 306.293123 -273.812866) (xy 306.328616 -273.846958) (xy 306.358181 -273.886302) (xy 306.381052 -273.929879)
			(xy 306.396636 -273.97656) (xy 306.404531 -274.025137) (xy 306.405026 -274.049744) (xy 306.404531 -274.074351)
			(xy 306.404352 -274.075452) (xy 306.72303 -274.075452) (xy 306.72303 -274.024036) (xy 306.731073 -273.973254)
			(xy 306.746961 -273.924355) (xy 306.770304 -273.878543) (xy 306.800525 -273.836947) (xy 306.836881 -273.800591)
			(xy 306.878477 -273.77037) (xy 306.924289 -273.747027) (xy 306.973188 -273.731139) (xy 307.02397 -273.723096)
			(xy 307.075386 -273.723096) (xy 307.126168 -273.731139) (xy 307.175067 -273.747027) (xy 307.220879 -273.77037)
			(xy 307.262475 -273.800591) (xy 307.298831 -273.836947) (xy 307.329052 -273.878543) (xy 307.352395 -273.924355)
			(xy 307.368283 -273.973254) (xy 307.376326 -274.024036) (xy 307.37683 -274.049744) (xy 307.694342 -274.049744)
			(xy 307.698302 -274.00069) (xy 307.710079 -273.952906) (xy 307.72937 -273.90763) (xy 307.755673 -273.866034)
			(xy 307.788308 -273.829197) (xy 307.826429 -273.798072) (xy 307.86905 -273.773465) (xy 307.915066 -273.756013)
			(xy 307.963285 -273.746169) (xy 308.01246 -273.744188) (xy 308.061315 -273.75012) (xy 308.108586 -273.763812)
			(xy 308.153048 -273.78491) (xy 308.193551 -273.812866) (xy 308.229044 -273.846958) (xy 308.258609 -273.886302)
			(xy 308.28148 -273.929879) (xy 308.297064 -273.97656) (xy 308.304959 -274.025137) (xy 308.305454 -274.049744)
			(xy 308.304959 -274.074351) (xy 308.30478 -274.075452) (xy 308.62295 -274.075452) (xy 308.62295 -274.024036)
			(xy 308.630993 -273.973254) (xy 308.646881 -273.924355) (xy 308.670224 -273.878543) (xy 308.700445 -273.836947)
			(xy 308.736801 -273.800591) (xy 308.778397 -273.77037) (xy 308.824209 -273.747027) (xy 308.873108 -273.731139)
			(xy 308.92389 -273.723096) (xy 308.975306 -273.723096) (xy 309.026088 -273.731139) (xy 309.074987 -273.747027)
			(xy 309.120799 -273.77037) (xy 309.162395 -273.800591) (xy 309.198751 -273.836947) (xy 309.228972 -273.878543)
			(xy 309.252315 -273.924355) (xy 309.268203 -273.973254) (xy 309.276246 -274.024036) (xy 309.27675 -274.049744)
			(xy 309.594262 -274.049744) (xy 309.598222 -274.00069) (xy 309.609999 -273.952906) (xy 309.62929 -273.90763)
			(xy 309.655593 -273.866034) (xy 309.688228 -273.829197) (xy 309.726349 -273.798072) (xy 309.76897 -273.773465)
			(xy 309.814986 -273.756013) (xy 309.863205 -273.746169) (xy 309.91238 -273.744188) (xy 309.961235 -273.75012)
			(xy 310.008506 -273.763812) (xy 310.052968 -273.78491) (xy 310.093471 -273.812866) (xy 310.128964 -273.846958)
			(xy 310.158529 -273.886302) (xy 310.1814 -273.929879) (xy 310.196984 -273.97656) (xy 310.204879 -274.025137)
			(xy 310.205374 -274.049744) (xy 310.204879 -274.074351) (xy 310.2047 -274.075452) (xy 310.52287 -274.075452)
			(xy 310.52287 -274.024036) (xy 310.530913 -273.973254) (xy 310.546801 -273.924355) (xy 310.570144 -273.878543)
			(xy 310.600365 -273.836947) (xy 310.636721 -273.800591) (xy 310.678317 -273.77037) (xy 310.724129 -273.747027)
			(xy 310.773028 -273.731139) (xy 310.82381 -273.723096) (xy 310.875226 -273.723096) (xy 310.926008 -273.731139)
			(xy 310.974907 -273.747027) (xy 311.020719 -273.77037) (xy 311.062315 -273.800591) (xy 311.098671 -273.836947)
			(xy 311.128892 -273.878543) (xy 311.152235 -273.924355) (xy 311.168123 -273.973254) (xy 311.176166 -274.024036)
			(xy 311.17667 -274.049744) (xy 311.494182 -274.049744) (xy 311.498142 -274.00069) (xy 311.509919 -273.952906)
			(xy 311.52921 -273.90763) (xy 311.555513 -273.866034) (xy 311.588148 -273.829197) (xy 311.626269 -273.798072)
			(xy 311.66889 -273.773465) (xy 311.714906 -273.756013) (xy 311.763125 -273.746169) (xy 311.8123 -273.744188)
			(xy 311.861155 -273.75012) (xy 311.908426 -273.763812) (xy 311.952888 -273.78491) (xy 311.993391 -273.812866)
			(xy 312.028884 -273.846958) (xy 312.058449 -273.886302) (xy 312.08132 -273.929879) (xy 312.096904 -273.97656)
			(xy 312.104799 -274.025137) (xy 312.105294 -274.049744) (xy 312.104799 -274.074351) (xy 312.10462 -274.075452)
			(xy 312.42279 -274.075452) (xy 312.42279 -274.024036) (xy 312.430833 -273.973254) (xy 312.446721 -273.924355)
			(xy 312.470064 -273.878543) (xy 312.500285 -273.836947) (xy 312.536641 -273.800591) (xy 312.578237 -273.77037)
			(xy 312.624049 -273.747027) (xy 312.672948 -273.731139) (xy 312.72373 -273.723096) (xy 312.775146 -273.723096)
			(xy 312.825928 -273.731139) (xy 312.874827 -273.747027) (xy 312.920639 -273.77037) (xy 312.962235 -273.800591)
			(xy 312.998591 -273.836947) (xy 313.028812 -273.878543) (xy 313.052155 -273.924355) (xy 313.068043 -273.973254)
			(xy 313.076086 -274.024036) (xy 313.07659 -274.049744) (xy 313.394102 -274.049744) (xy 313.398062 -274.00069)
			(xy 313.409839 -273.952906) (xy 313.42913 -273.90763) (xy 313.455433 -273.866034) (xy 313.488068 -273.829197)
			(xy 313.526189 -273.798072) (xy 313.56881 -273.773465) (xy 313.614826 -273.756013) (xy 313.663045 -273.746169)
			(xy 313.71222 -273.744188) (xy 313.761075 -273.75012) (xy 313.808346 -273.763812) (xy 313.852808 -273.78491)
			(xy 313.893311 -273.812866) (xy 313.928804 -273.846958) (xy 313.958369 -273.886302) (xy 313.98124 -273.929879)
			(xy 313.996824 -273.97656) (xy 314.004719 -274.025137) (xy 314.005214 -274.049744) (xy 314.344062 -274.049744)
			(xy 314.348022 -274.00069) (xy 314.359799 -273.952906) (xy 314.37909 -273.90763) (xy 314.405393 -273.866034)
			(xy 314.438028 -273.829197) (xy 314.476149 -273.798072) (xy 314.51877 -273.773465) (xy 314.564786 -273.756013)
			(xy 314.613005 -273.746169) (xy 314.66218 -273.744188) (xy 314.711035 -273.75012) (xy 314.758306 -273.763812)
			(xy 314.802768 -273.78491) (xy 314.843271 -273.812866) (xy 314.878764 -273.846958) (xy 314.908329 -273.886302)
			(xy 314.9312 -273.929879) (xy 314.946784 -273.97656) (xy 314.954679 -274.025137) (xy 314.955174 -274.049744)
			(xy 314.954679 -274.074351) (xy 314.946784 -274.122928) (xy 314.9312 -274.169609) (xy 314.908329 -274.213186)
			(xy 314.878764 -274.25253) (xy 314.843271 -274.286622) (xy 314.802768 -274.314578) (xy 314.758306 -274.335676)
			(xy 314.711035 -274.349368) (xy 314.66218 -274.3553) (xy 314.613005 -274.353319) (xy 314.564786 -274.343475)
			(xy 314.51877 -274.326023) (xy 314.476149 -274.301416) (xy 314.438028 -274.270291) (xy 314.405393 -274.233454)
			(xy 314.37909 -274.191858) (xy 314.359799 -274.146582) (xy 314.348022 -274.098798) (xy 314.344062 -274.049744)
			(xy 314.005214 -274.049744) (xy 314.004719 -274.074351) (xy 313.996824 -274.122928) (xy 313.98124 -274.169609)
			(xy 313.958369 -274.213186) (xy 313.928804 -274.25253) (xy 313.893311 -274.286622) (xy 313.852808 -274.314578)
			(xy 313.808346 -274.335676) (xy 313.761075 -274.349368) (xy 313.71222 -274.3553) (xy 313.663045 -274.353319)
			(xy 313.614826 -274.343475) (xy 313.56881 -274.326023) (xy 313.526189 -274.301416) (xy 313.488068 -274.270291)
			(xy 313.455433 -274.233454) (xy 313.42913 -274.191858) (xy 313.409839 -274.146582) (xy 313.398062 -274.098798)
			(xy 313.394102 -274.049744) (xy 313.07659 -274.049744) (xy 313.076086 -274.075452) (xy 313.068043 -274.126234)
			(xy 313.052155 -274.175133) (xy 313.028812 -274.220945) (xy 312.998591 -274.262541) (xy 312.962235 -274.298897)
			(xy 312.920639 -274.329118) (xy 312.874827 -274.352461) (xy 312.825928 -274.368349) (xy 312.775146 -274.376392)
			(xy 312.72373 -274.376392) (xy 312.672948 -274.368349) (xy 312.624049 -274.352461) (xy 312.578237 -274.329118)
			(xy 312.536641 -274.298897) (xy 312.500285 -274.262541) (xy 312.470064 -274.220945) (xy 312.446721 -274.175133)
			(xy 312.430833 -274.126234) (xy 312.42279 -274.075452) (xy 312.10462 -274.075452) (xy 312.096904 -274.122928)
			(xy 312.08132 -274.169609) (xy 312.058449 -274.213186) (xy 312.028884 -274.25253) (xy 311.993391 -274.286622)
			(xy 311.952888 -274.314578) (xy 311.908426 -274.335676) (xy 311.861155 -274.349368) (xy 311.8123 -274.3553)
			(xy 311.763125 -274.353319) (xy 311.714906 -274.343475) (xy 311.66889 -274.326023) (xy 311.626269 -274.301416)
			(xy 311.588148 -274.270291) (xy 311.555513 -274.233454) (xy 311.52921 -274.191858) (xy 311.509919 -274.146582)
			(xy 311.498142 -274.098798) (xy 311.494182 -274.049744) (xy 311.17667 -274.049744) (xy 311.176166 -274.075452)
			(xy 311.168123 -274.126234) (xy 311.152235 -274.175133) (xy 311.128892 -274.220945) (xy 311.098671 -274.262541)
			(xy 311.062315 -274.298897) (xy 311.020719 -274.329118) (xy 310.974907 -274.352461) (xy 310.926008 -274.368349)
			(xy 310.875226 -274.376392) (xy 310.82381 -274.376392) (xy 310.773028 -274.368349) (xy 310.724129 -274.352461)
			(xy 310.678317 -274.329118) (xy 310.636721 -274.298897) (xy 310.600365 -274.262541) (xy 310.570144 -274.220945)
			(xy 310.546801 -274.175133) (xy 310.530913 -274.126234) (xy 310.52287 -274.075452) (xy 310.2047 -274.075452)
			(xy 310.196984 -274.122928) (xy 310.1814 -274.169609) (xy 310.158529 -274.213186) (xy 310.128964 -274.25253)
			(xy 310.093471 -274.286622) (xy 310.052968 -274.314578) (xy 310.008506 -274.335676) (xy 309.961235 -274.349368)
			(xy 309.91238 -274.3553) (xy 309.863205 -274.353319) (xy 309.814986 -274.343475) (xy 309.76897 -274.326023)
			(xy 309.726349 -274.301416) (xy 309.688228 -274.270291) (xy 309.655593 -274.233454) (xy 309.62929 -274.191858)
			(xy 309.609999 -274.146582) (xy 309.598222 -274.098798) (xy 309.594262 -274.049744) (xy 309.27675 -274.049744)
			(xy 309.276246 -274.075452) (xy 309.268203 -274.126234) (xy 309.252315 -274.175133) (xy 309.228972 -274.220945)
			(xy 309.198751 -274.262541) (xy 309.162395 -274.298897) (xy 309.120799 -274.329118) (xy 309.074987 -274.352461)
			(xy 309.026088 -274.368349) (xy 308.975306 -274.376392) (xy 308.92389 -274.376392) (xy 308.873108 -274.368349)
			(xy 308.824209 -274.352461) (xy 308.778397 -274.329118) (xy 308.736801 -274.298897) (xy 308.700445 -274.262541)
			(xy 308.670224 -274.220945) (xy 308.646881 -274.175133) (xy 308.630993 -274.126234) (xy 308.62295 -274.075452)
			(xy 308.30478 -274.075452) (xy 308.297064 -274.122928) (xy 308.28148 -274.169609) (xy 308.258609 -274.213186)
			(xy 308.229044 -274.25253) (xy 308.193551 -274.286622) (xy 308.153048 -274.314578) (xy 308.108586 -274.335676)
			(xy 308.061315 -274.349368) (xy 308.01246 -274.3553) (xy 307.963285 -274.353319) (xy 307.915066 -274.343475)
			(xy 307.86905 -274.326023) (xy 307.826429 -274.301416) (xy 307.788308 -274.270291) (xy 307.755673 -274.233454)
			(xy 307.72937 -274.191858) (xy 307.710079 -274.146582) (xy 307.698302 -274.098798) (xy 307.694342 -274.049744)
			(xy 307.37683 -274.049744) (xy 307.376326 -274.075452) (xy 307.368283 -274.126234) (xy 307.352395 -274.175133)
			(xy 307.329052 -274.220945) (xy 307.298831 -274.262541) (xy 307.262475 -274.298897) (xy 307.220879 -274.329118)
			(xy 307.175067 -274.352461) (xy 307.126168 -274.368349) (xy 307.075386 -274.376392) (xy 307.02397 -274.376392)
			(xy 306.973188 -274.368349) (xy 306.924289 -274.352461) (xy 306.878477 -274.329118) (xy 306.836881 -274.298897)
			(xy 306.800525 -274.262541) (xy 306.770304 -274.220945) (xy 306.746961 -274.175133) (xy 306.731073 -274.126234)
			(xy 306.72303 -274.075452) (xy 306.404352 -274.075452) (xy 306.396636 -274.122928) (xy 306.381052 -274.169609)
			(xy 306.358181 -274.213186) (xy 306.328616 -274.25253) (xy 306.293123 -274.286622) (xy 306.25262 -274.314578)
			(xy 306.208158 -274.335676) (xy 306.160887 -274.349368) (xy 306.112032 -274.3553) (xy 306.062857 -274.353319)
			(xy 306.014638 -274.343475) (xy 305.968622 -274.326023) (xy 305.926001 -274.301416) (xy 305.88788 -274.270291)
			(xy 305.855245 -274.233454) (xy 305.828942 -274.191858) (xy 305.809651 -274.146582) (xy 305.797874 -274.098798)
			(xy 305.793914 -274.049744) (xy 305.476656 -274.049744) (xy 305.476152 -274.075452) (xy 305.468109 -274.126234)
			(xy 305.452221 -274.175133) (xy 305.428878 -274.220945) (xy 305.398657 -274.262541) (xy 305.362301 -274.298897)
			(xy 305.320705 -274.329118) (xy 305.274893 -274.352461) (xy 305.225994 -274.368349) (xy 305.175212 -274.376392)
			(xy 305.123796 -274.376392) (xy 305.073014 -274.368349) (xy 305.024115 -274.352461) (xy 304.978303 -274.329118)
			(xy 304.936707 -274.298897) (xy 304.900351 -274.262541) (xy 304.87013 -274.220945) (xy 304.846787 -274.175133)
			(xy 304.830899 -274.126234) (xy 304.822856 -274.075452) (xy 304.504432 -274.075452) (xy 304.496716 -274.122928)
			(xy 304.481132 -274.169609) (xy 304.458261 -274.213186) (xy 304.428696 -274.25253) (xy 304.393203 -274.286622)
			(xy 304.3527 -274.314578) (xy 304.308238 -274.335676) (xy 304.260967 -274.349368) (xy 304.212112 -274.3553)
			(xy 304.162937 -274.353319) (xy 304.114718 -274.343475) (xy 304.068702 -274.326023) (xy 304.026081 -274.301416)
			(xy 303.98796 -274.270291) (xy 303.955325 -274.233454) (xy 303.929022 -274.191858) (xy 303.909731 -274.146582)
			(xy 303.897954 -274.098798) (xy 303.893994 -274.049744) (xy 303.576736 -274.049744) (xy 303.576232 -274.075452)
			(xy 303.568189 -274.126234) (xy 303.552301 -274.175133) (xy 303.528958 -274.220945) (xy 303.498737 -274.262541)
			(xy 303.462381 -274.298897) (xy 303.420785 -274.329118) (xy 303.374973 -274.352461) (xy 303.326074 -274.368349)
			(xy 303.275292 -274.376392) (xy 303.223876 -274.376392) (xy 303.173094 -274.368349) (xy 303.124195 -274.352461)
			(xy 303.078383 -274.329118) (xy 303.036787 -274.298897) (xy 303.000431 -274.262541) (xy 302.97021 -274.220945)
			(xy 302.946867 -274.175133) (xy 302.930979 -274.126234) (xy 302.922936 -274.075452) (xy 302.604512 -274.075452)
			(xy 302.596796 -274.122928) (xy 302.581212 -274.169609) (xy 302.558341 -274.213186) (xy 302.528776 -274.25253)
			(xy 302.493283 -274.286622) (xy 302.45278 -274.314578) (xy 302.408318 -274.335676) (xy 302.361047 -274.349368)
			(xy 302.312192 -274.3553) (xy 302.263017 -274.353319) (xy 302.214798 -274.343475) (xy 302.168782 -274.326023)
			(xy 302.126161 -274.301416) (xy 302.08804 -274.270291) (xy 302.055405 -274.233454) (xy 302.029102 -274.191858)
			(xy 302.009811 -274.146582) (xy 301.998034 -274.098798) (xy 301.994074 -274.049744) (xy 301.676816 -274.049744)
			(xy 301.676312 -274.075452) (xy 301.668269 -274.126234) (xy 301.652381 -274.175133) (xy 301.629038 -274.220945)
			(xy 301.598817 -274.262541) (xy 301.562461 -274.298897) (xy 301.520865 -274.329118) (xy 301.475053 -274.352461)
			(xy 301.426154 -274.368349) (xy 301.375372 -274.376392) (xy 301.323956 -274.376392) (xy 301.273174 -274.368349)
			(xy 301.224275 -274.352461) (xy 301.178463 -274.329118) (xy 301.136867 -274.298897) (xy 301.100511 -274.262541)
			(xy 301.07029 -274.220945) (xy 301.046947 -274.175133) (xy 301.031059 -274.126234) (xy 301.023016 -274.075452)
			(xy 300.704338 -274.075452) (xy 300.696622 -274.122928) (xy 300.681038 -274.169609) (xy 300.658167 -274.213186)
			(xy 300.628602 -274.25253) (xy 300.593109 -274.286622) (xy 300.552606 -274.314578) (xy 300.508144 -274.335676)
			(xy 300.460873 -274.349368) (xy 300.412018 -274.3553) (xy 300.362843 -274.353319) (xy 300.314624 -274.343475)
			(xy 300.268608 -274.326023) (xy 300.225987 -274.301416) (xy 300.187866 -274.270291) (xy 300.155231 -274.233454)
			(xy 300.128928 -274.191858) (xy 300.109637 -274.146582) (xy 300.09786 -274.098798) (xy 300.0939 -274.049744)
			(xy 299.776642 -274.049744) (xy 299.776138 -274.075452) (xy 299.768095 -274.126234) (xy 299.752207 -274.175133)
			(xy 299.728864 -274.220945) (xy 299.698643 -274.262541) (xy 299.662287 -274.298897) (xy 299.620691 -274.329118)
			(xy 299.574879 -274.352461) (xy 299.52598 -274.368349) (xy 299.475198 -274.376392) (xy 299.423782 -274.376392)
			(xy 299.373 -274.368349) (xy 299.324101 -274.352461) (xy 299.278289 -274.329118) (xy 299.236693 -274.298897)
			(xy 299.200337 -274.262541) (xy 299.170116 -274.220945) (xy 299.146773 -274.175133) (xy 299.130885 -274.126234)
			(xy 299.122842 -274.075452) (xy 298.804418 -274.075452) (xy 298.796702 -274.122928) (xy 298.781118 -274.169609)
			(xy 298.758247 -274.213186) (xy 298.728682 -274.25253) (xy 298.693189 -274.286622) (xy 298.652686 -274.314578)
			(xy 298.608224 -274.335676) (xy 298.560953 -274.349368) (xy 298.512098 -274.3553) (xy 298.462923 -274.353319)
			(xy 298.414704 -274.343475) (xy 298.368688 -274.326023) (xy 298.326067 -274.301416) (xy 298.287946 -274.270291)
			(xy 298.255311 -274.233454) (xy 298.229008 -274.191858) (xy 298.209717 -274.146582) (xy 298.19794 -274.098798)
			(xy 298.19398 -274.049744) (xy 297.876722 -274.049744) (xy 297.876218 -274.075452) (xy 297.868175 -274.126234)
			(xy 297.852287 -274.175133) (xy 297.828944 -274.220945) (xy 297.798723 -274.262541) (xy 297.762367 -274.298897)
			(xy 297.720771 -274.329118) (xy 297.674959 -274.352461) (xy 297.62606 -274.368349) (xy 297.575278 -274.376392)
			(xy 297.523862 -274.376392) (xy 297.47308 -274.368349) (xy 297.424181 -274.352461) (xy 297.378369 -274.329118)
			(xy 297.336773 -274.298897) (xy 297.300417 -274.262541) (xy 297.270196 -274.220945) (xy 297.246853 -274.175133)
			(xy 297.230965 -274.126234) (xy 297.222922 -274.075452) (xy 296.904498 -274.075452) (xy 296.896782 -274.122928)
			(xy 296.881198 -274.169609) (xy 296.858327 -274.213186) (xy 296.828762 -274.25253) (xy 296.793269 -274.286622)
			(xy 296.752766 -274.314578) (xy 296.708304 -274.335676) (xy 296.661033 -274.349368) (xy 296.612178 -274.3553)
			(xy 296.563003 -274.353319) (xy 296.514784 -274.343475) (xy 296.468768 -274.326023) (xy 296.426147 -274.301416)
			(xy 296.388026 -274.270291) (xy 296.355391 -274.233454) (xy 296.329088 -274.191858) (xy 296.309797 -274.146582)
			(xy 296.29802 -274.098798) (xy 296.29406 -274.049744) (xy 295.976802 -274.049744) (xy 295.976298 -274.075452)
			(xy 295.968255 -274.126234) (xy 295.952367 -274.175133) (xy 295.929024 -274.220945) (xy 295.898803 -274.262541)
			(xy 295.862447 -274.298897) (xy 295.820851 -274.329118) (xy 295.775039 -274.352461) (xy 295.72614 -274.368349)
			(xy 295.675358 -274.376392) (xy 295.623942 -274.376392) (xy 295.57316 -274.368349) (xy 295.524261 -274.352461)
			(xy 295.478449 -274.329118) (xy 295.436853 -274.298897) (xy 295.400497 -274.262541) (xy 295.370276 -274.220945)
			(xy 295.346933 -274.175133) (xy 295.331045 -274.126234) (xy 295.323002 -274.075452) (xy 295.004324 -274.075452)
			(xy 294.996608 -274.122928) (xy 294.981024 -274.169609) (xy 294.958153 -274.213186) (xy 294.928588 -274.25253)
			(xy 294.893095 -274.286622) (xy 294.852592 -274.314578) (xy 294.80813 -274.335676) (xy 294.760859 -274.349368)
			(xy 294.712004 -274.3553) (xy 294.662829 -274.353319) (xy 294.61461 -274.343475) (xy 294.568594 -274.326023)
			(xy 294.525973 -274.301416) (xy 294.487852 -274.270291) (xy 294.455217 -274.233454) (xy 294.428914 -274.191858)
			(xy 294.409623 -274.146582) (xy 294.397846 -274.098798) (xy 294.393886 -274.049744) (xy 294.076628 -274.049744)
			(xy 294.076124 -274.075452) (xy 294.068081 -274.126234) (xy 294.052193 -274.175133) (xy 294.02885 -274.220945)
			(xy 293.998629 -274.262541) (xy 293.962273 -274.298897) (xy 293.920677 -274.329118) (xy 293.874865 -274.352461)
			(xy 293.825966 -274.368349) (xy 293.775184 -274.376392) (xy 293.723768 -274.376392) (xy 293.672986 -274.368349)
			(xy 293.624087 -274.352461) (xy 293.578275 -274.329118) (xy 293.536679 -274.298897) (xy 293.500323 -274.262541)
			(xy 293.470102 -274.220945) (xy 293.446759 -274.175133) (xy 293.430871 -274.126234) (xy 293.422828 -274.075452)
			(xy 293.104404 -274.075452) (xy 293.096688 -274.122928) (xy 293.081104 -274.169609) (xy 293.058233 -274.213186)
			(xy 293.028668 -274.25253) (xy 292.993175 -274.286622) (xy 292.952672 -274.314578) (xy 292.90821 -274.335676)
			(xy 292.860939 -274.349368) (xy 292.812084 -274.3553) (xy 292.762909 -274.353319) (xy 292.71469 -274.343475)
			(xy 292.668674 -274.326023) (xy 292.626053 -274.301416) (xy 292.587932 -274.270291) (xy 292.555297 -274.233454)
			(xy 292.528994 -274.191858) (xy 292.509703 -274.146582) (xy 292.497926 -274.098798) (xy 292.493966 -274.049744)
			(xy 292.176703 -274.049744) (xy 292.176204 -274.075198) (xy 292.168161 -274.12598) (xy 292.152273 -274.174879)
			(xy 292.12893 -274.220691) (xy 292.098709 -274.262287) (xy 292.062353 -274.298643) (xy 292.020757 -274.328864)
			(xy 291.974945 -274.352207) (xy 291.926046 -274.368095) (xy 291.875264 -274.376138) (xy 291.823848 -274.376138)
			(xy 291.773066 -274.368095) (xy 291.724167 -274.352207) (xy 291.678355 -274.328864) (xy 291.636759 -274.298643)
			(xy 291.600403 -274.262287) (xy 291.570182 -274.220691) (xy 291.546839 -274.174879) (xy 291.530951 -274.12598)
			(xy 291.522908 -274.075198) (xy 291.204525 -274.075198) (xy 291.196768 -274.122928) (xy 291.181184 -274.169609)
			(xy 291.158313 -274.213186) (xy 291.128748 -274.25253) (xy 291.093255 -274.286622) (xy 291.052752 -274.314578)
			(xy 291.00829 -274.335676) (xy 290.961019 -274.349368) (xy 290.912164 -274.3553) (xy 290.862989 -274.353319)
			(xy 290.81477 -274.343475) (xy 290.768754 -274.326023) (xy 290.726133 -274.301416) (xy 290.688012 -274.270291)
			(xy 290.655377 -274.233454) (xy 290.629074 -274.191858) (xy 290.609783 -274.146582) (xy 290.598006 -274.098798)
			(xy 290.594046 -274.049744) (xy 290.277042 -274.049744) (xy 290.276538 -274.075452) (xy 290.268495 -274.126234)
			(xy 290.252607 -274.175133) (xy 290.229264 -274.220945) (xy 290.199043 -274.262541) (xy 290.162687 -274.298897)
			(xy 290.121091 -274.329118) (xy 290.075279 -274.352461) (xy 290.02638 -274.368349) (xy 289.975598 -274.376392)
			(xy 289.924182 -274.376392) (xy 289.8734 -274.368349) (xy 289.824501 -274.352461) (xy 289.778689 -274.329118)
			(xy 289.737093 -274.298897) (xy 289.700737 -274.262541) (xy 289.670516 -274.220945) (xy 289.647173 -274.175133)
			(xy 289.631285 -274.126234) (xy 289.623242 -274.075452) (xy 289.304564 -274.075452) (xy 289.296848 -274.122928)
			(xy 289.281264 -274.169609) (xy 289.258393 -274.213186) (xy 289.228828 -274.25253) (xy 289.193335 -274.286622)
			(xy 289.152832 -274.314578) (xy 289.10837 -274.335676) (xy 289.061099 -274.349368) (xy 289.012244 -274.3553)
			(xy 288.963069 -274.353319) (xy 288.91485 -274.343475) (xy 288.868834 -274.326023) (xy 288.826213 -274.301416)
			(xy 288.788092 -274.270291) (xy 288.755457 -274.233454) (xy 288.729154 -274.191858) (xy 288.709863 -274.146582)
			(xy 288.698086 -274.098798) (xy 288.694126 -274.049744) (xy 288.376868 -274.049744) (xy 288.376364 -274.075452)
			(xy 288.368321 -274.126234) (xy 288.352433 -274.175133) (xy 288.32909 -274.220945) (xy 288.298869 -274.262541)
			(xy 288.262513 -274.298897) (xy 288.220917 -274.329118) (xy 288.175105 -274.352461) (xy 288.126206 -274.368349)
			(xy 288.075424 -274.376392) (xy 288.024008 -274.376392) (xy 287.973226 -274.368349) (xy 287.924327 -274.352461)
			(xy 287.878515 -274.329118) (xy 287.836919 -274.298897) (xy 287.800563 -274.262541) (xy 287.770342 -274.220945)
			(xy 287.746999 -274.175133) (xy 287.731111 -274.126234) (xy 287.723068 -274.075452) (xy 287.40439 -274.075452)
			(xy 287.396674 -274.122928) (xy 287.38109 -274.169609) (xy 287.358219 -274.213186) (xy 287.328654 -274.25253)
			(xy 287.293161 -274.286622) (xy 287.252658 -274.314578) (xy 287.208196 -274.335676) (xy 287.160925 -274.349368)
			(xy 287.11207 -274.3553) (xy 287.062895 -274.353319) (xy 287.014676 -274.343475) (xy 286.96866 -274.326023)
			(xy 286.926039 -274.301416) (xy 286.887918 -274.270291) (xy 286.855283 -274.233454) (xy 286.82898 -274.191858)
			(xy 286.809689 -274.146582) (xy 286.797912 -274.098798) (xy 286.793952 -274.049744) (xy 286.476948 -274.049744)
			(xy 286.476444 -274.075452) (xy 286.468401 -274.126234) (xy 286.452513 -274.175133) (xy 286.42917 -274.220945)
			(xy 286.398949 -274.262541) (xy 286.362593 -274.298897) (xy 286.320997 -274.329118) (xy 286.275185 -274.352461)
			(xy 286.226286 -274.368349) (xy 286.175504 -274.376392) (xy 286.124088 -274.376392) (xy 286.073306 -274.368349)
			(xy 286.024407 -274.352461) (xy 285.978595 -274.329118) (xy 285.936999 -274.298897) (xy 285.900643 -274.262541)
			(xy 285.870422 -274.220945) (xy 285.847079 -274.175133) (xy 285.831191 -274.126234) (xy 285.823148 -274.075452)
			(xy 285.50447 -274.075452) (xy 285.496754 -274.122928) (xy 285.48117 -274.169609) (xy 285.458299 -274.213186)
			(xy 285.428734 -274.25253) (xy 285.393241 -274.286622) (xy 285.352738 -274.314578) (xy 285.308276 -274.335676)
			(xy 285.261005 -274.349368) (xy 285.21215 -274.3553) (xy 285.162975 -274.353319) (xy 285.114756 -274.343475)
			(xy 285.06874 -274.326023) (xy 285.026119 -274.301416) (xy 284.987998 -274.270291) (xy 284.955363 -274.233454)
			(xy 284.92906 -274.191858) (xy 284.909769 -274.146582) (xy 284.897992 -274.098798) (xy 284.894032 -274.049744)
			(xy 284.577028 -274.049744) (xy 284.576524 -274.075452) (xy 284.568481 -274.126234) (xy 284.552593 -274.175133)
			(xy 284.52925 -274.220945) (xy 284.499029 -274.262541) (xy 284.462673 -274.298897) (xy 284.421077 -274.329118)
			(xy 284.375265 -274.352461) (xy 284.326366 -274.368349) (xy 284.275584 -274.376392) (xy 284.224168 -274.376392)
			(xy 284.173386 -274.368349) (xy 284.124487 -274.352461) (xy 284.078675 -274.329118) (xy 284.037079 -274.298897)
			(xy 284.000723 -274.262541) (xy 283.970502 -274.220945) (xy 283.947159 -274.175133) (xy 283.931271 -274.126234)
			(xy 283.923228 -274.075452) (xy 283.60455 -274.075452) (xy 283.596834 -274.122928) (xy 283.58125 -274.169609)
			(xy 283.558379 -274.213186) (xy 283.528814 -274.25253) (xy 283.493321 -274.286622) (xy 283.452818 -274.314578)
			(xy 283.408356 -274.335676) (xy 283.361085 -274.349368) (xy 283.31223 -274.3553) (xy 283.263055 -274.353319)
			(xy 283.214836 -274.343475) (xy 283.16882 -274.326023) (xy 283.126199 -274.301416) (xy 283.088078 -274.270291)
			(xy 283.055443 -274.233454) (xy 283.02914 -274.191858) (xy 283.009849 -274.146582) (xy 282.998072 -274.098798)
			(xy 282.994112 -274.049744) (xy 282.676304 -274.049744) (xy 282.676304 -274.075404) (xy 282.668262 -274.12618)
			(xy 282.652376 -274.175072) (xy 282.629037 -274.220877) (xy 282.59882 -274.262467) (xy 282.562469 -274.298819)
			(xy 282.520879 -274.329036) (xy 282.475074 -274.352375) (xy 282.426182 -274.368261) (xy 282.375406 -274.376303)
			(xy 282.349702 -274.376896) (xy 282.335978 -274.376705) (xy 282.308636 -274.374292) (xy 282.295092 -274.37207)
			(xy 282.283154 -274.370038) (xy 282.260294 -274.37715) (xy 282.18384 -274.45081) (xy 282.175966 -274.473416)
			(xy 282.17749 -274.485608) (xy 282.178687 -274.495406) (xy 282.179959 -274.515107) (xy 282.18003 -274.524978)
			(xy 282.179844 -274.539161) (xy 282.177173 -274.5674) (xy 282.174696 -274.581366) (xy 282.17241 -274.593812)
			(xy 282.179776 -274.617434) (xy 282.257246 -274.694904) (xy 282.280868 -274.70227) (xy 282.293314 -274.699984)
			(xy 282.307279 -274.697499) (xy 282.335519 -274.694828) (xy 282.349702 -274.69465) (xy 282.374961 -274.695172)
			(xy 282.424789 -274.703487) (xy 282.472569 -274.71989) (xy 282.516998 -274.743934) (xy 282.556863 -274.774963)
			(xy 282.591077 -274.81213) (xy 282.618708 -274.854421) (xy 282.639 -274.900684) (xy 282.651401 -274.949655)
			(xy 282.655573 -275) (xy 282.653446 -275.025666) (xy 282.973268 -275.025666) (xy 282.973268 -274.97425)
			(xy 282.981311 -274.923468) (xy 282.997199 -274.874569) (xy 283.020542 -274.828757) (xy 283.050763 -274.787161)
			(xy 283.087119 -274.750805) (xy 283.128715 -274.720584) (xy 283.174527 -274.697241) (xy 283.223426 -274.681353)
			(xy 283.274208 -274.67331) (xy 283.325624 -274.67331) (xy 283.376406 -274.681353) (xy 283.425305 -274.697241)
			(xy 283.471117 -274.720584) (xy 283.512713 -274.750805) (xy 283.549069 -274.787161) (xy 283.57929 -274.828757)
			(xy 283.602633 -274.874569) (xy 283.618521 -274.923468) (xy 283.626564 -274.97425) (xy 283.627068 -274.999958)
			(xy 283.944072 -274.999958) (xy 283.948032 -274.950904) (xy 283.959809 -274.90312) (xy 283.9791 -274.857844)
			(xy 284.005403 -274.816248) (xy 284.038038 -274.779411) (xy 284.076159 -274.748286) (xy 284.11878 -274.723679)
			(xy 284.164796 -274.706227) (xy 284.213015 -274.696383) (xy 284.26219 -274.694402) (xy 284.311045 -274.700334)
			(xy 284.358316 -274.714026) (xy 284.402778 -274.735124) (xy 284.443281 -274.76308) (xy 284.478774 -274.797172)
			(xy 284.508339 -274.836516) (xy 284.53121 -274.880093) (xy 284.546794 -274.926774) (xy 284.554689 -274.975351)
			(xy 284.555184 -274.999958) (xy 284.554689 -275.024565) (xy 284.55451 -275.025666) (xy 284.873188 -275.025666)
			(xy 284.873188 -274.97425) (xy 284.881231 -274.923468) (xy 284.897119 -274.874569) (xy 284.920462 -274.828757)
			(xy 284.950683 -274.787161) (xy 284.987039 -274.750805) (xy 285.028635 -274.720584) (xy 285.074447 -274.697241)
			(xy 285.123346 -274.681353) (xy 285.174128 -274.67331) (xy 285.225544 -274.67331) (xy 285.276326 -274.681353)
			(xy 285.325225 -274.697241) (xy 285.371037 -274.720584) (xy 285.412633 -274.750805) (xy 285.448989 -274.787161)
			(xy 285.47921 -274.828757) (xy 285.502553 -274.874569) (xy 285.518441 -274.923468) (xy 285.526484 -274.97425)
			(xy 285.526988 -274.999958) (xy 285.843992 -274.999958) (xy 285.847952 -274.950904) (xy 285.859729 -274.90312)
			(xy 285.87902 -274.857844) (xy 285.905323 -274.816248) (xy 285.937958 -274.779411) (xy 285.976079 -274.748286)
			(xy 286.0187 -274.723679) (xy 286.064716 -274.706227) (xy 286.112935 -274.696383) (xy 286.16211 -274.694402)
			(xy 286.210965 -274.700334) (xy 286.258236 -274.714026) (xy 286.302698 -274.735124) (xy 286.343201 -274.76308)
			(xy 286.378694 -274.797172) (xy 286.408259 -274.836516) (xy 286.43113 -274.880093) (xy 286.446714 -274.926774)
			(xy 286.454609 -274.975351) (xy 286.455104 -274.999958) (xy 286.454609 -275.024565) (xy 286.45443 -275.025666)
			(xy 286.773108 -275.025666) (xy 286.773108 -274.97425) (xy 286.781151 -274.923468) (xy 286.797039 -274.874569)
			(xy 286.820382 -274.828757) (xy 286.850603 -274.787161) (xy 286.886959 -274.750805) (xy 286.928555 -274.720584)
			(xy 286.974367 -274.697241) (xy 287.023266 -274.681353) (xy 287.074048 -274.67331) (xy 287.125464 -274.67331)
			(xy 287.176246 -274.681353) (xy 287.225145 -274.697241) (xy 287.270957 -274.720584) (xy 287.312553 -274.750805)
			(xy 287.348909 -274.787161) (xy 287.37913 -274.828757) (xy 287.402473 -274.874569) (xy 287.418361 -274.923468)
			(xy 287.426404 -274.97425) (xy 287.426908 -274.999958) (xy 287.743912 -274.999958) (xy 287.747872 -274.950904)
			(xy 287.759649 -274.90312) (xy 287.77894 -274.857844) (xy 287.805243 -274.816248) (xy 287.837878 -274.779411)
			(xy 287.875999 -274.748286) (xy 287.91862 -274.723679) (xy 287.964636 -274.706227) (xy 288.012855 -274.696383)
			(xy 288.06203 -274.694402) (xy 288.110885 -274.700334) (xy 288.158156 -274.714026) (xy 288.202618 -274.735124)
			(xy 288.243121 -274.76308) (xy 288.278614 -274.797172) (xy 288.308179 -274.836516) (xy 288.33105 -274.880093)
			(xy 288.346634 -274.926774) (xy 288.354529 -274.975351) (xy 288.355024 -274.999958) (xy 288.354529 -275.024565)
			(xy 288.35435 -275.025666) (xy 288.673282 -275.025666) (xy 288.673282 -274.97425) (xy 288.681325 -274.923468)
			(xy 288.697213 -274.874569) (xy 288.720556 -274.828757) (xy 288.750777 -274.787161) (xy 288.787133 -274.750805)
			(xy 288.828729 -274.720584) (xy 288.874541 -274.697241) (xy 288.92344 -274.681353) (xy 288.974222 -274.67331)
			(xy 289.025638 -274.67331) (xy 289.07642 -274.681353) (xy 289.125319 -274.697241) (xy 289.171131 -274.720584)
			(xy 289.212727 -274.750805) (xy 289.249083 -274.787161) (xy 289.279304 -274.828757) (xy 289.302647 -274.874569)
			(xy 289.318535 -274.923468) (xy 289.326578 -274.97425) (xy 289.327082 -274.999958) (xy 289.644086 -274.999958)
			(xy 289.648046 -274.950904) (xy 289.659823 -274.90312) (xy 289.679114 -274.857844) (xy 289.705417 -274.816248)
			(xy 289.738052 -274.779411) (xy 289.776173 -274.748286) (xy 289.818794 -274.723679) (xy 289.86481 -274.706227)
			(xy 289.913029 -274.696383) (xy 289.962204 -274.694402) (xy 290.011059 -274.700334) (xy 290.05833 -274.714026)
			(xy 290.102792 -274.735124) (xy 290.143295 -274.76308) (xy 290.178788 -274.797172) (xy 290.208353 -274.836516)
			(xy 290.231224 -274.880093) (xy 290.246808 -274.926774) (xy 290.254703 -274.975351) (xy 290.255198 -274.999958)
			(xy 290.254703 -275.024565) (xy 290.254524 -275.025666) (xy 290.573202 -275.025666) (xy 290.573202 -274.97425)
			(xy 290.581245 -274.923468) (xy 290.597133 -274.874569) (xy 290.620476 -274.828757) (xy 290.650697 -274.787161)
			(xy 290.687053 -274.750805) (xy 290.728649 -274.720584) (xy 290.774461 -274.697241) (xy 290.82336 -274.681353)
			(xy 290.874142 -274.67331) (xy 290.925558 -274.67331) (xy 290.97634 -274.681353) (xy 291.025239 -274.697241)
			(xy 291.071051 -274.720584) (xy 291.112647 -274.750805) (xy 291.149003 -274.787161) (xy 291.179224 -274.828757)
			(xy 291.202567 -274.874569) (xy 291.218455 -274.923468) (xy 291.226498 -274.97425) (xy 291.227002 -274.999958)
			(xy 291.544006 -274.999958) (xy 291.547966 -274.950904) (xy 291.559743 -274.90312) (xy 291.579034 -274.857844)
			(xy 291.605337 -274.816248) (xy 291.637972 -274.779411) (xy 291.676093 -274.748286) (xy 291.718714 -274.723679)
			(xy 291.76473 -274.706227) (xy 291.812949 -274.696383) (xy 291.862124 -274.694402) (xy 291.910979 -274.700334)
			(xy 291.95825 -274.714026) (xy 292.002712 -274.735124) (xy 292.043215 -274.76308) (xy 292.078708 -274.797172)
			(xy 292.108273 -274.836516) (xy 292.131144 -274.880093) (xy 292.146728 -274.926774) (xy 292.154623 -274.975351)
			(xy 292.155118 -274.999958) (xy 292.154623 -275.024565) (xy 292.154485 -275.025412) (xy 292.472868 -275.025412)
			(xy 292.472868 -274.973996) (xy 292.480911 -274.923214) (xy 292.496799 -274.874315) (xy 292.520142 -274.828503)
			(xy 292.550363 -274.786907) (xy 292.586719 -274.750551) (xy 292.628315 -274.72033) (xy 292.674127 -274.696987)
			(xy 292.723026 -274.681099) (xy 292.773808 -274.673056) (xy 292.825224 -274.673056) (xy 292.876006 -274.681099)
			(xy 292.924905 -274.696987) (xy 292.970717 -274.72033) (xy 293.012313 -274.750551) (xy 293.048669 -274.786907)
			(xy 293.07889 -274.828503) (xy 293.102233 -274.874315) (xy 293.118121 -274.923214) (xy 293.126164 -274.973996)
			(xy 293.126668 -274.999704) (xy 293.126663 -274.999958) (xy 293.443926 -274.999958) (xy 293.447886 -274.950904)
			(xy 293.459663 -274.90312) (xy 293.478954 -274.857844) (xy 293.505257 -274.816248) (xy 293.537892 -274.779411)
			(xy 293.576013 -274.748286) (xy 293.618634 -274.723679) (xy 293.66465 -274.706227) (xy 293.712869 -274.696383)
			(xy 293.762044 -274.694402) (xy 293.810899 -274.700334) (xy 293.85817 -274.714026) (xy 293.902632 -274.735124)
			(xy 293.943135 -274.76308) (xy 293.978628 -274.797172) (xy 294.008193 -274.836516) (xy 294.031064 -274.880093)
			(xy 294.046648 -274.926774) (xy 294.054543 -274.975351) (xy 294.055038 -274.999958) (xy 294.054543 -275.024565)
			(xy 294.054364 -275.025666) (xy 294.372788 -275.025666) (xy 294.372788 -274.97425) (xy 294.380831 -274.923468)
			(xy 294.396719 -274.874569) (xy 294.420062 -274.828757) (xy 294.450283 -274.787161) (xy 294.486639 -274.750805)
			(xy 294.528235 -274.720584) (xy 294.574047 -274.697241) (xy 294.622946 -274.681353) (xy 294.673728 -274.67331)
			(xy 294.725144 -274.67331) (xy 294.775926 -274.681353) (xy 294.824825 -274.697241) (xy 294.870637 -274.720584)
			(xy 294.912233 -274.750805) (xy 294.948589 -274.787161) (xy 294.97881 -274.828757) (xy 295.002153 -274.874569)
			(xy 295.018041 -274.923468) (xy 295.026084 -274.97425) (xy 295.026588 -274.999958) (xy 295.3441 -274.999958)
			(xy 295.34806 -274.950904) (xy 295.359837 -274.90312) (xy 295.379128 -274.857844) (xy 295.405431 -274.816248)
			(xy 295.438066 -274.779411) (xy 295.476187 -274.748286) (xy 295.518808 -274.723679) (xy 295.564824 -274.706227)
			(xy 295.613043 -274.696383) (xy 295.662218 -274.694402) (xy 295.711073 -274.700334) (xy 295.758344 -274.714026)
			(xy 295.802806 -274.735124) (xy 295.843309 -274.76308) (xy 295.878802 -274.797172) (xy 295.908367 -274.836516)
			(xy 295.931238 -274.880093) (xy 295.946822 -274.926774) (xy 295.954717 -274.975351) (xy 295.955212 -274.999958)
			(xy 295.954717 -275.024565) (xy 295.954579 -275.025412) (xy 296.272962 -275.025412) (xy 296.272962 -274.973996)
			(xy 296.281005 -274.923214) (xy 296.296893 -274.874315) (xy 296.320236 -274.828503) (xy 296.350457 -274.786907)
			(xy 296.386813 -274.750551) (xy 296.428409 -274.72033) (xy 296.474221 -274.696987) (xy 296.52312 -274.681099)
			(xy 296.573902 -274.673056) (xy 296.625318 -274.673056) (xy 296.6761 -274.681099) (xy 296.724999 -274.696987)
			(xy 296.770811 -274.72033) (xy 296.812407 -274.750551) (xy 296.848763 -274.786907) (xy 296.878984 -274.828503)
			(xy 296.902327 -274.874315) (xy 296.918215 -274.923214) (xy 296.926258 -274.973996) (xy 296.926762 -274.999704)
			(xy 296.926757 -274.999958) (xy 297.24402 -274.999958) (xy 297.24798 -274.950904) (xy 297.259757 -274.90312)
			(xy 297.279048 -274.857844) (xy 297.305351 -274.816248) (xy 297.337986 -274.779411) (xy 297.376107 -274.748286)
			(xy 297.418728 -274.723679) (xy 297.464744 -274.706227) (xy 297.512963 -274.696383) (xy 297.562138 -274.694402)
			(xy 297.610993 -274.700334) (xy 297.658264 -274.714026) (xy 297.702726 -274.735124) (xy 297.743229 -274.76308)
			(xy 297.778722 -274.797172) (xy 297.808287 -274.836516) (xy 297.831158 -274.880093) (xy 297.846742 -274.926774)
			(xy 297.854637 -274.975351) (xy 297.855132 -274.999958) (xy 297.854637 -275.024565) (xy 297.854458 -275.025666)
			(xy 298.172882 -275.025666) (xy 298.172882 -274.97425) (xy 298.180925 -274.923468) (xy 298.196813 -274.874569)
			(xy 298.220156 -274.828757) (xy 298.250377 -274.787161) (xy 298.286733 -274.750805) (xy 298.328329 -274.720584)
			(xy 298.374141 -274.697241) (xy 298.42304 -274.681353) (xy 298.473822 -274.67331) (xy 298.525238 -274.67331)
			(xy 298.57602 -274.681353) (xy 298.624919 -274.697241) (xy 298.670731 -274.720584) (xy 298.712327 -274.750805)
			(xy 298.748683 -274.787161) (xy 298.778904 -274.828757) (xy 298.802247 -274.874569) (xy 298.818135 -274.923468)
			(xy 298.826178 -274.97425) (xy 298.826682 -274.999958) (xy 299.14394 -274.999958) (xy 299.1479 -274.950904)
			(xy 299.159677 -274.90312) (xy 299.178968 -274.857844) (xy 299.205271 -274.816248) (xy 299.237906 -274.779411)
			(xy 299.276027 -274.748286) (xy 299.318648 -274.723679) (xy 299.364664 -274.706227) (xy 299.412883 -274.696383)
			(xy 299.462058 -274.694402) (xy 299.510913 -274.700334) (xy 299.558184 -274.714026) (xy 299.602646 -274.735124)
			(xy 299.643149 -274.76308) (xy 299.678642 -274.797172) (xy 299.708207 -274.836516) (xy 299.731078 -274.880093)
			(xy 299.746662 -274.926774) (xy 299.754557 -274.975351) (xy 299.755052 -274.999958) (xy 299.754557 -275.024565)
			(xy 299.754419 -275.025412) (xy 300.072802 -275.025412) (xy 300.072802 -274.973996) (xy 300.080845 -274.923214)
			(xy 300.096733 -274.874315) (xy 300.120076 -274.828503) (xy 300.150297 -274.786907) (xy 300.186653 -274.750551)
			(xy 300.228249 -274.72033) (xy 300.274061 -274.696987) (xy 300.32296 -274.681099) (xy 300.373742 -274.673056)
			(xy 300.425158 -274.673056) (xy 300.47594 -274.681099) (xy 300.524839 -274.696987) (xy 300.570651 -274.72033)
			(xy 300.612247 -274.750551) (xy 300.648603 -274.786907) (xy 300.678824 -274.828503) (xy 300.702167 -274.874315)
			(xy 300.718055 -274.923214) (xy 300.726098 -274.973996) (xy 300.726602 -274.999704) (xy 300.726597 -274.999958)
			(xy 301.044114 -274.999958) (xy 301.048074 -274.950904) (xy 301.059851 -274.90312) (xy 301.079142 -274.857844)
			(xy 301.105445 -274.816248) (xy 301.13808 -274.779411) (xy 301.176201 -274.748286) (xy 301.218822 -274.723679)
			(xy 301.264838 -274.706227) (xy 301.313057 -274.696383) (xy 301.362232 -274.694402) (xy 301.411087 -274.700334)
			(xy 301.458358 -274.714026) (xy 301.50282 -274.735124) (xy 301.543323 -274.76308) (xy 301.578816 -274.797172)
			(xy 301.608381 -274.836516) (xy 301.631252 -274.880093) (xy 301.646836 -274.926774) (xy 301.654731 -274.975351)
			(xy 301.655226 -274.999958) (xy 301.654731 -275.024565) (xy 301.654552 -275.025666) (xy 301.972722 -275.025666)
			(xy 301.972722 -274.97425) (xy 301.980765 -274.923468) (xy 301.996653 -274.874569) (xy 302.019996 -274.828757)
			(xy 302.050217 -274.787161) (xy 302.086573 -274.750805) (xy 302.128169 -274.720584) (xy 302.173981 -274.697241)
			(xy 302.22288 -274.681353) (xy 302.273662 -274.67331) (xy 302.325078 -274.67331) (xy 302.37586 -274.681353)
			(xy 302.424759 -274.697241) (xy 302.470571 -274.720584) (xy 302.512167 -274.750805) (xy 302.548523 -274.787161)
			(xy 302.578744 -274.828757) (xy 302.602087 -274.874569) (xy 302.617975 -274.923468) (xy 302.626018 -274.97425)
			(xy 302.626522 -274.999958) (xy 302.944034 -274.999958) (xy 302.947994 -274.950904) (xy 302.959771 -274.90312)
			(xy 302.979062 -274.857844) (xy 303.005365 -274.816248) (xy 303.038 -274.779411) (xy 303.076121 -274.748286)
			(xy 303.118742 -274.723679) (xy 303.164758 -274.706227) (xy 303.212977 -274.696383) (xy 303.262152 -274.694402)
			(xy 303.311007 -274.700334) (xy 303.358278 -274.714026) (xy 303.40274 -274.735124) (xy 303.443243 -274.76308)
			(xy 303.478736 -274.797172) (xy 303.508301 -274.836516) (xy 303.531172 -274.880093) (xy 303.546756 -274.926774)
			(xy 303.554651 -274.975351) (xy 303.555146 -274.999958) (xy 303.554651 -275.024565) (xy 303.554513 -275.025412)
			(xy 303.872896 -275.025412) (xy 303.872896 -274.973996) (xy 303.880939 -274.923214) (xy 303.896827 -274.874315)
			(xy 303.92017 -274.828503) (xy 303.950391 -274.786907) (xy 303.986747 -274.750551) (xy 304.028343 -274.72033)
			(xy 304.074155 -274.696987) (xy 304.123054 -274.681099) (xy 304.173836 -274.673056) (xy 304.225252 -274.673056)
			(xy 304.276034 -274.681099) (xy 304.324933 -274.696987) (xy 304.370745 -274.72033) (xy 304.412341 -274.750551)
			(xy 304.448697 -274.786907) (xy 304.478918 -274.828503) (xy 304.502261 -274.874315) (xy 304.518149 -274.923214)
			(xy 304.526192 -274.973996) (xy 304.526696 -274.999704) (xy 304.526691 -274.999958) (xy 304.843954 -274.999958)
			(xy 304.847914 -274.950904) (xy 304.859691 -274.90312) (xy 304.878982 -274.857844) (xy 304.905285 -274.816248)
			(xy 304.93792 -274.779411) (xy 304.976041 -274.748286) (xy 305.018662 -274.723679) (xy 305.064678 -274.706227)
			(xy 305.112897 -274.696383) (xy 305.162072 -274.694402) (xy 305.210927 -274.700334) (xy 305.258198 -274.714026)
			(xy 305.30266 -274.735124) (xy 305.343163 -274.76308) (xy 305.378656 -274.797172) (xy 305.408221 -274.836516)
			(xy 305.431092 -274.880093) (xy 305.446676 -274.926774) (xy 305.454571 -274.975351) (xy 305.455066 -274.999958)
			(xy 305.454571 -275.024565) (xy 305.454392 -275.025666) (xy 305.772816 -275.025666) (xy 305.772816 -274.97425)
			(xy 305.780859 -274.923468) (xy 305.796747 -274.874569) (xy 305.82009 -274.828757) (xy 305.850311 -274.787161)
			(xy 305.886667 -274.750805) (xy 305.928263 -274.720584) (xy 305.974075 -274.697241) (xy 306.022974 -274.681353)
			(xy 306.073756 -274.67331) (xy 306.125172 -274.67331) (xy 306.175954 -274.681353) (xy 306.224853 -274.697241)
			(xy 306.270665 -274.720584) (xy 306.312261 -274.750805) (xy 306.348617 -274.787161) (xy 306.378838 -274.828757)
			(xy 306.402181 -274.874569) (xy 306.418069 -274.923468) (xy 306.426112 -274.97425) (xy 306.426616 -274.999958)
			(xy 306.743874 -274.999958) (xy 306.747834 -274.950904) (xy 306.759611 -274.90312) (xy 306.778902 -274.857844)
			(xy 306.805205 -274.816248) (xy 306.83784 -274.779411) (xy 306.875961 -274.748286) (xy 306.918582 -274.723679)
			(xy 306.964598 -274.706227) (xy 307.012817 -274.696383) (xy 307.061992 -274.694402) (xy 307.110847 -274.700334)
			(xy 307.158118 -274.714026) (xy 307.20258 -274.735124) (xy 307.243083 -274.76308) (xy 307.278576 -274.797172)
			(xy 307.308141 -274.836516) (xy 307.331012 -274.880093) (xy 307.346596 -274.926774) (xy 307.354491 -274.975351)
			(xy 307.354986 -274.999958) (xy 307.354491 -275.024565) (xy 307.354353 -275.025412) (xy 307.67299 -275.025412)
			(xy 307.67299 -274.973996) (xy 307.681033 -274.923214) (xy 307.696921 -274.874315) (xy 307.720264 -274.828503)
			(xy 307.750485 -274.786907) (xy 307.786841 -274.750551) (xy 307.828437 -274.72033) (xy 307.874249 -274.696987)
			(xy 307.923148 -274.681099) (xy 307.97393 -274.673056) (xy 308.025346 -274.673056) (xy 308.076128 -274.681099)
			(xy 308.125027 -274.696987) (xy 308.170839 -274.72033) (xy 308.212435 -274.750551) (xy 308.248791 -274.786907)
			(xy 308.279012 -274.828503) (xy 308.302355 -274.874315) (xy 308.318243 -274.923214) (xy 308.326286 -274.973996)
			(xy 308.32679 -274.999704) (xy 308.326785 -274.999958) (xy 308.643794 -274.999958) (xy 308.647754 -274.950904)
			(xy 308.659531 -274.90312) (xy 308.678822 -274.857844) (xy 308.705125 -274.816248) (xy 308.73776 -274.779411)
			(xy 308.775881 -274.748286) (xy 308.818502 -274.723679) (xy 308.864518 -274.706227) (xy 308.912737 -274.696383)
			(xy 308.961912 -274.694402) (xy 309.010767 -274.700334) (xy 309.058038 -274.714026) (xy 309.1025 -274.735124)
			(xy 309.143003 -274.76308) (xy 309.178496 -274.797172) (xy 309.208061 -274.836516) (xy 309.230932 -274.880093)
			(xy 309.246516 -274.926774) (xy 309.254411 -274.975351) (xy 309.254906 -274.999958) (xy 309.254411 -275.024565)
			(xy 309.254232 -275.025666) (xy 309.57291 -275.025666) (xy 309.57291 -274.97425) (xy 309.580953 -274.923468)
			(xy 309.596841 -274.874569) (xy 309.620184 -274.828757) (xy 309.650405 -274.787161) (xy 309.686761 -274.750805)
			(xy 309.728357 -274.720584) (xy 309.774169 -274.697241) (xy 309.823068 -274.681353) (xy 309.87385 -274.67331)
			(xy 309.925266 -274.67331) (xy 309.976048 -274.681353) (xy 310.024947 -274.697241) (xy 310.070759 -274.720584)
			(xy 310.112355 -274.750805) (xy 310.148711 -274.787161) (xy 310.178932 -274.828757) (xy 310.202275 -274.874569)
			(xy 310.218163 -274.923468) (xy 310.226206 -274.97425) (xy 310.22671 -274.999958) (xy 310.543714 -274.999958)
			(xy 310.547674 -274.950904) (xy 310.559451 -274.90312) (xy 310.578742 -274.857844) (xy 310.605045 -274.816248)
			(xy 310.63768 -274.779411) (xy 310.675801 -274.748286) (xy 310.718422 -274.723679) (xy 310.764438 -274.706227)
			(xy 310.812657 -274.696383) (xy 310.861832 -274.694402) (xy 310.910687 -274.700334) (xy 310.957958 -274.714026)
			(xy 311.00242 -274.735124) (xy 311.042923 -274.76308) (xy 311.078416 -274.797172) (xy 311.107981 -274.836516)
			(xy 311.130852 -274.880093) (xy 311.146436 -274.926774) (xy 311.154331 -274.975351) (xy 311.154826 -274.999958)
			(xy 311.154331 -275.024565) (xy 311.154152 -275.025666) (xy 311.47283 -275.025666) (xy 311.47283 -274.97425)
			(xy 311.480873 -274.923468) (xy 311.496761 -274.874569) (xy 311.520104 -274.828757) (xy 311.550325 -274.787161)
			(xy 311.586681 -274.750805) (xy 311.628277 -274.720584) (xy 311.674089 -274.697241) (xy 311.722988 -274.681353)
			(xy 311.77377 -274.67331) (xy 311.825186 -274.67331) (xy 311.875968 -274.681353) (xy 311.924867 -274.697241)
			(xy 311.970679 -274.720584) (xy 312.012275 -274.750805) (xy 312.048631 -274.787161) (xy 312.078852 -274.828757)
			(xy 312.102195 -274.874569) (xy 312.118083 -274.923468) (xy 312.126126 -274.97425) (xy 312.12663 -274.999958)
			(xy 312.443888 -274.999958) (xy 312.447848 -274.950904) (xy 312.459625 -274.90312) (xy 312.478916 -274.857844)
			(xy 312.505219 -274.816248) (xy 312.537854 -274.779411) (xy 312.575975 -274.748286) (xy 312.618596 -274.723679)
			(xy 312.664612 -274.706227) (xy 312.712831 -274.696383) (xy 312.762006 -274.694402) (xy 312.810861 -274.700334)
			(xy 312.858132 -274.714026) (xy 312.902594 -274.735124) (xy 312.943097 -274.76308) (xy 312.97859 -274.797172)
			(xy 313.008155 -274.836516) (xy 313.031026 -274.880093) (xy 313.04661 -274.926774) (xy 313.054505 -274.975351)
			(xy 313.055 -274.999958) (xy 313.054505 -275.024565) (xy 313.054367 -275.025412) (xy 313.373258 -275.025412)
			(xy 313.373258 -274.973996) (xy 313.381301 -274.923214) (xy 313.397189 -274.874315) (xy 313.420532 -274.828503)
			(xy 313.450753 -274.786907) (xy 313.487109 -274.750551) (xy 313.528705 -274.72033) (xy 313.574517 -274.696987)
			(xy 313.623416 -274.681099) (xy 313.674198 -274.673056) (xy 313.725614 -274.673056) (xy 313.776396 -274.681099)
			(xy 313.825295 -274.696987) (xy 313.871107 -274.72033) (xy 313.912703 -274.750551) (xy 313.949059 -274.786907)
			(xy 313.97928 -274.828503) (xy 314.002623 -274.874315) (xy 314.018511 -274.923214) (xy 314.026554 -274.973996)
			(xy 314.027058 -274.999704) (xy 314.026554 -275.025412) (xy 314.323218 -275.025412) (xy 314.323218 -274.973996)
			(xy 314.331261 -274.923214) (xy 314.347149 -274.874315) (xy 314.370492 -274.828503) (xy 314.400713 -274.786907)
			(xy 314.437069 -274.750551) (xy 314.478665 -274.72033) (xy 314.524477 -274.696987) (xy 314.573376 -274.681099)
			(xy 314.624158 -274.673056) (xy 314.675574 -274.673056) (xy 314.726356 -274.681099) (xy 314.775255 -274.696987)
			(xy 314.821067 -274.72033) (xy 314.862663 -274.750551) (xy 314.899019 -274.786907) (xy 314.92924 -274.828503)
			(xy 314.952583 -274.874315) (xy 314.968471 -274.923214) (xy 314.976514 -274.973996) (xy 314.977018 -274.999704)
			(xy 314.977013 -274.999958) (xy 315.294276 -274.999958) (xy 315.298236 -274.950904) (xy 315.310013 -274.90312)
			(xy 315.329304 -274.857844) (xy 315.355607 -274.816248) (xy 315.388242 -274.779411) (xy 315.426363 -274.748286)
			(xy 315.468984 -274.723679) (xy 315.515 -274.706227) (xy 315.563219 -274.696383) (xy 315.612394 -274.694402)
			(xy 315.661249 -274.700334) (xy 315.70852 -274.714026) (xy 315.752982 -274.735124) (xy 315.793485 -274.76308)
			(xy 315.828978 -274.797172) (xy 315.858543 -274.836516) (xy 315.881414 -274.880093) (xy 315.896998 -274.926774)
			(xy 315.904893 -274.975351) (xy 315.905388 -274.999958) (xy 315.904893 -275.024565) (xy 315.896998 -275.073142)
			(xy 315.881414 -275.119823) (xy 315.858543 -275.1634) (xy 315.828978 -275.202744) (xy 315.793485 -275.236836)
			(xy 315.752982 -275.264792) (xy 315.70852 -275.28589) (xy 315.661249 -275.299582) (xy 315.612394 -275.305514)
			(xy 315.563219 -275.303533) (xy 315.515 -275.293689) (xy 315.468984 -275.276237) (xy 315.426363 -275.25163)
			(xy 315.388242 -275.220505) (xy 315.355607 -275.183668) (xy 315.329304 -275.142072) (xy 315.310013 -275.096796)
			(xy 315.298236 -275.049012) (xy 315.294276 -274.999958) (xy 314.977013 -274.999958) (xy 314.976514 -275.025412)
			(xy 314.968471 -275.076194) (xy 314.952583 -275.125093) (xy 314.92924 -275.170905) (xy 314.899019 -275.212501)
			(xy 314.862663 -275.248857) (xy 314.821067 -275.279078) (xy 314.775255 -275.302421) (xy 314.726356 -275.318309)
			(xy 314.675574 -275.326352) (xy 314.624158 -275.326352) (xy 314.573376 -275.318309) (xy 314.524477 -275.302421)
			(xy 314.478665 -275.279078) (xy 314.437069 -275.248857) (xy 314.400713 -275.212501) (xy 314.370492 -275.170905)
			(xy 314.347149 -275.125093) (xy 314.331261 -275.076194) (xy 314.323218 -275.025412) (xy 314.026554 -275.025412)
			(xy 314.018511 -275.076194) (xy 314.002623 -275.125093) (xy 313.97928 -275.170905) (xy 313.949059 -275.212501)
			(xy 313.912703 -275.248857) (xy 313.871107 -275.279078) (xy 313.825295 -275.302421) (xy 313.776396 -275.318309)
			(xy 313.725614 -275.326352) (xy 313.674198 -275.326352) (xy 313.623416 -275.318309) (xy 313.574517 -275.302421)
			(xy 313.528705 -275.279078) (xy 313.487109 -275.248857) (xy 313.450753 -275.212501) (xy 313.420532 -275.170905)
			(xy 313.397189 -275.125093) (xy 313.381301 -275.076194) (xy 313.373258 -275.025412) (xy 313.054367 -275.025412)
			(xy 313.04661 -275.073142) (xy 313.031026 -275.119823) (xy 313.008155 -275.1634) (xy 312.97859 -275.202744)
			(xy 312.943097 -275.236836) (xy 312.902594 -275.264792) (xy 312.858132 -275.28589) (xy 312.810861 -275.299582)
			(xy 312.762006 -275.305514) (xy 312.712831 -275.303533) (xy 312.664612 -275.293689) (xy 312.618596 -275.276237)
			(xy 312.575975 -275.25163) (xy 312.537854 -275.220505) (xy 312.505219 -275.183668) (xy 312.478916 -275.142072)
			(xy 312.459625 -275.096796) (xy 312.447848 -275.049012) (xy 312.443888 -274.999958) (xy 312.12663 -274.999958)
			(xy 312.126126 -275.025666) (xy 312.118083 -275.076448) (xy 312.102195 -275.125347) (xy 312.078852 -275.171159)
			(xy 312.048631 -275.212755) (xy 312.012275 -275.249111) (xy 311.970679 -275.279332) (xy 311.924867 -275.302675)
			(xy 311.875968 -275.318563) (xy 311.825186 -275.326606) (xy 311.77377 -275.326606) (xy 311.722988 -275.318563)
			(xy 311.674089 -275.302675) (xy 311.628277 -275.279332) (xy 311.586681 -275.249111) (xy 311.550325 -275.212755)
			(xy 311.520104 -275.171159) (xy 311.496761 -275.125347) (xy 311.480873 -275.076448) (xy 311.47283 -275.025666)
			(xy 311.154152 -275.025666) (xy 311.146436 -275.073142) (xy 311.130852 -275.119823) (xy 311.107981 -275.1634)
			(xy 311.078416 -275.202744) (xy 311.042923 -275.236836) (xy 311.00242 -275.264792) (xy 310.957958 -275.28589)
			(xy 310.910687 -275.299582) (xy 310.861832 -275.305514) (xy 310.812657 -275.303533) (xy 310.764438 -275.293689)
			(xy 310.718422 -275.276237) (xy 310.675801 -275.25163) (xy 310.63768 -275.220505) (xy 310.605045 -275.183668)
			(xy 310.578742 -275.142072) (xy 310.559451 -275.096796) (xy 310.547674 -275.049012) (xy 310.543714 -274.999958)
			(xy 310.22671 -274.999958) (xy 310.226206 -275.025666) (xy 310.218163 -275.076448) (xy 310.202275 -275.125347)
			(xy 310.178932 -275.171159) (xy 310.148711 -275.212755) (xy 310.112355 -275.249111) (xy 310.070759 -275.279332)
			(xy 310.024947 -275.302675) (xy 309.976048 -275.318563) (xy 309.925266 -275.326606) (xy 309.87385 -275.326606)
			(xy 309.823068 -275.318563) (xy 309.774169 -275.302675) (xy 309.728357 -275.279332) (xy 309.686761 -275.249111)
			(xy 309.650405 -275.212755) (xy 309.620184 -275.171159) (xy 309.596841 -275.125347) (xy 309.580953 -275.076448)
			(xy 309.57291 -275.025666) (xy 309.254232 -275.025666) (xy 309.246516 -275.073142) (xy 309.230932 -275.119823)
			(xy 309.208061 -275.1634) (xy 309.178496 -275.202744) (xy 309.143003 -275.236836) (xy 309.1025 -275.264792)
			(xy 309.058038 -275.28589) (xy 309.010767 -275.299582) (xy 308.961912 -275.305514) (xy 308.912737 -275.303533)
			(xy 308.864518 -275.293689) (xy 308.818502 -275.276237) (xy 308.775881 -275.25163) (xy 308.73776 -275.220505)
			(xy 308.705125 -275.183668) (xy 308.678822 -275.142072) (xy 308.659531 -275.096796) (xy 308.647754 -275.049012)
			(xy 308.643794 -274.999958) (xy 308.326785 -274.999958) (xy 308.326286 -275.025412) (xy 308.318243 -275.076194)
			(xy 308.302355 -275.125093) (xy 308.279012 -275.170905) (xy 308.248791 -275.212501) (xy 308.212435 -275.248857)
			(xy 308.170839 -275.279078) (xy 308.125027 -275.302421) (xy 308.076128 -275.318309) (xy 308.025346 -275.326352)
			(xy 307.97393 -275.326352) (xy 307.923148 -275.318309) (xy 307.874249 -275.302421) (xy 307.828437 -275.279078)
			(xy 307.786841 -275.248857) (xy 307.750485 -275.212501) (xy 307.720264 -275.170905) (xy 307.696921 -275.125093)
			(xy 307.681033 -275.076194) (xy 307.67299 -275.025412) (xy 307.354353 -275.025412) (xy 307.346596 -275.073142)
			(xy 307.331012 -275.119823) (xy 307.308141 -275.1634) (xy 307.278576 -275.202744) (xy 307.243083 -275.236836)
			(xy 307.20258 -275.264792) (xy 307.158118 -275.28589) (xy 307.110847 -275.299582) (xy 307.061992 -275.305514)
			(xy 307.012817 -275.303533) (xy 306.964598 -275.293689) (xy 306.918582 -275.276237) (xy 306.875961 -275.25163)
			(xy 306.83784 -275.220505) (xy 306.805205 -275.183668) (xy 306.778902 -275.142072) (xy 306.759611 -275.096796)
			(xy 306.747834 -275.049012) (xy 306.743874 -274.999958) (xy 306.426616 -274.999958) (xy 306.426112 -275.025666)
			(xy 306.418069 -275.076448) (xy 306.402181 -275.125347) (xy 306.378838 -275.171159) (xy 306.348617 -275.212755)
			(xy 306.312261 -275.249111) (xy 306.270665 -275.279332) (xy 306.224853 -275.302675) (xy 306.175954 -275.318563)
			(xy 306.125172 -275.326606) (xy 306.073756 -275.326606) (xy 306.022974 -275.318563) (xy 305.974075 -275.302675)
			(xy 305.928263 -275.279332) (xy 305.886667 -275.249111) (xy 305.850311 -275.212755) (xy 305.82009 -275.171159)
			(xy 305.796747 -275.125347) (xy 305.780859 -275.076448) (xy 305.772816 -275.025666) (xy 305.454392 -275.025666)
			(xy 305.446676 -275.073142) (xy 305.431092 -275.119823) (xy 305.408221 -275.1634) (xy 305.378656 -275.202744)
			(xy 305.343163 -275.236836) (xy 305.30266 -275.264792) (xy 305.258198 -275.28589) (xy 305.210927 -275.299582)
			(xy 305.162072 -275.305514) (xy 305.112897 -275.303533) (xy 305.064678 -275.293689) (xy 305.018662 -275.276237)
			(xy 304.976041 -275.25163) (xy 304.93792 -275.220505) (xy 304.905285 -275.183668) (xy 304.878982 -275.142072)
			(xy 304.859691 -275.096796) (xy 304.847914 -275.049012) (xy 304.843954 -274.999958) (xy 304.526691 -274.999958)
			(xy 304.526192 -275.025412) (xy 304.518149 -275.076194) (xy 304.502261 -275.125093) (xy 304.478918 -275.170905)
			(xy 304.448697 -275.212501) (xy 304.412341 -275.248857) (xy 304.370745 -275.279078) (xy 304.324933 -275.302421)
			(xy 304.276034 -275.318309) (xy 304.225252 -275.326352) (xy 304.173836 -275.326352) (xy 304.123054 -275.318309)
			(xy 304.074155 -275.302421) (xy 304.028343 -275.279078) (xy 303.986747 -275.248857) (xy 303.950391 -275.212501)
			(xy 303.92017 -275.170905) (xy 303.896827 -275.125093) (xy 303.880939 -275.076194) (xy 303.872896 -275.025412)
			(xy 303.554513 -275.025412) (xy 303.546756 -275.073142) (xy 303.531172 -275.119823) (xy 303.508301 -275.1634)
			(xy 303.478736 -275.202744) (xy 303.443243 -275.236836) (xy 303.40274 -275.264792) (xy 303.358278 -275.28589)
			(xy 303.311007 -275.299582) (xy 303.262152 -275.305514) (xy 303.212977 -275.303533) (xy 303.164758 -275.293689)
			(xy 303.118742 -275.276237) (xy 303.076121 -275.25163) (xy 303.038 -275.220505) (xy 303.005365 -275.183668)
			(xy 302.979062 -275.142072) (xy 302.959771 -275.096796) (xy 302.947994 -275.049012) (xy 302.944034 -274.999958)
			(xy 302.626522 -274.999958) (xy 302.626018 -275.025666) (xy 302.617975 -275.076448) (xy 302.602087 -275.125347)
			(xy 302.578744 -275.171159) (xy 302.548523 -275.212755) (xy 302.512167 -275.249111) (xy 302.470571 -275.279332)
			(xy 302.424759 -275.302675) (xy 302.37586 -275.318563) (xy 302.325078 -275.326606) (xy 302.273662 -275.326606)
			(xy 302.22288 -275.318563) (xy 302.173981 -275.302675) (xy 302.128169 -275.279332) (xy 302.086573 -275.249111)
			(xy 302.050217 -275.212755) (xy 302.019996 -275.171159) (xy 301.996653 -275.125347) (xy 301.980765 -275.076448)
			(xy 301.972722 -275.025666) (xy 301.654552 -275.025666) (xy 301.646836 -275.073142) (xy 301.631252 -275.119823)
			(xy 301.608381 -275.1634) (xy 301.578816 -275.202744) (xy 301.543323 -275.236836) (xy 301.50282 -275.264792)
			(xy 301.458358 -275.28589) (xy 301.411087 -275.299582) (xy 301.362232 -275.305514) (xy 301.313057 -275.303533)
			(xy 301.264838 -275.293689) (xy 301.218822 -275.276237) (xy 301.176201 -275.25163) (xy 301.13808 -275.220505)
			(xy 301.105445 -275.183668) (xy 301.079142 -275.142072) (xy 301.059851 -275.096796) (xy 301.048074 -275.049012)
			(xy 301.044114 -274.999958) (xy 300.726597 -274.999958) (xy 300.726098 -275.025412) (xy 300.718055 -275.076194)
			(xy 300.702167 -275.125093) (xy 300.678824 -275.170905) (xy 300.648603 -275.212501) (xy 300.612247 -275.248857)
			(xy 300.570651 -275.279078) (xy 300.524839 -275.302421) (xy 300.47594 -275.318309) (xy 300.425158 -275.326352)
			(xy 300.373742 -275.326352) (xy 300.32296 -275.318309) (xy 300.274061 -275.302421) (xy 300.228249 -275.279078)
			(xy 300.186653 -275.248857) (xy 300.150297 -275.212501) (xy 300.120076 -275.170905) (xy 300.096733 -275.125093)
			(xy 300.080845 -275.076194) (xy 300.072802 -275.025412) (xy 299.754419 -275.025412) (xy 299.746662 -275.073142)
			(xy 299.731078 -275.119823) (xy 299.708207 -275.1634) (xy 299.678642 -275.202744) (xy 299.643149 -275.236836)
			(xy 299.602646 -275.264792) (xy 299.558184 -275.28589) (xy 299.510913 -275.299582) (xy 299.462058 -275.305514)
			(xy 299.412883 -275.303533) (xy 299.364664 -275.293689) (xy 299.318648 -275.276237) (xy 299.276027 -275.25163)
			(xy 299.237906 -275.220505) (xy 299.205271 -275.183668) (xy 299.178968 -275.142072) (xy 299.159677 -275.096796)
			(xy 299.1479 -275.049012) (xy 299.14394 -274.999958) (xy 298.826682 -274.999958) (xy 298.826178 -275.025666)
			(xy 298.818135 -275.076448) (xy 298.802247 -275.125347) (xy 298.778904 -275.171159) (xy 298.748683 -275.212755)
			(xy 298.712327 -275.249111) (xy 298.670731 -275.279332) (xy 298.624919 -275.302675) (xy 298.57602 -275.318563)
			(xy 298.525238 -275.326606) (xy 298.473822 -275.326606) (xy 298.42304 -275.318563) (xy 298.374141 -275.302675)
			(xy 298.328329 -275.279332) (xy 298.286733 -275.249111) (xy 298.250377 -275.212755) (xy 298.220156 -275.171159)
			(xy 298.196813 -275.125347) (xy 298.180925 -275.076448) (xy 298.172882 -275.025666) (xy 297.854458 -275.025666)
			(xy 297.846742 -275.073142) (xy 297.831158 -275.119823) (xy 297.808287 -275.1634) (xy 297.778722 -275.202744)
			(xy 297.743229 -275.236836) (xy 297.702726 -275.264792) (xy 297.658264 -275.28589) (xy 297.610993 -275.299582)
			(xy 297.562138 -275.305514) (xy 297.512963 -275.303533) (xy 297.464744 -275.293689) (xy 297.418728 -275.276237)
			(xy 297.376107 -275.25163) (xy 297.337986 -275.220505) (xy 297.305351 -275.183668) (xy 297.279048 -275.142072)
			(xy 297.259757 -275.096796) (xy 297.24798 -275.049012) (xy 297.24402 -274.999958) (xy 296.926757 -274.999958)
			(xy 296.926258 -275.025412) (xy 296.918215 -275.076194) (xy 296.902327 -275.125093) (xy 296.878984 -275.170905)
			(xy 296.848763 -275.212501) (xy 296.812407 -275.248857) (xy 296.770811 -275.279078) (xy 296.724999 -275.302421)
			(xy 296.6761 -275.318309) (xy 296.625318 -275.326352) (xy 296.573902 -275.326352) (xy 296.52312 -275.318309)
			(xy 296.474221 -275.302421) (xy 296.428409 -275.279078) (xy 296.386813 -275.248857) (xy 296.350457 -275.212501)
			(xy 296.320236 -275.170905) (xy 296.296893 -275.125093) (xy 296.281005 -275.076194) (xy 296.272962 -275.025412)
			(xy 295.954579 -275.025412) (xy 295.946822 -275.073142) (xy 295.931238 -275.119823) (xy 295.908367 -275.1634)
			(xy 295.878802 -275.202744) (xy 295.843309 -275.236836) (xy 295.802806 -275.264792) (xy 295.758344 -275.28589)
			(xy 295.711073 -275.299582) (xy 295.662218 -275.305514) (xy 295.613043 -275.303533) (xy 295.564824 -275.293689)
			(xy 295.518808 -275.276237) (xy 295.476187 -275.25163) (xy 295.438066 -275.220505) (xy 295.405431 -275.183668)
			(xy 295.379128 -275.142072) (xy 295.359837 -275.096796) (xy 295.34806 -275.049012) (xy 295.3441 -274.999958)
			(xy 295.026588 -274.999958) (xy 295.026084 -275.025666) (xy 295.018041 -275.076448) (xy 295.002153 -275.125347)
			(xy 294.97881 -275.171159) (xy 294.948589 -275.212755) (xy 294.912233 -275.249111) (xy 294.870637 -275.279332)
			(xy 294.824825 -275.302675) (xy 294.775926 -275.318563) (xy 294.725144 -275.326606) (xy 294.673728 -275.326606)
			(xy 294.622946 -275.318563) (xy 294.574047 -275.302675) (xy 294.528235 -275.279332) (xy 294.486639 -275.249111)
			(xy 294.450283 -275.212755) (xy 294.420062 -275.171159) (xy 294.396719 -275.125347) (xy 294.380831 -275.076448)
			(xy 294.372788 -275.025666) (xy 294.054364 -275.025666) (xy 294.046648 -275.073142) (xy 294.031064 -275.119823)
			(xy 294.008193 -275.1634) (xy 293.978628 -275.202744) (xy 293.943135 -275.236836) (xy 293.902632 -275.264792)
			(xy 293.85817 -275.28589) (xy 293.810899 -275.299582) (xy 293.762044 -275.305514) (xy 293.712869 -275.303533)
			(xy 293.66465 -275.293689) (xy 293.618634 -275.276237) (xy 293.576013 -275.25163) (xy 293.537892 -275.220505)
			(xy 293.505257 -275.183668) (xy 293.478954 -275.142072) (xy 293.459663 -275.096796) (xy 293.447886 -275.049012)
			(xy 293.443926 -274.999958) (xy 293.126663 -274.999958) (xy 293.126164 -275.025412) (xy 293.118121 -275.076194)
			(xy 293.102233 -275.125093) (xy 293.07889 -275.170905) (xy 293.048669 -275.212501) (xy 293.012313 -275.248857)
			(xy 292.970717 -275.279078) (xy 292.924905 -275.302421) (xy 292.876006 -275.318309) (xy 292.825224 -275.326352)
			(xy 292.773808 -275.326352) (xy 292.723026 -275.318309) (xy 292.674127 -275.302421) (xy 292.628315 -275.279078)
			(xy 292.586719 -275.248857) (xy 292.550363 -275.212501) (xy 292.520142 -275.170905) (xy 292.496799 -275.125093)
			(xy 292.480911 -275.076194) (xy 292.472868 -275.025412) (xy 292.154485 -275.025412) (xy 292.146728 -275.073142)
			(xy 292.131144 -275.119823) (xy 292.108273 -275.1634) (xy 292.078708 -275.202744) (xy 292.043215 -275.236836)
			(xy 292.002712 -275.264792) (xy 291.95825 -275.28589) (xy 291.910979 -275.299582) (xy 291.862124 -275.305514)
			(xy 291.812949 -275.303533) (xy 291.76473 -275.293689) (xy 291.718714 -275.276237) (xy 291.676093 -275.25163)
			(xy 291.637972 -275.220505) (xy 291.605337 -275.183668) (xy 291.579034 -275.142072) (xy 291.559743 -275.096796)
			(xy 291.547966 -275.049012) (xy 291.544006 -274.999958) (xy 291.227002 -274.999958) (xy 291.226498 -275.025666)
			(xy 291.218455 -275.076448) (xy 291.202567 -275.125347) (xy 291.179224 -275.171159) (xy 291.149003 -275.212755)
			(xy 291.112647 -275.249111) (xy 291.071051 -275.279332) (xy 291.025239 -275.302675) (xy 290.97634 -275.318563)
			(xy 290.925558 -275.326606) (xy 290.874142 -275.326606) (xy 290.82336 -275.318563) (xy 290.774461 -275.302675)
			(xy 290.728649 -275.279332) (xy 290.687053 -275.249111) (xy 290.650697 -275.212755) (xy 290.620476 -275.171159)
			(xy 290.597133 -275.125347) (xy 290.581245 -275.076448) (xy 290.573202 -275.025666) (xy 290.254524 -275.025666)
			(xy 290.246808 -275.073142) (xy 290.231224 -275.119823) (xy 290.208353 -275.1634) (xy 290.178788 -275.202744)
			(xy 290.143295 -275.236836) (xy 290.102792 -275.264792) (xy 290.05833 -275.28589) (xy 290.011059 -275.299582)
			(xy 289.962204 -275.305514) (xy 289.913029 -275.303533) (xy 289.86481 -275.293689) (xy 289.818794 -275.276237)
			(xy 289.776173 -275.25163) (xy 289.738052 -275.220505) (xy 289.705417 -275.183668) (xy 289.679114 -275.142072)
			(xy 289.659823 -275.096796) (xy 289.648046 -275.049012) (xy 289.644086 -274.999958) (xy 289.327082 -274.999958)
			(xy 289.326578 -275.025666) (xy 289.318535 -275.076448) (xy 289.302647 -275.125347) (xy 289.279304 -275.171159)
			(xy 289.249083 -275.212755) (xy 289.212727 -275.249111) (xy 289.171131 -275.279332) (xy 289.125319 -275.302675)
			(xy 289.07642 -275.318563) (xy 289.025638 -275.326606) (xy 288.974222 -275.326606) (xy 288.92344 -275.318563)
			(xy 288.874541 -275.302675) (xy 288.828729 -275.279332) (xy 288.787133 -275.249111) (xy 288.750777 -275.212755)
			(xy 288.720556 -275.171159) (xy 288.697213 -275.125347) (xy 288.681325 -275.076448) (xy 288.673282 -275.025666)
			(xy 288.35435 -275.025666) (xy 288.346634 -275.073142) (xy 288.33105 -275.119823) (xy 288.308179 -275.1634)
			(xy 288.278614 -275.202744) (xy 288.243121 -275.236836) (xy 288.202618 -275.264792) (xy 288.158156 -275.28589)
			(xy 288.110885 -275.299582) (xy 288.06203 -275.305514) (xy 288.012855 -275.303533) (xy 287.964636 -275.293689)
			(xy 287.91862 -275.276237) (xy 287.875999 -275.25163) (xy 287.837878 -275.220505) (xy 287.805243 -275.183668)
			(xy 287.77894 -275.142072) (xy 287.759649 -275.096796) (xy 287.747872 -275.049012) (xy 287.743912 -274.999958)
			(xy 287.426908 -274.999958) (xy 287.426404 -275.025666) (xy 287.418361 -275.076448) (xy 287.402473 -275.125347)
			(xy 287.37913 -275.171159) (xy 287.348909 -275.212755) (xy 287.312553 -275.249111) (xy 287.270957 -275.279332)
			(xy 287.225145 -275.302675) (xy 287.176246 -275.318563) (xy 287.125464 -275.326606) (xy 287.074048 -275.326606)
			(xy 287.023266 -275.318563) (xy 286.974367 -275.302675) (xy 286.928555 -275.279332) (xy 286.886959 -275.249111)
			(xy 286.850603 -275.212755) (xy 286.820382 -275.171159) (xy 286.797039 -275.125347) (xy 286.781151 -275.076448)
			(xy 286.773108 -275.025666) (xy 286.45443 -275.025666) (xy 286.446714 -275.073142) (xy 286.43113 -275.119823)
			(xy 286.408259 -275.1634) (xy 286.378694 -275.202744) (xy 286.343201 -275.236836) (xy 286.302698 -275.264792)
			(xy 286.258236 -275.28589) (xy 286.210965 -275.299582) (xy 286.16211 -275.305514) (xy 286.112935 -275.303533)
			(xy 286.064716 -275.293689) (xy 286.0187 -275.276237) (xy 285.976079 -275.25163) (xy 285.937958 -275.220505)
			(xy 285.905323 -275.183668) (xy 285.87902 -275.142072) (xy 285.859729 -275.096796) (xy 285.847952 -275.049012)
			(xy 285.843992 -274.999958) (xy 285.526988 -274.999958) (xy 285.526484 -275.025666) (xy 285.518441 -275.076448)
			(xy 285.502553 -275.125347) (xy 285.47921 -275.171159) (xy 285.448989 -275.212755) (xy 285.412633 -275.249111)
			(xy 285.371037 -275.279332) (xy 285.325225 -275.302675) (xy 285.276326 -275.318563) (xy 285.225544 -275.326606)
			(xy 285.174128 -275.326606) (xy 285.123346 -275.318563) (xy 285.074447 -275.302675) (xy 285.028635 -275.279332)
			(xy 284.987039 -275.249111) (xy 284.950683 -275.212755) (xy 284.920462 -275.171159) (xy 284.897119 -275.125347)
			(xy 284.881231 -275.076448) (xy 284.873188 -275.025666) (xy 284.55451 -275.025666) (xy 284.546794 -275.073142)
			(xy 284.53121 -275.119823) (xy 284.508339 -275.1634) (xy 284.478774 -275.202744) (xy 284.443281 -275.236836)
			(xy 284.402778 -275.264792) (xy 284.358316 -275.28589) (xy 284.311045 -275.299582) (xy 284.26219 -275.305514)
			(xy 284.213015 -275.303533) (xy 284.164796 -275.293689) (xy 284.11878 -275.276237) (xy 284.076159 -275.25163)
			(xy 284.038038 -275.220505) (xy 284.005403 -275.183668) (xy 283.9791 -275.142072) (xy 283.959809 -275.096796)
			(xy 283.948032 -275.049012) (xy 283.944072 -274.999958) (xy 283.627068 -274.999958) (xy 283.626564 -275.025666)
			(xy 283.618521 -275.076448) (xy 283.602633 -275.125347) (xy 283.57929 -275.171159) (xy 283.549069 -275.212755)
			(xy 283.512713 -275.249111) (xy 283.471117 -275.279332) (xy 283.425305 -275.302675) (xy 283.376406 -275.318563)
			(xy 283.325624 -275.326606) (xy 283.274208 -275.326606) (xy 283.223426 -275.318563) (xy 283.174527 -275.302675)
			(xy 283.128715 -275.279332) (xy 283.087119 -275.249111) (xy 283.050763 -275.212755) (xy 283.020542 -275.171159)
			(xy 282.997199 -275.125347) (xy 282.981311 -275.076448) (xy 282.973268 -275.025666) (xy 282.653446 -275.025666)
			(xy 282.651401 -275.050345) (xy 282.639 -275.099316) (xy 282.618708 -275.145579) (xy 282.591077 -275.18787)
			(xy 282.556863 -275.225037) (xy 282.516998 -275.256066) (xy 282.472569 -275.28011) (xy 282.424789 -275.296513)
			(xy 282.374961 -275.304828) (xy 282.349702 -275.305266) (xy 282.33552 -275.30508) (xy 282.30728 -275.302407)
			(xy 282.293314 -275.299932) (xy 282.280868 -275.297646) (xy 282.257246 -275.305012) (xy 282.179776 -275.382482)
			(xy 282.17241 -275.406104) (xy 282.174696 -275.41855) (xy 282.177179 -275.432515) (xy 282.179848 -275.460755)
			(xy 282.18003 -275.474938) (xy 282.179846 -275.489121) (xy 282.177179 -275.517361) (xy 282.174696 -275.531326)
			(xy 282.17241 -275.543772) (xy 282.179776 -275.567394) (xy 282.257246 -275.644864) (xy 282.280868 -275.65223)
			(xy 282.293314 -275.649944) (xy 282.307279 -275.647459) (xy 282.335519 -275.644787) (xy 282.349702 -275.64461)
			(xy 282.374956 -275.645132) (xy 282.424774 -275.653445) (xy 282.472545 -275.669845) (xy 282.516965 -275.693884)
			(xy 282.556822 -275.724907) (xy 282.59103 -275.762066) (xy 282.618655 -275.80435) (xy 282.638943 -275.850603)
			(xy 282.651342 -275.899565) (xy 282.655513 -275.9499) (xy 282.653381 -275.975626) (xy 282.973268 -275.975626)
			(xy 282.973268 -275.92421) (xy 282.981311 -275.873428) (xy 282.997199 -275.824529) (xy 283.020542 -275.778717)
			(xy 283.050763 -275.737121) (xy 283.087119 -275.700765) (xy 283.128715 -275.670544) (xy 283.174527 -275.647201)
			(xy 283.223426 -275.631313) (xy 283.274208 -275.62327) (xy 283.325624 -275.62327) (xy 283.376406 -275.631313)
			(xy 283.425305 -275.647201) (xy 283.471117 -275.670544) (xy 283.512713 -275.700765) (xy 283.549069 -275.737121)
			(xy 283.57929 -275.778717) (xy 283.602633 -275.824529) (xy 283.618521 -275.873428) (xy 283.626564 -275.92421)
			(xy 283.627068 -275.949918) (xy 283.944072 -275.949918) (xy 283.948032 -275.900864) (xy 283.959809 -275.85308)
			(xy 283.9791 -275.807804) (xy 284.005403 -275.766208) (xy 284.038038 -275.729371) (xy 284.076159 -275.698246)
			(xy 284.11878 -275.673639) (xy 284.164796 -275.656187) (xy 284.213015 -275.646343) (xy 284.26219 -275.644362)
			(xy 284.311045 -275.650294) (xy 284.358316 -275.663986) (xy 284.402778 -275.685084) (xy 284.443281 -275.71304)
			(xy 284.478774 -275.747132) (xy 284.508339 -275.786476) (xy 284.53121 -275.830053) (xy 284.546794 -275.876734)
			(xy 284.554689 -275.925311) (xy 284.555184 -275.949918) (xy 284.554689 -275.974525) (xy 284.55451 -275.975626)
			(xy 284.873188 -275.975626) (xy 284.873188 -275.92421) (xy 284.881231 -275.873428) (xy 284.897119 -275.824529)
			(xy 284.920462 -275.778717) (xy 284.950683 -275.737121) (xy 284.987039 -275.700765) (xy 285.028635 -275.670544)
			(xy 285.074447 -275.647201) (xy 285.123346 -275.631313) (xy 285.174128 -275.62327) (xy 285.225544 -275.62327)
			(xy 285.276326 -275.631313) (xy 285.325225 -275.647201) (xy 285.371037 -275.670544) (xy 285.412633 -275.700765)
			(xy 285.448989 -275.737121) (xy 285.47921 -275.778717) (xy 285.502553 -275.824529) (xy 285.518441 -275.873428)
			(xy 285.526484 -275.92421) (xy 285.526988 -275.949918) (xy 285.843992 -275.949918) (xy 285.847952 -275.900864)
			(xy 285.859729 -275.85308) (xy 285.87902 -275.807804) (xy 285.905323 -275.766208) (xy 285.937958 -275.729371)
			(xy 285.976079 -275.698246) (xy 286.0187 -275.673639) (xy 286.064716 -275.656187) (xy 286.112935 -275.646343)
			(xy 286.16211 -275.644362) (xy 286.210965 -275.650294) (xy 286.258236 -275.663986) (xy 286.302698 -275.685084)
			(xy 286.343201 -275.71304) (xy 286.378694 -275.747132) (xy 286.408259 -275.786476) (xy 286.43113 -275.830053)
			(xy 286.446714 -275.876734) (xy 286.454609 -275.925311) (xy 286.455104 -275.949918) (xy 286.454609 -275.974525)
			(xy 286.45443 -275.975626) (xy 286.773108 -275.975626) (xy 286.773108 -275.92421) (xy 286.781151 -275.873428)
			(xy 286.797039 -275.824529) (xy 286.820382 -275.778717) (xy 286.850603 -275.737121) (xy 286.886959 -275.700765)
			(xy 286.928555 -275.670544) (xy 286.974367 -275.647201) (xy 287.023266 -275.631313) (xy 287.074048 -275.62327)
			(xy 287.125464 -275.62327) (xy 287.176246 -275.631313) (xy 287.225145 -275.647201) (xy 287.270957 -275.670544)
			(xy 287.312553 -275.700765) (xy 287.348909 -275.737121) (xy 287.37913 -275.778717) (xy 287.402473 -275.824529)
			(xy 287.418361 -275.873428) (xy 287.426404 -275.92421) (xy 287.426908 -275.949918) (xy 287.743912 -275.949918)
			(xy 287.747872 -275.900864) (xy 287.759649 -275.85308) (xy 287.77894 -275.807804) (xy 287.805243 -275.766208)
			(xy 287.837878 -275.729371) (xy 287.875999 -275.698246) (xy 287.91862 -275.673639) (xy 287.964636 -275.656187)
			(xy 288.012855 -275.646343) (xy 288.06203 -275.644362) (xy 288.110885 -275.650294) (xy 288.158156 -275.663986)
			(xy 288.202618 -275.685084) (xy 288.243121 -275.71304) (xy 288.278614 -275.747132) (xy 288.308179 -275.786476)
			(xy 288.33105 -275.830053) (xy 288.346634 -275.876734) (xy 288.354529 -275.925311) (xy 288.355024 -275.949918)
			(xy 288.354529 -275.974525) (xy 288.35435 -275.975626) (xy 288.673282 -275.975626) (xy 288.673282 -275.92421)
			(xy 288.681325 -275.873428) (xy 288.697213 -275.824529) (xy 288.720556 -275.778717) (xy 288.750777 -275.737121)
			(xy 288.787133 -275.700765) (xy 288.828729 -275.670544) (xy 288.874541 -275.647201) (xy 288.92344 -275.631313)
			(xy 288.974222 -275.62327) (xy 289.025638 -275.62327) (xy 289.07642 -275.631313) (xy 289.125319 -275.647201)
			(xy 289.171131 -275.670544) (xy 289.212727 -275.700765) (xy 289.249083 -275.737121) (xy 289.279304 -275.778717)
			(xy 289.302647 -275.824529) (xy 289.318535 -275.873428) (xy 289.326578 -275.92421) (xy 289.327082 -275.949918)
			(xy 289.644086 -275.949918) (xy 289.648046 -275.900864) (xy 289.659823 -275.85308) (xy 289.679114 -275.807804)
			(xy 289.705417 -275.766208) (xy 289.738052 -275.729371) (xy 289.776173 -275.698246) (xy 289.818794 -275.673639)
			(xy 289.86481 -275.656187) (xy 289.913029 -275.646343) (xy 289.962204 -275.644362) (xy 290.011059 -275.650294)
			(xy 290.05833 -275.663986) (xy 290.102792 -275.685084) (xy 290.143295 -275.71304) (xy 290.178788 -275.747132)
			(xy 290.208353 -275.786476) (xy 290.231224 -275.830053) (xy 290.246808 -275.876734) (xy 290.254703 -275.925311)
			(xy 290.255198 -275.949918) (xy 290.254703 -275.974525) (xy 290.254524 -275.975626) (xy 290.573202 -275.975626)
			(xy 290.573202 -275.92421) (xy 290.581245 -275.873428) (xy 290.597133 -275.824529) (xy 290.620476 -275.778717)
			(xy 290.650697 -275.737121) (xy 290.687053 -275.700765) (xy 290.728649 -275.670544) (xy 290.774461 -275.647201)
			(xy 290.82336 -275.631313) (xy 290.874142 -275.62327) (xy 290.925558 -275.62327) (xy 290.97634 -275.631313)
			(xy 291.025239 -275.647201) (xy 291.071051 -275.670544) (xy 291.112647 -275.700765) (xy 291.149003 -275.737121)
			(xy 291.179224 -275.778717) (xy 291.202567 -275.824529) (xy 291.218455 -275.873428) (xy 291.226498 -275.92421)
			(xy 291.227002 -275.949918) (xy 291.544006 -275.949918) (xy 291.547966 -275.900864) (xy 291.559743 -275.85308)
			(xy 291.579034 -275.807804) (xy 291.605337 -275.766208) (xy 291.637972 -275.729371) (xy 291.676093 -275.698246)
			(xy 291.718714 -275.673639) (xy 291.76473 -275.656187) (xy 291.812949 -275.646343) (xy 291.862124 -275.644362)
			(xy 291.910979 -275.650294) (xy 291.95825 -275.663986) (xy 292.002712 -275.685084) (xy 292.043215 -275.71304)
			(xy 292.078708 -275.747132) (xy 292.108273 -275.786476) (xy 292.131144 -275.830053) (xy 292.146728 -275.876734)
			(xy 292.154623 -275.925311) (xy 292.155118 -275.949918) (xy 292.154623 -275.974525) (xy 292.154485 -275.975372)
			(xy 292.472868 -275.975372) (xy 292.472868 -275.923956) (xy 292.480911 -275.873174) (xy 292.496799 -275.824275)
			(xy 292.520142 -275.778463) (xy 292.550363 -275.736867) (xy 292.586719 -275.700511) (xy 292.628315 -275.67029)
			(xy 292.674127 -275.646947) (xy 292.723026 -275.631059) (xy 292.773808 -275.623016) (xy 292.825224 -275.623016)
			(xy 292.876006 -275.631059) (xy 292.924905 -275.646947) (xy 292.970717 -275.67029) (xy 293.012313 -275.700511)
			(xy 293.048669 -275.736867) (xy 293.07889 -275.778463) (xy 293.102233 -275.824275) (xy 293.118121 -275.873174)
			(xy 293.126164 -275.923956) (xy 293.126668 -275.949664) (xy 293.126663 -275.949918) (xy 293.443926 -275.949918)
			(xy 293.447886 -275.900864) (xy 293.459663 -275.85308) (xy 293.478954 -275.807804) (xy 293.505257 -275.766208)
			(xy 293.537892 -275.729371) (xy 293.576013 -275.698246) (xy 293.618634 -275.673639) (xy 293.66465 -275.656187)
			(xy 293.712869 -275.646343) (xy 293.762044 -275.644362) (xy 293.810899 -275.650294) (xy 293.85817 -275.663986)
			(xy 293.902632 -275.685084) (xy 293.943135 -275.71304) (xy 293.978628 -275.747132) (xy 294.008193 -275.786476)
			(xy 294.031064 -275.830053) (xy 294.046648 -275.876734) (xy 294.054543 -275.925311) (xy 294.055038 -275.949918)
			(xy 294.054543 -275.974525) (xy 294.054364 -275.975626) (xy 294.372788 -275.975626) (xy 294.372788 -275.92421)
			(xy 294.380831 -275.873428) (xy 294.396719 -275.824529) (xy 294.420062 -275.778717) (xy 294.450283 -275.737121)
			(xy 294.486639 -275.700765) (xy 294.528235 -275.670544) (xy 294.574047 -275.647201) (xy 294.622946 -275.631313)
			(xy 294.673728 -275.62327) (xy 294.725144 -275.62327) (xy 294.775926 -275.631313) (xy 294.824825 -275.647201)
			(xy 294.870637 -275.670544) (xy 294.912233 -275.700765) (xy 294.948589 -275.737121) (xy 294.97881 -275.778717)
			(xy 295.002153 -275.824529) (xy 295.018041 -275.873428) (xy 295.026084 -275.92421) (xy 295.026588 -275.949918)
			(xy 295.3441 -275.949918) (xy 295.34806 -275.900864) (xy 295.359837 -275.85308) (xy 295.379128 -275.807804)
			(xy 295.405431 -275.766208) (xy 295.438066 -275.729371) (xy 295.476187 -275.698246) (xy 295.518808 -275.673639)
			(xy 295.564824 -275.656187) (xy 295.613043 -275.646343) (xy 295.662218 -275.644362) (xy 295.711073 -275.650294)
			(xy 295.758344 -275.663986) (xy 295.802806 -275.685084) (xy 295.843309 -275.71304) (xy 295.878802 -275.747132)
			(xy 295.908367 -275.786476) (xy 295.931238 -275.830053) (xy 295.946822 -275.876734) (xy 295.954717 -275.925311)
			(xy 295.955212 -275.949918) (xy 295.954717 -275.974525) (xy 295.954579 -275.975372) (xy 296.272962 -275.975372)
			(xy 296.272962 -275.923956) (xy 296.281005 -275.873174) (xy 296.296893 -275.824275) (xy 296.320236 -275.778463)
			(xy 296.350457 -275.736867) (xy 296.386813 -275.700511) (xy 296.428409 -275.67029) (xy 296.474221 -275.646947)
			(xy 296.52312 -275.631059) (xy 296.573902 -275.623016) (xy 296.625318 -275.623016) (xy 296.6761 -275.631059)
			(xy 296.724999 -275.646947) (xy 296.770811 -275.67029) (xy 296.812407 -275.700511) (xy 296.848763 -275.736867)
			(xy 296.878984 -275.778463) (xy 296.902327 -275.824275) (xy 296.918215 -275.873174) (xy 296.926258 -275.923956)
			(xy 296.926762 -275.949664) (xy 296.926757 -275.949918) (xy 297.24402 -275.949918) (xy 297.24798 -275.900864)
			(xy 297.259757 -275.85308) (xy 297.279048 -275.807804) (xy 297.305351 -275.766208) (xy 297.337986 -275.729371)
			(xy 297.376107 -275.698246) (xy 297.418728 -275.673639) (xy 297.464744 -275.656187) (xy 297.512963 -275.646343)
			(xy 297.562138 -275.644362) (xy 297.610993 -275.650294) (xy 297.658264 -275.663986) (xy 297.702726 -275.685084)
			(xy 297.743229 -275.71304) (xy 297.778722 -275.747132) (xy 297.808287 -275.786476) (xy 297.831158 -275.830053)
			(xy 297.846742 -275.876734) (xy 297.854637 -275.925311) (xy 297.855132 -275.949918) (xy 297.854637 -275.974525)
			(xy 297.854458 -275.975626) (xy 298.172882 -275.975626) (xy 298.172882 -275.92421) (xy 298.180925 -275.873428)
			(xy 298.196813 -275.824529) (xy 298.220156 -275.778717) (xy 298.250377 -275.737121) (xy 298.286733 -275.700765)
			(xy 298.328329 -275.670544) (xy 298.374141 -275.647201) (xy 298.42304 -275.631313) (xy 298.473822 -275.62327)
			(xy 298.525238 -275.62327) (xy 298.57602 -275.631313) (xy 298.624919 -275.647201) (xy 298.670731 -275.670544)
			(xy 298.712327 -275.700765) (xy 298.748683 -275.737121) (xy 298.778904 -275.778717) (xy 298.802247 -275.824529)
			(xy 298.818135 -275.873428) (xy 298.826178 -275.92421) (xy 298.826682 -275.949918) (xy 299.14394 -275.949918)
			(xy 299.1479 -275.900864) (xy 299.159677 -275.85308) (xy 299.178968 -275.807804) (xy 299.205271 -275.766208)
			(xy 299.237906 -275.729371) (xy 299.276027 -275.698246) (xy 299.318648 -275.673639) (xy 299.364664 -275.656187)
			(xy 299.412883 -275.646343) (xy 299.462058 -275.644362) (xy 299.510913 -275.650294) (xy 299.558184 -275.663986)
			(xy 299.602646 -275.685084) (xy 299.643149 -275.71304) (xy 299.678642 -275.747132) (xy 299.708207 -275.786476)
			(xy 299.731078 -275.830053) (xy 299.746662 -275.876734) (xy 299.754557 -275.925311) (xy 299.755052 -275.949918)
			(xy 299.754557 -275.974525) (xy 299.754419 -275.975372) (xy 300.072802 -275.975372) (xy 300.072802 -275.923956)
			(xy 300.080845 -275.873174) (xy 300.096733 -275.824275) (xy 300.120076 -275.778463) (xy 300.150297 -275.736867)
			(xy 300.186653 -275.700511) (xy 300.228249 -275.67029) (xy 300.274061 -275.646947) (xy 300.32296 -275.631059)
			(xy 300.373742 -275.623016) (xy 300.425158 -275.623016) (xy 300.47594 -275.631059) (xy 300.524839 -275.646947)
			(xy 300.570651 -275.67029) (xy 300.612247 -275.700511) (xy 300.648603 -275.736867) (xy 300.678824 -275.778463)
			(xy 300.702167 -275.824275) (xy 300.718055 -275.873174) (xy 300.726098 -275.923956) (xy 300.726602 -275.949664)
			(xy 300.726597 -275.949918) (xy 301.044114 -275.949918) (xy 301.048074 -275.900864) (xy 301.059851 -275.85308)
			(xy 301.079142 -275.807804) (xy 301.105445 -275.766208) (xy 301.13808 -275.729371) (xy 301.176201 -275.698246)
			(xy 301.218822 -275.673639) (xy 301.264838 -275.656187) (xy 301.313057 -275.646343) (xy 301.362232 -275.644362)
			(xy 301.411087 -275.650294) (xy 301.458358 -275.663986) (xy 301.50282 -275.685084) (xy 301.543323 -275.71304)
			(xy 301.578816 -275.747132) (xy 301.608381 -275.786476) (xy 301.631252 -275.830053) (xy 301.646836 -275.876734)
			(xy 301.654731 -275.925311) (xy 301.655226 -275.949918) (xy 301.654731 -275.974525) (xy 301.654552 -275.975626)
			(xy 301.972722 -275.975626) (xy 301.972722 -275.92421) (xy 301.980765 -275.873428) (xy 301.996653 -275.824529)
			(xy 302.019996 -275.778717) (xy 302.050217 -275.737121) (xy 302.086573 -275.700765) (xy 302.128169 -275.670544)
			(xy 302.173981 -275.647201) (xy 302.22288 -275.631313) (xy 302.273662 -275.62327) (xy 302.325078 -275.62327)
			(xy 302.37586 -275.631313) (xy 302.424759 -275.647201) (xy 302.470571 -275.670544) (xy 302.512167 -275.700765)
			(xy 302.548523 -275.737121) (xy 302.578744 -275.778717) (xy 302.602087 -275.824529) (xy 302.617975 -275.873428)
			(xy 302.626018 -275.92421) (xy 302.626522 -275.949918) (xy 302.944034 -275.949918) (xy 302.947994 -275.900864)
			(xy 302.959771 -275.85308) (xy 302.979062 -275.807804) (xy 303.005365 -275.766208) (xy 303.038 -275.729371)
			(xy 303.076121 -275.698246) (xy 303.118742 -275.673639) (xy 303.164758 -275.656187) (xy 303.212977 -275.646343)
			(xy 303.262152 -275.644362) (xy 303.311007 -275.650294) (xy 303.358278 -275.663986) (xy 303.40274 -275.685084)
			(xy 303.443243 -275.71304) (xy 303.478736 -275.747132) (xy 303.508301 -275.786476) (xy 303.531172 -275.830053)
			(xy 303.546756 -275.876734) (xy 303.554651 -275.925311) (xy 303.555146 -275.949918) (xy 303.554651 -275.974525)
			(xy 303.554513 -275.975372) (xy 303.872896 -275.975372) (xy 303.872896 -275.923956) (xy 303.880939 -275.873174)
			(xy 303.896827 -275.824275) (xy 303.92017 -275.778463) (xy 303.950391 -275.736867) (xy 303.986747 -275.700511)
			(xy 304.028343 -275.67029) (xy 304.074155 -275.646947) (xy 304.123054 -275.631059) (xy 304.173836 -275.623016)
			(xy 304.225252 -275.623016) (xy 304.276034 -275.631059) (xy 304.324933 -275.646947) (xy 304.370745 -275.67029)
			(xy 304.412341 -275.700511) (xy 304.448697 -275.736867) (xy 304.478918 -275.778463) (xy 304.502261 -275.824275)
			(xy 304.518149 -275.873174) (xy 304.526192 -275.923956) (xy 304.526696 -275.949664) (xy 304.526691 -275.949918)
			(xy 304.843954 -275.949918) (xy 304.847914 -275.900864) (xy 304.859691 -275.85308) (xy 304.878982 -275.807804)
			(xy 304.905285 -275.766208) (xy 304.93792 -275.729371) (xy 304.976041 -275.698246) (xy 305.018662 -275.673639)
			(xy 305.064678 -275.656187) (xy 305.112897 -275.646343) (xy 305.162072 -275.644362) (xy 305.210927 -275.650294)
			(xy 305.258198 -275.663986) (xy 305.30266 -275.685084) (xy 305.343163 -275.71304) (xy 305.378656 -275.747132)
			(xy 305.408221 -275.786476) (xy 305.431092 -275.830053) (xy 305.446676 -275.876734) (xy 305.454571 -275.925311)
			(xy 305.455066 -275.949918) (xy 305.454571 -275.974525) (xy 305.454392 -275.975626) (xy 305.772816 -275.975626)
			(xy 305.772816 -275.92421) (xy 305.780859 -275.873428) (xy 305.796747 -275.824529) (xy 305.82009 -275.778717)
			(xy 305.850311 -275.737121) (xy 305.886667 -275.700765) (xy 305.928263 -275.670544) (xy 305.974075 -275.647201)
			(xy 306.022974 -275.631313) (xy 306.073756 -275.62327) (xy 306.125172 -275.62327) (xy 306.175954 -275.631313)
			(xy 306.224853 -275.647201) (xy 306.270665 -275.670544) (xy 306.312261 -275.700765) (xy 306.348617 -275.737121)
			(xy 306.378838 -275.778717) (xy 306.402181 -275.824529) (xy 306.418069 -275.873428) (xy 306.426112 -275.92421)
			(xy 306.426616 -275.949918) (xy 306.744128 -275.949918) (xy 306.748088 -275.900864) (xy 306.759865 -275.85308)
			(xy 306.779156 -275.807804) (xy 306.805459 -275.766208) (xy 306.838094 -275.729371) (xy 306.876215 -275.698246)
			(xy 306.918836 -275.673639) (xy 306.964852 -275.656187) (xy 307.013071 -275.646343) (xy 307.062246 -275.644362)
			(xy 307.111101 -275.650294) (xy 307.158372 -275.663986) (xy 307.202834 -275.685084) (xy 307.243337 -275.71304)
			(xy 307.27883 -275.747132) (xy 307.308395 -275.786476) (xy 307.331266 -275.830053) (xy 307.34685 -275.876734)
			(xy 307.354745 -275.925311) (xy 307.35524 -275.949918) (xy 307.354745 -275.974525) (xy 307.354607 -275.975372)
			(xy 307.67299 -275.975372) (xy 307.67299 -275.923956) (xy 307.681033 -275.873174) (xy 307.696921 -275.824275)
			(xy 307.720264 -275.778463) (xy 307.750485 -275.736867) (xy 307.786841 -275.700511) (xy 307.828437 -275.67029)
			(xy 307.874249 -275.646947) (xy 307.923148 -275.631059) (xy 307.97393 -275.623016) (xy 308.025346 -275.623016)
			(xy 308.076128 -275.631059) (xy 308.125027 -275.646947) (xy 308.170839 -275.67029) (xy 308.212435 -275.700511)
			(xy 308.248791 -275.736867) (xy 308.279012 -275.778463) (xy 308.302355 -275.824275) (xy 308.318243 -275.873174)
			(xy 308.326286 -275.923956) (xy 308.32679 -275.949664) (xy 308.326785 -275.949918) (xy 308.644048 -275.949918)
			(xy 308.648008 -275.900864) (xy 308.659785 -275.85308) (xy 308.679076 -275.807804) (xy 308.705379 -275.766208)
			(xy 308.738014 -275.729371) (xy 308.776135 -275.698246) (xy 308.818756 -275.673639) (xy 308.864772 -275.656187)
			(xy 308.912991 -275.646343) (xy 308.962166 -275.644362) (xy 309.011021 -275.650294) (xy 309.058292 -275.663986)
			(xy 309.102754 -275.685084) (xy 309.143257 -275.71304) (xy 309.17875 -275.747132) (xy 309.208315 -275.786476)
			(xy 309.231186 -275.830053) (xy 309.24677 -275.876734) (xy 309.254665 -275.925311) (xy 309.25516 -275.949918)
			(xy 309.254665 -275.974525) (xy 309.254486 -275.975626) (xy 309.57291 -275.975626) (xy 309.57291 -275.92421)
			(xy 309.580953 -275.873428) (xy 309.596841 -275.824529) (xy 309.620184 -275.778717) (xy 309.650405 -275.737121)
			(xy 309.686761 -275.700765) (xy 309.728357 -275.670544) (xy 309.774169 -275.647201) (xy 309.823068 -275.631313)
			(xy 309.87385 -275.62327) (xy 309.925266 -275.62327) (xy 309.976048 -275.631313) (xy 310.024947 -275.647201)
			(xy 310.070759 -275.670544) (xy 310.112355 -275.700765) (xy 310.148711 -275.737121) (xy 310.178932 -275.778717)
			(xy 310.202275 -275.824529) (xy 310.218163 -275.873428) (xy 310.226206 -275.92421) (xy 310.22671 -275.949918)
			(xy 310.543968 -275.949918) (xy 310.547928 -275.900864) (xy 310.559705 -275.85308) (xy 310.578996 -275.807804)
			(xy 310.605299 -275.766208) (xy 310.637934 -275.729371) (xy 310.676055 -275.698246) (xy 310.718676 -275.673639)
			(xy 310.764692 -275.656187) (xy 310.812911 -275.646343) (xy 310.862086 -275.644362) (xy 310.910941 -275.650294)
			(xy 310.958212 -275.663986) (xy 311.002674 -275.685084) (xy 311.043177 -275.71304) (xy 311.07867 -275.747132)
			(xy 311.108235 -275.786476) (xy 311.131106 -275.830053) (xy 311.14669 -275.876734) (xy 311.154585 -275.925311)
			(xy 311.15508 -275.949918) (xy 311.154585 -275.974525) (xy 311.154406 -275.975626) (xy 311.47283 -275.975626)
			(xy 311.47283 -275.92421) (xy 311.480873 -275.873428) (xy 311.496761 -275.824529) (xy 311.520104 -275.778717)
			(xy 311.550325 -275.737121) (xy 311.586681 -275.700765) (xy 311.628277 -275.670544) (xy 311.674089 -275.647201)
			(xy 311.722988 -275.631313) (xy 311.77377 -275.62327) (xy 311.825186 -275.62327) (xy 311.875968 -275.631313)
			(xy 311.924867 -275.647201) (xy 311.970679 -275.670544) (xy 312.012275 -275.700765) (xy 312.048631 -275.737121)
			(xy 312.078852 -275.778717) (xy 312.102195 -275.824529) (xy 312.118083 -275.873428) (xy 312.126126 -275.92421)
			(xy 312.12663 -275.949918) (xy 312.444142 -275.949918) (xy 312.448102 -275.900864) (xy 312.459879 -275.85308)
			(xy 312.47917 -275.807804) (xy 312.505473 -275.766208) (xy 312.538108 -275.729371) (xy 312.576229 -275.698246)
			(xy 312.61885 -275.673639) (xy 312.664866 -275.656187) (xy 312.713085 -275.646343) (xy 312.76226 -275.644362)
			(xy 312.811115 -275.650294) (xy 312.858386 -275.663986) (xy 312.902848 -275.685084) (xy 312.943351 -275.71304)
			(xy 312.978844 -275.747132) (xy 313.008409 -275.786476) (xy 313.03128 -275.830053) (xy 313.046864 -275.876734)
			(xy 313.054759 -275.925311) (xy 313.055254 -275.949918) (xy 313.394102 -275.949918) (xy 313.398062 -275.900864)
			(xy 313.409839 -275.85308) (xy 313.42913 -275.807804) (xy 313.455433 -275.766208) (xy 313.488068 -275.729371)
			(xy 313.526189 -275.698246) (xy 313.56881 -275.673639) (xy 313.614826 -275.656187) (xy 313.663045 -275.646343)
			(xy 313.71222 -275.644362) (xy 313.761075 -275.650294) (xy 313.808346 -275.663986) (xy 313.852808 -275.685084)
			(xy 313.893311 -275.71304) (xy 313.928804 -275.747132) (xy 313.958369 -275.786476) (xy 313.98124 -275.830053)
			(xy 313.996824 -275.876734) (xy 314.004719 -275.925311) (xy 314.005214 -275.949918) (xy 314.344062 -275.949918)
			(xy 314.348022 -275.900864) (xy 314.359799 -275.85308) (xy 314.37909 -275.807804) (xy 314.405393 -275.766208)
			(xy 314.438028 -275.729371) (xy 314.476149 -275.698246) (xy 314.51877 -275.673639) (xy 314.564786 -275.656187)
			(xy 314.613005 -275.646343) (xy 314.66218 -275.644362) (xy 314.711035 -275.650294) (xy 314.758306 -275.663986)
			(xy 314.802768 -275.685084) (xy 314.843271 -275.71304) (xy 314.878764 -275.747132) (xy 314.908329 -275.786476)
			(xy 314.9312 -275.830053) (xy 314.946784 -275.876734) (xy 314.954679 -275.925311) (xy 314.955174 -275.949918)
			(xy 314.954679 -275.974525) (xy 314.946784 -276.023102) (xy 314.9312 -276.069783) (xy 314.908329 -276.11336)
			(xy 314.878764 -276.152704) (xy 314.843271 -276.186796) (xy 314.802768 -276.214752) (xy 314.758306 -276.23585)
			(xy 314.711035 -276.249542) (xy 314.66218 -276.255474) (xy 314.613005 -276.253493) (xy 314.564786 -276.243649)
			(xy 314.51877 -276.226197) (xy 314.476149 -276.20159) (xy 314.438028 -276.170465) (xy 314.405393 -276.133628)
			(xy 314.37909 -276.092032) (xy 314.359799 -276.046756) (xy 314.348022 -275.998972) (xy 314.344062 -275.949918)
			(xy 314.005214 -275.949918) (xy 314.004719 -275.974525) (xy 313.996824 -276.023102) (xy 313.98124 -276.069783)
			(xy 313.958369 -276.11336) (xy 313.928804 -276.152704) (xy 313.893311 -276.186796) (xy 313.852808 -276.214752)
			(xy 313.808346 -276.23585) (xy 313.761075 -276.249542) (xy 313.71222 -276.255474) (xy 313.663045 -276.253493)
			(xy 313.614826 -276.243649) (xy 313.56881 -276.226197) (xy 313.526189 -276.20159) (xy 313.488068 -276.170465)
			(xy 313.455433 -276.133628) (xy 313.42913 -276.092032) (xy 313.409839 -276.046756) (xy 313.398062 -275.998972)
			(xy 313.394102 -275.949918) (xy 313.055254 -275.949918) (xy 313.054759 -275.974525) (xy 313.046864 -276.023102)
			(xy 313.03128 -276.069783) (xy 313.008409 -276.11336) (xy 312.978844 -276.152704) (xy 312.943351 -276.186796)
			(xy 312.902848 -276.214752) (xy 312.858386 -276.23585) (xy 312.811115 -276.249542) (xy 312.76226 -276.255474)
			(xy 312.713085 -276.253493) (xy 312.664866 -276.243649) (xy 312.61885 -276.226197) (xy 312.576229 -276.20159)
			(xy 312.538108 -276.170465) (xy 312.505473 -276.133628) (xy 312.47917 -276.092032) (xy 312.459879 -276.046756)
			(xy 312.448102 -275.998972) (xy 312.444142 -275.949918) (xy 312.12663 -275.949918) (xy 312.126126 -275.975626)
			(xy 312.118083 -276.026408) (xy 312.102195 -276.075307) (xy 312.078852 -276.121119) (xy 312.048631 -276.162715)
			(xy 312.012275 -276.199071) (xy 311.970679 -276.229292) (xy 311.924867 -276.252635) (xy 311.875968 -276.268523)
			(xy 311.825186 -276.276566) (xy 311.77377 -276.276566) (xy 311.722988 -276.268523) (xy 311.674089 -276.252635)
			(xy 311.628277 -276.229292) (xy 311.586681 -276.199071) (xy 311.550325 -276.162715) (xy 311.520104 -276.121119)
			(xy 311.496761 -276.075307) (xy 311.480873 -276.026408) (xy 311.47283 -275.975626) (xy 311.154406 -275.975626)
			(xy 311.14669 -276.023102) (xy 311.131106 -276.069783) (xy 311.108235 -276.11336) (xy 311.07867 -276.152704)
			(xy 311.043177 -276.186796) (xy 311.002674 -276.214752) (xy 310.958212 -276.23585) (xy 310.910941 -276.249542)
			(xy 310.862086 -276.255474) (xy 310.812911 -276.253493) (xy 310.764692 -276.243649) (xy 310.718676 -276.226197)
			(xy 310.676055 -276.20159) (xy 310.637934 -276.170465) (xy 310.605299 -276.133628) (xy 310.578996 -276.092032)
			(xy 310.559705 -276.046756) (xy 310.547928 -275.998972) (xy 310.543968 -275.949918) (xy 310.22671 -275.949918)
			(xy 310.226206 -275.975626) (xy 310.218163 -276.026408) (xy 310.202275 -276.075307) (xy 310.178932 -276.121119)
			(xy 310.148711 -276.162715) (xy 310.112355 -276.199071) (xy 310.070759 -276.229292) (xy 310.024947 -276.252635)
			(xy 309.976048 -276.268523) (xy 309.925266 -276.276566) (xy 309.87385 -276.276566) (xy 309.823068 -276.268523)
			(xy 309.774169 -276.252635) (xy 309.728357 -276.229292) (xy 309.686761 -276.199071) (xy 309.650405 -276.162715)
			(xy 309.620184 -276.121119) (xy 309.596841 -276.075307) (xy 309.580953 -276.026408) (xy 309.57291 -275.975626)
			(xy 309.254486 -275.975626) (xy 309.24677 -276.023102) (xy 309.231186 -276.069783) (xy 309.208315 -276.11336)
			(xy 309.17875 -276.152704) (xy 309.143257 -276.186796) (xy 309.102754 -276.214752) (xy 309.058292 -276.23585)
			(xy 309.011021 -276.249542) (xy 308.962166 -276.255474) (xy 308.912991 -276.253493) (xy 308.864772 -276.243649)
			(xy 308.818756 -276.226197) (xy 308.776135 -276.20159) (xy 308.738014 -276.170465) (xy 308.705379 -276.133628)
			(xy 308.679076 -276.092032) (xy 308.659785 -276.046756) (xy 308.648008 -275.998972) (xy 308.644048 -275.949918)
			(xy 308.326785 -275.949918) (xy 308.326286 -275.975372) (xy 308.318243 -276.026154) (xy 308.302355 -276.075053)
			(xy 308.279012 -276.120865) (xy 308.248791 -276.162461) (xy 308.212435 -276.198817) (xy 308.170839 -276.229038)
			(xy 308.125027 -276.252381) (xy 308.076128 -276.268269) (xy 308.025346 -276.276312) (xy 307.97393 -276.276312)
			(xy 307.923148 -276.268269) (xy 307.874249 -276.252381) (xy 307.828437 -276.229038) (xy 307.786841 -276.198817)
			(xy 307.750485 -276.162461) (xy 307.720264 -276.120865) (xy 307.696921 -276.075053) (xy 307.681033 -276.026154)
			(xy 307.67299 -275.975372) (xy 307.354607 -275.975372) (xy 307.34685 -276.023102) (xy 307.331266 -276.069783)
			(xy 307.308395 -276.11336) (xy 307.27883 -276.152704) (xy 307.243337 -276.186796) (xy 307.202834 -276.214752)
			(xy 307.158372 -276.23585) (xy 307.111101 -276.249542) (xy 307.062246 -276.255474) (xy 307.013071 -276.253493)
			(xy 306.964852 -276.243649) (xy 306.918836 -276.226197) (xy 306.876215 -276.20159) (xy 306.838094 -276.170465)
			(xy 306.805459 -276.133628) (xy 306.779156 -276.092032) (xy 306.759865 -276.046756) (xy 306.748088 -275.998972)
			(xy 306.744128 -275.949918) (xy 306.426616 -275.949918) (xy 306.426112 -275.975626) (xy 306.418069 -276.026408)
			(xy 306.402181 -276.075307) (xy 306.378838 -276.121119) (xy 306.348617 -276.162715) (xy 306.312261 -276.199071)
			(xy 306.270665 -276.229292) (xy 306.224853 -276.252635) (xy 306.175954 -276.268523) (xy 306.125172 -276.276566)
			(xy 306.073756 -276.276566) (xy 306.022974 -276.268523) (xy 305.974075 -276.252635) (xy 305.928263 -276.229292)
			(xy 305.886667 -276.199071) (xy 305.850311 -276.162715) (xy 305.82009 -276.121119) (xy 305.796747 -276.075307)
			(xy 305.780859 -276.026408) (xy 305.772816 -275.975626) (xy 305.454392 -275.975626) (xy 305.446676 -276.023102)
			(xy 305.431092 -276.069783) (xy 305.408221 -276.11336) (xy 305.378656 -276.152704) (xy 305.343163 -276.186796)
			(xy 305.30266 -276.214752) (xy 305.258198 -276.23585) (xy 305.210927 -276.249542) (xy 305.162072 -276.255474)
			(xy 305.112897 -276.253493) (xy 305.064678 -276.243649) (xy 305.018662 -276.226197) (xy 304.976041 -276.20159)
			(xy 304.93792 -276.170465) (xy 304.905285 -276.133628) (xy 304.878982 -276.092032) (xy 304.859691 -276.046756)
			(xy 304.847914 -275.998972) (xy 304.843954 -275.949918) (xy 304.526691 -275.949918) (xy 304.526192 -275.975372)
			(xy 304.518149 -276.026154) (xy 304.502261 -276.075053) (xy 304.478918 -276.120865) (xy 304.448697 -276.162461)
			(xy 304.412341 -276.198817) (xy 304.370745 -276.229038) (xy 304.324933 -276.252381) (xy 304.276034 -276.268269)
			(xy 304.225252 -276.276312) (xy 304.173836 -276.276312) (xy 304.123054 -276.268269) (xy 304.074155 -276.252381)
			(xy 304.028343 -276.229038) (xy 303.986747 -276.198817) (xy 303.950391 -276.162461) (xy 303.92017 -276.120865)
			(xy 303.896827 -276.075053) (xy 303.880939 -276.026154) (xy 303.872896 -275.975372) (xy 303.554513 -275.975372)
			(xy 303.546756 -276.023102) (xy 303.531172 -276.069783) (xy 303.508301 -276.11336) (xy 303.478736 -276.152704)
			(xy 303.443243 -276.186796) (xy 303.40274 -276.214752) (xy 303.358278 -276.23585) (xy 303.311007 -276.249542)
			(xy 303.262152 -276.255474) (xy 303.212977 -276.253493) (xy 303.164758 -276.243649) (xy 303.118742 -276.226197)
			(xy 303.076121 -276.20159) (xy 303.038 -276.170465) (xy 303.005365 -276.133628) (xy 302.979062 -276.092032)
			(xy 302.959771 -276.046756) (xy 302.947994 -275.998972) (xy 302.944034 -275.949918) (xy 302.626522 -275.949918)
			(xy 302.626018 -275.975626) (xy 302.617975 -276.026408) (xy 302.602087 -276.075307) (xy 302.578744 -276.121119)
			(xy 302.548523 -276.162715) (xy 302.512167 -276.199071) (xy 302.470571 -276.229292) (xy 302.424759 -276.252635)
			(xy 302.37586 -276.268523) (xy 302.325078 -276.276566) (xy 302.273662 -276.276566) (xy 302.22288 -276.268523)
			(xy 302.173981 -276.252635) (xy 302.128169 -276.229292) (xy 302.086573 -276.199071) (xy 302.050217 -276.162715)
			(xy 302.019996 -276.121119) (xy 301.996653 -276.075307) (xy 301.980765 -276.026408) (xy 301.972722 -275.975626)
			(xy 301.654552 -275.975626) (xy 301.646836 -276.023102) (xy 301.631252 -276.069783) (xy 301.608381 -276.11336)
			(xy 301.578816 -276.152704) (xy 301.543323 -276.186796) (xy 301.50282 -276.214752) (xy 301.458358 -276.23585)
			(xy 301.411087 -276.249542) (xy 301.362232 -276.255474) (xy 301.313057 -276.253493) (xy 301.264838 -276.243649)
			(xy 301.218822 -276.226197) (xy 301.176201 -276.20159) (xy 301.13808 -276.170465) (xy 301.105445 -276.133628)
			(xy 301.079142 -276.092032) (xy 301.059851 -276.046756) (xy 301.048074 -275.998972) (xy 301.044114 -275.949918)
			(xy 300.726597 -275.949918) (xy 300.726098 -275.975372) (xy 300.718055 -276.026154) (xy 300.702167 -276.075053)
			(xy 300.678824 -276.120865) (xy 300.648603 -276.162461) (xy 300.612247 -276.198817) (xy 300.570651 -276.229038)
			(xy 300.524839 -276.252381) (xy 300.47594 -276.268269) (xy 300.425158 -276.276312) (xy 300.373742 -276.276312)
			(xy 300.32296 -276.268269) (xy 300.274061 -276.252381) (xy 300.228249 -276.229038) (xy 300.186653 -276.198817)
			(xy 300.150297 -276.162461) (xy 300.120076 -276.120865) (xy 300.096733 -276.075053) (xy 300.080845 -276.026154)
			(xy 300.072802 -275.975372) (xy 299.754419 -275.975372) (xy 299.746662 -276.023102) (xy 299.731078 -276.069783)
			(xy 299.708207 -276.11336) (xy 299.678642 -276.152704) (xy 299.643149 -276.186796) (xy 299.602646 -276.214752)
			(xy 299.558184 -276.23585) (xy 299.510913 -276.249542) (xy 299.462058 -276.255474) (xy 299.412883 -276.253493)
			(xy 299.364664 -276.243649) (xy 299.318648 -276.226197) (xy 299.276027 -276.20159) (xy 299.237906 -276.170465)
			(xy 299.205271 -276.133628) (xy 299.178968 -276.092032) (xy 299.159677 -276.046756) (xy 299.1479 -275.998972)
			(xy 299.14394 -275.949918) (xy 298.826682 -275.949918) (xy 298.826178 -275.975626) (xy 298.818135 -276.026408)
			(xy 298.802247 -276.075307) (xy 298.778904 -276.121119) (xy 298.748683 -276.162715) (xy 298.712327 -276.199071)
			(xy 298.670731 -276.229292) (xy 298.624919 -276.252635) (xy 298.57602 -276.268523) (xy 298.525238 -276.276566)
			(xy 298.473822 -276.276566) (xy 298.42304 -276.268523) (xy 298.374141 -276.252635) (xy 298.328329 -276.229292)
			(xy 298.286733 -276.199071) (xy 298.250377 -276.162715) (xy 298.220156 -276.121119) (xy 298.196813 -276.075307)
			(xy 298.180925 -276.026408) (xy 298.172882 -275.975626) (xy 297.854458 -275.975626) (xy 297.846742 -276.023102)
			(xy 297.831158 -276.069783) (xy 297.808287 -276.11336) (xy 297.778722 -276.152704) (xy 297.743229 -276.186796)
			(xy 297.702726 -276.214752) (xy 297.658264 -276.23585) (xy 297.610993 -276.249542) (xy 297.562138 -276.255474)
			(xy 297.512963 -276.253493) (xy 297.464744 -276.243649) (xy 297.418728 -276.226197) (xy 297.376107 -276.20159)
			(xy 297.337986 -276.170465) (xy 297.305351 -276.133628) (xy 297.279048 -276.092032) (xy 297.259757 -276.046756)
			(xy 297.24798 -275.998972) (xy 297.24402 -275.949918) (xy 296.926757 -275.949918) (xy 296.926258 -275.975372)
			(xy 296.918215 -276.026154) (xy 296.902327 -276.075053) (xy 296.878984 -276.120865) (xy 296.848763 -276.162461)
			(xy 296.812407 -276.198817) (xy 296.770811 -276.229038) (xy 296.724999 -276.252381) (xy 296.6761 -276.268269)
			(xy 296.625318 -276.276312) (xy 296.573902 -276.276312) (xy 296.52312 -276.268269) (xy 296.474221 -276.252381)
			(xy 296.428409 -276.229038) (xy 296.386813 -276.198817) (xy 296.350457 -276.162461) (xy 296.320236 -276.120865)
			(xy 296.296893 -276.075053) (xy 296.281005 -276.026154) (xy 296.272962 -275.975372) (xy 295.954579 -275.975372)
			(xy 295.946822 -276.023102) (xy 295.931238 -276.069783) (xy 295.908367 -276.11336) (xy 295.878802 -276.152704)
			(xy 295.843309 -276.186796) (xy 295.802806 -276.214752) (xy 295.758344 -276.23585) (xy 295.711073 -276.249542)
			(xy 295.662218 -276.255474) (xy 295.613043 -276.253493) (xy 295.564824 -276.243649) (xy 295.518808 -276.226197)
			(xy 295.476187 -276.20159) (xy 295.438066 -276.170465) (xy 295.405431 -276.133628) (xy 295.379128 -276.092032)
			(xy 295.359837 -276.046756) (xy 295.34806 -275.998972) (xy 295.3441 -275.949918) (xy 295.026588 -275.949918)
			(xy 295.026084 -275.975626) (xy 295.018041 -276.026408) (xy 295.002153 -276.075307) (xy 294.97881 -276.121119)
			(xy 294.948589 -276.162715) (xy 294.912233 -276.199071) (xy 294.870637 -276.229292) (xy 294.824825 -276.252635)
			(xy 294.775926 -276.268523) (xy 294.725144 -276.276566) (xy 294.673728 -276.276566) (xy 294.622946 -276.268523)
			(xy 294.574047 -276.252635) (xy 294.528235 -276.229292) (xy 294.486639 -276.199071) (xy 294.450283 -276.162715)
			(xy 294.420062 -276.121119) (xy 294.396719 -276.075307) (xy 294.380831 -276.026408) (xy 294.372788 -275.975626)
			(xy 294.054364 -275.975626) (xy 294.046648 -276.023102) (xy 294.031064 -276.069783) (xy 294.008193 -276.11336)
			(xy 293.978628 -276.152704) (xy 293.943135 -276.186796) (xy 293.902632 -276.214752) (xy 293.85817 -276.23585)
			(xy 293.810899 -276.249542) (xy 293.762044 -276.255474) (xy 293.712869 -276.253493) (xy 293.66465 -276.243649)
			(xy 293.618634 -276.226197) (xy 293.576013 -276.20159) (xy 293.537892 -276.170465) (xy 293.505257 -276.133628)
			(xy 293.478954 -276.092032) (xy 293.459663 -276.046756) (xy 293.447886 -275.998972) (xy 293.443926 -275.949918)
			(xy 293.126663 -275.949918) (xy 293.126164 -275.975372) (xy 293.118121 -276.026154) (xy 293.102233 -276.075053)
			(xy 293.07889 -276.120865) (xy 293.048669 -276.162461) (xy 293.012313 -276.198817) (xy 292.970717 -276.229038)
			(xy 292.924905 -276.252381) (xy 292.876006 -276.268269) (xy 292.825224 -276.276312) (xy 292.773808 -276.276312)
			(xy 292.723026 -276.268269) (xy 292.674127 -276.252381) (xy 292.628315 -276.229038) (xy 292.586719 -276.198817)
			(xy 292.550363 -276.162461) (xy 292.520142 -276.120865) (xy 292.496799 -276.075053) (xy 292.480911 -276.026154)
			(xy 292.472868 -275.975372) (xy 292.154485 -275.975372) (xy 292.146728 -276.023102) (xy 292.131144 -276.069783)
			(xy 292.108273 -276.11336) (xy 292.078708 -276.152704) (xy 292.043215 -276.186796) (xy 292.002712 -276.214752)
			(xy 291.95825 -276.23585) (xy 291.910979 -276.249542) (xy 291.862124 -276.255474) (xy 291.812949 -276.253493)
			(xy 291.76473 -276.243649) (xy 291.718714 -276.226197) (xy 291.676093 -276.20159) (xy 291.637972 -276.170465)
			(xy 291.605337 -276.133628) (xy 291.579034 -276.092032) (xy 291.559743 -276.046756) (xy 291.547966 -275.998972)
			(xy 291.544006 -275.949918) (xy 291.227002 -275.949918) (xy 291.226498 -275.975626) (xy 291.218455 -276.026408)
			(xy 291.202567 -276.075307) (xy 291.179224 -276.121119) (xy 291.149003 -276.162715) (xy 291.112647 -276.199071)
			(xy 291.071051 -276.229292) (xy 291.025239 -276.252635) (xy 290.97634 -276.268523) (xy 290.925558 -276.276566)
			(xy 290.874142 -276.276566) (xy 290.82336 -276.268523) (xy 290.774461 -276.252635) (xy 290.728649 -276.229292)
			(xy 290.687053 -276.199071) (xy 290.650697 -276.162715) (xy 290.620476 -276.121119) (xy 290.597133 -276.075307)
			(xy 290.581245 -276.026408) (xy 290.573202 -275.975626) (xy 290.254524 -275.975626) (xy 290.246808 -276.023102)
			(xy 290.231224 -276.069783) (xy 290.208353 -276.11336) (xy 290.178788 -276.152704) (xy 290.143295 -276.186796)
			(xy 290.102792 -276.214752) (xy 290.05833 -276.23585) (xy 290.011059 -276.249542) (xy 289.962204 -276.255474)
			(xy 289.913029 -276.253493) (xy 289.86481 -276.243649) (xy 289.818794 -276.226197) (xy 289.776173 -276.20159)
			(xy 289.738052 -276.170465) (xy 289.705417 -276.133628) (xy 289.679114 -276.092032) (xy 289.659823 -276.046756)
			(xy 289.648046 -275.998972) (xy 289.644086 -275.949918) (xy 289.327082 -275.949918) (xy 289.326578 -275.975626)
			(xy 289.318535 -276.026408) (xy 289.302647 -276.075307) (xy 289.279304 -276.121119) (xy 289.249083 -276.162715)
			(xy 289.212727 -276.199071) (xy 289.171131 -276.229292) (xy 289.125319 -276.252635) (xy 289.07642 -276.268523)
			(xy 289.025638 -276.276566) (xy 288.974222 -276.276566) (xy 288.92344 -276.268523) (xy 288.874541 -276.252635)
			(xy 288.828729 -276.229292) (xy 288.787133 -276.199071) (xy 288.750777 -276.162715) (xy 288.720556 -276.121119)
			(xy 288.697213 -276.075307) (xy 288.681325 -276.026408) (xy 288.673282 -275.975626) (xy 288.35435 -275.975626)
			(xy 288.346634 -276.023102) (xy 288.33105 -276.069783) (xy 288.308179 -276.11336) (xy 288.278614 -276.152704)
			(xy 288.243121 -276.186796) (xy 288.202618 -276.214752) (xy 288.158156 -276.23585) (xy 288.110885 -276.249542)
			(xy 288.06203 -276.255474) (xy 288.012855 -276.253493) (xy 287.964636 -276.243649) (xy 287.91862 -276.226197)
			(xy 287.875999 -276.20159) (xy 287.837878 -276.170465) (xy 287.805243 -276.133628) (xy 287.77894 -276.092032)
			(xy 287.759649 -276.046756) (xy 287.747872 -275.998972) (xy 287.743912 -275.949918) (xy 287.426908 -275.949918)
			(xy 287.426404 -275.975626) (xy 287.418361 -276.026408) (xy 287.402473 -276.075307) (xy 287.37913 -276.121119)
			(xy 287.348909 -276.162715) (xy 287.312553 -276.199071) (xy 287.270957 -276.229292) (xy 287.225145 -276.252635)
			(xy 287.176246 -276.268523) (xy 287.125464 -276.276566) (xy 287.074048 -276.276566) (xy 287.023266 -276.268523)
			(xy 286.974367 -276.252635) (xy 286.928555 -276.229292) (xy 286.886959 -276.199071) (xy 286.850603 -276.162715)
			(xy 286.820382 -276.121119) (xy 286.797039 -276.075307) (xy 286.781151 -276.026408) (xy 286.773108 -275.975626)
			(xy 286.45443 -275.975626) (xy 286.446714 -276.023102) (xy 286.43113 -276.069783) (xy 286.408259 -276.11336)
			(xy 286.378694 -276.152704) (xy 286.343201 -276.186796) (xy 286.302698 -276.214752) (xy 286.258236 -276.23585)
			(xy 286.210965 -276.249542) (xy 286.16211 -276.255474) (xy 286.112935 -276.253493) (xy 286.064716 -276.243649)
			(xy 286.0187 -276.226197) (xy 285.976079 -276.20159) (xy 285.937958 -276.170465) (xy 285.905323 -276.133628)
			(xy 285.87902 -276.092032) (xy 285.859729 -276.046756) (xy 285.847952 -275.998972) (xy 285.843992 -275.949918)
			(xy 285.526988 -275.949918) (xy 285.526484 -275.975626) (xy 285.518441 -276.026408) (xy 285.502553 -276.075307)
			(xy 285.47921 -276.121119) (xy 285.448989 -276.162715) (xy 285.412633 -276.199071) (xy 285.371037 -276.229292)
			(xy 285.325225 -276.252635) (xy 285.276326 -276.268523) (xy 285.225544 -276.276566) (xy 285.174128 -276.276566)
			(xy 285.123346 -276.268523) (xy 285.074447 -276.252635) (xy 285.028635 -276.229292) (xy 284.987039 -276.199071)
			(xy 284.950683 -276.162715) (xy 284.920462 -276.121119) (xy 284.897119 -276.075307) (xy 284.881231 -276.026408)
			(xy 284.873188 -275.975626) (xy 284.55451 -275.975626) (xy 284.546794 -276.023102) (xy 284.53121 -276.069783)
			(xy 284.508339 -276.11336) (xy 284.478774 -276.152704) (xy 284.443281 -276.186796) (xy 284.402778 -276.214752)
			(xy 284.358316 -276.23585) (xy 284.311045 -276.249542) (xy 284.26219 -276.255474) (xy 284.213015 -276.253493)
			(xy 284.164796 -276.243649) (xy 284.11878 -276.226197) (xy 284.076159 -276.20159) (xy 284.038038 -276.170465)
			(xy 284.005403 -276.133628) (xy 283.9791 -276.092032) (xy 283.959809 -276.046756) (xy 283.948032 -275.998972)
			(xy 283.944072 -275.949918) (xy 283.627068 -275.949918) (xy 283.626564 -275.975626) (xy 283.618521 -276.026408)
			(xy 283.602633 -276.075307) (xy 283.57929 -276.121119) (xy 283.549069 -276.162715) (xy 283.512713 -276.199071)
			(xy 283.471117 -276.229292) (xy 283.425305 -276.252635) (xy 283.376406 -276.268523) (xy 283.325624 -276.276566)
			(xy 283.274208 -276.276566) (xy 283.223426 -276.268523) (xy 283.174527 -276.252635) (xy 283.128715 -276.229292)
			(xy 283.087119 -276.199071) (xy 283.050763 -276.162715) (xy 283.020542 -276.121119) (xy 282.997199 -276.075307)
			(xy 282.981311 -276.026408) (xy 282.973268 -275.975626) (xy 282.653381 -275.975626) (xy 282.651342 -276.000235)
			(xy 282.638943 -276.049197) (xy 282.618655 -276.09545) (xy 282.59103 -276.137734) (xy 282.556822 -276.174893)
			(xy 282.516965 -276.205916) (xy 282.472545 -276.229955) (xy 282.424774 -276.246355) (xy 282.374956 -276.254668)
			(xy 282.349702 -276.255226) (xy 282.33552 -276.25504) (xy 282.30728 -276.252366) (xy 282.293314 -276.249892)
			(xy 282.280868 -276.247606) (xy 282.257246 -276.254972) (xy 282.179776 -276.332442) (xy 282.17241 -276.356064)
			(xy 282.174696 -276.36851) (xy 282.177181 -276.382475) (xy 282.179853 -276.410715) (xy 282.18003 -276.424898)
			(xy 282.179844 -276.43908) (xy 282.17717 -276.46732) (xy 282.174696 -276.481286) (xy 282.17241 -276.493732)
			(xy 282.179776 -276.517354) (xy 282.257246 -276.594824) (xy 282.280868 -276.60219) (xy 282.293314 -276.599904)
			(xy 282.307279 -276.597419) (xy 282.335519 -276.594747) (xy 282.349702 -276.59457) (xy 282.374959 -276.595092)
			(xy 282.424784 -276.603406) (xy 282.472561 -276.619809) (xy 282.516987 -276.643851) (xy 282.556849 -276.674877)
			(xy 282.591062 -276.712042) (xy 282.61869 -276.754331) (xy 282.638981 -276.80059) (xy 282.651382 -276.849558)
			(xy 282.655551 -276.899878) (xy 282.994112 -276.899878) (xy 282.998072 -276.850824) (xy 283.009849 -276.80304)
			(xy 283.02914 -276.757764) (xy 283.055443 -276.716168) (xy 283.088078 -276.679331) (xy 283.126199 -276.648206)
			(xy 283.16882 -276.623599) (xy 283.214836 -276.606147) (xy 283.263055 -276.596303) (xy 283.31223 -276.594322)
			(xy 283.361085 -276.600254) (xy 283.408356 -276.613946) (xy 283.452818 -276.635044) (xy 283.493321 -276.663)
			(xy 283.528814 -276.697092) (xy 283.558379 -276.736436) (xy 283.58125 -276.780013) (xy 283.596834 -276.826694)
			(xy 283.604729 -276.875271) (xy 283.605224 -276.899878) (xy 283.944072 -276.899878) (xy 283.948032 -276.850824)
			(xy 283.959809 -276.80304) (xy 283.9791 -276.757764) (xy 284.005403 -276.716168) (xy 284.038038 -276.679331)
			(xy 284.076159 -276.648206) (xy 284.11878 -276.623599) (xy 284.164796 -276.606147) (xy 284.213015 -276.596303)
			(xy 284.26219 -276.594322) (xy 284.311045 -276.600254) (xy 284.358316 -276.613946) (xy 284.402778 -276.635044)
			(xy 284.443281 -276.663) (xy 284.478774 -276.697092) (xy 284.508339 -276.736436) (xy 284.53121 -276.780013)
			(xy 284.546794 -276.826694) (xy 284.554689 -276.875271) (xy 284.555184 -276.899878) (xy 284.894032 -276.899878)
			(xy 284.897992 -276.850824) (xy 284.909769 -276.80304) (xy 284.92906 -276.757764) (xy 284.955363 -276.716168)
			(xy 284.987998 -276.679331) (xy 285.026119 -276.648206) (xy 285.06874 -276.623599) (xy 285.114756 -276.606147)
			(xy 285.162975 -276.596303) (xy 285.21215 -276.594322) (xy 285.261005 -276.600254) (xy 285.308276 -276.613946)
			(xy 285.352738 -276.635044) (xy 285.393241 -276.663) (xy 285.428734 -276.697092) (xy 285.458299 -276.736436)
			(xy 285.48117 -276.780013) (xy 285.496754 -276.826694) (xy 285.504649 -276.875271) (xy 285.505144 -276.899878)
			(xy 285.843992 -276.899878) (xy 285.847952 -276.850824) (xy 285.859729 -276.80304) (xy 285.87902 -276.757764)
			(xy 285.905323 -276.716168) (xy 285.937958 -276.679331) (xy 285.976079 -276.648206) (xy 286.0187 -276.623599)
			(xy 286.064716 -276.606147) (xy 286.112935 -276.596303) (xy 286.16211 -276.594322) (xy 286.210965 -276.600254)
			(xy 286.258236 -276.613946) (xy 286.302698 -276.635044) (xy 286.343201 -276.663) (xy 286.378694 -276.697092)
			(xy 286.408259 -276.736436) (xy 286.43113 -276.780013) (xy 286.446714 -276.826694) (xy 286.454609 -276.875271)
			(xy 286.455104 -276.899878) (xy 286.793952 -276.899878) (xy 286.797912 -276.850824) (xy 286.809689 -276.80304)
			(xy 286.82898 -276.757764) (xy 286.855283 -276.716168) (xy 286.887918 -276.679331) (xy 286.926039 -276.648206)
			(xy 286.96866 -276.623599) (xy 287.014676 -276.606147) (xy 287.062895 -276.596303) (xy 287.11207 -276.594322)
			(xy 287.160925 -276.600254) (xy 287.208196 -276.613946) (xy 287.252658 -276.635044) (xy 287.293161 -276.663)
			(xy 287.328654 -276.697092) (xy 287.358219 -276.736436) (xy 287.38109 -276.780013) (xy 287.396674 -276.826694)
			(xy 287.404569 -276.875271) (xy 287.405064 -276.899878) (xy 287.743912 -276.899878) (xy 287.747872 -276.850824)
			(xy 287.759649 -276.80304) (xy 287.77894 -276.757764) (xy 287.805243 -276.716168) (xy 287.837878 -276.679331)
			(xy 287.875999 -276.648206) (xy 287.91862 -276.623599) (xy 287.964636 -276.606147) (xy 288.012855 -276.596303)
			(xy 288.06203 -276.594322) (xy 288.110885 -276.600254) (xy 288.158156 -276.613946) (xy 288.202618 -276.635044)
			(xy 288.243121 -276.663) (xy 288.278614 -276.697092) (xy 288.308179 -276.736436) (xy 288.33105 -276.780013)
			(xy 288.346634 -276.826694) (xy 288.354529 -276.875271) (xy 288.355024 -276.899878) (xy 288.694126 -276.899878)
			(xy 288.698086 -276.850824) (xy 288.709863 -276.80304) (xy 288.729154 -276.757764) (xy 288.755457 -276.716168)
			(xy 288.788092 -276.679331) (xy 288.826213 -276.648206) (xy 288.868834 -276.623599) (xy 288.91485 -276.606147)
			(xy 288.963069 -276.596303) (xy 289.012244 -276.594322) (xy 289.061099 -276.600254) (xy 289.10837 -276.613946)
			(xy 289.152832 -276.635044) (xy 289.193335 -276.663) (xy 289.228828 -276.697092) (xy 289.258393 -276.736436)
			(xy 289.281264 -276.780013) (xy 289.296848 -276.826694) (xy 289.304743 -276.875271) (xy 289.305238 -276.899878)
			(xy 289.644086 -276.899878) (xy 289.648046 -276.850824) (xy 289.659823 -276.80304) (xy 289.679114 -276.757764)
			(xy 289.705417 -276.716168) (xy 289.738052 -276.679331) (xy 289.776173 -276.648206) (xy 289.818794 -276.623599)
			(xy 289.86481 -276.606147) (xy 289.913029 -276.596303) (xy 289.962204 -276.594322) (xy 290.011059 -276.600254)
			(xy 290.05833 -276.613946) (xy 290.102792 -276.635044) (xy 290.143295 -276.663) (xy 290.178788 -276.697092)
			(xy 290.208353 -276.736436) (xy 290.231224 -276.780013) (xy 290.246808 -276.826694) (xy 290.254703 -276.875271)
			(xy 290.255198 -276.899878) (xy 290.594046 -276.899878) (xy 290.598006 -276.850824) (xy 290.609783 -276.80304)
			(xy 290.629074 -276.757764) (xy 290.655377 -276.716168) (xy 290.688012 -276.679331) (xy 290.726133 -276.648206)
			(xy 290.768754 -276.623599) (xy 290.81477 -276.606147) (xy 290.862989 -276.596303) (xy 290.912164 -276.594322)
			(xy 290.961019 -276.600254) (xy 291.00829 -276.613946) (xy 291.052752 -276.635044) (xy 291.093255 -276.663)
			(xy 291.128748 -276.697092) (xy 291.158313 -276.736436) (xy 291.181184 -276.780013) (xy 291.196768 -276.826694)
			(xy 291.204663 -276.875271) (xy 291.205158 -276.899878) (xy 291.544006 -276.899878) (xy 291.547966 -276.850824)
			(xy 291.559743 -276.80304) (xy 291.579034 -276.757764) (xy 291.605337 -276.716168) (xy 291.637972 -276.679331)
			(xy 291.676093 -276.648206) (xy 291.718714 -276.623599) (xy 291.76473 -276.606147) (xy 291.812949 -276.596303)
			(xy 291.862124 -276.594322) (xy 291.910979 -276.600254) (xy 291.95825 -276.613946) (xy 292.002712 -276.635044)
			(xy 292.043215 -276.663) (xy 292.078708 -276.697092) (xy 292.108273 -276.736436) (xy 292.131144 -276.780013)
			(xy 292.146728 -276.826694) (xy 292.154623 -276.875271) (xy 292.155118 -276.899878) (xy 292.493966 -276.899878)
			(xy 292.497926 -276.850824) (xy 292.509703 -276.80304) (xy 292.528994 -276.757764) (xy 292.555297 -276.716168)
			(xy 292.587932 -276.679331) (xy 292.626053 -276.648206) (xy 292.668674 -276.623599) (xy 292.71469 -276.606147)
			(xy 292.762909 -276.596303) (xy 292.812084 -276.594322) (xy 292.860939 -276.600254) (xy 292.90821 -276.613946)
			(xy 292.952672 -276.635044) (xy 292.993175 -276.663) (xy 293.028668 -276.697092) (xy 293.058233 -276.736436)
			(xy 293.081104 -276.780013) (xy 293.096688 -276.826694) (xy 293.104583 -276.875271) (xy 293.105078 -276.899878)
			(xy 293.443926 -276.899878) (xy 293.447886 -276.850824) (xy 293.459663 -276.80304) (xy 293.478954 -276.757764)
			(xy 293.505257 -276.716168) (xy 293.537892 -276.679331) (xy 293.576013 -276.648206) (xy 293.618634 -276.623599)
			(xy 293.66465 -276.606147) (xy 293.712869 -276.596303) (xy 293.762044 -276.594322) (xy 293.810899 -276.600254)
			(xy 293.85817 -276.613946) (xy 293.902632 -276.635044) (xy 293.943135 -276.663) (xy 293.978628 -276.697092)
			(xy 294.008193 -276.736436) (xy 294.031064 -276.780013) (xy 294.046648 -276.826694) (xy 294.054543 -276.875271)
			(xy 294.055038 -276.899878) (xy 294.393886 -276.899878) (xy 294.397846 -276.850824) (xy 294.409623 -276.80304)
			(xy 294.428914 -276.757764) (xy 294.455217 -276.716168) (xy 294.487852 -276.679331) (xy 294.525973 -276.648206)
			(xy 294.568594 -276.623599) (xy 294.61461 -276.606147) (xy 294.662829 -276.596303) (xy 294.712004 -276.594322)
			(xy 294.760859 -276.600254) (xy 294.80813 -276.613946) (xy 294.852592 -276.635044) (xy 294.893095 -276.663)
			(xy 294.928588 -276.697092) (xy 294.958153 -276.736436) (xy 294.981024 -276.780013) (xy 294.996608 -276.826694)
			(xy 295.004503 -276.875271) (xy 295.004998 -276.899878) (xy 295.3441 -276.899878) (xy 295.34806 -276.850824)
			(xy 295.359837 -276.80304) (xy 295.379128 -276.757764) (xy 295.405431 -276.716168) (xy 295.438066 -276.679331)
			(xy 295.476187 -276.648206) (xy 295.518808 -276.623599) (xy 295.564824 -276.606147) (xy 295.613043 -276.596303)
			(xy 295.662218 -276.594322) (xy 295.711073 -276.600254) (xy 295.758344 -276.613946) (xy 295.802806 -276.635044)
			(xy 295.843309 -276.663) (xy 295.878802 -276.697092) (xy 295.908367 -276.736436) (xy 295.931238 -276.780013)
			(xy 295.946822 -276.826694) (xy 295.954717 -276.875271) (xy 295.955212 -276.899878) (xy 296.29406 -276.899878)
			(xy 296.29802 -276.850824) (xy 296.309797 -276.80304) (xy 296.329088 -276.757764) (xy 296.355391 -276.716168)
			(xy 296.388026 -276.679331) (xy 296.426147 -276.648206) (xy 296.468768 -276.623599) (xy 296.514784 -276.606147)
			(xy 296.563003 -276.596303) (xy 296.612178 -276.594322) (xy 296.661033 -276.600254) (xy 296.708304 -276.613946)
			(xy 296.752766 -276.635044) (xy 296.793269 -276.663) (xy 296.828762 -276.697092) (xy 296.858327 -276.736436)
			(xy 296.881198 -276.780013) (xy 296.896782 -276.826694) (xy 296.904677 -276.875271) (xy 296.905172 -276.899878)
			(xy 297.24402 -276.899878) (xy 297.24798 -276.850824) (xy 297.259757 -276.80304) (xy 297.279048 -276.757764)
			(xy 297.305351 -276.716168) (xy 297.337986 -276.679331) (xy 297.376107 -276.648206) (xy 297.418728 -276.623599)
			(xy 297.464744 -276.606147) (xy 297.512963 -276.596303) (xy 297.562138 -276.594322) (xy 297.610993 -276.600254)
			(xy 297.658264 -276.613946) (xy 297.702726 -276.635044) (xy 297.743229 -276.663) (xy 297.778722 -276.697092)
			(xy 297.808287 -276.736436) (xy 297.831158 -276.780013) (xy 297.846742 -276.826694) (xy 297.854637 -276.875271)
			(xy 297.855132 -276.899878) (xy 298.19398 -276.899878) (xy 298.19794 -276.850824) (xy 298.209717 -276.80304)
			(xy 298.229008 -276.757764) (xy 298.255311 -276.716168) (xy 298.287946 -276.679331) (xy 298.326067 -276.648206)
			(xy 298.368688 -276.623599) (xy 298.414704 -276.606147) (xy 298.462923 -276.596303) (xy 298.512098 -276.594322)
			(xy 298.560953 -276.600254) (xy 298.608224 -276.613946) (xy 298.652686 -276.635044) (xy 298.693189 -276.663)
			(xy 298.728682 -276.697092) (xy 298.758247 -276.736436) (xy 298.781118 -276.780013) (xy 298.796702 -276.826694)
			(xy 298.804597 -276.875271) (xy 298.805092 -276.899878) (xy 299.14394 -276.899878) (xy 299.1479 -276.850824)
			(xy 299.159677 -276.80304) (xy 299.178968 -276.757764) (xy 299.205271 -276.716168) (xy 299.237906 -276.679331)
			(xy 299.276027 -276.648206) (xy 299.318648 -276.623599) (xy 299.364664 -276.606147) (xy 299.412883 -276.596303)
			(xy 299.462058 -276.594322) (xy 299.510913 -276.600254) (xy 299.558184 -276.613946) (xy 299.602646 -276.635044)
			(xy 299.643149 -276.663) (xy 299.678642 -276.697092) (xy 299.708207 -276.736436) (xy 299.731078 -276.780013)
			(xy 299.746662 -276.826694) (xy 299.754557 -276.875271) (xy 299.755052 -276.899878) (xy 300.0939 -276.899878)
			(xy 300.09786 -276.850824) (xy 300.109637 -276.80304) (xy 300.128928 -276.757764) (xy 300.155231 -276.716168)
			(xy 300.187866 -276.679331) (xy 300.225987 -276.648206) (xy 300.268608 -276.623599) (xy 300.314624 -276.606147)
			(xy 300.362843 -276.596303) (xy 300.412018 -276.594322) (xy 300.460873 -276.600254) (xy 300.508144 -276.613946)
			(xy 300.552606 -276.635044) (xy 300.593109 -276.663) (xy 300.628602 -276.697092) (xy 300.658167 -276.736436)
			(xy 300.681038 -276.780013) (xy 300.696622 -276.826694) (xy 300.704517 -276.875271) (xy 300.705012 -276.899878)
			(xy 301.044114 -276.899878) (xy 301.048074 -276.850824) (xy 301.059851 -276.80304) (xy 301.079142 -276.757764)
			(xy 301.105445 -276.716168) (xy 301.13808 -276.679331) (xy 301.176201 -276.648206) (xy 301.218822 -276.623599)
			(xy 301.264838 -276.606147) (xy 301.313057 -276.596303) (xy 301.362232 -276.594322) (xy 301.411087 -276.600254)
			(xy 301.458358 -276.613946) (xy 301.50282 -276.635044) (xy 301.543323 -276.663) (xy 301.578816 -276.697092)
			(xy 301.608381 -276.736436) (xy 301.631252 -276.780013) (xy 301.646836 -276.826694) (xy 301.654731 -276.875271)
			(xy 301.655226 -276.899878) (xy 301.994074 -276.899878) (xy 301.998034 -276.850824) (xy 302.009811 -276.80304)
			(xy 302.029102 -276.757764) (xy 302.055405 -276.716168) (xy 302.08804 -276.679331) (xy 302.126161 -276.648206)
			(xy 302.168782 -276.623599) (xy 302.214798 -276.606147) (xy 302.263017 -276.596303) (xy 302.312192 -276.594322)
			(xy 302.361047 -276.600254) (xy 302.408318 -276.613946) (xy 302.45278 -276.635044) (xy 302.493283 -276.663)
			(xy 302.528776 -276.697092) (xy 302.558341 -276.736436) (xy 302.581212 -276.780013) (xy 302.596796 -276.826694)
			(xy 302.604691 -276.875271) (xy 302.605186 -276.899878) (xy 302.944034 -276.899878) (xy 302.947994 -276.850824)
			(xy 302.959771 -276.80304) (xy 302.979062 -276.757764) (xy 303.005365 -276.716168) (xy 303.038 -276.679331)
			(xy 303.076121 -276.648206) (xy 303.118742 -276.623599) (xy 303.164758 -276.606147) (xy 303.212977 -276.596303)
			(xy 303.262152 -276.594322) (xy 303.311007 -276.600254) (xy 303.358278 -276.613946) (xy 303.40274 -276.635044)
			(xy 303.443243 -276.663) (xy 303.478736 -276.697092) (xy 303.508301 -276.736436) (xy 303.531172 -276.780013)
			(xy 303.546756 -276.826694) (xy 303.554651 -276.875271) (xy 303.555146 -276.899878) (xy 303.893994 -276.899878)
			(xy 303.897954 -276.850824) (xy 303.909731 -276.80304) (xy 303.929022 -276.757764) (xy 303.955325 -276.716168)
			(xy 303.98796 -276.679331) (xy 304.026081 -276.648206) (xy 304.068702 -276.623599) (xy 304.114718 -276.606147)
			(xy 304.162937 -276.596303) (xy 304.212112 -276.594322) (xy 304.260967 -276.600254) (xy 304.308238 -276.613946)
			(xy 304.3527 -276.635044) (xy 304.393203 -276.663) (xy 304.428696 -276.697092) (xy 304.458261 -276.736436)
			(xy 304.481132 -276.780013) (xy 304.496716 -276.826694) (xy 304.504611 -276.875271) (xy 304.505106 -276.899878)
			(xy 304.843954 -276.899878) (xy 304.847914 -276.850824) (xy 304.859691 -276.80304) (xy 304.878982 -276.757764)
			(xy 304.905285 -276.716168) (xy 304.93792 -276.679331) (xy 304.976041 -276.648206) (xy 305.018662 -276.623599)
			(xy 305.064678 -276.606147) (xy 305.112897 -276.596303) (xy 305.162072 -276.594322) (xy 305.210927 -276.600254)
			(xy 305.258198 -276.613946) (xy 305.30266 -276.635044) (xy 305.343163 -276.663) (xy 305.378656 -276.697092)
			(xy 305.408221 -276.736436) (xy 305.431092 -276.780013) (xy 305.446676 -276.826694) (xy 305.454571 -276.875271)
			(xy 305.455066 -276.899878) (xy 305.79366 -276.899878) (xy 305.79762 -276.850824) (xy 305.809397 -276.80304)
			(xy 305.828688 -276.757764) (xy 305.854991 -276.716168) (xy 305.887626 -276.679331) (xy 305.925747 -276.648206)
			(xy 305.968368 -276.623599) (xy 306.014384 -276.606147) (xy 306.062603 -276.596303) (xy 306.111778 -276.594322)
			(xy 306.160633 -276.600254) (xy 306.207904 -276.613946) (xy 306.252366 -276.635044) (xy 306.292869 -276.663)
			(xy 306.328362 -276.697092) (xy 306.357927 -276.736436) (xy 306.380798 -276.780013) (xy 306.396382 -276.826694)
			(xy 306.404277 -276.875271) (xy 306.404772 -276.899878) (xy 306.743874 -276.899878) (xy 306.747834 -276.850824)
			(xy 306.759611 -276.80304) (xy 306.778902 -276.757764) (xy 306.805205 -276.716168) (xy 306.83784 -276.679331)
			(xy 306.875961 -276.648206) (xy 306.918582 -276.623599) (xy 306.964598 -276.606147) (xy 307.012817 -276.596303)
			(xy 307.061992 -276.594322) (xy 307.110847 -276.600254) (xy 307.158118 -276.613946) (xy 307.20258 -276.635044)
			(xy 307.243083 -276.663) (xy 307.278576 -276.697092) (xy 307.308141 -276.736436) (xy 307.331012 -276.780013)
			(xy 307.346596 -276.826694) (xy 307.354491 -276.875271) (xy 307.354986 -276.899878) (xy 307.693834 -276.899878)
			(xy 307.697794 -276.850824) (xy 307.709571 -276.80304) (xy 307.728862 -276.757764) (xy 307.755165 -276.716168)
			(xy 307.7878 -276.679331) (xy 307.825921 -276.648206) (xy 307.868542 -276.623599) (xy 307.914558 -276.606147)
			(xy 307.962777 -276.596303) (xy 308.011952 -276.594322) (xy 308.060807 -276.600254) (xy 308.108078 -276.613946)
			(xy 308.15254 -276.635044) (xy 308.193043 -276.663) (xy 308.228536 -276.697092) (xy 308.258101 -276.736436)
			(xy 308.280972 -276.780013) (xy 308.296556 -276.826694) (xy 308.304451 -276.875271) (xy 308.304946 -276.899878)
			(xy 308.643794 -276.899878) (xy 308.647754 -276.850824) (xy 308.659531 -276.80304) (xy 308.678822 -276.757764)
			(xy 308.705125 -276.716168) (xy 308.73776 -276.679331) (xy 308.775881 -276.648206) (xy 308.818502 -276.623599)
			(xy 308.864518 -276.606147) (xy 308.912737 -276.596303) (xy 308.961912 -276.594322) (xy 309.010767 -276.600254)
			(xy 309.058038 -276.613946) (xy 309.1025 -276.635044) (xy 309.143003 -276.663) (xy 309.178496 -276.697092)
			(xy 309.208061 -276.736436) (xy 309.230932 -276.780013) (xy 309.246516 -276.826694) (xy 309.254411 -276.875271)
			(xy 309.254906 -276.899878) (xy 309.593754 -276.899878) (xy 309.597714 -276.850824) (xy 309.609491 -276.80304)
			(xy 309.628782 -276.757764) (xy 309.655085 -276.716168) (xy 309.68772 -276.679331) (xy 309.725841 -276.648206)
			(xy 309.768462 -276.623599) (xy 309.814478 -276.606147) (xy 309.862697 -276.596303) (xy 309.911872 -276.594322)
			(xy 309.960727 -276.600254) (xy 310.007998 -276.613946) (xy 310.05246 -276.635044) (xy 310.092963 -276.663)
			(xy 310.128456 -276.697092) (xy 310.158021 -276.736436) (xy 310.180892 -276.780013) (xy 310.196476 -276.826694)
			(xy 310.204371 -276.875271) (xy 310.204866 -276.899878) (xy 310.543714 -276.899878) (xy 310.547674 -276.850824)
			(xy 310.559451 -276.80304) (xy 310.578742 -276.757764) (xy 310.605045 -276.716168) (xy 310.63768 -276.679331)
			(xy 310.675801 -276.648206) (xy 310.718422 -276.623599) (xy 310.764438 -276.606147) (xy 310.812657 -276.596303)
			(xy 310.861832 -276.594322) (xy 310.910687 -276.600254) (xy 310.957958 -276.613946) (xy 311.00242 -276.635044)
			(xy 311.042923 -276.663) (xy 311.078416 -276.697092) (xy 311.107981 -276.736436) (xy 311.130852 -276.780013)
			(xy 311.146436 -276.826694) (xy 311.154331 -276.875271) (xy 311.154826 -276.899878) (xy 311.493674 -276.899878)
			(xy 311.497634 -276.850824) (xy 311.509411 -276.80304) (xy 311.528702 -276.757764) (xy 311.555005 -276.716168)
			(xy 311.58764 -276.679331) (xy 311.625761 -276.648206) (xy 311.668382 -276.623599) (xy 311.714398 -276.606147)
			(xy 311.762617 -276.596303) (xy 311.811792 -276.594322) (xy 311.860647 -276.600254) (xy 311.907918 -276.613946)
			(xy 311.95238 -276.635044) (xy 311.992883 -276.663) (xy 312.028376 -276.697092) (xy 312.057941 -276.736436)
			(xy 312.080812 -276.780013) (xy 312.096396 -276.826694) (xy 312.104291 -276.875271) (xy 312.104786 -276.899878)
			(xy 312.443888 -276.899878) (xy 312.447848 -276.850824) (xy 312.459625 -276.80304) (xy 312.478916 -276.757764)
			(xy 312.505219 -276.716168) (xy 312.537854 -276.679331) (xy 312.575975 -276.648206) (xy 312.618596 -276.623599)
			(xy 312.664612 -276.606147) (xy 312.712831 -276.596303) (xy 312.762006 -276.594322) (xy 312.810861 -276.600254)
			(xy 312.858132 -276.613946) (xy 312.902594 -276.635044) (xy 312.943097 -276.663) (xy 312.97859 -276.697092)
			(xy 313.008155 -276.736436) (xy 313.031026 -276.780013) (xy 313.04661 -276.826694) (xy 313.054505 -276.875271)
			(xy 313.055 -276.899878) (xy 313.054505 -276.924485) (xy 313.054326 -276.925586) (xy 313.373258 -276.925586)
			(xy 313.373258 -276.87417) (xy 313.381301 -276.823388) (xy 313.397189 -276.774489) (xy 313.420532 -276.728677)
			(xy 313.450753 -276.687081) (xy 313.487109 -276.650725) (xy 313.528705 -276.620504) (xy 313.574517 -276.597161)
			(xy 313.623416 -276.581273) (xy 313.674198 -276.57323) (xy 313.725614 -276.57323) (xy 313.776396 -276.581273)
			(xy 313.825295 -276.597161) (xy 313.871107 -276.620504) (xy 313.912703 -276.650725) (xy 313.949059 -276.687081)
			(xy 313.97928 -276.728677) (xy 314.002623 -276.774489) (xy 314.018511 -276.823388) (xy 314.026554 -276.87417)
			(xy 314.027058 -276.899878) (xy 314.026554 -276.925586) (xy 314.323218 -276.925586) (xy 314.323218 -276.87417)
			(xy 314.331261 -276.823388) (xy 314.347149 -276.774489) (xy 314.370492 -276.728677) (xy 314.400713 -276.687081)
			(xy 314.437069 -276.650725) (xy 314.478665 -276.620504) (xy 314.524477 -276.597161) (xy 314.573376 -276.581273)
			(xy 314.624158 -276.57323) (xy 314.675574 -276.57323) (xy 314.726356 -276.581273) (xy 314.775255 -276.597161)
			(xy 314.821067 -276.620504) (xy 314.862663 -276.650725) (xy 314.899019 -276.687081) (xy 314.92924 -276.728677)
			(xy 314.952583 -276.774489) (xy 314.968471 -276.823388) (xy 314.976514 -276.87417) (xy 314.977018 -276.899878)
			(xy 314.977013 -276.900132) (xy 315.294276 -276.900132) (xy 315.298236 -276.851078) (xy 315.310013 -276.803294)
			(xy 315.329304 -276.758018) (xy 315.355607 -276.716422) (xy 315.388242 -276.679585) (xy 315.426363 -276.64846)
			(xy 315.468984 -276.623853) (xy 315.515 -276.606401) (xy 315.563219 -276.596557) (xy 315.612394 -276.594576)
			(xy 315.661249 -276.600508) (xy 315.70852 -276.6142) (xy 315.752982 -276.635298) (xy 315.793485 -276.663254)
			(xy 315.828978 -276.697346) (xy 315.858543 -276.73669) (xy 315.881414 -276.780267) (xy 315.896998 -276.826948)
			(xy 315.904893 -276.875525) (xy 315.905388 -276.900132) (xy 315.904893 -276.924739) (xy 315.896998 -276.973316)
			(xy 315.881414 -277.019997) (xy 315.858543 -277.063574) (xy 315.828978 -277.102918) (xy 315.793485 -277.13701)
			(xy 315.752982 -277.164966) (xy 315.70852 -277.186064) (xy 315.661249 -277.199756) (xy 315.612394 -277.205688)
			(xy 315.563219 -277.203707) (xy 315.515 -277.193863) (xy 315.468984 -277.176411) (xy 315.426363 -277.151804)
			(xy 315.388242 -277.120679) (xy 315.355607 -277.083842) (xy 315.329304 -277.042246) (xy 315.310013 -276.99697)
			(xy 315.298236 -276.949186) (xy 315.294276 -276.900132) (xy 314.977013 -276.900132) (xy 314.976514 -276.925586)
			(xy 314.968471 -276.976368) (xy 314.952583 -277.025267) (xy 314.92924 -277.071079) (xy 314.899019 -277.112675)
			(xy 314.862663 -277.149031) (xy 314.821067 -277.179252) (xy 314.775255 -277.202595) (xy 314.726356 -277.218483)
			(xy 314.675574 -277.226526) (xy 314.624158 -277.226526) (xy 314.573376 -277.218483) (xy 314.524477 -277.202595)
			(xy 314.478665 -277.179252) (xy 314.437069 -277.149031) (xy 314.400713 -277.112675) (xy 314.370492 -277.071079)
			(xy 314.347149 -277.025267) (xy 314.331261 -276.976368) (xy 314.323218 -276.925586) (xy 314.026554 -276.925586)
			(xy 314.018511 -276.976368) (xy 314.002623 -277.025267) (xy 313.97928 -277.071079) (xy 313.949059 -277.112675)
			(xy 313.912703 -277.149031) (xy 313.871107 -277.179252) (xy 313.825295 -277.202595) (xy 313.776396 -277.218483)
			(xy 313.725614 -277.226526) (xy 313.674198 -277.226526) (xy 313.623416 -277.218483) (xy 313.574517 -277.202595)
			(xy 313.528705 -277.179252) (xy 313.487109 -277.149031) (xy 313.450753 -277.112675) (xy 313.420532 -277.071079)
			(xy 313.397189 -277.025267) (xy 313.381301 -276.976368) (xy 313.373258 -276.925586) (xy 313.054326 -276.925586)
			(xy 313.04661 -276.973062) (xy 313.031026 -277.019743) (xy 313.008155 -277.06332) (xy 312.97859 -277.102664)
			(xy 312.943097 -277.136756) (xy 312.902594 -277.164712) (xy 312.858132 -277.18581) (xy 312.810861 -277.199502)
			(xy 312.762006 -277.205434) (xy 312.712831 -277.203453) (xy 312.664612 -277.193609) (xy 312.618596 -277.176157)
			(xy 312.575975 -277.15155) (xy 312.537854 -277.120425) (xy 312.505219 -277.083588) (xy 312.478916 -277.041992)
			(xy 312.459625 -276.996716) (xy 312.447848 -276.948932) (xy 312.443888 -276.899878) (xy 312.104786 -276.899878)
			(xy 312.104291 -276.924485) (xy 312.096396 -276.973062) (xy 312.080812 -277.019743) (xy 312.057941 -277.06332)
			(xy 312.028376 -277.102664) (xy 311.992883 -277.136756) (xy 311.95238 -277.164712) (xy 311.907918 -277.18581)
			(xy 311.860647 -277.199502) (xy 311.811792 -277.205434) (xy 311.762617 -277.203453) (xy 311.714398 -277.193609)
			(xy 311.668382 -277.176157) (xy 311.625761 -277.15155) (xy 311.58764 -277.120425) (xy 311.555005 -277.083588)
			(xy 311.528702 -277.041992) (xy 311.509411 -276.996716) (xy 311.497634 -276.948932) (xy 311.493674 -276.899878)
			(xy 311.154826 -276.899878) (xy 311.154331 -276.924485) (xy 311.146436 -276.973062) (xy 311.130852 -277.019743)
			(xy 311.107981 -277.06332) (xy 311.078416 -277.102664) (xy 311.042923 -277.136756) (xy 311.00242 -277.164712)
			(xy 310.957958 -277.18581) (xy 310.910687 -277.199502) (xy 310.861832 -277.205434) (xy 310.812657 -277.203453)
			(xy 310.764438 -277.193609) (xy 310.718422 -277.176157) (xy 310.675801 -277.15155) (xy 310.63768 -277.120425)
			(xy 310.605045 -277.083588) (xy 310.578742 -277.041992) (xy 310.559451 -276.996716) (xy 310.547674 -276.948932)
			(xy 310.543714 -276.899878) (xy 310.204866 -276.899878) (xy 310.204371 -276.924485) (xy 310.196476 -276.973062)
			(xy 310.180892 -277.019743) (xy 310.158021 -277.06332) (xy 310.128456 -277.102664) (xy 310.092963 -277.136756)
			(xy 310.05246 -277.164712) (xy 310.007998 -277.18581) (xy 309.960727 -277.199502) (xy 309.911872 -277.205434)
			(xy 309.862697 -277.203453) (xy 309.814478 -277.193609) (xy 309.768462 -277.176157) (xy 309.725841 -277.15155)
			(xy 309.68772 -277.120425) (xy 309.655085 -277.083588) (xy 309.628782 -277.041992) (xy 309.609491 -276.996716)
			(xy 309.597714 -276.948932) (xy 309.593754 -276.899878) (xy 309.254906 -276.899878) (xy 309.254411 -276.924485)
			(xy 309.246516 -276.973062) (xy 309.230932 -277.019743) (xy 309.208061 -277.06332) (xy 309.178496 -277.102664)
			(xy 309.143003 -277.136756) (xy 309.1025 -277.164712) (xy 309.058038 -277.18581) (xy 309.010767 -277.199502)
			(xy 308.961912 -277.205434) (xy 308.912737 -277.203453) (xy 308.864518 -277.193609) (xy 308.818502 -277.176157)
			(xy 308.775881 -277.15155) (xy 308.73776 -277.120425) (xy 308.705125 -277.083588) (xy 308.678822 -277.041992)
			(xy 308.659531 -276.996716) (xy 308.647754 -276.948932) (xy 308.643794 -276.899878) (xy 308.304946 -276.899878)
			(xy 308.304451 -276.924485) (xy 308.296556 -276.973062) (xy 308.280972 -277.019743) (xy 308.258101 -277.06332)
			(xy 308.228536 -277.102664) (xy 308.193043 -277.136756) (xy 308.15254 -277.164712) (xy 308.108078 -277.18581)
			(xy 308.060807 -277.199502) (xy 308.011952 -277.205434) (xy 307.962777 -277.203453) (xy 307.914558 -277.193609)
			(xy 307.868542 -277.176157) (xy 307.825921 -277.15155) (xy 307.7878 -277.120425) (xy 307.755165 -277.083588)
			(xy 307.728862 -277.041992) (xy 307.709571 -276.996716) (xy 307.697794 -276.948932) (xy 307.693834 -276.899878)
			(xy 307.354986 -276.899878) (xy 307.354491 -276.924485) (xy 307.346596 -276.973062) (xy 307.331012 -277.019743)
			(xy 307.308141 -277.06332) (xy 307.278576 -277.102664) (xy 307.243083 -277.136756) (xy 307.20258 -277.164712)
			(xy 307.158118 -277.18581) (xy 307.110847 -277.199502) (xy 307.061992 -277.205434) (xy 307.012817 -277.203453)
			(xy 306.964598 -277.193609) (xy 306.918582 -277.176157) (xy 306.875961 -277.15155) (xy 306.83784 -277.120425)
			(xy 306.805205 -277.083588) (xy 306.778902 -277.041992) (xy 306.759611 -276.996716) (xy 306.747834 -276.948932)
			(xy 306.743874 -276.899878) (xy 306.404772 -276.899878) (xy 306.404277 -276.924485) (xy 306.396382 -276.973062)
			(xy 306.380798 -277.019743) (xy 306.357927 -277.06332) (xy 306.328362 -277.102664) (xy 306.292869 -277.136756)
			(xy 306.252366 -277.164712) (xy 306.207904 -277.18581) (xy 306.160633 -277.199502) (xy 306.111778 -277.205434)
			(xy 306.062603 -277.203453) (xy 306.014384 -277.193609) (xy 305.968368 -277.176157) (xy 305.925747 -277.15155)
			(xy 305.887626 -277.120425) (xy 305.854991 -277.083588) (xy 305.828688 -277.041992) (xy 305.809397 -276.996716)
			(xy 305.79762 -276.948932) (xy 305.79366 -276.899878) (xy 305.455066 -276.899878) (xy 305.454571 -276.924485)
			(xy 305.446676 -276.973062) (xy 305.431092 -277.019743) (xy 305.408221 -277.06332) (xy 305.378656 -277.102664)
			(xy 305.343163 -277.136756) (xy 305.30266 -277.164712) (xy 305.258198 -277.18581) (xy 305.210927 -277.199502)
			(xy 305.162072 -277.205434) (xy 305.112897 -277.203453) (xy 305.064678 -277.193609) (xy 305.018662 -277.176157)
			(xy 304.976041 -277.15155) (xy 304.93792 -277.120425) (xy 304.905285 -277.083588) (xy 304.878982 -277.041992)
			(xy 304.859691 -276.996716) (xy 304.847914 -276.948932) (xy 304.843954 -276.899878) (xy 304.505106 -276.899878)
			(xy 304.504611 -276.924485) (xy 304.496716 -276.973062) (xy 304.481132 -277.019743) (xy 304.458261 -277.06332)
			(xy 304.428696 -277.102664) (xy 304.393203 -277.136756) (xy 304.3527 -277.164712) (xy 304.308238 -277.18581)
			(xy 304.260967 -277.199502) (xy 304.212112 -277.205434) (xy 304.162937 -277.203453) (xy 304.114718 -277.193609)
			(xy 304.068702 -277.176157) (xy 304.026081 -277.15155) (xy 303.98796 -277.120425) (xy 303.955325 -277.083588)
			(xy 303.929022 -277.041992) (xy 303.909731 -276.996716) (xy 303.897954 -276.948932) (xy 303.893994 -276.899878)
			(xy 303.555146 -276.899878) (xy 303.554651 -276.924485) (xy 303.546756 -276.973062) (xy 303.531172 -277.019743)
			(xy 303.508301 -277.06332) (xy 303.478736 -277.102664) (xy 303.443243 -277.136756) (xy 303.40274 -277.164712)
			(xy 303.358278 -277.18581) (xy 303.311007 -277.199502) (xy 303.262152 -277.205434) (xy 303.212977 -277.203453)
			(xy 303.164758 -277.193609) (xy 303.118742 -277.176157) (xy 303.076121 -277.15155) (xy 303.038 -277.120425)
			(xy 303.005365 -277.083588) (xy 302.979062 -277.041992) (xy 302.959771 -276.996716) (xy 302.947994 -276.948932)
			(xy 302.944034 -276.899878) (xy 302.605186 -276.899878) (xy 302.604691 -276.924485) (xy 302.596796 -276.973062)
			(xy 302.581212 -277.019743) (xy 302.558341 -277.06332) (xy 302.528776 -277.102664) (xy 302.493283 -277.136756)
			(xy 302.45278 -277.164712) (xy 302.408318 -277.18581) (xy 302.361047 -277.199502) (xy 302.312192 -277.205434)
			(xy 302.263017 -277.203453) (xy 302.214798 -277.193609) (xy 302.168782 -277.176157) (xy 302.126161 -277.15155)
			(xy 302.08804 -277.120425) (xy 302.055405 -277.083588) (xy 302.029102 -277.041992) (xy 302.009811 -276.996716)
			(xy 301.998034 -276.948932) (xy 301.994074 -276.899878) (xy 301.655226 -276.899878) (xy 301.654731 -276.924485)
			(xy 301.646836 -276.973062) (xy 301.631252 -277.019743) (xy 301.608381 -277.06332) (xy 301.578816 -277.102664)
			(xy 301.543323 -277.136756) (xy 301.50282 -277.164712) (xy 301.458358 -277.18581) (xy 301.411087 -277.199502)
			(xy 301.362232 -277.205434) (xy 301.313057 -277.203453) (xy 301.264838 -277.193609) (xy 301.218822 -277.176157)
			(xy 301.176201 -277.15155) (xy 301.13808 -277.120425) (xy 301.105445 -277.083588) (xy 301.079142 -277.041992)
			(xy 301.059851 -276.996716) (xy 301.048074 -276.948932) (xy 301.044114 -276.899878) (xy 300.705012 -276.899878)
			(xy 300.704517 -276.924485) (xy 300.696622 -276.973062) (xy 300.681038 -277.019743) (xy 300.658167 -277.06332)
			(xy 300.628602 -277.102664) (xy 300.593109 -277.136756) (xy 300.552606 -277.164712) (xy 300.508144 -277.18581)
			(xy 300.460873 -277.199502) (xy 300.412018 -277.205434) (xy 300.362843 -277.203453) (xy 300.314624 -277.193609)
			(xy 300.268608 -277.176157) (xy 300.225987 -277.15155) (xy 300.187866 -277.120425) (xy 300.155231 -277.083588)
			(xy 300.128928 -277.041992) (xy 300.109637 -276.996716) (xy 300.09786 -276.948932) (xy 300.0939 -276.899878)
			(xy 299.755052 -276.899878) (xy 299.754557 -276.924485) (xy 299.746662 -276.973062) (xy 299.731078 -277.019743)
			(xy 299.708207 -277.06332) (xy 299.678642 -277.102664) (xy 299.643149 -277.136756) (xy 299.602646 -277.164712)
			(xy 299.558184 -277.18581) (xy 299.510913 -277.199502) (xy 299.462058 -277.205434) (xy 299.412883 -277.203453)
			(xy 299.364664 -277.193609) (xy 299.318648 -277.176157) (xy 299.276027 -277.15155) (xy 299.237906 -277.120425)
			(xy 299.205271 -277.083588) (xy 299.178968 -277.041992) (xy 299.159677 -276.996716) (xy 299.1479 -276.948932)
			(xy 299.14394 -276.899878) (xy 298.805092 -276.899878) (xy 298.804597 -276.924485) (xy 298.796702 -276.973062)
			(xy 298.781118 -277.019743) (xy 298.758247 -277.06332) (xy 298.728682 -277.102664) (xy 298.693189 -277.136756)
			(xy 298.652686 -277.164712) (xy 298.608224 -277.18581) (xy 298.560953 -277.199502) (xy 298.512098 -277.205434)
			(xy 298.462923 -277.203453) (xy 298.414704 -277.193609) (xy 298.368688 -277.176157) (xy 298.326067 -277.15155)
			(xy 298.287946 -277.120425) (xy 298.255311 -277.083588) (xy 298.229008 -277.041992) (xy 298.209717 -276.996716)
			(xy 298.19794 -276.948932) (xy 298.19398 -276.899878) (xy 297.855132 -276.899878) (xy 297.854637 -276.924485)
			(xy 297.846742 -276.973062) (xy 297.831158 -277.019743) (xy 297.808287 -277.06332) (xy 297.778722 -277.102664)
			(xy 297.743229 -277.136756) (xy 297.702726 -277.164712) (xy 297.658264 -277.18581) (xy 297.610993 -277.199502)
			(xy 297.562138 -277.205434) (xy 297.512963 -277.203453) (xy 297.464744 -277.193609) (xy 297.418728 -277.176157)
			(xy 297.376107 -277.15155) (xy 297.337986 -277.120425) (xy 297.305351 -277.083588) (xy 297.279048 -277.041992)
			(xy 297.259757 -276.996716) (xy 297.24798 -276.948932) (xy 297.24402 -276.899878) (xy 296.905172 -276.899878)
			(xy 296.904677 -276.924485) (xy 296.896782 -276.973062) (xy 296.881198 -277.019743) (xy 296.858327 -277.06332)
			(xy 296.828762 -277.102664) (xy 296.793269 -277.136756) (xy 296.752766 -277.164712) (xy 296.708304 -277.18581)
			(xy 296.661033 -277.199502) (xy 296.612178 -277.205434) (xy 296.563003 -277.203453) (xy 296.514784 -277.193609)
			(xy 296.468768 -277.176157) (xy 296.426147 -277.15155) (xy 296.388026 -277.120425) (xy 296.355391 -277.083588)
			(xy 296.329088 -277.041992) (xy 296.309797 -276.996716) (xy 296.29802 -276.948932) (xy 296.29406 -276.899878)
			(xy 295.955212 -276.899878) (xy 295.954717 -276.924485) (xy 295.946822 -276.973062) (xy 295.931238 -277.019743)
			(xy 295.908367 -277.06332) (xy 295.878802 -277.102664) (xy 295.843309 -277.136756) (xy 295.802806 -277.164712)
			(xy 295.758344 -277.18581) (xy 295.711073 -277.199502) (xy 295.662218 -277.205434) (xy 295.613043 -277.203453)
			(xy 295.564824 -277.193609) (xy 295.518808 -277.176157) (xy 295.476187 -277.15155) (xy 295.438066 -277.120425)
			(xy 295.405431 -277.083588) (xy 295.379128 -277.041992) (xy 295.359837 -276.996716) (xy 295.34806 -276.948932)
			(xy 295.3441 -276.899878) (xy 295.004998 -276.899878) (xy 295.004503 -276.924485) (xy 294.996608 -276.973062)
			(xy 294.981024 -277.019743) (xy 294.958153 -277.06332) (xy 294.928588 -277.102664) (xy 294.893095 -277.136756)
			(xy 294.852592 -277.164712) (xy 294.80813 -277.18581) (xy 294.760859 -277.199502) (xy 294.712004 -277.205434)
			(xy 294.662829 -277.203453) (xy 294.61461 -277.193609) (xy 294.568594 -277.176157) (xy 294.525973 -277.15155)
			(xy 294.487852 -277.120425) (xy 294.455217 -277.083588) (xy 294.428914 -277.041992) (xy 294.409623 -276.996716)
			(xy 294.397846 -276.948932) (xy 294.393886 -276.899878) (xy 294.055038 -276.899878) (xy 294.054543 -276.924485)
			(xy 294.046648 -276.973062) (xy 294.031064 -277.019743) (xy 294.008193 -277.06332) (xy 293.978628 -277.102664)
			(xy 293.943135 -277.136756) (xy 293.902632 -277.164712) (xy 293.85817 -277.18581) (xy 293.810899 -277.199502)
			(xy 293.762044 -277.205434) (xy 293.712869 -277.203453) (xy 293.66465 -277.193609) (xy 293.618634 -277.176157)
			(xy 293.576013 -277.15155) (xy 293.537892 -277.120425) (xy 293.505257 -277.083588) (xy 293.478954 -277.041992)
			(xy 293.459663 -276.996716) (xy 293.447886 -276.948932) (xy 293.443926 -276.899878) (xy 293.105078 -276.899878)
			(xy 293.104583 -276.924485) (xy 293.096688 -276.973062) (xy 293.081104 -277.019743) (xy 293.058233 -277.06332)
			(xy 293.028668 -277.102664) (xy 292.993175 -277.136756) (xy 292.952672 -277.164712) (xy 292.90821 -277.18581)
			(xy 292.860939 -277.199502) (xy 292.812084 -277.205434) (xy 292.762909 -277.203453) (xy 292.71469 -277.193609)
			(xy 292.668674 -277.176157) (xy 292.626053 -277.15155) (xy 292.587932 -277.120425) (xy 292.555297 -277.083588)
			(xy 292.528994 -277.041992) (xy 292.509703 -276.996716) (xy 292.497926 -276.948932) (xy 292.493966 -276.899878)
			(xy 292.155118 -276.899878) (xy 292.154623 -276.924485) (xy 292.146728 -276.973062) (xy 292.131144 -277.019743)
			(xy 292.108273 -277.06332) (xy 292.078708 -277.102664) (xy 292.043215 -277.136756) (xy 292.002712 -277.164712)
			(xy 291.95825 -277.18581) (xy 291.910979 -277.199502) (xy 291.862124 -277.205434) (xy 291.812949 -277.203453)
			(xy 291.76473 -277.193609) (xy 291.718714 -277.176157) (xy 291.676093 -277.15155) (xy 291.637972 -277.120425)
			(xy 291.605337 -277.083588) (xy 291.579034 -277.041992) (xy 291.559743 -276.996716) (xy 291.547966 -276.948932)
			(xy 291.544006 -276.899878) (xy 291.205158 -276.899878) (xy 291.204663 -276.924485) (xy 291.196768 -276.973062)
			(xy 291.181184 -277.019743) (xy 291.158313 -277.06332) (xy 291.128748 -277.102664) (xy 291.093255 -277.136756)
			(xy 291.052752 -277.164712) (xy 291.00829 -277.18581) (xy 290.961019 -277.199502) (xy 290.912164 -277.205434)
			(xy 290.862989 -277.203453) (xy 290.81477 -277.193609) (xy 290.768754 -277.176157) (xy 290.726133 -277.15155)
			(xy 290.688012 -277.120425) (xy 290.655377 -277.083588) (xy 290.629074 -277.041992) (xy 290.609783 -276.996716)
			(xy 290.598006 -276.948932) (xy 290.594046 -276.899878) (xy 290.255198 -276.899878) (xy 290.254703 -276.924485)
			(xy 290.246808 -276.973062) (xy 290.231224 -277.019743) (xy 290.208353 -277.06332) (xy 290.178788 -277.102664)
			(xy 290.143295 -277.136756) (xy 290.102792 -277.164712) (xy 290.05833 -277.18581) (xy 290.011059 -277.199502)
			(xy 289.962204 -277.205434) (xy 289.913029 -277.203453) (xy 289.86481 -277.193609) (xy 289.818794 -277.176157)
			(xy 289.776173 -277.15155) (xy 289.738052 -277.120425) (xy 289.705417 -277.083588) (xy 289.679114 -277.041992)
			(xy 289.659823 -276.996716) (xy 289.648046 -276.948932) (xy 289.644086 -276.899878) (xy 289.305238 -276.899878)
			(xy 289.304743 -276.924485) (xy 289.296848 -276.973062) (xy 289.281264 -277.019743) (xy 289.258393 -277.06332)
			(xy 289.228828 -277.102664) (xy 289.193335 -277.136756) (xy 289.152832 -277.164712) (xy 289.10837 -277.18581)
			(xy 289.061099 -277.199502) (xy 289.012244 -277.205434) (xy 288.963069 -277.203453) (xy 288.91485 -277.193609)
			(xy 288.868834 -277.176157) (xy 288.826213 -277.15155) (xy 288.788092 -277.120425) (xy 288.755457 -277.083588)
			(xy 288.729154 -277.041992) (xy 288.709863 -276.996716) (xy 288.698086 -276.948932) (xy 288.694126 -276.899878)
			(xy 288.355024 -276.899878) (xy 288.354529 -276.924485) (xy 288.346634 -276.973062) (xy 288.33105 -277.019743)
			(xy 288.308179 -277.06332) (xy 288.278614 -277.102664) (xy 288.243121 -277.136756) (xy 288.202618 -277.164712)
			(xy 288.158156 -277.18581) (xy 288.110885 -277.199502) (xy 288.06203 -277.205434) (xy 288.012855 -277.203453)
			(xy 287.964636 -277.193609) (xy 287.91862 -277.176157) (xy 287.875999 -277.15155) (xy 287.837878 -277.120425)
			(xy 287.805243 -277.083588) (xy 287.77894 -277.041992) (xy 287.759649 -276.996716) (xy 287.747872 -276.948932)
			(xy 287.743912 -276.899878) (xy 287.405064 -276.899878) (xy 287.404569 -276.924485) (xy 287.396674 -276.973062)
			(xy 287.38109 -277.019743) (xy 287.358219 -277.06332) (xy 287.328654 -277.102664) (xy 287.293161 -277.136756)
			(xy 287.252658 -277.164712) (xy 287.208196 -277.18581) (xy 287.160925 -277.199502) (xy 287.11207 -277.205434)
			(xy 287.062895 -277.203453) (xy 287.014676 -277.193609) (xy 286.96866 -277.176157) (xy 286.926039 -277.15155)
			(xy 286.887918 -277.120425) (xy 286.855283 -277.083588) (xy 286.82898 -277.041992) (xy 286.809689 -276.996716)
			(xy 286.797912 -276.948932) (xy 286.793952 -276.899878) (xy 286.455104 -276.899878) (xy 286.454609 -276.924485)
			(xy 286.446714 -276.973062) (xy 286.43113 -277.019743) (xy 286.408259 -277.06332) (xy 286.378694 -277.102664)
			(xy 286.343201 -277.136756) (xy 286.302698 -277.164712) (xy 286.258236 -277.18581) (xy 286.210965 -277.199502)
			(xy 286.16211 -277.205434) (xy 286.112935 -277.203453) (xy 286.064716 -277.193609) (xy 286.0187 -277.176157)
			(xy 285.976079 -277.15155) (xy 285.937958 -277.120425) (xy 285.905323 -277.083588) (xy 285.87902 -277.041992)
			(xy 285.859729 -276.996716) (xy 285.847952 -276.948932) (xy 285.843992 -276.899878) (xy 285.505144 -276.899878)
			(xy 285.504649 -276.924485) (xy 285.496754 -276.973062) (xy 285.48117 -277.019743) (xy 285.458299 -277.06332)
			(xy 285.428734 -277.102664) (xy 285.393241 -277.136756) (xy 285.352738 -277.164712) (xy 285.308276 -277.18581)
			(xy 285.261005 -277.199502) (xy 285.21215 -277.205434) (xy 285.162975 -277.203453) (xy 285.114756 -277.193609)
			(xy 285.06874 -277.176157) (xy 285.026119 -277.15155) (xy 284.987998 -277.120425) (xy 284.955363 -277.083588)
			(xy 284.92906 -277.041992) (xy 284.909769 -276.996716) (xy 284.897992 -276.948932) (xy 284.894032 -276.899878)
			(xy 284.555184 -276.899878) (xy 284.554689 -276.924485) (xy 284.546794 -276.973062) (xy 284.53121 -277.019743)
			(xy 284.508339 -277.06332) (xy 284.478774 -277.102664) (xy 284.443281 -277.136756) (xy 284.402778 -277.164712)
			(xy 284.358316 -277.18581) (xy 284.311045 -277.199502) (xy 284.26219 -277.205434) (xy 284.213015 -277.203453)
			(xy 284.164796 -277.193609) (xy 284.11878 -277.176157) (xy 284.076159 -277.15155) (xy 284.038038 -277.120425)
			(xy 284.005403 -277.083588) (xy 283.9791 -277.041992) (xy 283.959809 -276.996716) (xy 283.948032 -276.948932)
			(xy 283.944072 -276.899878) (xy 283.605224 -276.899878) (xy 283.604729 -276.924485) (xy 283.596834 -276.973062)
			(xy 283.58125 -277.019743) (xy 283.558379 -277.06332) (xy 283.528814 -277.102664) (xy 283.493321 -277.136756)
			(xy 283.452818 -277.164712) (xy 283.408356 -277.18581) (xy 283.361085 -277.199502) (xy 283.31223 -277.205434)
			(xy 283.263055 -277.203453) (xy 283.214836 -277.193609) (xy 283.16882 -277.176157) (xy 283.126199 -277.15155)
			(xy 283.088078 -277.120425) (xy 283.055443 -277.083588) (xy 283.02914 -277.041992) (xy 283.009849 -276.996716)
			(xy 282.998072 -276.948932) (xy 282.994112 -276.899878) (xy 282.655551 -276.899878) (xy 282.655553 -276.8999)
			(xy 282.651382 -276.950242) (xy 282.638981 -276.99921) (xy 282.61869 -277.045469) (xy 282.591062 -277.087758)
			(xy 282.556849 -277.124923) (xy 282.516987 -277.155949) (xy 282.472561 -277.179991) (xy 282.424784 -277.196394)
			(xy 282.374959 -277.204708) (xy 282.349702 -277.205186) (xy 282.340534 -277.205094) (xy 282.322234 -277.20395)
			(xy 282.313126 -277.2029) (xy 282.300934 -277.20163) (xy 282.278836 -277.209504) (xy 282.205684 -277.285958)
			(xy 282.198572 -277.308564) (xy 282.200604 -277.320502) (xy 282.202732 -277.33399) (xy 282.205017 -277.361204)
			(xy 282.205176 -277.374858) (xy 282.205176 -277.423372) (xy 282.205629 -277.434034) (xy 282.214302 -277.453513)
			(xy 282.22194 -277.460964) (xy 282.285948 -277.518876) (xy 282.306014 -277.52548) (xy 282.316936 -277.524464)
			(xy 282.349702 -277.52294) (xy 282.375387 -277.523444) (xy 282.426124 -277.53148) (xy 282.474979 -277.547354)
			(xy 282.520749 -277.570676) (xy 282.562308 -277.60087) (xy 282.598631 -277.637194) (xy 282.628825 -277.678753)
			(xy 282.652146 -277.724523) (xy 282.66802 -277.773378) (xy 282.676056 -277.824115) (xy 282.676056 -277.849838)
			(xy 282.994112 -277.849838) (xy 282.998072 -277.800784) (xy 283.009849 -277.753) (xy 283.02914 -277.707724)
			(xy 283.055443 -277.666128) (xy 283.088078 -277.629291) (xy 283.126199 -277.598166) (xy 283.16882 -277.573559)
			(xy 283.214836 -277.556107) (xy 283.263055 -277.546263) (xy 283.31223 -277.544282) (xy 283.361085 -277.550214)
			(xy 283.408356 -277.563906) (xy 283.452818 -277.585004) (xy 283.493321 -277.61296) (xy 283.528814 -277.647052)
			(xy 283.558379 -277.686396) (xy 283.58125 -277.729973) (xy 283.596834 -277.776654) (xy 283.604729 -277.825231)
			(xy 283.605224 -277.849838) (xy 283.604729 -277.874445) (xy 283.60455 -277.875546) (xy 283.923228 -277.875546)
			(xy 283.923228 -277.82413) (xy 283.931271 -277.773348) (xy 283.947159 -277.724449) (xy 283.970502 -277.678637)
			(xy 284.000723 -277.637041) (xy 284.037079 -277.600685) (xy 284.078675 -277.570464) (xy 284.124487 -277.547121)
			(xy 284.173386 -277.531233) (xy 284.224168 -277.52319) (xy 284.275584 -277.52319) (xy 284.326366 -277.531233)
			(xy 284.375265 -277.547121) (xy 284.421077 -277.570464) (xy 284.462673 -277.600685) (xy 284.499029 -277.637041)
			(xy 284.52925 -277.678637) (xy 284.552593 -277.724449) (xy 284.568481 -277.773348) (xy 284.576524 -277.82413)
			(xy 284.577028 -277.849838) (xy 284.894032 -277.849838) (xy 284.897992 -277.800784) (xy 284.909769 -277.753)
			(xy 284.92906 -277.707724) (xy 284.955363 -277.666128) (xy 284.987998 -277.629291) (xy 285.026119 -277.598166)
			(xy 285.06874 -277.573559) (xy 285.114756 -277.556107) (xy 285.162975 -277.546263) (xy 285.21215 -277.544282)
			(xy 285.261005 -277.550214) (xy 285.308276 -277.563906) (xy 285.352738 -277.585004) (xy 285.393241 -277.61296)
			(xy 285.428734 -277.647052) (xy 285.458299 -277.686396) (xy 285.48117 -277.729973) (xy 285.496754 -277.776654)
			(xy 285.504649 -277.825231) (xy 285.505144 -277.849838) (xy 285.504649 -277.874445) (xy 285.50447 -277.875546)
			(xy 285.823148 -277.875546) (xy 285.823148 -277.82413) (xy 285.831191 -277.773348) (xy 285.847079 -277.724449)
			(xy 285.870422 -277.678637) (xy 285.900643 -277.637041) (xy 285.936999 -277.600685) (xy 285.978595 -277.570464)
			(xy 286.024407 -277.547121) (xy 286.073306 -277.531233) (xy 286.124088 -277.52319) (xy 286.175504 -277.52319)
			(xy 286.226286 -277.531233) (xy 286.275185 -277.547121) (xy 286.320997 -277.570464) (xy 286.362593 -277.600685)
			(xy 286.398949 -277.637041) (xy 286.42917 -277.678637) (xy 286.452513 -277.724449) (xy 286.468401 -277.773348)
			(xy 286.476444 -277.82413) (xy 286.476948 -277.849838) (xy 286.793952 -277.849838) (xy 286.797912 -277.800784)
			(xy 286.809689 -277.753) (xy 286.82898 -277.707724) (xy 286.855283 -277.666128) (xy 286.887918 -277.629291)
			(xy 286.926039 -277.598166) (xy 286.96866 -277.573559) (xy 287.014676 -277.556107) (xy 287.062895 -277.546263)
			(xy 287.11207 -277.544282) (xy 287.160925 -277.550214) (xy 287.208196 -277.563906) (xy 287.252658 -277.585004)
			(xy 287.293161 -277.61296) (xy 287.328654 -277.647052) (xy 287.358219 -277.686396) (xy 287.38109 -277.729973)
			(xy 287.396674 -277.776654) (xy 287.404569 -277.825231) (xy 287.405064 -277.849838) (xy 287.404569 -277.874445)
			(xy 287.40439 -277.875546) (xy 287.723068 -277.875546) (xy 287.723068 -277.82413) (xy 287.731111 -277.773348)
			(xy 287.746999 -277.724449) (xy 287.770342 -277.678637) (xy 287.800563 -277.637041) (xy 287.836919 -277.600685)
			(xy 287.878515 -277.570464) (xy 287.924327 -277.547121) (xy 287.973226 -277.531233) (xy 288.024008 -277.52319)
			(xy 288.075424 -277.52319) (xy 288.126206 -277.531233) (xy 288.175105 -277.547121) (xy 288.220917 -277.570464)
			(xy 288.262513 -277.600685) (xy 288.298869 -277.637041) (xy 288.32909 -277.678637) (xy 288.352433 -277.724449)
			(xy 288.368321 -277.773348) (xy 288.376364 -277.82413) (xy 288.376868 -277.849838) (xy 288.694126 -277.849838)
			(xy 288.698086 -277.800784) (xy 288.709863 -277.753) (xy 288.729154 -277.707724) (xy 288.755457 -277.666128)
			(xy 288.788092 -277.629291) (xy 288.826213 -277.598166) (xy 288.868834 -277.573559) (xy 288.91485 -277.556107)
			(xy 288.963069 -277.546263) (xy 289.012244 -277.544282) (xy 289.061099 -277.550214) (xy 289.10837 -277.563906)
			(xy 289.152832 -277.585004) (xy 289.193335 -277.61296) (xy 289.228828 -277.647052) (xy 289.258393 -277.686396)
			(xy 289.281264 -277.729973) (xy 289.296848 -277.776654) (xy 289.304743 -277.825231) (xy 289.305238 -277.849838)
			(xy 289.304743 -277.874445) (xy 289.304564 -277.875546) (xy 289.623242 -277.875546) (xy 289.623242 -277.82413)
			(xy 289.631285 -277.773348) (xy 289.647173 -277.724449) (xy 289.670516 -277.678637) (xy 289.700737 -277.637041)
			(xy 289.737093 -277.600685) (xy 289.778689 -277.570464) (xy 289.824501 -277.547121) (xy 289.8734 -277.531233)
			(xy 289.924182 -277.52319) (xy 289.975598 -277.52319) (xy 290.02638 -277.531233) (xy 290.075279 -277.547121)
			(xy 290.121091 -277.570464) (xy 290.162687 -277.600685) (xy 290.199043 -277.637041) (xy 290.229264 -277.678637)
			(xy 290.252607 -277.724449) (xy 290.268495 -277.773348) (xy 290.276538 -277.82413) (xy 290.277042 -277.849838)
			(xy 290.594046 -277.849838) (xy 290.598006 -277.800784) (xy 290.609783 -277.753) (xy 290.629074 -277.707724)
			(xy 290.655377 -277.666128) (xy 290.688012 -277.629291) (xy 290.726133 -277.598166) (xy 290.768754 -277.573559)
			(xy 290.81477 -277.556107) (xy 290.862989 -277.546263) (xy 290.912164 -277.544282) (xy 290.961019 -277.550214)
			(xy 291.00829 -277.563906) (xy 291.052752 -277.585004) (xy 291.093255 -277.61296) (xy 291.128748 -277.647052)
			(xy 291.158313 -277.686396) (xy 291.181184 -277.729973) (xy 291.196768 -277.776654) (xy 291.204663 -277.825231)
			(xy 291.205158 -277.849838) (xy 291.204663 -277.874445) (xy 291.204484 -277.875546) (xy 291.522908 -277.875546)
			(xy 291.522908 -277.82413) (xy 291.530951 -277.773348) (xy 291.546839 -277.724449) (xy 291.570182 -277.678637)
			(xy 291.600403 -277.637041) (xy 291.636759 -277.600685) (xy 291.678355 -277.570464) (xy 291.724167 -277.547121)
			(xy 291.773066 -277.531233) (xy 291.823848 -277.52319) (xy 291.875264 -277.52319) (xy 291.926046 -277.531233)
			(xy 291.974945 -277.547121) (xy 292.020757 -277.570464) (xy 292.062353 -277.600685) (xy 292.098709 -277.637041)
			(xy 292.12893 -277.678637) (xy 292.152273 -277.724449) (xy 292.168161 -277.773348) (xy 292.176204 -277.82413)
			(xy 292.176708 -277.849838) (xy 292.493966 -277.849838) (xy 292.497926 -277.800784) (xy 292.509703 -277.753)
			(xy 292.528994 -277.707724) (xy 292.555297 -277.666128) (xy 292.587932 -277.629291) (xy 292.626053 -277.598166)
			(xy 292.668674 -277.573559) (xy 292.71469 -277.556107) (xy 292.762909 -277.546263) (xy 292.812084 -277.544282)
			(xy 292.860939 -277.550214) (xy 292.90821 -277.563906) (xy 292.952672 -277.585004) (xy 292.993175 -277.61296)
			(xy 293.028668 -277.647052) (xy 293.058233 -277.686396) (xy 293.081104 -277.729973) (xy 293.096688 -277.776654)
			(xy 293.104583 -277.825231) (xy 293.105078 -277.849838) (xy 293.104583 -277.874445) (xy 293.104404 -277.875546)
			(xy 293.422828 -277.875546) (xy 293.422828 -277.82413) (xy 293.430871 -277.773348) (xy 293.446759 -277.724449)
			(xy 293.470102 -277.678637) (xy 293.500323 -277.637041) (xy 293.536679 -277.600685) (xy 293.578275 -277.570464)
			(xy 293.624087 -277.547121) (xy 293.672986 -277.531233) (xy 293.723768 -277.52319) (xy 293.775184 -277.52319)
			(xy 293.825966 -277.531233) (xy 293.874865 -277.547121) (xy 293.920677 -277.570464) (xy 293.962273 -277.600685)
			(xy 293.998629 -277.637041) (xy 294.02885 -277.678637) (xy 294.052193 -277.724449) (xy 294.068081 -277.773348)
			(xy 294.076124 -277.82413) (xy 294.076628 -277.849838) (xy 294.393886 -277.849838) (xy 294.397846 -277.800784)
			(xy 294.409623 -277.753) (xy 294.428914 -277.707724) (xy 294.455217 -277.666128) (xy 294.487852 -277.629291)
			(xy 294.525973 -277.598166) (xy 294.568594 -277.573559) (xy 294.61461 -277.556107) (xy 294.662829 -277.546263)
			(xy 294.712004 -277.544282) (xy 294.760859 -277.550214) (xy 294.80813 -277.563906) (xy 294.852592 -277.585004)
			(xy 294.893095 -277.61296) (xy 294.928588 -277.647052) (xy 294.958153 -277.686396) (xy 294.981024 -277.729973)
			(xy 294.996608 -277.776654) (xy 295.004503 -277.825231) (xy 295.004998 -277.849838) (xy 295.004503 -277.874445)
			(xy 295.004324 -277.875546) (xy 295.323002 -277.875546) (xy 295.323002 -277.82413) (xy 295.331045 -277.773348)
			(xy 295.346933 -277.724449) (xy 295.370276 -277.678637) (xy 295.400497 -277.637041) (xy 295.436853 -277.600685)
			(xy 295.478449 -277.570464) (xy 295.524261 -277.547121) (xy 295.57316 -277.531233) (xy 295.623942 -277.52319)
			(xy 295.675358 -277.52319) (xy 295.72614 -277.531233) (xy 295.775039 -277.547121) (xy 295.820851 -277.570464)
			(xy 295.862447 -277.600685) (xy 295.898803 -277.637041) (xy 295.929024 -277.678637) (xy 295.952367 -277.724449)
			(xy 295.968255 -277.773348) (xy 295.976298 -277.82413) (xy 295.976802 -277.849838) (xy 296.29406 -277.849838)
			(xy 296.29802 -277.800784) (xy 296.309797 -277.753) (xy 296.329088 -277.707724) (xy 296.355391 -277.666128)
			(xy 296.388026 -277.629291) (xy 296.426147 -277.598166) (xy 296.468768 -277.573559) (xy 296.514784 -277.556107)
			(xy 296.563003 -277.546263) (xy 296.612178 -277.544282) (xy 296.661033 -277.550214) (xy 296.708304 -277.563906)
			(xy 296.752766 -277.585004) (xy 296.793269 -277.61296) (xy 296.828762 -277.647052) (xy 296.858327 -277.686396)
			(xy 296.881198 -277.729973) (xy 296.896782 -277.776654) (xy 296.904677 -277.825231) (xy 296.905172 -277.849838)
			(xy 296.904677 -277.874445) (xy 296.904498 -277.875546) (xy 297.222922 -277.875546) (xy 297.222922 -277.82413)
			(xy 297.230965 -277.773348) (xy 297.246853 -277.724449) (xy 297.270196 -277.678637) (xy 297.300417 -277.637041)
			(xy 297.336773 -277.600685) (xy 297.378369 -277.570464) (xy 297.424181 -277.547121) (xy 297.47308 -277.531233)
			(xy 297.523862 -277.52319) (xy 297.575278 -277.52319) (xy 297.62606 -277.531233) (xy 297.674959 -277.547121)
			(xy 297.720771 -277.570464) (xy 297.762367 -277.600685) (xy 297.798723 -277.637041) (xy 297.828944 -277.678637)
			(xy 297.852287 -277.724449) (xy 297.868175 -277.773348) (xy 297.876218 -277.82413) (xy 297.876722 -277.849838)
			(xy 298.19398 -277.849838) (xy 298.19794 -277.800784) (xy 298.209717 -277.753) (xy 298.229008 -277.707724)
			(xy 298.255311 -277.666128) (xy 298.287946 -277.629291) (xy 298.326067 -277.598166) (xy 298.368688 -277.573559)
			(xy 298.414704 -277.556107) (xy 298.462923 -277.546263) (xy 298.512098 -277.544282) (xy 298.560953 -277.550214)
			(xy 298.608224 -277.563906) (xy 298.652686 -277.585004) (xy 298.693189 -277.61296) (xy 298.728682 -277.647052)
			(xy 298.758247 -277.686396) (xy 298.781118 -277.729973) (xy 298.796702 -277.776654) (xy 298.804597 -277.825231)
			(xy 298.805092 -277.849838) (xy 298.804597 -277.874445) (xy 298.804418 -277.875546) (xy 299.122842 -277.875546)
			(xy 299.122842 -277.82413) (xy 299.130885 -277.773348) (xy 299.146773 -277.724449) (xy 299.170116 -277.678637)
			(xy 299.200337 -277.637041) (xy 299.236693 -277.600685) (xy 299.278289 -277.570464) (xy 299.324101 -277.547121)
			(xy 299.373 -277.531233) (xy 299.423782 -277.52319) (xy 299.475198 -277.52319) (xy 299.52598 -277.531233)
			(xy 299.574879 -277.547121) (xy 299.620691 -277.570464) (xy 299.662287 -277.600685) (xy 299.698643 -277.637041)
			(xy 299.728864 -277.678637) (xy 299.752207 -277.724449) (xy 299.768095 -277.773348) (xy 299.776138 -277.82413)
			(xy 299.776642 -277.849838) (xy 300.0939 -277.849838) (xy 300.09786 -277.800784) (xy 300.109637 -277.753)
			(xy 300.128928 -277.707724) (xy 300.155231 -277.666128) (xy 300.187866 -277.629291) (xy 300.225987 -277.598166)
			(xy 300.268608 -277.573559) (xy 300.314624 -277.556107) (xy 300.362843 -277.546263) (xy 300.412018 -277.544282)
			(xy 300.460873 -277.550214) (xy 300.508144 -277.563906) (xy 300.552606 -277.585004) (xy 300.593109 -277.61296)
			(xy 300.628602 -277.647052) (xy 300.658167 -277.686396) (xy 300.681038 -277.729973) (xy 300.696622 -277.776654)
			(xy 300.704517 -277.825231) (xy 300.705012 -277.849838) (xy 300.704517 -277.874445) (xy 300.704338 -277.875546)
			(xy 301.023016 -277.875546) (xy 301.023016 -277.82413) (xy 301.031059 -277.773348) (xy 301.046947 -277.724449)
			(xy 301.07029 -277.678637) (xy 301.100511 -277.637041) (xy 301.136867 -277.600685) (xy 301.178463 -277.570464)
			(xy 301.224275 -277.547121) (xy 301.273174 -277.531233) (xy 301.323956 -277.52319) (xy 301.375372 -277.52319)
			(xy 301.426154 -277.531233) (xy 301.475053 -277.547121) (xy 301.520865 -277.570464) (xy 301.562461 -277.600685)
			(xy 301.598817 -277.637041) (xy 301.629038 -277.678637) (xy 301.652381 -277.724449) (xy 301.668269 -277.773348)
			(xy 301.676312 -277.82413) (xy 301.676816 -277.849838) (xy 301.994074 -277.849838) (xy 301.998034 -277.800784)
			(xy 302.009811 -277.753) (xy 302.029102 -277.707724) (xy 302.055405 -277.666128) (xy 302.08804 -277.629291)
			(xy 302.126161 -277.598166) (xy 302.168782 -277.573559) (xy 302.214798 -277.556107) (xy 302.263017 -277.546263)
			(xy 302.312192 -277.544282) (xy 302.361047 -277.550214) (xy 302.408318 -277.563906) (xy 302.45278 -277.585004)
			(xy 302.493283 -277.61296) (xy 302.528776 -277.647052) (xy 302.558341 -277.686396) (xy 302.581212 -277.729973)
			(xy 302.596796 -277.776654) (xy 302.604691 -277.825231) (xy 302.605186 -277.849838) (xy 302.604691 -277.874445)
			(xy 302.604512 -277.875546) (xy 302.922936 -277.875546) (xy 302.922936 -277.82413) (xy 302.930979 -277.773348)
			(xy 302.946867 -277.724449) (xy 302.97021 -277.678637) (xy 303.000431 -277.637041) (xy 303.036787 -277.600685)
			(xy 303.078383 -277.570464) (xy 303.124195 -277.547121) (xy 303.173094 -277.531233) (xy 303.223876 -277.52319)
			(xy 303.275292 -277.52319) (xy 303.326074 -277.531233) (xy 303.374973 -277.547121) (xy 303.420785 -277.570464)
			(xy 303.462381 -277.600685) (xy 303.498737 -277.637041) (xy 303.528958 -277.678637) (xy 303.552301 -277.724449)
			(xy 303.568189 -277.773348) (xy 303.576232 -277.82413) (xy 303.576736 -277.849838) (xy 303.893994 -277.849838)
			(xy 303.897954 -277.800784) (xy 303.909731 -277.753) (xy 303.929022 -277.707724) (xy 303.955325 -277.666128)
			(xy 303.98796 -277.629291) (xy 304.026081 -277.598166) (xy 304.068702 -277.573559) (xy 304.114718 -277.556107)
			(xy 304.162937 -277.546263) (xy 304.212112 -277.544282) (xy 304.260967 -277.550214) (xy 304.308238 -277.563906)
			(xy 304.3527 -277.585004) (xy 304.393203 -277.61296) (xy 304.428696 -277.647052) (xy 304.458261 -277.686396)
			(xy 304.481132 -277.729973) (xy 304.496716 -277.776654) (xy 304.504611 -277.825231) (xy 304.505106 -277.849838)
			(xy 304.504611 -277.874445) (xy 304.504432 -277.875546) (xy 304.822856 -277.875546) (xy 304.822856 -277.82413)
			(xy 304.830899 -277.773348) (xy 304.846787 -277.724449) (xy 304.87013 -277.678637) (xy 304.900351 -277.637041)
			(xy 304.936707 -277.600685) (xy 304.978303 -277.570464) (xy 305.024115 -277.547121) (xy 305.073014 -277.531233)
			(xy 305.123796 -277.52319) (xy 305.175212 -277.52319) (xy 305.225994 -277.531233) (xy 305.274893 -277.547121)
			(xy 305.320705 -277.570464) (xy 305.362301 -277.600685) (xy 305.398657 -277.637041) (xy 305.428878 -277.678637)
			(xy 305.452221 -277.724449) (xy 305.468109 -277.773348) (xy 305.476152 -277.82413) (xy 305.476656 -277.849838)
			(xy 305.793914 -277.849838) (xy 305.797874 -277.800784) (xy 305.809651 -277.753) (xy 305.828942 -277.707724)
			(xy 305.855245 -277.666128) (xy 305.88788 -277.629291) (xy 305.926001 -277.598166) (xy 305.968622 -277.573559)
			(xy 306.014638 -277.556107) (xy 306.062857 -277.546263) (xy 306.112032 -277.544282) (xy 306.160887 -277.550214)
			(xy 306.208158 -277.563906) (xy 306.25262 -277.585004) (xy 306.293123 -277.61296) (xy 306.328616 -277.647052)
			(xy 306.358181 -277.686396) (xy 306.381052 -277.729973) (xy 306.396636 -277.776654) (xy 306.404531 -277.825231)
			(xy 306.405026 -277.849838) (xy 306.404531 -277.874445) (xy 306.404352 -277.875546) (xy 306.72303 -277.875546)
			(xy 306.72303 -277.82413) (xy 306.731073 -277.773348) (xy 306.746961 -277.724449) (xy 306.770304 -277.678637)
			(xy 306.800525 -277.637041) (xy 306.836881 -277.600685) (xy 306.878477 -277.570464) (xy 306.924289 -277.547121)
			(xy 306.973188 -277.531233) (xy 307.02397 -277.52319) (xy 307.075386 -277.52319) (xy 307.126168 -277.531233)
			(xy 307.175067 -277.547121) (xy 307.220879 -277.570464) (xy 307.262475 -277.600685) (xy 307.298831 -277.637041)
			(xy 307.329052 -277.678637) (xy 307.352395 -277.724449) (xy 307.368283 -277.773348) (xy 307.376326 -277.82413)
			(xy 307.37683 -277.849838) (xy 307.694088 -277.849838) (xy 307.698048 -277.800784) (xy 307.709825 -277.753)
			(xy 307.729116 -277.707724) (xy 307.755419 -277.666128) (xy 307.788054 -277.629291) (xy 307.826175 -277.598166)
			(xy 307.868796 -277.573559) (xy 307.914812 -277.556107) (xy 307.963031 -277.546263) (xy 308.012206 -277.544282)
			(xy 308.061061 -277.550214) (xy 308.108332 -277.563906) (xy 308.152794 -277.585004) (xy 308.193297 -277.61296)
			(xy 308.22879 -277.647052) (xy 308.258355 -277.686396) (xy 308.281226 -277.729973) (xy 308.29681 -277.776654)
			(xy 308.304705 -277.825231) (xy 308.3052 -277.849838) (xy 308.304705 -277.874445) (xy 308.304526 -277.875546)
			(xy 308.62295 -277.875546) (xy 308.62295 -277.82413) (xy 308.630993 -277.773348) (xy 308.646881 -277.724449)
			(xy 308.670224 -277.678637) (xy 308.700445 -277.637041) (xy 308.736801 -277.600685) (xy 308.778397 -277.570464)
			(xy 308.824209 -277.547121) (xy 308.873108 -277.531233) (xy 308.92389 -277.52319) (xy 308.975306 -277.52319)
			(xy 309.026088 -277.531233) (xy 309.074987 -277.547121) (xy 309.120799 -277.570464) (xy 309.162395 -277.600685)
			(xy 309.198751 -277.637041) (xy 309.228972 -277.678637) (xy 309.252315 -277.724449) (xy 309.268203 -277.773348)
			(xy 309.276246 -277.82413) (xy 309.27675 -277.849838) (xy 309.594008 -277.849838) (xy 309.597968 -277.800784)
			(xy 309.609745 -277.753) (xy 309.629036 -277.707724) (xy 309.655339 -277.666128) (xy 309.687974 -277.629291)
			(xy 309.726095 -277.598166) (xy 309.768716 -277.573559) (xy 309.814732 -277.556107) (xy 309.862951 -277.546263)
			(xy 309.912126 -277.544282) (xy 309.960981 -277.550214) (xy 310.008252 -277.563906) (xy 310.052714 -277.585004)
			(xy 310.093217 -277.61296) (xy 310.12871 -277.647052) (xy 310.158275 -277.686396) (xy 310.181146 -277.729973)
			(xy 310.19673 -277.776654) (xy 310.204625 -277.825231) (xy 310.20512 -277.849838) (xy 310.204625 -277.874445)
			(xy 310.204446 -277.875546) (xy 310.52287 -277.875546) (xy 310.52287 -277.82413) (xy 310.530913 -277.773348)
			(xy 310.546801 -277.724449) (xy 310.570144 -277.678637) (xy 310.600365 -277.637041) (xy 310.636721 -277.600685)
			(xy 310.678317 -277.570464) (xy 310.724129 -277.547121) (xy 310.773028 -277.531233) (xy 310.82381 -277.52319)
			(xy 310.875226 -277.52319) (xy 310.926008 -277.531233) (xy 310.974907 -277.547121) (xy 311.020719 -277.570464)
			(xy 311.062315 -277.600685) (xy 311.098671 -277.637041) (xy 311.128892 -277.678637) (xy 311.152235 -277.724449)
			(xy 311.168123 -277.773348) (xy 311.176166 -277.82413) (xy 311.17667 -277.849838) (xy 311.493928 -277.849838)
			(xy 311.497888 -277.800784) (xy 311.509665 -277.753) (xy 311.528956 -277.707724) (xy 311.555259 -277.666128)
			(xy 311.587894 -277.629291) (xy 311.626015 -277.598166) (xy 311.668636 -277.573559) (xy 311.714652 -277.556107)
			(xy 311.762871 -277.546263) (xy 311.812046 -277.544282) (xy 311.860901 -277.550214) (xy 311.908172 -277.563906)
			(xy 311.952634 -277.585004) (xy 311.993137 -277.61296) (xy 312.02863 -277.647052) (xy 312.058195 -277.686396)
			(xy 312.081066 -277.729973) (xy 312.09665 -277.776654) (xy 312.104545 -277.825231) (xy 312.10504 -277.849838)
			(xy 312.104545 -277.874445) (xy 312.104366 -277.875546) (xy 312.423044 -277.875546) (xy 312.423044 -277.82413)
			(xy 312.431087 -277.773348) (xy 312.446975 -277.724449) (xy 312.470318 -277.678637) (xy 312.500539 -277.637041)
			(xy 312.536895 -277.600685) (xy 312.578491 -277.570464) (xy 312.624303 -277.547121) (xy 312.673202 -277.531233)
			(xy 312.723984 -277.52319) (xy 312.7754 -277.52319) (xy 312.826182 -277.531233) (xy 312.875081 -277.547121)
			(xy 312.920893 -277.570464) (xy 312.962489 -277.600685) (xy 312.998845 -277.637041) (xy 313.029066 -277.678637)
			(xy 313.052409 -277.724449) (xy 313.068297 -277.773348) (xy 313.07634 -277.82413) (xy 313.076844 -277.849838)
			(xy 313.394102 -277.849838) (xy 313.398062 -277.800784) (xy 313.409839 -277.753) (xy 313.42913 -277.707724)
			(xy 313.455433 -277.666128) (xy 313.488068 -277.629291) (xy 313.526189 -277.598166) (xy 313.56881 -277.573559)
			(xy 313.614826 -277.556107) (xy 313.663045 -277.546263) (xy 313.71222 -277.544282) (xy 313.761075 -277.550214)
			(xy 313.808346 -277.563906) (xy 313.852808 -277.585004) (xy 313.893311 -277.61296) (xy 313.928804 -277.647052)
			(xy 313.958369 -277.686396) (xy 313.98124 -277.729973) (xy 313.996824 -277.776654) (xy 314.004719 -277.825231)
			(xy 314.005214 -277.849838) (xy 314.344062 -277.849838) (xy 314.348022 -277.800784) (xy 314.359799 -277.753)
			(xy 314.37909 -277.707724) (xy 314.405393 -277.666128) (xy 314.438028 -277.629291) (xy 314.476149 -277.598166)
			(xy 314.51877 -277.573559) (xy 314.564786 -277.556107) (xy 314.613005 -277.546263) (xy 314.66218 -277.544282)
			(xy 314.711035 -277.550214) (xy 314.758306 -277.563906) (xy 314.802768 -277.585004) (xy 314.843271 -277.61296)
			(xy 314.878764 -277.647052) (xy 314.908329 -277.686396) (xy 314.9312 -277.729973) (xy 314.946784 -277.776654)
			(xy 314.954679 -277.825231) (xy 314.955174 -277.849838) (xy 314.954679 -277.874445) (xy 314.946784 -277.923022)
			(xy 314.9312 -277.969703) (xy 314.908329 -278.01328) (xy 314.878764 -278.052624) (xy 314.843271 -278.086716)
			(xy 314.802768 -278.114672) (xy 314.758306 -278.13577) (xy 314.711035 -278.149462) (xy 314.66218 -278.155394)
			(xy 314.613005 -278.153413) (xy 314.564786 -278.143569) (xy 314.51877 -278.126117) (xy 314.476149 -278.10151)
			(xy 314.438028 -278.070385) (xy 314.405393 -278.033548) (xy 314.37909 -277.991952) (xy 314.359799 -277.946676)
			(xy 314.348022 -277.898892) (xy 314.344062 -277.849838) (xy 314.005214 -277.849838) (xy 314.004719 -277.874445)
			(xy 313.996824 -277.923022) (xy 313.98124 -277.969703) (xy 313.958369 -278.01328) (xy 313.928804 -278.052624)
			(xy 313.893311 -278.086716) (xy 313.852808 -278.114672) (xy 313.808346 -278.13577) (xy 313.761075 -278.149462)
			(xy 313.71222 -278.155394) (xy 313.663045 -278.153413) (xy 313.614826 -278.143569) (xy 313.56881 -278.126117)
			(xy 313.526189 -278.10151) (xy 313.488068 -278.070385) (xy 313.455433 -278.033548) (xy 313.42913 -277.991952)
			(xy 313.409839 -277.946676) (xy 313.398062 -277.898892) (xy 313.394102 -277.849838) (xy 313.076844 -277.849838)
			(xy 313.07634 -277.875546) (xy 313.068297 -277.926328) (xy 313.052409 -277.975227) (xy 313.029066 -278.021039)
			(xy 312.998845 -278.062635) (xy 312.962489 -278.098991) (xy 312.920893 -278.129212) (xy 312.875081 -278.152555)
			(xy 312.826182 -278.168443) (xy 312.7754 -278.176486) (xy 312.723984 -278.176486) (xy 312.673202 -278.168443)
			(xy 312.624303 -278.152555) (xy 312.578491 -278.129212) (xy 312.536895 -278.098991) (xy 312.500539 -278.062635)
			(xy 312.470318 -278.021039) (xy 312.446975 -277.975227) (xy 312.431087 -277.926328) (xy 312.423044 -277.875546)
			(xy 312.104366 -277.875546) (xy 312.09665 -277.923022) (xy 312.081066 -277.969703) (xy 312.058195 -278.01328)
			(xy 312.02863 -278.052624) (xy 311.993137 -278.086716) (xy 311.952634 -278.114672) (xy 311.908172 -278.13577)
			(xy 311.860901 -278.149462) (xy 311.812046 -278.155394) (xy 311.762871 -278.153413) (xy 311.714652 -278.143569)
			(xy 311.668636 -278.126117) (xy 311.626015 -278.10151) (xy 311.587894 -278.070385) (xy 311.555259 -278.033548)
			(xy 311.528956 -277.991952) (xy 311.509665 -277.946676) (xy 311.497888 -277.898892) (xy 311.493928 -277.849838)
			(xy 311.17667 -277.849838) (xy 311.176166 -277.875546) (xy 311.168123 -277.926328) (xy 311.152235 -277.975227)
			(xy 311.128892 -278.021039) (xy 311.098671 -278.062635) (xy 311.062315 -278.098991) (xy 311.020719 -278.129212)
			(xy 310.974907 -278.152555) (xy 310.926008 -278.168443) (xy 310.875226 -278.176486) (xy 310.82381 -278.176486)
			(xy 310.773028 -278.168443) (xy 310.724129 -278.152555) (xy 310.678317 -278.129212) (xy 310.636721 -278.098991)
			(xy 310.600365 -278.062635) (xy 310.570144 -278.021039) (xy 310.546801 -277.975227) (xy 310.530913 -277.926328)
			(xy 310.52287 -277.875546) (xy 310.204446 -277.875546) (xy 310.19673 -277.923022) (xy 310.181146 -277.969703)
			(xy 310.158275 -278.01328) (xy 310.12871 -278.052624) (xy 310.093217 -278.086716) (xy 310.052714 -278.114672)
			(xy 310.008252 -278.13577) (xy 309.960981 -278.149462) (xy 309.912126 -278.155394) (xy 309.862951 -278.153413)
			(xy 309.814732 -278.143569) (xy 309.768716 -278.126117) (xy 309.726095 -278.10151) (xy 309.687974 -278.070385)
			(xy 309.655339 -278.033548) (xy 309.629036 -277.991952) (xy 309.609745 -277.946676) (xy 309.597968 -277.898892)
			(xy 309.594008 -277.849838) (xy 309.27675 -277.849838) (xy 309.276246 -277.875546) (xy 309.268203 -277.926328)
			(xy 309.252315 -277.975227) (xy 309.228972 -278.021039) (xy 309.198751 -278.062635) (xy 309.162395 -278.098991)
			(xy 309.120799 -278.129212) (xy 309.074987 -278.152555) (xy 309.026088 -278.168443) (xy 308.975306 -278.176486)
			(xy 308.92389 -278.176486) (xy 308.873108 -278.168443) (xy 308.824209 -278.152555) (xy 308.778397 -278.129212)
			(xy 308.736801 -278.098991) (xy 308.700445 -278.062635) (xy 308.670224 -278.021039) (xy 308.646881 -277.975227)
			(xy 308.630993 -277.926328) (xy 308.62295 -277.875546) (xy 308.304526 -277.875546) (xy 308.29681 -277.923022)
			(xy 308.281226 -277.969703) (xy 308.258355 -278.01328) (xy 308.22879 -278.052624) (xy 308.193297 -278.086716)
			(xy 308.152794 -278.114672) (xy 308.108332 -278.13577) (xy 308.061061 -278.149462) (xy 308.012206 -278.155394)
			(xy 307.963031 -278.153413) (xy 307.914812 -278.143569) (xy 307.868796 -278.126117) (xy 307.826175 -278.10151)
			(xy 307.788054 -278.070385) (xy 307.755419 -278.033548) (xy 307.729116 -277.991952) (xy 307.709825 -277.946676)
			(xy 307.698048 -277.898892) (xy 307.694088 -277.849838) (xy 307.37683 -277.849838) (xy 307.376326 -277.875546)
			(xy 307.368283 -277.926328) (xy 307.352395 -277.975227) (xy 307.329052 -278.021039) (xy 307.298831 -278.062635)
			(xy 307.262475 -278.098991) (xy 307.220879 -278.129212) (xy 307.175067 -278.152555) (xy 307.126168 -278.168443)
			(xy 307.075386 -278.176486) (xy 307.02397 -278.176486) (xy 306.973188 -278.168443) (xy 306.924289 -278.152555)
			(xy 306.878477 -278.129212) (xy 306.836881 -278.098991) (xy 306.800525 -278.062635) (xy 306.770304 -278.021039)
			(xy 306.746961 -277.975227) (xy 306.731073 -277.926328) (xy 306.72303 -277.875546) (xy 306.404352 -277.875546)
			(xy 306.396636 -277.923022) (xy 306.381052 -277.969703) (xy 306.358181 -278.01328) (xy 306.328616 -278.052624)
			(xy 306.293123 -278.086716) (xy 306.25262 -278.114672) (xy 306.208158 -278.13577) (xy 306.160887 -278.149462)
			(xy 306.112032 -278.155394) (xy 306.062857 -278.153413) (xy 306.014638 -278.143569) (xy 305.968622 -278.126117)
			(xy 305.926001 -278.10151) (xy 305.88788 -278.070385) (xy 305.855245 -278.033548) (xy 305.828942 -277.991952)
			(xy 305.809651 -277.946676) (xy 305.797874 -277.898892) (xy 305.793914 -277.849838) (xy 305.476656 -277.849838)
			(xy 305.476152 -277.875546) (xy 305.468109 -277.926328) (xy 305.452221 -277.975227) (xy 305.428878 -278.021039)
			(xy 305.398657 -278.062635) (xy 305.362301 -278.098991) (xy 305.320705 -278.129212) (xy 305.274893 -278.152555)
			(xy 305.225994 -278.168443) (xy 305.175212 -278.176486) (xy 305.123796 -278.176486) (xy 305.073014 -278.168443)
			(xy 305.024115 -278.152555) (xy 304.978303 -278.129212) (xy 304.936707 -278.098991) (xy 304.900351 -278.062635)
			(xy 304.87013 -278.021039) (xy 304.846787 -277.975227) (xy 304.830899 -277.926328) (xy 304.822856 -277.875546)
			(xy 304.504432 -277.875546) (xy 304.496716 -277.923022) (xy 304.481132 -277.969703) (xy 304.458261 -278.01328)
			(xy 304.428696 -278.052624) (xy 304.393203 -278.086716) (xy 304.3527 -278.114672) (xy 304.308238 -278.13577)
			(xy 304.260967 -278.149462) (xy 304.212112 -278.155394) (xy 304.162937 -278.153413) (xy 304.114718 -278.143569)
			(xy 304.068702 -278.126117) (xy 304.026081 -278.10151) (xy 303.98796 -278.070385) (xy 303.955325 -278.033548)
			(xy 303.929022 -277.991952) (xy 303.909731 -277.946676) (xy 303.897954 -277.898892) (xy 303.893994 -277.849838)
			(xy 303.576736 -277.849838) (xy 303.576232 -277.875546) (xy 303.568189 -277.926328) (xy 303.552301 -277.975227)
			(xy 303.528958 -278.021039) (xy 303.498737 -278.062635) (xy 303.462381 -278.098991) (xy 303.420785 -278.129212)
			(xy 303.374973 -278.152555) (xy 303.326074 -278.168443) (xy 303.275292 -278.176486) (xy 303.223876 -278.176486)
			(xy 303.173094 -278.168443) (xy 303.124195 -278.152555) (xy 303.078383 -278.129212) (xy 303.036787 -278.098991)
			(xy 303.000431 -278.062635) (xy 302.97021 -278.021039) (xy 302.946867 -277.975227) (xy 302.930979 -277.926328)
			(xy 302.922936 -277.875546) (xy 302.604512 -277.875546) (xy 302.596796 -277.923022) (xy 302.581212 -277.969703)
			(xy 302.558341 -278.01328) (xy 302.528776 -278.052624) (xy 302.493283 -278.086716) (xy 302.45278 -278.114672)
			(xy 302.408318 -278.13577) (xy 302.361047 -278.149462) (xy 302.312192 -278.155394) (xy 302.263017 -278.153413)
			(xy 302.214798 -278.143569) (xy 302.168782 -278.126117) (xy 302.126161 -278.10151) (xy 302.08804 -278.070385)
			(xy 302.055405 -278.033548) (xy 302.029102 -277.991952) (xy 302.009811 -277.946676) (xy 301.998034 -277.898892)
			(xy 301.994074 -277.849838) (xy 301.676816 -277.849838) (xy 301.676312 -277.875546) (xy 301.668269 -277.926328)
			(xy 301.652381 -277.975227) (xy 301.629038 -278.021039) (xy 301.598817 -278.062635) (xy 301.562461 -278.098991)
			(xy 301.520865 -278.129212) (xy 301.475053 -278.152555) (xy 301.426154 -278.168443) (xy 301.375372 -278.176486)
			(xy 301.323956 -278.176486) (xy 301.273174 -278.168443) (xy 301.224275 -278.152555) (xy 301.178463 -278.129212)
			(xy 301.136867 -278.098991) (xy 301.100511 -278.062635) (xy 301.07029 -278.021039) (xy 301.046947 -277.975227)
			(xy 301.031059 -277.926328) (xy 301.023016 -277.875546) (xy 300.704338 -277.875546) (xy 300.696622 -277.923022)
			(xy 300.681038 -277.969703) (xy 300.658167 -278.01328) (xy 300.628602 -278.052624) (xy 300.593109 -278.086716)
			(xy 300.552606 -278.114672) (xy 300.508144 -278.13577) (xy 300.460873 -278.149462) (xy 300.412018 -278.155394)
			(xy 300.362843 -278.153413) (xy 300.314624 -278.143569) (xy 300.268608 -278.126117) (xy 300.225987 -278.10151)
			(xy 300.187866 -278.070385) (xy 300.155231 -278.033548) (xy 300.128928 -277.991952) (xy 300.109637 -277.946676)
			(xy 300.09786 -277.898892) (xy 300.0939 -277.849838) (xy 299.776642 -277.849838) (xy 299.776138 -277.875546)
			(xy 299.768095 -277.926328) (xy 299.752207 -277.975227) (xy 299.728864 -278.021039) (xy 299.698643 -278.062635)
			(xy 299.662287 -278.098991) (xy 299.620691 -278.129212) (xy 299.574879 -278.152555) (xy 299.52598 -278.168443)
			(xy 299.475198 -278.176486) (xy 299.423782 -278.176486) (xy 299.373 -278.168443) (xy 299.324101 -278.152555)
			(xy 299.278289 -278.129212) (xy 299.236693 -278.098991) (xy 299.200337 -278.062635) (xy 299.170116 -278.021039)
			(xy 299.146773 -277.975227) (xy 299.130885 -277.926328) (xy 299.122842 -277.875546) (xy 298.804418 -277.875546)
			(xy 298.796702 -277.923022) (xy 298.781118 -277.969703) (xy 298.758247 -278.01328) (xy 298.728682 -278.052624)
			(xy 298.693189 -278.086716) (xy 298.652686 -278.114672) (xy 298.608224 -278.13577) (xy 298.560953 -278.149462)
			(xy 298.512098 -278.155394) (xy 298.462923 -278.153413) (xy 298.414704 -278.143569) (xy 298.368688 -278.126117)
			(xy 298.326067 -278.10151) (xy 298.287946 -278.070385) (xy 298.255311 -278.033548) (xy 298.229008 -277.991952)
			(xy 298.209717 -277.946676) (xy 298.19794 -277.898892) (xy 298.19398 -277.849838) (xy 297.876722 -277.849838)
			(xy 297.876218 -277.875546) (xy 297.868175 -277.926328) (xy 297.852287 -277.975227) (xy 297.828944 -278.021039)
			(xy 297.798723 -278.062635) (xy 297.762367 -278.098991) (xy 297.720771 -278.129212) (xy 297.674959 -278.152555)
			(xy 297.62606 -278.168443) (xy 297.575278 -278.176486) (xy 297.523862 -278.176486) (xy 297.47308 -278.168443)
			(xy 297.424181 -278.152555) (xy 297.378369 -278.129212) (xy 297.336773 -278.098991) (xy 297.300417 -278.062635)
			(xy 297.270196 -278.021039) (xy 297.246853 -277.975227) (xy 297.230965 -277.926328) (xy 297.222922 -277.875546)
			(xy 296.904498 -277.875546) (xy 296.896782 -277.923022) (xy 296.881198 -277.969703) (xy 296.858327 -278.01328)
			(xy 296.828762 -278.052624) (xy 296.793269 -278.086716) (xy 296.752766 -278.114672) (xy 296.708304 -278.13577)
			(xy 296.661033 -278.149462) (xy 296.612178 -278.155394) (xy 296.563003 -278.153413) (xy 296.514784 -278.143569)
			(xy 296.468768 -278.126117) (xy 296.426147 -278.10151) (xy 296.388026 -278.070385) (xy 296.355391 -278.033548)
			(xy 296.329088 -277.991952) (xy 296.309797 -277.946676) (xy 296.29802 -277.898892) (xy 296.29406 -277.849838)
			(xy 295.976802 -277.849838) (xy 295.976298 -277.875546) (xy 295.968255 -277.926328) (xy 295.952367 -277.975227)
			(xy 295.929024 -278.021039) (xy 295.898803 -278.062635) (xy 295.862447 -278.098991) (xy 295.820851 -278.129212)
			(xy 295.775039 -278.152555) (xy 295.72614 -278.168443) (xy 295.675358 -278.176486) (xy 295.623942 -278.176486)
			(xy 295.57316 -278.168443) (xy 295.524261 -278.152555) (xy 295.478449 -278.129212) (xy 295.436853 -278.098991)
			(xy 295.400497 -278.062635) (xy 295.370276 -278.021039) (xy 295.346933 -277.975227) (xy 295.331045 -277.926328)
			(xy 295.323002 -277.875546) (xy 295.004324 -277.875546) (xy 294.996608 -277.923022) (xy 294.981024 -277.969703)
			(xy 294.958153 -278.01328) (xy 294.928588 -278.052624) (xy 294.893095 -278.086716) (xy 294.852592 -278.114672)
			(xy 294.80813 -278.13577) (xy 294.760859 -278.149462) (xy 294.712004 -278.155394) (xy 294.662829 -278.153413)
			(xy 294.61461 -278.143569) (xy 294.568594 -278.126117) (xy 294.525973 -278.10151) (xy 294.487852 -278.070385)
			(xy 294.455217 -278.033548) (xy 294.428914 -277.991952) (xy 294.409623 -277.946676) (xy 294.397846 -277.898892)
			(xy 294.393886 -277.849838) (xy 294.076628 -277.849838) (xy 294.076124 -277.875546) (xy 294.068081 -277.926328)
			(xy 294.052193 -277.975227) (xy 294.02885 -278.021039) (xy 293.998629 -278.062635) (xy 293.962273 -278.098991)
			(xy 293.920677 -278.129212) (xy 293.874865 -278.152555) (xy 293.825966 -278.168443) (xy 293.775184 -278.176486)
			(xy 293.723768 -278.176486) (xy 293.672986 -278.168443) (xy 293.624087 -278.152555) (xy 293.578275 -278.129212)
			(xy 293.536679 -278.098991) (xy 293.500323 -278.062635) (xy 293.470102 -278.021039) (xy 293.446759 -277.975227)
			(xy 293.430871 -277.926328) (xy 293.422828 -277.875546) (xy 293.104404 -277.875546) (xy 293.096688 -277.923022)
			(xy 293.081104 -277.969703) (xy 293.058233 -278.01328) (xy 293.028668 -278.052624) (xy 292.993175 -278.086716)
			(xy 292.952672 -278.114672) (xy 292.90821 -278.13577) (xy 292.860939 -278.149462) (xy 292.812084 -278.155394)
			(xy 292.762909 -278.153413) (xy 292.71469 -278.143569) (xy 292.668674 -278.126117) (xy 292.626053 -278.10151)
			(xy 292.587932 -278.070385) (xy 292.555297 -278.033548) (xy 292.528994 -277.991952) (xy 292.509703 -277.946676)
			(xy 292.497926 -277.898892) (xy 292.493966 -277.849838) (xy 292.176708 -277.849838) (xy 292.176204 -277.875546)
			(xy 292.168161 -277.926328) (xy 292.152273 -277.975227) (xy 292.12893 -278.021039) (xy 292.098709 -278.062635)
			(xy 292.062353 -278.098991) (xy 292.020757 -278.129212) (xy 291.974945 -278.152555) (xy 291.926046 -278.168443)
			(xy 291.875264 -278.176486) (xy 291.823848 -278.176486) (xy 291.773066 -278.168443) (xy 291.724167 -278.152555)
			(xy 291.678355 -278.129212) (xy 291.636759 -278.098991) (xy 291.600403 -278.062635) (xy 291.570182 -278.021039)
			(xy 291.546839 -277.975227) (xy 291.530951 -277.926328) (xy 291.522908 -277.875546) (xy 291.204484 -277.875546)
			(xy 291.196768 -277.923022) (xy 291.181184 -277.969703) (xy 291.158313 -278.01328) (xy 291.128748 -278.052624)
			(xy 291.093255 -278.086716) (xy 291.052752 -278.114672) (xy 291.00829 -278.13577) (xy 290.961019 -278.149462)
			(xy 290.912164 -278.155394) (xy 290.862989 -278.153413) (xy 290.81477 -278.143569) (xy 290.768754 -278.126117)
			(xy 290.726133 -278.10151) (xy 290.688012 -278.070385) (xy 290.655377 -278.033548) (xy 290.629074 -277.991952)
			(xy 290.609783 -277.946676) (xy 290.598006 -277.898892) (xy 290.594046 -277.849838) (xy 290.277042 -277.849838)
			(xy 290.276538 -277.875546) (xy 290.268495 -277.926328) (xy 290.252607 -277.975227) (xy 290.229264 -278.021039)
			(xy 290.199043 -278.062635) (xy 290.162687 -278.098991) (xy 290.121091 -278.129212) (xy 290.075279 -278.152555)
			(xy 290.02638 -278.168443) (xy 289.975598 -278.176486) (xy 289.924182 -278.176486) (xy 289.8734 -278.168443)
			(xy 289.824501 -278.152555) (xy 289.778689 -278.129212) (xy 289.737093 -278.098991) (xy 289.700737 -278.062635)
			(xy 289.670516 -278.021039) (xy 289.647173 -277.975227) (xy 289.631285 -277.926328) (xy 289.623242 -277.875546)
			(xy 289.304564 -277.875546) (xy 289.296848 -277.923022) (xy 289.281264 -277.969703) (xy 289.258393 -278.01328)
			(xy 289.228828 -278.052624) (xy 289.193335 -278.086716) (xy 289.152832 -278.114672) (xy 289.10837 -278.13577)
			(xy 289.061099 -278.149462) (xy 289.012244 -278.155394) (xy 288.963069 -278.153413) (xy 288.91485 -278.143569)
			(xy 288.868834 -278.126117) (xy 288.826213 -278.10151) (xy 288.788092 -278.070385) (xy 288.755457 -278.033548)
			(xy 288.729154 -277.991952) (xy 288.709863 -277.946676) (xy 288.698086 -277.898892) (xy 288.694126 -277.849838)
			(xy 288.376868 -277.849838) (xy 288.376364 -277.875546) (xy 288.368321 -277.926328) (xy 288.352433 -277.975227)
			(xy 288.32909 -278.021039) (xy 288.298869 -278.062635) (xy 288.262513 -278.098991) (xy 288.220917 -278.129212)
			(xy 288.175105 -278.152555) (xy 288.126206 -278.168443) (xy 288.075424 -278.176486) (xy 288.024008 -278.176486)
			(xy 287.973226 -278.168443) (xy 287.924327 -278.152555) (xy 287.878515 -278.129212) (xy 287.836919 -278.098991)
			(xy 287.800563 -278.062635) (xy 287.770342 -278.021039) (xy 287.746999 -277.975227) (xy 287.731111 -277.926328)
			(xy 287.723068 -277.875546) (xy 287.40439 -277.875546) (xy 287.396674 -277.923022) (xy 287.38109 -277.969703)
			(xy 287.358219 -278.01328) (xy 287.328654 -278.052624) (xy 287.293161 -278.086716) (xy 287.252658 -278.114672)
			(xy 287.208196 -278.13577) (xy 287.160925 -278.149462) (xy 287.11207 -278.155394) (xy 287.062895 -278.153413)
			(xy 287.014676 -278.143569) (xy 286.96866 -278.126117) (xy 286.926039 -278.10151) (xy 286.887918 -278.070385)
			(xy 286.855283 -278.033548) (xy 286.82898 -277.991952) (xy 286.809689 -277.946676) (xy 286.797912 -277.898892)
			(xy 286.793952 -277.849838) (xy 286.476948 -277.849838) (xy 286.476444 -277.875546) (xy 286.468401 -277.926328)
			(xy 286.452513 -277.975227) (xy 286.42917 -278.021039) (xy 286.398949 -278.062635) (xy 286.362593 -278.098991)
			(xy 286.320997 -278.129212) (xy 286.275185 -278.152555) (xy 286.226286 -278.168443) (xy 286.175504 -278.176486)
			(xy 286.124088 -278.176486) (xy 286.073306 -278.168443) (xy 286.024407 -278.152555) (xy 285.978595 -278.129212)
			(xy 285.936999 -278.098991) (xy 285.900643 -278.062635) (xy 285.870422 -278.021039) (xy 285.847079 -277.975227)
			(xy 285.831191 -277.926328) (xy 285.823148 -277.875546) (xy 285.50447 -277.875546) (xy 285.496754 -277.923022)
			(xy 285.48117 -277.969703) (xy 285.458299 -278.01328) (xy 285.428734 -278.052624) (xy 285.393241 -278.086716)
			(xy 285.352738 -278.114672) (xy 285.308276 -278.13577) (xy 285.261005 -278.149462) (xy 285.21215 -278.155394)
			(xy 285.162975 -278.153413) (xy 285.114756 -278.143569) (xy 285.06874 -278.126117) (xy 285.026119 -278.10151)
			(xy 284.987998 -278.070385) (xy 284.955363 -278.033548) (xy 284.92906 -277.991952) (xy 284.909769 -277.946676)
			(xy 284.897992 -277.898892) (xy 284.894032 -277.849838) (xy 284.577028 -277.849838) (xy 284.576524 -277.875546)
			(xy 284.568481 -277.926328) (xy 284.552593 -277.975227) (xy 284.52925 -278.021039) (xy 284.499029 -278.062635)
			(xy 284.462673 -278.098991) (xy 284.421077 -278.129212) (xy 284.375265 -278.152555) (xy 284.326366 -278.168443)
			(xy 284.275584 -278.176486) (xy 284.224168 -278.176486) (xy 284.173386 -278.168443) (xy 284.124487 -278.152555)
			(xy 284.078675 -278.129212) (xy 284.037079 -278.098991) (xy 284.000723 -278.062635) (xy 283.970502 -278.021039)
			(xy 283.947159 -277.975227) (xy 283.931271 -277.926328) (xy 283.923228 -277.875546) (xy 283.60455 -277.875546)
			(xy 283.596834 -277.923022) (xy 283.58125 -277.969703) (xy 283.558379 -278.01328) (xy 283.528814 -278.052624)
			(xy 283.493321 -278.086716) (xy 283.452818 -278.114672) (xy 283.408356 -278.13577) (xy 283.361085 -278.149462)
			(xy 283.31223 -278.155394) (xy 283.263055 -278.153413) (xy 283.214836 -278.143569) (xy 283.16882 -278.126117)
			(xy 283.126199 -278.10151) (xy 283.088078 -278.070385) (xy 283.055443 -278.033548) (xy 283.02914 -277.991952)
			(xy 283.009849 -277.946676) (xy 282.998072 -277.898892) (xy 282.994112 -277.849838) (xy 282.676056 -277.849838)
			(xy 282.676056 -277.875485) (xy 282.66802 -277.926222) (xy 282.652146 -277.975077) (xy 282.628825 -278.020847)
			(xy 282.598631 -278.062406) (xy 282.562308 -278.09873) (xy 282.520749 -278.128924) (xy 282.474979 -278.152246)
			(xy 282.426124 -278.16812) (xy 282.375387 -278.176156) (xy 282.349702 -278.176736) (xy 282.316936 -278.175212)
			(xy 282.306014 -278.174196) (xy 282.285948 -278.1808) (xy 282.22194 -278.238712) (xy 282.214433 -278.246257)
			(xy 282.205778 -278.265677) (xy 282.205176 -278.276304) (xy 282.205176 -278.324818) (xy 282.205132 -278.334172)
			(xy 282.204113 -278.352852) (xy 282.203144 -278.362156) (xy 282.20162 -278.37384) (xy 282.20924 -278.39543)
			(xy 282.28163 -278.468328) (xy 282.30322 -278.475948) (xy 282.314904 -278.474678) (xy 282.349702 -278.4729)
			(xy 282.37539 -278.473404) (xy 282.426133 -278.481441) (xy 282.474994 -278.497317) (xy 282.52077 -278.520642)
			(xy 282.562334 -278.55084) (xy 282.598662 -278.587168) (xy 282.628859 -278.628732) (xy 282.652183 -278.674508)
			(xy 282.668059 -278.723369) (xy 282.676096 -278.774112) (xy 282.676096 -278.799798) (xy 282.994112 -278.799798)
			(xy 282.998072 -278.750744) (xy 283.009849 -278.70296) (xy 283.02914 -278.657684) (xy 283.055443 -278.616088)
			(xy 283.088078 -278.579251) (xy 283.126199 -278.548126) (xy 283.16882 -278.523519) (xy 283.214836 -278.506067)
			(xy 283.263055 -278.496223) (xy 283.31223 -278.494242) (xy 283.361085 -278.500174) (xy 283.408356 -278.513866)
			(xy 283.452818 -278.534964) (xy 283.493321 -278.56292) (xy 283.528814 -278.597012) (xy 283.558379 -278.636356)
			(xy 283.58125 -278.679933) (xy 283.596834 -278.726614) (xy 283.604729 -278.775191) (xy 283.605224 -278.799798)
			(xy 283.604729 -278.824405) (xy 283.60455 -278.825506) (xy 283.923228 -278.825506) (xy 283.923228 -278.77409)
			(xy 283.931271 -278.723308) (xy 283.947159 -278.674409) (xy 283.970502 -278.628597) (xy 284.000723 -278.587001)
			(xy 284.037079 -278.550645) (xy 284.078675 -278.520424) (xy 284.124487 -278.497081) (xy 284.173386 -278.481193)
			(xy 284.224168 -278.47315) (xy 284.275584 -278.47315) (xy 284.326366 -278.481193) (xy 284.375265 -278.497081)
			(xy 284.421077 -278.520424) (xy 284.462673 -278.550645) (xy 284.499029 -278.587001) (xy 284.52925 -278.628597)
			(xy 284.552593 -278.674409) (xy 284.568481 -278.723308) (xy 284.576524 -278.77409) (xy 284.577028 -278.799798)
			(xy 284.894032 -278.799798) (xy 284.897992 -278.750744) (xy 284.909769 -278.70296) (xy 284.92906 -278.657684)
			(xy 284.955363 -278.616088) (xy 284.987998 -278.579251) (xy 285.026119 -278.548126) (xy 285.06874 -278.523519)
			(xy 285.114756 -278.506067) (xy 285.162975 -278.496223) (xy 285.21215 -278.494242) (xy 285.261005 -278.500174)
			(xy 285.308276 -278.513866) (xy 285.352738 -278.534964) (xy 285.393241 -278.56292) (xy 285.428734 -278.597012)
			(xy 285.458299 -278.636356) (xy 285.48117 -278.679933) (xy 285.496754 -278.726614) (xy 285.504649 -278.775191)
			(xy 285.505144 -278.799798) (xy 285.504649 -278.824405) (xy 285.50447 -278.825506) (xy 285.823148 -278.825506)
			(xy 285.823148 -278.77409) (xy 285.831191 -278.723308) (xy 285.847079 -278.674409) (xy 285.870422 -278.628597)
			(xy 285.900643 -278.587001) (xy 285.936999 -278.550645) (xy 285.978595 -278.520424) (xy 286.024407 -278.497081)
			(xy 286.073306 -278.481193) (xy 286.124088 -278.47315) (xy 286.175504 -278.47315) (xy 286.226286 -278.481193)
			(xy 286.275185 -278.497081) (xy 286.320997 -278.520424) (xy 286.362593 -278.550645) (xy 286.398949 -278.587001)
			(xy 286.42917 -278.628597) (xy 286.452513 -278.674409) (xy 286.468401 -278.723308) (xy 286.476444 -278.77409)
			(xy 286.476948 -278.799798) (xy 286.793952 -278.799798) (xy 286.797912 -278.750744) (xy 286.809689 -278.70296)
			(xy 286.82898 -278.657684) (xy 286.855283 -278.616088) (xy 286.887918 -278.579251) (xy 286.926039 -278.548126)
			(xy 286.96866 -278.523519) (xy 287.014676 -278.506067) (xy 287.062895 -278.496223) (xy 287.11207 -278.494242)
			(xy 287.160925 -278.500174) (xy 287.208196 -278.513866) (xy 287.252658 -278.534964) (xy 287.293161 -278.56292)
			(xy 287.328654 -278.597012) (xy 287.358219 -278.636356) (xy 287.38109 -278.679933) (xy 287.396674 -278.726614)
			(xy 287.404569 -278.775191) (xy 287.405064 -278.799798) (xy 287.404569 -278.824405) (xy 287.40439 -278.825506)
			(xy 287.723068 -278.825506) (xy 287.723068 -278.77409) (xy 287.731111 -278.723308) (xy 287.746999 -278.674409)
			(xy 287.770342 -278.628597) (xy 287.800563 -278.587001) (xy 287.836919 -278.550645) (xy 287.878515 -278.520424)
			(xy 287.924327 -278.497081) (xy 287.973226 -278.481193) (xy 288.024008 -278.47315) (xy 288.075424 -278.47315)
			(xy 288.126206 -278.481193) (xy 288.175105 -278.497081) (xy 288.220917 -278.520424) (xy 288.262513 -278.550645)
			(xy 288.298869 -278.587001) (xy 288.32909 -278.628597) (xy 288.352433 -278.674409) (xy 288.368321 -278.723308)
			(xy 288.376364 -278.77409) (xy 288.376868 -278.799798) (xy 288.694126 -278.799798) (xy 288.698086 -278.750744)
			(xy 288.709863 -278.70296) (xy 288.729154 -278.657684) (xy 288.755457 -278.616088) (xy 288.788092 -278.579251)
			(xy 288.826213 -278.548126) (xy 288.868834 -278.523519) (xy 288.91485 -278.506067) (xy 288.963069 -278.496223)
			(xy 289.012244 -278.494242) (xy 289.061099 -278.500174) (xy 289.10837 -278.513866) (xy 289.152832 -278.534964)
			(xy 289.193335 -278.56292) (xy 289.228828 -278.597012) (xy 289.258393 -278.636356) (xy 289.281264 -278.679933)
			(xy 289.296848 -278.726614) (xy 289.304743 -278.775191) (xy 289.305238 -278.799798) (xy 289.304743 -278.824405)
			(xy 289.304564 -278.825506) (xy 289.623242 -278.825506) (xy 289.623242 -278.77409) (xy 289.631285 -278.723308)
			(xy 289.647173 -278.674409) (xy 289.670516 -278.628597) (xy 289.700737 -278.587001) (xy 289.737093 -278.550645)
			(xy 289.778689 -278.520424) (xy 289.824501 -278.497081) (xy 289.8734 -278.481193) (xy 289.924182 -278.47315)
			(xy 289.975598 -278.47315) (xy 290.02638 -278.481193) (xy 290.075279 -278.497081) (xy 290.121091 -278.520424)
			(xy 290.162687 -278.550645) (xy 290.199043 -278.587001) (xy 290.229264 -278.628597) (xy 290.252607 -278.674409)
			(xy 290.268495 -278.723308) (xy 290.276538 -278.77409) (xy 290.277042 -278.799798) (xy 290.594046 -278.799798)
			(xy 290.598006 -278.750744) (xy 290.609783 -278.70296) (xy 290.629074 -278.657684) (xy 290.655377 -278.616088)
			(xy 290.688012 -278.579251) (xy 290.726133 -278.548126) (xy 290.768754 -278.523519) (xy 290.81477 -278.506067)
			(xy 290.862989 -278.496223) (xy 290.912164 -278.494242) (xy 290.961019 -278.500174) (xy 291.00829 -278.513866)
			(xy 291.052752 -278.534964) (xy 291.093255 -278.56292) (xy 291.128748 -278.597012) (xy 291.158313 -278.636356)
			(xy 291.181184 -278.679933) (xy 291.196768 -278.726614) (xy 291.204663 -278.775191) (xy 291.205158 -278.799798)
			(xy 291.204663 -278.824405) (xy 291.204484 -278.825506) (xy 291.522908 -278.825506) (xy 291.522908 -278.77409)
			(xy 291.530951 -278.723308) (xy 291.546839 -278.674409) (xy 291.570182 -278.628597) (xy 291.600403 -278.587001)
			(xy 291.636759 -278.550645) (xy 291.678355 -278.520424) (xy 291.724167 -278.497081) (xy 291.773066 -278.481193)
			(xy 291.823848 -278.47315) (xy 291.875264 -278.47315) (xy 291.926046 -278.481193) (xy 291.974945 -278.497081)
			(xy 292.020757 -278.520424) (xy 292.062353 -278.550645) (xy 292.098709 -278.587001) (xy 292.12893 -278.628597)
			(xy 292.152273 -278.674409) (xy 292.168161 -278.723308) (xy 292.176204 -278.77409) (xy 292.176708 -278.799798)
			(xy 292.493966 -278.799798) (xy 292.497926 -278.750744) (xy 292.509703 -278.70296) (xy 292.528994 -278.657684)
			(xy 292.555297 -278.616088) (xy 292.587932 -278.579251) (xy 292.626053 -278.548126) (xy 292.668674 -278.523519)
			(xy 292.71469 -278.506067) (xy 292.762909 -278.496223) (xy 292.812084 -278.494242) (xy 292.860939 -278.500174)
			(xy 292.90821 -278.513866) (xy 292.952672 -278.534964) (xy 292.993175 -278.56292) (xy 293.028668 -278.597012)
			(xy 293.058233 -278.636356) (xy 293.081104 -278.679933) (xy 293.096688 -278.726614) (xy 293.104583 -278.775191)
			(xy 293.105078 -278.799798) (xy 293.104583 -278.824405) (xy 293.104404 -278.825506) (xy 293.422828 -278.825506)
			(xy 293.422828 -278.77409) (xy 293.430871 -278.723308) (xy 293.446759 -278.674409) (xy 293.470102 -278.628597)
			(xy 293.500323 -278.587001) (xy 293.536679 -278.550645) (xy 293.578275 -278.520424) (xy 293.624087 -278.497081)
			(xy 293.672986 -278.481193) (xy 293.723768 -278.47315) (xy 293.775184 -278.47315) (xy 293.825966 -278.481193)
			(xy 293.874865 -278.497081) (xy 293.920677 -278.520424) (xy 293.962273 -278.550645) (xy 293.998629 -278.587001)
			(xy 294.02885 -278.628597) (xy 294.052193 -278.674409) (xy 294.068081 -278.723308) (xy 294.076124 -278.77409)
			(xy 294.076628 -278.799798) (xy 294.393886 -278.799798) (xy 294.397846 -278.750744) (xy 294.409623 -278.70296)
			(xy 294.428914 -278.657684) (xy 294.455217 -278.616088) (xy 294.487852 -278.579251) (xy 294.525973 -278.548126)
			(xy 294.568594 -278.523519) (xy 294.61461 -278.506067) (xy 294.662829 -278.496223) (xy 294.712004 -278.494242)
			(xy 294.760859 -278.500174) (xy 294.80813 -278.513866) (xy 294.852592 -278.534964) (xy 294.893095 -278.56292)
			(xy 294.928588 -278.597012) (xy 294.958153 -278.636356) (xy 294.981024 -278.679933) (xy 294.996608 -278.726614)
			(xy 295.004503 -278.775191) (xy 295.004998 -278.799798) (xy 295.004503 -278.824405) (xy 295.004324 -278.825506)
			(xy 295.323002 -278.825506) (xy 295.323002 -278.77409) (xy 295.331045 -278.723308) (xy 295.346933 -278.674409)
			(xy 295.370276 -278.628597) (xy 295.400497 -278.587001) (xy 295.436853 -278.550645) (xy 295.478449 -278.520424)
			(xy 295.524261 -278.497081) (xy 295.57316 -278.481193) (xy 295.623942 -278.47315) (xy 295.675358 -278.47315)
			(xy 295.72614 -278.481193) (xy 295.775039 -278.497081) (xy 295.820851 -278.520424) (xy 295.862447 -278.550645)
			(xy 295.898803 -278.587001) (xy 295.929024 -278.628597) (xy 295.952367 -278.674409) (xy 295.968255 -278.723308)
			(xy 295.976298 -278.77409) (xy 295.976802 -278.799798) (xy 296.29406 -278.799798) (xy 296.29802 -278.750744)
			(xy 296.309797 -278.70296) (xy 296.329088 -278.657684) (xy 296.355391 -278.616088) (xy 296.388026 -278.579251)
			(xy 296.426147 -278.548126) (xy 296.468768 -278.523519) (xy 296.514784 -278.506067) (xy 296.563003 -278.496223)
			(xy 296.612178 -278.494242) (xy 296.661033 -278.500174) (xy 296.708304 -278.513866) (xy 296.752766 -278.534964)
			(xy 296.793269 -278.56292) (xy 296.828762 -278.597012) (xy 296.858327 -278.636356) (xy 296.881198 -278.679933)
			(xy 296.896782 -278.726614) (xy 296.904677 -278.775191) (xy 296.905172 -278.799798) (xy 296.904677 -278.824405)
			(xy 296.904498 -278.825506) (xy 297.222922 -278.825506) (xy 297.222922 -278.77409) (xy 297.230965 -278.723308)
			(xy 297.246853 -278.674409) (xy 297.270196 -278.628597) (xy 297.300417 -278.587001) (xy 297.336773 -278.550645)
			(xy 297.378369 -278.520424) (xy 297.424181 -278.497081) (xy 297.47308 -278.481193) (xy 297.523862 -278.47315)
			(xy 297.575278 -278.47315) (xy 297.62606 -278.481193) (xy 297.674959 -278.497081) (xy 297.720771 -278.520424)
			(xy 297.762367 -278.550645) (xy 297.798723 -278.587001) (xy 297.828944 -278.628597) (xy 297.852287 -278.674409)
			(xy 297.868175 -278.723308) (xy 297.876218 -278.77409) (xy 297.876722 -278.799798) (xy 298.19398 -278.799798)
			(xy 298.19794 -278.750744) (xy 298.209717 -278.70296) (xy 298.229008 -278.657684) (xy 298.255311 -278.616088)
			(xy 298.287946 -278.579251) (xy 298.326067 -278.548126) (xy 298.368688 -278.523519) (xy 298.414704 -278.506067)
			(xy 298.462923 -278.496223) (xy 298.512098 -278.494242) (xy 298.560953 -278.500174) (xy 298.608224 -278.513866)
			(xy 298.652686 -278.534964) (xy 298.693189 -278.56292) (xy 298.728682 -278.597012) (xy 298.758247 -278.636356)
			(xy 298.781118 -278.679933) (xy 298.796702 -278.726614) (xy 298.804597 -278.775191) (xy 298.805092 -278.799798)
			(xy 298.804597 -278.824405) (xy 298.804418 -278.825506) (xy 299.122842 -278.825506) (xy 299.122842 -278.77409)
			(xy 299.130885 -278.723308) (xy 299.146773 -278.674409) (xy 299.170116 -278.628597) (xy 299.200337 -278.587001)
			(xy 299.236693 -278.550645) (xy 299.278289 -278.520424) (xy 299.324101 -278.497081) (xy 299.373 -278.481193)
			(xy 299.423782 -278.47315) (xy 299.475198 -278.47315) (xy 299.52598 -278.481193) (xy 299.574879 -278.497081)
			(xy 299.620691 -278.520424) (xy 299.662287 -278.550645) (xy 299.698643 -278.587001) (xy 299.728864 -278.628597)
			(xy 299.752207 -278.674409) (xy 299.768095 -278.723308) (xy 299.776138 -278.77409) (xy 299.776642 -278.799798)
			(xy 300.0939 -278.799798) (xy 300.09786 -278.750744) (xy 300.109637 -278.70296) (xy 300.128928 -278.657684)
			(xy 300.155231 -278.616088) (xy 300.187866 -278.579251) (xy 300.225987 -278.548126) (xy 300.268608 -278.523519)
			(xy 300.314624 -278.506067) (xy 300.362843 -278.496223) (xy 300.412018 -278.494242) (xy 300.460873 -278.500174)
			(xy 300.508144 -278.513866) (xy 300.552606 -278.534964) (xy 300.593109 -278.56292) (xy 300.628602 -278.597012)
			(xy 300.658167 -278.636356) (xy 300.681038 -278.679933) (xy 300.696622 -278.726614) (xy 300.704517 -278.775191)
			(xy 300.705012 -278.799798) (xy 300.704517 -278.824405) (xy 300.704338 -278.825506) (xy 301.023016 -278.825506)
			(xy 301.023016 -278.77409) (xy 301.031059 -278.723308) (xy 301.046947 -278.674409) (xy 301.07029 -278.628597)
			(xy 301.100511 -278.587001) (xy 301.136867 -278.550645) (xy 301.178463 -278.520424) (xy 301.224275 -278.497081)
			(xy 301.273174 -278.481193) (xy 301.323956 -278.47315) (xy 301.375372 -278.47315) (xy 301.426154 -278.481193)
			(xy 301.475053 -278.497081) (xy 301.520865 -278.520424) (xy 301.562461 -278.550645) (xy 301.598817 -278.587001)
			(xy 301.629038 -278.628597) (xy 301.652381 -278.674409) (xy 301.668269 -278.723308) (xy 301.676312 -278.77409)
			(xy 301.676816 -278.799798) (xy 301.994074 -278.799798) (xy 301.998034 -278.750744) (xy 302.009811 -278.70296)
			(xy 302.029102 -278.657684) (xy 302.055405 -278.616088) (xy 302.08804 -278.579251) (xy 302.126161 -278.548126)
			(xy 302.168782 -278.523519) (xy 302.214798 -278.506067) (xy 302.263017 -278.496223) (xy 302.312192 -278.494242)
			(xy 302.361047 -278.500174) (xy 302.408318 -278.513866) (xy 302.45278 -278.534964) (xy 302.493283 -278.56292)
			(xy 302.528776 -278.597012) (xy 302.558341 -278.636356) (xy 302.581212 -278.679933) (xy 302.596796 -278.726614)
			(xy 302.604691 -278.775191) (xy 302.605186 -278.799798) (xy 302.604691 -278.824405) (xy 302.604512 -278.825506)
			(xy 302.922936 -278.825506) (xy 302.922936 -278.77409) (xy 302.930979 -278.723308) (xy 302.946867 -278.674409)
			(xy 302.97021 -278.628597) (xy 303.000431 -278.587001) (xy 303.036787 -278.550645) (xy 303.078383 -278.520424)
			(xy 303.124195 -278.497081) (xy 303.173094 -278.481193) (xy 303.223876 -278.47315) (xy 303.275292 -278.47315)
			(xy 303.326074 -278.481193) (xy 303.374973 -278.497081) (xy 303.420785 -278.520424) (xy 303.462381 -278.550645)
			(xy 303.498737 -278.587001) (xy 303.528958 -278.628597) (xy 303.552301 -278.674409) (xy 303.568189 -278.723308)
			(xy 303.576232 -278.77409) (xy 303.576736 -278.799798) (xy 303.893994 -278.799798) (xy 303.897954 -278.750744)
			(xy 303.909731 -278.70296) (xy 303.929022 -278.657684) (xy 303.955325 -278.616088) (xy 303.98796 -278.579251)
			(xy 304.026081 -278.548126) (xy 304.068702 -278.523519) (xy 304.114718 -278.506067) (xy 304.162937 -278.496223)
			(xy 304.212112 -278.494242) (xy 304.260967 -278.500174) (xy 304.308238 -278.513866) (xy 304.3527 -278.534964)
			(xy 304.393203 -278.56292) (xy 304.428696 -278.597012) (xy 304.458261 -278.636356) (xy 304.481132 -278.679933)
			(xy 304.496716 -278.726614) (xy 304.504611 -278.775191) (xy 304.505106 -278.799798) (xy 304.504611 -278.824405)
			(xy 304.504432 -278.825506) (xy 304.822856 -278.825506) (xy 304.822856 -278.77409) (xy 304.830899 -278.723308)
			(xy 304.846787 -278.674409) (xy 304.87013 -278.628597) (xy 304.900351 -278.587001) (xy 304.936707 -278.550645)
			(xy 304.978303 -278.520424) (xy 305.024115 -278.497081) (xy 305.073014 -278.481193) (xy 305.123796 -278.47315)
			(xy 305.175212 -278.47315) (xy 305.225994 -278.481193) (xy 305.274893 -278.497081) (xy 305.320705 -278.520424)
			(xy 305.362301 -278.550645) (xy 305.398657 -278.587001) (xy 305.428878 -278.628597) (xy 305.452221 -278.674409)
			(xy 305.468109 -278.723308) (xy 305.476152 -278.77409) (xy 305.476656 -278.799798) (xy 305.793914 -278.799798)
			(xy 305.797874 -278.750744) (xy 305.809651 -278.70296) (xy 305.828942 -278.657684) (xy 305.855245 -278.616088)
			(xy 305.88788 -278.579251) (xy 305.926001 -278.548126) (xy 305.968622 -278.523519) (xy 306.014638 -278.506067)
			(xy 306.062857 -278.496223) (xy 306.112032 -278.494242) (xy 306.160887 -278.500174) (xy 306.208158 -278.513866)
			(xy 306.25262 -278.534964) (xy 306.293123 -278.56292) (xy 306.328616 -278.597012) (xy 306.358181 -278.636356)
			(xy 306.381052 -278.679933) (xy 306.396636 -278.726614) (xy 306.404531 -278.775191) (xy 306.405026 -278.799798)
			(xy 306.404531 -278.824405) (xy 306.404352 -278.825506) (xy 306.72303 -278.825506) (xy 306.72303 -278.77409)
			(xy 306.731073 -278.723308) (xy 306.746961 -278.674409) (xy 306.770304 -278.628597) (xy 306.800525 -278.587001)
			(xy 306.836881 -278.550645) (xy 306.878477 -278.520424) (xy 306.924289 -278.497081) (xy 306.973188 -278.481193)
			(xy 307.02397 -278.47315) (xy 307.075386 -278.47315) (xy 307.126168 -278.481193) (xy 307.175067 -278.497081)
			(xy 307.220879 -278.520424) (xy 307.262475 -278.550645) (xy 307.298831 -278.587001) (xy 307.329052 -278.628597)
			(xy 307.352395 -278.674409) (xy 307.368283 -278.723308) (xy 307.376326 -278.77409) (xy 307.37683 -278.799798)
			(xy 307.694088 -278.799798) (xy 307.698048 -278.750744) (xy 307.709825 -278.70296) (xy 307.729116 -278.657684)
			(xy 307.755419 -278.616088) (xy 307.788054 -278.579251) (xy 307.826175 -278.548126) (xy 307.868796 -278.523519)
			(xy 307.914812 -278.506067) (xy 307.963031 -278.496223) (xy 308.012206 -278.494242) (xy 308.061061 -278.500174)
			(xy 308.108332 -278.513866) (xy 308.152794 -278.534964) (xy 308.193297 -278.56292) (xy 308.22879 -278.597012)
			(xy 308.258355 -278.636356) (xy 308.281226 -278.679933) (xy 308.29681 -278.726614) (xy 308.304705 -278.775191)
			(xy 308.3052 -278.799798) (xy 308.304705 -278.824405) (xy 308.304526 -278.825506) (xy 308.62295 -278.825506)
			(xy 308.62295 -278.77409) (xy 308.630993 -278.723308) (xy 308.646881 -278.674409) (xy 308.670224 -278.628597)
			(xy 308.700445 -278.587001) (xy 308.736801 -278.550645) (xy 308.778397 -278.520424) (xy 308.824209 -278.497081)
			(xy 308.873108 -278.481193) (xy 308.92389 -278.47315) (xy 308.975306 -278.47315) (xy 309.026088 -278.481193)
			(xy 309.074987 -278.497081) (xy 309.120799 -278.520424) (xy 309.162395 -278.550645) (xy 309.198751 -278.587001)
			(xy 309.228972 -278.628597) (xy 309.252315 -278.674409) (xy 309.268203 -278.723308) (xy 309.276246 -278.77409)
			(xy 309.27675 -278.799798) (xy 309.594008 -278.799798) (xy 309.597968 -278.750744) (xy 309.609745 -278.70296)
			(xy 309.629036 -278.657684) (xy 309.655339 -278.616088) (xy 309.687974 -278.579251) (xy 309.726095 -278.548126)
			(xy 309.768716 -278.523519) (xy 309.814732 -278.506067) (xy 309.862951 -278.496223) (xy 309.912126 -278.494242)
			(xy 309.960981 -278.500174) (xy 310.008252 -278.513866) (xy 310.052714 -278.534964) (xy 310.093217 -278.56292)
			(xy 310.12871 -278.597012) (xy 310.158275 -278.636356) (xy 310.181146 -278.679933) (xy 310.19673 -278.726614)
			(xy 310.204625 -278.775191) (xy 310.20512 -278.799798) (xy 310.204625 -278.824405) (xy 310.204446 -278.825506)
			(xy 310.52287 -278.825506) (xy 310.52287 -278.77409) (xy 310.530913 -278.723308) (xy 310.546801 -278.674409)
			(xy 310.570144 -278.628597) (xy 310.600365 -278.587001) (xy 310.636721 -278.550645) (xy 310.678317 -278.520424)
			(xy 310.724129 -278.497081) (xy 310.773028 -278.481193) (xy 310.82381 -278.47315) (xy 310.875226 -278.47315)
			(xy 310.926008 -278.481193) (xy 310.974907 -278.497081) (xy 311.020719 -278.520424) (xy 311.062315 -278.550645)
			(xy 311.098671 -278.587001) (xy 311.128892 -278.628597) (xy 311.152235 -278.674409) (xy 311.168123 -278.723308)
			(xy 311.176166 -278.77409) (xy 311.17667 -278.799798) (xy 311.493928 -278.799798) (xy 311.497888 -278.750744)
			(xy 311.509665 -278.70296) (xy 311.528956 -278.657684) (xy 311.555259 -278.616088) (xy 311.587894 -278.579251)
			(xy 311.626015 -278.548126) (xy 311.668636 -278.523519) (xy 311.714652 -278.506067) (xy 311.762871 -278.496223)
			(xy 311.812046 -278.494242) (xy 311.860901 -278.500174) (xy 311.908172 -278.513866) (xy 311.952634 -278.534964)
			(xy 311.993137 -278.56292) (xy 312.02863 -278.597012) (xy 312.058195 -278.636356) (xy 312.081066 -278.679933)
			(xy 312.09665 -278.726614) (xy 312.104545 -278.775191) (xy 312.10504 -278.799798) (xy 312.104545 -278.824405)
			(xy 312.104366 -278.825506) (xy 312.423044 -278.825506) (xy 312.423044 -278.77409) (xy 312.431087 -278.723308)
			(xy 312.446975 -278.674409) (xy 312.470318 -278.628597) (xy 312.500539 -278.587001) (xy 312.536895 -278.550645)
			(xy 312.578491 -278.520424) (xy 312.624303 -278.497081) (xy 312.673202 -278.481193) (xy 312.723984 -278.47315)
			(xy 312.7754 -278.47315) (xy 312.826182 -278.481193) (xy 312.875081 -278.497081) (xy 312.920893 -278.520424)
			(xy 312.962489 -278.550645) (xy 312.998845 -278.587001) (xy 313.029066 -278.628597) (xy 313.052409 -278.674409)
			(xy 313.068297 -278.723308) (xy 313.07634 -278.77409) (xy 313.076844 -278.799798) (xy 313.394102 -278.799798)
			(xy 313.398062 -278.750744) (xy 313.409839 -278.70296) (xy 313.42913 -278.657684) (xy 313.455433 -278.616088)
			(xy 313.488068 -278.579251) (xy 313.526189 -278.548126) (xy 313.56881 -278.523519) (xy 313.614826 -278.506067)
			(xy 313.663045 -278.496223) (xy 313.71222 -278.494242) (xy 313.761075 -278.500174) (xy 313.808346 -278.513866)
			(xy 313.852808 -278.534964) (xy 313.893311 -278.56292) (xy 313.928804 -278.597012) (xy 313.958369 -278.636356)
			(xy 313.98124 -278.679933) (xy 313.996824 -278.726614) (xy 314.004719 -278.775191) (xy 314.005214 -278.799798)
			(xy 314.344062 -278.799798) (xy 314.348022 -278.750744) (xy 314.359799 -278.70296) (xy 314.37909 -278.657684)
			(xy 314.405393 -278.616088) (xy 314.438028 -278.579251) (xy 314.476149 -278.548126) (xy 314.51877 -278.523519)
			(xy 314.564786 -278.506067) (xy 314.613005 -278.496223) (xy 314.66218 -278.494242) (xy 314.711035 -278.500174)
			(xy 314.758306 -278.513866) (xy 314.802768 -278.534964) (xy 314.843271 -278.56292) (xy 314.878764 -278.597012)
			(xy 314.908329 -278.636356) (xy 314.9312 -278.679933) (xy 314.946784 -278.726614) (xy 314.954679 -278.775191)
			(xy 314.955174 -278.799798) (xy 314.954679 -278.824405) (xy 314.946784 -278.872982) (xy 314.9312 -278.919663)
			(xy 314.908329 -278.96324) (xy 314.878764 -279.002584) (xy 314.843271 -279.036676) (xy 314.802768 -279.064632)
			(xy 314.758306 -279.08573) (xy 314.711035 -279.099422) (xy 314.66218 -279.105354) (xy 314.613005 -279.103373)
			(xy 314.564786 -279.093529) (xy 314.51877 -279.076077) (xy 314.476149 -279.05147) (xy 314.438028 -279.020345)
			(xy 314.405393 -278.983508) (xy 314.37909 -278.941912) (xy 314.359799 -278.896636) (xy 314.348022 -278.848852)
			(xy 314.344062 -278.799798) (xy 314.005214 -278.799798) (xy 314.004719 -278.824405) (xy 313.996824 -278.872982)
			(xy 313.98124 -278.919663) (xy 313.958369 -278.96324) (xy 313.928804 -279.002584) (xy 313.893311 -279.036676)
			(xy 313.852808 -279.064632) (xy 313.808346 -279.08573) (xy 313.761075 -279.099422) (xy 313.71222 -279.105354)
			(xy 313.663045 -279.103373) (xy 313.614826 -279.093529) (xy 313.56881 -279.076077) (xy 313.526189 -279.05147)
			(xy 313.488068 -279.020345) (xy 313.455433 -278.983508) (xy 313.42913 -278.941912) (xy 313.409839 -278.896636)
			(xy 313.398062 -278.848852) (xy 313.394102 -278.799798) (xy 313.076844 -278.799798) (xy 313.07634 -278.825506)
			(xy 313.068297 -278.876288) (xy 313.052409 -278.925187) (xy 313.029066 -278.970999) (xy 312.998845 -279.012595)
			(xy 312.962489 -279.048951) (xy 312.920893 -279.079172) (xy 312.875081 -279.102515) (xy 312.826182 -279.118403)
			(xy 312.7754 -279.126446) (xy 312.723984 -279.126446) (xy 312.673202 -279.118403) (xy 312.624303 -279.102515)
			(xy 312.578491 -279.079172) (xy 312.536895 -279.048951) (xy 312.500539 -279.012595) (xy 312.470318 -278.970999)
			(xy 312.446975 -278.925187) (xy 312.431087 -278.876288) (xy 312.423044 -278.825506) (xy 312.104366 -278.825506)
			(xy 312.09665 -278.872982) (xy 312.081066 -278.919663) (xy 312.058195 -278.96324) (xy 312.02863 -279.002584)
			(xy 311.993137 -279.036676) (xy 311.952634 -279.064632) (xy 311.908172 -279.08573) (xy 311.860901 -279.099422)
			(xy 311.812046 -279.105354) (xy 311.762871 -279.103373) (xy 311.714652 -279.093529) (xy 311.668636 -279.076077)
			(xy 311.626015 -279.05147) (xy 311.587894 -279.020345) (xy 311.555259 -278.983508) (xy 311.528956 -278.941912)
			(xy 311.509665 -278.896636) (xy 311.497888 -278.848852) (xy 311.493928 -278.799798) (xy 311.17667 -278.799798)
			(xy 311.176166 -278.825506) (xy 311.168123 -278.876288) (xy 311.152235 -278.925187) (xy 311.128892 -278.970999)
			(xy 311.098671 -279.012595) (xy 311.062315 -279.048951) (xy 311.020719 -279.079172) (xy 310.974907 -279.102515)
			(xy 310.926008 -279.118403) (xy 310.875226 -279.126446) (xy 310.82381 -279.126446) (xy 310.773028 -279.118403)
			(xy 310.724129 -279.102515) (xy 310.678317 -279.079172) (xy 310.636721 -279.048951) (xy 310.600365 -279.012595)
			(xy 310.570144 -278.970999) (xy 310.546801 -278.925187) (xy 310.530913 -278.876288) (xy 310.52287 -278.825506)
			(xy 310.204446 -278.825506) (xy 310.19673 -278.872982) (xy 310.181146 -278.919663) (xy 310.158275 -278.96324)
			(xy 310.12871 -279.002584) (xy 310.093217 -279.036676) (xy 310.052714 -279.064632) (xy 310.008252 -279.08573)
			(xy 309.960981 -279.099422) (xy 309.912126 -279.105354) (xy 309.862951 -279.103373) (xy 309.814732 -279.093529)
			(xy 309.768716 -279.076077) (xy 309.726095 -279.05147) (xy 309.687974 -279.020345) (xy 309.655339 -278.983508)
			(xy 309.629036 -278.941912) (xy 309.609745 -278.896636) (xy 309.597968 -278.848852) (xy 309.594008 -278.799798)
			(xy 309.27675 -278.799798) (xy 309.276246 -278.825506) (xy 309.268203 -278.876288) (xy 309.252315 -278.925187)
			(xy 309.228972 -278.970999) (xy 309.198751 -279.012595) (xy 309.162395 -279.048951) (xy 309.120799 -279.079172)
			(xy 309.074987 -279.102515) (xy 309.026088 -279.118403) (xy 308.975306 -279.126446) (xy 308.92389 -279.126446)
			(xy 308.873108 -279.118403) (xy 308.824209 -279.102515) (xy 308.778397 -279.079172) (xy 308.736801 -279.048951)
			(xy 308.700445 -279.012595) (xy 308.670224 -278.970999) (xy 308.646881 -278.925187) (xy 308.630993 -278.876288)
			(xy 308.62295 -278.825506) (xy 308.304526 -278.825506) (xy 308.29681 -278.872982) (xy 308.281226 -278.919663)
			(xy 308.258355 -278.96324) (xy 308.22879 -279.002584) (xy 308.193297 -279.036676) (xy 308.152794 -279.064632)
			(xy 308.108332 -279.08573) (xy 308.061061 -279.099422) (xy 308.012206 -279.105354) (xy 307.963031 -279.103373)
			(xy 307.914812 -279.093529) (xy 307.868796 -279.076077) (xy 307.826175 -279.05147) (xy 307.788054 -279.020345)
			(xy 307.755419 -278.983508) (xy 307.729116 -278.941912) (xy 307.709825 -278.896636) (xy 307.698048 -278.848852)
			(xy 307.694088 -278.799798) (xy 307.37683 -278.799798) (xy 307.376326 -278.825506) (xy 307.368283 -278.876288)
			(xy 307.352395 -278.925187) (xy 307.329052 -278.970999) (xy 307.298831 -279.012595) (xy 307.262475 -279.048951)
			(xy 307.220879 -279.079172) (xy 307.175067 -279.102515) (xy 307.126168 -279.118403) (xy 307.075386 -279.126446)
			(xy 307.02397 -279.126446) (xy 306.973188 -279.118403) (xy 306.924289 -279.102515) (xy 306.878477 -279.079172)
			(xy 306.836881 -279.048951) (xy 306.800525 -279.012595) (xy 306.770304 -278.970999) (xy 306.746961 -278.925187)
			(xy 306.731073 -278.876288) (xy 306.72303 -278.825506) (xy 306.404352 -278.825506) (xy 306.396636 -278.872982)
			(xy 306.381052 -278.919663) (xy 306.358181 -278.96324) (xy 306.328616 -279.002584) (xy 306.293123 -279.036676)
			(xy 306.25262 -279.064632) (xy 306.208158 -279.08573) (xy 306.160887 -279.099422) (xy 306.112032 -279.105354)
			(xy 306.062857 -279.103373) (xy 306.014638 -279.093529) (xy 305.968622 -279.076077) (xy 305.926001 -279.05147)
			(xy 305.88788 -279.020345) (xy 305.855245 -278.983508) (xy 305.828942 -278.941912) (xy 305.809651 -278.896636)
			(xy 305.797874 -278.848852) (xy 305.793914 -278.799798) (xy 305.476656 -278.799798) (xy 305.476152 -278.825506)
			(xy 305.468109 -278.876288) (xy 305.452221 -278.925187) (xy 305.428878 -278.970999) (xy 305.398657 -279.012595)
			(xy 305.362301 -279.048951) (xy 305.320705 -279.079172) (xy 305.274893 -279.102515) (xy 305.225994 -279.118403)
			(xy 305.175212 -279.126446) (xy 305.123796 -279.126446) (xy 305.073014 -279.118403) (xy 305.024115 -279.102515)
			(xy 304.978303 -279.079172) (xy 304.936707 -279.048951) (xy 304.900351 -279.012595) (xy 304.87013 -278.970999)
			(xy 304.846787 -278.925187) (xy 304.830899 -278.876288) (xy 304.822856 -278.825506) (xy 304.504432 -278.825506)
			(xy 304.496716 -278.872982) (xy 304.481132 -278.919663) (xy 304.458261 -278.96324) (xy 304.428696 -279.002584)
			(xy 304.393203 -279.036676) (xy 304.3527 -279.064632) (xy 304.308238 -279.08573) (xy 304.260967 -279.099422)
			(xy 304.212112 -279.105354) (xy 304.162937 -279.103373) (xy 304.114718 -279.093529) (xy 304.068702 -279.076077)
			(xy 304.026081 -279.05147) (xy 303.98796 -279.020345) (xy 303.955325 -278.983508) (xy 303.929022 -278.941912)
			(xy 303.909731 -278.896636) (xy 303.897954 -278.848852) (xy 303.893994 -278.799798) (xy 303.576736 -278.799798)
			(xy 303.576232 -278.825506) (xy 303.568189 -278.876288) (xy 303.552301 -278.925187) (xy 303.528958 -278.970999)
			(xy 303.498737 -279.012595) (xy 303.462381 -279.048951) (xy 303.420785 -279.079172) (xy 303.374973 -279.102515)
			(xy 303.326074 -279.118403) (xy 303.275292 -279.126446) (xy 303.223876 -279.126446) (xy 303.173094 -279.118403)
			(xy 303.124195 -279.102515) (xy 303.078383 -279.079172) (xy 303.036787 -279.048951) (xy 303.000431 -279.012595)
			(xy 302.97021 -278.970999) (xy 302.946867 -278.925187) (xy 302.930979 -278.876288) (xy 302.922936 -278.825506)
			(xy 302.604512 -278.825506) (xy 302.596796 -278.872982) (xy 302.581212 -278.919663) (xy 302.558341 -278.96324)
			(xy 302.528776 -279.002584) (xy 302.493283 -279.036676) (xy 302.45278 -279.064632) (xy 302.408318 -279.08573)
			(xy 302.361047 -279.099422) (xy 302.312192 -279.105354) (xy 302.263017 -279.103373) (xy 302.214798 -279.093529)
			(xy 302.168782 -279.076077) (xy 302.126161 -279.05147) (xy 302.08804 -279.020345) (xy 302.055405 -278.983508)
			(xy 302.029102 -278.941912) (xy 302.009811 -278.896636) (xy 301.998034 -278.848852) (xy 301.994074 -278.799798)
			(xy 301.676816 -278.799798) (xy 301.676312 -278.825506) (xy 301.668269 -278.876288) (xy 301.652381 -278.925187)
			(xy 301.629038 -278.970999) (xy 301.598817 -279.012595) (xy 301.562461 -279.048951) (xy 301.520865 -279.079172)
			(xy 301.475053 -279.102515) (xy 301.426154 -279.118403) (xy 301.375372 -279.126446) (xy 301.323956 -279.126446)
			(xy 301.273174 -279.118403) (xy 301.224275 -279.102515) (xy 301.178463 -279.079172) (xy 301.136867 -279.048951)
			(xy 301.100511 -279.012595) (xy 301.07029 -278.970999) (xy 301.046947 -278.925187) (xy 301.031059 -278.876288)
			(xy 301.023016 -278.825506) (xy 300.704338 -278.825506) (xy 300.696622 -278.872982) (xy 300.681038 -278.919663)
			(xy 300.658167 -278.96324) (xy 300.628602 -279.002584) (xy 300.593109 -279.036676) (xy 300.552606 -279.064632)
			(xy 300.508144 -279.08573) (xy 300.460873 -279.099422) (xy 300.412018 -279.105354) (xy 300.362843 -279.103373)
			(xy 300.314624 -279.093529) (xy 300.268608 -279.076077) (xy 300.225987 -279.05147) (xy 300.187866 -279.020345)
			(xy 300.155231 -278.983508) (xy 300.128928 -278.941912) (xy 300.109637 -278.896636) (xy 300.09786 -278.848852)
			(xy 300.0939 -278.799798) (xy 299.776642 -278.799798) (xy 299.776138 -278.825506) (xy 299.768095 -278.876288)
			(xy 299.752207 -278.925187) (xy 299.728864 -278.970999) (xy 299.698643 -279.012595) (xy 299.662287 -279.048951)
			(xy 299.620691 -279.079172) (xy 299.574879 -279.102515) (xy 299.52598 -279.118403) (xy 299.475198 -279.126446)
			(xy 299.423782 -279.126446) (xy 299.373 -279.118403) (xy 299.324101 -279.102515) (xy 299.278289 -279.079172)
			(xy 299.236693 -279.048951) (xy 299.200337 -279.012595) (xy 299.170116 -278.970999) (xy 299.146773 -278.925187)
			(xy 299.130885 -278.876288) (xy 299.122842 -278.825506) (xy 298.804418 -278.825506) (xy 298.796702 -278.872982)
			(xy 298.781118 -278.919663) (xy 298.758247 -278.96324) (xy 298.728682 -279.002584) (xy 298.693189 -279.036676)
			(xy 298.652686 -279.064632) (xy 298.608224 -279.08573) (xy 298.560953 -279.099422) (xy 298.512098 -279.105354)
			(xy 298.462923 -279.103373) (xy 298.414704 -279.093529) (xy 298.368688 -279.076077) (xy 298.326067 -279.05147)
			(xy 298.287946 -279.020345) (xy 298.255311 -278.983508) (xy 298.229008 -278.941912) (xy 298.209717 -278.896636)
			(xy 298.19794 -278.848852) (xy 298.19398 -278.799798) (xy 297.876722 -278.799798) (xy 297.876218 -278.825506)
			(xy 297.868175 -278.876288) (xy 297.852287 -278.925187) (xy 297.828944 -278.970999) (xy 297.798723 -279.012595)
			(xy 297.762367 -279.048951) (xy 297.720771 -279.079172) (xy 297.674959 -279.102515) (xy 297.62606 -279.118403)
			(xy 297.575278 -279.126446) (xy 297.523862 -279.126446) (xy 297.47308 -279.118403) (xy 297.424181 -279.102515)
			(xy 297.378369 -279.079172) (xy 297.336773 -279.048951) (xy 297.300417 -279.012595) (xy 297.270196 -278.970999)
			(xy 297.246853 -278.925187) (xy 297.230965 -278.876288) (xy 297.222922 -278.825506) (xy 296.904498 -278.825506)
			(xy 296.896782 -278.872982) (xy 296.881198 -278.919663) (xy 296.858327 -278.96324) (xy 296.828762 -279.002584)
			(xy 296.793269 -279.036676) (xy 296.752766 -279.064632) (xy 296.708304 -279.08573) (xy 296.661033 -279.099422)
			(xy 296.612178 -279.105354) (xy 296.563003 -279.103373) (xy 296.514784 -279.093529) (xy 296.468768 -279.076077)
			(xy 296.426147 -279.05147) (xy 296.388026 -279.020345) (xy 296.355391 -278.983508) (xy 296.329088 -278.941912)
			(xy 296.309797 -278.896636) (xy 296.29802 -278.848852) (xy 296.29406 -278.799798) (xy 295.976802 -278.799798)
			(xy 295.976298 -278.825506) (xy 295.968255 -278.876288) (xy 295.952367 -278.925187) (xy 295.929024 -278.970999)
			(xy 295.898803 -279.012595) (xy 295.862447 -279.048951) (xy 295.820851 -279.079172) (xy 295.775039 -279.102515)
			(xy 295.72614 -279.118403) (xy 295.675358 -279.126446) (xy 295.623942 -279.126446) (xy 295.57316 -279.118403)
			(xy 295.524261 -279.102515) (xy 295.478449 -279.079172) (xy 295.436853 -279.048951) (xy 295.400497 -279.012595)
			(xy 295.370276 -278.970999) (xy 295.346933 -278.925187) (xy 295.331045 -278.876288) (xy 295.323002 -278.825506)
			(xy 295.004324 -278.825506) (xy 294.996608 -278.872982) (xy 294.981024 -278.919663) (xy 294.958153 -278.96324)
			(xy 294.928588 -279.002584) (xy 294.893095 -279.036676) (xy 294.852592 -279.064632) (xy 294.80813 -279.08573)
			(xy 294.760859 -279.099422) (xy 294.712004 -279.105354) (xy 294.662829 -279.103373) (xy 294.61461 -279.093529)
			(xy 294.568594 -279.076077) (xy 294.525973 -279.05147) (xy 294.487852 -279.020345) (xy 294.455217 -278.983508)
			(xy 294.428914 -278.941912) (xy 294.409623 -278.896636) (xy 294.397846 -278.848852) (xy 294.393886 -278.799798)
			(xy 294.076628 -278.799798) (xy 294.076124 -278.825506) (xy 294.068081 -278.876288) (xy 294.052193 -278.925187)
			(xy 294.02885 -278.970999) (xy 293.998629 -279.012595) (xy 293.962273 -279.048951) (xy 293.920677 -279.079172)
			(xy 293.874865 -279.102515) (xy 293.825966 -279.118403) (xy 293.775184 -279.126446) (xy 293.723768 -279.126446)
			(xy 293.672986 -279.118403) (xy 293.624087 -279.102515) (xy 293.578275 -279.079172) (xy 293.536679 -279.048951)
			(xy 293.500323 -279.012595) (xy 293.470102 -278.970999) (xy 293.446759 -278.925187) (xy 293.430871 -278.876288)
			(xy 293.422828 -278.825506) (xy 293.104404 -278.825506) (xy 293.096688 -278.872982) (xy 293.081104 -278.919663)
			(xy 293.058233 -278.96324) (xy 293.028668 -279.002584) (xy 292.993175 -279.036676) (xy 292.952672 -279.064632)
			(xy 292.90821 -279.08573) (xy 292.860939 -279.099422) (xy 292.812084 -279.105354) (xy 292.762909 -279.103373)
			(xy 292.71469 -279.093529) (xy 292.668674 -279.076077) (xy 292.626053 -279.05147) (xy 292.587932 -279.020345)
			(xy 292.555297 -278.983508) (xy 292.528994 -278.941912) (xy 292.509703 -278.896636) (xy 292.497926 -278.848852)
			(xy 292.493966 -278.799798) (xy 292.176708 -278.799798) (xy 292.176204 -278.825506) (xy 292.168161 -278.876288)
			(xy 292.152273 -278.925187) (xy 292.12893 -278.970999) (xy 292.098709 -279.012595) (xy 292.062353 -279.048951)
			(xy 292.020757 -279.079172) (xy 291.974945 -279.102515) (xy 291.926046 -279.118403) (xy 291.875264 -279.126446)
			(xy 291.823848 -279.126446) (xy 291.773066 -279.118403) (xy 291.724167 -279.102515) (xy 291.678355 -279.079172)
			(xy 291.636759 -279.048951) (xy 291.600403 -279.012595) (xy 291.570182 -278.970999) (xy 291.546839 -278.925187)
			(xy 291.530951 -278.876288) (xy 291.522908 -278.825506) (xy 291.204484 -278.825506) (xy 291.196768 -278.872982)
			(xy 291.181184 -278.919663) (xy 291.158313 -278.96324) (xy 291.128748 -279.002584) (xy 291.093255 -279.036676)
			(xy 291.052752 -279.064632) (xy 291.00829 -279.08573) (xy 290.961019 -279.099422) (xy 290.912164 -279.105354)
			(xy 290.862989 -279.103373) (xy 290.81477 -279.093529) (xy 290.768754 -279.076077) (xy 290.726133 -279.05147)
			(xy 290.688012 -279.020345) (xy 290.655377 -278.983508) (xy 290.629074 -278.941912) (xy 290.609783 -278.896636)
			(xy 290.598006 -278.848852) (xy 290.594046 -278.799798) (xy 290.277042 -278.799798) (xy 290.276538 -278.825506)
			(xy 290.268495 -278.876288) (xy 290.252607 -278.925187) (xy 290.229264 -278.970999) (xy 290.199043 -279.012595)
			(xy 290.162687 -279.048951) (xy 290.121091 -279.079172) (xy 290.075279 -279.102515) (xy 290.02638 -279.118403)
			(xy 289.975598 -279.126446) (xy 289.924182 -279.126446) (xy 289.8734 -279.118403) (xy 289.824501 -279.102515)
			(xy 289.778689 -279.079172) (xy 289.737093 -279.048951) (xy 289.700737 -279.012595) (xy 289.670516 -278.970999)
			(xy 289.647173 -278.925187) (xy 289.631285 -278.876288) (xy 289.623242 -278.825506) (xy 289.304564 -278.825506)
			(xy 289.296848 -278.872982) (xy 289.281264 -278.919663) (xy 289.258393 -278.96324) (xy 289.228828 -279.002584)
			(xy 289.193335 -279.036676) (xy 289.152832 -279.064632) (xy 289.10837 -279.08573) (xy 289.061099 -279.099422)
			(xy 289.012244 -279.105354) (xy 288.963069 -279.103373) (xy 288.91485 -279.093529) (xy 288.868834 -279.076077)
			(xy 288.826213 -279.05147) (xy 288.788092 -279.020345) (xy 288.755457 -278.983508) (xy 288.729154 -278.941912)
			(xy 288.709863 -278.896636) (xy 288.698086 -278.848852) (xy 288.694126 -278.799798) (xy 288.376868 -278.799798)
			(xy 288.376364 -278.825506) (xy 288.368321 -278.876288) (xy 288.352433 -278.925187) (xy 288.32909 -278.970999)
			(xy 288.298869 -279.012595) (xy 288.262513 -279.048951) (xy 288.220917 -279.079172) (xy 288.175105 -279.102515)
			(xy 288.126206 -279.118403) (xy 288.075424 -279.126446) (xy 288.024008 -279.126446) (xy 287.973226 -279.118403)
			(xy 287.924327 -279.102515) (xy 287.878515 -279.079172) (xy 287.836919 -279.048951) (xy 287.800563 -279.012595)
			(xy 287.770342 -278.970999) (xy 287.746999 -278.925187) (xy 287.731111 -278.876288) (xy 287.723068 -278.825506)
			(xy 287.40439 -278.825506) (xy 287.396674 -278.872982) (xy 287.38109 -278.919663) (xy 287.358219 -278.96324)
			(xy 287.328654 -279.002584) (xy 287.293161 -279.036676) (xy 287.252658 -279.064632) (xy 287.208196 -279.08573)
			(xy 287.160925 -279.099422) (xy 287.11207 -279.105354) (xy 287.062895 -279.103373) (xy 287.014676 -279.093529)
			(xy 286.96866 -279.076077) (xy 286.926039 -279.05147) (xy 286.887918 -279.020345) (xy 286.855283 -278.983508)
			(xy 286.82898 -278.941912) (xy 286.809689 -278.896636) (xy 286.797912 -278.848852) (xy 286.793952 -278.799798)
			(xy 286.476948 -278.799798) (xy 286.476444 -278.825506) (xy 286.468401 -278.876288) (xy 286.452513 -278.925187)
			(xy 286.42917 -278.970999) (xy 286.398949 -279.012595) (xy 286.362593 -279.048951) (xy 286.320997 -279.079172)
			(xy 286.275185 -279.102515) (xy 286.226286 -279.118403) (xy 286.175504 -279.126446) (xy 286.124088 -279.126446)
			(xy 286.073306 -279.118403) (xy 286.024407 -279.102515) (xy 285.978595 -279.079172) (xy 285.936999 -279.048951)
			(xy 285.900643 -279.012595) (xy 285.870422 -278.970999) (xy 285.847079 -278.925187) (xy 285.831191 -278.876288)
			(xy 285.823148 -278.825506) (xy 285.50447 -278.825506) (xy 285.496754 -278.872982) (xy 285.48117 -278.919663)
			(xy 285.458299 -278.96324) (xy 285.428734 -279.002584) (xy 285.393241 -279.036676) (xy 285.352738 -279.064632)
			(xy 285.308276 -279.08573) (xy 285.261005 -279.099422) (xy 285.21215 -279.105354) (xy 285.162975 -279.103373)
			(xy 285.114756 -279.093529) (xy 285.06874 -279.076077) (xy 285.026119 -279.05147) (xy 284.987998 -279.020345)
			(xy 284.955363 -278.983508) (xy 284.92906 -278.941912) (xy 284.909769 -278.896636) (xy 284.897992 -278.848852)
			(xy 284.894032 -278.799798) (xy 284.577028 -278.799798) (xy 284.576524 -278.825506) (xy 284.568481 -278.876288)
			(xy 284.552593 -278.925187) (xy 284.52925 -278.970999) (xy 284.499029 -279.012595) (xy 284.462673 -279.048951)
			(xy 284.421077 -279.079172) (xy 284.375265 -279.102515) (xy 284.326366 -279.118403) (xy 284.275584 -279.126446)
			(xy 284.224168 -279.126446) (xy 284.173386 -279.118403) (xy 284.124487 -279.102515) (xy 284.078675 -279.079172)
			(xy 284.037079 -279.048951) (xy 284.000723 -279.012595) (xy 283.970502 -278.970999) (xy 283.947159 -278.925187)
			(xy 283.931271 -278.876288) (xy 283.923228 -278.825506) (xy 283.60455 -278.825506) (xy 283.596834 -278.872982)
			(xy 283.58125 -278.919663) (xy 283.558379 -278.96324) (xy 283.528814 -279.002584) (xy 283.493321 -279.036676)
			(xy 283.452818 -279.064632) (xy 283.408356 -279.08573) (xy 283.361085 -279.099422) (xy 283.31223 -279.105354)
			(xy 283.263055 -279.103373) (xy 283.214836 -279.093529) (xy 283.16882 -279.076077) (xy 283.126199 -279.05147)
			(xy 283.088078 -279.020345) (xy 283.055443 -278.983508) (xy 283.02914 -278.941912) (xy 283.009849 -278.896636)
			(xy 282.998072 -278.848852) (xy 282.994112 -278.799798) (xy 282.676096 -278.799798) (xy 282.676096 -278.825488)
			(xy 282.668059 -278.876231) (xy 282.652183 -278.925092) (xy 282.628859 -278.970868) (xy 282.598662 -279.012432)
			(xy 282.562334 -279.04876) (xy 282.52077 -279.078958) (xy 282.474994 -279.102283) (xy 282.426133 -279.118159)
			(xy 282.37539 -279.126196) (xy 282.349702 -279.126696) (xy 282.335983 -279.126568) (xy 282.308641 -279.124281)
			(xy 282.295092 -279.122124) (xy 282.283154 -279.120346) (xy 282.260294 -279.127204) (xy 282.18384 -279.200864)
			(xy 282.175966 -279.22347) (xy 282.17749 -279.235408) (xy 282.178687 -279.245206) (xy 282.179959 -279.264907)
			(xy 282.18003 -279.274778) (xy 282.179844 -279.288961) (xy 282.177173 -279.3172) (xy 282.174696 -279.331166)
			(xy 282.17241 -279.343612) (xy 282.179776 -279.367234) (xy 282.257246 -279.444704) (xy 282.280868 -279.45207)
			(xy 282.293314 -279.449784) (xy 282.307279 -279.447299) (xy 282.335519 -279.444628) (xy 282.349702 -279.44445)
			(xy 282.374961 -279.444972) (xy 282.424789 -279.453287) (xy 282.472569 -279.46969) (xy 282.516998 -279.493734)
			(xy 282.556863 -279.524763) (xy 282.591077 -279.56193) (xy 282.618708 -279.604221) (xy 282.639 -279.650484)
			(xy 282.651401 -279.699455) (xy 282.655573 -279.7498) (xy 282.653467 -279.775212) (xy 282.973268 -279.775212)
			(xy 282.973268 -279.723796) (xy 282.981311 -279.673014) (xy 282.997199 -279.624115) (xy 283.020542 -279.578303)
			(xy 283.050763 -279.536707) (xy 283.087119 -279.500351) (xy 283.128715 -279.47013) (xy 283.174527 -279.446787)
			(xy 283.223426 -279.430899) (xy 283.274208 -279.422856) (xy 283.325624 -279.422856) (xy 283.376406 -279.430899)
			(xy 283.425305 -279.446787) (xy 283.471117 -279.47013) (xy 283.512713 -279.500351) (xy 283.549069 -279.536707)
			(xy 283.57929 -279.578303) (xy 283.602633 -279.624115) (xy 283.618521 -279.673014) (xy 283.626564 -279.723796)
			(xy 283.627068 -279.749504) (xy 283.627063 -279.749758) (xy 283.944072 -279.749758) (xy 283.948032 -279.700704)
			(xy 283.959809 -279.65292) (xy 283.9791 -279.607644) (xy 284.005403 -279.566048) (xy 284.038038 -279.529211)
			(xy 284.076159 -279.498086) (xy 284.11878 -279.473479) (xy 284.164796 -279.456027) (xy 284.213015 -279.446183)
			(xy 284.26219 -279.444202) (xy 284.311045 -279.450134) (xy 284.358316 -279.463826) (xy 284.402778 -279.484924)
			(xy 284.443281 -279.51288) (xy 284.478774 -279.546972) (xy 284.508339 -279.586316) (xy 284.53121 -279.629893)
			(xy 284.546794 -279.676574) (xy 284.554689 -279.725151) (xy 284.555184 -279.749758) (xy 284.554689 -279.774365)
			(xy 284.554551 -279.775212) (xy 284.873188 -279.775212) (xy 284.873188 -279.723796) (xy 284.881231 -279.673014)
			(xy 284.897119 -279.624115) (xy 284.920462 -279.578303) (xy 284.950683 -279.536707) (xy 284.987039 -279.500351)
			(xy 285.028635 -279.47013) (xy 285.074447 -279.446787) (xy 285.123346 -279.430899) (xy 285.174128 -279.422856)
			(xy 285.225544 -279.422856) (xy 285.276326 -279.430899) (xy 285.325225 -279.446787) (xy 285.371037 -279.47013)
			(xy 285.412633 -279.500351) (xy 285.448989 -279.536707) (xy 285.47921 -279.578303) (xy 285.502553 -279.624115)
			(xy 285.518441 -279.673014) (xy 285.526484 -279.723796) (xy 285.526988 -279.749504) (xy 285.526983 -279.749758)
			(xy 285.843992 -279.749758) (xy 285.847952 -279.700704) (xy 285.859729 -279.65292) (xy 285.87902 -279.607644)
			(xy 285.905323 -279.566048) (xy 285.937958 -279.529211) (xy 285.976079 -279.498086) (xy 286.0187 -279.473479)
			(xy 286.064716 -279.456027) (xy 286.112935 -279.446183) (xy 286.16211 -279.444202) (xy 286.210965 -279.450134)
			(xy 286.258236 -279.463826) (xy 286.302698 -279.484924) (xy 286.343201 -279.51288) (xy 286.378694 -279.546972)
			(xy 286.408259 -279.586316) (xy 286.43113 -279.629893) (xy 286.446714 -279.676574) (xy 286.454609 -279.725151)
			(xy 286.455104 -279.749758) (xy 286.454609 -279.774365) (xy 286.454471 -279.775212) (xy 286.773108 -279.775212)
			(xy 286.773108 -279.723796) (xy 286.781151 -279.673014) (xy 286.797039 -279.624115) (xy 286.820382 -279.578303)
			(xy 286.850603 -279.536707) (xy 286.886959 -279.500351) (xy 286.928555 -279.47013) (xy 286.974367 -279.446787)
			(xy 287.023266 -279.430899) (xy 287.074048 -279.422856) (xy 287.125464 -279.422856) (xy 287.176246 -279.430899)
			(xy 287.225145 -279.446787) (xy 287.270957 -279.47013) (xy 287.312553 -279.500351) (xy 287.348909 -279.536707)
			(xy 287.37913 -279.578303) (xy 287.402473 -279.624115) (xy 287.418361 -279.673014) (xy 287.426404 -279.723796)
			(xy 287.426908 -279.749504) (xy 287.426903 -279.749758) (xy 287.743912 -279.749758) (xy 287.747872 -279.700704)
			(xy 287.759649 -279.65292) (xy 287.77894 -279.607644) (xy 287.805243 -279.566048) (xy 287.837878 -279.529211)
			(xy 287.875999 -279.498086) (xy 287.91862 -279.473479) (xy 287.964636 -279.456027) (xy 288.012855 -279.446183)
			(xy 288.06203 -279.444202) (xy 288.110885 -279.450134) (xy 288.158156 -279.463826) (xy 288.202618 -279.484924)
			(xy 288.243121 -279.51288) (xy 288.278614 -279.546972) (xy 288.308179 -279.586316) (xy 288.33105 -279.629893)
			(xy 288.346634 -279.676574) (xy 288.354529 -279.725151) (xy 288.355024 -279.749758) (xy 288.354529 -279.774365)
			(xy 288.354391 -279.775212) (xy 288.673028 -279.775212) (xy 288.673028 -279.723796) (xy 288.681071 -279.673014)
			(xy 288.696959 -279.624115) (xy 288.720302 -279.578303) (xy 288.750523 -279.536707) (xy 288.786879 -279.500351)
			(xy 288.828475 -279.47013) (xy 288.874287 -279.446787) (xy 288.923186 -279.430899) (xy 288.973968 -279.422856)
			(xy 289.025384 -279.422856) (xy 289.076166 -279.430899) (xy 289.125065 -279.446787) (xy 289.170877 -279.47013)
			(xy 289.212473 -279.500351) (xy 289.248829 -279.536707) (xy 289.27905 -279.578303) (xy 289.302393 -279.624115)
			(xy 289.318281 -279.673014) (xy 289.326324 -279.723796) (xy 289.326828 -279.749504) (xy 289.326823 -279.749758)
			(xy 289.644086 -279.749758) (xy 289.648046 -279.700704) (xy 289.659823 -279.65292) (xy 289.679114 -279.607644)
			(xy 289.705417 -279.566048) (xy 289.738052 -279.529211) (xy 289.776173 -279.498086) (xy 289.818794 -279.473479)
			(xy 289.86481 -279.456027) (xy 289.913029 -279.446183) (xy 289.962204 -279.444202) (xy 290.011059 -279.450134)
			(xy 290.05833 -279.463826) (xy 290.102792 -279.484924) (xy 290.143295 -279.51288) (xy 290.178788 -279.546972)
			(xy 290.208353 -279.586316) (xy 290.231224 -279.629893) (xy 290.246808 -279.676574) (xy 290.254703 -279.725151)
			(xy 290.255198 -279.749758) (xy 290.254703 -279.774365) (xy 290.254565 -279.775212) (xy 290.573202 -279.775212)
			(xy 290.573202 -279.723796) (xy 290.581245 -279.673014) (xy 290.597133 -279.624115) (xy 290.620476 -279.578303)
			(xy 290.650697 -279.536707) (xy 290.687053 -279.500351) (xy 290.728649 -279.47013) (xy 290.774461 -279.446787)
			(xy 290.82336 -279.430899) (xy 290.874142 -279.422856) (xy 290.925558 -279.422856) (xy 290.97634 -279.430899)
			(xy 291.025239 -279.446787) (xy 291.071051 -279.47013) (xy 291.112647 -279.500351) (xy 291.149003 -279.536707)
			(xy 291.179224 -279.578303) (xy 291.202567 -279.624115) (xy 291.218455 -279.673014) (xy 291.226498 -279.723796)
			(xy 291.227002 -279.749504) (xy 291.226997 -279.749758) (xy 291.544006 -279.749758) (xy 291.547966 -279.700704)
			(xy 291.559743 -279.65292) (xy 291.579034 -279.607644) (xy 291.605337 -279.566048) (xy 291.637972 -279.529211)
			(xy 291.676093 -279.498086) (xy 291.718714 -279.473479) (xy 291.76473 -279.456027) (xy 291.812949 -279.446183)
			(xy 291.862124 -279.444202) (xy 291.910979 -279.450134) (xy 291.95825 -279.463826) (xy 292.002712 -279.484924)
			(xy 292.043215 -279.51288) (xy 292.078708 -279.546972) (xy 292.108273 -279.586316) (xy 292.131144 -279.629893)
			(xy 292.146728 -279.676574) (xy 292.154623 -279.725151) (xy 292.155118 -279.749758) (xy 292.154623 -279.774365)
			(xy 292.154485 -279.775212) (xy 292.473122 -279.775212) (xy 292.473122 -279.723796) (xy 292.481165 -279.673014)
			(xy 292.497053 -279.624115) (xy 292.520396 -279.578303) (xy 292.550617 -279.536707) (xy 292.586973 -279.500351)
			(xy 292.628569 -279.47013) (xy 292.674381 -279.446787) (xy 292.72328 -279.430899) (xy 292.774062 -279.422856)
			(xy 292.825478 -279.422856) (xy 292.87626 -279.430899) (xy 292.925159 -279.446787) (xy 292.970971 -279.47013)
			(xy 293.012567 -279.500351) (xy 293.048923 -279.536707) (xy 293.079144 -279.578303) (xy 293.102487 -279.624115)
			(xy 293.118375 -279.673014) (xy 293.126418 -279.723796) (xy 293.126922 -279.749504) (xy 293.126917 -279.749758)
			(xy 293.443926 -279.749758) (xy 293.447886 -279.700704) (xy 293.459663 -279.65292) (xy 293.478954 -279.607644)
			(xy 293.505257 -279.566048) (xy 293.537892 -279.529211) (xy 293.576013 -279.498086) (xy 293.618634 -279.473479)
			(xy 293.66465 -279.456027) (xy 293.712869 -279.446183) (xy 293.762044 -279.444202) (xy 293.810899 -279.450134)
			(xy 293.85817 -279.463826) (xy 293.902632 -279.484924) (xy 293.943135 -279.51288) (xy 293.978628 -279.546972)
			(xy 294.008193 -279.586316) (xy 294.031064 -279.629893) (xy 294.046648 -279.676574) (xy 294.054543 -279.725151)
			(xy 294.055038 -279.749758) (xy 294.054543 -279.774365) (xy 294.054405 -279.775212) (xy 294.373042 -279.775212)
			(xy 294.373042 -279.723796) (xy 294.381085 -279.673014) (xy 294.396973 -279.624115) (xy 294.420316 -279.578303)
			(xy 294.450537 -279.536707) (xy 294.486893 -279.500351) (xy 294.528489 -279.47013) (xy 294.574301 -279.446787)
			(xy 294.6232 -279.430899) (xy 294.673982 -279.422856) (xy 294.725398 -279.422856) (xy 294.77618 -279.430899)
			(xy 294.825079 -279.446787) (xy 294.870891 -279.47013) (xy 294.912487 -279.500351) (xy 294.948843 -279.536707)
			(xy 294.979064 -279.578303) (xy 295.002407 -279.624115) (xy 295.018295 -279.673014) (xy 295.026338 -279.723796)
			(xy 295.026842 -279.749504) (xy 295.026837 -279.749758) (xy 295.3441 -279.749758) (xy 295.34806 -279.700704)
			(xy 295.359837 -279.65292) (xy 295.379128 -279.607644) (xy 295.405431 -279.566048) (xy 295.438066 -279.529211)
			(xy 295.476187 -279.498086) (xy 295.518808 -279.473479) (xy 295.564824 -279.456027) (xy 295.613043 -279.446183)
			(xy 295.662218 -279.444202) (xy 295.711073 -279.450134) (xy 295.758344 -279.463826) (xy 295.802806 -279.484924)
			(xy 295.843309 -279.51288) (xy 295.878802 -279.546972) (xy 295.908367 -279.586316) (xy 295.931238 -279.629893)
			(xy 295.946822 -279.676574) (xy 295.954717 -279.725151) (xy 295.955212 -279.749758) (xy 295.954717 -279.774365)
			(xy 295.954579 -279.775212) (xy 296.273216 -279.775212) (xy 296.273216 -279.723796) (xy 296.281259 -279.673014)
			(xy 296.297147 -279.624115) (xy 296.32049 -279.578303) (xy 296.350711 -279.536707) (xy 296.387067 -279.500351)
			(xy 296.428663 -279.47013) (xy 296.474475 -279.446787) (xy 296.523374 -279.430899) (xy 296.574156 -279.422856)
			(xy 296.625572 -279.422856) (xy 296.676354 -279.430899) (xy 296.725253 -279.446787) (xy 296.771065 -279.47013)
			(xy 296.812661 -279.500351) (xy 296.849017 -279.536707) (xy 296.879238 -279.578303) (xy 296.902581 -279.624115)
			(xy 296.918469 -279.673014) (xy 296.926512 -279.723796) (xy 296.927016 -279.749504) (xy 296.927011 -279.749758)
			(xy 297.24402 -279.749758) (xy 297.24798 -279.700704) (xy 297.259757 -279.65292) (xy 297.279048 -279.607644)
			(xy 297.305351 -279.566048) (xy 297.337986 -279.529211) (xy 297.376107 -279.498086) (xy 297.418728 -279.473479)
			(xy 297.464744 -279.456027) (xy 297.512963 -279.446183) (xy 297.562138 -279.444202) (xy 297.610993 -279.450134)
			(xy 297.658264 -279.463826) (xy 297.702726 -279.484924) (xy 297.743229 -279.51288) (xy 297.778722 -279.546972)
			(xy 297.808287 -279.586316) (xy 297.831158 -279.629893) (xy 297.846742 -279.676574) (xy 297.854637 -279.725151)
			(xy 297.855132 -279.749758) (xy 297.854637 -279.774365) (xy 297.854499 -279.775212) (xy 298.173136 -279.775212)
			(xy 298.173136 -279.723796) (xy 298.181179 -279.673014) (xy 298.197067 -279.624115) (xy 298.22041 -279.578303)
			(xy 298.250631 -279.536707) (xy 298.286987 -279.500351) (xy 298.328583 -279.47013) (xy 298.374395 -279.446787)
			(xy 298.423294 -279.430899) (xy 298.474076 -279.422856) (xy 298.525492 -279.422856) (xy 298.576274 -279.430899)
			(xy 298.625173 -279.446787) (xy 298.670985 -279.47013) (xy 298.712581 -279.500351) (xy 298.748937 -279.536707)
			(xy 298.779158 -279.578303) (xy 298.802501 -279.624115) (xy 298.818389 -279.673014) (xy 298.826432 -279.723796)
			(xy 298.826936 -279.749504) (xy 298.826931 -279.749758) (xy 299.14394 -279.749758) (xy 299.1479 -279.700704)
			(xy 299.159677 -279.65292) (xy 299.178968 -279.607644) (xy 299.205271 -279.566048) (xy 299.237906 -279.529211)
			(xy 299.276027 -279.498086) (xy 299.318648 -279.473479) (xy 299.364664 -279.456027) (xy 299.412883 -279.446183)
			(xy 299.462058 -279.444202) (xy 299.510913 -279.450134) (xy 299.558184 -279.463826) (xy 299.602646 -279.484924)
			(xy 299.643149 -279.51288) (xy 299.678642 -279.546972) (xy 299.708207 -279.586316) (xy 299.731078 -279.629893)
			(xy 299.746662 -279.676574) (xy 299.754557 -279.725151) (xy 299.755052 -279.749758) (xy 299.754557 -279.774365)
			(xy 299.754419 -279.775212) (xy 300.073056 -279.775212) (xy 300.073056 -279.723796) (xy 300.081099 -279.673014)
			(xy 300.096987 -279.624115) (xy 300.12033 -279.578303) (xy 300.150551 -279.536707) (xy 300.186907 -279.500351)
			(xy 300.228503 -279.47013) (xy 300.274315 -279.446787) (xy 300.323214 -279.430899) (xy 300.373996 -279.422856)
			(xy 300.425412 -279.422856) (xy 300.476194 -279.430899) (xy 300.525093 -279.446787) (xy 300.570905 -279.47013)
			(xy 300.612501 -279.500351) (xy 300.648857 -279.536707) (xy 300.679078 -279.578303) (xy 300.702421 -279.624115)
			(xy 300.718309 -279.673014) (xy 300.726352 -279.723796) (xy 300.726856 -279.749504) (xy 300.726851 -279.749758)
			(xy 301.044114 -279.749758) (xy 301.048074 -279.700704) (xy 301.059851 -279.65292) (xy 301.079142 -279.607644)
			(xy 301.105445 -279.566048) (xy 301.13808 -279.529211) (xy 301.176201 -279.498086) (xy 301.218822 -279.473479)
			(xy 301.264838 -279.456027) (xy 301.313057 -279.446183) (xy 301.362232 -279.444202) (xy 301.411087 -279.450134)
			(xy 301.458358 -279.463826) (xy 301.50282 -279.484924) (xy 301.543323 -279.51288) (xy 301.578816 -279.546972)
			(xy 301.608381 -279.586316) (xy 301.631252 -279.629893) (xy 301.646836 -279.676574) (xy 301.654731 -279.725151)
			(xy 301.655226 -279.749758) (xy 301.654731 -279.774365) (xy 301.654593 -279.775212) (xy 301.97323 -279.775212)
			(xy 301.97323 -279.723796) (xy 301.981273 -279.673014) (xy 301.997161 -279.624115) (xy 302.020504 -279.578303)
			(xy 302.050725 -279.536707) (xy 302.087081 -279.500351) (xy 302.128677 -279.47013) (xy 302.174489 -279.446787)
			(xy 302.223388 -279.430899) (xy 302.27417 -279.422856) (xy 302.325586 -279.422856) (xy 302.376368 -279.430899)
			(xy 302.425267 -279.446787) (xy 302.471079 -279.47013) (xy 302.512675 -279.500351) (xy 302.549031 -279.536707)
			(xy 302.579252 -279.578303) (xy 302.602595 -279.624115) (xy 302.618483 -279.673014) (xy 302.626526 -279.723796)
			(xy 302.62703 -279.749504) (xy 302.627025 -279.749758) (xy 302.944034 -279.749758) (xy 302.947994 -279.700704)
			(xy 302.959771 -279.65292) (xy 302.979062 -279.607644) (xy 303.005365 -279.566048) (xy 303.038 -279.529211)
			(xy 303.076121 -279.498086) (xy 303.118742 -279.473479) (xy 303.164758 -279.456027) (xy 303.212977 -279.446183)
			(xy 303.262152 -279.444202) (xy 303.311007 -279.450134) (xy 303.358278 -279.463826) (xy 303.40274 -279.484924)
			(xy 303.443243 -279.51288) (xy 303.478736 -279.546972) (xy 303.508301 -279.586316) (xy 303.531172 -279.629893)
			(xy 303.546756 -279.676574) (xy 303.554651 -279.725151) (xy 303.555146 -279.749758) (xy 303.554651 -279.774365)
			(xy 303.554513 -279.775212) (xy 303.87315 -279.775212) (xy 303.87315 -279.723796) (xy 303.881193 -279.673014)
			(xy 303.897081 -279.624115) (xy 303.920424 -279.578303) (xy 303.950645 -279.536707) (xy 303.987001 -279.500351)
			(xy 304.028597 -279.47013) (xy 304.074409 -279.446787) (xy 304.123308 -279.430899) (xy 304.17409 -279.422856)
			(xy 304.225506 -279.422856) (xy 304.276288 -279.430899) (xy 304.325187 -279.446787) (xy 304.370999 -279.47013)
			(xy 304.412595 -279.500351) (xy 304.448951 -279.536707) (xy 304.479172 -279.578303) (xy 304.502515 -279.624115)
			(xy 304.518403 -279.673014) (xy 304.526446 -279.723796) (xy 304.52695 -279.749504) (xy 304.526945 -279.749758)
			(xy 304.843954 -279.749758) (xy 304.847914 -279.700704) (xy 304.859691 -279.65292) (xy 304.878982 -279.607644)
			(xy 304.905285 -279.566048) (xy 304.93792 -279.529211) (xy 304.976041 -279.498086) (xy 305.018662 -279.473479)
			(xy 305.064678 -279.456027) (xy 305.112897 -279.446183) (xy 305.162072 -279.444202) (xy 305.210927 -279.450134)
			(xy 305.258198 -279.463826) (xy 305.30266 -279.484924) (xy 305.343163 -279.51288) (xy 305.378656 -279.546972)
			(xy 305.408221 -279.586316) (xy 305.431092 -279.629893) (xy 305.446676 -279.676574) (xy 305.454571 -279.725151)
			(xy 305.455066 -279.749758) (xy 305.454571 -279.774365) (xy 305.454433 -279.775212) (xy 305.77307 -279.775212)
			(xy 305.77307 -279.723796) (xy 305.781113 -279.673014) (xy 305.797001 -279.624115) (xy 305.820344 -279.578303)
			(xy 305.850565 -279.536707) (xy 305.886921 -279.500351) (xy 305.928517 -279.47013) (xy 305.974329 -279.446787)
			(xy 306.023228 -279.430899) (xy 306.07401 -279.422856) (xy 306.125426 -279.422856) (xy 306.176208 -279.430899)
			(xy 306.225107 -279.446787) (xy 306.270919 -279.47013) (xy 306.312515 -279.500351) (xy 306.348871 -279.536707)
			(xy 306.379092 -279.578303) (xy 306.402435 -279.624115) (xy 306.418323 -279.673014) (xy 306.426366 -279.723796)
			(xy 306.42687 -279.749504) (xy 306.426865 -279.749758) (xy 306.743874 -279.749758) (xy 306.747834 -279.700704)
			(xy 306.759611 -279.65292) (xy 306.778902 -279.607644) (xy 306.805205 -279.566048) (xy 306.83784 -279.529211)
			(xy 306.875961 -279.498086) (xy 306.918582 -279.473479) (xy 306.964598 -279.456027) (xy 307.012817 -279.446183)
			(xy 307.061992 -279.444202) (xy 307.110847 -279.450134) (xy 307.158118 -279.463826) (xy 307.20258 -279.484924)
			(xy 307.243083 -279.51288) (xy 307.278576 -279.546972) (xy 307.308141 -279.586316) (xy 307.331012 -279.629893)
			(xy 307.346596 -279.676574) (xy 307.354491 -279.725151) (xy 307.354986 -279.749758) (xy 307.354491 -279.774365)
			(xy 307.354353 -279.775212) (xy 307.673244 -279.775212) (xy 307.673244 -279.723796) (xy 307.681287 -279.673014)
			(xy 307.697175 -279.624115) (xy 307.720518 -279.578303) (xy 307.750739 -279.536707) (xy 307.787095 -279.500351)
			(xy 307.828691 -279.47013) (xy 307.874503 -279.446787) (xy 307.923402 -279.430899) (xy 307.974184 -279.422856)
			(xy 308.0256 -279.422856) (xy 308.076382 -279.430899) (xy 308.125281 -279.446787) (xy 308.171093 -279.47013)
			(xy 308.212689 -279.500351) (xy 308.249045 -279.536707) (xy 308.279266 -279.578303) (xy 308.302609 -279.624115)
			(xy 308.318497 -279.673014) (xy 308.32654 -279.723796) (xy 308.327044 -279.749504) (xy 308.327039 -279.749758)
			(xy 308.644048 -279.749758) (xy 308.648008 -279.700704) (xy 308.659785 -279.65292) (xy 308.679076 -279.607644)
			(xy 308.705379 -279.566048) (xy 308.738014 -279.529211) (xy 308.776135 -279.498086) (xy 308.818756 -279.473479)
			(xy 308.864772 -279.456027) (xy 308.912991 -279.446183) (xy 308.962166 -279.444202) (xy 309.011021 -279.450134)
			(xy 309.058292 -279.463826) (xy 309.102754 -279.484924) (xy 309.143257 -279.51288) (xy 309.17875 -279.546972)
			(xy 309.208315 -279.586316) (xy 309.231186 -279.629893) (xy 309.24677 -279.676574) (xy 309.254665 -279.725151)
			(xy 309.25516 -279.749758) (xy 309.254665 -279.774365) (xy 309.254527 -279.775212) (xy 309.573164 -279.775212)
			(xy 309.573164 -279.723796) (xy 309.581207 -279.673014) (xy 309.597095 -279.624115) (xy 309.620438 -279.578303)
			(xy 309.650659 -279.536707) (xy 309.687015 -279.500351) (xy 309.728611 -279.47013) (xy 309.774423 -279.446787)
			(xy 309.823322 -279.430899) (xy 309.874104 -279.422856) (xy 309.92552 -279.422856) (xy 309.976302 -279.430899)
			(xy 310.025201 -279.446787) (xy 310.071013 -279.47013) (xy 310.112609 -279.500351) (xy 310.148965 -279.536707)
			(xy 310.179186 -279.578303) (xy 310.202529 -279.624115) (xy 310.218417 -279.673014) (xy 310.22646 -279.723796)
			(xy 310.226964 -279.749504) (xy 310.226959 -279.749758) (xy 310.543968 -279.749758) (xy 310.547928 -279.700704)
			(xy 310.559705 -279.65292) (xy 310.578996 -279.607644) (xy 310.605299 -279.566048) (xy 310.637934 -279.529211)
			(xy 310.676055 -279.498086) (xy 310.718676 -279.473479) (xy 310.764692 -279.456027) (xy 310.812911 -279.446183)
			(xy 310.862086 -279.444202) (xy 310.910941 -279.450134) (xy 310.958212 -279.463826) (xy 311.002674 -279.484924)
			(xy 311.043177 -279.51288) (xy 311.07867 -279.546972) (xy 311.108235 -279.586316) (xy 311.131106 -279.629893)
			(xy 311.14669 -279.676574) (xy 311.154585 -279.725151) (xy 311.15508 -279.749758) (xy 311.154585 -279.774365)
			(xy 311.154406 -279.775466) (xy 311.473084 -279.775466) (xy 311.473084 -279.72405) (xy 311.481127 -279.673268)
			(xy 311.497015 -279.624369) (xy 311.520358 -279.578557) (xy 311.550579 -279.536961) (xy 311.586935 -279.500605)
			(xy 311.628531 -279.470384) (xy 311.674343 -279.447041) (xy 311.723242 -279.431153) (xy 311.774024 -279.42311)
			(xy 311.82544 -279.42311) (xy 311.876222 -279.431153) (xy 311.925121 -279.447041) (xy 311.970933 -279.470384)
			(xy 312.012529 -279.500605) (xy 312.048885 -279.536961) (xy 312.079106 -279.578557) (xy 312.102449 -279.624369)
			(xy 312.118337 -279.673268) (xy 312.12638 -279.72405) (xy 312.126884 -279.749758) (xy 312.443888 -279.749758)
			(xy 312.447848 -279.700704) (xy 312.459625 -279.65292) (xy 312.478916 -279.607644) (xy 312.505219 -279.566048)
			(xy 312.537854 -279.529211) (xy 312.575975 -279.498086) (xy 312.618596 -279.473479) (xy 312.664612 -279.456027)
			(xy 312.712831 -279.446183) (xy 312.762006 -279.444202) (xy 312.810861 -279.450134) (xy 312.858132 -279.463826)
			(xy 312.902594 -279.484924) (xy 312.943097 -279.51288) (xy 312.97859 -279.546972) (xy 313.008155 -279.586316)
			(xy 313.031026 -279.629893) (xy 313.04661 -279.676574) (xy 313.054505 -279.725151) (xy 313.055 -279.749758)
			(xy 313.054505 -279.774365) (xy 313.054326 -279.775466) (xy 313.373258 -279.775466) (xy 313.373258 -279.72405)
			(xy 313.381301 -279.673268) (xy 313.397189 -279.624369) (xy 313.420532 -279.578557) (xy 313.450753 -279.536961)
			(xy 313.487109 -279.500605) (xy 313.528705 -279.470384) (xy 313.574517 -279.447041) (xy 313.623416 -279.431153)
			(xy 313.674198 -279.42311) (xy 313.725614 -279.42311) (xy 313.776396 -279.431153) (xy 313.825295 -279.447041)
			(xy 313.871107 -279.470384) (xy 313.912703 -279.500605) (xy 313.949059 -279.536961) (xy 313.97928 -279.578557)
			(xy 314.002623 -279.624369) (xy 314.018511 -279.673268) (xy 314.026554 -279.72405) (xy 314.027058 -279.749758)
			(xy 314.026554 -279.775466) (xy 314.323218 -279.775466) (xy 314.323218 -279.72405) (xy 314.331261 -279.673268)
			(xy 314.347149 -279.624369) (xy 314.370492 -279.578557) (xy 314.400713 -279.536961) (xy 314.437069 -279.500605)
			(xy 314.478665 -279.470384) (xy 314.524477 -279.447041) (xy 314.573376 -279.431153) (xy 314.624158 -279.42311)
			(xy 314.675574 -279.42311) (xy 314.726356 -279.431153) (xy 314.775255 -279.447041) (xy 314.821067 -279.470384)
			(xy 314.862663 -279.500605) (xy 314.899019 -279.536961) (xy 314.92924 -279.578557) (xy 314.952583 -279.624369)
			(xy 314.968471 -279.673268) (xy 314.976514 -279.72405) (xy 314.977018 -279.749758) (xy 314.977013 -279.750012)
			(xy 315.294276 -279.750012) (xy 315.298236 -279.700958) (xy 315.310013 -279.653174) (xy 315.329304 -279.607898)
			(xy 315.355607 -279.566302) (xy 315.388242 -279.529465) (xy 315.426363 -279.49834) (xy 315.468984 -279.473733)
			(xy 315.515 -279.456281) (xy 315.563219 -279.446437) (xy 315.612394 -279.444456) (xy 315.661249 -279.450388)
			(xy 315.70852 -279.46408) (xy 315.752982 -279.485178) (xy 315.793485 -279.513134) (xy 315.828978 -279.547226)
			(xy 315.858543 -279.58657) (xy 315.881414 -279.630147) (xy 315.896998 -279.676828) (xy 315.904893 -279.725405)
			(xy 315.905388 -279.750012) (xy 315.904893 -279.774619) (xy 315.896998 -279.823196) (xy 315.881414 -279.869877)
			(xy 315.858543 -279.913454) (xy 315.828978 -279.952798) (xy 315.793485 -279.98689) (xy 315.752982 -280.014846)
			(xy 315.70852 -280.035944) (xy 315.661249 -280.049636) (xy 315.612394 -280.055568) (xy 315.563219 -280.053587)
			(xy 315.515 -280.043743) (xy 315.468984 -280.026291) (xy 315.426363 -280.001684) (xy 315.388242 -279.970559)
			(xy 315.355607 -279.933722) (xy 315.329304 -279.892126) (xy 315.310013 -279.84685) (xy 315.298236 -279.799066)
			(xy 315.294276 -279.750012) (xy 314.977013 -279.750012) (xy 314.976514 -279.775466) (xy 314.968471 -279.826248)
			(xy 314.952583 -279.875147) (xy 314.92924 -279.920959) (xy 314.899019 -279.962555) (xy 314.862663 -279.998911)
			(xy 314.821067 -280.029132) (xy 314.775255 -280.052475) (xy 314.726356 -280.068363) (xy 314.675574 -280.076406)
			(xy 314.624158 -280.076406) (xy 314.573376 -280.068363) (xy 314.524477 -280.052475) (xy 314.478665 -280.029132)
			(xy 314.437069 -279.998911) (xy 314.400713 -279.962555) (xy 314.370492 -279.920959) (xy 314.347149 -279.875147)
			(xy 314.331261 -279.826248) (xy 314.323218 -279.775466) (xy 314.026554 -279.775466) (xy 314.018511 -279.826248)
			(xy 314.002623 -279.875147) (xy 313.97928 -279.920959) (xy 313.949059 -279.962555) (xy 313.912703 -279.998911)
			(xy 313.871107 -280.029132) (xy 313.825295 -280.052475) (xy 313.776396 -280.068363) (xy 313.725614 -280.076406)
			(xy 313.674198 -280.076406) (xy 313.623416 -280.068363) (xy 313.574517 -280.052475) (xy 313.528705 -280.029132)
			(xy 313.487109 -279.998911) (xy 313.450753 -279.962555) (xy 313.420532 -279.920959) (xy 313.397189 -279.875147)
			(xy 313.381301 -279.826248) (xy 313.373258 -279.775466) (xy 313.054326 -279.775466) (xy 313.04661 -279.822942)
			(xy 313.031026 -279.869623) (xy 313.008155 -279.9132) (xy 312.97859 -279.952544) (xy 312.943097 -279.986636)
			(xy 312.902594 -280.014592) (xy 312.858132 -280.03569) (xy 312.810861 -280.049382) (xy 312.762006 -280.055314)
			(xy 312.712831 -280.053333) (xy 312.664612 -280.043489) (xy 312.618596 -280.026037) (xy 312.575975 -280.00143)
			(xy 312.537854 -279.970305) (xy 312.505219 -279.933468) (xy 312.478916 -279.891872) (xy 312.459625 -279.846596)
			(xy 312.447848 -279.798812) (xy 312.443888 -279.749758) (xy 312.126884 -279.749758) (xy 312.12638 -279.775466)
			(xy 312.118337 -279.826248) (xy 312.102449 -279.875147) (xy 312.079106 -279.920959) (xy 312.048885 -279.962555)
			(xy 312.012529 -279.998911) (xy 311.970933 -280.029132) (xy 311.925121 -280.052475) (xy 311.876222 -280.068363)
			(xy 311.82544 -280.076406) (xy 311.774024 -280.076406) (xy 311.723242 -280.068363) (xy 311.674343 -280.052475)
			(xy 311.628531 -280.029132) (xy 311.586935 -279.998911) (xy 311.550579 -279.962555) (xy 311.520358 -279.920959)
			(xy 311.497015 -279.875147) (xy 311.481127 -279.826248) (xy 311.473084 -279.775466) (xy 311.154406 -279.775466)
			(xy 311.14669 -279.822942) (xy 311.131106 -279.869623) (xy 311.108235 -279.9132) (xy 311.07867 -279.952544)
			(xy 311.043177 -279.986636) (xy 311.002674 -280.014592) (xy 310.958212 -280.03569) (xy 310.910941 -280.049382)
			(xy 310.862086 -280.055314) (xy 310.812911 -280.053333) (xy 310.764692 -280.043489) (xy 310.718676 -280.026037)
			(xy 310.676055 -280.00143) (xy 310.637934 -279.970305) (xy 310.605299 -279.933468) (xy 310.578996 -279.891872)
			(xy 310.559705 -279.846596) (xy 310.547928 -279.798812) (xy 310.543968 -279.749758) (xy 310.226959 -279.749758)
			(xy 310.22646 -279.775212) (xy 310.218417 -279.825994) (xy 310.202529 -279.874893) (xy 310.179186 -279.920705)
			(xy 310.148965 -279.962301) (xy 310.112609 -279.998657) (xy 310.071013 -280.028878) (xy 310.025201 -280.052221)
			(xy 309.976302 -280.068109) (xy 309.92552 -280.076152) (xy 309.874104 -280.076152) (xy 309.823322 -280.068109)
			(xy 309.774423 -280.052221) (xy 309.728611 -280.028878) (xy 309.687015 -279.998657) (xy 309.650659 -279.962301)
			(xy 309.620438 -279.920705) (xy 309.597095 -279.874893) (xy 309.581207 -279.825994) (xy 309.573164 -279.775212)
			(xy 309.254527 -279.775212) (xy 309.24677 -279.822942) (xy 309.231186 -279.869623) (xy 309.208315 -279.9132)
			(xy 309.17875 -279.952544) (xy 309.143257 -279.986636) (xy 309.102754 -280.014592) (xy 309.058292 -280.03569)
			(xy 309.011021 -280.049382) (xy 308.962166 -280.055314) (xy 308.912991 -280.053333) (xy 308.864772 -280.043489)
			(xy 308.818756 -280.026037) (xy 308.776135 -280.00143) (xy 308.738014 -279.970305) (xy 308.705379 -279.933468)
			(xy 308.679076 -279.891872) (xy 308.659785 -279.846596) (xy 308.648008 -279.798812) (xy 308.644048 -279.749758)
			(xy 308.327039 -279.749758) (xy 308.32654 -279.775212) (xy 308.318497 -279.825994) (xy 308.302609 -279.874893)
			(xy 308.279266 -279.920705) (xy 308.249045 -279.962301) (xy 308.212689 -279.998657) (xy 308.171093 -280.028878)
			(xy 308.125281 -280.052221) (xy 308.076382 -280.068109) (xy 308.0256 -280.076152) (xy 307.974184 -280.076152)
			(xy 307.923402 -280.068109) (xy 307.874503 -280.052221) (xy 307.828691 -280.028878) (xy 307.787095 -279.998657)
			(xy 307.750739 -279.962301) (xy 307.720518 -279.920705) (xy 307.697175 -279.874893) (xy 307.681287 -279.825994)
			(xy 307.673244 -279.775212) (xy 307.354353 -279.775212) (xy 307.346596 -279.822942) (xy 307.331012 -279.869623)
			(xy 307.308141 -279.9132) (xy 307.278576 -279.952544) (xy 307.243083 -279.986636) (xy 307.20258 -280.014592)
			(xy 307.158118 -280.03569) (xy 307.110847 -280.049382) (xy 307.061992 -280.055314) (xy 307.012817 -280.053333)
			(xy 306.964598 -280.043489) (xy 306.918582 -280.026037) (xy 306.875961 -280.00143) (xy 306.83784 -279.970305)
			(xy 306.805205 -279.933468) (xy 306.778902 -279.891872) (xy 306.759611 -279.846596) (xy 306.747834 -279.798812)
			(xy 306.743874 -279.749758) (xy 306.426865 -279.749758) (xy 306.426366 -279.775212) (xy 306.418323 -279.825994)
			(xy 306.402435 -279.874893) (xy 306.379092 -279.920705) (xy 306.348871 -279.962301) (xy 306.312515 -279.998657)
			(xy 306.270919 -280.028878) (xy 306.225107 -280.052221) (xy 306.176208 -280.068109) (xy 306.125426 -280.076152)
			(xy 306.07401 -280.076152) (xy 306.023228 -280.068109) (xy 305.974329 -280.052221) (xy 305.928517 -280.028878)
			(xy 305.886921 -279.998657) (xy 305.850565 -279.962301) (xy 305.820344 -279.920705) (xy 305.797001 -279.874893)
			(xy 305.781113 -279.825994) (xy 305.77307 -279.775212) (xy 305.454433 -279.775212) (xy 305.446676 -279.822942)
			(xy 305.431092 -279.869623) (xy 305.408221 -279.9132) (xy 305.378656 -279.952544) (xy 305.343163 -279.986636)
			(xy 305.30266 -280.014592) (xy 305.258198 -280.03569) (xy 305.210927 -280.049382) (xy 305.162072 -280.055314)
			(xy 305.112897 -280.053333) (xy 305.064678 -280.043489) (xy 305.018662 -280.026037) (xy 304.976041 -280.00143)
			(xy 304.93792 -279.970305) (xy 304.905285 -279.933468) (xy 304.878982 -279.891872) (xy 304.859691 -279.846596)
			(xy 304.847914 -279.798812) (xy 304.843954 -279.749758) (xy 304.526945 -279.749758) (xy 304.526446 -279.775212)
			(xy 304.518403 -279.825994) (xy 304.502515 -279.874893) (xy 304.479172 -279.920705) (xy 304.448951 -279.962301)
			(xy 304.412595 -279.998657) (xy 304.370999 -280.028878) (xy 304.325187 -280.052221) (xy 304.276288 -280.068109)
			(xy 304.225506 -280.076152) (xy 304.17409 -280.076152) (xy 304.123308 -280.068109) (xy 304.074409 -280.052221)
			(xy 304.028597 -280.028878) (xy 303.987001 -279.998657) (xy 303.950645 -279.962301) (xy 303.920424 -279.920705)
			(xy 303.897081 -279.874893) (xy 303.881193 -279.825994) (xy 303.87315 -279.775212) (xy 303.554513 -279.775212)
			(xy 303.546756 -279.822942) (xy 303.531172 -279.869623) (xy 303.508301 -279.9132) (xy 303.478736 -279.952544)
			(xy 303.443243 -279.986636) (xy 303.40274 -280.014592) (xy 303.358278 -280.03569) (xy 303.311007 -280.049382)
			(xy 303.262152 -280.055314) (xy 303.212977 -280.053333) (xy 303.164758 -280.043489) (xy 303.118742 -280.026037)
			(xy 303.076121 -280.00143) (xy 303.038 -279.970305) (xy 303.005365 -279.933468) (xy 302.979062 -279.891872)
			(xy 302.959771 -279.846596) (xy 302.947994 -279.798812) (xy 302.944034 -279.749758) (xy 302.627025 -279.749758)
			(xy 302.626526 -279.775212) (xy 302.618483 -279.825994) (xy 302.602595 -279.874893) (xy 302.579252 -279.920705)
			(xy 302.549031 -279.962301) (xy 302.512675 -279.998657) (xy 302.471079 -280.028878) (xy 302.425267 -280.052221)
			(xy 302.376368 -280.068109) (xy 302.325586 -280.076152) (xy 302.27417 -280.076152) (xy 302.223388 -280.068109)
			(xy 302.174489 -280.052221) (xy 302.128677 -280.028878) (xy 302.087081 -279.998657) (xy 302.050725 -279.962301)
			(xy 302.020504 -279.920705) (xy 301.997161 -279.874893) (xy 301.981273 -279.825994) (xy 301.97323 -279.775212)
			(xy 301.654593 -279.775212) (xy 301.646836 -279.822942) (xy 301.631252 -279.869623) (xy 301.608381 -279.9132)
			(xy 301.578816 -279.952544) (xy 301.543323 -279.986636) (xy 301.50282 -280.014592) (xy 301.458358 -280.03569)
			(xy 301.411087 -280.049382) (xy 301.362232 -280.055314) (xy 301.313057 -280.053333) (xy 301.264838 -280.043489)
			(xy 301.218822 -280.026037) (xy 301.176201 -280.00143) (xy 301.13808 -279.970305) (xy 301.105445 -279.933468)
			(xy 301.079142 -279.891872) (xy 301.059851 -279.846596) (xy 301.048074 -279.798812) (xy 301.044114 -279.749758)
			(xy 300.726851 -279.749758) (xy 300.726352 -279.775212) (xy 300.718309 -279.825994) (xy 300.702421 -279.874893)
			(xy 300.679078 -279.920705) (xy 300.648857 -279.962301) (xy 300.612501 -279.998657) (xy 300.570905 -280.028878)
			(xy 300.525093 -280.052221) (xy 300.476194 -280.068109) (xy 300.425412 -280.076152) (xy 300.373996 -280.076152)
			(xy 300.323214 -280.068109) (xy 300.274315 -280.052221) (xy 300.228503 -280.028878) (xy 300.186907 -279.998657)
			(xy 300.150551 -279.962301) (xy 300.12033 -279.920705) (xy 300.096987 -279.874893) (xy 300.081099 -279.825994)
			(xy 300.073056 -279.775212) (xy 299.754419 -279.775212) (xy 299.746662 -279.822942) (xy 299.731078 -279.869623)
			(xy 299.708207 -279.9132) (xy 299.678642 -279.952544) (xy 299.643149 -279.986636) (xy 299.602646 -280.014592)
			(xy 299.558184 -280.03569) (xy 299.510913 -280.049382) (xy 299.462058 -280.055314) (xy 299.412883 -280.053333)
			(xy 299.364664 -280.043489) (xy 299.318648 -280.026037) (xy 299.276027 -280.00143) (xy 299.237906 -279.970305)
			(xy 299.205271 -279.933468) (xy 299.178968 -279.891872) (xy 299.159677 -279.846596) (xy 299.1479 -279.798812)
			(xy 299.14394 -279.749758) (xy 298.826931 -279.749758) (xy 298.826432 -279.775212) (xy 298.818389 -279.825994)
			(xy 298.802501 -279.874893) (xy 298.779158 -279.920705) (xy 298.748937 -279.962301) (xy 298.712581 -279.998657)
			(xy 298.670985 -280.028878) (xy 298.625173 -280.052221) (xy 298.576274 -280.068109) (xy 298.525492 -280.076152)
			(xy 298.474076 -280.076152) (xy 298.423294 -280.068109) (xy 298.374395 -280.052221) (xy 298.328583 -280.028878)
			(xy 298.286987 -279.998657) (xy 298.250631 -279.962301) (xy 298.22041 -279.920705) (xy 298.197067 -279.874893)
			(xy 298.181179 -279.825994) (xy 298.173136 -279.775212) (xy 297.854499 -279.775212) (xy 297.846742 -279.822942)
			(xy 297.831158 -279.869623) (xy 297.808287 -279.9132) (xy 297.778722 -279.952544) (xy 297.743229 -279.986636)
			(xy 297.702726 -280.014592) (xy 297.658264 -280.03569) (xy 297.610993 -280.049382) (xy 297.562138 -280.055314)
			(xy 297.512963 -280.053333) (xy 297.464744 -280.043489) (xy 297.418728 -280.026037) (xy 297.376107 -280.00143)
			(xy 297.337986 -279.970305) (xy 297.305351 -279.933468) (xy 297.279048 -279.891872) (xy 297.259757 -279.846596)
			(xy 297.24798 -279.798812) (xy 297.24402 -279.749758) (xy 296.927011 -279.749758) (xy 296.926512 -279.775212)
			(xy 296.918469 -279.825994) (xy 296.902581 -279.874893) (xy 296.879238 -279.920705) (xy 296.849017 -279.962301)
			(xy 296.812661 -279.998657) (xy 296.771065 -280.028878) (xy 296.725253 -280.052221) (xy 296.676354 -280.068109)
			(xy 296.625572 -280.076152) (xy 296.574156 -280.076152) (xy 296.523374 -280.068109) (xy 296.474475 -280.052221)
			(xy 296.428663 -280.028878) (xy 296.387067 -279.998657) (xy 296.350711 -279.962301) (xy 296.32049 -279.920705)
			(xy 296.297147 -279.874893) (xy 296.281259 -279.825994) (xy 296.273216 -279.775212) (xy 295.954579 -279.775212)
			(xy 295.946822 -279.822942) (xy 295.931238 -279.869623) (xy 295.908367 -279.9132) (xy 295.878802 -279.952544)
			(xy 295.843309 -279.986636) (xy 295.802806 -280.014592) (xy 295.758344 -280.03569) (xy 295.711073 -280.049382)
			(xy 295.662218 -280.055314) (xy 295.613043 -280.053333) (xy 295.564824 -280.043489) (xy 295.518808 -280.026037)
			(xy 295.476187 -280.00143) (xy 295.438066 -279.970305) (xy 295.405431 -279.933468) (xy 295.379128 -279.891872)
			(xy 295.359837 -279.846596) (xy 295.34806 -279.798812) (xy 295.3441 -279.749758) (xy 295.026837 -279.749758)
			(xy 295.026338 -279.775212) (xy 295.018295 -279.825994) (xy 295.002407 -279.874893) (xy 294.979064 -279.920705)
			(xy 294.948843 -279.962301) (xy 294.912487 -279.998657) (xy 294.870891 -280.028878) (xy 294.825079 -280.052221)
			(xy 294.77618 -280.068109) (xy 294.725398 -280.076152) (xy 294.673982 -280.076152) (xy 294.6232 -280.068109)
			(xy 294.574301 -280.052221) (xy 294.528489 -280.028878) (xy 294.486893 -279.998657) (xy 294.450537 -279.962301)
			(xy 294.420316 -279.920705) (xy 294.396973 -279.874893) (xy 294.381085 -279.825994) (xy 294.373042 -279.775212)
			(xy 294.054405 -279.775212) (xy 294.046648 -279.822942) (xy 294.031064 -279.869623) (xy 294.008193 -279.9132)
			(xy 293.978628 -279.952544) (xy 293.943135 -279.986636) (xy 293.902632 -280.014592) (xy 293.85817 -280.03569)
			(xy 293.810899 -280.049382) (xy 293.762044 -280.055314) (xy 293.712869 -280.053333) (xy 293.66465 -280.043489)
			(xy 293.618634 -280.026037) (xy 293.576013 -280.00143) (xy 293.537892 -279.970305) (xy 293.505257 -279.933468)
			(xy 293.478954 -279.891872) (xy 293.459663 -279.846596) (xy 293.447886 -279.798812) (xy 293.443926 -279.749758)
			(xy 293.126917 -279.749758) (xy 293.126418 -279.775212) (xy 293.118375 -279.825994) (xy 293.102487 -279.874893)
			(xy 293.079144 -279.920705) (xy 293.048923 -279.962301) (xy 293.012567 -279.998657) (xy 292.970971 -280.028878)
			(xy 292.925159 -280.052221) (xy 292.87626 -280.068109) (xy 292.825478 -280.076152) (xy 292.774062 -280.076152)
			(xy 292.72328 -280.068109) (xy 292.674381 -280.052221) (xy 292.628569 -280.028878) (xy 292.586973 -279.998657)
			(xy 292.550617 -279.962301) (xy 292.520396 -279.920705) (xy 292.497053 -279.874893) (xy 292.481165 -279.825994)
			(xy 292.473122 -279.775212) (xy 292.154485 -279.775212) (xy 292.146728 -279.822942) (xy 292.131144 -279.869623)
			(xy 292.108273 -279.9132) (xy 292.078708 -279.952544) (xy 292.043215 -279.986636) (xy 292.002712 -280.014592)
			(xy 291.95825 -280.03569) (xy 291.910979 -280.049382) (xy 291.862124 -280.055314) (xy 291.812949 -280.053333)
			(xy 291.76473 -280.043489) (xy 291.718714 -280.026037) (xy 291.676093 -280.00143) (xy 291.637972 -279.970305)
			(xy 291.605337 -279.933468) (xy 291.579034 -279.891872) (xy 291.559743 -279.846596) (xy 291.547966 -279.798812)
			(xy 291.544006 -279.749758) (xy 291.226997 -279.749758) (xy 291.226498 -279.775212) (xy 291.218455 -279.825994)
			(xy 291.202567 -279.874893) (xy 291.179224 -279.920705) (xy 291.149003 -279.962301) (xy 291.112647 -279.998657)
			(xy 291.071051 -280.028878) (xy 291.025239 -280.052221) (xy 290.97634 -280.068109) (xy 290.925558 -280.076152)
			(xy 290.874142 -280.076152) (xy 290.82336 -280.068109) (xy 290.774461 -280.052221) (xy 290.728649 -280.028878)
			(xy 290.687053 -279.998657) (xy 290.650697 -279.962301) (xy 290.620476 -279.920705) (xy 290.597133 -279.874893)
			(xy 290.581245 -279.825994) (xy 290.573202 -279.775212) (xy 290.254565 -279.775212) (xy 290.246808 -279.822942)
			(xy 290.231224 -279.869623) (xy 290.208353 -279.9132) (xy 290.178788 -279.952544) (xy 290.143295 -279.986636)
			(xy 290.102792 -280.014592) (xy 290.05833 -280.03569) (xy 290.011059 -280.049382) (xy 289.962204 -280.055314)
			(xy 289.913029 -280.053333) (xy 289.86481 -280.043489) (xy 289.818794 -280.026037) (xy 289.776173 -280.00143)
			(xy 289.738052 -279.970305) (xy 289.705417 -279.933468) (xy 289.679114 -279.891872) (xy 289.659823 -279.846596)
			(xy 289.648046 -279.798812) (xy 289.644086 -279.749758) (xy 289.326823 -279.749758) (xy 289.326324 -279.775212)
			(xy 289.318281 -279.825994) (xy 289.302393 -279.874893) (xy 289.27905 -279.920705) (xy 289.248829 -279.962301)
			(xy 289.212473 -279.998657) (xy 289.170877 -280.028878) (xy 289.125065 -280.052221) (xy 289.076166 -280.068109)
			(xy 289.025384 -280.076152) (xy 288.973968 -280.076152) (xy 288.923186 -280.068109) (xy 288.874287 -280.052221)
			(xy 288.828475 -280.028878) (xy 288.786879 -279.998657) (xy 288.750523 -279.962301) (xy 288.720302 -279.920705)
			(xy 288.696959 -279.874893) (xy 288.681071 -279.825994) (xy 288.673028 -279.775212) (xy 288.354391 -279.775212)
			(xy 288.346634 -279.822942) (xy 288.33105 -279.869623) (xy 288.308179 -279.9132) (xy 288.278614 -279.952544)
			(xy 288.243121 -279.986636) (xy 288.202618 -280.014592) (xy 288.158156 -280.03569) (xy 288.110885 -280.049382)
			(xy 288.06203 -280.055314) (xy 288.012855 -280.053333) (xy 287.964636 -280.043489) (xy 287.91862 -280.026037)
			(xy 287.875999 -280.00143) (xy 287.837878 -279.970305) (xy 287.805243 -279.933468) (xy 287.77894 -279.891872)
			(xy 287.759649 -279.846596) (xy 287.747872 -279.798812) (xy 287.743912 -279.749758) (xy 287.426903 -279.749758)
			(xy 287.426404 -279.775212) (xy 287.418361 -279.825994) (xy 287.402473 -279.874893) (xy 287.37913 -279.920705)
			(xy 287.348909 -279.962301) (xy 287.312553 -279.998657) (xy 287.270957 -280.028878) (xy 287.225145 -280.052221)
			(xy 287.176246 -280.068109) (xy 287.125464 -280.076152) (xy 287.074048 -280.076152) (xy 287.023266 -280.068109)
			(xy 286.974367 -280.052221) (xy 286.928555 -280.028878) (xy 286.886959 -279.998657) (xy 286.850603 -279.962301)
			(xy 286.820382 -279.920705) (xy 286.797039 -279.874893) (xy 286.781151 -279.825994) (xy 286.773108 -279.775212)
			(xy 286.454471 -279.775212) (xy 286.446714 -279.822942) (xy 286.43113 -279.869623) (xy 286.408259 -279.9132)
			(xy 286.378694 -279.952544) (xy 286.343201 -279.986636) (xy 286.302698 -280.014592) (xy 286.258236 -280.03569)
			(xy 286.210965 -280.049382) (xy 286.16211 -280.055314) (xy 286.112935 -280.053333) (xy 286.064716 -280.043489)
			(xy 286.0187 -280.026037) (xy 285.976079 -280.00143) (xy 285.937958 -279.970305) (xy 285.905323 -279.933468)
			(xy 285.87902 -279.891872) (xy 285.859729 -279.846596) (xy 285.847952 -279.798812) (xy 285.843992 -279.749758)
			(xy 285.526983 -279.749758) (xy 285.526484 -279.775212) (xy 285.518441 -279.825994) (xy 285.502553 -279.874893)
			(xy 285.47921 -279.920705) (xy 285.448989 -279.962301) (xy 285.412633 -279.998657) (xy 285.371037 -280.028878)
			(xy 285.325225 -280.052221) (xy 285.276326 -280.068109) (xy 285.225544 -280.076152) (xy 285.174128 -280.076152)
			(xy 285.123346 -280.068109) (xy 285.074447 -280.052221) (xy 285.028635 -280.028878) (xy 284.987039 -279.998657)
			(xy 284.950683 -279.962301) (xy 284.920462 -279.920705) (xy 284.897119 -279.874893) (xy 284.881231 -279.825994)
			(xy 284.873188 -279.775212) (xy 284.554551 -279.775212) (xy 284.546794 -279.822942) (xy 284.53121 -279.869623)
			(xy 284.508339 -279.9132) (xy 284.478774 -279.952544) (xy 284.443281 -279.986636) (xy 284.402778 -280.014592)
			(xy 284.358316 -280.03569) (xy 284.311045 -280.049382) (xy 284.26219 -280.055314) (xy 284.213015 -280.053333)
			(xy 284.164796 -280.043489) (xy 284.11878 -280.026037) (xy 284.076159 -280.00143) (xy 284.038038 -279.970305)
			(xy 284.005403 -279.933468) (xy 283.9791 -279.891872) (xy 283.959809 -279.846596) (xy 283.948032 -279.798812)
			(xy 283.944072 -279.749758) (xy 283.627063 -279.749758) (xy 283.626564 -279.775212) (xy 283.618521 -279.825994)
			(xy 283.602633 -279.874893) (xy 283.57929 -279.920705) (xy 283.549069 -279.962301) (xy 283.512713 -279.998657)
			(xy 283.471117 -280.028878) (xy 283.425305 -280.052221) (xy 283.376406 -280.068109) (xy 283.325624 -280.076152)
			(xy 283.274208 -280.076152) (xy 283.223426 -280.068109) (xy 283.174527 -280.052221) (xy 283.128715 -280.028878)
			(xy 283.087119 -279.998657) (xy 283.050763 -279.962301) (xy 283.020542 -279.920705) (xy 282.997199 -279.874893)
			(xy 282.981311 -279.825994) (xy 282.973268 -279.775212) (xy 282.653467 -279.775212) (xy 282.651401 -279.800145)
			(xy 282.639 -279.849116) (xy 282.618708 -279.895379) (xy 282.591077 -279.93767) (xy 282.556863 -279.974837)
			(xy 282.516998 -280.005866) (xy 282.472569 -280.02991) (xy 282.424789 -280.046313) (xy 282.374961 -280.054628)
			(xy 282.349702 -280.055066) (xy 282.33552 -280.05488) (xy 282.30728 -280.052207) (xy 282.293314 -280.049732)
			(xy 282.280868 -280.047446) (xy 282.257246 -280.054812) (xy 282.179776 -280.132282) (xy 282.17241 -280.155904)
			(xy 282.174696 -280.16835) (xy 282.177179 -280.182315) (xy 282.179848 -280.210555) (xy 282.18003 -280.224738)
			(xy 282.179846 -280.238921) (xy 282.177179 -280.267161) (xy 282.174696 -280.281126) (xy 282.17241 -280.293572)
			(xy 282.179776 -280.317194) (xy 282.257246 -280.394664) (xy 282.280868 -280.40203) (xy 282.293314 -280.399744)
			(xy 282.307279 -280.397259) (xy 282.335519 -280.394587) (xy 282.349702 -280.39441) (xy 282.374956 -280.394932)
			(xy 282.424774 -280.403245) (xy 282.472545 -280.419645) (xy 282.516965 -280.443684) (xy 282.556822 -280.474707)
			(xy 282.59103 -280.511866) (xy 282.618655 -280.55415) (xy 282.638943 -280.600403) (xy 282.651342 -280.649365)
			(xy 282.655513 -280.6997) (xy 282.653381 -280.725426) (xy 282.973268 -280.725426) (xy 282.973268 -280.67401)
			(xy 282.981311 -280.623228) (xy 282.997199 -280.574329) (xy 283.020542 -280.528517) (xy 283.050763 -280.486921)
			(xy 283.087119 -280.450565) (xy 283.128715 -280.420344) (xy 283.174527 -280.397001) (xy 283.223426 -280.381113)
			(xy 283.274208 -280.37307) (xy 283.325624 -280.37307) (xy 283.376406 -280.381113) (xy 283.425305 -280.397001)
			(xy 283.471117 -280.420344) (xy 283.512713 -280.450565) (xy 283.549069 -280.486921) (xy 283.57929 -280.528517)
			(xy 283.602633 -280.574329) (xy 283.618521 -280.623228) (xy 283.626564 -280.67401) (xy 283.627068 -280.699718)
			(xy 283.944072 -280.699718) (xy 283.948032 -280.650664) (xy 283.959809 -280.60288) (xy 283.9791 -280.557604)
			(xy 284.005403 -280.516008) (xy 284.038038 -280.479171) (xy 284.076159 -280.448046) (xy 284.11878 -280.423439)
			(xy 284.164796 -280.405987) (xy 284.213015 -280.396143) (xy 284.26219 -280.394162) (xy 284.311045 -280.400094)
			(xy 284.358316 -280.413786) (xy 284.402778 -280.434884) (xy 284.443281 -280.46284) (xy 284.478774 -280.496932)
			(xy 284.508339 -280.536276) (xy 284.53121 -280.579853) (xy 284.546794 -280.626534) (xy 284.554689 -280.675111)
			(xy 284.555184 -280.699718) (xy 284.554689 -280.724325) (xy 284.55451 -280.725426) (xy 284.873188 -280.725426)
			(xy 284.873188 -280.67401) (xy 284.881231 -280.623228) (xy 284.897119 -280.574329) (xy 284.920462 -280.528517)
			(xy 284.950683 -280.486921) (xy 284.987039 -280.450565) (xy 285.028635 -280.420344) (xy 285.074447 -280.397001)
			(xy 285.123346 -280.381113) (xy 285.174128 -280.37307) (xy 285.225544 -280.37307) (xy 285.276326 -280.381113)
			(xy 285.325225 -280.397001) (xy 285.371037 -280.420344) (xy 285.412633 -280.450565) (xy 285.448989 -280.486921)
			(xy 285.47921 -280.528517) (xy 285.502553 -280.574329) (xy 285.518441 -280.623228) (xy 285.526484 -280.67401)
			(xy 285.526988 -280.699718) (xy 285.843992 -280.699718) (xy 285.847952 -280.650664) (xy 285.859729 -280.60288)
			(xy 285.87902 -280.557604) (xy 285.905323 -280.516008) (xy 285.937958 -280.479171) (xy 285.976079 -280.448046)
			(xy 286.0187 -280.423439) (xy 286.064716 -280.405987) (xy 286.112935 -280.396143) (xy 286.16211 -280.394162)
			(xy 286.210965 -280.400094) (xy 286.258236 -280.413786) (xy 286.302698 -280.434884) (xy 286.343201 -280.46284)
			(xy 286.378694 -280.496932) (xy 286.408259 -280.536276) (xy 286.43113 -280.579853) (xy 286.446714 -280.626534)
			(xy 286.454609 -280.675111) (xy 286.455104 -280.699718) (xy 286.454609 -280.724325) (xy 286.45443 -280.725426)
			(xy 286.773108 -280.725426) (xy 286.773108 -280.67401) (xy 286.781151 -280.623228) (xy 286.797039 -280.574329)
			(xy 286.820382 -280.528517) (xy 286.850603 -280.486921) (xy 286.886959 -280.450565) (xy 286.928555 -280.420344)
			(xy 286.974367 -280.397001) (xy 287.023266 -280.381113) (xy 287.074048 -280.37307) (xy 287.125464 -280.37307)
			(xy 287.176246 -280.381113) (xy 287.225145 -280.397001) (xy 287.270957 -280.420344) (xy 287.312553 -280.450565)
			(xy 287.348909 -280.486921) (xy 287.37913 -280.528517) (xy 287.402473 -280.574329) (xy 287.418361 -280.623228)
			(xy 287.426404 -280.67401) (xy 287.426908 -280.699718) (xy 287.743912 -280.699718) (xy 287.747872 -280.650664)
			(xy 287.759649 -280.60288) (xy 287.77894 -280.557604) (xy 287.805243 -280.516008) (xy 287.837878 -280.479171)
			(xy 287.875999 -280.448046) (xy 287.91862 -280.423439) (xy 287.964636 -280.405987) (xy 288.012855 -280.396143)
			(xy 288.06203 -280.394162) (xy 288.110885 -280.400094) (xy 288.158156 -280.413786) (xy 288.202618 -280.434884)
			(xy 288.243121 -280.46284) (xy 288.278614 -280.496932) (xy 288.308179 -280.536276) (xy 288.33105 -280.579853)
			(xy 288.346634 -280.626534) (xy 288.354529 -280.675111) (xy 288.355024 -280.699718) (xy 288.354529 -280.724325)
			(xy 288.35435 -280.725426) (xy 288.673028 -280.725426) (xy 288.673028 -280.67401) (xy 288.681071 -280.623228)
			(xy 288.696959 -280.574329) (xy 288.720302 -280.528517) (xy 288.750523 -280.486921) (xy 288.786879 -280.450565)
			(xy 288.828475 -280.420344) (xy 288.874287 -280.397001) (xy 288.923186 -280.381113) (xy 288.973968 -280.37307)
			(xy 289.025384 -280.37307) (xy 289.076166 -280.381113) (xy 289.125065 -280.397001) (xy 289.170877 -280.420344)
			(xy 289.212473 -280.450565) (xy 289.248829 -280.486921) (xy 289.27905 -280.528517) (xy 289.302393 -280.574329)
			(xy 289.318281 -280.623228) (xy 289.326324 -280.67401) (xy 289.326828 -280.699718) (xy 289.644086 -280.699718)
			(xy 289.648046 -280.650664) (xy 289.659823 -280.60288) (xy 289.679114 -280.557604) (xy 289.705417 -280.516008)
			(xy 289.738052 -280.479171) (xy 289.776173 -280.448046) (xy 289.818794 -280.423439) (xy 289.86481 -280.405987)
			(xy 289.913029 -280.396143) (xy 289.962204 -280.394162) (xy 290.011059 -280.400094) (xy 290.05833 -280.413786)
			(xy 290.102792 -280.434884) (xy 290.143295 -280.46284) (xy 290.178788 -280.496932) (xy 290.208353 -280.536276)
			(xy 290.231224 -280.579853) (xy 290.246808 -280.626534) (xy 290.254703 -280.675111) (xy 290.255198 -280.699718)
			(xy 290.254703 -280.724325) (xy 290.254524 -280.725426) (xy 290.573202 -280.725426) (xy 290.573202 -280.67401)
			(xy 290.581245 -280.623228) (xy 290.597133 -280.574329) (xy 290.620476 -280.528517) (xy 290.650697 -280.486921)
			(xy 290.687053 -280.450565) (xy 290.728649 -280.420344) (xy 290.774461 -280.397001) (xy 290.82336 -280.381113)
			(xy 290.874142 -280.37307) (xy 290.925558 -280.37307) (xy 290.97634 -280.381113) (xy 291.025239 -280.397001)
			(xy 291.071051 -280.420344) (xy 291.112647 -280.450565) (xy 291.149003 -280.486921) (xy 291.179224 -280.528517)
			(xy 291.202567 -280.574329) (xy 291.218455 -280.623228) (xy 291.226498 -280.67401) (xy 291.227002 -280.699718)
			(xy 291.544006 -280.699718) (xy 291.547966 -280.650664) (xy 291.559743 -280.60288) (xy 291.579034 -280.557604)
			(xy 291.605337 -280.516008) (xy 291.637972 -280.479171) (xy 291.676093 -280.448046) (xy 291.718714 -280.423439)
			(xy 291.76473 -280.405987) (xy 291.812949 -280.396143) (xy 291.862124 -280.394162) (xy 291.910979 -280.400094)
			(xy 291.95825 -280.413786) (xy 292.002712 -280.434884) (xy 292.043215 -280.46284) (xy 292.078708 -280.496932)
			(xy 292.108273 -280.536276) (xy 292.131144 -280.579853) (xy 292.146728 -280.626534) (xy 292.154623 -280.675111)
			(xy 292.155118 -280.699718) (xy 292.154623 -280.724325) (xy 292.154444 -280.725426) (xy 292.473122 -280.725426)
			(xy 292.473122 -280.67401) (xy 292.481165 -280.623228) (xy 292.497053 -280.574329) (xy 292.520396 -280.528517)
			(xy 292.550617 -280.486921) (xy 292.586973 -280.450565) (xy 292.628569 -280.420344) (xy 292.674381 -280.397001)
			(xy 292.72328 -280.381113) (xy 292.774062 -280.37307) (xy 292.825478 -280.37307) (xy 292.87626 -280.381113)
			(xy 292.925159 -280.397001) (xy 292.970971 -280.420344) (xy 293.012567 -280.450565) (xy 293.048923 -280.486921)
			(xy 293.079144 -280.528517) (xy 293.102487 -280.574329) (xy 293.118375 -280.623228) (xy 293.126418 -280.67401)
			(xy 293.126922 -280.699718) (xy 293.443926 -280.699718) (xy 293.447886 -280.650664) (xy 293.459663 -280.60288)
			(xy 293.478954 -280.557604) (xy 293.505257 -280.516008) (xy 293.537892 -280.479171) (xy 293.576013 -280.448046)
			(xy 293.618634 -280.423439) (xy 293.66465 -280.405987) (xy 293.712869 -280.396143) (xy 293.762044 -280.394162)
			(xy 293.810899 -280.400094) (xy 293.85817 -280.413786) (xy 293.902632 -280.434884) (xy 293.943135 -280.46284)
			(xy 293.978628 -280.496932) (xy 294.008193 -280.536276) (xy 294.031064 -280.579853) (xy 294.046648 -280.626534)
			(xy 294.054543 -280.675111) (xy 294.055038 -280.699718) (xy 294.054543 -280.724325) (xy 294.054364 -280.725426)
			(xy 294.373042 -280.725426) (xy 294.373042 -280.67401) (xy 294.381085 -280.623228) (xy 294.396973 -280.574329)
			(xy 294.420316 -280.528517) (xy 294.450537 -280.486921) (xy 294.486893 -280.450565) (xy 294.528489 -280.420344)
			(xy 294.574301 -280.397001) (xy 294.6232 -280.381113) (xy 294.673982 -280.37307) (xy 294.725398 -280.37307)
			(xy 294.77618 -280.381113) (xy 294.825079 -280.397001) (xy 294.870891 -280.420344) (xy 294.912487 -280.450565)
			(xy 294.948843 -280.486921) (xy 294.979064 -280.528517) (xy 295.002407 -280.574329) (xy 295.018295 -280.623228)
			(xy 295.026338 -280.67401) (xy 295.026842 -280.699718) (xy 295.3441 -280.699718) (xy 295.34806 -280.650664)
			(xy 295.359837 -280.60288) (xy 295.379128 -280.557604) (xy 295.405431 -280.516008) (xy 295.438066 -280.479171)
			(xy 295.476187 -280.448046) (xy 295.518808 -280.423439) (xy 295.564824 -280.405987) (xy 295.613043 -280.396143)
			(xy 295.662218 -280.394162) (xy 295.711073 -280.400094) (xy 295.758344 -280.413786) (xy 295.802806 -280.434884)
			(xy 295.843309 -280.46284) (xy 295.878802 -280.496932) (xy 295.908367 -280.536276) (xy 295.931238 -280.579853)
			(xy 295.946822 -280.626534) (xy 295.954717 -280.675111) (xy 295.955212 -280.699718) (xy 295.954717 -280.724325)
			(xy 295.954538 -280.725426) (xy 296.273216 -280.725426) (xy 296.273216 -280.67401) (xy 296.281259 -280.623228)
			(xy 296.297147 -280.574329) (xy 296.32049 -280.528517) (xy 296.350711 -280.486921) (xy 296.387067 -280.450565)
			(xy 296.428663 -280.420344) (xy 296.474475 -280.397001) (xy 296.523374 -280.381113) (xy 296.574156 -280.37307)
			(xy 296.625572 -280.37307) (xy 296.676354 -280.381113) (xy 296.725253 -280.397001) (xy 296.771065 -280.420344)
			(xy 296.812661 -280.450565) (xy 296.849017 -280.486921) (xy 296.879238 -280.528517) (xy 296.902581 -280.574329)
			(xy 296.918469 -280.623228) (xy 296.926512 -280.67401) (xy 296.927016 -280.699718) (xy 297.24402 -280.699718)
			(xy 297.24798 -280.650664) (xy 297.259757 -280.60288) (xy 297.279048 -280.557604) (xy 297.305351 -280.516008)
			(xy 297.337986 -280.479171) (xy 297.376107 -280.448046) (xy 297.418728 -280.423439) (xy 297.464744 -280.405987)
			(xy 297.512963 -280.396143) (xy 297.562138 -280.394162) (xy 297.610993 -280.400094) (xy 297.658264 -280.413786)
			(xy 297.702726 -280.434884) (xy 297.743229 -280.46284) (xy 297.778722 -280.496932) (xy 297.808287 -280.536276)
			(xy 297.831158 -280.579853) (xy 297.846742 -280.626534) (xy 297.854637 -280.675111) (xy 297.855132 -280.699718)
			(xy 297.854637 -280.724325) (xy 297.854458 -280.725426) (xy 298.173136 -280.725426) (xy 298.173136 -280.67401)
			(xy 298.181179 -280.623228) (xy 298.197067 -280.574329) (xy 298.22041 -280.528517) (xy 298.250631 -280.486921)
			(xy 298.286987 -280.450565) (xy 298.328583 -280.420344) (xy 298.374395 -280.397001) (xy 298.423294 -280.381113)
			(xy 298.474076 -280.37307) (xy 298.525492 -280.37307) (xy 298.576274 -280.381113) (xy 298.625173 -280.397001)
			(xy 298.670985 -280.420344) (xy 298.712581 -280.450565) (xy 298.748937 -280.486921) (xy 298.779158 -280.528517)
			(xy 298.802501 -280.574329) (xy 298.818389 -280.623228) (xy 298.826432 -280.67401) (xy 298.826936 -280.699718)
			(xy 299.14394 -280.699718) (xy 299.1479 -280.650664) (xy 299.159677 -280.60288) (xy 299.178968 -280.557604)
			(xy 299.205271 -280.516008) (xy 299.237906 -280.479171) (xy 299.276027 -280.448046) (xy 299.318648 -280.423439)
			(xy 299.364664 -280.405987) (xy 299.412883 -280.396143) (xy 299.462058 -280.394162) (xy 299.510913 -280.400094)
			(xy 299.558184 -280.413786) (xy 299.602646 -280.434884) (xy 299.643149 -280.46284) (xy 299.678642 -280.496932)
			(xy 299.708207 -280.536276) (xy 299.731078 -280.579853) (xy 299.746662 -280.626534) (xy 299.754557 -280.675111)
			(xy 299.755052 -280.699718) (xy 299.754557 -280.724325) (xy 299.754378 -280.725426) (xy 300.073056 -280.725426)
			(xy 300.073056 -280.67401) (xy 300.081099 -280.623228) (xy 300.096987 -280.574329) (xy 300.12033 -280.528517)
			(xy 300.150551 -280.486921) (xy 300.186907 -280.450565) (xy 300.228503 -280.420344) (xy 300.274315 -280.397001)
			(xy 300.323214 -280.381113) (xy 300.373996 -280.37307) (xy 300.425412 -280.37307) (xy 300.476194 -280.381113)
			(xy 300.525093 -280.397001) (xy 300.570905 -280.420344) (xy 300.612501 -280.450565) (xy 300.648857 -280.486921)
			(xy 300.679078 -280.528517) (xy 300.702421 -280.574329) (xy 300.718309 -280.623228) (xy 300.726352 -280.67401)
			(xy 300.726856 -280.699718) (xy 301.044114 -280.699718) (xy 301.048074 -280.650664) (xy 301.059851 -280.60288)
			(xy 301.079142 -280.557604) (xy 301.105445 -280.516008) (xy 301.13808 -280.479171) (xy 301.176201 -280.448046)
			(xy 301.218822 -280.423439) (xy 301.264838 -280.405987) (xy 301.313057 -280.396143) (xy 301.362232 -280.394162)
			(xy 301.411087 -280.400094) (xy 301.458358 -280.413786) (xy 301.50282 -280.434884) (xy 301.543323 -280.46284)
			(xy 301.578816 -280.496932) (xy 301.608381 -280.536276) (xy 301.631252 -280.579853) (xy 301.646836 -280.626534)
			(xy 301.654731 -280.675111) (xy 301.655226 -280.699718) (xy 301.654731 -280.724325) (xy 301.654552 -280.725426)
			(xy 301.97323 -280.725426) (xy 301.97323 -280.67401) (xy 301.981273 -280.623228) (xy 301.997161 -280.574329)
			(xy 302.020504 -280.528517) (xy 302.050725 -280.486921) (xy 302.087081 -280.450565) (xy 302.128677 -280.420344)
			(xy 302.174489 -280.397001) (xy 302.223388 -280.381113) (xy 302.27417 -280.37307) (xy 302.325586 -280.37307)
			(xy 302.376368 -280.381113) (xy 302.425267 -280.397001) (xy 302.471079 -280.420344) (xy 302.512675 -280.450565)
			(xy 302.549031 -280.486921) (xy 302.579252 -280.528517) (xy 302.602595 -280.574329) (xy 302.618483 -280.623228)
			(xy 302.626526 -280.67401) (xy 302.62703 -280.699718) (xy 302.944034 -280.699718) (xy 302.947994 -280.650664)
			(xy 302.959771 -280.60288) (xy 302.979062 -280.557604) (xy 303.005365 -280.516008) (xy 303.038 -280.479171)
			(xy 303.076121 -280.448046) (xy 303.118742 -280.423439) (xy 303.164758 -280.405987) (xy 303.212977 -280.396143)
			(xy 303.262152 -280.394162) (xy 303.311007 -280.400094) (xy 303.358278 -280.413786) (xy 303.40274 -280.434884)
			(xy 303.443243 -280.46284) (xy 303.478736 -280.496932) (xy 303.508301 -280.536276) (xy 303.531172 -280.579853)
			(xy 303.546756 -280.626534) (xy 303.554651 -280.675111) (xy 303.555146 -280.699718) (xy 303.554651 -280.724325)
			(xy 303.554472 -280.725426) (xy 303.87315 -280.725426) (xy 303.87315 -280.67401) (xy 303.881193 -280.623228)
			(xy 303.897081 -280.574329) (xy 303.920424 -280.528517) (xy 303.950645 -280.486921) (xy 303.987001 -280.450565)
			(xy 304.028597 -280.420344) (xy 304.074409 -280.397001) (xy 304.123308 -280.381113) (xy 304.17409 -280.37307)
			(xy 304.225506 -280.37307) (xy 304.276288 -280.381113) (xy 304.325187 -280.397001) (xy 304.370999 -280.420344)
			(xy 304.412595 -280.450565) (xy 304.448951 -280.486921) (xy 304.479172 -280.528517) (xy 304.502515 -280.574329)
			(xy 304.518403 -280.623228) (xy 304.526446 -280.67401) (xy 304.52695 -280.699718) (xy 304.843954 -280.699718)
			(xy 304.847914 -280.650664) (xy 304.859691 -280.60288) (xy 304.878982 -280.557604) (xy 304.905285 -280.516008)
			(xy 304.93792 -280.479171) (xy 304.976041 -280.448046) (xy 305.018662 -280.423439) (xy 305.064678 -280.405987)
			(xy 305.112897 -280.396143) (xy 305.162072 -280.394162) (xy 305.210927 -280.400094) (xy 305.258198 -280.413786)
			(xy 305.30266 -280.434884) (xy 305.343163 -280.46284) (xy 305.378656 -280.496932) (xy 305.408221 -280.536276)
			(xy 305.431092 -280.579853) (xy 305.446676 -280.626534) (xy 305.454571 -280.675111) (xy 305.455066 -280.699718)
			(xy 305.454571 -280.724325) (xy 305.454392 -280.725426) (xy 305.77307 -280.725426) (xy 305.77307 -280.67401)
			(xy 305.781113 -280.623228) (xy 305.797001 -280.574329) (xy 305.820344 -280.528517) (xy 305.850565 -280.486921)
			(xy 305.886921 -280.450565) (xy 305.928517 -280.420344) (xy 305.974329 -280.397001) (xy 306.023228 -280.381113)
			(xy 306.07401 -280.37307) (xy 306.125426 -280.37307) (xy 306.176208 -280.381113) (xy 306.225107 -280.397001)
			(xy 306.270919 -280.420344) (xy 306.312515 -280.450565) (xy 306.348871 -280.486921) (xy 306.379092 -280.528517)
			(xy 306.402435 -280.574329) (xy 306.418323 -280.623228) (xy 306.426366 -280.67401) (xy 306.42687 -280.699718)
			(xy 306.744128 -280.699718) (xy 306.748088 -280.650664) (xy 306.759865 -280.60288) (xy 306.779156 -280.557604)
			(xy 306.805459 -280.516008) (xy 306.838094 -280.479171) (xy 306.876215 -280.448046) (xy 306.918836 -280.423439)
			(xy 306.964852 -280.405987) (xy 307.013071 -280.396143) (xy 307.062246 -280.394162) (xy 307.111101 -280.400094)
			(xy 307.158372 -280.413786) (xy 307.202834 -280.434884) (xy 307.243337 -280.46284) (xy 307.27883 -280.496932)
			(xy 307.308395 -280.536276) (xy 307.331266 -280.579853) (xy 307.34685 -280.626534) (xy 307.354745 -280.675111)
			(xy 307.35524 -280.699718) (xy 307.354745 -280.724325) (xy 307.354566 -280.725426) (xy 307.673244 -280.725426)
			(xy 307.673244 -280.67401) (xy 307.681287 -280.623228) (xy 307.697175 -280.574329) (xy 307.720518 -280.528517)
			(xy 307.750739 -280.486921) (xy 307.787095 -280.450565) (xy 307.828691 -280.420344) (xy 307.874503 -280.397001)
			(xy 307.923402 -280.381113) (xy 307.974184 -280.37307) (xy 308.0256 -280.37307) (xy 308.076382 -280.381113)
			(xy 308.125281 -280.397001) (xy 308.171093 -280.420344) (xy 308.212689 -280.450565) (xy 308.249045 -280.486921)
			(xy 308.279266 -280.528517) (xy 308.302609 -280.574329) (xy 308.318497 -280.623228) (xy 308.32654 -280.67401)
			(xy 308.327044 -280.699718) (xy 308.644048 -280.699718) (xy 308.648008 -280.650664) (xy 308.659785 -280.60288)
			(xy 308.679076 -280.557604) (xy 308.705379 -280.516008) (xy 308.738014 -280.479171) (xy 308.776135 -280.448046)
			(xy 308.818756 -280.423439) (xy 308.864772 -280.405987) (xy 308.912991 -280.396143) (xy 308.962166 -280.394162)
			(xy 309.011021 -280.400094) (xy 309.058292 -280.413786) (xy 309.102754 -280.434884) (xy 309.143257 -280.46284)
			(xy 309.17875 -280.496932) (xy 309.208315 -280.536276) (xy 309.231186 -280.579853) (xy 309.24677 -280.626534)
			(xy 309.254665 -280.675111) (xy 309.25516 -280.699718) (xy 309.254665 -280.724325) (xy 309.254486 -280.725426)
			(xy 309.573164 -280.725426) (xy 309.573164 -280.67401) (xy 309.581207 -280.623228) (xy 309.597095 -280.574329)
			(xy 309.620438 -280.528517) (xy 309.650659 -280.486921) (xy 309.687015 -280.450565) (xy 309.728611 -280.420344)
			(xy 309.774423 -280.397001) (xy 309.823322 -280.381113) (xy 309.874104 -280.37307) (xy 309.92552 -280.37307)
			(xy 309.976302 -280.381113) (xy 310.025201 -280.397001) (xy 310.071013 -280.420344) (xy 310.112609 -280.450565)
			(xy 310.148965 -280.486921) (xy 310.179186 -280.528517) (xy 310.202529 -280.574329) (xy 310.218417 -280.623228)
			(xy 310.22646 -280.67401) (xy 310.226964 -280.699718) (xy 310.543968 -280.699718) (xy 310.547928 -280.650664)
			(xy 310.559705 -280.60288) (xy 310.578996 -280.557604) (xy 310.605299 -280.516008) (xy 310.637934 -280.479171)
			(xy 310.676055 -280.448046) (xy 310.718676 -280.423439) (xy 310.764692 -280.405987) (xy 310.812911 -280.396143)
			(xy 310.862086 -280.394162) (xy 310.910941 -280.400094) (xy 310.958212 -280.413786) (xy 311.002674 -280.434884)
			(xy 311.043177 -280.46284) (xy 311.07867 -280.496932) (xy 311.108235 -280.536276) (xy 311.131106 -280.579853)
			(xy 311.14669 -280.626534) (xy 311.154585 -280.675111) (xy 311.15508 -280.699718) (xy 311.154585 -280.724325)
			(xy 311.154406 -280.725426) (xy 311.473084 -280.725426) (xy 311.473084 -280.67401) (xy 311.481127 -280.623228)
			(xy 311.497015 -280.574329) (xy 311.520358 -280.528517) (xy 311.550579 -280.486921) (xy 311.586935 -280.450565)
			(xy 311.628531 -280.420344) (xy 311.674343 -280.397001) (xy 311.723242 -280.381113) (xy 311.774024 -280.37307)
			(xy 311.82544 -280.37307) (xy 311.876222 -280.381113) (xy 311.925121 -280.397001) (xy 311.970933 -280.420344)
			(xy 312.012529 -280.450565) (xy 312.048885 -280.486921) (xy 312.079106 -280.528517) (xy 312.102449 -280.574329)
			(xy 312.118337 -280.623228) (xy 312.12638 -280.67401) (xy 312.126884 -280.699718) (xy 312.444142 -280.699718)
			(xy 312.448102 -280.650664) (xy 312.459879 -280.60288) (xy 312.47917 -280.557604) (xy 312.505473 -280.516008)
			(xy 312.538108 -280.479171) (xy 312.576229 -280.448046) (xy 312.61885 -280.423439) (xy 312.664866 -280.405987)
			(xy 312.713085 -280.396143) (xy 312.76226 -280.394162) (xy 312.811115 -280.400094) (xy 312.858386 -280.413786)
			(xy 312.902848 -280.434884) (xy 312.943351 -280.46284) (xy 312.978844 -280.496932) (xy 313.008409 -280.536276)
			(xy 313.03128 -280.579853) (xy 313.046864 -280.626534) (xy 313.054759 -280.675111) (xy 313.055254 -280.699718)
			(xy 313.394102 -280.699718) (xy 313.398062 -280.650664) (xy 313.409839 -280.60288) (xy 313.42913 -280.557604)
			(xy 313.455433 -280.516008) (xy 313.488068 -280.479171) (xy 313.526189 -280.448046) (xy 313.56881 -280.423439)
			(xy 313.614826 -280.405987) (xy 313.663045 -280.396143) (xy 313.71222 -280.394162) (xy 313.761075 -280.400094)
			(xy 313.808346 -280.413786) (xy 313.852808 -280.434884) (xy 313.893311 -280.46284) (xy 313.928804 -280.496932)
			(xy 313.958369 -280.536276) (xy 313.98124 -280.579853) (xy 313.996824 -280.626534) (xy 314.004719 -280.675111)
			(xy 314.005214 -280.699718) (xy 314.344062 -280.699718) (xy 314.348022 -280.650664) (xy 314.359799 -280.60288)
			(xy 314.37909 -280.557604) (xy 314.405393 -280.516008) (xy 314.438028 -280.479171) (xy 314.476149 -280.448046)
			(xy 314.51877 -280.423439) (xy 314.564786 -280.405987) (xy 314.613005 -280.396143) (xy 314.66218 -280.394162)
			(xy 314.711035 -280.400094) (xy 314.758306 -280.413786) (xy 314.802768 -280.434884) (xy 314.843271 -280.46284)
			(xy 314.878764 -280.496932) (xy 314.908329 -280.536276) (xy 314.9312 -280.579853) (xy 314.946784 -280.626534)
			(xy 314.954679 -280.675111) (xy 314.955174 -280.699718) (xy 314.954679 -280.724325) (xy 314.946784 -280.772902)
			(xy 314.9312 -280.819583) (xy 314.908329 -280.86316) (xy 314.878764 -280.902504) (xy 314.843271 -280.936596)
			(xy 314.802768 -280.964552) (xy 314.758306 -280.98565) (xy 314.711035 -280.999342) (xy 314.66218 -281.005274)
			(xy 314.613005 -281.003293) (xy 314.564786 -280.993449) (xy 314.51877 -280.975997) (xy 314.476149 -280.95139)
			(xy 314.438028 -280.920265) (xy 314.405393 -280.883428) (xy 314.37909 -280.841832) (xy 314.359799 -280.796556)
			(xy 314.348022 -280.748772) (xy 314.344062 -280.699718) (xy 314.005214 -280.699718) (xy 314.004719 -280.724325)
			(xy 313.996824 -280.772902) (xy 313.98124 -280.819583) (xy 313.958369 -280.86316) (xy 313.928804 -280.902504)
			(xy 313.893311 -280.936596) (xy 313.852808 -280.964552) (xy 313.808346 -280.98565) (xy 313.761075 -280.999342)
			(xy 313.71222 -281.005274) (xy 313.663045 -281.003293) (xy 313.614826 -280.993449) (xy 313.56881 -280.975997)
			(xy 313.526189 -280.95139) (xy 313.488068 -280.920265) (xy 313.455433 -280.883428) (xy 313.42913 -280.841832)
			(xy 313.409839 -280.796556) (xy 313.398062 -280.748772) (xy 313.394102 -280.699718) (xy 313.055254 -280.699718)
			(xy 313.054759 -280.724325) (xy 313.046864 -280.772902) (xy 313.03128 -280.819583) (xy 313.008409 -280.86316)
			(xy 312.978844 -280.902504) (xy 312.943351 -280.936596) (xy 312.902848 -280.964552) (xy 312.858386 -280.98565)
			(xy 312.811115 -280.999342) (xy 312.76226 -281.005274) (xy 312.713085 -281.003293) (xy 312.664866 -280.993449)
			(xy 312.61885 -280.975997) (xy 312.576229 -280.95139) (xy 312.538108 -280.920265) (xy 312.505473 -280.883428)
			(xy 312.47917 -280.841832) (xy 312.459879 -280.796556) (xy 312.448102 -280.748772) (xy 312.444142 -280.699718)
			(xy 312.126884 -280.699718) (xy 312.12638 -280.725426) (xy 312.118337 -280.776208) (xy 312.102449 -280.825107)
			(xy 312.079106 -280.870919) (xy 312.048885 -280.912515) (xy 312.012529 -280.948871) (xy 311.970933 -280.979092)
			(xy 311.925121 -281.002435) (xy 311.876222 -281.018323) (xy 311.82544 -281.026366) (xy 311.774024 -281.026366)
			(xy 311.723242 -281.018323) (xy 311.674343 -281.002435) (xy 311.628531 -280.979092) (xy 311.586935 -280.948871)
			(xy 311.550579 -280.912515) (xy 311.520358 -280.870919) (xy 311.497015 -280.825107) (xy 311.481127 -280.776208)
			(xy 311.473084 -280.725426) (xy 311.154406 -280.725426) (xy 311.14669 -280.772902) (xy 311.131106 -280.819583)
			(xy 311.108235 -280.86316) (xy 311.07867 -280.902504) (xy 311.043177 -280.936596) (xy 311.002674 -280.964552)
			(xy 310.958212 -280.98565) (xy 310.910941 -280.999342) (xy 310.862086 -281.005274) (xy 310.812911 -281.003293)
			(xy 310.764692 -280.993449) (xy 310.718676 -280.975997) (xy 310.676055 -280.95139) (xy 310.637934 -280.920265)
			(xy 310.605299 -280.883428) (xy 310.578996 -280.841832) (xy 310.559705 -280.796556) (xy 310.547928 -280.748772)
			(xy 310.543968 -280.699718) (xy 310.226964 -280.699718) (xy 310.22646 -280.725426) (xy 310.218417 -280.776208)
			(xy 310.202529 -280.825107) (xy 310.179186 -280.870919) (xy 310.148965 -280.912515) (xy 310.112609 -280.948871)
			(xy 310.071013 -280.979092) (xy 310.025201 -281.002435) (xy 309.976302 -281.018323) (xy 309.92552 -281.026366)
			(xy 309.874104 -281.026366) (xy 309.823322 -281.018323) (xy 309.774423 -281.002435) (xy 309.728611 -280.979092)
			(xy 309.687015 -280.948871) (xy 309.650659 -280.912515) (xy 309.620438 -280.870919) (xy 309.597095 -280.825107)
			(xy 309.581207 -280.776208) (xy 309.573164 -280.725426) (xy 309.254486 -280.725426) (xy 309.24677 -280.772902)
			(xy 309.231186 -280.819583) (xy 309.208315 -280.86316) (xy 309.17875 -280.902504) (xy 309.143257 -280.936596)
			(xy 309.102754 -280.964552) (xy 309.058292 -280.98565) (xy 309.011021 -280.999342) (xy 308.962166 -281.005274)
			(xy 308.912991 -281.003293) (xy 308.864772 -280.993449) (xy 308.818756 -280.975997) (xy 308.776135 -280.95139)
			(xy 308.738014 -280.920265) (xy 308.705379 -280.883428) (xy 308.679076 -280.841832) (xy 308.659785 -280.796556)
			(xy 308.648008 -280.748772) (xy 308.644048 -280.699718) (xy 308.327044 -280.699718) (xy 308.32654 -280.725426)
			(xy 308.318497 -280.776208) (xy 308.302609 -280.825107) (xy 308.279266 -280.870919) (xy 308.249045 -280.912515)
			(xy 308.212689 -280.948871) (xy 308.171093 -280.979092) (xy 308.125281 -281.002435) (xy 308.076382 -281.018323)
			(xy 308.0256 -281.026366) (xy 307.974184 -281.026366) (xy 307.923402 -281.018323) (xy 307.874503 -281.002435)
			(xy 307.828691 -280.979092) (xy 307.787095 -280.948871) (xy 307.750739 -280.912515) (xy 307.720518 -280.870919)
			(xy 307.697175 -280.825107) (xy 307.681287 -280.776208) (xy 307.673244 -280.725426) (xy 307.354566 -280.725426)
			(xy 307.34685 -280.772902) (xy 307.331266 -280.819583) (xy 307.308395 -280.86316) (xy 307.27883 -280.902504)
			(xy 307.243337 -280.936596) (xy 307.202834 -280.964552) (xy 307.158372 -280.98565) (xy 307.111101 -280.999342)
			(xy 307.062246 -281.005274) (xy 307.013071 -281.003293) (xy 306.964852 -280.993449) (xy 306.918836 -280.975997)
			(xy 306.876215 -280.95139) (xy 306.838094 -280.920265) (xy 306.805459 -280.883428) (xy 306.779156 -280.841832)
			(xy 306.759865 -280.796556) (xy 306.748088 -280.748772) (xy 306.744128 -280.699718) (xy 306.42687 -280.699718)
			(xy 306.426366 -280.725426) (xy 306.418323 -280.776208) (xy 306.402435 -280.825107) (xy 306.379092 -280.870919)
			(xy 306.348871 -280.912515) (xy 306.312515 -280.948871) (xy 306.270919 -280.979092) (xy 306.225107 -281.002435)
			(xy 306.176208 -281.018323) (xy 306.125426 -281.026366) (xy 306.07401 -281.026366) (xy 306.023228 -281.018323)
			(xy 305.974329 -281.002435) (xy 305.928517 -280.979092) (xy 305.886921 -280.948871) (xy 305.850565 -280.912515)
			(xy 305.820344 -280.870919) (xy 305.797001 -280.825107) (xy 305.781113 -280.776208) (xy 305.77307 -280.725426)
			(xy 305.454392 -280.725426) (xy 305.446676 -280.772902) (xy 305.431092 -280.819583) (xy 305.408221 -280.86316)
			(xy 305.378656 -280.902504) (xy 305.343163 -280.936596) (xy 305.30266 -280.964552) (xy 305.258198 -280.98565)
			(xy 305.210927 -280.999342) (xy 305.162072 -281.005274) (xy 305.112897 -281.003293) (xy 305.064678 -280.993449)
			(xy 305.018662 -280.975997) (xy 304.976041 -280.95139) (xy 304.93792 -280.920265) (xy 304.905285 -280.883428)
			(xy 304.878982 -280.841832) (xy 304.859691 -280.796556) (xy 304.847914 -280.748772) (xy 304.843954 -280.699718)
			(xy 304.52695 -280.699718) (xy 304.526446 -280.725426) (xy 304.518403 -280.776208) (xy 304.502515 -280.825107)
			(xy 304.479172 -280.870919) (xy 304.448951 -280.912515) (xy 304.412595 -280.948871) (xy 304.370999 -280.979092)
			(xy 304.325187 -281.002435) (xy 304.276288 -281.018323) (xy 304.225506 -281.026366) (xy 304.17409 -281.026366)
			(xy 304.123308 -281.018323) (xy 304.074409 -281.002435) (xy 304.028597 -280.979092) (xy 303.987001 -280.948871)
			(xy 303.950645 -280.912515) (xy 303.920424 -280.870919) (xy 303.897081 -280.825107) (xy 303.881193 -280.776208)
			(xy 303.87315 -280.725426) (xy 303.554472 -280.725426) (xy 303.546756 -280.772902) (xy 303.531172 -280.819583)
			(xy 303.508301 -280.86316) (xy 303.478736 -280.902504) (xy 303.443243 -280.936596) (xy 303.40274 -280.964552)
			(xy 303.358278 -280.98565) (xy 303.311007 -280.999342) (xy 303.262152 -281.005274) (xy 303.212977 -281.003293)
			(xy 303.164758 -280.993449) (xy 303.118742 -280.975997) (xy 303.076121 -280.95139) (xy 303.038 -280.920265)
			(xy 303.005365 -280.883428) (xy 302.979062 -280.841832) (xy 302.959771 -280.796556) (xy 302.947994 -280.748772)
			(xy 302.944034 -280.699718) (xy 302.62703 -280.699718) (xy 302.626526 -280.725426) (xy 302.618483 -280.776208)
			(xy 302.602595 -280.825107) (xy 302.579252 -280.870919) (xy 302.549031 -280.912515) (xy 302.512675 -280.948871)
			(xy 302.471079 -280.979092) (xy 302.425267 -281.002435) (xy 302.376368 -281.018323) (xy 302.325586 -281.026366)
			(xy 302.27417 -281.026366) (xy 302.223388 -281.018323) (xy 302.174489 -281.002435) (xy 302.128677 -280.979092)
			(xy 302.087081 -280.948871) (xy 302.050725 -280.912515) (xy 302.020504 -280.870919) (xy 301.997161 -280.825107)
			(xy 301.981273 -280.776208) (xy 301.97323 -280.725426) (xy 301.654552 -280.725426) (xy 301.646836 -280.772902)
			(xy 301.631252 -280.819583) (xy 301.608381 -280.86316) (xy 301.578816 -280.902504) (xy 301.543323 -280.936596)
			(xy 301.50282 -280.964552) (xy 301.458358 -280.98565) (xy 301.411087 -280.999342) (xy 301.362232 -281.005274)
			(xy 301.313057 -281.003293) (xy 301.264838 -280.993449) (xy 301.218822 -280.975997) (xy 301.176201 -280.95139)
			(xy 301.13808 -280.920265) (xy 301.105445 -280.883428) (xy 301.079142 -280.841832) (xy 301.059851 -280.796556)
			(xy 301.048074 -280.748772) (xy 301.044114 -280.699718) (xy 300.726856 -280.699718) (xy 300.726352 -280.725426)
			(xy 300.718309 -280.776208) (xy 300.702421 -280.825107) (xy 300.679078 -280.870919) (xy 300.648857 -280.912515)
			(xy 300.612501 -280.948871) (xy 300.570905 -280.979092) (xy 300.525093 -281.002435) (xy 300.476194 -281.018323)
			(xy 300.425412 -281.026366) (xy 300.373996 -281.026366) (xy 300.323214 -281.018323) (xy 300.274315 -281.002435)
			(xy 300.228503 -280.979092) (xy 300.186907 -280.948871) (xy 300.150551 -280.912515) (xy 300.12033 -280.870919)
			(xy 300.096987 -280.825107) (xy 300.081099 -280.776208) (xy 300.073056 -280.725426) (xy 299.754378 -280.725426)
			(xy 299.746662 -280.772902) (xy 299.731078 -280.819583) (xy 299.708207 -280.86316) (xy 299.678642 -280.902504)
			(xy 299.643149 -280.936596) (xy 299.602646 -280.964552) (xy 299.558184 -280.98565) (xy 299.510913 -280.999342)
			(xy 299.462058 -281.005274) (xy 299.412883 -281.003293) (xy 299.364664 -280.993449) (xy 299.318648 -280.975997)
			(xy 299.276027 -280.95139) (xy 299.237906 -280.920265) (xy 299.205271 -280.883428) (xy 299.178968 -280.841832)
			(xy 299.159677 -280.796556) (xy 299.1479 -280.748772) (xy 299.14394 -280.699718) (xy 298.826936 -280.699718)
			(xy 298.826432 -280.725426) (xy 298.818389 -280.776208) (xy 298.802501 -280.825107) (xy 298.779158 -280.870919)
			(xy 298.748937 -280.912515) (xy 298.712581 -280.948871) (xy 298.670985 -280.979092) (xy 298.625173 -281.002435)
			(xy 298.576274 -281.018323) (xy 298.525492 -281.026366) (xy 298.474076 -281.026366) (xy 298.423294 -281.018323)
			(xy 298.374395 -281.002435) (xy 298.328583 -280.979092) (xy 298.286987 -280.948871) (xy 298.250631 -280.912515)
			(xy 298.22041 -280.870919) (xy 298.197067 -280.825107) (xy 298.181179 -280.776208) (xy 298.173136 -280.725426)
			(xy 297.854458 -280.725426) (xy 297.846742 -280.772902) (xy 297.831158 -280.819583) (xy 297.808287 -280.86316)
			(xy 297.778722 -280.902504) (xy 297.743229 -280.936596) (xy 297.702726 -280.964552) (xy 297.658264 -280.98565)
			(xy 297.610993 -280.999342) (xy 297.562138 -281.005274) (xy 297.512963 -281.003293) (xy 297.464744 -280.993449)
			(xy 297.418728 -280.975997) (xy 297.376107 -280.95139) (xy 297.337986 -280.920265) (xy 297.305351 -280.883428)
			(xy 297.279048 -280.841832) (xy 297.259757 -280.796556) (xy 297.24798 -280.748772) (xy 297.24402 -280.699718)
			(xy 296.927016 -280.699718) (xy 296.926512 -280.725426) (xy 296.918469 -280.776208) (xy 296.902581 -280.825107)
			(xy 296.879238 -280.870919) (xy 296.849017 -280.912515) (xy 296.812661 -280.948871) (xy 296.771065 -280.979092)
			(xy 296.725253 -281.002435) (xy 296.676354 -281.018323) (xy 296.625572 -281.026366) (xy 296.574156 -281.026366)
			(xy 296.523374 -281.018323) (xy 296.474475 -281.002435) (xy 296.428663 -280.979092) (xy 296.387067 -280.948871)
			(xy 296.350711 -280.912515) (xy 296.32049 -280.870919) (xy 296.297147 -280.825107) (xy 296.281259 -280.776208)
			(xy 296.273216 -280.725426) (xy 295.954538 -280.725426) (xy 295.946822 -280.772902) (xy 295.931238 -280.819583)
			(xy 295.908367 -280.86316) (xy 295.878802 -280.902504) (xy 295.843309 -280.936596) (xy 295.802806 -280.964552)
			(xy 295.758344 -280.98565) (xy 295.711073 -280.999342) (xy 295.662218 -281.005274) (xy 295.613043 -281.003293)
			(xy 295.564824 -280.993449) (xy 295.518808 -280.975997) (xy 295.476187 -280.95139) (xy 295.438066 -280.920265)
			(xy 295.405431 -280.883428) (xy 295.379128 -280.841832) (xy 295.359837 -280.796556) (xy 295.34806 -280.748772)
			(xy 295.3441 -280.699718) (xy 295.026842 -280.699718) (xy 295.026338 -280.725426) (xy 295.018295 -280.776208)
			(xy 295.002407 -280.825107) (xy 294.979064 -280.870919) (xy 294.948843 -280.912515) (xy 294.912487 -280.948871)
			(xy 294.870891 -280.979092) (xy 294.825079 -281.002435) (xy 294.77618 -281.018323) (xy 294.725398 -281.026366)
			(xy 294.673982 -281.026366) (xy 294.6232 -281.018323) (xy 294.574301 -281.002435) (xy 294.528489 -280.979092)
			(xy 294.486893 -280.948871) (xy 294.450537 -280.912515) (xy 294.420316 -280.870919) (xy 294.396973 -280.825107)
			(xy 294.381085 -280.776208) (xy 294.373042 -280.725426) (xy 294.054364 -280.725426) (xy 294.046648 -280.772902)
			(xy 294.031064 -280.819583) (xy 294.008193 -280.86316) (xy 293.978628 -280.902504) (xy 293.943135 -280.936596)
			(xy 293.902632 -280.964552) (xy 293.85817 -280.98565) (xy 293.810899 -280.999342) (xy 293.762044 -281.005274)
			(xy 293.712869 -281.003293) (xy 293.66465 -280.993449) (xy 293.618634 -280.975997) (xy 293.576013 -280.95139)
			(xy 293.537892 -280.920265) (xy 293.505257 -280.883428) (xy 293.478954 -280.841832) (xy 293.459663 -280.796556)
			(xy 293.447886 -280.748772) (xy 293.443926 -280.699718) (xy 293.126922 -280.699718) (xy 293.126418 -280.725426)
			(xy 293.118375 -280.776208) (xy 293.102487 -280.825107) (xy 293.079144 -280.870919) (xy 293.048923 -280.912515)
			(xy 293.012567 -280.948871) (xy 292.970971 -280.979092) (xy 292.925159 -281.002435) (xy 292.87626 -281.018323)
			(xy 292.825478 -281.026366) (xy 292.774062 -281.026366) (xy 292.72328 -281.018323) (xy 292.674381 -281.002435)
			(xy 292.628569 -280.979092) (xy 292.586973 -280.948871) (xy 292.550617 -280.912515) (xy 292.520396 -280.870919)
			(xy 292.497053 -280.825107) (xy 292.481165 -280.776208) (xy 292.473122 -280.725426) (xy 292.154444 -280.725426)
			(xy 292.146728 -280.772902) (xy 292.131144 -280.819583) (xy 292.108273 -280.86316) (xy 292.078708 -280.902504)
			(xy 292.043215 -280.936596) (xy 292.002712 -280.964552) (xy 291.95825 -280.98565) (xy 291.910979 -280.999342)
			(xy 291.862124 -281.005274) (xy 291.812949 -281.003293) (xy 291.76473 -280.993449) (xy 291.718714 -280.975997)
			(xy 291.676093 -280.95139) (xy 291.637972 -280.920265) (xy 291.605337 -280.883428) (xy 291.579034 -280.841832)
			(xy 291.559743 -280.796556) (xy 291.547966 -280.748772) (xy 291.544006 -280.699718) (xy 291.227002 -280.699718)
			(xy 291.226498 -280.725426) (xy 291.218455 -280.776208) (xy 291.202567 -280.825107) (xy 291.179224 -280.870919)
			(xy 291.149003 -280.912515) (xy 291.112647 -280.948871) (xy 291.071051 -280.979092) (xy 291.025239 -281.002435)
			(xy 290.97634 -281.018323) (xy 290.925558 -281.026366) (xy 290.874142 -281.026366) (xy 290.82336 -281.018323)
			(xy 290.774461 -281.002435) (xy 290.728649 -280.979092) (xy 290.687053 -280.948871) (xy 290.650697 -280.912515)
			(xy 290.620476 -280.870919) (xy 290.597133 -280.825107) (xy 290.581245 -280.776208) (xy 290.573202 -280.725426)
			(xy 290.254524 -280.725426) (xy 290.246808 -280.772902) (xy 290.231224 -280.819583) (xy 290.208353 -280.86316)
			(xy 290.178788 -280.902504) (xy 290.143295 -280.936596) (xy 290.102792 -280.964552) (xy 290.05833 -280.98565)
			(xy 290.011059 -280.999342) (xy 289.962204 -281.005274) (xy 289.913029 -281.003293) (xy 289.86481 -280.993449)
			(xy 289.818794 -280.975997) (xy 289.776173 -280.95139) (xy 289.738052 -280.920265) (xy 289.705417 -280.883428)
			(xy 289.679114 -280.841832) (xy 289.659823 -280.796556) (xy 289.648046 -280.748772) (xy 289.644086 -280.699718)
			(xy 289.326828 -280.699718) (xy 289.326324 -280.725426) (xy 289.318281 -280.776208) (xy 289.302393 -280.825107)
			(xy 289.27905 -280.870919) (xy 289.248829 -280.912515) (xy 289.212473 -280.948871) (xy 289.170877 -280.979092)
			(xy 289.125065 -281.002435) (xy 289.076166 -281.018323) (xy 289.025384 -281.026366) (xy 288.973968 -281.026366)
			(xy 288.923186 -281.018323) (xy 288.874287 -281.002435) (xy 288.828475 -280.979092) (xy 288.786879 -280.948871)
			(xy 288.750523 -280.912515) (xy 288.720302 -280.870919) (xy 288.696959 -280.825107) (xy 288.681071 -280.776208)
			(xy 288.673028 -280.725426) (xy 288.35435 -280.725426) (xy 288.346634 -280.772902) (xy 288.33105 -280.819583)
			(xy 288.308179 -280.86316) (xy 288.278614 -280.902504) (xy 288.243121 -280.936596) (xy 288.202618 -280.964552)
			(xy 288.158156 -280.98565) (xy 288.110885 -280.999342) (xy 288.06203 -281.005274) (xy 288.012855 -281.003293)
			(xy 287.964636 -280.993449) (xy 287.91862 -280.975997) (xy 287.875999 -280.95139) (xy 287.837878 -280.920265)
			(xy 287.805243 -280.883428) (xy 287.77894 -280.841832) (xy 287.759649 -280.796556) (xy 287.747872 -280.748772)
			(xy 287.743912 -280.699718) (xy 287.426908 -280.699718) (xy 287.426404 -280.725426) (xy 287.418361 -280.776208)
			(xy 287.402473 -280.825107) (xy 287.37913 -280.870919) (xy 287.348909 -280.912515) (xy 287.312553 -280.948871)
			(xy 287.270957 -280.979092) (xy 287.225145 -281.002435) (xy 287.176246 -281.018323) (xy 287.125464 -281.026366)
			(xy 287.074048 -281.026366) (xy 287.023266 -281.018323) (xy 286.974367 -281.002435) (xy 286.928555 -280.979092)
			(xy 286.886959 -280.948871) (xy 286.850603 -280.912515) (xy 286.820382 -280.870919) (xy 286.797039 -280.825107)
			(xy 286.781151 -280.776208) (xy 286.773108 -280.725426) (xy 286.45443 -280.725426) (xy 286.446714 -280.772902)
			(xy 286.43113 -280.819583) (xy 286.408259 -280.86316) (xy 286.378694 -280.902504) (xy 286.343201 -280.936596)
			(xy 286.302698 -280.964552) (xy 286.258236 -280.98565) (xy 286.210965 -280.999342) (xy 286.16211 -281.005274)
			(xy 286.112935 -281.003293) (xy 286.064716 -280.993449) (xy 286.0187 -280.975997) (xy 285.976079 -280.95139)
			(xy 285.937958 -280.920265) (xy 285.905323 -280.883428) (xy 285.87902 -280.841832) (xy 285.859729 -280.796556)
			(xy 285.847952 -280.748772) (xy 285.843992 -280.699718) (xy 285.526988 -280.699718) (xy 285.526484 -280.725426)
			(xy 285.518441 -280.776208) (xy 285.502553 -280.825107) (xy 285.47921 -280.870919) (xy 285.448989 -280.912515)
			(xy 285.412633 -280.948871) (xy 285.371037 -280.979092) (xy 285.325225 -281.002435) (xy 285.276326 -281.018323)
			(xy 285.225544 -281.026366) (xy 285.174128 -281.026366) (xy 285.123346 -281.018323) (xy 285.074447 -281.002435)
			(xy 285.028635 -280.979092) (xy 284.987039 -280.948871) (xy 284.950683 -280.912515) (xy 284.920462 -280.870919)
			(xy 284.897119 -280.825107) (xy 284.881231 -280.776208) (xy 284.873188 -280.725426) (xy 284.55451 -280.725426)
			(xy 284.546794 -280.772902) (xy 284.53121 -280.819583) (xy 284.508339 -280.86316) (xy 284.478774 -280.902504)
			(xy 284.443281 -280.936596) (xy 284.402778 -280.964552) (xy 284.358316 -280.98565) (xy 284.311045 -280.999342)
			(xy 284.26219 -281.005274) (xy 284.213015 -281.003293) (xy 284.164796 -280.993449) (xy 284.11878 -280.975997)
			(xy 284.076159 -280.95139) (xy 284.038038 -280.920265) (xy 284.005403 -280.883428) (xy 283.9791 -280.841832)
			(xy 283.959809 -280.796556) (xy 283.948032 -280.748772) (xy 283.944072 -280.699718) (xy 283.627068 -280.699718)
			(xy 283.626564 -280.725426) (xy 283.618521 -280.776208) (xy 283.602633 -280.825107) (xy 283.57929 -280.870919)
			(xy 283.549069 -280.912515) (xy 283.512713 -280.948871) (xy 283.471117 -280.979092) (xy 283.425305 -281.002435)
			(xy 283.376406 -281.018323) (xy 283.325624 -281.026366) (xy 283.274208 -281.026366) (xy 283.223426 -281.018323)
			(xy 283.174527 -281.002435) (xy 283.128715 -280.979092) (xy 283.087119 -280.948871) (xy 283.050763 -280.912515)
			(xy 283.020542 -280.870919) (xy 282.997199 -280.825107) (xy 282.981311 -280.776208) (xy 282.973268 -280.725426)
			(xy 282.653381 -280.725426) (xy 282.651342 -280.750035) (xy 282.638943 -280.798997) (xy 282.618655 -280.84525)
			(xy 282.59103 -280.887534) (xy 282.556822 -280.924693) (xy 282.516965 -280.955716) (xy 282.472545 -280.979755)
			(xy 282.424774 -280.996155) (xy 282.374956 -281.004468) (xy 282.349702 -281.005026) (xy 282.33552 -281.00484)
			(xy 282.30728 -281.002166) (xy 282.293314 -280.999692) (xy 282.280868 -280.997406) (xy 282.256992 -281.004772)
			(xy 282.179776 -281.081988) (xy 282.17241 -281.106118) (xy 282.174696 -281.11831) (xy 282.177196 -281.132337)
			(xy 282.179869 -281.160705) (xy 282.18003 -281.174952) (xy 282.179846 -281.189135) (xy 282.177177 -281.217375)
			(xy 282.174696 -281.23134) (xy 282.17241 -281.243786) (xy 282.179776 -281.267408) (xy 282.257246 -281.344878)
			(xy 282.280868 -281.352244) (xy 282.293314 -281.349958) (xy 282.307279 -281.347473) (xy 282.335519 -281.3448)
			(xy 282.349702 -281.344624) (xy 282.374955 -281.345146) (xy 282.424771 -281.353459) (xy 282.472539 -281.369858)
			(xy 282.516957 -281.393896) (xy 282.556813 -281.424917) (xy 282.591019 -281.462075) (xy 282.618642 -281.504356)
			(xy 282.63893 -281.550608) (xy 282.651328 -281.599567) (xy 282.655499 -281.6499) (xy 282.655496 -281.649932)
			(xy 282.994112 -281.649932) (xy 282.998072 -281.600878) (xy 283.009849 -281.553094) (xy 283.02914 -281.507818)
			(xy 283.055443 -281.466222) (xy 283.088078 -281.429385) (xy 283.126199 -281.39826) (xy 283.16882 -281.373653)
			(xy 283.214836 -281.356201) (xy 283.263055 -281.346357) (xy 283.31223 -281.344376) (xy 283.361085 -281.350308)
			(xy 283.408356 -281.364) (xy 283.452818 -281.385098) (xy 283.493321 -281.413054) (xy 283.528814 -281.447146)
			(xy 283.558379 -281.48649) (xy 283.58125 -281.530067) (xy 283.596834 -281.576748) (xy 283.604729 -281.625325)
			(xy 283.605224 -281.649932) (xy 283.944072 -281.649932) (xy 283.948032 -281.600878) (xy 283.959809 -281.553094)
			(xy 283.9791 -281.507818) (xy 284.005403 -281.466222) (xy 284.038038 -281.429385) (xy 284.076159 -281.39826)
			(xy 284.11878 -281.373653) (xy 284.164796 -281.356201) (xy 284.213015 -281.346357) (xy 284.26219 -281.344376)
			(xy 284.311045 -281.350308) (xy 284.358316 -281.364) (xy 284.402778 -281.385098) (xy 284.443281 -281.413054)
			(xy 284.478774 -281.447146) (xy 284.508339 -281.48649) (xy 284.53121 -281.530067) (xy 284.546794 -281.576748)
			(xy 284.554689 -281.625325) (xy 284.555184 -281.649932) (xy 284.894032 -281.649932) (xy 284.897992 -281.600878)
			(xy 284.909769 -281.553094) (xy 284.92906 -281.507818) (xy 284.955363 -281.466222) (xy 284.987998 -281.429385)
			(xy 285.026119 -281.39826) (xy 285.06874 -281.373653) (xy 285.114756 -281.356201) (xy 285.162975 -281.346357)
			(xy 285.21215 -281.344376) (xy 285.261005 -281.350308) (xy 285.308276 -281.364) (xy 285.352738 -281.385098)
			(xy 285.393241 -281.413054) (xy 285.428734 -281.447146) (xy 285.458299 -281.48649) (xy 285.48117 -281.530067)
			(xy 285.496754 -281.576748) (xy 285.504649 -281.625325) (xy 285.505144 -281.649932) (xy 285.843992 -281.649932)
			(xy 285.847952 -281.600878) (xy 285.859729 -281.553094) (xy 285.87902 -281.507818) (xy 285.905323 -281.466222)
			(xy 285.937958 -281.429385) (xy 285.976079 -281.39826) (xy 286.0187 -281.373653) (xy 286.064716 -281.356201)
			(xy 286.112935 -281.346357) (xy 286.16211 -281.344376) (xy 286.210965 -281.350308) (xy 286.258236 -281.364)
			(xy 286.302698 -281.385098) (xy 286.343201 -281.413054) (xy 286.378694 -281.447146) (xy 286.408259 -281.48649)
			(xy 286.43113 -281.530067) (xy 286.446714 -281.576748) (xy 286.454609 -281.625325) (xy 286.455104 -281.649932)
			(xy 286.793952 -281.649932) (xy 286.797912 -281.600878) (xy 286.809689 -281.553094) (xy 286.82898 -281.507818)
			(xy 286.855283 -281.466222) (xy 286.887918 -281.429385) (xy 286.926039 -281.39826) (xy 286.96866 -281.373653)
			(xy 287.014676 -281.356201) (xy 287.062895 -281.346357) (xy 287.11207 -281.344376) (xy 287.160925 -281.350308)
			(xy 287.208196 -281.364) (xy 287.252658 -281.385098) (xy 287.293161 -281.413054) (xy 287.328654 -281.447146)
			(xy 287.358219 -281.48649) (xy 287.38109 -281.530067) (xy 287.396674 -281.576748) (xy 287.404569 -281.625325)
			(xy 287.405064 -281.649932) (xy 287.743912 -281.649932) (xy 287.747872 -281.600878) (xy 287.759649 -281.553094)
			(xy 287.77894 -281.507818) (xy 287.805243 -281.466222) (xy 287.837878 -281.429385) (xy 287.875999 -281.39826)
			(xy 287.91862 -281.373653) (xy 287.964636 -281.356201) (xy 288.012855 -281.346357) (xy 288.06203 -281.344376)
			(xy 288.110885 -281.350308) (xy 288.158156 -281.364) (xy 288.202618 -281.385098) (xy 288.243121 -281.413054)
			(xy 288.278614 -281.447146) (xy 288.308179 -281.48649) (xy 288.33105 -281.530067) (xy 288.346634 -281.576748)
			(xy 288.354529 -281.625325) (xy 288.355024 -281.649932) (xy 288.694126 -281.649932) (xy 288.698086 -281.600878)
			(xy 288.709863 -281.553094) (xy 288.729154 -281.507818) (xy 288.755457 -281.466222) (xy 288.788092 -281.429385)
			(xy 288.826213 -281.39826) (xy 288.868834 -281.373653) (xy 288.91485 -281.356201) (xy 288.963069 -281.346357)
			(xy 289.012244 -281.344376) (xy 289.061099 -281.350308) (xy 289.10837 -281.364) (xy 289.152832 -281.385098)
			(xy 289.193335 -281.413054) (xy 289.228828 -281.447146) (xy 289.258393 -281.48649) (xy 289.281264 -281.530067)
			(xy 289.296848 -281.576748) (xy 289.304743 -281.625325) (xy 289.305238 -281.649932) (xy 289.644086 -281.649932)
			(xy 289.648046 -281.600878) (xy 289.659823 -281.553094) (xy 289.679114 -281.507818) (xy 289.705417 -281.466222)
			(xy 289.738052 -281.429385) (xy 289.776173 -281.39826) (xy 289.818794 -281.373653) (xy 289.86481 -281.356201)
			(xy 289.913029 -281.346357) (xy 289.962204 -281.344376) (xy 290.011059 -281.350308) (xy 290.05833 -281.364)
			(xy 290.102792 -281.385098) (xy 290.143295 -281.413054) (xy 290.178788 -281.447146) (xy 290.208353 -281.48649)
			(xy 290.231224 -281.530067) (xy 290.246808 -281.576748) (xy 290.254703 -281.625325) (xy 290.255198 -281.649932)
			(xy 290.594046 -281.649932) (xy 290.598006 -281.600878) (xy 290.609783 -281.553094) (xy 290.629074 -281.507818)
			(xy 290.655377 -281.466222) (xy 290.688012 -281.429385) (xy 290.726133 -281.39826) (xy 290.768754 -281.373653)
			(xy 290.81477 -281.356201) (xy 290.862989 -281.346357) (xy 290.912164 -281.344376) (xy 290.961019 -281.350308)
			(xy 291.00829 -281.364) (xy 291.052752 -281.385098) (xy 291.093255 -281.413054) (xy 291.128748 -281.447146)
			(xy 291.158313 -281.48649) (xy 291.181184 -281.530067) (xy 291.196768 -281.576748) (xy 291.204663 -281.625325)
			(xy 291.205158 -281.649932) (xy 291.544006 -281.649932) (xy 291.547966 -281.600878) (xy 291.559743 -281.553094)
			(xy 291.579034 -281.507818) (xy 291.605337 -281.466222) (xy 291.637972 -281.429385) (xy 291.676093 -281.39826)
			(xy 291.718714 -281.373653) (xy 291.76473 -281.356201) (xy 291.812949 -281.346357) (xy 291.862124 -281.344376)
			(xy 291.910979 -281.350308) (xy 291.95825 -281.364) (xy 292.002712 -281.385098) (xy 292.043215 -281.413054)
			(xy 292.078708 -281.447146) (xy 292.108273 -281.48649) (xy 292.131144 -281.530067) (xy 292.146728 -281.576748)
			(xy 292.154623 -281.625325) (xy 292.155118 -281.649932) (xy 292.493966 -281.649932) (xy 292.497926 -281.600878)
			(xy 292.509703 -281.553094) (xy 292.528994 -281.507818) (xy 292.555297 -281.466222) (xy 292.587932 -281.429385)
			(xy 292.626053 -281.39826) (xy 292.668674 -281.373653) (xy 292.71469 -281.356201) (xy 292.762909 -281.346357)
			(xy 292.812084 -281.344376) (xy 292.860939 -281.350308) (xy 292.90821 -281.364) (xy 292.952672 -281.385098)
			(xy 292.993175 -281.413054) (xy 293.028668 -281.447146) (xy 293.058233 -281.48649) (xy 293.081104 -281.530067)
			(xy 293.096688 -281.576748) (xy 293.104583 -281.625325) (xy 293.105078 -281.649932) (xy 293.443926 -281.649932)
			(xy 293.447886 -281.600878) (xy 293.459663 -281.553094) (xy 293.478954 -281.507818) (xy 293.505257 -281.466222)
			(xy 293.537892 -281.429385) (xy 293.576013 -281.39826) (xy 293.618634 -281.373653) (xy 293.66465 -281.356201)
			(xy 293.712869 -281.346357) (xy 293.762044 -281.344376) (xy 293.810899 -281.350308) (xy 293.85817 -281.364)
			(xy 293.902632 -281.385098) (xy 293.943135 -281.413054) (xy 293.978628 -281.447146) (xy 294.008193 -281.48649)
			(xy 294.031064 -281.530067) (xy 294.046648 -281.576748) (xy 294.054543 -281.625325) (xy 294.055038 -281.649932)
			(xy 294.393886 -281.649932) (xy 294.397846 -281.600878) (xy 294.409623 -281.553094) (xy 294.428914 -281.507818)
			(xy 294.455217 -281.466222) (xy 294.487852 -281.429385) (xy 294.525973 -281.39826) (xy 294.568594 -281.373653)
			(xy 294.61461 -281.356201) (xy 294.662829 -281.346357) (xy 294.712004 -281.344376) (xy 294.760859 -281.350308)
			(xy 294.80813 -281.364) (xy 294.852592 -281.385098) (xy 294.893095 -281.413054) (xy 294.928588 -281.447146)
			(xy 294.958153 -281.48649) (xy 294.981024 -281.530067) (xy 294.996608 -281.576748) (xy 295.004503 -281.625325)
			(xy 295.004998 -281.649932) (xy 295.3441 -281.649932) (xy 295.34806 -281.600878) (xy 295.359837 -281.553094)
			(xy 295.379128 -281.507818) (xy 295.405431 -281.466222) (xy 295.438066 -281.429385) (xy 295.476187 -281.39826)
			(xy 295.518808 -281.373653) (xy 295.564824 -281.356201) (xy 295.613043 -281.346357) (xy 295.662218 -281.344376)
			(xy 295.711073 -281.350308) (xy 295.758344 -281.364) (xy 295.802806 -281.385098) (xy 295.843309 -281.413054)
			(xy 295.878802 -281.447146) (xy 295.908367 -281.48649) (xy 295.931238 -281.530067) (xy 295.946822 -281.576748)
			(xy 295.954717 -281.625325) (xy 295.955212 -281.649932) (xy 296.29406 -281.649932) (xy 296.29802 -281.600878)
			(xy 296.309797 -281.553094) (xy 296.329088 -281.507818) (xy 296.355391 -281.466222) (xy 296.388026 -281.429385)
			(xy 296.426147 -281.39826) (xy 296.468768 -281.373653) (xy 296.514784 -281.356201) (xy 296.563003 -281.346357)
			(xy 296.612178 -281.344376) (xy 296.661033 -281.350308) (xy 296.708304 -281.364) (xy 296.752766 -281.385098)
			(xy 296.793269 -281.413054) (xy 296.828762 -281.447146) (xy 296.858327 -281.48649) (xy 296.881198 -281.530067)
			(xy 296.896782 -281.576748) (xy 296.904677 -281.625325) (xy 296.905172 -281.649932) (xy 297.24402 -281.649932)
			(xy 297.24798 -281.600878) (xy 297.259757 -281.553094) (xy 297.279048 -281.507818) (xy 297.305351 -281.466222)
			(xy 297.337986 -281.429385) (xy 297.376107 -281.39826) (xy 297.418728 -281.373653) (xy 297.464744 -281.356201)
			(xy 297.512963 -281.346357) (xy 297.562138 -281.344376) (xy 297.610993 -281.350308) (xy 297.658264 -281.364)
			(xy 297.702726 -281.385098) (xy 297.743229 -281.413054) (xy 297.778722 -281.447146) (xy 297.808287 -281.48649)
			(xy 297.831158 -281.530067) (xy 297.846742 -281.576748) (xy 297.854637 -281.625325) (xy 297.855132 -281.649932)
			(xy 298.19398 -281.649932) (xy 298.19794 -281.600878) (xy 298.209717 -281.553094) (xy 298.229008 -281.507818)
			(xy 298.255311 -281.466222) (xy 298.287946 -281.429385) (xy 298.326067 -281.39826) (xy 298.368688 -281.373653)
			(xy 298.414704 -281.356201) (xy 298.462923 -281.346357) (xy 298.512098 -281.344376) (xy 298.560953 -281.350308)
			(xy 298.608224 -281.364) (xy 298.652686 -281.385098) (xy 298.693189 -281.413054) (xy 298.728682 -281.447146)
			(xy 298.758247 -281.48649) (xy 298.781118 -281.530067) (xy 298.796702 -281.576748) (xy 298.804597 -281.625325)
			(xy 298.805092 -281.649932) (xy 299.14394 -281.649932) (xy 299.1479 -281.600878) (xy 299.159677 -281.553094)
			(xy 299.178968 -281.507818) (xy 299.205271 -281.466222) (xy 299.237906 -281.429385) (xy 299.276027 -281.39826)
			(xy 299.318648 -281.373653) (xy 299.364664 -281.356201) (xy 299.412883 -281.346357) (xy 299.462058 -281.344376)
			(xy 299.510913 -281.350308) (xy 299.558184 -281.364) (xy 299.602646 -281.385098) (xy 299.643149 -281.413054)
			(xy 299.678642 -281.447146) (xy 299.708207 -281.48649) (xy 299.731078 -281.530067) (xy 299.746662 -281.576748)
			(xy 299.754557 -281.625325) (xy 299.755052 -281.649932) (xy 300.0939 -281.649932) (xy 300.09786 -281.600878)
			(xy 300.109637 -281.553094) (xy 300.128928 -281.507818) (xy 300.155231 -281.466222) (xy 300.187866 -281.429385)
			(xy 300.225987 -281.39826) (xy 300.268608 -281.373653) (xy 300.314624 -281.356201) (xy 300.362843 -281.346357)
			(xy 300.412018 -281.344376) (xy 300.460873 -281.350308) (xy 300.508144 -281.364) (xy 300.552606 -281.385098)
			(xy 300.593109 -281.413054) (xy 300.628602 -281.447146) (xy 300.658167 -281.48649) (xy 300.681038 -281.530067)
			(xy 300.696622 -281.576748) (xy 300.704517 -281.625325) (xy 300.705012 -281.649932) (xy 301.044114 -281.649932)
			(xy 301.048074 -281.600878) (xy 301.059851 -281.553094) (xy 301.079142 -281.507818) (xy 301.105445 -281.466222)
			(xy 301.13808 -281.429385) (xy 301.176201 -281.39826) (xy 301.218822 -281.373653) (xy 301.264838 -281.356201)
			(xy 301.313057 -281.346357) (xy 301.362232 -281.344376) (xy 301.411087 -281.350308) (xy 301.458358 -281.364)
			(xy 301.50282 -281.385098) (xy 301.543323 -281.413054) (xy 301.578816 -281.447146) (xy 301.608381 -281.48649)
			(xy 301.631252 -281.530067) (xy 301.646836 -281.576748) (xy 301.654731 -281.625325) (xy 301.655226 -281.649932)
			(xy 301.994074 -281.649932) (xy 301.998034 -281.600878) (xy 302.009811 -281.553094) (xy 302.029102 -281.507818)
			(xy 302.055405 -281.466222) (xy 302.08804 -281.429385) (xy 302.126161 -281.39826) (xy 302.168782 -281.373653)
			(xy 302.214798 -281.356201) (xy 302.263017 -281.346357) (xy 302.312192 -281.344376) (xy 302.361047 -281.350308)
			(xy 302.408318 -281.364) (xy 302.45278 -281.385098) (xy 302.493283 -281.413054) (xy 302.528776 -281.447146)
			(xy 302.558341 -281.48649) (xy 302.581212 -281.530067) (xy 302.596796 -281.576748) (xy 302.604691 -281.625325)
			(xy 302.605186 -281.649932) (xy 302.944034 -281.649932) (xy 302.947994 -281.600878) (xy 302.959771 -281.553094)
			(xy 302.979062 -281.507818) (xy 303.005365 -281.466222) (xy 303.038 -281.429385) (xy 303.076121 -281.39826)
			(xy 303.118742 -281.373653) (xy 303.164758 -281.356201) (xy 303.212977 -281.346357) (xy 303.262152 -281.344376)
			(xy 303.311007 -281.350308) (xy 303.358278 -281.364) (xy 303.40274 -281.385098) (xy 303.443243 -281.413054)
			(xy 303.478736 -281.447146) (xy 303.508301 -281.48649) (xy 303.531172 -281.530067) (xy 303.546756 -281.576748)
			(xy 303.554651 -281.625325) (xy 303.555146 -281.649932) (xy 303.893994 -281.649932) (xy 303.897954 -281.600878)
			(xy 303.909731 -281.553094) (xy 303.929022 -281.507818) (xy 303.955325 -281.466222) (xy 303.98796 -281.429385)
			(xy 304.026081 -281.39826) (xy 304.068702 -281.373653) (xy 304.114718 -281.356201) (xy 304.162937 -281.346357)
			(xy 304.212112 -281.344376) (xy 304.260967 -281.350308) (xy 304.308238 -281.364) (xy 304.3527 -281.385098)
			(xy 304.393203 -281.413054) (xy 304.428696 -281.447146) (xy 304.458261 -281.48649) (xy 304.481132 -281.530067)
			(xy 304.496716 -281.576748) (xy 304.504611 -281.625325) (xy 304.505106 -281.649932) (xy 304.843954 -281.649932)
			(xy 304.847914 -281.600878) (xy 304.859691 -281.553094) (xy 304.878982 -281.507818) (xy 304.905285 -281.466222)
			(xy 304.93792 -281.429385) (xy 304.976041 -281.39826) (xy 305.018662 -281.373653) (xy 305.064678 -281.356201)
			(xy 305.112897 -281.346357) (xy 305.162072 -281.344376) (xy 305.210927 -281.350308) (xy 305.258198 -281.364)
			(xy 305.30266 -281.385098) (xy 305.343163 -281.413054) (xy 305.378656 -281.447146) (xy 305.408221 -281.48649)
			(xy 305.431092 -281.530067) (xy 305.446676 -281.576748) (xy 305.454571 -281.625325) (xy 305.455066 -281.649932)
			(xy 305.793914 -281.649932) (xy 305.797874 -281.600878) (xy 305.809651 -281.553094) (xy 305.828942 -281.507818)
			(xy 305.855245 -281.466222) (xy 305.88788 -281.429385) (xy 305.926001 -281.39826) (xy 305.968622 -281.373653)
			(xy 306.014638 -281.356201) (xy 306.062857 -281.346357) (xy 306.112032 -281.344376) (xy 306.160887 -281.350308)
			(xy 306.208158 -281.364) (xy 306.25262 -281.385098) (xy 306.293123 -281.413054) (xy 306.328616 -281.447146)
			(xy 306.358181 -281.48649) (xy 306.381052 -281.530067) (xy 306.396636 -281.576748) (xy 306.404531 -281.625325)
			(xy 306.405026 -281.649932) (xy 306.744128 -281.649932) (xy 306.748088 -281.600878) (xy 306.759865 -281.553094)
			(xy 306.779156 -281.507818) (xy 306.805459 -281.466222) (xy 306.838094 -281.429385) (xy 306.876215 -281.39826)
			(xy 306.918836 -281.373653) (xy 306.964852 -281.356201) (xy 307.013071 -281.346357) (xy 307.062246 -281.344376)
			(xy 307.111101 -281.350308) (xy 307.158372 -281.364) (xy 307.202834 -281.385098) (xy 307.243337 -281.413054)
			(xy 307.27883 -281.447146) (xy 307.308395 -281.48649) (xy 307.331266 -281.530067) (xy 307.34685 -281.576748)
			(xy 307.354745 -281.625325) (xy 307.35524 -281.649932) (xy 307.694088 -281.649932) (xy 307.698048 -281.600878)
			(xy 307.709825 -281.553094) (xy 307.729116 -281.507818) (xy 307.755419 -281.466222) (xy 307.788054 -281.429385)
			(xy 307.826175 -281.39826) (xy 307.868796 -281.373653) (xy 307.914812 -281.356201) (xy 307.963031 -281.346357)
			(xy 308.012206 -281.344376) (xy 308.061061 -281.350308) (xy 308.108332 -281.364) (xy 308.152794 -281.385098)
			(xy 308.193297 -281.413054) (xy 308.22879 -281.447146) (xy 308.258355 -281.48649) (xy 308.281226 -281.530067)
			(xy 308.29681 -281.576748) (xy 308.304705 -281.625325) (xy 308.3052 -281.649932) (xy 308.644048 -281.649932)
			(xy 308.648008 -281.600878) (xy 308.659785 -281.553094) (xy 308.679076 -281.507818) (xy 308.705379 -281.466222)
			(xy 308.738014 -281.429385) (xy 308.776135 -281.39826) (xy 308.818756 -281.373653) (xy 308.864772 -281.356201)
			(xy 308.912991 -281.346357) (xy 308.962166 -281.344376) (xy 309.011021 -281.350308) (xy 309.058292 -281.364)
			(xy 309.102754 -281.385098) (xy 309.143257 -281.413054) (xy 309.17875 -281.447146) (xy 309.208315 -281.48649)
			(xy 309.231186 -281.530067) (xy 309.24677 -281.576748) (xy 309.254665 -281.625325) (xy 309.255155 -281.649678)
			(xy 309.593754 -281.649678) (xy 309.597714 -281.600624) (xy 309.609491 -281.55284) (xy 309.628782 -281.507564)
			(xy 309.655085 -281.465968) (xy 309.68772 -281.429131) (xy 309.725841 -281.398006) (xy 309.768462 -281.373399)
			(xy 309.814478 -281.355947) (xy 309.862697 -281.346103) (xy 309.911872 -281.344122) (xy 309.960727 -281.350054)
			(xy 310.007998 -281.363746) (xy 310.05246 -281.384844) (xy 310.092963 -281.4128) (xy 310.128456 -281.446892)
			(xy 310.158021 -281.486236) (xy 310.180892 -281.529813) (xy 310.196476 -281.576494) (xy 310.204371 -281.625071)
			(xy 310.204866 -281.649678) (xy 310.204861 -281.649932) (xy 310.543714 -281.649932) (xy 310.547674 -281.600878)
			(xy 310.559451 -281.553094) (xy 310.578742 -281.507818) (xy 310.605045 -281.466222) (xy 310.63768 -281.429385)
			(xy 310.675801 -281.39826) (xy 310.718422 -281.373653) (xy 310.764438 -281.356201) (xy 310.812657 -281.346357)
			(xy 310.861832 -281.344376) (xy 310.910687 -281.350308) (xy 310.957958 -281.364) (xy 311.00242 -281.385098)
			(xy 311.042923 -281.413054) (xy 311.078416 -281.447146) (xy 311.107981 -281.48649) (xy 311.130852 -281.530067)
			(xy 311.146436 -281.576748) (xy 311.154331 -281.625325) (xy 311.154826 -281.649932) (xy 311.493928 -281.649932)
			(xy 311.497888 -281.600878) (xy 311.509665 -281.553094) (xy 311.528956 -281.507818) (xy 311.555259 -281.466222)
			(xy 311.587894 -281.429385) (xy 311.626015 -281.39826) (xy 311.668636 -281.373653) (xy 311.714652 -281.356201)
			(xy 311.762871 -281.346357) (xy 311.812046 -281.344376) (xy 311.860901 -281.350308) (xy 311.908172 -281.364)
			(xy 311.952634 -281.385098) (xy 311.993137 -281.413054) (xy 312.02863 -281.447146) (xy 312.058195 -281.48649)
			(xy 312.081066 -281.530067) (xy 312.09665 -281.576748) (xy 312.104545 -281.625325) (xy 312.10504 -281.649932)
			(xy 312.443888 -281.649932) (xy 312.447848 -281.600878) (xy 312.459625 -281.553094) (xy 312.478916 -281.507818)
			(xy 312.505219 -281.466222) (xy 312.537854 -281.429385) (xy 312.575975 -281.39826) (xy 312.618596 -281.373653)
			(xy 312.664612 -281.356201) (xy 312.712831 -281.346357) (xy 312.762006 -281.344376) (xy 312.810861 -281.350308)
			(xy 312.858132 -281.364) (xy 312.902594 -281.385098) (xy 312.943097 -281.413054) (xy 312.97859 -281.447146)
			(xy 313.008155 -281.48649) (xy 313.031026 -281.530067) (xy 313.04661 -281.576748) (xy 313.054505 -281.625325)
			(xy 313.055 -281.649932) (xy 313.054505 -281.674539) (xy 313.054326 -281.67564) (xy 313.373258 -281.67564)
			(xy 313.373258 -281.624224) (xy 313.381301 -281.573442) (xy 313.397189 -281.524543) (xy 313.420532 -281.478731)
			(xy 313.450753 -281.437135) (xy 313.487109 -281.400779) (xy 313.528705 -281.370558) (xy 313.574517 -281.347215)
			(xy 313.623416 -281.331327) (xy 313.674198 -281.323284) (xy 313.725614 -281.323284) (xy 313.776396 -281.331327)
			(xy 313.825295 -281.347215) (xy 313.871107 -281.370558) (xy 313.912703 -281.400779) (xy 313.949059 -281.437135)
			(xy 313.97928 -281.478731) (xy 314.002623 -281.524543) (xy 314.018511 -281.573442) (xy 314.026554 -281.624224)
			(xy 314.027058 -281.649932) (xy 314.026554 -281.67564) (xy 314.323218 -281.67564) (xy 314.323218 -281.624224)
			(xy 314.331261 -281.573442) (xy 314.347149 -281.524543) (xy 314.370492 -281.478731) (xy 314.400713 -281.437135)
			(xy 314.437069 -281.400779) (xy 314.478665 -281.370558) (xy 314.524477 -281.347215) (xy 314.573376 -281.331327)
			(xy 314.624158 -281.323284) (xy 314.675574 -281.323284) (xy 314.726356 -281.331327) (xy 314.775255 -281.347215)
			(xy 314.821067 -281.370558) (xy 314.862663 -281.400779) (xy 314.899019 -281.437135) (xy 314.92924 -281.478731)
			(xy 314.952583 -281.524543) (xy 314.968471 -281.573442) (xy 314.976514 -281.624224) (xy 314.977018 -281.649932)
			(xy 314.977013 -281.650186) (xy 315.294276 -281.650186) (xy 315.298236 -281.601132) (xy 315.310013 -281.553348)
			(xy 315.329304 -281.508072) (xy 315.355607 -281.466476) (xy 315.388242 -281.429639) (xy 315.426363 -281.398514)
			(xy 315.468984 -281.373907) (xy 315.515 -281.356455) (xy 315.563219 -281.346611) (xy 315.612394 -281.34463)
			(xy 315.661249 -281.350562) (xy 315.70852 -281.364254) (xy 315.752982 -281.385352) (xy 315.793485 -281.413308)
			(xy 315.828978 -281.4474) (xy 315.858543 -281.486744) (xy 315.881414 -281.530321) (xy 315.896998 -281.577002)
			(xy 315.904893 -281.625579) (xy 315.905388 -281.650186) (xy 315.904893 -281.674793) (xy 315.896998 -281.72337)
			(xy 315.881414 -281.770051) (xy 315.858543 -281.813628) (xy 315.828978 -281.852972) (xy 315.793485 -281.887064)
			(xy 315.752982 -281.91502) (xy 315.70852 -281.936118) (xy 315.661249 -281.94981) (xy 315.612394 -281.955742)
			(xy 315.563219 -281.953761) (xy 315.515 -281.943917) (xy 315.468984 -281.926465) (xy 315.426363 -281.901858)
			(xy 315.388242 -281.870733) (xy 315.355607 -281.833896) (xy 315.329304 -281.7923) (xy 315.310013 -281.747024)
			(xy 315.298236 -281.69924) (xy 315.294276 -281.650186) (xy 314.977013 -281.650186) (xy 314.976514 -281.67564)
			(xy 314.968471 -281.726422) (xy 314.952583 -281.775321) (xy 314.92924 -281.821133) (xy 314.899019 -281.862729)
			(xy 314.862663 -281.899085) (xy 314.821067 -281.929306) (xy 314.775255 -281.952649) (xy 314.726356 -281.968537)
			(xy 314.675574 -281.97658) (xy 314.624158 -281.97658) (xy 314.573376 -281.968537) (xy 314.524477 -281.952649)
			(xy 314.478665 -281.929306) (xy 314.437069 -281.899085) (xy 314.400713 -281.862729) (xy 314.370492 -281.821133)
			(xy 314.347149 -281.775321) (xy 314.331261 -281.726422) (xy 314.323218 -281.67564) (xy 314.026554 -281.67564)
			(xy 314.018511 -281.726422) (xy 314.002623 -281.775321) (xy 313.97928 -281.821133) (xy 313.949059 -281.862729)
			(xy 313.912703 -281.899085) (xy 313.871107 -281.929306) (xy 313.825295 -281.952649) (xy 313.776396 -281.968537)
			(xy 313.725614 -281.97658) (xy 313.674198 -281.97658) (xy 313.623416 -281.968537) (xy 313.574517 -281.952649)
			(xy 313.528705 -281.929306) (xy 313.487109 -281.899085) (xy 313.450753 -281.862729) (xy 313.420532 -281.821133)
			(xy 313.397189 -281.775321) (xy 313.381301 -281.726422) (xy 313.373258 -281.67564) (xy 313.054326 -281.67564)
			(xy 313.04661 -281.723116) (xy 313.031026 -281.769797) (xy 313.008155 -281.813374) (xy 312.97859 -281.852718)
			(xy 312.943097 -281.88681) (xy 312.902594 -281.914766) (xy 312.858132 -281.935864) (xy 312.810861 -281.949556)
			(xy 312.762006 -281.955488) (xy 312.712831 -281.953507) (xy 312.664612 -281.943663) (xy 312.618596 -281.926211)
			(xy 312.575975 -281.901604) (xy 312.537854 -281.870479) (xy 312.505219 -281.833642) (xy 312.478916 -281.792046)
			(xy 312.459625 -281.74677) (xy 312.447848 -281.698986) (xy 312.443888 -281.649932) (xy 312.10504 -281.649932)
			(xy 312.104545 -281.674539) (xy 312.09665 -281.723116) (xy 312.081066 -281.769797) (xy 312.058195 -281.813374)
			(xy 312.02863 -281.852718) (xy 311.993137 -281.88681) (xy 311.952634 -281.914766) (xy 311.908172 -281.935864)
			(xy 311.860901 -281.949556) (xy 311.812046 -281.955488) (xy 311.762871 -281.953507) (xy 311.714652 -281.943663)
			(xy 311.668636 -281.926211) (xy 311.626015 -281.901604) (xy 311.587894 -281.870479) (xy 311.555259 -281.833642)
			(xy 311.528956 -281.792046) (xy 311.509665 -281.74677) (xy 311.497888 -281.698986) (xy 311.493928 -281.649932)
			(xy 311.154826 -281.649932) (xy 311.154331 -281.674539) (xy 311.146436 -281.723116) (xy 311.130852 -281.769797)
			(xy 311.107981 -281.813374) (xy 311.078416 -281.852718) (xy 311.042923 -281.88681) (xy 311.00242 -281.914766)
			(xy 310.957958 -281.935864) (xy 310.910687 -281.949556) (xy 310.861832 -281.955488) (xy 310.812657 -281.953507)
			(xy 310.764438 -281.943663) (xy 310.718422 -281.926211) (xy 310.675801 -281.901604) (xy 310.63768 -281.870479)
			(xy 310.605045 -281.833642) (xy 310.578742 -281.792046) (xy 310.559451 -281.74677) (xy 310.547674 -281.698986)
			(xy 310.543714 -281.649932) (xy 310.204861 -281.649932) (xy 310.204371 -281.674285) (xy 310.196476 -281.722862)
			(xy 310.180892 -281.769543) (xy 310.158021 -281.81312) (xy 310.128456 -281.852464) (xy 310.092963 -281.886556)
			(xy 310.05246 -281.914512) (xy 310.007998 -281.93561) (xy 309.960727 -281.949302) (xy 309.911872 -281.955234)
			(xy 309.862697 -281.953253) (xy 309.814478 -281.943409) (xy 309.768462 -281.925957) (xy 309.725841 -281.90135)
			(xy 309.68772 -281.870225) (xy 309.655085 -281.833388) (xy 309.628782 -281.791792) (xy 309.609491 -281.746516)
			(xy 309.597714 -281.698732) (xy 309.593754 -281.649678) (xy 309.255155 -281.649678) (xy 309.25516 -281.649932)
			(xy 309.254665 -281.674539) (xy 309.24677 -281.723116) (xy 309.231186 -281.769797) (xy 309.208315 -281.813374)
			(xy 309.17875 -281.852718) (xy 309.143257 -281.88681) (xy 309.102754 -281.914766) (xy 309.058292 -281.935864)
			(xy 309.011021 -281.949556) (xy 308.962166 -281.955488) (xy 308.912991 -281.953507) (xy 308.864772 -281.943663)
			(xy 308.818756 -281.926211) (xy 308.776135 -281.901604) (xy 308.738014 -281.870479) (xy 308.705379 -281.833642)
			(xy 308.679076 -281.792046) (xy 308.659785 -281.74677) (xy 308.648008 -281.698986) (xy 308.644048 -281.649932)
			(xy 308.3052 -281.649932) (xy 308.304705 -281.674539) (xy 308.29681 -281.723116) (xy 308.281226 -281.769797)
			(xy 308.258355 -281.813374) (xy 308.22879 -281.852718) (xy 308.193297 -281.88681) (xy 308.152794 -281.914766)
			(xy 308.108332 -281.935864) (xy 308.061061 -281.949556) (xy 308.012206 -281.955488) (xy 307.963031 -281.953507)
			(xy 307.914812 -281.943663) (xy 307.868796 -281.926211) (xy 307.826175 -281.901604) (xy 307.788054 -281.870479)
			(xy 307.755419 -281.833642) (xy 307.729116 -281.792046) (xy 307.709825 -281.74677) (xy 307.698048 -281.698986)
			(xy 307.694088 -281.649932) (xy 307.35524 -281.649932) (xy 307.354745 -281.674539) (xy 307.34685 -281.723116)
			(xy 307.331266 -281.769797) (xy 307.308395 -281.813374) (xy 307.27883 -281.852718) (xy 307.243337 -281.88681)
			(xy 307.202834 -281.914766) (xy 307.158372 -281.935864) (xy 307.111101 -281.949556) (xy 307.062246 -281.955488)
			(xy 307.013071 -281.953507) (xy 306.964852 -281.943663) (xy 306.918836 -281.926211) (xy 306.876215 -281.901604)
			(xy 306.838094 -281.870479) (xy 306.805459 -281.833642) (xy 306.779156 -281.792046) (xy 306.759865 -281.74677)
			(xy 306.748088 -281.698986) (xy 306.744128 -281.649932) (xy 306.405026 -281.649932) (xy 306.404531 -281.674539)
			(xy 306.396636 -281.723116) (xy 306.381052 -281.769797) (xy 306.358181 -281.813374) (xy 306.328616 -281.852718)
			(xy 306.293123 -281.88681) (xy 306.25262 -281.914766) (xy 306.208158 -281.935864) (xy 306.160887 -281.949556)
			(xy 306.112032 -281.955488) (xy 306.062857 -281.953507) (xy 306.014638 -281.943663) (xy 305.968622 -281.926211)
			(xy 305.926001 -281.901604) (xy 305.88788 -281.870479) (xy 305.855245 -281.833642) (xy 305.828942 -281.792046)
			(xy 305.809651 -281.74677) (xy 305.797874 -281.698986) (xy 305.793914 -281.649932) (xy 305.455066 -281.649932)
			(xy 305.454571 -281.674539) (xy 305.446676 -281.723116) (xy 305.431092 -281.769797) (xy 305.408221 -281.813374)
			(xy 305.378656 -281.852718) (xy 305.343163 -281.88681) (xy 305.30266 -281.914766) (xy 305.258198 -281.935864)
			(xy 305.210927 -281.949556) (xy 305.162072 -281.955488) (xy 305.112897 -281.953507) (xy 305.064678 -281.943663)
			(xy 305.018662 -281.926211) (xy 304.976041 -281.901604) (xy 304.93792 -281.870479) (xy 304.905285 -281.833642)
			(xy 304.878982 -281.792046) (xy 304.859691 -281.74677) (xy 304.847914 -281.698986) (xy 304.843954 -281.649932)
			(xy 304.505106 -281.649932) (xy 304.504611 -281.674539) (xy 304.496716 -281.723116) (xy 304.481132 -281.769797)
			(xy 304.458261 -281.813374) (xy 304.428696 -281.852718) (xy 304.393203 -281.88681) (xy 304.3527 -281.914766)
			(xy 304.308238 -281.935864) (xy 304.260967 -281.949556) (xy 304.212112 -281.955488) (xy 304.162937 -281.953507)
			(xy 304.114718 -281.943663) (xy 304.068702 -281.926211) (xy 304.026081 -281.901604) (xy 303.98796 -281.870479)
			(xy 303.955325 -281.833642) (xy 303.929022 -281.792046) (xy 303.909731 -281.74677) (xy 303.897954 -281.698986)
			(xy 303.893994 -281.649932) (xy 303.555146 -281.649932) (xy 303.554651 -281.674539) (xy 303.546756 -281.723116)
			(xy 303.531172 -281.769797) (xy 303.508301 -281.813374) (xy 303.478736 -281.852718) (xy 303.443243 -281.88681)
			(xy 303.40274 -281.914766) (xy 303.358278 -281.935864) (xy 303.311007 -281.949556) (xy 303.262152 -281.955488)
			(xy 303.212977 -281.953507) (xy 303.164758 -281.943663) (xy 303.118742 -281.926211) (xy 303.076121 -281.901604)
			(xy 303.038 -281.870479) (xy 303.005365 -281.833642) (xy 302.979062 -281.792046) (xy 302.959771 -281.74677)
			(xy 302.947994 -281.698986) (xy 302.944034 -281.649932) (xy 302.605186 -281.649932) (xy 302.604691 -281.674539)
			(xy 302.596796 -281.723116) (xy 302.581212 -281.769797) (xy 302.558341 -281.813374) (xy 302.528776 -281.852718)
			(xy 302.493283 -281.88681) (xy 302.45278 -281.914766) (xy 302.408318 -281.935864) (xy 302.361047 -281.949556)
			(xy 302.312192 -281.955488) (xy 302.263017 -281.953507) (xy 302.214798 -281.943663) (xy 302.168782 -281.926211)
			(xy 302.126161 -281.901604) (xy 302.08804 -281.870479) (xy 302.055405 -281.833642) (xy 302.029102 -281.792046)
			(xy 302.009811 -281.74677) (xy 301.998034 -281.698986) (xy 301.994074 -281.649932) (xy 301.655226 -281.649932)
			(xy 301.654731 -281.674539) (xy 301.646836 -281.723116) (xy 301.631252 -281.769797) (xy 301.608381 -281.813374)
			(xy 301.578816 -281.852718) (xy 301.543323 -281.88681) (xy 301.50282 -281.914766) (xy 301.458358 -281.935864)
			(xy 301.411087 -281.949556) (xy 301.362232 -281.955488) (xy 301.313057 -281.953507) (xy 301.264838 -281.943663)
			(xy 301.218822 -281.926211) (xy 301.176201 -281.901604) (xy 301.13808 -281.870479) (xy 301.105445 -281.833642)
			(xy 301.079142 -281.792046) (xy 301.059851 -281.74677) (xy 301.048074 -281.698986) (xy 301.044114 -281.649932)
			(xy 300.705012 -281.649932) (xy 300.704517 -281.674539) (xy 300.696622 -281.723116) (xy 300.681038 -281.769797)
			(xy 300.658167 -281.813374) (xy 300.628602 -281.852718) (xy 300.593109 -281.88681) (xy 300.552606 -281.914766)
			(xy 300.508144 -281.935864) (xy 300.460873 -281.949556) (xy 300.412018 -281.955488) (xy 300.362843 -281.953507)
			(xy 300.314624 -281.943663) (xy 300.268608 -281.926211) (xy 300.225987 -281.901604) (xy 300.187866 -281.870479)
			(xy 300.155231 -281.833642) (xy 300.128928 -281.792046) (xy 300.109637 -281.74677) (xy 300.09786 -281.698986)
			(xy 300.0939 -281.649932) (xy 299.755052 -281.649932) (xy 299.754557 -281.674539) (xy 299.746662 -281.723116)
			(xy 299.731078 -281.769797) (xy 299.708207 -281.813374) (xy 299.678642 -281.852718) (xy 299.643149 -281.88681)
			(xy 299.602646 -281.914766) (xy 299.558184 -281.935864) (xy 299.510913 -281.949556) (xy 299.462058 -281.955488)
			(xy 299.412883 -281.953507) (xy 299.364664 -281.943663) (xy 299.318648 -281.926211) (xy 299.276027 -281.901604)
			(xy 299.237906 -281.870479) (xy 299.205271 -281.833642) (xy 299.178968 -281.792046) (xy 299.159677 -281.74677)
			(xy 299.1479 -281.698986) (xy 299.14394 -281.649932) (xy 298.805092 -281.649932) (xy 298.804597 -281.674539)
			(xy 298.796702 -281.723116) (xy 298.781118 -281.769797) (xy 298.758247 -281.813374) (xy 298.728682 -281.852718)
			(xy 298.693189 -281.88681) (xy 298.652686 -281.914766) (xy 298.608224 -281.935864) (xy 298.560953 -281.949556)
			(xy 298.512098 -281.955488) (xy 298.462923 -281.953507) (xy 298.414704 -281.943663) (xy 298.368688 -281.926211)
			(xy 298.326067 -281.901604) (xy 298.287946 -281.870479) (xy 298.255311 -281.833642) (xy 298.229008 -281.792046)
			(xy 298.209717 -281.74677) (xy 298.19794 -281.698986) (xy 298.19398 -281.649932) (xy 297.855132 -281.649932)
			(xy 297.854637 -281.674539) (xy 297.846742 -281.723116) (xy 297.831158 -281.769797) (xy 297.808287 -281.813374)
			(xy 297.778722 -281.852718) (xy 297.743229 -281.88681) (xy 297.702726 -281.914766) (xy 297.658264 -281.935864)
			(xy 297.610993 -281.949556) (xy 297.562138 -281.955488) (xy 297.512963 -281.953507) (xy 297.464744 -281.943663)
			(xy 297.418728 -281.926211) (xy 297.376107 -281.901604) (xy 297.337986 -281.870479) (xy 297.305351 -281.833642)
			(xy 297.279048 -281.792046) (xy 297.259757 -281.74677) (xy 297.24798 -281.698986) (xy 297.24402 -281.649932)
			(xy 296.905172 -281.649932) (xy 296.904677 -281.674539) (xy 296.896782 -281.723116) (xy 296.881198 -281.769797)
			(xy 296.858327 -281.813374) (xy 296.828762 -281.852718) (xy 296.793269 -281.88681) (xy 296.752766 -281.914766)
			(xy 296.708304 -281.935864) (xy 296.661033 -281.949556) (xy 296.612178 -281.955488) (xy 296.563003 -281.953507)
			(xy 296.514784 -281.943663) (xy 296.468768 -281.926211) (xy 296.426147 -281.901604) (xy 296.388026 -281.870479)
			(xy 296.355391 -281.833642) (xy 296.329088 -281.792046) (xy 296.309797 -281.74677) (xy 296.29802 -281.698986)
			(xy 296.29406 -281.649932) (xy 295.955212 -281.649932) (xy 295.954717 -281.674539) (xy 295.946822 -281.723116)
			(xy 295.931238 -281.769797) (xy 295.908367 -281.813374) (xy 295.878802 -281.852718) (xy 295.843309 -281.88681)
			(xy 295.802806 -281.914766) (xy 295.758344 -281.935864) (xy 295.711073 -281.949556) (xy 295.662218 -281.955488)
			(xy 295.613043 -281.953507) (xy 295.564824 -281.943663) (xy 295.518808 -281.926211) (xy 295.476187 -281.901604)
			(xy 295.438066 -281.870479) (xy 295.405431 -281.833642) (xy 295.379128 -281.792046) (xy 295.359837 -281.74677)
			(xy 295.34806 -281.698986) (xy 295.3441 -281.649932) (xy 295.004998 -281.649932) (xy 295.004503 -281.674539)
			(xy 294.996608 -281.723116) (xy 294.981024 -281.769797) (xy 294.958153 -281.813374) (xy 294.928588 -281.852718)
			(xy 294.893095 -281.88681) (xy 294.852592 -281.914766) (xy 294.80813 -281.935864) (xy 294.760859 -281.949556)
			(xy 294.712004 -281.955488) (xy 294.662829 -281.953507) (xy 294.61461 -281.943663) (xy 294.568594 -281.926211)
			(xy 294.525973 -281.901604) (xy 294.487852 -281.870479) (xy 294.455217 -281.833642) (xy 294.428914 -281.792046)
			(xy 294.409623 -281.74677) (xy 294.397846 -281.698986) (xy 294.393886 -281.649932) (xy 294.055038 -281.649932)
			(xy 294.054543 -281.674539) (xy 294.046648 -281.723116) (xy 294.031064 -281.769797) (xy 294.008193 -281.813374)
			(xy 293.978628 -281.852718) (xy 293.943135 -281.88681) (xy 293.902632 -281.914766) (xy 293.85817 -281.935864)
			(xy 293.810899 -281.949556) (xy 293.762044 -281.955488) (xy 293.712869 -281.953507) (xy 293.66465 -281.943663)
			(xy 293.618634 -281.926211) (xy 293.576013 -281.901604) (xy 293.537892 -281.870479) (xy 293.505257 -281.833642)
			(xy 293.478954 -281.792046) (xy 293.459663 -281.74677) (xy 293.447886 -281.698986) (xy 293.443926 -281.649932)
			(xy 293.105078 -281.649932) (xy 293.104583 -281.674539) (xy 293.096688 -281.723116) (xy 293.081104 -281.769797)
			(xy 293.058233 -281.813374) (xy 293.028668 -281.852718) (xy 292.993175 -281.88681) (xy 292.952672 -281.914766)
			(xy 292.90821 -281.935864) (xy 292.860939 -281.949556) (xy 292.812084 -281.955488) (xy 292.762909 -281.953507)
			(xy 292.71469 -281.943663) (xy 292.668674 -281.926211) (xy 292.626053 -281.901604) (xy 292.587932 -281.870479)
			(xy 292.555297 -281.833642) (xy 292.528994 -281.792046) (xy 292.509703 -281.74677) (xy 292.497926 -281.698986)
			(xy 292.493966 -281.649932) (xy 292.155118 -281.649932) (xy 292.154623 -281.674539) (xy 292.146728 -281.723116)
			(xy 292.131144 -281.769797) (xy 292.108273 -281.813374) (xy 292.078708 -281.852718) (xy 292.043215 -281.88681)
			(xy 292.002712 -281.914766) (xy 291.95825 -281.935864) (xy 291.910979 -281.949556) (xy 291.862124 -281.955488)
			(xy 291.812949 -281.953507) (xy 291.76473 -281.943663) (xy 291.718714 -281.926211) (xy 291.676093 -281.901604)
			(xy 291.637972 -281.870479) (xy 291.605337 -281.833642) (xy 291.579034 -281.792046) (xy 291.559743 -281.74677)
			(xy 291.547966 -281.698986) (xy 291.544006 -281.649932) (xy 291.205158 -281.649932) (xy 291.204663 -281.674539)
			(xy 291.196768 -281.723116) (xy 291.181184 -281.769797) (xy 291.158313 -281.813374) (xy 291.128748 -281.852718)
			(xy 291.093255 -281.88681) (xy 291.052752 -281.914766) (xy 291.00829 -281.935864) (xy 290.961019 -281.949556)
			(xy 290.912164 -281.955488) (xy 290.862989 -281.953507) (xy 290.81477 -281.943663) (xy 290.768754 -281.926211)
			(xy 290.726133 -281.901604) (xy 290.688012 -281.870479) (xy 290.655377 -281.833642) (xy 290.629074 -281.792046)
			(xy 290.609783 -281.74677) (xy 290.598006 -281.698986) (xy 290.594046 -281.649932) (xy 290.255198 -281.649932)
			(xy 290.254703 -281.674539) (xy 290.246808 -281.723116) (xy 290.231224 -281.769797) (xy 290.208353 -281.813374)
			(xy 290.178788 -281.852718) (xy 290.143295 -281.88681) (xy 290.102792 -281.914766) (xy 290.05833 -281.935864)
			(xy 290.011059 -281.949556) (xy 289.962204 -281.955488) (xy 289.913029 -281.953507) (xy 289.86481 -281.943663)
			(xy 289.818794 -281.926211) (xy 289.776173 -281.901604) (xy 289.738052 -281.870479) (xy 289.705417 -281.833642)
			(xy 289.679114 -281.792046) (xy 289.659823 -281.74677) (xy 289.648046 -281.698986) (xy 289.644086 -281.649932)
			(xy 289.305238 -281.649932) (xy 289.304743 -281.674539) (xy 289.296848 -281.723116) (xy 289.281264 -281.769797)
			(xy 289.258393 -281.813374) (xy 289.228828 -281.852718) (xy 289.193335 -281.88681) (xy 289.152832 -281.914766)
			(xy 289.10837 -281.935864) (xy 289.061099 -281.949556) (xy 289.012244 -281.955488) (xy 288.963069 -281.953507)
			(xy 288.91485 -281.943663) (xy 288.868834 -281.926211) (xy 288.826213 -281.901604) (xy 288.788092 -281.870479)
			(xy 288.755457 -281.833642) (xy 288.729154 -281.792046) (xy 288.709863 -281.74677) (xy 288.698086 -281.698986)
			(xy 288.694126 -281.649932) (xy 288.355024 -281.649932) (xy 288.354529 -281.674539) (xy 288.346634 -281.723116)
			(xy 288.33105 -281.769797) (xy 288.308179 -281.813374) (xy 288.278614 -281.852718) (xy 288.243121 -281.88681)
			(xy 288.202618 -281.914766) (xy 288.158156 -281.935864) (xy 288.110885 -281.949556) (xy 288.06203 -281.955488)
			(xy 288.012855 -281.953507) (xy 287.964636 -281.943663) (xy 287.91862 -281.926211) (xy 287.875999 -281.901604)
			(xy 287.837878 -281.870479) (xy 287.805243 -281.833642) (xy 287.77894 -281.792046) (xy 287.759649 -281.74677)
			(xy 287.747872 -281.698986) (xy 287.743912 -281.649932) (xy 287.405064 -281.649932) (xy 287.404569 -281.674539)
			(xy 287.396674 -281.723116) (xy 287.38109 -281.769797) (xy 287.358219 -281.813374) (xy 287.328654 -281.852718)
			(xy 287.293161 -281.88681) (xy 287.252658 -281.914766) (xy 287.208196 -281.935864) (xy 287.160925 -281.949556)
			(xy 287.11207 -281.955488) (xy 287.062895 -281.953507) (xy 287.014676 -281.943663) (xy 286.96866 -281.926211)
			(xy 286.926039 -281.901604) (xy 286.887918 -281.870479) (xy 286.855283 -281.833642) (xy 286.82898 -281.792046)
			(xy 286.809689 -281.74677) (xy 286.797912 -281.698986) (xy 286.793952 -281.649932) (xy 286.455104 -281.649932)
			(xy 286.454609 -281.674539) (xy 286.446714 -281.723116) (xy 286.43113 -281.769797) (xy 286.408259 -281.813374)
			(xy 286.378694 -281.852718) (xy 286.343201 -281.88681) (xy 286.302698 -281.914766) (xy 286.258236 -281.935864)
			(xy 286.210965 -281.949556) (xy 286.16211 -281.955488) (xy 286.112935 -281.953507) (xy 286.064716 -281.943663)
			(xy 286.0187 -281.926211) (xy 285.976079 -281.901604) (xy 285.937958 -281.870479) (xy 285.905323 -281.833642)
			(xy 285.87902 -281.792046) (xy 285.859729 -281.74677) (xy 285.847952 -281.698986) (xy 285.843992 -281.649932)
			(xy 285.505144 -281.649932) (xy 285.504649 -281.674539) (xy 285.496754 -281.723116) (xy 285.48117 -281.769797)
			(xy 285.458299 -281.813374) (xy 285.428734 -281.852718) (xy 285.393241 -281.88681) (xy 285.352738 -281.914766)
			(xy 285.308276 -281.935864) (xy 285.261005 -281.949556) (xy 285.21215 -281.955488) (xy 285.162975 -281.953507)
			(xy 285.114756 -281.943663) (xy 285.06874 -281.926211) (xy 285.026119 -281.901604) (xy 284.987998 -281.870479)
			(xy 284.955363 -281.833642) (xy 284.92906 -281.792046) (xy 284.909769 -281.74677) (xy 284.897992 -281.698986)
			(xy 284.894032 -281.649932) (xy 284.555184 -281.649932) (xy 284.554689 -281.674539) (xy 284.546794 -281.723116)
			(xy 284.53121 -281.769797) (xy 284.508339 -281.813374) (xy 284.478774 -281.852718) (xy 284.443281 -281.88681)
			(xy 284.402778 -281.914766) (xy 284.358316 -281.935864) (xy 284.311045 -281.949556) (xy 284.26219 -281.955488)
			(xy 284.213015 -281.953507) (xy 284.164796 -281.943663) (xy 284.11878 -281.926211) (xy 284.076159 -281.901604)
			(xy 284.038038 -281.870479) (xy 284.005403 -281.833642) (xy 283.9791 -281.792046) (xy 283.959809 -281.74677)
			(xy 283.948032 -281.698986) (xy 283.944072 -281.649932) (xy 283.605224 -281.649932) (xy 283.604729 -281.674539)
			(xy 283.596834 -281.723116) (xy 283.58125 -281.769797) (xy 283.558379 -281.813374) (xy 283.528814 -281.852718)
			(xy 283.493321 -281.88681) (xy 283.452818 -281.914766) (xy 283.408356 -281.935864) (xy 283.361085 -281.949556)
			(xy 283.31223 -281.955488) (xy 283.263055 -281.953507) (xy 283.214836 -281.943663) (xy 283.16882 -281.926211)
			(xy 283.126199 -281.901604) (xy 283.088078 -281.870479) (xy 283.055443 -281.833642) (xy 283.02914 -281.792046)
			(xy 283.009849 -281.74677) (xy 282.998072 -281.698986) (xy 282.994112 -281.649932) (xy 282.655496 -281.649932)
			(xy 282.651328 -281.700233) (xy 282.63893 -281.749192) (xy 282.618642 -281.795444) (xy 282.591019 -281.837725)
			(xy 282.556813 -281.874883) (xy 282.516957 -281.905904) (xy 282.472539 -281.929942) (xy 282.424771 -281.946341)
			(xy 282.374955 -281.954654) (xy 282.349702 -281.95524) (xy 282.33552 -281.955054) (xy 282.30728 -281.952381)
			(xy 282.293314 -281.949906) (xy 282.280868 -281.94762) (xy 282.257246 -281.954986) (xy 282.179776 -282.032456)
			(xy 282.17241 -282.056078) (xy 282.174696 -282.068524) (xy 282.177181 -282.082489) (xy 282.179851 -282.110729)
			(xy 282.18003 -282.124912) (xy 282.179559 -282.148903) (xy 282.172051 -282.196295) (xy 282.157223 -282.241929)
			(xy 282.135439 -282.284681) (xy 282.107236 -282.3235) (xy 282.073308 -282.357429) (xy 282.03449 -282.385634)
			(xy 281.991738 -282.407419) (xy 281.946105 -282.422249) (xy 281.898713 -282.429758) (xy 281.874722 -282.43022)
			(xy 281.844648 -282.429526) (xy 281.785663 -282.417758) (xy 281.757628 -282.406852) (xy 281.745763 -282.402612)
			(xy 281.720707 -282.40499) (xy 281.709876 -282.411424) (xy 281.639518 -282.458414) (xy 281.629464 -282.465935)
			(xy 281.617623 -282.488042) (xy 281.616912 -282.500578) (xy 281.616912 -282.699206) (xy 281.617555 -282.711761)
			(xy 281.629412 -282.733893) (xy 281.639518 -282.74137) (xy 281.720544 -282.795472) (xy 281.745436 -282.798012)
			(xy 281.757628 -282.792932) (xy 281.785665 -282.782032) (xy 281.844649 -282.770265) (xy 281.874722 -282.769564)
			(xy 281.899978 -282.770087) (xy 281.949802 -282.778405) (xy 281.997577 -282.794809) (xy 282.042001 -282.818853)
			(xy 282.081861 -282.84988) (xy 282.116071 -282.887045) (xy 282.143698 -282.929333) (xy 282.163988 -282.975592)
			(xy 282.176388 -283.02456) (xy 282.180557 -283.074872) (xy 282.519132 -283.074872) (xy 282.523092 -283.025818)
			(xy 282.534869 -282.978034) (xy 282.55416 -282.932758) (xy 282.580463 -282.891162) (xy 282.613098 -282.854325)
			(xy 282.651219 -282.8232) (xy 282.69384 -282.798593) (xy 282.739856 -282.781141) (xy 282.788075 -282.771297)
			(xy 282.83725 -282.769316) (xy 282.886105 -282.775248) (xy 282.933376 -282.78894) (xy 282.977838 -282.810038)
			(xy 283.018341 -282.837994) (xy 283.053834 -282.872086) (xy 283.083399 -282.91143) (xy 283.10627 -282.955007)
			(xy 283.121854 -283.001688) (xy 283.129749 -283.050265) (xy 283.130244 -283.074872) (xy 283.469092 -283.074872)
			(xy 283.473052 -283.025818) (xy 283.484829 -282.978034) (xy 283.50412 -282.932758) (xy 283.530423 -282.891162)
			(xy 283.563058 -282.854325) (xy 283.601179 -282.8232) (xy 283.6438 -282.798593) (xy 283.689816 -282.781141)
			(xy 283.738035 -282.771297) (xy 283.78721 -282.769316) (xy 283.836065 -282.775248) (xy 283.883336 -282.78894)
			(xy 283.927798 -282.810038) (xy 283.968301 -282.837994) (xy 284.003794 -282.872086) (xy 284.033359 -282.91143)
			(xy 284.05623 -282.955007) (xy 284.071814 -283.001688) (xy 284.079709 -283.050265) (xy 284.080204 -283.074872)
			(xy 284.419052 -283.074872) (xy 284.423012 -283.025818) (xy 284.434789 -282.978034) (xy 284.45408 -282.932758)
			(xy 284.480383 -282.891162) (xy 284.513018 -282.854325) (xy 284.551139 -282.8232) (xy 284.59376 -282.798593)
			(xy 284.639776 -282.781141) (xy 284.687995 -282.771297) (xy 284.73717 -282.769316) (xy 284.786025 -282.775248)
			(xy 284.833296 -282.78894) (xy 284.877758 -282.810038) (xy 284.918261 -282.837994) (xy 284.953754 -282.872086)
			(xy 284.983319 -282.91143) (xy 285.00619 -282.955007) (xy 285.021774 -283.001688) (xy 285.029669 -283.050265)
			(xy 285.030164 -283.074872) (xy 285.369012 -283.074872) (xy 285.372972 -283.025818) (xy 285.384749 -282.978034)
			(xy 285.40404 -282.932758) (xy 285.430343 -282.891162) (xy 285.462978 -282.854325) (xy 285.501099 -282.8232)
			(xy 285.54372 -282.798593) (xy 285.589736 -282.781141) (xy 285.637955 -282.771297) (xy 285.68713 -282.769316)
			(xy 285.735985 -282.775248) (xy 285.783256 -282.78894) (xy 285.827718 -282.810038) (xy 285.868221 -282.837994)
			(xy 285.903714 -282.872086) (xy 285.933279 -282.91143) (xy 285.95615 -282.955007) (xy 285.971734 -283.001688)
			(xy 285.979629 -283.050265) (xy 285.979958 -283.066643) (xy 286.319052 -283.066643) (xy 286.324416 -283.017287)
			(xy 286.337694 -282.969449) (xy 286.358536 -282.92439) (xy 286.386394 -282.883296) (xy 286.420533 -282.84725)
			(xy 286.460053 -282.817202) (xy 286.503915 -282.793944) (xy 286.550961 -282.778088) (xy 286.599953 -282.770052)
			(xy 286.624776 -282.769564) (xy 286.638959 -282.769744) (xy 286.667199 -282.772414) (xy 286.681164 -282.774898)
			(xy 286.69361 -282.777184) (xy 286.717232 -282.769818) (xy 286.794702 -282.692348) (xy 286.802068 -282.668726)
			(xy 286.799782 -282.65628) (xy 286.797307 -282.642314) (xy 286.794634 -282.614074) (xy 286.794448 -282.599892)
			(xy 286.79497 -282.574637) (xy 286.803283 -282.524815) (xy 286.819684 -282.477041) (xy 286.843725 -282.432618)
			(xy 286.874749 -282.392758) (xy 286.911911 -282.358548) (xy 286.954197 -282.330922) (xy 287.000453 -282.310632)
			(xy 287.049418 -282.298232) (xy 287.099756 -282.294061) (xy 287.150094 -282.298232) (xy 287.199059 -282.310632)
			(xy 287.245315 -282.330922) (xy 287.287601 -282.358548) (xy 287.324763 -282.392758) (xy 287.355787 -282.432618)
			(xy 287.379828 -282.477041) (xy 287.396229 -282.524815) (xy 287.404542 -282.574637) (xy 287.405064 -282.599892)
			(xy 306.743874 -282.599892) (xy 306.747834 -282.550838) (xy 306.759611 -282.503054) (xy 306.778902 -282.457778)
			(xy 306.805205 -282.416182) (xy 306.83784 -282.379345) (xy 306.875961 -282.34822) (xy 306.918582 -282.323613)
			(xy 306.964598 -282.306161) (xy 307.012817 -282.296317) (xy 307.061992 -282.294336) (xy 307.110847 -282.300268)
			(xy 307.158118 -282.31396) (xy 307.20258 -282.335058) (xy 307.243083 -282.363014) (xy 307.278576 -282.397106)
			(xy 307.308141 -282.43645) (xy 307.331012 -282.480027) (xy 307.346596 -282.526708) (xy 307.354491 -282.575285)
			(xy 307.354986 -282.599892) (xy 307.354491 -282.624499) (xy 307.354312 -282.6256) (xy 308.623204 -282.6256)
			(xy 308.623204 -282.574184) (xy 308.631247 -282.523402) (xy 308.647135 -282.474503) (xy 308.670478 -282.428691)
			(xy 308.700699 -282.387095) (xy 308.737055 -282.350739) (xy 308.778651 -282.320518) (xy 308.824463 -282.297175)
			(xy 308.873362 -282.281287) (xy 308.924144 -282.273244) (xy 308.97556 -282.273244) (xy 309.026342 -282.281287)
			(xy 309.075241 -282.297175) (xy 309.121053 -282.320518) (xy 309.162649 -282.350739) (xy 309.199005 -282.387095)
			(xy 309.229226 -282.428691) (xy 309.252569 -282.474503) (xy 309.268457 -282.523402) (xy 309.2765 -282.574184)
			(xy 309.277004 -282.599892) (xy 309.2765 -282.6256) (xy 309.573164 -282.6256) (xy 309.573164 -282.574184)
			(xy 309.581207 -282.523402) (xy 309.597095 -282.474503) (xy 309.620438 -282.428691) (xy 309.650659 -282.387095)
			(xy 309.687015 -282.350739) (xy 309.728611 -282.320518) (xy 309.774423 -282.297175) (xy 309.823322 -282.281287)
			(xy 309.874104 -282.273244) (xy 309.92552 -282.273244) (xy 309.976302 -282.281287) (xy 310.025201 -282.297175)
			(xy 310.071013 -282.320518) (xy 310.112609 -282.350739) (xy 310.148965 -282.387095) (xy 310.179186 -282.428691)
			(xy 310.202529 -282.474503) (xy 310.218417 -282.523402) (xy 310.22646 -282.574184) (xy 310.226964 -282.599892)
			(xy 310.543968 -282.599892) (xy 310.547928 -282.550838) (xy 310.559705 -282.503054) (xy 310.578996 -282.457778)
			(xy 310.605299 -282.416182) (xy 310.637934 -282.379345) (xy 310.676055 -282.34822) (xy 310.718676 -282.323613)
			(xy 310.764692 -282.306161) (xy 310.812911 -282.296317) (xy 310.862086 -282.294336) (xy 310.910941 -282.300268)
			(xy 310.958212 -282.31396) (xy 311.002674 -282.335058) (xy 311.043177 -282.363014) (xy 311.07867 -282.397106)
			(xy 311.108235 -282.43645) (xy 311.131106 -282.480027) (xy 311.14669 -282.526708) (xy 311.154585 -282.575285)
			(xy 311.15508 -282.599892) (xy 311.154585 -282.624499) (xy 311.154406 -282.6256) (xy 311.473084 -282.6256)
			(xy 311.473084 -282.574184) (xy 311.481127 -282.523402) (xy 311.497015 -282.474503) (xy 311.520358 -282.428691)
			(xy 311.550579 -282.387095) (xy 311.586935 -282.350739) (xy 311.628531 -282.320518) (xy 311.674343 -282.297175)
			(xy 311.723242 -282.281287) (xy 311.774024 -282.273244) (xy 311.82544 -282.273244) (xy 311.876222 -282.281287)
			(xy 311.925121 -282.297175) (xy 311.970933 -282.320518) (xy 312.012529 -282.350739) (xy 312.048885 -282.387095)
			(xy 312.079106 -282.428691) (xy 312.102449 -282.474503) (xy 312.118337 -282.523402) (xy 312.12638 -282.574184)
			(xy 312.126884 -282.599892) (xy 312.12638 -282.6256) (xy 312.423044 -282.6256) (xy 312.423044 -282.574184)
			(xy 312.431087 -282.523402) (xy 312.446975 -282.474503) (xy 312.470318 -282.428691) (xy 312.500539 -282.387095)
			(xy 312.536895 -282.350739) (xy 312.578491 -282.320518) (xy 312.624303 -282.297175) (xy 312.673202 -282.281287)
			(xy 312.723984 -282.273244) (xy 312.7754 -282.273244) (xy 312.826182 -282.281287) (xy 312.875081 -282.297175)
			(xy 312.920893 -282.320518) (xy 312.962489 -282.350739) (xy 312.998845 -282.387095) (xy 313.029066 -282.428691)
			(xy 313.052409 -282.474503) (xy 313.068297 -282.523402) (xy 313.07634 -282.574184) (xy 313.076844 -282.599892)
			(xy 313.394102 -282.599892) (xy 313.398062 -282.550838) (xy 313.409839 -282.503054) (xy 313.42913 -282.457778)
			(xy 313.455433 -282.416182) (xy 313.488068 -282.379345) (xy 313.526189 -282.34822) (xy 313.56881 -282.323613)
			(xy 313.614826 -282.306161) (xy 313.663045 -282.296317) (xy 313.71222 -282.294336) (xy 313.761075 -282.300268)
			(xy 313.808346 -282.31396) (xy 313.852808 -282.335058) (xy 313.893311 -282.363014) (xy 313.928804 -282.397106)
			(xy 313.958369 -282.43645) (xy 313.98124 -282.480027) (xy 313.996824 -282.526708) (xy 314.004719 -282.575285)
			(xy 314.005214 -282.599892) (xy 314.344062 -282.599892) (xy 314.348022 -282.550838) (xy 314.359799 -282.503054)
			(xy 314.37909 -282.457778) (xy 314.405393 -282.416182) (xy 314.438028 -282.379345) (xy 314.476149 -282.34822)
			(xy 314.51877 -282.323613) (xy 314.564786 -282.306161) (xy 314.613005 -282.296317) (xy 314.66218 -282.294336)
			(xy 314.711035 -282.300268) (xy 314.758306 -282.31396) (xy 314.802768 -282.335058) (xy 314.843271 -282.363014)
			(xy 314.878764 -282.397106) (xy 314.908329 -282.43645) (xy 314.9312 -282.480027) (xy 314.946784 -282.526708)
			(xy 314.954679 -282.575285) (xy 314.955174 -282.599892) (xy 314.954679 -282.624499) (xy 314.946784 -282.673076)
			(xy 314.9312 -282.719757) (xy 314.908329 -282.763334) (xy 314.878764 -282.802678) (xy 314.843271 -282.83677)
			(xy 314.802768 -282.864726) (xy 314.758306 -282.885824) (xy 314.711035 -282.899516) (xy 314.66218 -282.905448)
			(xy 314.613005 -282.903467) (xy 314.564786 -282.893623) (xy 314.51877 -282.876171) (xy 314.476149 -282.851564)
			(xy 314.438028 -282.820439) (xy 314.405393 -282.783602) (xy 314.37909 -282.742006) (xy 314.359799 -282.69673)
			(xy 314.348022 -282.648946) (xy 314.344062 -282.599892) (xy 314.005214 -282.599892) (xy 314.004719 -282.624499)
			(xy 313.996824 -282.673076) (xy 313.98124 -282.719757) (xy 313.958369 -282.763334) (xy 313.928804 -282.802678)
			(xy 313.893311 -282.83677) (xy 313.852808 -282.864726) (xy 313.808346 -282.885824) (xy 313.761075 -282.899516)
			(xy 313.71222 -282.905448) (xy 313.663045 -282.903467) (xy 313.614826 -282.893623) (xy 313.56881 -282.876171)
			(xy 313.526189 -282.851564) (xy 313.488068 -282.820439) (xy 313.455433 -282.783602) (xy 313.42913 -282.742006)
			(xy 313.409839 -282.69673) (xy 313.398062 -282.648946) (xy 313.394102 -282.599892) (xy 313.076844 -282.599892)
			(xy 313.07634 -282.6256) (xy 313.068297 -282.676382) (xy 313.052409 -282.725281) (xy 313.029066 -282.771093)
			(xy 312.998845 -282.812689) (xy 312.962489 -282.849045) (xy 312.920893 -282.879266) (xy 312.875081 -282.902609)
			(xy 312.826182 -282.918497) (xy 312.7754 -282.92654) (xy 312.723984 -282.92654) (xy 312.673202 -282.918497)
			(xy 312.624303 -282.902609) (xy 312.578491 -282.879266) (xy 312.536895 -282.849045) (xy 312.500539 -282.812689)
			(xy 312.470318 -282.771093) (xy 312.446975 -282.725281) (xy 312.431087 -282.676382) (xy 312.423044 -282.6256)
			(xy 312.12638 -282.6256) (xy 312.118337 -282.676382) (xy 312.102449 -282.725281) (xy 312.079106 -282.771093)
			(xy 312.048885 -282.812689) (xy 312.012529 -282.849045) (xy 311.970933 -282.879266) (xy 311.925121 -282.902609)
			(xy 311.876222 -282.918497) (xy 311.82544 -282.92654) (xy 311.774024 -282.92654) (xy 311.723242 -282.918497)
			(xy 311.674343 -282.902609) (xy 311.628531 -282.879266) (xy 311.586935 -282.849045) (xy 311.550579 -282.812689)
			(xy 311.520358 -282.771093) (xy 311.497015 -282.725281) (xy 311.481127 -282.676382) (xy 311.473084 -282.6256)
			(xy 311.154406 -282.6256) (xy 311.14669 -282.673076) (xy 311.131106 -282.719757) (xy 311.108235 -282.763334)
			(xy 311.07867 -282.802678) (xy 311.043177 -282.83677) (xy 311.002674 -282.864726) (xy 310.958212 -282.885824)
			(xy 310.910941 -282.899516) (xy 310.862086 -282.905448) (xy 310.812911 -282.903467) (xy 310.764692 -282.893623)
			(xy 310.718676 -282.876171) (xy 310.676055 -282.851564) (xy 310.637934 -282.820439) (xy 310.605299 -282.783602)
			(xy 310.578996 -282.742006) (xy 310.559705 -282.69673) (xy 310.547928 -282.648946) (xy 310.543968 -282.599892)
			(xy 310.226964 -282.599892) (xy 310.22646 -282.6256) (xy 310.218417 -282.676382) (xy 310.202529 -282.725281)
			(xy 310.179186 -282.771093) (xy 310.148965 -282.812689) (xy 310.112609 -282.849045) (xy 310.071013 -282.879266)
			(xy 310.025201 -282.902609) (xy 309.976302 -282.918497) (xy 309.92552 -282.92654) (xy 309.874104 -282.92654)
			(xy 309.823322 -282.918497) (xy 309.774423 -282.902609) (xy 309.728611 -282.879266) (xy 309.687015 -282.849045)
			(xy 309.650659 -282.812689) (xy 309.620438 -282.771093) (xy 309.597095 -282.725281) (xy 309.581207 -282.676382)
			(xy 309.573164 -282.6256) (xy 309.2765 -282.6256) (xy 309.268457 -282.676382) (xy 309.252569 -282.725281)
			(xy 309.229226 -282.771093) (xy 309.199005 -282.812689) (xy 309.162649 -282.849045) (xy 309.121053 -282.879266)
			(xy 309.075241 -282.902609) (xy 309.026342 -282.918497) (xy 308.97556 -282.92654) (xy 308.924144 -282.92654)
			(xy 308.873362 -282.918497) (xy 308.824463 -282.902609) (xy 308.778651 -282.879266) (xy 308.737055 -282.849045)
			(xy 308.700699 -282.812689) (xy 308.670478 -282.771093) (xy 308.647135 -282.725281) (xy 308.631247 -282.676382)
			(xy 308.623204 -282.6256) (xy 307.354312 -282.6256) (xy 307.346596 -282.673076) (xy 307.331012 -282.719757)
			(xy 307.308141 -282.763334) (xy 307.278576 -282.802678) (xy 307.243083 -282.83677) (xy 307.20258 -282.864726)
			(xy 307.158118 -282.885824) (xy 307.110847 -282.899516) (xy 307.061992 -282.905448) (xy 307.012817 -282.903467)
			(xy 306.964598 -282.893623) (xy 306.918582 -282.876171) (xy 306.875961 -282.851564) (xy 306.83784 -282.820439)
			(xy 306.805205 -282.783602) (xy 306.778902 -282.742006) (xy 306.759611 -282.69673) (xy 306.747834 -282.648946)
			(xy 306.743874 -282.599892) (xy 287.405064 -282.599892) (xy 287.404887 -282.614075) (xy 287.402215 -282.642315)
			(xy 287.39973 -282.65628) (xy 287.397444 -282.668726) (xy 287.40481 -282.692348) (xy 287.48228 -282.769818)
			(xy 287.505902 -282.777184) (xy 287.518348 -282.774898) (xy 287.532313 -282.772419) (xy 287.560553 -282.769749)
			(xy 287.574736 -282.769564) (xy 287.599554 -282.770117) (xy 287.648535 -282.778153) (xy 287.69557 -282.794007)
			(xy 287.739421 -282.817262) (xy 287.778932 -282.847304) (xy 287.813062 -282.883343) (xy 287.840913 -282.924429)
			(xy 287.861749 -282.96948) (xy 287.875023 -283.017307) (xy 287.880384 -283.066653) (xy 287.879937 -283.074872)
			(xy 288.219146 -283.074872) (xy 288.223106 -283.025818) (xy 288.234883 -282.978034) (xy 288.254174 -282.932758)
			(xy 288.280477 -282.891162) (xy 288.313112 -282.854325) (xy 288.351233 -282.8232) (xy 288.393854 -282.798593)
			(xy 288.43987 -282.781141) (xy 288.488089 -282.771297) (xy 288.537264 -282.769316) (xy 288.586119 -282.775248)
			(xy 288.63339 -282.78894) (xy 288.677852 -282.810038) (xy 288.718355 -282.837994) (xy 288.753848 -282.872086)
			(xy 288.783413 -282.91143) (xy 288.806284 -282.955007) (xy 288.821868 -283.001688) (xy 288.829763 -283.050265)
			(xy 288.830258 -283.074872) (xy 289.169106 -283.074872) (xy 289.173066 -283.025818) (xy 289.184843 -282.978034)
			(xy 289.204134 -282.932758) (xy 289.230437 -282.891162) (xy 289.263072 -282.854325) (xy 289.301193 -282.8232)
			(xy 289.343814 -282.798593) (xy 289.38983 -282.781141) (xy 289.438049 -282.771297) (xy 289.487224 -282.769316)
			(xy 289.536079 -282.775248) (xy 289.58335 -282.78894) (xy 289.627812 -282.810038) (xy 289.668315 -282.837994)
			(xy 289.703808 -282.872086) (xy 289.733373 -282.91143) (xy 289.756244 -282.955007) (xy 289.771828 -283.001688)
			(xy 289.779723 -283.050265) (xy 289.780218 -283.074872) (xy 290.119066 -283.074872) (xy 290.123026 -283.025818)
			(xy 290.134803 -282.978034) (xy 290.154094 -282.932758) (xy 290.180397 -282.891162) (xy 290.213032 -282.854325)
			(xy 290.251153 -282.8232) (xy 290.293774 -282.798593) (xy 290.33979 -282.781141) (xy 290.388009 -282.771297)
			(xy 290.437184 -282.769316) (xy 290.486039 -282.775248) (xy 290.53331 -282.78894) (xy 290.577772 -282.810038)
			(xy 290.618275 -282.837994) (xy 290.653768 -282.872086) (xy 290.683333 -282.91143) (xy 290.706204 -282.955007)
			(xy 290.721788 -283.001688) (xy 290.729683 -283.050265) (xy 290.730178 -283.074872) (xy 292.018986 -283.074872)
			(xy 292.022946 -283.025818) (xy 292.034723 -282.978034) (xy 292.054014 -282.932758) (xy 292.080317 -282.891162)
			(xy 292.112952 -282.854325) (xy 292.151073 -282.8232) (xy 292.193694 -282.798593) (xy 292.23971 -282.781141)
			(xy 292.287929 -282.771297) (xy 292.337104 -282.769316) (xy 292.385959 -282.775248) (xy 292.43323 -282.78894)
			(xy 292.477692 -282.810038) (xy 292.518195 -282.837994) (xy 292.553688 -282.872086) (xy 292.583253 -282.91143)
			(xy 292.606124 -282.955007) (xy 292.621708 -283.001688) (xy 292.629603 -283.050265) (xy 292.630098 -283.074872)
			(xy 292.968946 -283.074872) (xy 292.972906 -283.025818) (xy 292.984683 -282.978034) (xy 293.003974 -282.932758)
			(xy 293.030277 -282.891162) (xy 293.062912 -282.854325) (xy 293.101033 -282.8232) (xy 293.143654 -282.798593)
			(xy 293.18967 -282.781141) (xy 293.237889 -282.771297) (xy 293.287064 -282.769316) (xy 293.335919 -282.775248)
			(xy 293.38319 -282.78894) (xy 293.427652 -282.810038) (xy 293.468155 -282.837994) (xy 293.503648 -282.872086)
			(xy 293.533213 -282.91143) (xy 293.556084 -282.955007) (xy 293.571668 -283.001688) (xy 293.579563 -283.050265)
			(xy 293.580058 -283.074872) (xy 293.918906 -283.074872) (xy 293.922866 -283.025818) (xy 293.934643 -282.978034)
			(xy 293.953934 -282.932758) (xy 293.980237 -282.891162) (xy 294.012872 -282.854325) (xy 294.050993 -282.8232)
			(xy 294.093614 -282.798593) (xy 294.13963 -282.781141) (xy 294.187849 -282.771297) (xy 294.237024 -282.769316)
			(xy 294.285879 -282.775248) (xy 294.33315 -282.78894) (xy 294.377612 -282.810038) (xy 294.418115 -282.837994)
			(xy 294.453608 -282.872086) (xy 294.483173 -282.91143) (xy 294.506044 -282.955007) (xy 294.521628 -283.001688)
			(xy 294.529523 -283.050265) (xy 294.530018 -283.074872) (xy 294.86912 -283.074872) (xy 294.87308 -283.025818)
			(xy 294.884857 -282.978034) (xy 294.904148 -282.932758) (xy 294.930451 -282.891162) (xy 294.963086 -282.854325)
			(xy 295.001207 -282.8232) (xy 295.043828 -282.798593) (xy 295.089844 -282.781141) (xy 295.138063 -282.771297)
			(xy 295.187238 -282.769316) (xy 295.236093 -282.775248) (xy 295.283364 -282.78894) (xy 295.327826 -282.810038)
			(xy 295.368329 -282.837994) (xy 295.403822 -282.872086) (xy 295.433387 -282.91143) (xy 295.456258 -282.955007)
			(xy 295.471842 -283.001688) (xy 295.479737 -283.050265) (xy 295.480232 -283.074872) (xy 295.81908 -283.074872)
			(xy 295.82304 -283.025818) (xy 295.834817 -282.978034) (xy 295.854108 -282.932758) (xy 295.880411 -282.891162)
			(xy 295.913046 -282.854325) (xy 295.951167 -282.8232) (xy 295.993788 -282.798593) (xy 296.039804 -282.781141)
			(xy 296.088023 -282.771297) (xy 296.137198 -282.769316) (xy 296.186053 -282.775248) (xy 296.233324 -282.78894)
			(xy 296.277786 -282.810038) (xy 296.318289 -282.837994) (xy 296.353782 -282.872086) (xy 296.383347 -282.91143)
			(xy 296.406218 -282.955007) (xy 296.421802 -283.001688) (xy 296.429697 -283.050265) (xy 296.430192 -283.074872)
			(xy 296.76904 -283.074872) (xy 296.773 -283.025818) (xy 296.784777 -282.978034) (xy 296.804068 -282.932758)
			(xy 296.830371 -282.891162) (xy 296.863006 -282.854325) (xy 296.901127 -282.8232) (xy 296.943748 -282.798593)
			(xy 296.989764 -282.781141) (xy 297.037983 -282.771297) (xy 297.087158 -282.769316) (xy 297.136013 -282.775248)
			(xy 297.183284 -282.78894) (xy 297.227746 -282.810038) (xy 297.268249 -282.837994) (xy 297.303742 -282.872086)
			(xy 297.333307 -282.91143) (xy 297.356178 -282.955007) (xy 297.371762 -283.001688) (xy 297.379657 -283.050265)
			(xy 297.380152 -283.074872) (xy 297.719 -283.074872) (xy 297.72296 -283.025818) (xy 297.734737 -282.978034)
			(xy 297.754028 -282.932758) (xy 297.780331 -282.891162) (xy 297.812966 -282.854325) (xy 297.851087 -282.8232)
			(xy 297.893708 -282.798593) (xy 297.939724 -282.781141) (xy 297.987943 -282.771297) (xy 298.037118 -282.769316)
			(xy 298.085973 -282.775248) (xy 298.133244 -282.78894) (xy 298.177706 -282.810038) (xy 298.218209 -282.837994)
			(xy 298.253702 -282.872086) (xy 298.283267 -282.91143) (xy 298.306138 -282.955007) (xy 298.321722 -283.001688)
			(xy 298.329617 -283.050265) (xy 298.330112 -283.074872) (xy 298.66896 -283.074872) (xy 298.67292 -283.025818)
			(xy 298.684697 -282.978034) (xy 298.703988 -282.932758) (xy 298.730291 -282.891162) (xy 298.762926 -282.854325)
			(xy 298.801047 -282.8232) (xy 298.843668 -282.798593) (xy 298.889684 -282.781141) (xy 298.937903 -282.771297)
			(xy 298.987078 -282.769316) (xy 299.035933 -282.775248) (xy 299.083204 -282.78894) (xy 299.127666 -282.810038)
			(xy 299.168169 -282.837994) (xy 299.203662 -282.872086) (xy 299.233227 -282.91143) (xy 299.256098 -282.955007)
			(xy 299.271682 -283.001688) (xy 299.279577 -283.050265) (xy 299.280072 -283.074872) (xy 300.56888 -283.074872)
			(xy 300.57284 -283.025818) (xy 300.584617 -282.978034) (xy 300.603908 -282.932758) (xy 300.630211 -282.891162)
			(xy 300.662846 -282.854325) (xy 300.700967 -282.8232) (xy 300.743588 -282.798593) (xy 300.789604 -282.781141)
			(xy 300.837823 -282.771297) (xy 300.886998 -282.769316) (xy 300.935853 -282.775248) (xy 300.983124 -282.78894)
			(xy 301.027586 -282.810038) (xy 301.068089 -282.837994) (xy 301.103582 -282.872086) (xy 301.133147 -282.91143)
			(xy 301.156018 -282.955007) (xy 301.171602 -283.001688) (xy 301.179497 -283.050265) (xy 301.179992 -283.074872)
			(xy 301.519094 -283.074872) (xy 301.523054 -283.025818) (xy 301.534831 -282.978034) (xy 301.554122 -282.932758)
			(xy 301.580425 -282.891162) (xy 301.61306 -282.854325) (xy 301.651181 -282.8232) (xy 301.693802 -282.798593)
			(xy 301.739818 -282.781141) (xy 301.788037 -282.771297) (xy 301.837212 -282.769316) (xy 301.886067 -282.775248)
			(xy 301.933338 -282.78894) (xy 301.9778 -282.810038) (xy 302.018303 -282.837994) (xy 302.053796 -282.872086)
			(xy 302.083361 -282.91143) (xy 302.106232 -282.955007) (xy 302.121816 -283.001688) (xy 302.129711 -283.050265)
			(xy 302.130206 -283.074872) (xy 302.469054 -283.074872) (xy 302.473014 -283.025818) (xy 302.484791 -282.978034)
			(xy 302.504082 -282.932758) (xy 302.530385 -282.891162) (xy 302.56302 -282.854325) (xy 302.601141 -282.8232)
			(xy 302.643762 -282.798593) (xy 302.689778 -282.781141) (xy 302.737997 -282.771297) (xy 302.787172 -282.769316)
			(xy 302.836027 -282.775248) (xy 302.883298 -282.78894) (xy 302.92776 -282.810038) (xy 302.968263 -282.837994)
			(xy 303.003756 -282.872086) (xy 303.033321 -282.91143) (xy 303.056192 -282.955007) (xy 303.071776 -283.001688)
			(xy 303.079671 -283.050265) (xy 303.080166 -283.074872) (xy 303.419014 -283.074872) (xy 303.422974 -283.025818)
			(xy 303.434751 -282.978034) (xy 303.454042 -282.932758) (xy 303.480345 -282.891162) (xy 303.51298 -282.854325)
			(xy 303.551101 -282.8232) (xy 303.593722 -282.798593) (xy 303.639738 -282.781141) (xy 303.687957 -282.771297)
			(xy 303.737132 -282.769316) (xy 303.785987 -282.775248) (xy 303.833258 -282.78894) (xy 303.87772 -282.810038)
			(xy 303.918223 -282.837994) (xy 303.953716 -282.872086) (xy 303.983281 -282.91143) (xy 304.006152 -282.955007)
			(xy 304.021736 -283.001688) (xy 304.029631 -283.050265) (xy 304.030126 -283.074872) (xy 304.368974 -283.074872)
			(xy 304.372934 -283.025818) (xy 304.384711 -282.978034) (xy 304.404002 -282.932758) (xy 304.430305 -282.891162)
			(xy 304.46294 -282.854325) (xy 304.501061 -282.8232) (xy 304.543682 -282.798593) (xy 304.589698 -282.781141)
			(xy 304.637917 -282.771297) (xy 304.687092 -282.769316) (xy 304.735947 -282.775248) (xy 304.783218 -282.78894)
			(xy 304.82768 -282.810038) (xy 304.868183 -282.837994) (xy 304.903676 -282.872086) (xy 304.933241 -282.91143)
			(xy 304.956112 -282.955007) (xy 304.971696 -283.001688) (xy 304.979591 -283.050265) (xy 304.980086 -283.074872)
			(xy 304.979591 -283.099479) (xy 304.971696 -283.148056) (xy 304.956112 -283.194737) (xy 304.933241 -283.238314)
			(xy 304.903676 -283.277658) (xy 304.868183 -283.31175) (xy 304.82768 -283.339706) (xy 304.783218 -283.360804)
			(xy 304.735947 -283.374496) (xy 304.687092 -283.380428) (xy 304.637917 -283.378447) (xy 304.589698 -283.368603)
			(xy 304.543682 -283.351151) (xy 304.501061 -283.326544) (xy 304.46294 -283.295419) (xy 304.430305 -283.258582)
			(xy 304.404002 -283.216986) (xy 304.384711 -283.17171) (xy 304.372934 -283.123926) (xy 304.368974 -283.074872)
			(xy 304.030126 -283.074872) (xy 304.029631 -283.099479) (xy 304.021736 -283.148056) (xy 304.006152 -283.194737)
			(xy 303.983281 -283.238314) (xy 303.953716 -283.277658) (xy 303.918223 -283.31175) (xy 303.87772 -283.339706)
			(xy 303.833258 -283.360804) (xy 303.785987 -283.374496) (xy 303.737132 -283.380428) (xy 303.687957 -283.378447)
			(xy 303.639738 -283.368603) (xy 303.593722 -283.351151) (xy 303.551101 -283.326544) (xy 303.51298 -283.295419)
			(xy 303.480345 -283.258582) (xy 303.454042 -283.216986) (xy 303.434751 -283.17171) (xy 303.422974 -283.123926)
			(xy 303.419014 -283.074872) (xy 303.080166 -283.074872) (xy 303.079671 -283.099479) (xy 303.071776 -283.148056)
			(xy 303.056192 -283.194737) (xy 303.033321 -283.238314) (xy 303.003756 -283.277658) (xy 302.968263 -283.31175)
			(xy 302.92776 -283.339706) (xy 302.883298 -283.360804) (xy 302.836027 -283.374496) (xy 302.787172 -283.380428)
			(xy 302.737997 -283.378447) (xy 302.689778 -283.368603) (xy 302.643762 -283.351151) (xy 302.601141 -283.326544)
			(xy 302.56302 -283.295419) (xy 302.530385 -283.258582) (xy 302.504082 -283.216986) (xy 302.484791 -283.17171)
			(xy 302.473014 -283.123926) (xy 302.469054 -283.074872) (xy 302.130206 -283.074872) (xy 302.129711 -283.099479)
			(xy 302.121816 -283.148056) (xy 302.106232 -283.194737) (xy 302.083361 -283.238314) (xy 302.053796 -283.277658)
			(xy 302.018303 -283.31175) (xy 301.9778 -283.339706) (xy 301.933338 -283.360804) (xy 301.886067 -283.374496)
			(xy 301.837212 -283.380428) (xy 301.788037 -283.378447) (xy 301.739818 -283.368603) (xy 301.693802 -283.351151)
			(xy 301.651181 -283.326544) (xy 301.61306 -283.295419) (xy 301.580425 -283.258582) (xy 301.554122 -283.216986)
			(xy 301.534831 -283.17171) (xy 301.523054 -283.123926) (xy 301.519094 -283.074872) (xy 301.179992 -283.074872)
			(xy 301.179497 -283.099479) (xy 301.171602 -283.148056) (xy 301.156018 -283.194737) (xy 301.133147 -283.238314)
			(xy 301.103582 -283.277658) (xy 301.068089 -283.31175) (xy 301.027586 -283.339706) (xy 300.983124 -283.360804)
			(xy 300.935853 -283.374496) (xy 300.886998 -283.380428) (xy 300.837823 -283.378447) (xy 300.789604 -283.368603)
			(xy 300.743588 -283.351151) (xy 300.700967 -283.326544) (xy 300.662846 -283.295419) (xy 300.630211 -283.258582)
			(xy 300.603908 -283.216986) (xy 300.584617 -283.17171) (xy 300.57284 -283.123926) (xy 300.56888 -283.074872)
			(xy 299.280072 -283.074872) (xy 299.279577 -283.099479) (xy 299.271682 -283.148056) (xy 299.256098 -283.194737)
			(xy 299.233227 -283.238314) (xy 299.203662 -283.277658) (xy 299.168169 -283.31175) (xy 299.127666 -283.339706)
			(xy 299.083204 -283.360804) (xy 299.035933 -283.374496) (xy 298.987078 -283.380428) (xy 298.937903 -283.378447)
			(xy 298.889684 -283.368603) (xy 298.843668 -283.351151) (xy 298.801047 -283.326544) (xy 298.762926 -283.295419)
			(xy 298.730291 -283.258582) (xy 298.703988 -283.216986) (xy 298.684697 -283.17171) (xy 298.67292 -283.123926)
			(xy 298.66896 -283.074872) (xy 298.330112 -283.074872) (xy 298.329617 -283.099479) (xy 298.321722 -283.148056)
			(xy 298.306138 -283.194737) (xy 298.283267 -283.238314) (xy 298.253702 -283.277658) (xy 298.218209 -283.31175)
			(xy 298.177706 -283.339706) (xy 298.133244 -283.360804) (xy 298.085973 -283.374496) (xy 298.037118 -283.380428)
			(xy 297.987943 -283.378447) (xy 297.939724 -283.368603) (xy 297.893708 -283.351151) (xy 297.851087 -283.326544)
			(xy 297.812966 -283.295419) (xy 297.780331 -283.258582) (xy 297.754028 -283.216986) (xy 297.734737 -283.17171)
			(xy 297.72296 -283.123926) (xy 297.719 -283.074872) (xy 297.380152 -283.074872) (xy 297.379657 -283.099479)
			(xy 297.371762 -283.148056) (xy 297.356178 -283.194737) (xy 297.333307 -283.238314) (xy 297.303742 -283.277658)
			(xy 297.268249 -283.31175) (xy 297.227746 -283.339706) (xy 297.183284 -283.360804) (xy 297.136013 -283.374496)
			(xy 297.087158 -283.380428) (xy 297.037983 -283.378447) (xy 296.989764 -283.368603) (xy 296.943748 -283.351151)
			(xy 296.901127 -283.326544) (xy 296.863006 -283.295419) (xy 296.830371 -283.258582) (xy 296.804068 -283.216986)
			(xy 296.784777 -283.17171) (xy 296.773 -283.123926) (xy 296.76904 -283.074872) (xy 296.430192 -283.074872)
			(xy 296.429697 -283.099479) (xy 296.421802 -283.148056) (xy 296.406218 -283.194737) (xy 296.383347 -283.238314)
			(xy 296.353782 -283.277658) (xy 296.318289 -283.31175) (xy 296.277786 -283.339706) (xy 296.233324 -283.360804)
			(xy 296.186053 -283.374496) (xy 296.137198 -283.380428) (xy 296.088023 -283.378447) (xy 296.039804 -283.368603)
			(xy 295.993788 -283.351151) (xy 295.951167 -283.326544) (xy 295.913046 -283.295419) (xy 295.880411 -283.258582)
			(xy 295.854108 -283.216986) (xy 295.834817 -283.17171) (xy 295.82304 -283.123926) (xy 295.81908 -283.074872)
			(xy 295.480232 -283.074872) (xy 295.479737 -283.099479) (xy 295.471842 -283.148056) (xy 295.456258 -283.194737)
			(xy 295.433387 -283.238314) (xy 295.403822 -283.277658) (xy 295.368329 -283.31175) (xy 295.327826 -283.339706)
			(xy 295.283364 -283.360804) (xy 295.236093 -283.374496) (xy 295.187238 -283.380428) (xy 295.138063 -283.378447)
			(xy 295.089844 -283.368603) (xy 295.043828 -283.351151) (xy 295.001207 -283.326544) (xy 294.963086 -283.295419)
			(xy 294.930451 -283.258582) (xy 294.904148 -283.216986) (xy 294.884857 -283.17171) (xy 294.87308 -283.123926)
			(xy 294.86912 -283.074872) (xy 294.530018 -283.074872) (xy 294.529523 -283.099479) (xy 294.521628 -283.148056)
			(xy 294.506044 -283.194737) (xy 294.483173 -283.238314) (xy 294.453608 -283.277658) (xy 294.418115 -283.31175)
			(xy 294.377612 -283.339706) (xy 294.33315 -283.360804) (xy 294.285879 -283.374496) (xy 294.237024 -283.380428)
			(xy 294.187849 -283.378447) (xy 294.13963 -283.368603) (xy 294.093614 -283.351151) (xy 294.050993 -283.326544)
			(xy 294.012872 -283.295419) (xy 293.980237 -283.258582) (xy 293.953934 -283.216986) (xy 293.934643 -283.17171)
			(xy 293.922866 -283.123926) (xy 293.918906 -283.074872) (xy 293.580058 -283.074872) (xy 293.579563 -283.099479)
			(xy 293.571668 -283.148056) (xy 293.556084 -283.194737) (xy 293.533213 -283.238314) (xy 293.503648 -283.277658)
			(xy 293.468155 -283.31175) (xy 293.427652 -283.339706) (xy 293.38319 -283.360804) (xy 293.335919 -283.374496)
			(xy 293.287064 -283.380428) (xy 293.237889 -283.378447) (xy 293.18967 -283.368603) (xy 293.143654 -283.351151)
			(xy 293.101033 -283.326544) (xy 293.062912 -283.295419) (xy 293.030277 -283.258582) (xy 293.003974 -283.216986)
			(xy 292.984683 -283.17171) (xy 292.972906 -283.123926) (xy 292.968946 -283.074872) (xy 292.630098 -283.074872)
			(xy 292.629603 -283.099479) (xy 292.621708 -283.148056) (xy 292.606124 -283.194737) (xy 292.583253 -283.238314)
			(xy 292.553688 -283.277658) (xy 292.518195 -283.31175) (xy 292.477692 -283.339706) (xy 292.43323 -283.360804)
			(xy 292.385959 -283.374496) (xy 292.337104 -283.380428) (xy 292.287929 -283.378447) (xy 292.23971 -283.368603)
			(xy 292.193694 -283.351151) (xy 292.151073 -283.326544) (xy 292.112952 -283.295419) (xy 292.080317 -283.258582)
			(xy 292.054014 -283.216986) (xy 292.034723 -283.17171) (xy 292.022946 -283.123926) (xy 292.018986 -283.074872)
			(xy 290.730178 -283.074872) (xy 290.729683 -283.099479) (xy 290.721788 -283.148056) (xy 290.706204 -283.194737)
			(xy 290.683333 -283.238314) (xy 290.653768 -283.277658) (xy 290.618275 -283.31175) (xy 290.577772 -283.339706)
			(xy 290.53331 -283.360804) (xy 290.486039 -283.374496) (xy 290.437184 -283.380428) (xy 290.388009 -283.378447)
			(xy 290.33979 -283.368603) (xy 290.293774 -283.351151) (xy 290.251153 -283.326544) (xy 290.213032 -283.295419)
			(xy 290.180397 -283.258582) (xy 290.154094 -283.216986) (xy 290.134803 -283.17171) (xy 290.123026 -283.123926)
			(xy 290.119066 -283.074872) (xy 289.780218 -283.074872) (xy 289.779723 -283.099479) (xy 289.771828 -283.148056)
			(xy 289.756244 -283.194737) (xy 289.733373 -283.238314) (xy 289.703808 -283.277658) (xy 289.668315 -283.31175)
			(xy 289.627812 -283.339706) (xy 289.58335 -283.360804) (xy 289.536079 -283.374496) (xy 289.487224 -283.380428)
			(xy 289.438049 -283.378447) (xy 289.38983 -283.368603) (xy 289.343814 -283.351151) (xy 289.301193 -283.326544)
			(xy 289.263072 -283.295419) (xy 289.230437 -283.258582) (xy 289.204134 -283.216986) (xy 289.184843 -283.17171)
			(xy 289.173066 -283.123926) (xy 289.169106 -283.074872) (xy 288.830258 -283.074872) (xy 288.829763 -283.099479)
			(xy 288.821868 -283.148056) (xy 288.806284 -283.194737) (xy 288.783413 -283.238314) (xy 288.753848 -283.277658)
			(xy 288.718355 -283.31175) (xy 288.677852 -283.339706) (xy 288.63339 -283.360804) (xy 288.586119 -283.374496)
			(xy 288.537264 -283.380428) (xy 288.488089 -283.378447) (xy 288.43987 -283.368603) (xy 288.393854 -283.351151)
			(xy 288.351233 -283.326544) (xy 288.313112 -283.295419) (xy 288.280477 -283.258582) (xy 288.254174 -283.216986)
			(xy 288.234883 -283.17171) (xy 288.223106 -283.123926) (xy 288.219146 -283.074872) (xy 287.879937 -283.074872)
			(xy 287.877691 -283.116215) (xy 287.867016 -283.164689) (xy 287.848639 -283.210798) (xy 287.823044 -283.253325)
			(xy 287.790907 -283.291152) (xy 287.753073 -283.323282) (xy 287.71054 -283.348867) (xy 287.664428 -283.367235)
			(xy 287.615952 -283.3779) (xy 287.566389 -283.380582) (xy 287.517045 -283.375211) (xy 287.469219 -283.361927)
			(xy 287.424173 -283.341081) (xy 287.383093 -283.313222) (xy 287.347061 -283.279084) (xy 287.317027 -283.239567)
			(xy 287.293781 -283.195711) (xy 287.277937 -283.148672) (xy 287.269911 -283.09969) (xy 287.269428 -283.074872)
			(xy 287.2696 -283.060689) (xy 287.272275 -283.032449) (xy 287.274762 -283.018484) (xy 287.277048 -283.006038)
			(xy 287.269682 -282.982416) (xy 287.192212 -282.904946) (xy 287.16859 -282.89758) (xy 287.156144 -282.899866)
			(xy 287.142179 -282.902346) (xy 287.113939 -282.905015) (xy 287.099756 -282.9052) (xy 287.085573 -282.905016)
			(xy 287.057333 -282.902349) (xy 287.043368 -282.899866) (xy 287.030922 -282.89758) (xy 287.0073 -282.904946)
			(xy 286.92983 -282.982416) (xy 286.922464 -283.006038) (xy 286.92475 -283.018484) (xy 286.927234 -283.032449)
			(xy 286.929901 -283.060689) (xy 286.930084 -283.074872) (xy 286.929652 -283.099695) (xy 286.921625 -283.148688)
			(xy 286.905777 -283.195737) (xy 286.882526 -283.239603) (xy 286.852485 -283.279128) (xy 286.816445 -283.313273)
			(xy 286.775356 -283.341138) (xy 286.7303 -283.361988) (xy 286.682464 -283.375274) (xy 286.633109 -283.380646)
			(xy 286.583535 -283.377963) (xy 286.535049 -283.367294) (xy 286.488927 -283.348922) (xy 286.446385 -283.323331)
			(xy 286.408543 -283.291193) (xy 286.3764 -283.253358) (xy 286.350801 -283.21082) (xy 286.332421 -283.164701)
			(xy 286.321744 -283.116216) (xy 286.319052 -283.066643) (xy 285.979958 -283.066643) (xy 285.980124 -283.074872)
			(xy 285.979629 -283.099479) (xy 285.971734 -283.148056) (xy 285.95615 -283.194737) (xy 285.933279 -283.238314)
			(xy 285.903714 -283.277658) (xy 285.868221 -283.31175) (xy 285.827718 -283.339706) (xy 285.783256 -283.360804)
			(xy 285.735985 -283.374496) (xy 285.68713 -283.380428) (xy 285.637955 -283.378447) (xy 285.589736 -283.368603)
			(xy 285.54372 -283.351151) (xy 285.501099 -283.326544) (xy 285.462978 -283.295419) (xy 285.430343 -283.258582)
			(xy 285.40404 -283.216986) (xy 285.384749 -283.17171) (xy 285.372972 -283.123926) (xy 285.369012 -283.074872)
			(xy 285.030164 -283.074872) (xy 285.029669 -283.099479) (xy 285.021774 -283.148056) (xy 285.00619 -283.194737)
			(xy 284.983319 -283.238314) (xy 284.953754 -283.277658) (xy 284.918261 -283.31175) (xy 284.877758 -283.339706)
			(xy 284.833296 -283.360804) (xy 284.786025 -283.374496) (xy 284.73717 -283.380428) (xy 284.687995 -283.378447)
			(xy 284.639776 -283.368603) (xy 284.59376 -283.351151) (xy 284.551139 -283.326544) (xy 284.513018 -283.295419)
			(xy 284.480383 -283.258582) (xy 284.45408 -283.216986) (xy 284.434789 -283.17171) (xy 284.423012 -283.123926)
			(xy 284.419052 -283.074872) (xy 284.080204 -283.074872) (xy 284.079709 -283.099479) (xy 284.071814 -283.148056)
			(xy 284.05623 -283.194737) (xy 284.033359 -283.238314) (xy 284.003794 -283.277658) (xy 283.968301 -283.31175)
			(xy 283.927798 -283.339706) (xy 283.883336 -283.360804) (xy 283.836065 -283.374496) (xy 283.78721 -283.380428)
			(xy 283.738035 -283.378447) (xy 283.689816 -283.368603) (xy 283.6438 -283.351151) (xy 283.601179 -283.326544)
			(xy 283.563058 -283.295419) (xy 283.530423 -283.258582) (xy 283.50412 -283.216986) (xy 283.484829 -283.17171)
			(xy 283.473052 -283.123926) (xy 283.469092 -283.074872) (xy 283.130244 -283.074872) (xy 283.129749 -283.099479)
			(xy 283.121854 -283.148056) (xy 283.10627 -283.194737) (xy 283.083399 -283.238314) (xy 283.053834 -283.277658)
			(xy 283.018341 -283.31175) (xy 282.977838 -283.339706) (xy 282.933376 -283.360804) (xy 282.886105 -283.374496)
			(xy 282.83725 -283.380428) (xy 282.788075 -283.378447) (xy 282.739856 -283.368603) (xy 282.69384 -283.351151)
			(xy 282.651219 -283.326544) (xy 282.613098 -283.295419) (xy 282.580463 -283.258582) (xy 282.55416 -283.216986)
			(xy 282.534869 -283.17171) (xy 282.523092 -283.123926) (xy 282.519132 -283.074872) (xy 282.180557 -283.074872)
			(xy 282.180559 -283.0749) (xy 282.176388 -283.12524) (xy 282.163988 -283.174208) (xy 282.143698 -283.220467)
			(xy 282.116071 -283.262755) (xy 282.081861 -283.29992) (xy 282.042001 -283.330947) (xy 281.997577 -283.354991)
			(xy 281.949802 -283.371395) (xy 281.899978 -283.379713) (xy 281.874722 -283.38018) (xy 281.844648 -283.379487)
			(xy 281.785662 -283.36772) (xy 281.757628 -283.356812) (xy 281.745436 -283.351732) (xy 281.720544 -283.354272)
			(xy 281.639518 -283.408374) (xy 281.629457 -283.415892) (xy 281.617599 -283.437998) (xy 281.616912 -283.450538)
			(xy 281.616912 -283.549852) (xy 305.793914 -283.549852) (xy 305.797874 -283.500798) (xy 305.809651 -283.453014)
			(xy 305.828942 -283.407738) (xy 305.855245 -283.366142) (xy 305.88788 -283.329305) (xy 305.926001 -283.29818)
			(xy 305.968622 -283.273573) (xy 306.014638 -283.256121) (xy 306.062857 -283.246277) (xy 306.112032 -283.244296)
			(xy 306.160887 -283.250228) (xy 306.208158 -283.26392) (xy 306.25262 -283.285018) (xy 306.293123 -283.312974)
			(xy 306.328616 -283.347066) (xy 306.358181 -283.38641) (xy 306.381052 -283.429987) (xy 306.396636 -283.476668)
			(xy 306.404531 -283.525245) (xy 306.405026 -283.549852) (xy 306.404531 -283.574459) (xy 306.404352 -283.57556)
			(xy 306.72303 -283.57556) (xy 306.72303 -283.524144) (xy 306.731073 -283.473362) (xy 306.746961 -283.424463)
			(xy 306.770304 -283.378651) (xy 306.800525 -283.337055) (xy 306.836881 -283.300699) (xy 306.878477 -283.270478)
			(xy 306.924289 -283.247135) (xy 306.973188 -283.231247) (xy 307.02397 -283.223204) (xy 307.075386 -283.223204)
			(xy 307.126168 -283.231247) (xy 307.175067 -283.247135) (xy 307.220879 -283.270478) (xy 307.262475 -283.300699)
			(xy 307.298831 -283.337055) (xy 307.329052 -283.378651) (xy 307.352395 -283.424463) (xy 307.368283 -283.473362)
			(xy 307.376326 -283.524144) (xy 307.37683 -283.549852) (xy 307.376326 -283.57556) (xy 307.673244 -283.57556)
			(xy 307.673244 -283.524144) (xy 307.681287 -283.473362) (xy 307.697175 -283.424463) (xy 307.720518 -283.378651)
			(xy 307.750739 -283.337055) (xy 307.787095 -283.300699) (xy 307.828691 -283.270478) (xy 307.874503 -283.247135)
			(xy 307.923402 -283.231247) (xy 307.974184 -283.223204) (xy 308.0256 -283.223204) (xy 308.076382 -283.231247)
			(xy 308.125281 -283.247135) (xy 308.171093 -283.270478) (xy 308.212689 -283.300699) (xy 308.249045 -283.337055)
			(xy 308.279266 -283.378651) (xy 308.302609 -283.424463) (xy 308.318497 -283.473362) (xy 308.32654 -283.524144)
			(xy 308.327044 -283.549852) (xy 308.644048 -283.549852) (xy 308.648008 -283.500798) (xy 308.659785 -283.453014)
			(xy 308.679076 -283.407738) (xy 308.705379 -283.366142) (xy 308.738014 -283.329305) (xy 308.776135 -283.29818)
			(xy 308.818756 -283.273573) (xy 308.864772 -283.256121) (xy 308.912991 -283.246277) (xy 308.962166 -283.244296)
			(xy 309.011021 -283.250228) (xy 309.058292 -283.26392) (xy 309.102754 -283.285018) (xy 309.143257 -283.312974)
			(xy 309.17875 -283.347066) (xy 309.208315 -283.38641) (xy 309.231186 -283.429987) (xy 309.24677 -283.476668)
			(xy 309.254665 -283.525245) (xy 309.25516 -283.549852) (xy 309.594008 -283.549852) (xy 309.597968 -283.500798)
			(xy 309.609745 -283.453014) (xy 309.629036 -283.407738) (xy 309.655339 -283.366142) (xy 309.687974 -283.329305)
			(xy 309.726095 -283.29818) (xy 309.768716 -283.273573) (xy 309.814732 -283.256121) (xy 309.862951 -283.246277)
			(xy 309.912126 -283.244296) (xy 309.960981 -283.250228) (xy 310.008252 -283.26392) (xy 310.052714 -283.285018)
			(xy 310.093217 -283.312974) (xy 310.12871 -283.347066) (xy 310.158275 -283.38641) (xy 310.181146 -283.429987)
			(xy 310.19673 -283.476668) (xy 310.204625 -283.525245) (xy 310.20512 -283.549852) (xy 310.543968 -283.549852)
			(xy 310.547928 -283.500798) (xy 310.559705 -283.453014) (xy 310.578996 -283.407738) (xy 310.605299 -283.366142)
			(xy 310.637934 -283.329305) (xy 310.676055 -283.29818) (xy 310.718676 -283.273573) (xy 310.764692 -283.256121)
			(xy 310.812911 -283.246277) (xy 310.862086 -283.244296) (xy 310.910941 -283.250228) (xy 310.958212 -283.26392)
			(xy 311.002674 -283.285018) (xy 311.043177 -283.312974) (xy 311.07867 -283.347066) (xy 311.108235 -283.38641)
			(xy 311.131106 -283.429987) (xy 311.14669 -283.476668) (xy 311.154585 -283.525245) (xy 311.15508 -283.549852)
			(xy 311.493928 -283.549852) (xy 311.497888 -283.500798) (xy 311.509665 -283.453014) (xy 311.528956 -283.407738)
			(xy 311.555259 -283.366142) (xy 311.587894 -283.329305) (xy 311.626015 -283.29818) (xy 311.668636 -283.273573)
			(xy 311.714652 -283.256121) (xy 311.762871 -283.246277) (xy 311.812046 -283.244296) (xy 311.860901 -283.250228)
			(xy 311.908172 -283.26392) (xy 311.952634 -283.285018) (xy 311.993137 -283.312974) (xy 312.02863 -283.347066)
			(xy 312.058195 -283.38641) (xy 312.081066 -283.429987) (xy 312.09665 -283.476668) (xy 312.104545 -283.525245)
			(xy 312.10504 -283.549852) (xy 312.443888 -283.549852) (xy 312.447848 -283.500798) (xy 312.459625 -283.453014)
			(xy 312.478916 -283.407738) (xy 312.505219 -283.366142) (xy 312.537854 -283.329305) (xy 312.575975 -283.29818)
			(xy 312.618596 -283.273573) (xy 312.664612 -283.256121) (xy 312.712831 -283.246277) (xy 312.762006 -283.244296)
			(xy 312.810861 -283.250228) (xy 312.858132 -283.26392) (xy 312.902594 -283.285018) (xy 312.943097 -283.312974)
			(xy 312.97859 -283.347066) (xy 313.008155 -283.38641) (xy 313.031026 -283.429987) (xy 313.04661 -283.476668)
			(xy 313.054505 -283.525245) (xy 313.055 -283.549852) (xy 313.054505 -283.574459) (xy 313.054326 -283.57556)
			(xy 313.373258 -283.57556) (xy 313.373258 -283.524144) (xy 313.381301 -283.473362) (xy 313.397189 -283.424463)
			(xy 313.420532 -283.378651) (xy 313.450753 -283.337055) (xy 313.487109 -283.300699) (xy 313.528705 -283.270478)
			(xy 313.574517 -283.247135) (xy 313.623416 -283.231247) (xy 313.674198 -283.223204) (xy 313.725614 -283.223204)
			(xy 313.776396 -283.231247) (xy 313.825295 -283.247135) (xy 313.871107 -283.270478) (xy 313.912703 -283.300699)
			(xy 313.949059 -283.337055) (xy 313.97928 -283.378651) (xy 314.002623 -283.424463) (xy 314.018511 -283.473362)
			(xy 314.026554 -283.524144) (xy 314.027058 -283.549852) (xy 314.026554 -283.57556) (xy 314.323218 -283.57556)
			(xy 314.323218 -283.524144) (xy 314.331261 -283.473362) (xy 314.347149 -283.424463) (xy 314.370492 -283.378651)
			(xy 314.400713 -283.337055) (xy 314.437069 -283.300699) (xy 314.478665 -283.270478) (xy 314.524477 -283.247135)
			(xy 314.573376 -283.231247) (xy 314.624158 -283.223204) (xy 314.675574 -283.223204) (xy 314.726356 -283.231247)
			(xy 314.775255 -283.247135) (xy 314.821067 -283.270478) (xy 314.862663 -283.300699) (xy 314.899019 -283.337055)
			(xy 314.92924 -283.378651) (xy 314.952583 -283.424463) (xy 314.968471 -283.473362) (xy 314.976514 -283.524144)
			(xy 314.977018 -283.549852) (xy 314.977013 -283.550106) (xy 315.294276 -283.550106) (xy 315.298236 -283.501052)
			(xy 315.310013 -283.453268) (xy 315.329304 -283.407992) (xy 315.355607 -283.366396) (xy 315.388242 -283.329559)
			(xy 315.426363 -283.298434) (xy 315.468984 -283.273827) (xy 315.515 -283.256375) (xy 315.563219 -283.246531)
			(xy 315.612394 -283.24455) (xy 315.661249 -283.250482) (xy 315.70852 -283.264174) (xy 315.752982 -283.285272)
			(xy 315.793485 -283.313228) (xy 315.828978 -283.34732) (xy 315.858543 -283.386664) (xy 315.881414 -283.430241)
			(xy 315.896998 -283.476922) (xy 315.904893 -283.525499) (xy 315.905388 -283.550106) (xy 315.904893 -283.574713)
			(xy 315.896998 -283.62329) (xy 315.881414 -283.669971) (xy 315.858543 -283.713548) (xy 315.828978 -283.752892)
			(xy 315.793485 -283.786984) (xy 315.752982 -283.81494) (xy 315.70852 -283.836038) (xy 315.661249 -283.84973)
			(xy 315.612394 -283.855662) (xy 315.563219 -283.853681) (xy 315.515 -283.843837) (xy 315.468984 -283.826385)
			(xy 315.426363 -283.801778) (xy 315.388242 -283.770653) (xy 315.355607 -283.733816) (xy 315.329304 -283.69222)
			(xy 315.310013 -283.646944) (xy 315.298236 -283.59916) (xy 315.294276 -283.550106) (xy 314.977013 -283.550106)
			(xy 314.976514 -283.57556) (xy 314.968471 -283.626342) (xy 314.952583 -283.675241) (xy 314.92924 -283.721053)
			(xy 314.899019 -283.762649) (xy 314.862663 -283.799005) (xy 314.821067 -283.829226) (xy 314.775255 -283.852569)
			(xy 314.726356 -283.868457) (xy 314.675574 -283.8765) (xy 314.624158 -283.8765) (xy 314.573376 -283.868457)
			(xy 314.524477 -283.852569) (xy 314.478665 -283.829226) (xy 314.437069 -283.799005) (xy 314.400713 -283.762649)
			(xy 314.370492 -283.721053) (xy 314.347149 -283.675241) (xy 314.331261 -283.626342) (xy 314.323218 -283.57556)
			(xy 314.026554 -283.57556) (xy 314.018511 -283.626342) (xy 314.002623 -283.675241) (xy 313.97928 -283.721053)
			(xy 313.949059 -283.762649) (xy 313.912703 -283.799005) (xy 313.871107 -283.829226) (xy 313.825295 -283.852569)
			(xy 313.776396 -283.868457) (xy 313.725614 -283.8765) (xy 313.674198 -283.8765) (xy 313.623416 -283.868457)
			(xy 313.574517 -283.852569) (xy 313.528705 -283.829226) (xy 313.487109 -283.799005) (xy 313.450753 -283.762649)
			(xy 313.420532 -283.721053) (xy 313.397189 -283.675241) (xy 313.381301 -283.626342) (xy 313.373258 -283.57556)
			(xy 313.054326 -283.57556) (xy 313.04661 -283.623036) (xy 313.031026 -283.669717) (xy 313.008155 -283.713294)
			(xy 312.97859 -283.752638) (xy 312.943097 -283.78673) (xy 312.902594 -283.814686) (xy 312.858132 -283.835784)
			(xy 312.810861 -283.849476) (xy 312.762006 -283.855408) (xy 312.712831 -283.853427) (xy 312.664612 -283.843583)
			(xy 312.618596 -283.826131) (xy 312.575975 -283.801524) (xy 312.537854 -283.770399) (xy 312.505219 -283.733562)
			(xy 312.478916 -283.691966) (xy 312.459625 -283.64669) (xy 312.447848 -283.598906) (xy 312.443888 -283.549852)
			(xy 312.10504 -283.549852) (xy 312.104545 -283.574459) (xy 312.09665 -283.623036) (xy 312.081066 -283.669717)
			(xy 312.058195 -283.713294) (xy 312.02863 -283.752638) (xy 311.993137 -283.78673) (xy 311.952634 -283.814686)
			(xy 311.908172 -283.835784) (xy 311.860901 -283.849476) (xy 311.812046 -283.855408) (xy 311.762871 -283.853427)
			(xy 311.714652 -283.843583) (xy 311.668636 -283.826131) (xy 311.626015 -283.801524) (xy 311.587894 -283.770399)
			(xy 311.555259 -283.733562) (xy 311.528956 -283.691966) (xy 311.509665 -283.64669) (xy 311.497888 -283.598906)
			(xy 311.493928 -283.549852) (xy 311.15508 -283.549852) (xy 311.154585 -283.574459) (xy 311.14669 -283.623036)
			(xy 311.131106 -283.669717) (xy 311.108235 -283.713294) (xy 311.07867 -283.752638) (xy 311.043177 -283.78673)
			(xy 311.002674 -283.814686) (xy 310.958212 -283.835784) (xy 310.910941 -283.849476) (xy 310.862086 -283.855408)
			(xy 310.812911 -283.853427) (xy 310.764692 -283.843583) (xy 310.718676 -283.826131) (xy 310.676055 -283.801524)
			(xy 310.637934 -283.770399) (xy 310.605299 -283.733562) (xy 310.578996 -283.691966) (xy 310.559705 -283.64669)
			(xy 310.547928 -283.598906) (xy 310.543968 -283.549852) (xy 310.20512 -283.549852) (xy 310.204625 -283.574459)
			(xy 310.19673 -283.623036) (xy 310.181146 -283.669717) (xy 310.158275 -283.713294) (xy 310.12871 -283.752638)
			(xy 310.093217 -283.78673) (xy 310.052714 -283.814686) (xy 310.008252 -283.835784) (xy 309.960981 -283.849476)
			(xy 309.912126 -283.855408) (xy 309.862951 -283.853427) (xy 309.814732 -283.843583) (xy 309.768716 -283.826131)
			(xy 309.726095 -283.801524) (xy 309.687974 -283.770399) (xy 309.655339 -283.733562) (xy 309.629036 -283.691966)
			(xy 309.609745 -283.64669) (xy 309.597968 -283.598906) (xy 309.594008 -283.549852) (xy 309.25516 -283.549852)
			(xy 309.254665 -283.574459) (xy 309.24677 -283.623036) (xy 309.231186 -283.669717) (xy 309.208315 -283.713294)
			(xy 309.17875 -283.752638) (xy 309.143257 -283.78673) (xy 309.102754 -283.814686) (xy 309.058292 -283.835784)
			(xy 309.011021 -283.849476) (xy 308.962166 -283.855408) (xy 308.912991 -283.853427) (xy 308.864772 -283.843583)
			(xy 308.818756 -283.826131) (xy 308.776135 -283.801524) (xy 308.738014 -283.770399) (xy 308.705379 -283.733562)
			(xy 308.679076 -283.691966) (xy 308.659785 -283.64669) (xy 308.648008 -283.598906) (xy 308.644048 -283.549852)
			(xy 308.327044 -283.549852) (xy 308.32654 -283.57556) (xy 308.318497 -283.626342) (xy 308.302609 -283.675241)
			(xy 308.279266 -283.721053) (xy 308.249045 -283.762649) (xy 308.212689 -283.799005) (xy 308.171093 -283.829226)
			(xy 308.125281 -283.852569) (xy 308.076382 -283.868457) (xy 308.0256 -283.8765) (xy 307.974184 -283.8765)
			(xy 307.923402 -283.868457) (xy 307.874503 -283.852569) (xy 307.828691 -283.829226) (xy 307.787095 -283.799005)
			(xy 307.750739 -283.762649) (xy 307.720518 -283.721053) (xy 307.697175 -283.675241) (xy 307.681287 -283.626342)
			(xy 307.673244 -283.57556) (xy 307.376326 -283.57556) (xy 307.368283 -283.626342) (xy 307.352395 -283.675241)
			(xy 307.329052 -283.721053) (xy 307.298831 -283.762649) (xy 307.262475 -283.799005) (xy 307.220879 -283.829226)
			(xy 307.175067 -283.852569) (xy 307.126168 -283.868457) (xy 307.075386 -283.8765) (xy 307.02397 -283.8765)
			(xy 306.973188 -283.868457) (xy 306.924289 -283.852569) (xy 306.878477 -283.829226) (xy 306.836881 -283.799005)
			(xy 306.800525 -283.762649) (xy 306.770304 -283.721053) (xy 306.746961 -283.675241) (xy 306.731073 -283.626342)
			(xy 306.72303 -283.57556) (xy 306.404352 -283.57556) (xy 306.396636 -283.623036) (xy 306.381052 -283.669717)
			(xy 306.358181 -283.713294) (xy 306.328616 -283.752638) (xy 306.293123 -283.78673) (xy 306.25262 -283.814686)
			(xy 306.208158 -283.835784) (xy 306.160887 -283.849476) (xy 306.112032 -283.855408) (xy 306.062857 -283.853427)
			(xy 306.014638 -283.843583) (xy 305.968622 -283.826131) (xy 305.926001 -283.801524) (xy 305.88788 -283.770399)
			(xy 305.855245 -283.733562) (xy 305.828942 -283.691966) (xy 305.809651 -283.64669) (xy 305.797874 -283.598906)
			(xy 305.793914 -283.549852) (xy 281.616912 -283.549852) (xy 281.616912 -283.649166) (xy 281.617569 -283.661714)
			(xy 281.62944 -283.683823) (xy 281.639518 -283.69133) (xy 281.720544 -283.745432) (xy 281.745436 -283.747972)
			(xy 281.757628 -283.742892) (xy 281.785665 -283.731994) (xy 281.844649 -283.720227) (xy 281.874722 -283.719524)
			(xy 281.899973 -283.720047) (xy 281.949787 -283.728363) (xy 281.997553 -283.744764) (xy 282.041968 -283.768803)
			(xy 282.081821 -283.799824) (xy 282.116024 -283.836982) (xy 282.143646 -283.879262) (xy 282.163931 -283.925512)
			(xy 282.176329 -283.974469) (xy 282.180499 -284.0248) (xy 282.180496 -284.024832) (xy 282.519132 -284.024832)
			(xy 282.523092 -283.975778) (xy 282.534869 -283.927994) (xy 282.55416 -283.882718) (xy 282.580463 -283.841122)
			(xy 282.613098 -283.804285) (xy 282.651219 -283.77316) (xy 282.69384 -283.748553) (xy 282.739856 -283.731101)
			(xy 282.788075 -283.721257) (xy 282.83725 -283.719276) (xy 282.886105 -283.725208) (xy 282.933376 -283.7389)
			(xy 282.977838 -283.759998) (xy 283.018341 -283.787954) (xy 283.053834 -283.822046) (xy 283.083399 -283.86139)
			(xy 283.10627 -283.904967) (xy 283.121854 -283.951648) (xy 283.129749 -284.000225) (xy 283.130244 -284.024832)
			(xy 283.469092 -284.024832) (xy 283.473052 -283.975778) (xy 283.484829 -283.927994) (xy 283.50412 -283.882718)
			(xy 283.530423 -283.841122) (xy 283.563058 -283.804285) (xy 283.601179 -283.77316) (xy 283.6438 -283.748553)
			(xy 283.689816 -283.731101) (xy 283.738035 -283.721257) (xy 283.78721 -283.719276) (xy 283.836065 -283.725208)
			(xy 283.883336 -283.7389) (xy 283.927798 -283.759998) (xy 283.968301 -283.787954) (xy 284.003794 -283.822046)
			(xy 284.033359 -283.86139) (xy 284.05623 -283.904967) (xy 284.071814 -283.951648) (xy 284.079709 -284.000225)
			(xy 284.080204 -284.024832) (xy 284.419052 -284.024832) (xy 284.423012 -283.975778) (xy 284.434789 -283.927994)
			(xy 284.45408 -283.882718) (xy 284.480383 -283.841122) (xy 284.513018 -283.804285) (xy 284.551139 -283.77316)
			(xy 284.59376 -283.748553) (xy 284.639776 -283.731101) (xy 284.687995 -283.721257) (xy 284.73717 -283.719276)
			(xy 284.786025 -283.725208) (xy 284.833296 -283.7389) (xy 284.877758 -283.759998) (xy 284.918261 -283.787954)
			(xy 284.953754 -283.822046) (xy 284.983319 -283.86139) (xy 285.00619 -283.904967) (xy 285.021774 -283.951648)
			(xy 285.029669 -284.000225) (xy 285.030164 -284.024832) (xy 285.369012 -284.024832) (xy 285.372972 -283.975778)
			(xy 285.384749 -283.927994) (xy 285.40404 -283.882718) (xy 285.430343 -283.841122) (xy 285.462978 -283.804285)
			(xy 285.501099 -283.77316) (xy 285.54372 -283.748553) (xy 285.589736 -283.731101) (xy 285.637955 -283.721257)
			(xy 285.68713 -283.719276) (xy 285.735985 -283.725208) (xy 285.783256 -283.7389) (xy 285.827718 -283.759998)
			(xy 285.868221 -283.787954) (xy 285.903714 -283.822046) (xy 285.933279 -283.86139) (xy 285.95615 -283.904967)
			(xy 285.971734 -283.951648) (xy 285.979629 -284.000225) (xy 285.980124 -284.024832) (xy 286.318972 -284.024832)
			(xy 286.322932 -283.975778) (xy 286.334709 -283.927994) (xy 286.354 -283.882718) (xy 286.380303 -283.841122)
			(xy 286.412938 -283.804285) (xy 286.451059 -283.77316) (xy 286.49368 -283.748553) (xy 286.539696 -283.731101)
			(xy 286.587915 -283.721257) (xy 286.63709 -283.719276) (xy 286.685945 -283.725208) (xy 286.733216 -283.7389)
			(xy 286.777678 -283.759998) (xy 286.818181 -283.787954) (xy 286.853674 -283.822046) (xy 286.883239 -283.86139)
			(xy 286.90611 -283.904967) (xy 286.921694 -283.951648) (xy 286.929589 -284.000225) (xy 286.930084 -284.024832)
			(xy 287.268932 -284.024832) (xy 287.272892 -283.975778) (xy 287.284669 -283.927994) (xy 287.30396 -283.882718)
			(xy 287.330263 -283.841122) (xy 287.362898 -283.804285) (xy 287.401019 -283.77316) (xy 287.44364 -283.748553)
			(xy 287.489656 -283.731101) (xy 287.537875 -283.721257) (xy 287.58705 -283.719276) (xy 287.635905 -283.725208)
			(xy 287.683176 -283.7389) (xy 287.727638 -283.759998) (xy 287.768141 -283.787954) (xy 287.803634 -283.822046)
			(xy 287.833199 -283.86139) (xy 287.85607 -283.904967) (xy 287.871654 -283.951648) (xy 287.879549 -284.000225)
			(xy 287.880044 -284.024832) (xy 288.218892 -284.024832) (xy 288.222852 -283.975778) (xy 288.234629 -283.927994)
			(xy 288.25392 -283.882718) (xy 288.280223 -283.841122) (xy 288.312858 -283.804285) (xy 288.350979 -283.77316)
			(xy 288.3936 -283.748553) (xy 288.439616 -283.731101) (xy 288.487835 -283.721257) (xy 288.53701 -283.719276)
			(xy 288.585865 -283.725208) (xy 288.633136 -283.7389) (xy 288.677598 -283.759998) (xy 288.718101 -283.787954)
			(xy 288.753594 -283.822046) (xy 288.783159 -283.86139) (xy 288.80603 -283.904967) (xy 288.821614 -283.951648)
			(xy 288.829509 -284.000225) (xy 288.830004 -284.024832) (xy 289.169106 -284.024832) (xy 289.173066 -283.975778)
			(xy 289.184843 -283.927994) (xy 289.204134 -283.882718) (xy 289.230437 -283.841122) (xy 289.263072 -283.804285)
			(xy 289.301193 -283.77316) (xy 289.343814 -283.748553) (xy 289.38983 -283.731101) (xy 289.438049 -283.721257)
			(xy 289.487224 -283.719276) (xy 289.536079 -283.725208) (xy 289.58335 -283.7389) (xy 289.627812 -283.759998)
			(xy 289.668315 -283.787954) (xy 289.703808 -283.822046) (xy 289.733373 -283.86139) (xy 289.756244 -283.904967)
			(xy 289.771828 -283.951648) (xy 289.779723 -284.000225) (xy 289.780218 -284.024832) (xy 290.119066 -284.024832)
			(xy 290.123026 -283.975778) (xy 290.134803 -283.927994) (xy 290.154094 -283.882718) (xy 290.180397 -283.841122)
			(xy 290.213032 -283.804285) (xy 290.251153 -283.77316) (xy 290.293774 -283.748553) (xy 290.33979 -283.731101)
			(xy 290.388009 -283.721257) (xy 290.437184 -283.719276) (xy 290.486039 -283.725208) (xy 290.53331 -283.7389)
			(xy 290.577772 -283.759998) (xy 290.618275 -283.787954) (xy 290.653768 -283.822046) (xy 290.683333 -283.86139)
			(xy 290.706204 -283.904967) (xy 290.721788 -283.951648) (xy 290.729683 -284.000225) (xy 290.730178 -284.024832)
			(xy 292.018986 -284.024832) (xy 292.022946 -283.975778) (xy 292.034723 -283.927994) (xy 292.054014 -283.882718)
			(xy 292.080317 -283.841122) (xy 292.112952 -283.804285) (xy 292.151073 -283.77316) (xy 292.193694 -283.748553)
			(xy 292.23971 -283.731101) (xy 292.287929 -283.721257) (xy 292.337104 -283.719276) (xy 292.385959 -283.725208)
			(xy 292.43323 -283.7389) (xy 292.477692 -283.759998) (xy 292.518195 -283.787954) (xy 292.553688 -283.822046)
			(xy 292.583253 -283.86139) (xy 292.606124 -283.904967) (xy 292.621708 -283.951648) (xy 292.629603 -284.000225)
			(xy 292.630098 -284.024832) (xy 292.968946 -284.024832) (xy 292.972906 -283.975778) (xy 292.984683 -283.927994)
			(xy 293.003974 -283.882718) (xy 293.030277 -283.841122) (xy 293.062912 -283.804285) (xy 293.101033 -283.77316)
			(xy 293.143654 -283.748553) (xy 293.18967 -283.731101) (xy 293.237889 -283.721257) (xy 293.287064 -283.719276)
			(xy 293.335919 -283.725208) (xy 293.38319 -283.7389) (xy 293.427652 -283.759998) (xy 293.468155 -283.787954)
			(xy 293.503648 -283.822046) (xy 293.533213 -283.86139) (xy 293.556084 -283.904967) (xy 293.571668 -283.951648)
			(xy 293.579563 -284.000225) (xy 293.580058 -284.024832) (xy 293.918906 -284.024832) (xy 293.922866 -283.975778)
			(xy 293.934643 -283.927994) (xy 293.953934 -283.882718) (xy 293.980237 -283.841122) (xy 294.012872 -283.804285)
			(xy 294.050993 -283.77316) (xy 294.093614 -283.748553) (xy 294.13963 -283.731101) (xy 294.187849 -283.721257)
			(xy 294.237024 -283.719276) (xy 294.285879 -283.725208) (xy 294.33315 -283.7389) (xy 294.377612 -283.759998)
			(xy 294.418115 -283.787954) (xy 294.453608 -283.822046) (xy 294.483173 -283.86139) (xy 294.506044 -283.904967)
			(xy 294.521628 -283.951648) (xy 294.529523 -284.000225) (xy 294.530018 -284.024832) (xy 294.86912 -284.024832)
			(xy 294.87308 -283.975778) (xy 294.884857 -283.927994) (xy 294.904148 -283.882718) (xy 294.930451 -283.841122)
			(xy 294.963086 -283.804285) (xy 295.001207 -283.77316) (xy 295.043828 -283.748553) (xy 295.089844 -283.731101)
			(xy 295.138063 -283.721257) (xy 295.187238 -283.719276) (xy 295.236093 -283.725208) (xy 295.283364 -283.7389)
			(xy 295.327826 -283.759998) (xy 295.368329 -283.787954) (xy 295.403822 -283.822046) (xy 295.433387 -283.86139)
			(xy 295.456258 -283.904967) (xy 295.471842 -283.951648) (xy 295.479737 -284.000225) (xy 295.480232 -284.024832)
			(xy 295.81908 -284.024832) (xy 295.82304 -283.975778) (xy 295.834817 -283.927994) (xy 295.854108 -283.882718)
			(xy 295.880411 -283.841122) (xy 295.913046 -283.804285) (xy 295.951167 -283.77316) (xy 295.993788 -283.748553)
			(xy 296.039804 -283.731101) (xy 296.088023 -283.721257) (xy 296.137198 -283.719276) (xy 296.186053 -283.725208)
			(xy 296.233324 -283.7389) (xy 296.277786 -283.759998) (xy 296.318289 -283.787954) (xy 296.353782 -283.822046)
			(xy 296.383347 -283.86139) (xy 296.406218 -283.904967) (xy 296.421802 -283.951648) (xy 296.429697 -284.000225)
			(xy 296.430192 -284.024832) (xy 296.76904 -284.024832) (xy 296.773 -283.975778) (xy 296.784777 -283.927994)
			(xy 296.804068 -283.882718) (xy 296.830371 -283.841122) (xy 296.863006 -283.804285) (xy 296.901127 -283.77316)
			(xy 296.943748 -283.748553) (xy 296.989764 -283.731101) (xy 297.037983 -283.721257) (xy 297.087158 -283.719276)
			(xy 297.136013 -283.725208) (xy 297.183284 -283.7389) (xy 297.227746 -283.759998) (xy 297.268249 -283.787954)
			(xy 297.303742 -283.822046) (xy 297.333307 -283.86139) (xy 297.356178 -283.904967) (xy 297.371762 -283.951648)
			(xy 297.379657 -284.000225) (xy 297.380152 -284.024832) (xy 297.719 -284.024832) (xy 297.72296 -283.975778)
			(xy 297.734737 -283.927994) (xy 297.754028 -283.882718) (xy 297.780331 -283.841122) (xy 297.812966 -283.804285)
			(xy 297.851087 -283.77316) (xy 297.893708 -283.748553) (xy 297.939724 -283.731101) (xy 297.987943 -283.721257)
			(xy 298.037118 -283.719276) (xy 298.085973 -283.725208) (xy 298.133244 -283.7389) (xy 298.177706 -283.759998)
			(xy 298.218209 -283.787954) (xy 298.253702 -283.822046) (xy 298.283267 -283.86139) (xy 298.306138 -283.904967)
			(xy 298.321722 -283.951648) (xy 298.329617 -284.000225) (xy 298.330112 -284.024832) (xy 298.66896 -284.024832)
			(xy 298.67292 -283.975778) (xy 298.684697 -283.927994) (xy 298.703988 -283.882718) (xy 298.730291 -283.841122)
			(xy 298.762926 -283.804285) (xy 298.801047 -283.77316) (xy 298.843668 -283.748553) (xy 298.889684 -283.731101)
			(xy 298.937903 -283.721257) (xy 298.987078 -283.719276) (xy 299.035933 -283.725208) (xy 299.083204 -283.7389)
			(xy 299.127666 -283.759998) (xy 299.168169 -283.787954) (xy 299.203662 -283.822046) (xy 299.233227 -283.86139)
			(xy 299.256098 -283.904967) (xy 299.271682 -283.951648) (xy 299.279577 -284.000225) (xy 299.280072 -284.024832)
			(xy 300.56888 -284.024832) (xy 300.57284 -283.975778) (xy 300.584617 -283.927994) (xy 300.603908 -283.882718)
			(xy 300.630211 -283.841122) (xy 300.662846 -283.804285) (xy 300.700967 -283.77316) (xy 300.743588 -283.748553)
			(xy 300.789604 -283.731101) (xy 300.837823 -283.721257) (xy 300.886998 -283.719276) (xy 300.935853 -283.725208)
			(xy 300.983124 -283.7389) (xy 301.027586 -283.759998) (xy 301.068089 -283.787954) (xy 301.103582 -283.822046)
			(xy 301.133147 -283.86139) (xy 301.156018 -283.904967) (xy 301.171602 -283.951648) (xy 301.179497 -284.000225)
			(xy 301.179992 -284.024832) (xy 301.519094 -284.024832) (xy 301.523054 -283.975778) (xy 301.534831 -283.927994)
			(xy 301.554122 -283.882718) (xy 301.580425 -283.841122) (xy 301.61306 -283.804285) (xy 301.651181 -283.77316)
			(xy 301.693802 -283.748553) (xy 301.739818 -283.731101) (xy 301.788037 -283.721257) (xy 301.837212 -283.719276)
			(xy 301.886067 -283.725208) (xy 301.933338 -283.7389) (xy 301.9778 -283.759998) (xy 302.018303 -283.787954)
			(xy 302.053796 -283.822046) (xy 302.083361 -283.86139) (xy 302.106232 -283.904967) (xy 302.121816 -283.951648)
			(xy 302.129711 -284.000225) (xy 302.130206 -284.024832) (xy 302.469054 -284.024832) (xy 302.473014 -283.975778)
			(xy 302.484791 -283.927994) (xy 302.504082 -283.882718) (xy 302.530385 -283.841122) (xy 302.56302 -283.804285)
			(xy 302.601141 -283.77316) (xy 302.643762 -283.748553) (xy 302.689778 -283.731101) (xy 302.737997 -283.721257)
			(xy 302.787172 -283.719276) (xy 302.836027 -283.725208) (xy 302.883298 -283.7389) (xy 302.92776 -283.759998)
			(xy 302.968263 -283.787954) (xy 303.003756 -283.822046) (xy 303.033321 -283.86139) (xy 303.056192 -283.904967)
			(xy 303.071776 -283.951648) (xy 303.079671 -284.000225) (xy 303.080166 -284.024832) (xy 303.419014 -284.024832)
			(xy 303.422974 -283.975778) (xy 303.434751 -283.927994) (xy 303.454042 -283.882718) (xy 303.480345 -283.841122)
			(xy 303.51298 -283.804285) (xy 303.551101 -283.77316) (xy 303.593722 -283.748553) (xy 303.639738 -283.731101)
			(xy 303.687957 -283.721257) (xy 303.737132 -283.719276) (xy 303.785987 -283.725208) (xy 303.833258 -283.7389)
			(xy 303.87772 -283.759998) (xy 303.918223 -283.787954) (xy 303.953716 -283.822046) (xy 303.983281 -283.86139)
			(xy 304.006152 -283.904967) (xy 304.021736 -283.951648) (xy 304.029631 -284.000225) (xy 304.030126 -284.024832)
			(xy 304.368974 -284.024832) (xy 304.372934 -283.975778) (xy 304.384711 -283.927994) (xy 304.404002 -283.882718)
			(xy 304.430305 -283.841122) (xy 304.46294 -283.804285) (xy 304.501061 -283.77316) (xy 304.543682 -283.748553)
			(xy 304.589698 -283.731101) (xy 304.637917 -283.721257) (xy 304.687092 -283.719276) (xy 304.735947 -283.725208)
			(xy 304.783218 -283.7389) (xy 304.82768 -283.759998) (xy 304.868183 -283.787954) (xy 304.903676 -283.822046)
			(xy 304.933241 -283.86139) (xy 304.956112 -283.904967) (xy 304.971696 -283.951648) (xy 304.979591 -284.000225)
			(xy 304.980086 -284.024832) (xy 304.979591 -284.049439) (xy 304.971696 -284.098016) (xy 304.956112 -284.144697)
			(xy 304.933241 -284.188274) (xy 304.903676 -284.227618) (xy 304.868183 -284.26171) (xy 304.82768 -284.289666)
			(xy 304.783218 -284.310764) (xy 304.735947 -284.324456) (xy 304.687092 -284.330388) (xy 304.637917 -284.328407)
			(xy 304.589698 -284.318563) (xy 304.543682 -284.301111) (xy 304.501061 -284.276504) (xy 304.46294 -284.245379)
			(xy 304.430305 -284.208542) (xy 304.404002 -284.166946) (xy 304.384711 -284.12167) (xy 304.372934 -284.073886)
			(xy 304.368974 -284.024832) (xy 304.030126 -284.024832) (xy 304.029631 -284.049439) (xy 304.021736 -284.098016)
			(xy 304.006152 -284.144697) (xy 303.983281 -284.188274) (xy 303.953716 -284.227618) (xy 303.918223 -284.26171)
			(xy 303.87772 -284.289666) (xy 303.833258 -284.310764) (xy 303.785987 -284.324456) (xy 303.737132 -284.330388)
			(xy 303.687957 -284.328407) (xy 303.639738 -284.318563) (xy 303.593722 -284.301111) (xy 303.551101 -284.276504)
			(xy 303.51298 -284.245379) (xy 303.480345 -284.208542) (xy 303.454042 -284.166946) (xy 303.434751 -284.12167)
			(xy 303.422974 -284.073886) (xy 303.419014 -284.024832) (xy 303.080166 -284.024832) (xy 303.079671 -284.049439)
			(xy 303.071776 -284.098016) (xy 303.056192 -284.144697) (xy 303.033321 -284.188274) (xy 303.003756 -284.227618)
			(xy 302.968263 -284.26171) (xy 302.92776 -284.289666) (xy 302.883298 -284.310764) (xy 302.836027 -284.324456)
			(xy 302.787172 -284.330388) (xy 302.737997 -284.328407) (xy 302.689778 -284.318563) (xy 302.643762 -284.301111)
			(xy 302.601141 -284.276504) (xy 302.56302 -284.245379) (xy 302.530385 -284.208542) (xy 302.504082 -284.166946)
			(xy 302.484791 -284.12167) (xy 302.473014 -284.073886) (xy 302.469054 -284.024832) (xy 302.130206 -284.024832)
			(xy 302.129711 -284.049439) (xy 302.121816 -284.098016) (xy 302.106232 -284.144697) (xy 302.083361 -284.188274)
			(xy 302.053796 -284.227618) (xy 302.018303 -284.26171) (xy 301.9778 -284.289666) (xy 301.933338 -284.310764)
			(xy 301.886067 -284.324456) (xy 301.837212 -284.330388) (xy 301.788037 -284.328407) (xy 301.739818 -284.318563)
			(xy 301.693802 -284.301111) (xy 301.651181 -284.276504) (xy 301.61306 -284.245379) (xy 301.580425 -284.208542)
			(xy 301.554122 -284.166946) (xy 301.534831 -284.12167) (xy 301.523054 -284.073886) (xy 301.519094 -284.024832)
			(xy 301.179992 -284.024832) (xy 301.179497 -284.049439) (xy 301.171602 -284.098016) (xy 301.156018 -284.144697)
			(xy 301.133147 -284.188274) (xy 301.103582 -284.227618) (xy 301.068089 -284.26171) (xy 301.027586 -284.289666)
			(xy 300.983124 -284.310764) (xy 300.935853 -284.324456) (xy 300.886998 -284.330388) (xy 300.837823 -284.328407)
			(xy 300.789604 -284.318563) (xy 300.743588 -284.301111) (xy 300.700967 -284.276504) (xy 300.662846 -284.245379)
			(xy 300.630211 -284.208542) (xy 300.603908 -284.166946) (xy 300.584617 -284.12167) (xy 300.57284 -284.073886)
			(xy 300.56888 -284.024832) (xy 299.280072 -284.024832) (xy 299.279577 -284.049439) (xy 299.271682 -284.098016)
			(xy 299.256098 -284.144697) (xy 299.233227 -284.188274) (xy 299.203662 -284.227618) (xy 299.168169 -284.26171)
			(xy 299.127666 -284.289666) (xy 299.083204 -284.310764) (xy 299.035933 -284.324456) (xy 298.987078 -284.330388)
			(xy 298.937903 -284.328407) (xy 298.889684 -284.318563) (xy 298.843668 -284.301111) (xy 298.801047 -284.276504)
			(xy 298.762926 -284.245379) (xy 298.730291 -284.208542) (xy 298.703988 -284.166946) (xy 298.684697 -284.12167)
			(xy 298.67292 -284.073886) (xy 298.66896 -284.024832) (xy 298.330112 -284.024832) (xy 298.329617 -284.049439)
			(xy 298.321722 -284.098016) (xy 298.306138 -284.144697) (xy 298.283267 -284.188274) (xy 298.253702 -284.227618)
			(xy 298.218209 -284.26171) (xy 298.177706 -284.289666) (xy 298.133244 -284.310764) (xy 298.085973 -284.324456)
			(xy 298.037118 -284.330388) (xy 297.987943 -284.328407) (xy 297.939724 -284.318563) (xy 297.893708 -284.301111)
			(xy 297.851087 -284.276504) (xy 297.812966 -284.245379) (xy 297.780331 -284.208542) (xy 297.754028 -284.166946)
			(xy 297.734737 -284.12167) (xy 297.72296 -284.073886) (xy 297.719 -284.024832) (xy 297.380152 -284.024832)
			(xy 297.379657 -284.049439) (xy 297.371762 -284.098016) (xy 297.356178 -284.144697) (xy 297.333307 -284.188274)
			(xy 297.303742 -284.227618) (xy 297.268249 -284.26171) (xy 297.227746 -284.289666) (xy 297.183284 -284.310764)
			(xy 297.136013 -284.324456) (xy 297.087158 -284.330388) (xy 297.037983 -284.328407) (xy 296.989764 -284.318563)
			(xy 296.943748 -284.301111) (xy 296.901127 -284.276504) (xy 296.863006 -284.245379) (xy 296.830371 -284.208542)
			(xy 296.804068 -284.166946) (xy 296.784777 -284.12167) (xy 296.773 -284.073886) (xy 296.76904 -284.024832)
			(xy 296.430192 -284.024832) (xy 296.429697 -284.049439) (xy 296.421802 -284.098016) (xy 296.406218 -284.144697)
			(xy 296.383347 -284.188274) (xy 296.353782 -284.227618) (xy 296.318289 -284.26171) (xy 296.277786 -284.289666)
			(xy 296.233324 -284.310764) (xy 296.186053 -284.324456) (xy 296.137198 -284.330388) (xy 296.088023 -284.328407)
			(xy 296.039804 -284.318563) (xy 295.993788 -284.301111) (xy 295.951167 -284.276504) (xy 295.913046 -284.245379)
			(xy 295.880411 -284.208542) (xy 295.854108 -284.166946) (xy 295.834817 -284.12167) (xy 295.82304 -284.073886)
			(xy 295.81908 -284.024832) (xy 295.480232 -284.024832) (xy 295.479737 -284.049439) (xy 295.471842 -284.098016)
			(xy 295.456258 -284.144697) (xy 295.433387 -284.188274) (xy 295.403822 -284.227618) (xy 295.368329 -284.26171)
			(xy 295.327826 -284.289666) (xy 295.283364 -284.310764) (xy 295.236093 -284.324456) (xy 295.187238 -284.330388)
			(xy 295.138063 -284.328407) (xy 295.089844 -284.318563) (xy 295.043828 -284.301111) (xy 295.001207 -284.276504)
			(xy 294.963086 -284.245379) (xy 294.930451 -284.208542) (xy 294.904148 -284.166946) (xy 294.884857 -284.12167)
			(xy 294.87308 -284.073886) (xy 294.86912 -284.024832) (xy 294.530018 -284.024832) (xy 294.529523 -284.049439)
			(xy 294.521628 -284.098016) (xy 294.506044 -284.144697) (xy 294.483173 -284.188274) (xy 294.453608 -284.227618)
			(xy 294.418115 -284.26171) (xy 294.377612 -284.289666) (xy 294.33315 -284.310764) (xy 294.285879 -284.324456)
			(xy 294.237024 -284.330388) (xy 294.187849 -284.328407) (xy 294.13963 -284.318563) (xy 294.093614 -284.301111)
			(xy 294.050993 -284.276504) (xy 294.012872 -284.245379) (xy 293.980237 -284.208542) (xy 293.953934 -284.166946)
			(xy 293.934643 -284.12167) (xy 293.922866 -284.073886) (xy 293.918906 -284.024832) (xy 293.580058 -284.024832)
			(xy 293.579563 -284.049439) (xy 293.571668 -284.098016) (xy 293.556084 -284.144697) (xy 293.533213 -284.188274)
			(xy 293.503648 -284.227618) (xy 293.468155 -284.26171) (xy 293.427652 -284.289666) (xy 293.38319 -284.310764)
			(xy 293.335919 -284.324456) (xy 293.287064 -284.330388) (xy 293.237889 -284.328407) (xy 293.18967 -284.318563)
			(xy 293.143654 -284.301111) (xy 293.101033 -284.276504) (xy 293.062912 -284.245379) (xy 293.030277 -284.208542)
			(xy 293.003974 -284.166946) (xy 292.984683 -284.12167) (xy 292.972906 -284.073886) (xy 292.968946 -284.024832)
			(xy 292.630098 -284.024832) (xy 292.629603 -284.049439) (xy 292.621708 -284.098016) (xy 292.606124 -284.144697)
			(xy 292.583253 -284.188274) (xy 292.553688 -284.227618) (xy 292.518195 -284.26171) (xy 292.477692 -284.289666)
			(xy 292.43323 -284.310764) (xy 292.385959 -284.324456) (xy 292.337104 -284.330388) (xy 292.287929 -284.328407)
			(xy 292.23971 -284.318563) (xy 292.193694 -284.301111) (xy 292.151073 -284.276504) (xy 292.112952 -284.245379)
			(xy 292.080317 -284.208542) (xy 292.054014 -284.166946) (xy 292.034723 -284.12167) (xy 292.022946 -284.073886)
			(xy 292.018986 -284.024832) (xy 290.730178 -284.024832) (xy 290.729683 -284.049439) (xy 290.721788 -284.098016)
			(xy 290.706204 -284.144697) (xy 290.683333 -284.188274) (xy 290.653768 -284.227618) (xy 290.618275 -284.26171)
			(xy 290.577772 -284.289666) (xy 290.53331 -284.310764) (xy 290.486039 -284.324456) (xy 290.437184 -284.330388)
			(xy 290.388009 -284.328407) (xy 290.33979 -284.318563) (xy 290.293774 -284.301111) (xy 290.251153 -284.276504)
			(xy 290.213032 -284.245379) (xy 290.180397 -284.208542) (xy 290.154094 -284.166946) (xy 290.134803 -284.12167)
			(xy 290.123026 -284.073886) (xy 290.119066 -284.024832) (xy 289.780218 -284.024832) (xy 289.779723 -284.049439)
			(xy 289.771828 -284.098016) (xy 289.756244 -284.144697) (xy 289.733373 -284.188274) (xy 289.703808 -284.227618)
			(xy 289.668315 -284.26171) (xy 289.627812 -284.289666) (xy 289.58335 -284.310764) (xy 289.536079 -284.324456)
			(xy 289.487224 -284.330388) (xy 289.438049 -284.328407) (xy 289.38983 -284.318563) (xy 289.343814 -284.301111)
			(xy 289.301193 -284.276504) (xy 289.263072 -284.245379) (xy 289.230437 -284.208542) (xy 289.204134 -284.166946)
			(xy 289.184843 -284.12167) (xy 289.173066 -284.073886) (xy 289.169106 -284.024832) (xy 288.830004 -284.024832)
			(xy 288.829509 -284.049439) (xy 288.821614 -284.098016) (xy 288.80603 -284.144697) (xy 288.783159 -284.188274)
			(xy 288.753594 -284.227618) (xy 288.718101 -284.26171) (xy 288.677598 -284.289666) (xy 288.633136 -284.310764)
			(xy 288.585865 -284.324456) (xy 288.53701 -284.330388) (xy 288.487835 -284.328407) (xy 288.439616 -284.318563)
			(xy 288.3936 -284.301111) (xy 288.350979 -284.276504) (xy 288.312858 -284.245379) (xy 288.280223 -284.208542)
			(xy 288.25392 -284.166946) (xy 288.234629 -284.12167) (xy 288.222852 -284.073886) (xy 288.218892 -284.024832)
			(xy 287.880044 -284.024832) (xy 287.879549 -284.049439) (xy 287.871654 -284.098016) (xy 287.85607 -284.144697)
			(xy 287.833199 -284.188274) (xy 287.803634 -284.227618) (xy 287.768141 -284.26171) (xy 287.727638 -284.289666)
			(xy 287.683176 -284.310764) (xy 287.635905 -284.324456) (xy 287.58705 -284.330388) (xy 287.537875 -284.328407)
			(xy 287.489656 -284.318563) (xy 287.44364 -284.301111) (xy 287.401019 -284.276504) (xy 287.362898 -284.245379)
			(xy 287.330263 -284.208542) (xy 287.30396 -284.166946) (xy 287.284669 -284.12167) (xy 287.272892 -284.073886)
			(xy 287.268932 -284.024832) (xy 286.930084 -284.024832) (xy 286.929589 -284.049439) (xy 286.921694 -284.098016)
			(xy 286.90611 -284.144697) (xy 286.883239 -284.188274) (xy 286.853674 -284.227618) (xy 286.818181 -284.26171)
			(xy 286.777678 -284.289666) (xy 286.733216 -284.310764) (xy 286.685945 -284.324456) (xy 286.63709 -284.330388)
			(xy 286.587915 -284.328407) (xy 286.539696 -284.318563) (xy 286.49368 -284.301111) (xy 286.451059 -284.276504)
			(xy 286.412938 -284.245379) (xy 286.380303 -284.208542) (xy 286.354 -284.166946) (xy 286.334709 -284.12167)
			(xy 286.322932 -284.073886) (xy 286.318972 -284.024832) (xy 285.980124 -284.024832) (xy 285.979629 -284.049439)
			(xy 285.971734 -284.098016) (xy 285.95615 -284.144697) (xy 285.933279 -284.188274) (xy 285.903714 -284.227618)
			(xy 285.868221 -284.26171) (xy 285.827718 -284.289666) (xy 285.783256 -284.310764) (xy 285.735985 -284.324456)
			(xy 285.68713 -284.330388) (xy 285.637955 -284.328407) (xy 285.589736 -284.318563) (xy 285.54372 -284.301111)
			(xy 285.501099 -284.276504) (xy 285.462978 -284.245379) (xy 285.430343 -284.208542) (xy 285.40404 -284.166946)
			(xy 285.384749 -284.12167) (xy 285.372972 -284.073886) (xy 285.369012 -284.024832) (xy 285.030164 -284.024832)
			(xy 285.029669 -284.049439) (xy 285.021774 -284.098016) (xy 285.00619 -284.144697) (xy 284.983319 -284.188274)
			(xy 284.953754 -284.227618) (xy 284.918261 -284.26171) (xy 284.877758 -284.289666) (xy 284.833296 -284.310764)
			(xy 284.786025 -284.324456) (xy 284.73717 -284.330388) (xy 284.687995 -284.328407) (xy 284.639776 -284.318563)
			(xy 284.59376 -284.301111) (xy 284.551139 -284.276504) (xy 284.513018 -284.245379) (xy 284.480383 -284.208542)
			(xy 284.45408 -284.166946) (xy 284.434789 -284.12167) (xy 284.423012 -284.073886) (xy 284.419052 -284.024832)
			(xy 284.080204 -284.024832) (xy 284.079709 -284.049439) (xy 284.071814 -284.098016) (xy 284.05623 -284.144697)
			(xy 284.033359 -284.188274) (xy 284.003794 -284.227618) (xy 283.968301 -284.26171) (xy 283.927798 -284.289666)
			(xy 283.883336 -284.310764) (xy 283.836065 -284.324456) (xy 283.78721 -284.330388) (xy 283.738035 -284.328407)
			(xy 283.689816 -284.318563) (xy 283.6438 -284.301111) (xy 283.601179 -284.276504) (xy 283.563058 -284.245379)
			(xy 283.530423 -284.208542) (xy 283.50412 -284.166946) (xy 283.484829 -284.12167) (xy 283.473052 -284.073886)
			(xy 283.469092 -284.024832) (xy 283.130244 -284.024832) (xy 283.129749 -284.049439) (xy 283.121854 -284.098016)
			(xy 283.10627 -284.144697) (xy 283.083399 -284.188274) (xy 283.053834 -284.227618) (xy 283.018341 -284.26171)
			(xy 282.977838 -284.289666) (xy 282.933376 -284.310764) (xy 282.886105 -284.324456) (xy 282.83725 -284.330388)
			(xy 282.788075 -284.328407) (xy 282.739856 -284.318563) (xy 282.69384 -284.301111) (xy 282.651219 -284.276504)
			(xy 282.613098 -284.245379) (xy 282.580463 -284.208542) (xy 282.55416 -284.166946) (xy 282.534869 -284.12167)
			(xy 282.523092 -284.073886) (xy 282.519132 -284.024832) (xy 282.180496 -284.024832) (xy 282.176329 -284.075131)
			(xy 282.163931 -284.124088) (xy 282.143646 -284.170338) (xy 282.116024 -284.212618) (xy 282.081821 -284.249776)
			(xy 282.041968 -284.280797) (xy 281.997553 -284.304836) (xy 281.949787 -284.321237) (xy 281.899973 -284.329553)
			(xy 281.874722 -284.33014) (xy 281.844648 -284.329446) (xy 281.785663 -284.317679) (xy 281.757628 -284.306772)
			(xy 281.745436 -284.301692) (xy 281.720544 -284.304232) (xy 281.639518 -284.358334) (xy 281.629468 -284.365856)
			(xy 281.617635 -284.387963) (xy 281.616912 -284.400498) (xy 281.616912 -284.499812) (xy 305.793914 -284.499812)
			(xy 305.797874 -284.450758) (xy 305.809651 -284.402974) (xy 305.828942 -284.357698) (xy 305.855245 -284.316102)
			(xy 305.88788 -284.279265) (xy 305.926001 -284.24814) (xy 305.968622 -284.223533) (xy 306.014638 -284.206081)
			(xy 306.062857 -284.196237) (xy 306.112032 -284.194256) (xy 306.160887 -284.200188) (xy 306.208158 -284.21388)
			(xy 306.25262 -284.234978) (xy 306.293123 -284.262934) (xy 306.328616 -284.297026) (xy 306.358181 -284.33637)
			(xy 306.381052 -284.379947) (xy 306.396636 -284.426628) (xy 306.404531 -284.475205) (xy 306.405026 -284.499812)
			(xy 306.743874 -284.499812) (xy 306.747834 -284.450758) (xy 306.759611 -284.402974) (xy 306.778902 -284.357698)
			(xy 306.805205 -284.316102) (xy 306.83784 -284.279265) (xy 306.875961 -284.24814) (xy 306.918582 -284.223533)
			(xy 306.964598 -284.206081) (xy 307.012817 -284.196237) (xy 307.061992 -284.194256) (xy 307.110847 -284.200188)
			(xy 307.158118 -284.21388) (xy 307.20258 -284.234978) (xy 307.243083 -284.262934) (xy 307.278576 -284.297026)
			(xy 307.308141 -284.33637) (xy 307.331012 -284.379947) (xy 307.346596 -284.426628) (xy 307.354491 -284.475205)
			(xy 307.354986 -284.499812) (xy 307.694088 -284.499812) (xy 307.698048 -284.450758) (xy 307.709825 -284.402974)
			(xy 307.729116 -284.357698) (xy 307.755419 -284.316102) (xy 307.788054 -284.279265) (xy 307.826175 -284.24814)
			(xy 307.868796 -284.223533) (xy 307.914812 -284.206081) (xy 307.963031 -284.196237) (xy 308.012206 -284.194256)
			(xy 308.061061 -284.200188) (xy 308.108332 -284.21388) (xy 308.152794 -284.234978) (xy 308.193297 -284.262934)
			(xy 308.22879 -284.297026) (xy 308.258355 -284.33637) (xy 308.281226 -284.379947) (xy 308.29681 -284.426628)
			(xy 308.304705 -284.475205) (xy 308.3052 -284.499812) (xy 308.304705 -284.524419) (xy 308.304526 -284.52552)
			(xy 308.623204 -284.52552) (xy 308.623204 -284.474104) (xy 308.631247 -284.423322) (xy 308.647135 -284.374423)
			(xy 308.670478 -284.328611) (xy 308.700699 -284.287015) (xy 308.737055 -284.250659) (xy 308.778651 -284.220438)
			(xy 308.824463 -284.197095) (xy 308.873362 -284.181207) (xy 308.924144 -284.173164) (xy 308.97556 -284.173164)
			(xy 309.026342 -284.181207) (xy 309.075241 -284.197095) (xy 309.121053 -284.220438) (xy 309.162649 -284.250659)
			(xy 309.199005 -284.287015) (xy 309.229226 -284.328611) (xy 309.252569 -284.374423) (xy 309.268457 -284.423322)
			(xy 309.2765 -284.474104) (xy 309.277004 -284.499812) (xy 309.2765 -284.52552) (xy 309.573164 -284.52552)
			(xy 309.573164 -284.474104) (xy 309.581207 -284.423322) (xy 309.597095 -284.374423) (xy 309.620438 -284.328611)
			(xy 309.650659 -284.287015) (xy 309.687015 -284.250659) (xy 309.728611 -284.220438) (xy 309.774423 -284.197095)
			(xy 309.823322 -284.181207) (xy 309.874104 -284.173164) (xy 309.92552 -284.173164) (xy 309.976302 -284.181207)
			(xy 310.025201 -284.197095) (xy 310.071013 -284.220438) (xy 310.112609 -284.250659) (xy 310.148965 -284.287015)
			(xy 310.179186 -284.328611) (xy 310.202529 -284.374423) (xy 310.218417 -284.423322) (xy 310.22646 -284.474104)
			(xy 310.226964 -284.499812) (xy 310.543968 -284.499812) (xy 310.547928 -284.450758) (xy 310.559705 -284.402974)
			(xy 310.578996 -284.357698) (xy 310.605299 -284.316102) (xy 310.637934 -284.279265) (xy 310.676055 -284.24814)
			(xy 310.718676 -284.223533) (xy 310.764692 -284.206081) (xy 310.812911 -284.196237) (xy 310.862086 -284.194256)
			(xy 310.910941 -284.200188) (xy 310.958212 -284.21388) (xy 311.002674 -284.234978) (xy 311.043177 -284.262934)
			(xy 311.07867 -284.297026) (xy 311.108235 -284.33637) (xy 311.131106 -284.379947) (xy 311.14669 -284.426628)
			(xy 311.154585 -284.475205) (xy 311.15508 -284.499812) (xy 311.154585 -284.524419) (xy 311.154406 -284.52552)
			(xy 311.473084 -284.52552) (xy 311.473084 -284.474104) (xy 311.481127 -284.423322) (xy 311.497015 -284.374423)
			(xy 311.520358 -284.328611) (xy 311.550579 -284.287015) (xy 311.586935 -284.250659) (xy 311.628531 -284.220438)
			(xy 311.674343 -284.197095) (xy 311.723242 -284.181207) (xy 311.774024 -284.173164) (xy 311.82544 -284.173164)
			(xy 311.876222 -284.181207) (xy 311.925121 -284.197095) (xy 311.970933 -284.220438) (xy 312.012529 -284.250659)
			(xy 312.048885 -284.287015) (xy 312.079106 -284.328611) (xy 312.102449 -284.374423) (xy 312.118337 -284.423322)
			(xy 312.12638 -284.474104) (xy 312.126884 -284.499812) (xy 312.12638 -284.52552) (xy 312.423044 -284.52552)
			(xy 312.423044 -284.474104) (xy 312.431087 -284.423322) (xy 312.446975 -284.374423) (xy 312.470318 -284.328611)
			(xy 312.500539 -284.287015) (xy 312.536895 -284.250659) (xy 312.578491 -284.220438) (xy 312.624303 -284.197095)
			(xy 312.673202 -284.181207) (xy 312.723984 -284.173164) (xy 312.7754 -284.173164) (xy 312.826182 -284.181207)
			(xy 312.875081 -284.197095) (xy 312.920893 -284.220438) (xy 312.962489 -284.250659) (xy 312.998845 -284.287015)
			(xy 313.029066 -284.328611) (xy 313.052409 -284.374423) (xy 313.068297 -284.423322) (xy 313.07634 -284.474104)
			(xy 313.076844 -284.499812) (xy 313.394102 -284.499812) (xy 313.398062 -284.450758) (xy 313.409839 -284.402974)
			(xy 313.42913 -284.357698) (xy 313.455433 -284.316102) (xy 313.488068 -284.279265) (xy 313.526189 -284.24814)
			(xy 313.56881 -284.223533) (xy 313.614826 -284.206081) (xy 313.663045 -284.196237) (xy 313.71222 -284.194256)
			(xy 313.761075 -284.200188) (xy 313.808346 -284.21388) (xy 313.852808 -284.234978) (xy 313.893311 -284.262934)
			(xy 313.928804 -284.297026) (xy 313.958369 -284.33637) (xy 313.98124 -284.379947) (xy 313.996824 -284.426628)
			(xy 314.004719 -284.475205) (xy 314.005214 -284.499812) (xy 314.344062 -284.499812) (xy 314.348022 -284.450758)
			(xy 314.359799 -284.402974) (xy 314.37909 -284.357698) (xy 314.405393 -284.316102) (xy 314.438028 -284.279265)
			(xy 314.476149 -284.24814) (xy 314.51877 -284.223533) (xy 314.564786 -284.206081) (xy 314.613005 -284.196237)
			(xy 314.66218 -284.194256) (xy 314.711035 -284.200188) (xy 314.758306 -284.21388) (xy 314.802768 -284.234978)
			(xy 314.843271 -284.262934) (xy 314.878764 -284.297026) (xy 314.908329 -284.33637) (xy 314.9312 -284.379947)
			(xy 314.946784 -284.426628) (xy 314.954679 -284.475205) (xy 314.955174 -284.499812) (xy 314.954679 -284.524419)
			(xy 314.946784 -284.572996) (xy 314.9312 -284.619677) (xy 314.908329 -284.663254) (xy 314.878764 -284.702598)
			(xy 314.843271 -284.73669) (xy 314.802768 -284.764646) (xy 314.758306 -284.785744) (xy 314.711035 -284.799436)
			(xy 314.66218 -284.805368) (xy 314.613005 -284.803387) (xy 314.564786 -284.793543) (xy 314.51877 -284.776091)
			(xy 314.476149 -284.751484) (xy 314.438028 -284.720359) (xy 314.405393 -284.683522) (xy 314.37909 -284.641926)
			(xy 314.359799 -284.59665) (xy 314.348022 -284.548866) (xy 314.344062 -284.499812) (xy 314.005214 -284.499812)
			(xy 314.004719 -284.524419) (xy 313.996824 -284.572996) (xy 313.98124 -284.619677) (xy 313.958369 -284.663254)
			(xy 313.928804 -284.702598) (xy 313.893311 -284.73669) (xy 313.852808 -284.764646) (xy 313.808346 -284.785744)
			(xy 313.761075 -284.799436) (xy 313.71222 -284.805368) (xy 313.663045 -284.803387) (xy 313.614826 -284.793543)
			(xy 313.56881 -284.776091) (xy 313.526189 -284.751484) (xy 313.488068 -284.720359) (xy 313.455433 -284.683522)
			(xy 313.42913 -284.641926) (xy 313.409839 -284.59665) (xy 313.398062 -284.548866) (xy 313.394102 -284.499812)
			(xy 313.076844 -284.499812) (xy 313.07634 -284.52552) (xy 313.068297 -284.576302) (xy 313.052409 -284.625201)
			(xy 313.029066 -284.671013) (xy 312.998845 -284.712609) (xy 312.962489 -284.748965) (xy 312.920893 -284.779186)
			(xy 312.875081 -284.802529) (xy 312.826182 -284.818417) (xy 312.7754 -284.82646) (xy 312.723984 -284.82646)
			(xy 312.673202 -284.818417) (xy 312.624303 -284.802529) (xy 312.578491 -284.779186) (xy 312.536895 -284.748965)
			(xy 312.500539 -284.712609) (xy 312.470318 -284.671013) (xy 312.446975 -284.625201) (xy 312.431087 -284.576302)
			(xy 312.423044 -284.52552) (xy 312.12638 -284.52552) (xy 312.118337 -284.576302) (xy 312.102449 -284.625201)
			(xy 312.079106 -284.671013) (xy 312.048885 -284.712609) (xy 312.012529 -284.748965) (xy 311.970933 -284.779186)
			(xy 311.925121 -284.802529) (xy 311.876222 -284.818417) (xy 311.82544 -284.82646) (xy 311.774024 -284.82646)
			(xy 311.723242 -284.818417) (xy 311.674343 -284.802529) (xy 311.628531 -284.779186) (xy 311.586935 -284.748965)
			(xy 311.550579 -284.712609) (xy 311.520358 -284.671013) (xy 311.497015 -284.625201) (xy 311.481127 -284.576302)
			(xy 311.473084 -284.52552) (xy 311.154406 -284.52552) (xy 311.14669 -284.572996) (xy 311.131106 -284.619677)
			(xy 311.108235 -284.663254) (xy 311.07867 -284.702598) (xy 311.043177 -284.73669) (xy 311.002674 -284.764646)
			(xy 310.958212 -284.785744) (xy 310.910941 -284.799436) (xy 310.862086 -284.805368) (xy 310.812911 -284.803387)
			(xy 310.764692 -284.793543) (xy 310.718676 -284.776091) (xy 310.676055 -284.751484) (xy 310.637934 -284.720359)
			(xy 310.605299 -284.683522) (xy 310.578996 -284.641926) (xy 310.559705 -284.59665) (xy 310.547928 -284.548866)
			(xy 310.543968 -284.499812) (xy 310.226964 -284.499812) (xy 310.22646 -284.52552) (xy 310.218417 -284.576302)
			(xy 310.202529 -284.625201) (xy 310.179186 -284.671013) (xy 310.148965 -284.712609) (xy 310.112609 -284.748965)
			(xy 310.071013 -284.779186) (xy 310.025201 -284.802529) (xy 309.976302 -284.818417) (xy 309.92552 -284.82646)
			(xy 309.874104 -284.82646) (xy 309.823322 -284.818417) (xy 309.774423 -284.802529) (xy 309.728611 -284.779186)
			(xy 309.687015 -284.748965) (xy 309.650659 -284.712609) (xy 309.620438 -284.671013) (xy 309.597095 -284.625201)
			(xy 309.581207 -284.576302) (xy 309.573164 -284.52552) (xy 309.2765 -284.52552) (xy 309.268457 -284.576302)
			(xy 309.252569 -284.625201) (xy 309.229226 -284.671013) (xy 309.199005 -284.712609) (xy 309.162649 -284.748965)
			(xy 309.121053 -284.779186) (xy 309.075241 -284.802529) (xy 309.026342 -284.818417) (xy 308.97556 -284.82646)
			(xy 308.924144 -284.82646) (xy 308.873362 -284.818417) (xy 308.824463 -284.802529) (xy 308.778651 -284.779186)
			(xy 308.737055 -284.748965) (xy 308.700699 -284.712609) (xy 308.670478 -284.671013) (xy 308.647135 -284.625201)
			(xy 308.631247 -284.576302) (xy 308.623204 -284.52552) (xy 308.304526 -284.52552) (xy 308.29681 -284.572996)
			(xy 308.281226 -284.619677) (xy 308.258355 -284.663254) (xy 308.22879 -284.702598) (xy 308.193297 -284.73669)
			(xy 308.152794 -284.764646) (xy 308.108332 -284.785744) (xy 308.061061 -284.799436) (xy 308.012206 -284.805368)
			(xy 307.963031 -284.803387) (xy 307.914812 -284.793543) (xy 307.868796 -284.776091) (xy 307.826175 -284.751484)
			(xy 307.788054 -284.720359) (xy 307.755419 -284.683522) (xy 307.729116 -284.641926) (xy 307.709825 -284.59665)
			(xy 307.698048 -284.548866) (xy 307.694088 -284.499812) (xy 307.354986 -284.499812) (xy 307.354491 -284.524419)
			(xy 307.346596 -284.572996) (xy 307.331012 -284.619677) (xy 307.308141 -284.663254) (xy 307.278576 -284.702598)
			(xy 307.243083 -284.73669) (xy 307.20258 -284.764646) (xy 307.158118 -284.785744) (xy 307.110847 -284.799436)
			(xy 307.061992 -284.805368) (xy 307.012817 -284.803387) (xy 306.964598 -284.793543) (xy 306.918582 -284.776091)
			(xy 306.875961 -284.751484) (xy 306.83784 -284.720359) (xy 306.805205 -284.683522) (xy 306.778902 -284.641926)
			(xy 306.759611 -284.59665) (xy 306.747834 -284.548866) (xy 306.743874 -284.499812) (xy 306.405026 -284.499812)
			(xy 306.404531 -284.524419) (xy 306.396636 -284.572996) (xy 306.381052 -284.619677) (xy 306.358181 -284.663254)
			(xy 306.328616 -284.702598) (xy 306.293123 -284.73669) (xy 306.25262 -284.764646) (xy 306.208158 -284.785744)
			(xy 306.160887 -284.799436) (xy 306.112032 -284.805368) (xy 306.062857 -284.803387) (xy 306.014638 -284.793543)
			(xy 305.968622 -284.776091) (xy 305.926001 -284.751484) (xy 305.88788 -284.720359) (xy 305.855245 -284.683522)
			(xy 305.828942 -284.641926) (xy 305.809651 -284.59665) (xy 305.797874 -284.548866) (xy 305.793914 -284.499812)
			(xy 281.616912 -284.499812) (xy 281.616912 -284.599126) (xy 281.61756 -284.611679) (xy 281.629421 -284.633803)
			(xy 281.639518 -284.64129) (xy 281.720544 -284.695392) (xy 281.745436 -284.697932) (xy 281.757628 -284.692852)
			(xy 281.785665 -284.681952) (xy 281.844649 -284.670183) (xy 281.874722 -284.669484) (xy 281.899977 -284.670007)
			(xy 281.949797 -284.678324) (xy 281.997569 -284.694727) (xy 282.04199 -284.718769) (xy 282.081848 -284.749795)
			(xy 282.116056 -284.786957) (xy 282.143681 -284.829243) (xy 282.163969 -284.875499) (xy 282.176368 -284.924463)
			(xy 282.180538 -284.974792) (xy 282.519132 -284.974792) (xy 282.523092 -284.925738) (xy 282.534869 -284.877954)
			(xy 282.55416 -284.832678) (xy 282.580463 -284.791082) (xy 282.613098 -284.754245) (xy 282.651219 -284.72312)
			(xy 282.69384 -284.698513) (xy 282.739856 -284.681061) (xy 282.788075 -284.671217) (xy 282.83725 -284.669236)
			(xy 282.886105 -284.675168) (xy 282.933376 -284.68886) (xy 282.977838 -284.709958) (xy 283.018341 -284.737914)
			(xy 283.053834 -284.772006) (xy 283.083399 -284.81135) (xy 283.10627 -284.854927) (xy 283.121854 -284.901608)
			(xy 283.129749 -284.950185) (xy 283.130244 -284.974792) (xy 283.469092 -284.974792) (xy 283.473052 -284.925738)
			(xy 283.484829 -284.877954) (xy 283.50412 -284.832678) (xy 283.530423 -284.791082) (xy 283.563058 -284.754245)
			(xy 283.601179 -284.72312) (xy 283.6438 -284.698513) (xy 283.689816 -284.681061) (xy 283.738035 -284.671217)
			(xy 283.78721 -284.669236) (xy 283.836065 -284.675168) (xy 283.883336 -284.68886) (xy 283.927798 -284.709958)
			(xy 283.968301 -284.737914) (xy 284.003794 -284.772006) (xy 284.033359 -284.81135) (xy 284.05623 -284.854927)
			(xy 284.071814 -284.901608) (xy 284.079709 -284.950185) (xy 284.080204 -284.974792) (xy 284.419052 -284.974792)
			(xy 284.423012 -284.925738) (xy 284.434789 -284.877954) (xy 284.45408 -284.832678) (xy 284.480383 -284.791082)
			(xy 284.513018 -284.754245) (xy 284.551139 -284.72312) (xy 284.59376 -284.698513) (xy 284.639776 -284.681061)
			(xy 284.687995 -284.671217) (xy 284.73717 -284.669236) (xy 284.786025 -284.675168) (xy 284.833296 -284.68886)
			(xy 284.877758 -284.709958) (xy 284.918261 -284.737914) (xy 284.953754 -284.772006) (xy 284.983319 -284.81135)
			(xy 285.00619 -284.854927) (xy 285.021774 -284.901608) (xy 285.029669 -284.950185) (xy 285.030164 -284.974792)
			(xy 285.369012 -284.974792) (xy 285.372972 -284.925738) (xy 285.384749 -284.877954) (xy 285.40404 -284.832678)
			(xy 285.430343 -284.791082) (xy 285.462978 -284.754245) (xy 285.501099 -284.72312) (xy 285.54372 -284.698513)
			(xy 285.589736 -284.681061) (xy 285.637955 -284.671217) (xy 285.68713 -284.669236) (xy 285.735985 -284.675168)
			(xy 285.783256 -284.68886) (xy 285.827718 -284.709958) (xy 285.868221 -284.737914) (xy 285.903714 -284.772006)
			(xy 285.933279 -284.81135) (xy 285.95615 -284.854927) (xy 285.971734 -284.901608) (xy 285.979629 -284.950185)
			(xy 285.980124 -284.974792) (xy 286.318972 -284.974792) (xy 286.322932 -284.925738) (xy 286.334709 -284.877954)
			(xy 286.354 -284.832678) (xy 286.380303 -284.791082) (xy 286.412938 -284.754245) (xy 286.451059 -284.72312)
			(xy 286.49368 -284.698513) (xy 286.539696 -284.681061) (xy 286.587915 -284.671217) (xy 286.63709 -284.669236)
			(xy 286.685945 -284.675168) (xy 286.733216 -284.68886) (xy 286.777678 -284.709958) (xy 286.818181 -284.737914)
			(xy 286.853674 -284.772006) (xy 286.883239 -284.81135) (xy 286.90611 -284.854927) (xy 286.921694 -284.901608)
			(xy 286.929589 -284.950185) (xy 286.930084 -284.974792) (xy 287.268932 -284.974792) (xy 287.272892 -284.925738)
			(xy 287.284669 -284.877954) (xy 287.30396 -284.832678) (xy 287.330263 -284.791082) (xy 287.362898 -284.754245)
			(xy 287.401019 -284.72312) (xy 287.44364 -284.698513) (xy 287.489656 -284.681061) (xy 287.537875 -284.671217)
			(xy 287.58705 -284.669236) (xy 287.635905 -284.675168) (xy 287.683176 -284.68886) (xy 287.727638 -284.709958)
			(xy 287.768141 -284.737914) (xy 287.803634 -284.772006) (xy 287.833199 -284.81135) (xy 287.85607 -284.854927)
			(xy 287.871654 -284.901608) (xy 287.879549 -284.950185) (xy 287.880044 -284.974792) (xy 288.218892 -284.974792)
			(xy 288.222852 -284.925738) (xy 288.234629 -284.877954) (xy 288.25392 -284.832678) (xy 288.280223 -284.791082)
			(xy 288.312858 -284.754245) (xy 288.350979 -284.72312) (xy 288.3936 -284.698513) (xy 288.439616 -284.681061)
			(xy 288.487835 -284.671217) (xy 288.53701 -284.669236) (xy 288.585865 -284.675168) (xy 288.633136 -284.68886)
			(xy 288.677598 -284.709958) (xy 288.718101 -284.737914) (xy 288.753594 -284.772006) (xy 288.783159 -284.81135)
			(xy 288.80603 -284.854927) (xy 288.821614 -284.901608) (xy 288.829509 -284.950185) (xy 288.830004 -284.974792)
			(xy 289.169106 -284.974792) (xy 289.173066 -284.925738) (xy 289.184843 -284.877954) (xy 289.204134 -284.832678)
			(xy 289.230437 -284.791082) (xy 289.263072 -284.754245) (xy 289.301193 -284.72312) (xy 289.343814 -284.698513)
			(xy 289.38983 -284.681061) (xy 289.438049 -284.671217) (xy 289.487224 -284.669236) (xy 289.536079 -284.675168)
			(xy 289.58335 -284.68886) (xy 289.627812 -284.709958) (xy 289.668315 -284.737914) (xy 289.703808 -284.772006)
			(xy 289.733373 -284.81135) (xy 289.756244 -284.854927) (xy 289.771828 -284.901608) (xy 289.779723 -284.950185)
			(xy 289.780218 -284.974792) (xy 290.119066 -284.974792) (xy 290.123026 -284.925738) (xy 290.134803 -284.877954)
			(xy 290.154094 -284.832678) (xy 290.180397 -284.791082) (xy 290.213032 -284.754245) (xy 290.251153 -284.72312)
			(xy 290.293774 -284.698513) (xy 290.33979 -284.681061) (xy 290.388009 -284.671217) (xy 290.437184 -284.669236)
			(xy 290.486039 -284.675168) (xy 290.53331 -284.68886) (xy 290.577772 -284.709958) (xy 290.618275 -284.737914)
			(xy 290.653768 -284.772006) (xy 290.683333 -284.81135) (xy 290.706204 -284.854927) (xy 290.721788 -284.901608)
			(xy 290.729683 -284.950185) (xy 290.730178 -284.974792) (xy 292.018986 -284.974792) (xy 292.022946 -284.925738)
			(xy 292.034723 -284.877954) (xy 292.054014 -284.832678) (xy 292.080317 -284.791082) (xy 292.112952 -284.754245)
			(xy 292.151073 -284.72312) (xy 292.193694 -284.698513) (xy 292.23971 -284.681061) (xy 292.287929 -284.671217)
			(xy 292.337104 -284.669236) (xy 292.385959 -284.675168) (xy 292.43323 -284.68886) (xy 292.477692 -284.709958)
			(xy 292.518195 -284.737914) (xy 292.553688 -284.772006) (xy 292.583253 -284.81135) (xy 292.606124 -284.854927)
			(xy 292.621708 -284.901608) (xy 292.629603 -284.950185) (xy 292.630098 -284.974792) (xy 292.968946 -284.974792)
			(xy 292.972906 -284.925738) (xy 292.984683 -284.877954) (xy 293.003974 -284.832678) (xy 293.030277 -284.791082)
			(xy 293.062912 -284.754245) (xy 293.101033 -284.72312) (xy 293.143654 -284.698513) (xy 293.18967 -284.681061)
			(xy 293.237889 -284.671217) (xy 293.287064 -284.669236) (xy 293.335919 -284.675168) (xy 293.38319 -284.68886)
			(xy 293.427652 -284.709958) (xy 293.468155 -284.737914) (xy 293.503648 -284.772006) (xy 293.533213 -284.81135)
			(xy 293.556084 -284.854927) (xy 293.571668 -284.901608) (xy 293.579563 -284.950185) (xy 293.580058 -284.974792)
			(xy 293.918906 -284.974792) (xy 293.922866 -284.925738) (xy 293.934643 -284.877954) (xy 293.953934 -284.832678)
			(xy 293.980237 -284.791082) (xy 294.012872 -284.754245) (xy 294.050993 -284.72312) (xy 294.093614 -284.698513)
			(xy 294.13963 -284.681061) (xy 294.187849 -284.671217) (xy 294.237024 -284.669236) (xy 294.285879 -284.675168)
			(xy 294.33315 -284.68886) (xy 294.377612 -284.709958) (xy 294.418115 -284.737914) (xy 294.453608 -284.772006)
			(xy 294.483173 -284.81135) (xy 294.506044 -284.854927) (xy 294.521628 -284.901608) (xy 294.529523 -284.950185)
			(xy 294.530018 -284.974792) (xy 294.86912 -284.974792) (xy 294.87308 -284.925738) (xy 294.884857 -284.877954)
			(xy 294.904148 -284.832678) (xy 294.930451 -284.791082) (xy 294.963086 -284.754245) (xy 295.001207 -284.72312)
			(xy 295.043828 -284.698513) (xy 295.089844 -284.681061) (xy 295.138063 -284.671217) (xy 295.187238 -284.669236)
			(xy 295.236093 -284.675168) (xy 295.283364 -284.68886) (xy 295.327826 -284.709958) (xy 295.368329 -284.737914)
			(xy 295.403822 -284.772006) (xy 295.433387 -284.81135) (xy 295.456258 -284.854927) (xy 295.471842 -284.901608)
			(xy 295.479737 -284.950185) (xy 295.480232 -284.974792) (xy 295.81908 -284.974792) (xy 295.82304 -284.925738)
			(xy 295.834817 -284.877954) (xy 295.854108 -284.832678) (xy 295.880411 -284.791082) (xy 295.913046 -284.754245)
			(xy 295.951167 -284.72312) (xy 295.993788 -284.698513) (xy 296.039804 -284.681061) (xy 296.088023 -284.671217)
			(xy 296.137198 -284.669236) (xy 296.186053 -284.675168) (xy 296.233324 -284.68886) (xy 296.277786 -284.709958)
			(xy 296.318289 -284.737914) (xy 296.353782 -284.772006) (xy 296.383347 -284.81135) (xy 296.406218 -284.854927)
			(xy 296.421802 -284.901608) (xy 296.429697 -284.950185) (xy 296.430192 -284.974792) (xy 296.76904 -284.974792)
			(xy 296.773 -284.925738) (xy 296.784777 -284.877954) (xy 296.804068 -284.832678) (xy 296.830371 -284.791082)
			(xy 296.863006 -284.754245) (xy 296.901127 -284.72312) (xy 296.943748 -284.698513) (xy 296.989764 -284.681061)
			(xy 297.037983 -284.671217) (xy 297.087158 -284.669236) (xy 297.136013 -284.675168) (xy 297.183284 -284.68886)
			(xy 297.227746 -284.709958) (xy 297.268249 -284.737914) (xy 297.303742 -284.772006) (xy 297.333307 -284.81135)
			(xy 297.356178 -284.854927) (xy 297.371762 -284.901608) (xy 297.379657 -284.950185) (xy 297.380152 -284.974792)
			(xy 297.719 -284.974792) (xy 297.72296 -284.925738) (xy 297.734737 -284.877954) (xy 297.754028 -284.832678)
			(xy 297.780331 -284.791082) (xy 297.812966 -284.754245) (xy 297.851087 -284.72312) (xy 297.893708 -284.698513)
			(xy 297.939724 -284.681061) (xy 297.987943 -284.671217) (xy 298.037118 -284.669236) (xy 298.085973 -284.675168)
			(xy 298.133244 -284.68886) (xy 298.177706 -284.709958) (xy 298.218209 -284.737914) (xy 298.253702 -284.772006)
			(xy 298.283267 -284.81135) (xy 298.306138 -284.854927) (xy 298.321722 -284.901608) (xy 298.329617 -284.950185)
			(xy 298.330112 -284.974792) (xy 298.66896 -284.974792) (xy 298.67292 -284.925738) (xy 298.684697 -284.877954)
			(xy 298.703988 -284.832678) (xy 298.730291 -284.791082) (xy 298.762926 -284.754245) (xy 298.801047 -284.72312)
			(xy 298.843668 -284.698513) (xy 298.889684 -284.681061) (xy 298.937903 -284.671217) (xy 298.987078 -284.669236)
			(xy 299.035933 -284.675168) (xy 299.083204 -284.68886) (xy 299.127666 -284.709958) (xy 299.168169 -284.737914)
			(xy 299.203662 -284.772006) (xy 299.233227 -284.81135) (xy 299.256098 -284.854927) (xy 299.271682 -284.901608)
			(xy 299.279577 -284.950185) (xy 299.280072 -284.974792) (xy 299.61892 -284.974792) (xy 299.62288 -284.925738)
			(xy 299.634657 -284.877954) (xy 299.653948 -284.832678) (xy 299.680251 -284.791082) (xy 299.712886 -284.754245)
			(xy 299.751007 -284.72312) (xy 299.793628 -284.698513) (xy 299.839644 -284.681061) (xy 299.887863 -284.671217)
			(xy 299.937038 -284.669236) (xy 299.985893 -284.675168) (xy 300.033164 -284.68886) (xy 300.077626 -284.709958)
			(xy 300.118129 -284.737914) (xy 300.153622 -284.772006) (xy 300.183187 -284.81135) (xy 300.206058 -284.854927)
			(xy 300.221642 -284.901608) (xy 300.229537 -284.950185) (xy 300.230032 -284.974792) (xy 300.56888 -284.974792)
			(xy 300.57284 -284.925738) (xy 300.584617 -284.877954) (xy 300.603908 -284.832678) (xy 300.630211 -284.791082)
			(xy 300.662846 -284.754245) (xy 300.700967 -284.72312) (xy 300.743588 -284.698513) (xy 300.789604 -284.681061)
			(xy 300.837823 -284.671217) (xy 300.886998 -284.669236) (xy 300.935853 -284.675168) (xy 300.983124 -284.68886)
			(xy 301.027586 -284.709958) (xy 301.068089 -284.737914) (xy 301.103582 -284.772006) (xy 301.133147 -284.81135)
			(xy 301.156018 -284.854927) (xy 301.171602 -284.901608) (xy 301.179497 -284.950185) (xy 301.179992 -284.974792)
			(xy 301.519094 -284.974792) (xy 301.523054 -284.925738) (xy 301.534831 -284.877954) (xy 301.554122 -284.832678)
			(xy 301.580425 -284.791082) (xy 301.61306 -284.754245) (xy 301.651181 -284.72312) (xy 301.693802 -284.698513)
			(xy 301.739818 -284.681061) (xy 301.788037 -284.671217) (xy 301.837212 -284.669236) (xy 301.886067 -284.675168)
			(xy 301.933338 -284.68886) (xy 301.9778 -284.709958) (xy 302.018303 -284.737914) (xy 302.053796 -284.772006)
			(xy 302.083361 -284.81135) (xy 302.106232 -284.854927) (xy 302.121816 -284.901608) (xy 302.129711 -284.950185)
			(xy 302.130206 -284.974792) (xy 302.469054 -284.974792) (xy 302.473014 -284.925738) (xy 302.484791 -284.877954)
			(xy 302.504082 -284.832678) (xy 302.530385 -284.791082) (xy 302.56302 -284.754245) (xy 302.601141 -284.72312)
			(xy 302.643762 -284.698513) (xy 302.689778 -284.681061) (xy 302.737997 -284.671217) (xy 302.787172 -284.669236)
			(xy 302.836027 -284.675168) (xy 302.883298 -284.68886) (xy 302.92776 -284.709958) (xy 302.968263 -284.737914)
			(xy 303.003756 -284.772006) (xy 303.033321 -284.81135) (xy 303.056192 -284.854927) (xy 303.071776 -284.901608)
			(xy 303.079671 -284.950185) (xy 303.080166 -284.974792) (xy 303.079671 -284.999399) (xy 303.071776 -285.047976)
			(xy 303.056192 -285.094657) (xy 303.033321 -285.138234) (xy 303.003756 -285.177578) (xy 302.968263 -285.21167)
			(xy 302.92776 -285.239626) (xy 302.883298 -285.260724) (xy 302.836027 -285.274416) (xy 302.787172 -285.280348)
			(xy 302.737997 -285.278367) (xy 302.689778 -285.268523) (xy 302.643762 -285.251071) (xy 302.601141 -285.226464)
			(xy 302.56302 -285.195339) (xy 302.530385 -285.158502) (xy 302.504082 -285.116906) (xy 302.484791 -285.07163)
			(xy 302.473014 -285.023846) (xy 302.469054 -284.974792) (xy 302.130206 -284.974792) (xy 302.129711 -284.999399)
			(xy 302.121816 -285.047976) (xy 302.106232 -285.094657) (xy 302.083361 -285.138234) (xy 302.053796 -285.177578)
			(xy 302.018303 -285.21167) (xy 301.9778 -285.239626) (xy 301.933338 -285.260724) (xy 301.886067 -285.274416)
			(xy 301.837212 -285.280348) (xy 301.788037 -285.278367) (xy 301.739818 -285.268523) (xy 301.693802 -285.251071)
			(xy 301.651181 -285.226464) (xy 301.61306 -285.195339) (xy 301.580425 -285.158502) (xy 301.554122 -285.116906)
			(xy 301.534831 -285.07163) (xy 301.523054 -285.023846) (xy 301.519094 -284.974792) (xy 301.179992 -284.974792)
			(xy 301.179497 -284.999399) (xy 301.171602 -285.047976) (xy 301.156018 -285.094657) (xy 301.133147 -285.138234)
			(xy 301.103582 -285.177578) (xy 301.068089 -285.21167) (xy 301.027586 -285.239626) (xy 300.983124 -285.260724)
			(xy 300.935853 -285.274416) (xy 300.886998 -285.280348) (xy 300.837823 -285.278367) (xy 300.789604 -285.268523)
			(xy 300.743588 -285.251071) (xy 300.700967 -285.226464) (xy 300.662846 -285.195339) (xy 300.630211 -285.158502)
			(xy 300.603908 -285.116906) (xy 300.584617 -285.07163) (xy 300.57284 -285.023846) (xy 300.56888 -284.974792)
			(xy 300.230032 -284.974792) (xy 300.229537 -284.999399) (xy 300.221642 -285.047976) (xy 300.206058 -285.094657)
			(xy 300.183187 -285.138234) (xy 300.153622 -285.177578) (xy 300.118129 -285.21167) (xy 300.077626 -285.239626)
			(xy 300.033164 -285.260724) (xy 299.985893 -285.274416) (xy 299.937038 -285.280348) (xy 299.887863 -285.278367)
			(xy 299.839644 -285.268523) (xy 299.793628 -285.251071) (xy 299.751007 -285.226464) (xy 299.712886 -285.195339)
			(xy 299.680251 -285.158502) (xy 299.653948 -285.116906) (xy 299.634657 -285.07163) (xy 299.62288 -285.023846)
			(xy 299.61892 -284.974792) (xy 299.280072 -284.974792) (xy 299.279577 -284.999399) (xy 299.271682 -285.047976)
			(xy 299.256098 -285.094657) (xy 299.233227 -285.138234) (xy 299.203662 -285.177578) (xy 299.168169 -285.21167)
			(xy 299.127666 -285.239626) (xy 299.083204 -285.260724) (xy 299.035933 -285.274416) (xy 298.987078 -285.280348)
			(xy 298.937903 -285.278367) (xy 298.889684 -285.268523) (xy 298.843668 -285.251071) (xy 298.801047 -285.226464)
			(xy 298.762926 -285.195339) (xy 298.730291 -285.158502) (xy 298.703988 -285.116906) (xy 298.684697 -285.07163)
			(xy 298.67292 -285.023846) (xy 298.66896 -284.974792) (xy 298.330112 -284.974792) (xy 298.329617 -284.999399)
			(xy 298.321722 -285.047976) (xy 298.306138 -285.094657) (xy 298.283267 -285.138234) (xy 298.253702 -285.177578)
			(xy 298.218209 -285.21167) (xy 298.177706 -285.239626) (xy 298.133244 -285.260724) (xy 298.085973 -285.274416)
			(xy 298.037118 -285.280348) (xy 297.987943 -285.278367) (xy 297.939724 -285.268523) (xy 297.893708 -285.251071)
			(xy 297.851087 -285.226464) (xy 297.812966 -285.195339) (xy 297.780331 -285.158502) (xy 297.754028 -285.116906)
			(xy 297.734737 -285.07163) (xy 297.72296 -285.023846) (xy 297.719 -284.974792) (xy 297.380152 -284.974792)
			(xy 297.379657 -284.999399) (xy 297.371762 -285.047976) (xy 297.356178 -285.094657) (xy 297.333307 -285.138234)
			(xy 297.303742 -285.177578) (xy 297.268249 -285.21167) (xy 297.227746 -285.239626) (xy 297.183284 -285.260724)
			(xy 297.136013 -285.274416) (xy 297.087158 -285.280348) (xy 297.037983 -285.278367) (xy 296.989764 -285.268523)
			(xy 296.943748 -285.251071) (xy 296.901127 -285.226464) (xy 296.863006 -285.195339) (xy 296.830371 -285.158502)
			(xy 296.804068 -285.116906) (xy 296.784777 -285.07163) (xy 296.773 -285.023846) (xy 296.76904 -284.974792)
			(xy 296.430192 -284.974792) (xy 296.429697 -284.999399) (xy 296.421802 -285.047976) (xy 296.406218 -285.094657)
			(xy 296.383347 -285.138234) (xy 296.353782 -285.177578) (xy 296.318289 -285.21167) (xy 296.277786 -285.239626)
			(xy 296.233324 -285.260724) (xy 296.186053 -285.274416) (xy 296.137198 -285.280348) (xy 296.088023 -285.278367)
			(xy 296.039804 -285.268523) (xy 295.993788 -285.251071) (xy 295.951167 -285.226464) (xy 295.913046 -285.195339)
			(xy 295.880411 -285.158502) (xy 295.854108 -285.116906) (xy 295.834817 -285.07163) (xy 295.82304 -285.023846)
			(xy 295.81908 -284.974792) (xy 295.480232 -284.974792) (xy 295.479737 -284.999399) (xy 295.471842 -285.047976)
			(xy 295.456258 -285.094657) (xy 295.433387 -285.138234) (xy 295.403822 -285.177578) (xy 295.368329 -285.21167)
			(xy 295.327826 -285.239626) (xy 295.283364 -285.260724) (xy 295.236093 -285.274416) (xy 295.187238 -285.280348)
			(xy 295.138063 -285.278367) (xy 295.089844 -285.268523) (xy 295.043828 -285.251071) (xy 295.001207 -285.226464)
			(xy 294.963086 -285.195339) (xy 294.930451 -285.158502) (xy 294.904148 -285.116906) (xy 294.884857 -285.07163)
			(xy 294.87308 -285.023846) (xy 294.86912 -284.974792) (xy 294.530018 -284.974792) (xy 294.529523 -284.999399)
			(xy 294.521628 -285.047976) (xy 294.506044 -285.094657) (xy 294.483173 -285.138234) (xy 294.453608 -285.177578)
			(xy 294.418115 -285.21167) (xy 294.377612 -285.239626) (xy 294.33315 -285.260724) (xy 294.285879 -285.274416)
			(xy 294.237024 -285.280348) (xy 294.187849 -285.278367) (xy 294.13963 -285.268523) (xy 294.093614 -285.251071)
			(xy 294.050993 -285.226464) (xy 294.012872 -285.195339) (xy 293.980237 -285.158502) (xy 293.953934 -285.116906)
			(xy 293.934643 -285.07163) (xy 293.922866 -285.023846) (xy 293.918906 -284.974792) (xy 293.580058 -284.974792)
			(xy 293.579563 -284.999399) (xy 293.571668 -285.047976) (xy 293.556084 -285.094657) (xy 293.533213 -285.138234)
			(xy 293.503648 -285.177578) (xy 293.468155 -285.21167) (xy 293.427652 -285.239626) (xy 293.38319 -285.260724)
			(xy 293.335919 -285.274416) (xy 293.287064 -285.280348) (xy 293.237889 -285.278367) (xy 293.18967 -285.268523)
			(xy 293.143654 -285.251071) (xy 293.101033 -285.226464) (xy 293.062912 -285.195339) (xy 293.030277 -285.158502)
			(xy 293.003974 -285.116906) (xy 292.984683 -285.07163) (xy 292.972906 -285.023846) (xy 292.968946 -284.974792)
			(xy 292.630098 -284.974792) (xy 292.629603 -284.999399) (xy 292.621708 -285.047976) (xy 292.606124 -285.094657)
			(xy 292.583253 -285.138234) (xy 292.553688 -285.177578) (xy 292.518195 -285.21167) (xy 292.477692 -285.239626)
			(xy 292.43323 -285.260724) (xy 292.385959 -285.274416) (xy 292.337104 -285.280348) (xy 292.287929 -285.278367)
			(xy 292.23971 -285.268523) (xy 292.193694 -285.251071) (xy 292.151073 -285.226464) (xy 292.112952 -285.195339)
			(xy 292.080317 -285.158502) (xy 292.054014 -285.116906) (xy 292.034723 -285.07163) (xy 292.022946 -285.023846)
			(xy 292.018986 -284.974792) (xy 290.730178 -284.974792) (xy 290.729683 -284.999399) (xy 290.721788 -285.047976)
			(xy 290.706204 -285.094657) (xy 290.683333 -285.138234) (xy 290.653768 -285.177578) (xy 290.618275 -285.21167)
			(xy 290.577772 -285.239626) (xy 290.53331 -285.260724) (xy 290.486039 -285.274416) (xy 290.437184 -285.280348)
			(xy 290.388009 -285.278367) (xy 290.33979 -285.268523) (xy 290.293774 -285.251071) (xy 290.251153 -285.226464)
			(xy 290.213032 -285.195339) (xy 290.180397 -285.158502) (xy 290.154094 -285.116906) (xy 290.134803 -285.07163)
			(xy 290.123026 -285.023846) (xy 290.119066 -284.974792) (xy 289.780218 -284.974792) (xy 289.779723 -284.999399)
			(xy 289.771828 -285.047976) (xy 289.756244 -285.094657) (xy 289.733373 -285.138234) (xy 289.703808 -285.177578)
			(xy 289.668315 -285.21167) (xy 289.627812 -285.239626) (xy 289.58335 -285.260724) (xy 289.536079 -285.274416)
			(xy 289.487224 -285.280348) (xy 289.438049 -285.278367) (xy 289.38983 -285.268523) (xy 289.343814 -285.251071)
			(xy 289.301193 -285.226464) (xy 289.263072 -285.195339) (xy 289.230437 -285.158502) (xy 289.204134 -285.116906)
			(xy 289.184843 -285.07163) (xy 289.173066 -285.023846) (xy 289.169106 -284.974792) (xy 288.830004 -284.974792)
			(xy 288.829509 -284.999399) (xy 288.821614 -285.047976) (xy 288.80603 -285.094657) (xy 288.783159 -285.138234)
			(xy 288.753594 -285.177578) (xy 288.718101 -285.21167) (xy 288.677598 -285.239626) (xy 288.633136 -285.260724)
			(xy 288.585865 -285.274416) (xy 288.53701 -285.280348) (xy 288.487835 -285.278367) (xy 288.439616 -285.268523)
			(xy 288.3936 -285.251071) (xy 288.350979 -285.226464) (xy 288.312858 -285.195339) (xy 288.280223 -285.158502)
			(xy 288.25392 -285.116906) (xy 288.234629 -285.07163) (xy 288.222852 -285.023846) (xy 288.218892 -284.974792)
			(xy 287.880044 -284.974792) (xy 287.879549 -284.999399) (xy 287.871654 -285.047976) (xy 287.85607 -285.094657)
			(xy 287.833199 -285.138234) (xy 287.803634 -285.177578) (xy 287.768141 -285.21167) (xy 287.727638 -285.239626)
			(xy 287.683176 -285.260724) (xy 287.635905 -285.274416) (xy 287.58705 -285.280348) (xy 287.537875 -285.278367)
			(xy 287.489656 -285.268523) (xy 287.44364 -285.251071) (xy 287.401019 -285.226464) (xy 287.362898 -285.195339)
			(xy 287.330263 -285.158502) (xy 287.30396 -285.116906) (xy 287.284669 -285.07163) (xy 287.272892 -285.023846)
			(xy 287.268932 -284.974792) (xy 286.930084 -284.974792) (xy 286.929589 -284.999399) (xy 286.921694 -285.047976)
			(xy 286.90611 -285.094657) (xy 286.883239 -285.138234) (xy 286.853674 -285.177578) (xy 286.818181 -285.21167)
			(xy 286.777678 -285.239626) (xy 286.733216 -285.260724) (xy 286.685945 -285.274416) (xy 286.63709 -285.280348)
			(xy 286.587915 -285.278367) (xy 286.539696 -285.268523) (xy 286.49368 -285.251071) (xy 286.451059 -285.226464)
			(xy 286.412938 -285.195339) (xy 286.380303 -285.158502) (xy 286.354 -285.116906) (xy 286.334709 -285.07163)
			(xy 286.322932 -285.023846) (xy 286.318972 -284.974792) (xy 285.980124 -284.974792) (xy 285.979629 -284.999399)
			(xy 285.971734 -285.047976) (xy 285.95615 -285.094657) (xy 285.933279 -285.138234) (xy 285.903714 -285.177578)
			(xy 285.868221 -285.21167) (xy 285.827718 -285.239626) (xy 285.783256 -285.260724) (xy 285.735985 -285.274416)
			(xy 285.68713 -285.280348) (xy 285.637955 -285.278367) (xy 285.589736 -285.268523) (xy 285.54372 -285.251071)
			(xy 285.501099 -285.226464) (xy 285.462978 -285.195339) (xy 285.430343 -285.158502) (xy 285.40404 -285.116906)
			(xy 285.384749 -285.07163) (xy 285.372972 -285.023846) (xy 285.369012 -284.974792) (xy 285.030164 -284.974792)
			(xy 285.029669 -284.999399) (xy 285.021774 -285.047976) (xy 285.00619 -285.094657) (xy 284.983319 -285.138234)
			(xy 284.953754 -285.177578) (xy 284.918261 -285.21167) (xy 284.877758 -285.239626) (xy 284.833296 -285.260724)
			(xy 284.786025 -285.274416) (xy 284.73717 -285.280348) (xy 284.687995 -285.278367) (xy 284.639776 -285.268523)
			(xy 284.59376 -285.251071) (xy 284.551139 -285.226464) (xy 284.513018 -285.195339) (xy 284.480383 -285.158502)
			(xy 284.45408 -285.116906) (xy 284.434789 -285.07163) (xy 284.423012 -285.023846) (xy 284.419052 -284.974792)
			(xy 284.080204 -284.974792) (xy 284.079709 -284.999399) (xy 284.071814 -285.047976) (xy 284.05623 -285.094657)
			(xy 284.033359 -285.138234) (xy 284.003794 -285.177578) (xy 283.968301 -285.21167) (xy 283.927798 -285.239626)
			(xy 283.883336 -285.260724) (xy 283.836065 -285.274416) (xy 283.78721 -285.280348) (xy 283.738035 -285.278367)
			(xy 283.689816 -285.268523) (xy 283.6438 -285.251071) (xy 283.601179 -285.226464) (xy 283.563058 -285.195339)
			(xy 283.530423 -285.158502) (xy 283.50412 -285.116906) (xy 283.484829 -285.07163) (xy 283.473052 -285.023846)
			(xy 283.469092 -284.974792) (xy 283.130244 -284.974792) (xy 283.129749 -284.999399) (xy 283.121854 -285.047976)
			(xy 283.10627 -285.094657) (xy 283.083399 -285.138234) (xy 283.053834 -285.177578) (xy 283.018341 -285.21167)
			(xy 282.977838 -285.239626) (xy 282.933376 -285.260724) (xy 282.886105 -285.274416) (xy 282.83725 -285.280348)
			(xy 282.788075 -285.278367) (xy 282.739856 -285.268523) (xy 282.69384 -285.251071) (xy 282.651219 -285.226464)
			(xy 282.613098 -285.195339) (xy 282.580463 -285.158502) (xy 282.55416 -285.116906) (xy 282.534869 -285.07163)
			(xy 282.523092 -285.023846) (xy 282.519132 -284.974792) (xy 282.180538 -284.974792) (xy 282.180539 -284.9748)
			(xy 282.176368 -285.025137) (xy 282.163969 -285.074101) (xy 282.143681 -285.120357) (xy 282.116056 -285.162643)
			(xy 282.081848 -285.199805) (xy 282.04199 -285.230831) (xy 281.997569 -285.254873) (xy 281.949797 -285.271276)
			(xy 281.899977 -285.279593) (xy 281.874722 -285.2801) (xy 281.844648 -285.279407) (xy 281.785662 -285.267641)
			(xy 281.757628 -285.256732) (xy 281.745436 -285.251652) (xy 281.720544 -285.254192) (xy 281.639518 -285.308294)
			(xy 281.629461 -285.315813) (xy 281.617611 -285.33792) (xy 281.616912 -285.350458) (xy 281.616912 -285.449772)
			(xy 305.793914 -285.449772) (xy 305.797874 -285.400718) (xy 305.809651 -285.352934) (xy 305.828942 -285.307658)
			(xy 305.855245 -285.266062) (xy 305.88788 -285.229225) (xy 305.926001 -285.1981) (xy 305.968622 -285.173493)
			(xy 306.014638 -285.156041) (xy 306.062857 -285.146197) (xy 306.112032 -285.144216) (xy 306.160887 -285.150148)
			(xy 306.208158 -285.16384) (xy 306.25262 -285.184938) (xy 306.293123 -285.212894) (xy 306.328616 -285.246986)
			(xy 306.358181 -285.28633) (xy 306.381052 -285.329907) (xy 306.396636 -285.376588) (xy 306.404531 -285.425165)
			(xy 306.405026 -285.449772) (xy 306.404531 -285.474379) (xy 306.404352 -285.47548) (xy 306.72303 -285.47548)
			(xy 306.72303 -285.424064) (xy 306.731073 -285.373282) (xy 306.746961 -285.324383) (xy 306.770304 -285.278571)
			(xy 306.800525 -285.236975) (xy 306.836881 -285.200619) (xy 306.878477 -285.170398) (xy 306.924289 -285.147055)
			(xy 306.973188 -285.131167) (xy 307.02397 -285.123124) (xy 307.075386 -285.123124) (xy 307.126168 -285.131167)
			(xy 307.175067 -285.147055) (xy 307.220879 -285.170398) (xy 307.262475 -285.200619) (xy 307.298831 -285.236975)
			(xy 307.329052 -285.278571) (xy 307.352395 -285.324383) (xy 307.368283 -285.373282) (xy 307.376326 -285.424064)
			(xy 307.37683 -285.449772) (xy 307.376326 -285.47548) (xy 307.673244 -285.47548) (xy 307.673244 -285.424064)
			(xy 307.681287 -285.373282) (xy 307.697175 -285.324383) (xy 307.720518 -285.278571) (xy 307.750739 -285.236975)
			(xy 307.787095 -285.200619) (xy 307.828691 -285.170398) (xy 307.874503 -285.147055) (xy 307.923402 -285.131167)
			(xy 307.974184 -285.123124) (xy 308.0256 -285.123124) (xy 308.076382 -285.131167) (xy 308.125281 -285.147055)
			(xy 308.171093 -285.170398) (xy 308.212689 -285.200619) (xy 308.249045 -285.236975) (xy 308.279266 -285.278571)
			(xy 308.302609 -285.324383) (xy 308.318497 -285.373282) (xy 308.32654 -285.424064) (xy 308.327044 -285.449772)
			(xy 308.644048 -285.449772) (xy 308.648008 -285.400718) (xy 308.659785 -285.352934) (xy 308.679076 -285.307658)
			(xy 308.705379 -285.266062) (xy 308.738014 -285.229225) (xy 308.776135 -285.1981) (xy 308.818756 -285.173493)
			(xy 308.864772 -285.156041) (xy 308.912991 -285.146197) (xy 308.962166 -285.144216) (xy 309.011021 -285.150148)
			(xy 309.058292 -285.16384) (xy 309.102754 -285.184938) (xy 309.143257 -285.212894) (xy 309.17875 -285.246986)
			(xy 309.208315 -285.28633) (xy 309.231186 -285.329907) (xy 309.24677 -285.376588) (xy 309.254665 -285.425165)
			(xy 309.25516 -285.449772) (xy 309.594008 -285.449772) (xy 309.597968 -285.400718) (xy 309.609745 -285.352934)
			(xy 309.629036 -285.307658) (xy 309.655339 -285.266062) (xy 309.687974 -285.229225) (xy 309.726095 -285.1981)
			(xy 309.768716 -285.173493) (xy 309.814732 -285.156041) (xy 309.862951 -285.146197) (xy 309.912126 -285.144216)
			(xy 309.960981 -285.150148) (xy 310.008252 -285.16384) (xy 310.052714 -285.184938) (xy 310.093217 -285.212894)
			(xy 310.12871 -285.246986) (xy 310.158275 -285.28633) (xy 310.181146 -285.329907) (xy 310.19673 -285.376588)
			(xy 310.204625 -285.425165) (xy 310.20512 -285.449772) (xy 310.543968 -285.449772) (xy 310.547928 -285.400718)
			(xy 310.559705 -285.352934) (xy 310.578996 -285.307658) (xy 310.605299 -285.266062) (xy 310.637934 -285.229225)
			(xy 310.676055 -285.1981) (xy 310.718676 -285.173493) (xy 310.764692 -285.156041) (xy 310.812911 -285.146197)
			(xy 310.862086 -285.144216) (xy 310.910941 -285.150148) (xy 310.958212 -285.16384) (xy 311.002674 -285.184938)
			(xy 311.043177 -285.212894) (xy 311.07867 -285.246986) (xy 311.108235 -285.28633) (xy 311.131106 -285.329907)
			(xy 311.14669 -285.376588) (xy 311.154585 -285.425165) (xy 311.15508 -285.449772) (xy 311.493928 -285.449772)
			(xy 311.497888 -285.400718) (xy 311.509665 -285.352934) (xy 311.528956 -285.307658) (xy 311.555259 -285.266062)
			(xy 311.587894 -285.229225) (xy 311.626015 -285.1981) (xy 311.668636 -285.173493) (xy 311.714652 -285.156041)
			(xy 311.762871 -285.146197) (xy 311.812046 -285.144216) (xy 311.860901 -285.150148) (xy 311.908172 -285.16384)
			(xy 311.952634 -285.184938) (xy 311.993137 -285.212894) (xy 312.02863 -285.246986) (xy 312.058195 -285.28633)
			(xy 312.081066 -285.329907) (xy 312.09665 -285.376588) (xy 312.104545 -285.425165) (xy 312.10504 -285.449772)
			(xy 312.443888 -285.449772) (xy 312.447848 -285.400718) (xy 312.459625 -285.352934) (xy 312.478916 -285.307658)
			(xy 312.505219 -285.266062) (xy 312.537854 -285.229225) (xy 312.575975 -285.1981) (xy 312.618596 -285.173493)
			(xy 312.664612 -285.156041) (xy 312.712831 -285.146197) (xy 312.762006 -285.144216) (xy 312.810861 -285.150148)
			(xy 312.858132 -285.16384) (xy 312.902594 -285.184938) (xy 312.943097 -285.212894) (xy 312.97859 -285.246986)
			(xy 313.008155 -285.28633) (xy 313.031026 -285.329907) (xy 313.04661 -285.376588) (xy 313.054505 -285.425165)
			(xy 313.055 -285.449772) (xy 313.054505 -285.474379) (xy 313.054326 -285.47548) (xy 313.373258 -285.47548)
			(xy 313.373258 -285.424064) (xy 313.381301 -285.373282) (xy 313.397189 -285.324383) (xy 313.420532 -285.278571)
			(xy 313.450753 -285.236975) (xy 313.487109 -285.200619) (xy 313.528705 -285.170398) (xy 313.574517 -285.147055)
			(xy 313.623416 -285.131167) (xy 313.674198 -285.123124) (xy 313.725614 -285.123124) (xy 313.776396 -285.131167)
			(xy 313.825295 -285.147055) (xy 313.871107 -285.170398) (xy 313.912703 -285.200619) (xy 313.949059 -285.236975)
			(xy 313.97928 -285.278571) (xy 314.002623 -285.324383) (xy 314.018511 -285.373282) (xy 314.026554 -285.424064)
			(xy 314.027058 -285.449772) (xy 314.026554 -285.47548) (xy 314.323218 -285.47548) (xy 314.323218 -285.424064)
			(xy 314.331261 -285.373282) (xy 314.347149 -285.324383) (xy 314.370492 -285.278571) (xy 314.400713 -285.236975)
			(xy 314.437069 -285.200619) (xy 314.478665 -285.170398) (xy 314.524477 -285.147055) (xy 314.573376 -285.131167)
			(xy 314.624158 -285.123124) (xy 314.675574 -285.123124) (xy 314.726356 -285.131167) (xy 314.775255 -285.147055)
			(xy 314.821067 -285.170398) (xy 314.862663 -285.200619) (xy 314.899019 -285.236975) (xy 314.92924 -285.278571)
			(xy 314.952583 -285.324383) (xy 314.968471 -285.373282) (xy 314.976514 -285.424064) (xy 314.977018 -285.449772)
			(xy 314.977013 -285.450026) (xy 315.294276 -285.450026) (xy 315.298236 -285.400972) (xy 315.310013 -285.353188)
			(xy 315.329304 -285.307912) (xy 315.355607 -285.266316) (xy 315.388242 -285.229479) (xy 315.426363 -285.198354)
			(xy 315.468984 -285.173747) (xy 315.515 -285.156295) (xy 315.563219 -285.146451) (xy 315.612394 -285.14447)
			(xy 315.661249 -285.150402) (xy 315.70852 -285.164094) (xy 315.752982 -285.185192) (xy 315.793485 -285.213148)
			(xy 315.828978 -285.24724) (xy 315.858543 -285.286584) (xy 315.881414 -285.330161) (xy 315.896998 -285.376842)
			(xy 315.904893 -285.425419) (xy 315.905388 -285.450026) (xy 315.904893 -285.474633) (xy 315.897788 -285.518352)
			(xy 323.668134 -285.518352) (xy 323.672205 -285.46273) (xy 323.684331 -285.408293) (xy 323.704254 -285.356202)
			(xy 323.73155 -285.307567) (xy 323.765636 -285.263424) (xy 323.805785 -285.224715) (xy 323.851143 -285.192264)
			(xy 323.900743 -285.166763) (xy 323.953527 -285.148756) (xy 324.00837 -285.138626) (xy 324.064104 -285.136589)
			(xy 324.119541 -285.142689) (xy 324.173498 -285.156795) (xy 324.224827 -285.178607) (xy 324.272433 -285.207661)
			(xy 324.315301 -285.243336) (xy 324.352518 -285.284873) (xy 324.383291 -285.331386) (xy 324.406963 -285.381883)
			(xy 324.423031 -285.43529) (xy 324.431151 -285.490466) (xy 324.43166 -285.518352) (xy 324.431151 -285.546238)
			(xy 324.423031 -285.601414) (xy 324.406963 -285.654821) (xy 324.383291 -285.705318) (xy 324.363308 -285.735522)
			(xy 328.755502 -285.735522) (xy 328.755917 -285.708786) (xy 328.763382 -285.655838) (xy 328.778169 -285.604451)
			(xy 328.799988 -285.555633) (xy 328.828411 -285.510341) (xy 328.862881 -285.469463) (xy 328.882502 -285.451296)
			(xy 328.89063 -285.444184) (xy 328.899266 -285.425388) (xy 328.901806 -285.330392) (xy 328.89444 -285.311342)
			(xy 328.88682 -285.303722) (xy 328.866067 -285.282129) (xy 328.830894 -285.23366) (xy 328.803731 -285.180287)
			(xy 328.785246 -285.123324) (xy 328.775895 -285.064172) (xy 328.775314 -285.034228) (xy 328.7758 -285.006977)
			(xy 328.783556 -284.953029) (xy 328.798911 -284.900734) (xy 328.821553 -284.851157) (xy 328.851019 -284.805307)
			(xy 328.88671 -284.764116) (xy 328.927901 -284.728425) (xy 328.973751 -284.698959) (xy 329.023328 -284.676317)
			(xy 329.075623 -284.660962) (xy 329.129571 -284.653206) (xy 329.184073 -284.653206) (xy 329.238021 -284.660962)
			(xy 329.290316 -284.676317) (xy 329.339893 -284.698959) (xy 329.385743 -284.728425) (xy 329.426934 -284.764116)
			(xy 329.462625 -284.805307) (xy 329.492091 -284.851157) (xy 329.514733 -284.900734) (xy 329.530088 -284.953029)
			(xy 329.537844 -285.006977) (xy 329.53833 -285.034228) (xy 329.537871 -285.060962) (xy 329.530414 -285.113908)
			(xy 329.515635 -285.165294) (xy 329.493824 -285.214111) (xy 329.465409 -285.259405) (xy 329.430947 -285.300285)
			(xy 329.41133 -285.318454) (xy 329.403202 -285.325566) (xy 329.394566 -285.344362) (xy 329.392026 -285.439358)
			(xy 329.399392 -285.458408) (xy 329.407012 -285.466028) (xy 329.427747 -285.487637) (xy 329.462921 -285.536103)
			(xy 329.490087 -285.589472) (xy 329.508576 -285.646431) (xy 329.517934 -285.70558) (xy 329.518518 -285.735522)
			(xy 329.518032 -285.762773) (xy 329.510276 -285.816721) (xy 329.494921 -285.869016) (xy 329.472279 -285.918593)
			(xy 329.442813 -285.964443) (xy 329.407122 -286.005634) (xy 329.365931 -286.041325) (xy 329.320081 -286.070791)
			(xy 329.270504 -286.093433) (xy 329.218209 -286.108788) (xy 329.164261 -286.116544) (xy 329.109759 -286.116544)
			(xy 329.055811 -286.108788) (xy 329.003516 -286.093433) (xy 328.953939 -286.070791) (xy 328.908089 -286.041325)
			(xy 328.866898 -286.005634) (xy 328.831207 -285.964443) (xy 328.801741 -285.918593) (xy 328.779099 -285.869016)
			(xy 328.763744 -285.816721) (xy 328.755988 -285.762773) (xy 328.755502 -285.735522) (xy 324.363308 -285.735522)
			(xy 324.352518 -285.751831) (xy 324.315301 -285.793368) (xy 324.272433 -285.829043) (xy 324.224827 -285.858097)
			(xy 324.173498 -285.879909) (xy 324.119541 -285.894015) (xy 324.064104 -285.900115) (xy 324.00837 -285.898078)
			(xy 323.953527 -285.887948) (xy 323.900743 -285.869941) (xy 323.851143 -285.84444) (xy 323.805785 -285.811989)
			(xy 323.765636 -285.77328) (xy 323.73155 -285.729137) (xy 323.704254 -285.680502) (xy 323.684331 -285.628411)
			(xy 323.672205 -285.573974) (xy 323.668134 -285.518352) (xy 315.897788 -285.518352) (xy 315.896998 -285.52321)
			(xy 315.881414 -285.569891) (xy 315.858543 -285.613468) (xy 315.828978 -285.652812) (xy 315.793485 -285.686904)
			(xy 315.752982 -285.71486) (xy 315.70852 -285.735958) (xy 315.661249 -285.74965) (xy 315.612394 -285.755582)
			(xy 315.563219 -285.753601) (xy 315.515 -285.743757) (xy 315.468984 -285.726305) (xy 315.426363 -285.701698)
			(xy 315.388242 -285.670573) (xy 315.355607 -285.633736) (xy 315.329304 -285.59214) (xy 315.310013 -285.546864)
			(xy 315.298236 -285.49908) (xy 315.294276 -285.450026) (xy 314.977013 -285.450026) (xy 314.976514 -285.47548)
			(xy 314.968471 -285.526262) (xy 314.952583 -285.575161) (xy 314.92924 -285.620973) (xy 314.899019 -285.662569)
			(xy 314.862663 -285.698925) (xy 314.821067 -285.729146) (xy 314.775255 -285.752489) (xy 314.726356 -285.768377)
			(xy 314.675574 -285.77642) (xy 314.624158 -285.77642) (xy 314.573376 -285.768377) (xy 314.524477 -285.752489)
			(xy 314.478665 -285.729146) (xy 314.437069 -285.698925) (xy 314.400713 -285.662569) (xy 314.370492 -285.620973)
			(xy 314.347149 -285.575161) (xy 314.331261 -285.526262) (xy 314.323218 -285.47548) (xy 314.026554 -285.47548)
			(xy 314.018511 -285.526262) (xy 314.002623 -285.575161) (xy 313.97928 -285.620973) (xy 313.949059 -285.662569)
			(xy 313.912703 -285.698925) (xy 313.871107 -285.729146) (xy 313.825295 -285.752489) (xy 313.776396 -285.768377)
			(xy 313.725614 -285.77642) (xy 313.674198 -285.77642) (xy 313.623416 -285.768377) (xy 313.574517 -285.752489)
			(xy 313.528705 -285.729146) (xy 313.487109 -285.698925) (xy 313.450753 -285.662569) (xy 313.420532 -285.620973)
			(xy 313.397189 -285.575161) (xy 313.381301 -285.526262) (xy 313.373258 -285.47548) (xy 313.054326 -285.47548)
			(xy 313.04661 -285.522956) (xy 313.031026 -285.569637) (xy 313.008155 -285.613214) (xy 312.97859 -285.652558)
			(xy 312.943097 -285.68665) (xy 312.902594 -285.714606) (xy 312.858132 -285.735704) (xy 312.810861 -285.749396)
			(xy 312.762006 -285.755328) (xy 312.712831 -285.753347) (xy 312.664612 -285.743503) (xy 312.618596 -285.726051)
			(xy 312.575975 -285.701444) (xy 312.537854 -285.670319) (xy 312.505219 -285.633482) (xy 312.478916 -285.591886)
			(xy 312.459625 -285.54661) (xy 312.447848 -285.498826) (xy 312.443888 -285.449772) (xy 312.10504 -285.449772)
			(xy 312.104545 -285.474379) (xy 312.09665 -285.522956) (xy 312.081066 -285.569637) (xy 312.058195 -285.613214)
			(xy 312.02863 -285.652558) (xy 311.993137 -285.68665) (xy 311.952634 -285.714606) (xy 311.908172 -285.735704)
			(xy 311.860901 -285.749396) (xy 311.812046 -285.755328) (xy 311.762871 -285.753347) (xy 311.714652 -285.743503)
			(xy 311.668636 -285.726051) (xy 311.626015 -285.701444) (xy 311.587894 -285.670319) (xy 311.555259 -285.633482)
			(xy 311.528956 -285.591886) (xy 311.509665 -285.54661) (xy 311.497888 -285.498826) (xy 311.493928 -285.449772)
			(xy 311.15508 -285.449772) (xy 311.154585 -285.474379) (xy 311.14669 -285.522956) (xy 311.131106 -285.569637)
			(xy 311.108235 -285.613214) (xy 311.07867 -285.652558) (xy 311.043177 -285.68665) (xy 311.002674 -285.714606)
			(xy 310.958212 -285.735704) (xy 310.910941 -285.749396) (xy 310.862086 -285.755328) (xy 310.812911 -285.753347)
			(xy 310.764692 -285.743503) (xy 310.718676 -285.726051) (xy 310.676055 -285.701444) (xy 310.637934 -285.670319)
			(xy 310.605299 -285.633482) (xy 310.578996 -285.591886) (xy 310.559705 -285.54661) (xy 310.547928 -285.498826)
			(xy 310.543968 -285.449772) (xy 310.20512 -285.449772) (xy 310.204625 -285.474379) (xy 310.19673 -285.522956)
			(xy 310.181146 -285.569637) (xy 310.158275 -285.613214) (xy 310.12871 -285.652558) (xy 310.093217 -285.68665)
			(xy 310.052714 -285.714606) (xy 310.008252 -285.735704) (xy 309.960981 -285.749396) (xy 309.912126 -285.755328)
			(xy 309.862951 -285.753347) (xy 309.814732 -285.743503) (xy 309.768716 -285.726051) (xy 309.726095 -285.701444)
			(xy 309.687974 -285.670319) (xy 309.655339 -285.633482) (xy 309.629036 -285.591886) (xy 309.609745 -285.54661)
			(xy 309.597968 -285.498826) (xy 309.594008 -285.449772) (xy 309.25516 -285.449772) (xy 309.254665 -285.474379)
			(xy 309.24677 -285.522956) (xy 309.231186 -285.569637) (xy 309.208315 -285.613214) (xy 309.17875 -285.652558)
			(xy 309.143257 -285.68665) (xy 309.102754 -285.714606) (xy 309.058292 -285.735704) (xy 309.011021 -285.749396)
			(xy 308.962166 -285.755328) (xy 308.912991 -285.753347) (xy 308.864772 -285.743503) (xy 308.818756 -285.726051)
			(xy 308.776135 -285.701444) (xy 308.738014 -285.670319) (xy 308.705379 -285.633482) (xy 308.679076 -285.591886)
			(xy 308.659785 -285.54661) (xy 308.648008 -285.498826) (xy 308.644048 -285.449772) (xy 308.327044 -285.449772)
			(xy 308.32654 -285.47548) (xy 308.318497 -285.526262) (xy 308.302609 -285.575161) (xy 308.279266 -285.620973)
			(xy 308.249045 -285.662569) (xy 308.212689 -285.698925) (xy 308.171093 -285.729146) (xy 308.125281 -285.752489)
			(xy 308.076382 -285.768377) (xy 308.0256 -285.77642) (xy 307.974184 -285.77642) (xy 307.923402 -285.768377)
			(xy 307.874503 -285.752489) (xy 307.828691 -285.729146) (xy 307.787095 -285.698925) (xy 307.750739 -285.662569)
			(xy 307.720518 -285.620973) (xy 307.697175 -285.575161) (xy 307.681287 -285.526262) (xy 307.673244 -285.47548)
			(xy 307.376326 -285.47548) (xy 307.368283 -285.526262) (xy 307.352395 -285.575161) (xy 307.329052 -285.620973)
			(xy 307.298831 -285.662569) (xy 307.262475 -285.698925) (xy 307.220879 -285.729146) (xy 307.175067 -285.752489)
			(xy 307.126168 -285.768377) (xy 307.075386 -285.77642) (xy 307.02397 -285.77642) (xy 306.973188 -285.768377)
			(xy 306.924289 -285.752489) (xy 306.878477 -285.729146) (xy 306.836881 -285.698925) (xy 306.800525 -285.662569)
			(xy 306.770304 -285.620973) (xy 306.746961 -285.575161) (xy 306.731073 -285.526262) (xy 306.72303 -285.47548)
			(xy 306.404352 -285.47548) (xy 306.396636 -285.522956) (xy 306.381052 -285.569637) (xy 306.358181 -285.613214)
			(xy 306.328616 -285.652558) (xy 306.293123 -285.68665) (xy 306.25262 -285.714606) (xy 306.208158 -285.735704)
			(xy 306.160887 -285.749396) (xy 306.112032 -285.755328) (xy 306.062857 -285.753347) (xy 306.014638 -285.743503)
			(xy 305.968622 -285.726051) (xy 305.926001 -285.701444) (xy 305.88788 -285.670319) (xy 305.855245 -285.633482)
			(xy 305.828942 -285.591886) (xy 305.809651 -285.54661) (xy 305.797874 -285.498826) (xy 305.793914 -285.449772)
			(xy 281.616912 -285.449772) (xy 281.616912 -285.549086) (xy 281.617551 -285.561644) (xy 281.629403 -285.583783)
			(xy 281.639518 -285.59125) (xy 281.720544 -285.645352) (xy 281.745436 -285.647892) (xy 281.757628 -285.642812)
			(xy 281.785665 -285.631913) (xy 281.844649 -285.620146) (xy 281.874722 -285.619444) (xy 281.89998 -285.619967)
			(xy 281.949807 -285.628285) (xy 281.997585 -285.64469) (xy 282.042012 -285.668736) (xy 282.081875 -285.699765)
			(xy 282.116088 -285.736932) (xy 282.143716 -285.779224) (xy 282.164008 -285.825485) (xy 282.176408 -285.874456)
			(xy 282.180576 -285.924752) (xy 282.519132 -285.924752) (xy 282.523092 -285.875698) (xy 282.534869 -285.827914)
			(xy 282.55416 -285.782638) (xy 282.580463 -285.741042) (xy 282.613098 -285.704205) (xy 282.651219 -285.67308)
			(xy 282.69384 -285.648473) (xy 282.739856 -285.631021) (xy 282.788075 -285.621177) (xy 282.83725 -285.619196)
			(xy 282.886105 -285.625128) (xy 282.933376 -285.63882) (xy 282.977838 -285.659918) (xy 283.018341 -285.687874)
			(xy 283.053834 -285.721966) (xy 283.083399 -285.76131) (xy 283.10627 -285.804887) (xy 283.121854 -285.851568)
			(xy 283.129749 -285.900145) (xy 283.130244 -285.924752) (xy 283.469092 -285.924752) (xy 283.473052 -285.875698)
			(xy 283.484829 -285.827914) (xy 283.50412 -285.782638) (xy 283.530423 -285.741042) (xy 283.563058 -285.704205)
			(xy 283.601179 -285.67308) (xy 283.6438 -285.648473) (xy 283.689816 -285.631021) (xy 283.738035 -285.621177)
			(xy 283.78721 -285.619196) (xy 283.836065 -285.625128) (xy 283.883336 -285.63882) (xy 283.927798 -285.659918)
			(xy 283.968301 -285.687874) (xy 284.003794 -285.721966) (xy 284.033359 -285.76131) (xy 284.05623 -285.804887)
			(xy 284.071814 -285.851568) (xy 284.079709 -285.900145) (xy 284.080204 -285.924752) (xy 284.419052 -285.924752)
			(xy 284.423012 -285.875698) (xy 284.434789 -285.827914) (xy 284.45408 -285.782638) (xy 284.480383 -285.741042)
			(xy 284.513018 -285.704205) (xy 284.551139 -285.67308) (xy 284.59376 -285.648473) (xy 284.639776 -285.631021)
			(xy 284.687995 -285.621177) (xy 284.73717 -285.619196) (xy 284.786025 -285.625128) (xy 284.833296 -285.63882)
			(xy 284.877758 -285.659918) (xy 284.918261 -285.687874) (xy 284.953754 -285.721966) (xy 284.983319 -285.76131)
			(xy 285.00619 -285.804887) (xy 285.021774 -285.851568) (xy 285.029669 -285.900145) (xy 285.030164 -285.924752)
			(xy 285.369012 -285.924752) (xy 285.372972 -285.875698) (xy 285.384749 -285.827914) (xy 285.40404 -285.782638)
			(xy 285.430343 -285.741042) (xy 285.462978 -285.704205) (xy 285.501099 -285.67308) (xy 285.54372 -285.648473)
			(xy 285.589736 -285.631021) (xy 285.637955 -285.621177) (xy 285.68713 -285.619196) (xy 285.735985 -285.625128)
			(xy 285.783256 -285.63882) (xy 285.827718 -285.659918) (xy 285.868221 -285.687874) (xy 285.903714 -285.721966)
			(xy 285.933279 -285.76131) (xy 285.95615 -285.804887) (xy 285.971734 -285.851568) (xy 285.979629 -285.900145)
			(xy 285.980124 -285.924752) (xy 286.318972 -285.924752) (xy 286.322932 -285.875698) (xy 286.334709 -285.827914)
			(xy 286.354 -285.782638) (xy 286.380303 -285.741042) (xy 286.412938 -285.704205) (xy 286.451059 -285.67308)
			(xy 286.49368 -285.648473) (xy 286.539696 -285.631021) (xy 286.587915 -285.621177) (xy 286.63709 -285.619196)
			(xy 286.685945 -285.625128) (xy 286.733216 -285.63882) (xy 286.777678 -285.659918) (xy 286.818181 -285.687874)
			(xy 286.853674 -285.721966) (xy 286.883239 -285.76131) (xy 286.90611 -285.804887) (xy 286.921694 -285.851568)
			(xy 286.929589 -285.900145) (xy 286.930084 -285.924752) (xy 287.268932 -285.924752) (xy 287.272892 -285.875698)
			(xy 287.284669 -285.827914) (xy 287.30396 -285.782638) (xy 287.330263 -285.741042) (xy 287.362898 -285.704205)
			(xy 287.401019 -285.67308) (xy 287.44364 -285.648473) (xy 287.489656 -285.631021) (xy 287.537875 -285.621177)
			(xy 287.58705 -285.619196) (xy 287.635905 -285.625128) (xy 287.683176 -285.63882) (xy 287.727638 -285.659918)
			(xy 287.768141 -285.687874) (xy 287.803634 -285.721966) (xy 287.833199 -285.76131) (xy 287.85607 -285.804887)
			(xy 287.871654 -285.851568) (xy 287.879549 -285.900145) (xy 287.880044 -285.924752) (xy 288.218892 -285.924752)
			(xy 288.222852 -285.875698) (xy 288.234629 -285.827914) (xy 288.25392 -285.782638) (xy 288.280223 -285.741042)
			(xy 288.312858 -285.704205) (xy 288.350979 -285.67308) (xy 288.3936 -285.648473) (xy 288.439616 -285.631021)
			(xy 288.487835 -285.621177) (xy 288.53701 -285.619196) (xy 288.585865 -285.625128) (xy 288.633136 -285.63882)
			(xy 288.677598 -285.659918) (xy 288.718101 -285.687874) (xy 288.753594 -285.721966) (xy 288.783159 -285.76131)
			(xy 288.80603 -285.804887) (xy 288.821614 -285.851568) (xy 288.829509 -285.900145) (xy 288.830004 -285.924752)
			(xy 289.169106 -285.924752) (xy 289.173066 -285.875698) (xy 289.184843 -285.827914) (xy 289.204134 -285.782638)
			(xy 289.230437 -285.741042) (xy 289.263072 -285.704205) (xy 289.301193 -285.67308) (xy 289.343814 -285.648473)
			(xy 289.38983 -285.631021) (xy 289.438049 -285.621177) (xy 289.487224 -285.619196) (xy 289.536079 -285.625128)
			(xy 289.58335 -285.63882) (xy 289.627812 -285.659918) (xy 289.668315 -285.687874) (xy 289.703808 -285.721966)
			(xy 289.733373 -285.76131) (xy 289.756244 -285.804887) (xy 289.771828 -285.851568) (xy 289.779723 -285.900145)
			(xy 289.780218 -285.924752) (xy 290.119066 -285.924752) (xy 290.123026 -285.875698) (xy 290.134803 -285.827914)
			(xy 290.154094 -285.782638) (xy 290.180397 -285.741042) (xy 290.213032 -285.704205) (xy 290.251153 -285.67308)
			(xy 290.293774 -285.648473) (xy 290.33979 -285.631021) (xy 290.388009 -285.621177) (xy 290.437184 -285.619196)
			(xy 290.486039 -285.625128) (xy 290.53331 -285.63882) (xy 290.577772 -285.659918) (xy 290.618275 -285.687874)
			(xy 290.653768 -285.721966) (xy 290.683333 -285.76131) (xy 290.706204 -285.804887) (xy 290.721788 -285.851568)
			(xy 290.729683 -285.900145) (xy 290.730178 -285.924752) (xy 292.018986 -285.924752) (xy 292.022946 -285.875698)
			(xy 292.034723 -285.827914) (xy 292.054014 -285.782638) (xy 292.080317 -285.741042) (xy 292.112952 -285.704205)
			(xy 292.151073 -285.67308) (xy 292.193694 -285.648473) (xy 292.23971 -285.631021) (xy 292.287929 -285.621177)
			(xy 292.337104 -285.619196) (xy 292.385959 -285.625128) (xy 292.43323 -285.63882) (xy 292.477692 -285.659918)
			(xy 292.518195 -285.687874) (xy 292.553688 -285.721966) (xy 292.583253 -285.76131) (xy 292.606124 -285.804887)
			(xy 292.621708 -285.851568) (xy 292.629603 -285.900145) (xy 292.630098 -285.924752) (xy 292.968946 -285.924752)
			(xy 292.972906 -285.875698) (xy 292.984683 -285.827914) (xy 293.003974 -285.782638) (xy 293.030277 -285.741042)
			(xy 293.062912 -285.704205) (xy 293.101033 -285.67308) (xy 293.143654 -285.648473) (xy 293.18967 -285.631021)
			(xy 293.237889 -285.621177) (xy 293.287064 -285.619196) (xy 293.335919 -285.625128) (xy 293.38319 -285.63882)
			(xy 293.427652 -285.659918) (xy 293.468155 -285.687874) (xy 293.503648 -285.721966) (xy 293.533213 -285.76131)
			(xy 293.556084 -285.804887) (xy 293.571668 -285.851568) (xy 293.579563 -285.900145) (xy 293.580058 -285.924752)
			(xy 293.918906 -285.924752) (xy 293.922866 -285.875698) (xy 293.934643 -285.827914) (xy 293.953934 -285.782638)
			(xy 293.980237 -285.741042) (xy 294.012872 -285.704205) (xy 294.050993 -285.67308) (xy 294.093614 -285.648473)
			(xy 294.13963 -285.631021) (xy 294.187849 -285.621177) (xy 294.237024 -285.619196) (xy 294.285879 -285.625128)
			(xy 294.33315 -285.63882) (xy 294.377612 -285.659918) (xy 294.418115 -285.687874) (xy 294.453608 -285.721966)
			(xy 294.483173 -285.76131) (xy 294.506044 -285.804887) (xy 294.521628 -285.851568) (xy 294.529523 -285.900145)
			(xy 294.530018 -285.924752) (xy 294.86912 -285.924752) (xy 294.87308 -285.875698) (xy 294.884857 -285.827914)
			(xy 294.904148 -285.782638) (xy 294.930451 -285.741042) (xy 294.963086 -285.704205) (xy 295.001207 -285.67308)
			(xy 295.043828 -285.648473) (xy 295.089844 -285.631021) (xy 295.138063 -285.621177) (xy 295.187238 -285.619196)
			(xy 295.236093 -285.625128) (xy 295.283364 -285.63882) (xy 295.327826 -285.659918) (xy 295.368329 -285.687874)
			(xy 295.403822 -285.721966) (xy 295.433387 -285.76131) (xy 295.456258 -285.804887) (xy 295.471842 -285.851568)
			(xy 295.479737 -285.900145) (xy 295.480232 -285.924752) (xy 295.81908 -285.924752) (xy 295.82304 -285.875698)
			(xy 295.834817 -285.827914) (xy 295.854108 -285.782638) (xy 295.880411 -285.741042) (xy 295.913046 -285.704205)
			(xy 295.951167 -285.67308) (xy 295.993788 -285.648473) (xy 296.039804 -285.631021) (xy 296.088023 -285.621177)
			(xy 296.137198 -285.619196) (xy 296.186053 -285.625128) (xy 296.233324 -285.63882) (xy 296.277786 -285.659918)
			(xy 296.318289 -285.687874) (xy 296.353782 -285.721966) (xy 296.383347 -285.76131) (xy 296.406218 -285.804887)
			(xy 296.421802 -285.851568) (xy 296.429697 -285.900145) (xy 296.430192 -285.924752) (xy 296.76904 -285.924752)
			(xy 296.773 -285.875698) (xy 296.784777 -285.827914) (xy 296.804068 -285.782638) (xy 296.830371 -285.741042)
			(xy 296.863006 -285.704205) (xy 296.901127 -285.67308) (xy 296.943748 -285.648473) (xy 296.989764 -285.631021)
			(xy 297.037983 -285.621177) (xy 297.087158 -285.619196) (xy 297.136013 -285.625128) (xy 297.183284 -285.63882)
			(xy 297.227746 -285.659918) (xy 297.268249 -285.687874) (xy 297.303742 -285.721966) (xy 297.333307 -285.76131)
			(xy 297.356178 -285.804887) (xy 297.371762 -285.851568) (xy 297.379657 -285.900145) (xy 297.380152 -285.924752)
			(xy 297.719 -285.924752) (xy 297.72296 -285.875698) (xy 297.734737 -285.827914) (xy 297.754028 -285.782638)
			(xy 297.780331 -285.741042) (xy 297.812966 -285.704205) (xy 297.851087 -285.67308) (xy 297.893708 -285.648473)
			(xy 297.939724 -285.631021) (xy 297.987943 -285.621177) (xy 298.037118 -285.619196) (xy 298.085973 -285.625128)
			(xy 298.133244 -285.63882) (xy 298.177706 -285.659918) (xy 298.218209 -285.687874) (xy 298.253702 -285.721966)
			(xy 298.283267 -285.76131) (xy 298.306138 -285.804887) (xy 298.321722 -285.851568) (xy 298.329617 -285.900145)
			(xy 298.330112 -285.924752) (xy 298.66896 -285.924752) (xy 298.67292 -285.875698) (xy 298.684697 -285.827914)
			(xy 298.703988 -285.782638) (xy 298.730291 -285.741042) (xy 298.762926 -285.704205) (xy 298.801047 -285.67308)
			(xy 298.843668 -285.648473) (xy 298.889684 -285.631021) (xy 298.937903 -285.621177) (xy 298.987078 -285.619196)
			(xy 299.035933 -285.625128) (xy 299.083204 -285.63882) (xy 299.127666 -285.659918) (xy 299.168169 -285.687874)
			(xy 299.203662 -285.721966) (xy 299.233227 -285.76131) (xy 299.256098 -285.804887) (xy 299.271682 -285.851568)
			(xy 299.279577 -285.900145) (xy 299.280072 -285.924752) (xy 299.61892 -285.924752) (xy 299.62288 -285.875698)
			(xy 299.634657 -285.827914) (xy 299.653948 -285.782638) (xy 299.680251 -285.741042) (xy 299.712886 -285.704205)
			(xy 299.751007 -285.67308) (xy 299.793628 -285.648473) (xy 299.839644 -285.631021) (xy 299.887863 -285.621177)
			(xy 299.937038 -285.619196) (xy 299.985893 -285.625128) (xy 300.033164 -285.63882) (xy 300.077626 -285.659918)
			(xy 300.118129 -285.687874) (xy 300.153622 -285.721966) (xy 300.183187 -285.76131) (xy 300.206058 -285.804887)
			(xy 300.221642 -285.851568) (xy 300.229537 -285.900145) (xy 300.230032 -285.924752) (xy 300.56888 -285.924752)
			(xy 300.57284 -285.875698) (xy 300.584617 -285.827914) (xy 300.603908 -285.782638) (xy 300.630211 -285.741042)
			(xy 300.662846 -285.704205) (xy 300.700967 -285.67308) (xy 300.743588 -285.648473) (xy 300.789604 -285.631021)
			(xy 300.837823 -285.621177) (xy 300.886998 -285.619196) (xy 300.935853 -285.625128) (xy 300.983124 -285.63882)
			(xy 301.027586 -285.659918) (xy 301.068089 -285.687874) (xy 301.103582 -285.721966) (xy 301.133147 -285.76131)
			(xy 301.156018 -285.804887) (xy 301.171602 -285.851568) (xy 301.179497 -285.900145) (xy 301.179992 -285.924752)
			(xy 301.519094 -285.924752) (xy 301.523054 -285.875698) (xy 301.534831 -285.827914) (xy 301.554122 -285.782638)
			(xy 301.580425 -285.741042) (xy 301.61306 -285.704205) (xy 301.651181 -285.67308) (xy 301.693802 -285.648473)
			(xy 301.739818 -285.631021) (xy 301.788037 -285.621177) (xy 301.837212 -285.619196) (xy 301.886067 -285.625128)
			(xy 301.933338 -285.63882) (xy 301.9778 -285.659918) (xy 302.018303 -285.687874) (xy 302.053796 -285.721966)
			(xy 302.083361 -285.76131) (xy 302.106232 -285.804887) (xy 302.121816 -285.851568) (xy 302.129711 -285.900145)
			(xy 302.130206 -285.924752) (xy 302.469054 -285.924752) (xy 302.473014 -285.875698) (xy 302.484791 -285.827914)
			(xy 302.504082 -285.782638) (xy 302.530385 -285.741042) (xy 302.56302 -285.704205) (xy 302.601141 -285.67308)
			(xy 302.643762 -285.648473) (xy 302.689778 -285.631021) (xy 302.737997 -285.621177) (xy 302.787172 -285.619196)
			(xy 302.836027 -285.625128) (xy 302.883298 -285.63882) (xy 302.92776 -285.659918) (xy 302.968263 -285.687874)
			(xy 303.003756 -285.721966) (xy 303.033321 -285.76131) (xy 303.056192 -285.804887) (xy 303.071776 -285.851568)
			(xy 303.079671 -285.900145) (xy 303.080166 -285.924752) (xy 303.079671 -285.949359) (xy 303.071776 -285.997936)
			(xy 303.056192 -286.044617) (xy 303.033321 -286.088194) (xy 303.003756 -286.127538) (xy 302.968263 -286.16163)
			(xy 302.92776 -286.189586) (xy 302.883298 -286.210684) (xy 302.836027 -286.224376) (xy 302.787172 -286.230308)
			(xy 302.737997 -286.228327) (xy 302.689778 -286.218483) (xy 302.643762 -286.201031) (xy 302.601141 -286.176424)
			(xy 302.56302 -286.145299) (xy 302.530385 -286.108462) (xy 302.504082 -286.066866) (xy 302.484791 -286.02159)
			(xy 302.473014 -285.973806) (xy 302.469054 -285.924752) (xy 302.130206 -285.924752) (xy 302.129711 -285.949359)
			(xy 302.121816 -285.997936) (xy 302.106232 -286.044617) (xy 302.083361 -286.088194) (xy 302.053796 -286.127538)
			(xy 302.018303 -286.16163) (xy 301.9778 -286.189586) (xy 301.933338 -286.210684) (xy 301.886067 -286.224376)
			(xy 301.837212 -286.230308) (xy 301.788037 -286.228327) (xy 301.739818 -286.218483) (xy 301.693802 -286.201031)
			(xy 301.651181 -286.176424) (xy 301.61306 -286.145299) (xy 301.580425 -286.108462) (xy 301.554122 -286.066866)
			(xy 301.534831 -286.02159) (xy 301.523054 -285.973806) (xy 301.519094 -285.924752) (xy 301.179992 -285.924752)
			(xy 301.179497 -285.949359) (xy 301.171602 -285.997936) (xy 301.156018 -286.044617) (xy 301.133147 -286.088194)
			(xy 301.103582 -286.127538) (xy 301.068089 -286.16163) (xy 301.027586 -286.189586) (xy 300.983124 -286.210684)
			(xy 300.935853 -286.224376) (xy 300.886998 -286.230308) (xy 300.837823 -286.228327) (xy 300.789604 -286.218483)
			(xy 300.743588 -286.201031) (xy 300.700967 -286.176424) (xy 300.662846 -286.145299) (xy 300.630211 -286.108462)
			(xy 300.603908 -286.066866) (xy 300.584617 -286.02159) (xy 300.57284 -285.973806) (xy 300.56888 -285.924752)
			(xy 300.230032 -285.924752) (xy 300.229537 -285.949359) (xy 300.221642 -285.997936) (xy 300.206058 -286.044617)
			(xy 300.183187 -286.088194) (xy 300.153622 -286.127538) (xy 300.118129 -286.16163) (xy 300.077626 -286.189586)
			(xy 300.033164 -286.210684) (xy 299.985893 -286.224376) (xy 299.937038 -286.230308) (xy 299.887863 -286.228327)
			(xy 299.839644 -286.218483) (xy 299.793628 -286.201031) (xy 299.751007 -286.176424) (xy 299.712886 -286.145299)
			(xy 299.680251 -286.108462) (xy 299.653948 -286.066866) (xy 299.634657 -286.02159) (xy 299.62288 -285.973806)
			(xy 299.61892 -285.924752) (xy 299.280072 -285.924752) (xy 299.279577 -285.949359) (xy 299.271682 -285.997936)
			(xy 299.256098 -286.044617) (xy 299.233227 -286.088194) (xy 299.203662 -286.127538) (xy 299.168169 -286.16163)
			(xy 299.127666 -286.189586) (xy 299.083204 -286.210684) (xy 299.035933 -286.224376) (xy 298.987078 -286.230308)
			(xy 298.937903 -286.228327) (xy 298.889684 -286.218483) (xy 298.843668 -286.201031) (xy 298.801047 -286.176424)
			(xy 298.762926 -286.145299) (xy 298.730291 -286.108462) (xy 298.703988 -286.066866) (xy 298.684697 -286.02159)
			(xy 298.67292 -285.973806) (xy 298.66896 -285.924752) (xy 298.330112 -285.924752) (xy 298.329617 -285.949359)
			(xy 298.321722 -285.997936) (xy 298.306138 -286.044617) (xy 298.283267 -286.088194) (xy 298.253702 -286.127538)
			(xy 298.218209 -286.16163) (xy 298.177706 -286.189586) (xy 298.133244 -286.210684) (xy 298.085973 -286.224376)
			(xy 298.037118 -286.230308) (xy 297.987943 -286.228327) (xy 297.939724 -286.218483) (xy 297.893708 -286.201031)
			(xy 297.851087 -286.176424) (xy 297.812966 -286.145299) (xy 297.780331 -286.108462) (xy 297.754028 -286.066866)
			(xy 297.734737 -286.02159) (xy 297.72296 -285.973806) (xy 297.719 -285.924752) (xy 297.380152 -285.924752)
			(xy 297.379657 -285.949359) (xy 297.371762 -285.997936) (xy 297.356178 -286.044617) (xy 297.333307 -286.088194)
			(xy 297.303742 -286.127538) (xy 297.268249 -286.16163) (xy 297.227746 -286.189586) (xy 297.183284 -286.210684)
			(xy 297.136013 -286.224376) (xy 297.087158 -286.230308) (xy 297.037983 -286.228327) (xy 296.989764 -286.218483)
			(xy 296.943748 -286.201031) (xy 296.901127 -286.176424) (xy 296.863006 -286.145299) (xy 296.830371 -286.108462)
			(xy 296.804068 -286.066866) (xy 296.784777 -286.02159) (xy 296.773 -285.973806) (xy 296.76904 -285.924752)
			(xy 296.430192 -285.924752) (xy 296.429697 -285.949359) (xy 296.421802 -285.997936) (xy 296.406218 -286.044617)
			(xy 296.383347 -286.088194) (xy 296.353782 -286.127538) (xy 296.318289 -286.16163) (xy 296.277786 -286.189586)
			(xy 296.233324 -286.210684) (xy 296.186053 -286.224376) (xy 296.137198 -286.230308) (xy 296.088023 -286.228327)
			(xy 296.039804 -286.218483) (xy 295.993788 -286.201031) (xy 295.951167 -286.176424) (xy 295.913046 -286.145299)
			(xy 295.880411 -286.108462) (xy 295.854108 -286.066866) (xy 295.834817 -286.02159) (xy 295.82304 -285.973806)
			(xy 295.81908 -285.924752) (xy 295.480232 -285.924752) (xy 295.479737 -285.949359) (xy 295.471842 -285.997936)
			(xy 295.456258 -286.044617) (xy 295.433387 -286.088194) (xy 295.403822 -286.127538) (xy 295.368329 -286.16163)
			(xy 295.327826 -286.189586) (xy 295.283364 -286.210684) (xy 295.236093 -286.224376) (xy 295.187238 -286.230308)
			(xy 295.138063 -286.228327) (xy 295.089844 -286.218483) (xy 295.043828 -286.201031) (xy 295.001207 -286.176424)
			(xy 294.963086 -286.145299) (xy 294.930451 -286.108462) (xy 294.904148 -286.066866) (xy 294.884857 -286.02159)
			(xy 294.87308 -285.973806) (xy 294.86912 -285.924752) (xy 294.530018 -285.924752) (xy 294.529523 -285.949359)
			(xy 294.521628 -285.997936) (xy 294.506044 -286.044617) (xy 294.483173 -286.088194) (xy 294.453608 -286.127538)
			(xy 294.418115 -286.16163) (xy 294.377612 -286.189586) (xy 294.33315 -286.210684) (xy 294.285879 -286.224376)
			(xy 294.237024 -286.230308) (xy 294.187849 -286.228327) (xy 294.13963 -286.218483) (xy 294.093614 -286.201031)
			(xy 294.050993 -286.176424) (xy 294.012872 -286.145299) (xy 293.980237 -286.108462) (xy 293.953934 -286.066866)
			(xy 293.934643 -286.02159) (xy 293.922866 -285.973806) (xy 293.918906 -285.924752) (xy 293.580058 -285.924752)
			(xy 293.579563 -285.949359) (xy 293.571668 -285.997936) (xy 293.556084 -286.044617) (xy 293.533213 -286.088194)
			(xy 293.503648 -286.127538) (xy 293.468155 -286.16163) (xy 293.427652 -286.189586) (xy 293.38319 -286.210684)
			(xy 293.335919 -286.224376) (xy 293.287064 -286.230308) (xy 293.237889 -286.228327) (xy 293.18967 -286.218483)
			(xy 293.143654 -286.201031) (xy 293.101033 -286.176424) (xy 293.062912 -286.145299) (xy 293.030277 -286.108462)
			(xy 293.003974 -286.066866) (xy 292.984683 -286.02159) (xy 292.972906 -285.973806) (xy 292.968946 -285.924752)
			(xy 292.630098 -285.924752) (xy 292.629603 -285.949359) (xy 292.621708 -285.997936) (xy 292.606124 -286.044617)
			(xy 292.583253 -286.088194) (xy 292.553688 -286.127538) (xy 292.518195 -286.16163) (xy 292.477692 -286.189586)
			(xy 292.43323 -286.210684) (xy 292.385959 -286.224376) (xy 292.337104 -286.230308) (xy 292.287929 -286.228327)
			(xy 292.23971 -286.218483) (xy 292.193694 -286.201031) (xy 292.151073 -286.176424) (xy 292.112952 -286.145299)
			(xy 292.080317 -286.108462) (xy 292.054014 -286.066866) (xy 292.034723 -286.02159) (xy 292.022946 -285.973806)
			(xy 292.018986 -285.924752) (xy 290.730178 -285.924752) (xy 290.729683 -285.949359) (xy 290.721788 -285.997936)
			(xy 290.706204 -286.044617) (xy 290.683333 -286.088194) (xy 290.653768 -286.127538) (xy 290.618275 -286.16163)
			(xy 290.577772 -286.189586) (xy 290.53331 -286.210684) (xy 290.486039 -286.224376) (xy 290.437184 -286.230308)
			(xy 290.388009 -286.228327) (xy 290.33979 -286.218483) (xy 290.293774 -286.201031) (xy 290.251153 -286.176424)
			(xy 290.213032 -286.145299) (xy 290.180397 -286.108462) (xy 290.154094 -286.066866) (xy 290.134803 -286.02159)
			(xy 290.123026 -285.973806) (xy 290.119066 -285.924752) (xy 289.780218 -285.924752) (xy 289.779723 -285.949359)
			(xy 289.771828 -285.997936) (xy 289.756244 -286.044617) (xy 289.733373 -286.088194) (xy 289.703808 -286.127538)
			(xy 289.668315 -286.16163) (xy 289.627812 -286.189586) (xy 289.58335 -286.210684) (xy 289.536079 -286.224376)
			(xy 289.487224 -286.230308) (xy 289.438049 -286.228327) (xy 289.38983 -286.218483) (xy 289.343814 -286.201031)
			(xy 289.301193 -286.176424) (xy 289.263072 -286.145299) (xy 289.230437 -286.108462) (xy 289.204134 -286.066866)
			(xy 289.184843 -286.02159) (xy 289.173066 -285.973806) (xy 289.169106 -285.924752) (xy 288.830004 -285.924752)
			(xy 288.829509 -285.949359) (xy 288.821614 -285.997936) (xy 288.80603 -286.044617) (xy 288.783159 -286.088194)
			(xy 288.753594 -286.127538) (xy 288.718101 -286.16163) (xy 288.677598 -286.189586) (xy 288.633136 -286.210684)
			(xy 288.585865 -286.224376) (xy 288.53701 -286.230308) (xy 288.487835 -286.228327) (xy 288.439616 -286.218483)
			(xy 288.3936 -286.201031) (xy 288.350979 -286.176424) (xy 288.312858 -286.145299) (xy 288.280223 -286.108462)
			(xy 288.25392 -286.066866) (xy 288.234629 -286.02159) (xy 288.222852 -285.973806) (xy 288.218892 -285.924752)
			(xy 287.880044 -285.924752) (xy 287.879549 -285.949359) (xy 287.871654 -285.997936) (xy 287.85607 -286.044617)
			(xy 287.833199 -286.088194) (xy 287.803634 -286.127538) (xy 287.768141 -286.16163) (xy 287.727638 -286.189586)
			(xy 287.683176 -286.210684) (xy 287.635905 -286.224376) (xy 287.58705 -286.230308) (xy 287.537875 -286.228327)
			(xy 287.489656 -286.218483) (xy 287.44364 -286.201031) (xy 287.401019 -286.176424) (xy 287.362898 -286.145299)
			(xy 287.330263 -286.108462) (xy 287.30396 -286.066866) (xy 287.284669 -286.02159) (xy 287.272892 -285.973806)
			(xy 287.268932 -285.924752) (xy 286.930084 -285.924752) (xy 286.929589 -285.949359) (xy 286.921694 -285.997936)
			(xy 286.90611 -286.044617) (xy 286.883239 -286.088194) (xy 286.853674 -286.127538) (xy 286.818181 -286.16163)
			(xy 286.777678 -286.189586) (xy 286.733216 -286.210684) (xy 286.685945 -286.224376) (xy 286.63709 -286.230308)
			(xy 286.587915 -286.228327) (xy 286.539696 -286.218483) (xy 286.49368 -286.201031) (xy 286.451059 -286.176424)
			(xy 286.412938 -286.145299) (xy 286.380303 -286.108462) (xy 286.354 -286.066866) (xy 286.334709 -286.02159)
			(xy 286.322932 -285.973806) (xy 286.318972 -285.924752) (xy 285.980124 -285.924752) (xy 285.979629 -285.949359)
			(xy 285.971734 -285.997936) (xy 285.95615 -286.044617) (xy 285.933279 -286.088194) (xy 285.903714 -286.127538)
			(xy 285.868221 -286.16163) (xy 285.827718 -286.189586) (xy 285.783256 -286.210684) (xy 285.735985 -286.224376)
			(xy 285.68713 -286.230308) (xy 285.637955 -286.228327) (xy 285.589736 -286.218483) (xy 285.54372 -286.201031)
			(xy 285.501099 -286.176424) (xy 285.462978 -286.145299) (xy 285.430343 -286.108462) (xy 285.40404 -286.066866)
			(xy 285.384749 -286.02159) (xy 285.372972 -285.973806) (xy 285.369012 -285.924752) (xy 285.030164 -285.924752)
			(xy 285.029669 -285.949359) (xy 285.021774 -285.997936) (xy 285.00619 -286.044617) (xy 284.983319 -286.088194)
			(xy 284.953754 -286.127538) (xy 284.918261 -286.16163) (xy 284.877758 -286.189586) (xy 284.833296 -286.210684)
			(xy 284.786025 -286.224376) (xy 284.73717 -286.230308) (xy 284.687995 -286.228327) (xy 284.639776 -286.218483)
			(xy 284.59376 -286.201031) (xy 284.551139 -286.176424) (xy 284.513018 -286.145299) (xy 284.480383 -286.108462)
			(xy 284.45408 -286.066866) (xy 284.434789 -286.02159) (xy 284.423012 -285.973806) (xy 284.419052 -285.924752)
			(xy 284.080204 -285.924752) (xy 284.079709 -285.949359) (xy 284.071814 -285.997936) (xy 284.05623 -286.044617)
			(xy 284.033359 -286.088194) (xy 284.003794 -286.127538) (xy 283.968301 -286.16163) (xy 283.927798 -286.189586)
			(xy 283.883336 -286.210684) (xy 283.836065 -286.224376) (xy 283.78721 -286.230308) (xy 283.738035 -286.228327)
			(xy 283.689816 -286.218483) (xy 283.6438 -286.201031) (xy 283.601179 -286.176424) (xy 283.563058 -286.145299)
			(xy 283.530423 -286.108462) (xy 283.50412 -286.066866) (xy 283.484829 -286.02159) (xy 283.473052 -285.973806)
			(xy 283.469092 -285.924752) (xy 283.130244 -285.924752) (xy 283.129749 -285.949359) (xy 283.121854 -285.997936)
			(xy 283.10627 -286.044617) (xy 283.083399 -286.088194) (xy 283.053834 -286.127538) (xy 283.018341 -286.16163)
			(xy 282.977838 -286.189586) (xy 282.933376 -286.210684) (xy 282.886105 -286.224376) (xy 282.83725 -286.230308)
			(xy 282.788075 -286.228327) (xy 282.739856 -286.218483) (xy 282.69384 -286.201031) (xy 282.651219 -286.176424)
			(xy 282.613098 -286.145299) (xy 282.580463 -286.108462) (xy 282.55416 -286.066866) (xy 282.534869 -286.02159)
			(xy 282.523092 -285.973806) (xy 282.519132 -285.924752) (xy 282.180576 -285.924752) (xy 282.18058 -285.9248)
			(xy 282.176408 -285.975144) (xy 282.164008 -286.024115) (xy 282.143716 -286.070376) (xy 282.116088 -286.112668)
			(xy 282.081875 -286.149835) (xy 282.042012 -286.180864) (xy 281.997585 -286.20491) (xy 281.949807 -286.221315)
			(xy 281.89998 -286.229633) (xy 281.874722 -286.23006) (xy 281.844648 -286.229366) (xy 281.785663 -286.217599)
			(xy 281.757628 -286.206692) (xy 281.745436 -286.201612) (xy 281.720544 -286.204152) (xy 281.639518 -286.258254)
			(xy 281.629471 -286.265777) (xy 281.617647 -286.287885) (xy 281.616912 -286.300418) (xy 281.616912 -286.399732)
			(xy 305.793914 -286.399732) (xy 305.797874 -286.350678) (xy 305.809651 -286.302894) (xy 305.828942 -286.257618)
			(xy 305.855245 -286.216022) (xy 305.88788 -286.179185) (xy 305.926001 -286.14806) (xy 305.968622 -286.123453)
			(xy 306.014638 -286.106001) (xy 306.062857 -286.096157) (xy 306.112032 -286.094176) (xy 306.160887 -286.100108)
			(xy 306.208158 -286.1138) (xy 306.25262 -286.134898) (xy 306.293123 -286.162854) (xy 306.328616 -286.196946)
			(xy 306.358181 -286.23629) (xy 306.381052 -286.279867) (xy 306.396636 -286.326548) (xy 306.404531 -286.375125)
			(xy 306.405026 -286.399732) (xy 306.744128 -286.399732) (xy 306.748088 -286.350678) (xy 306.759865 -286.302894)
			(xy 306.779156 -286.257618) (xy 306.805459 -286.216022) (xy 306.838094 -286.179185) (xy 306.876215 -286.14806)
			(xy 306.918836 -286.123453) (xy 306.964852 -286.106001) (xy 307.013071 -286.096157) (xy 307.062246 -286.094176)
			(xy 307.111101 -286.100108) (xy 307.158372 -286.1138) (xy 307.202834 -286.134898) (xy 307.243337 -286.162854)
			(xy 307.27883 -286.196946) (xy 307.308395 -286.23629) (xy 307.331266 -286.279867) (xy 307.34685 -286.326548)
			(xy 307.354745 -286.375125) (xy 307.35524 -286.399732) (xy 307.694088 -286.399732) (xy 307.698048 -286.350678)
			(xy 307.709825 -286.302894) (xy 307.729116 -286.257618) (xy 307.755419 -286.216022) (xy 307.788054 -286.179185)
			(xy 307.826175 -286.14806) (xy 307.868796 -286.123453) (xy 307.914812 -286.106001) (xy 307.963031 -286.096157)
			(xy 308.012206 -286.094176) (xy 308.061061 -286.100108) (xy 308.108332 -286.1138) (xy 308.152794 -286.134898)
			(xy 308.193297 -286.162854) (xy 308.22879 -286.196946) (xy 308.258355 -286.23629) (xy 308.281226 -286.279867)
			(xy 308.29681 -286.326548) (xy 308.304705 -286.375125) (xy 308.3052 -286.399732) (xy 308.304705 -286.424339)
			(xy 308.304485 -286.425694) (xy 308.623204 -286.425694) (xy 308.623204 -286.374278) (xy 308.631247 -286.323496)
			(xy 308.647135 -286.274597) (xy 308.670478 -286.228785) (xy 308.700699 -286.187189) (xy 308.737055 -286.150833)
			(xy 308.778651 -286.120612) (xy 308.824463 -286.097269) (xy 308.873362 -286.081381) (xy 308.924144 -286.073338)
			(xy 308.97556 -286.073338) (xy 309.026342 -286.081381) (xy 309.075241 -286.097269) (xy 309.121053 -286.120612)
			(xy 309.162649 -286.150833) (xy 309.199005 -286.187189) (xy 309.229226 -286.228785) (xy 309.252569 -286.274597)
			(xy 309.268457 -286.323496) (xy 309.2765 -286.374278) (xy 309.277004 -286.399986) (xy 309.2765 -286.425694)
			(xy 309.573164 -286.425694) (xy 309.573164 -286.374278) (xy 309.581207 -286.323496) (xy 309.597095 -286.274597)
			(xy 309.620438 -286.228785) (xy 309.650659 -286.187189) (xy 309.687015 -286.150833) (xy 309.728611 -286.120612)
			(xy 309.774423 -286.097269) (xy 309.823322 -286.081381) (xy 309.874104 -286.073338) (xy 309.92552 -286.073338)
			(xy 309.976302 -286.081381) (xy 310.025201 -286.097269) (xy 310.071013 -286.120612) (xy 310.112609 -286.150833)
			(xy 310.148965 -286.187189) (xy 310.179186 -286.228785) (xy 310.202529 -286.274597) (xy 310.218417 -286.323496)
			(xy 310.22646 -286.374278) (xy 310.226959 -286.399732) (xy 310.543968 -286.399732) (xy 310.547928 -286.350678)
			(xy 310.559705 -286.302894) (xy 310.578996 -286.257618) (xy 310.605299 -286.216022) (xy 310.637934 -286.179185)
			(xy 310.676055 -286.14806) (xy 310.718676 -286.123453) (xy 310.764692 -286.106001) (xy 310.812911 -286.096157)
			(xy 310.862086 -286.094176) (xy 310.910941 -286.100108) (xy 310.958212 -286.1138) (xy 311.002674 -286.134898)
			(xy 311.043177 -286.162854) (xy 311.07867 -286.196946) (xy 311.108235 -286.23629) (xy 311.131106 -286.279867)
			(xy 311.14669 -286.326548) (xy 311.154585 -286.375125) (xy 311.15508 -286.399732) (xy 311.154585 -286.424339)
			(xy 311.154406 -286.42544) (xy 311.473084 -286.42544) (xy 311.473084 -286.374024) (xy 311.481127 -286.323242)
			(xy 311.497015 -286.274343) (xy 311.520358 -286.228531) (xy 311.550579 -286.186935) (xy 311.586935 -286.150579)
			(xy 311.628531 -286.120358) (xy 311.674343 -286.097015) (xy 311.723242 -286.081127) (xy 311.774024 -286.073084)
			(xy 311.82544 -286.073084) (xy 311.876222 -286.081127) (xy 311.925121 -286.097015) (xy 311.970933 -286.120358)
			(xy 312.012529 -286.150579) (xy 312.048885 -286.186935) (xy 312.079106 -286.228531) (xy 312.102449 -286.274343)
			(xy 312.118337 -286.323242) (xy 312.12638 -286.374024) (xy 312.126884 -286.399732) (xy 312.12638 -286.42544)
			(xy 312.423044 -286.42544) (xy 312.423044 -286.374024) (xy 312.431087 -286.323242) (xy 312.446975 -286.274343)
			(xy 312.470318 -286.228531) (xy 312.500539 -286.186935) (xy 312.536895 -286.150579) (xy 312.578491 -286.120358)
			(xy 312.624303 -286.097015) (xy 312.673202 -286.081127) (xy 312.723984 -286.073084) (xy 312.7754 -286.073084)
			(xy 312.826182 -286.081127) (xy 312.875081 -286.097015) (xy 312.920893 -286.120358) (xy 312.962489 -286.150579)
			(xy 312.998845 -286.186935) (xy 313.029066 -286.228531) (xy 313.052409 -286.274343) (xy 313.068297 -286.323242)
			(xy 313.07634 -286.374024) (xy 313.076844 -286.399732) (xy 313.394102 -286.399732) (xy 313.398062 -286.350678)
			(xy 313.409839 -286.302894) (xy 313.42913 -286.257618) (xy 313.455433 -286.216022) (xy 313.488068 -286.179185)
			(xy 313.526189 -286.14806) (xy 313.56881 -286.123453) (xy 313.614826 -286.106001) (xy 313.663045 -286.096157)
			(xy 313.71222 -286.094176) (xy 313.761075 -286.100108) (xy 313.808346 -286.1138) (xy 313.852808 -286.134898)
			(xy 313.893311 -286.162854) (xy 313.928804 -286.196946) (xy 313.958369 -286.23629) (xy 313.98124 -286.279867)
			(xy 313.996824 -286.326548) (xy 314.004719 -286.375125) (xy 314.005214 -286.399732) (xy 314.344062 -286.399732)
			(xy 314.348022 -286.350678) (xy 314.359799 -286.302894) (xy 314.37909 -286.257618) (xy 314.405393 -286.216022)
			(xy 314.438028 -286.179185) (xy 314.476149 -286.14806) (xy 314.51877 -286.123453) (xy 314.564786 -286.106001)
			(xy 314.613005 -286.096157) (xy 314.66218 -286.094176) (xy 314.711035 -286.100108) (xy 314.758306 -286.1138)
			(xy 314.802768 -286.134898) (xy 314.843271 -286.162854) (xy 314.878764 -286.196946) (xy 314.908329 -286.23629)
			(xy 314.9312 -286.279867) (xy 314.946784 -286.326548) (xy 314.954679 -286.375125) (xy 314.955174 -286.399732)
			(xy 314.954679 -286.424339) (xy 314.946784 -286.472916) (xy 314.9312 -286.519597) (xy 314.908329 -286.563174)
			(xy 314.878764 -286.602518) (xy 314.843271 -286.63661) (xy 314.802768 -286.664566) (xy 314.758306 -286.685664)
			(xy 314.711035 -286.699356) (xy 314.66218 -286.705288) (xy 314.613005 -286.703307) (xy 314.564786 -286.693463)
			(xy 314.51877 -286.676011) (xy 314.476149 -286.651404) (xy 314.438028 -286.620279) (xy 314.405393 -286.583442)
			(xy 314.37909 -286.541846) (xy 314.359799 -286.49657) (xy 314.348022 -286.448786) (xy 314.344062 -286.399732)
			(xy 314.005214 -286.399732) (xy 314.004719 -286.424339) (xy 313.996824 -286.472916) (xy 313.98124 -286.519597)
			(xy 313.958369 -286.563174) (xy 313.928804 -286.602518) (xy 313.893311 -286.63661) (xy 313.852808 -286.664566)
			(xy 313.808346 -286.685664) (xy 313.761075 -286.699356) (xy 313.71222 -286.705288) (xy 313.663045 -286.703307)
			(xy 313.614826 -286.693463) (xy 313.56881 -286.676011) (xy 313.526189 -286.651404) (xy 313.488068 -286.620279)
			(xy 313.455433 -286.583442) (xy 313.42913 -286.541846) (xy 313.409839 -286.49657) (xy 313.398062 -286.448786)
			(xy 313.394102 -286.399732) (xy 313.076844 -286.399732) (xy 313.07634 -286.42544) (xy 313.068297 -286.476222)
			(xy 313.052409 -286.525121) (xy 313.029066 -286.570933) (xy 312.998845 -286.612529) (xy 312.962489 -286.648885)
			(xy 312.920893 -286.679106) (xy 312.875081 -286.702449) (xy 312.826182 -286.718337) (xy 312.7754 -286.72638)
			(xy 312.723984 -286.72638) (xy 312.673202 -286.718337) (xy 312.624303 -286.702449) (xy 312.578491 -286.679106)
			(xy 312.536895 -286.648885) (xy 312.500539 -286.612529) (xy 312.470318 -286.570933) (xy 312.446975 -286.525121)
			(xy 312.431087 -286.476222) (xy 312.423044 -286.42544) (xy 312.12638 -286.42544) (xy 312.118337 -286.476222)
			(xy 312.102449 -286.525121) (xy 312.079106 -286.570933) (xy 312.048885 -286.612529) (xy 312.012529 -286.648885)
			(xy 311.970933 -286.679106) (xy 311.925121 -286.702449) (xy 311.876222 -286.718337) (xy 311.82544 -286.72638)
			(xy 311.774024 -286.72638) (xy 311.723242 -286.718337) (xy 311.674343 -286.702449) (xy 311.628531 -286.679106)
			(xy 311.586935 -286.648885) (xy 311.550579 -286.612529) (xy 311.520358 -286.570933) (xy 311.497015 -286.525121)
			(xy 311.481127 -286.476222) (xy 311.473084 -286.42544) (xy 311.154406 -286.42544) (xy 311.14669 -286.472916)
			(xy 311.131106 -286.519597) (xy 311.108235 -286.563174) (xy 311.07867 -286.602518) (xy 311.043177 -286.63661)
			(xy 311.002674 -286.664566) (xy 310.958212 -286.685664) (xy 310.910941 -286.699356) (xy 310.862086 -286.705288)
			(xy 310.812911 -286.703307) (xy 310.764692 -286.693463) (xy 310.718676 -286.676011) (xy 310.676055 -286.651404)
			(xy 310.637934 -286.620279) (xy 310.605299 -286.583442) (xy 310.578996 -286.541846) (xy 310.559705 -286.49657)
			(xy 310.547928 -286.448786) (xy 310.543968 -286.399732) (xy 310.226959 -286.399732) (xy 310.226964 -286.399986)
			(xy 310.22646 -286.425694) (xy 310.218417 -286.476476) (xy 310.202529 -286.525375) (xy 310.179186 -286.571187)
			(xy 310.148965 -286.612783) (xy 310.112609 -286.649139) (xy 310.071013 -286.67936) (xy 310.025201 -286.702703)
			(xy 309.976302 -286.718591) (xy 309.92552 -286.726634) (xy 309.874104 -286.726634) (xy 309.823322 -286.718591)
			(xy 309.774423 -286.702703) (xy 309.728611 -286.67936) (xy 309.687015 -286.649139) (xy 309.650659 -286.612783)
			(xy 309.620438 -286.571187) (xy 309.597095 -286.525375) (xy 309.581207 -286.476476) (xy 309.573164 -286.425694)
			(xy 309.2765 -286.425694) (xy 309.268457 -286.476476) (xy 309.252569 -286.525375) (xy 309.229226 -286.571187)
			(xy 309.199005 -286.612783) (xy 309.162649 -286.649139) (xy 309.121053 -286.67936) (xy 309.075241 -286.702703)
			(xy 309.026342 -286.718591) (xy 308.97556 -286.726634) (xy 308.924144 -286.726634) (xy 308.873362 -286.718591)
			(xy 308.824463 -286.702703) (xy 308.778651 -286.67936) (xy 308.737055 -286.649139) (xy 308.700699 -286.612783)
			(xy 308.670478 -286.571187) (xy 308.647135 -286.525375) (xy 308.631247 -286.476476) (xy 308.623204 -286.425694)
			(xy 308.304485 -286.425694) (xy 308.29681 -286.472916) (xy 308.281226 -286.519597) (xy 308.258355 -286.563174)
			(xy 308.22879 -286.602518) (xy 308.193297 -286.63661) (xy 308.152794 -286.664566) (xy 308.108332 -286.685664)
			(xy 308.061061 -286.699356) (xy 308.012206 -286.705288) (xy 307.963031 -286.703307) (xy 307.914812 -286.693463)
			(xy 307.868796 -286.676011) (xy 307.826175 -286.651404) (xy 307.788054 -286.620279) (xy 307.755419 -286.583442)
			(xy 307.729116 -286.541846) (xy 307.709825 -286.49657) (xy 307.698048 -286.448786) (xy 307.694088 -286.399732)
			(xy 307.35524 -286.399732) (xy 307.354745 -286.424339) (xy 307.34685 -286.472916) (xy 307.331266 -286.519597)
			(xy 307.308395 -286.563174) (xy 307.27883 -286.602518) (xy 307.243337 -286.63661) (xy 307.202834 -286.664566)
			(xy 307.158372 -286.685664) (xy 307.111101 -286.699356) (xy 307.062246 -286.705288) (xy 307.013071 -286.703307)
			(xy 306.964852 -286.693463) (xy 306.918836 -286.676011) (xy 306.876215 -286.651404) (xy 306.838094 -286.620279)
			(xy 306.805459 -286.583442) (xy 306.779156 -286.541846) (xy 306.759865 -286.49657) (xy 306.748088 -286.448786)
			(xy 306.744128 -286.399732) (xy 306.405026 -286.399732) (xy 306.404531 -286.424339) (xy 306.396636 -286.472916)
			(xy 306.381052 -286.519597) (xy 306.358181 -286.563174) (xy 306.328616 -286.602518) (xy 306.293123 -286.63661)
			(xy 306.25262 -286.664566) (xy 306.208158 -286.685664) (xy 306.160887 -286.699356) (xy 306.112032 -286.705288)
			(xy 306.062857 -286.703307) (xy 306.014638 -286.693463) (xy 305.968622 -286.676011) (xy 305.926001 -286.651404)
			(xy 305.88788 -286.620279) (xy 305.855245 -286.583442) (xy 305.828942 -286.541846) (xy 305.809651 -286.49657)
			(xy 305.797874 -286.448786) (xy 305.793914 -286.399732) (xy 281.616912 -286.399732) (xy 281.616912 -286.4993)
			(xy 281.617554 -286.511856) (xy 281.62941 -286.53399) (xy 281.639518 -286.541464) (xy 281.720544 -286.595566)
			(xy 281.745436 -286.598106) (xy 281.757628 -286.593026) (xy 281.785665 -286.582126) (xy 281.844649 -286.570359)
			(xy 281.874722 -286.569658) (xy 281.899979 -286.570181) (xy 281.949803 -286.578499) (xy 281.997579 -286.594904)
			(xy 282.042004 -286.618948) (xy 282.081865 -286.649976) (xy 282.116076 -286.687141) (xy 282.143704 -286.72943)
			(xy 282.163994 -286.77569) (xy 282.176394 -286.824659) (xy 282.180562 -286.874966) (xy 282.519132 -286.874966)
			(xy 282.523092 -286.825912) (xy 282.534869 -286.778128) (xy 282.55416 -286.732852) (xy 282.580463 -286.691256)
			(xy 282.613098 -286.654419) (xy 282.651219 -286.623294) (xy 282.69384 -286.598687) (xy 282.739856 -286.581235)
			(xy 282.788075 -286.571391) (xy 282.83725 -286.56941) (xy 282.886105 -286.575342) (xy 282.933376 -286.589034)
			(xy 282.977838 -286.610132) (xy 283.018341 -286.638088) (xy 283.053834 -286.67218) (xy 283.083399 -286.711524)
			(xy 283.10627 -286.755101) (xy 283.121854 -286.801782) (xy 283.129749 -286.850359) (xy 283.130244 -286.874966)
			(xy 283.469092 -286.874966) (xy 283.473052 -286.825912) (xy 283.484829 -286.778128) (xy 283.50412 -286.732852)
			(xy 283.530423 -286.691256) (xy 283.563058 -286.654419) (xy 283.601179 -286.623294) (xy 283.6438 -286.598687)
			(xy 283.689816 -286.581235) (xy 283.738035 -286.571391) (xy 283.78721 -286.56941) (xy 283.836065 -286.575342)
			(xy 283.883336 -286.589034) (xy 283.927798 -286.610132) (xy 283.968301 -286.638088) (xy 284.003794 -286.67218)
			(xy 284.033359 -286.711524) (xy 284.05623 -286.755101) (xy 284.071814 -286.801782) (xy 284.079709 -286.850359)
			(xy 284.080204 -286.874966) (xy 284.419052 -286.874966) (xy 284.423012 -286.825912) (xy 284.434789 -286.778128)
			(xy 284.45408 -286.732852) (xy 284.480383 -286.691256) (xy 284.513018 -286.654419) (xy 284.551139 -286.623294)
			(xy 284.59376 -286.598687) (xy 284.639776 -286.581235) (xy 284.687995 -286.571391) (xy 284.73717 -286.56941)
			(xy 284.786025 -286.575342) (xy 284.833296 -286.589034) (xy 284.877758 -286.610132) (xy 284.918261 -286.638088)
			(xy 284.953754 -286.67218) (xy 284.983319 -286.711524) (xy 285.00619 -286.755101) (xy 285.021774 -286.801782)
			(xy 285.029669 -286.850359) (xy 285.030164 -286.874966) (xy 285.369012 -286.874966) (xy 285.372972 -286.825912)
			(xy 285.384749 -286.778128) (xy 285.40404 -286.732852) (xy 285.430343 -286.691256) (xy 285.462978 -286.654419)
			(xy 285.501099 -286.623294) (xy 285.54372 -286.598687) (xy 285.589736 -286.581235) (xy 285.637955 -286.571391)
			(xy 285.68713 -286.56941) (xy 285.735985 -286.575342) (xy 285.783256 -286.589034) (xy 285.827718 -286.610132)
			(xy 285.868221 -286.638088) (xy 285.903714 -286.67218) (xy 285.933279 -286.711524) (xy 285.95615 -286.755101)
			(xy 285.971734 -286.801782) (xy 285.979629 -286.850359) (xy 285.980124 -286.874966) (xy 286.318972 -286.874966)
			(xy 286.322932 -286.825912) (xy 286.334709 -286.778128) (xy 286.354 -286.732852) (xy 286.380303 -286.691256)
			(xy 286.412938 -286.654419) (xy 286.451059 -286.623294) (xy 286.49368 -286.598687) (xy 286.539696 -286.581235)
			(xy 286.587915 -286.571391) (xy 286.63709 -286.56941) (xy 286.685945 -286.575342) (xy 286.733216 -286.589034)
			(xy 286.777678 -286.610132) (xy 286.818181 -286.638088) (xy 286.853674 -286.67218) (xy 286.883239 -286.711524)
			(xy 286.90611 -286.755101) (xy 286.921694 -286.801782) (xy 286.929589 -286.850359) (xy 286.930084 -286.874966)
			(xy 287.268932 -286.874966) (xy 287.272892 -286.825912) (xy 287.284669 -286.778128) (xy 287.30396 -286.732852)
			(xy 287.330263 -286.691256) (xy 287.362898 -286.654419) (xy 287.401019 -286.623294) (xy 287.44364 -286.598687)
			(xy 287.489656 -286.581235) (xy 287.537875 -286.571391) (xy 287.58705 -286.56941) (xy 287.635905 -286.575342)
			(xy 287.683176 -286.589034) (xy 287.727638 -286.610132) (xy 287.768141 -286.638088) (xy 287.803634 -286.67218)
			(xy 287.833199 -286.711524) (xy 287.85607 -286.755101) (xy 287.871654 -286.801782) (xy 287.879549 -286.850359)
			(xy 287.880044 -286.874966) (xy 288.218892 -286.874966) (xy 288.222852 -286.825912) (xy 288.234629 -286.778128)
			(xy 288.25392 -286.732852) (xy 288.280223 -286.691256) (xy 288.312858 -286.654419) (xy 288.350979 -286.623294)
			(xy 288.3936 -286.598687) (xy 288.439616 -286.581235) (xy 288.487835 -286.571391) (xy 288.53701 -286.56941)
			(xy 288.585865 -286.575342) (xy 288.633136 -286.589034) (xy 288.677598 -286.610132) (xy 288.718101 -286.638088)
			(xy 288.753594 -286.67218) (xy 288.783159 -286.711524) (xy 288.80603 -286.755101) (xy 288.821614 -286.801782)
			(xy 288.829509 -286.850359) (xy 288.830004 -286.874966) (xy 289.169106 -286.874966) (xy 289.173066 -286.825912)
			(xy 289.184843 -286.778128) (xy 289.204134 -286.732852) (xy 289.230437 -286.691256) (xy 289.263072 -286.654419)
			(xy 289.301193 -286.623294) (xy 289.343814 -286.598687) (xy 289.38983 -286.581235) (xy 289.438049 -286.571391)
			(xy 289.487224 -286.56941) (xy 289.536079 -286.575342) (xy 289.58335 -286.589034) (xy 289.627812 -286.610132)
			(xy 289.668315 -286.638088) (xy 289.703808 -286.67218) (xy 289.733373 -286.711524) (xy 289.756244 -286.755101)
			(xy 289.771828 -286.801782) (xy 289.779723 -286.850359) (xy 289.780218 -286.874966) (xy 290.119066 -286.874966)
			(xy 290.123026 -286.825912) (xy 290.134803 -286.778128) (xy 290.154094 -286.732852) (xy 290.180397 -286.691256)
			(xy 290.213032 -286.654419) (xy 290.251153 -286.623294) (xy 290.293774 -286.598687) (xy 290.33979 -286.581235)
			(xy 290.388009 -286.571391) (xy 290.437184 -286.56941) (xy 290.486039 -286.575342) (xy 290.53331 -286.589034)
			(xy 290.577772 -286.610132) (xy 290.618275 -286.638088) (xy 290.653768 -286.67218) (xy 290.683333 -286.711524)
			(xy 290.706204 -286.755101) (xy 290.721788 -286.801782) (xy 290.729683 -286.850359) (xy 290.730178 -286.874966)
			(xy 292.018986 -286.874966) (xy 292.022946 -286.825912) (xy 292.034723 -286.778128) (xy 292.054014 -286.732852)
			(xy 292.080317 -286.691256) (xy 292.112952 -286.654419) (xy 292.151073 -286.623294) (xy 292.193694 -286.598687)
			(xy 292.23971 -286.581235) (xy 292.287929 -286.571391) (xy 292.337104 -286.56941) (xy 292.385959 -286.575342)
			(xy 292.43323 -286.589034) (xy 292.477692 -286.610132) (xy 292.518195 -286.638088) (xy 292.553688 -286.67218)
			(xy 292.583253 -286.711524) (xy 292.606124 -286.755101) (xy 292.621708 -286.801782) (xy 292.629603 -286.850359)
			(xy 292.630098 -286.874966) (xy 292.968946 -286.874966) (xy 292.972906 -286.825912) (xy 292.984683 -286.778128)
			(xy 293.003974 -286.732852) (xy 293.030277 -286.691256) (xy 293.062912 -286.654419) (xy 293.101033 -286.623294)
			(xy 293.143654 -286.598687) (xy 293.18967 -286.581235) (xy 293.237889 -286.571391) (xy 293.287064 -286.56941)
			(xy 293.335919 -286.575342) (xy 293.38319 -286.589034) (xy 293.427652 -286.610132) (xy 293.468155 -286.638088)
			(xy 293.503648 -286.67218) (xy 293.533213 -286.711524) (xy 293.556084 -286.755101) (xy 293.571668 -286.801782)
			(xy 293.579563 -286.850359) (xy 293.580058 -286.874966) (xy 293.918906 -286.874966) (xy 293.922866 -286.825912)
			(xy 293.934643 -286.778128) (xy 293.953934 -286.732852) (xy 293.980237 -286.691256) (xy 294.012872 -286.654419)
			(xy 294.050993 -286.623294) (xy 294.093614 -286.598687) (xy 294.13963 -286.581235) (xy 294.187849 -286.571391)
			(xy 294.237024 -286.56941) (xy 294.285879 -286.575342) (xy 294.33315 -286.589034) (xy 294.377612 -286.610132)
			(xy 294.418115 -286.638088) (xy 294.453608 -286.67218) (xy 294.483173 -286.711524) (xy 294.506044 -286.755101)
			(xy 294.521628 -286.801782) (xy 294.529523 -286.850359) (xy 294.530018 -286.874966) (xy 294.86912 -286.874966)
			(xy 294.87308 -286.825912) (xy 294.884857 -286.778128) (xy 294.904148 -286.732852) (xy 294.930451 -286.691256)
			(xy 294.963086 -286.654419) (xy 295.001207 -286.623294) (xy 295.043828 -286.598687) (xy 295.089844 -286.581235)
			(xy 295.138063 -286.571391) (xy 295.187238 -286.56941) (xy 295.236093 -286.575342) (xy 295.283364 -286.589034)
			(xy 295.327826 -286.610132) (xy 295.368329 -286.638088) (xy 295.403822 -286.67218) (xy 295.433387 -286.711524)
			(xy 295.456258 -286.755101) (xy 295.471842 -286.801782) (xy 295.479737 -286.850359) (xy 295.480232 -286.874966)
			(xy 295.81908 -286.874966) (xy 295.82304 -286.825912) (xy 295.834817 -286.778128) (xy 295.854108 -286.732852)
			(xy 295.880411 -286.691256) (xy 295.913046 -286.654419) (xy 295.951167 -286.623294) (xy 295.993788 -286.598687)
			(xy 296.039804 -286.581235) (xy 296.088023 -286.571391) (xy 296.137198 -286.56941) (xy 296.186053 -286.575342)
			(xy 296.233324 -286.589034) (xy 296.277786 -286.610132) (xy 296.318289 -286.638088) (xy 296.353782 -286.67218)
			(xy 296.383347 -286.711524) (xy 296.406218 -286.755101) (xy 296.421802 -286.801782) (xy 296.429697 -286.850359)
			(xy 296.430192 -286.874966) (xy 296.76904 -286.874966) (xy 296.773 -286.825912) (xy 296.784777 -286.778128)
			(xy 296.804068 -286.732852) (xy 296.830371 -286.691256) (xy 296.863006 -286.654419) (xy 296.901127 -286.623294)
			(xy 296.943748 -286.598687) (xy 296.989764 -286.581235) (xy 297.037983 -286.571391) (xy 297.087158 -286.56941)
			(xy 297.136013 -286.575342) (xy 297.183284 -286.589034) (xy 297.227746 -286.610132) (xy 297.268249 -286.638088)
			(xy 297.303742 -286.67218) (xy 297.333307 -286.711524) (xy 297.356178 -286.755101) (xy 297.371762 -286.801782)
			(xy 297.379657 -286.850359) (xy 297.380152 -286.874966) (xy 297.719 -286.874966) (xy 297.72296 -286.825912)
			(xy 297.734737 -286.778128) (xy 297.754028 -286.732852) (xy 297.780331 -286.691256) (xy 297.812966 -286.654419)
			(xy 297.851087 -286.623294) (xy 297.893708 -286.598687) (xy 297.939724 -286.581235) (xy 297.987943 -286.571391)
			(xy 298.037118 -286.56941) (xy 298.085973 -286.575342) (xy 298.133244 -286.589034) (xy 298.177706 -286.610132)
			(xy 298.218209 -286.638088) (xy 298.253702 -286.67218) (xy 298.283267 -286.711524) (xy 298.306138 -286.755101)
			(xy 298.321722 -286.801782) (xy 298.329617 -286.850359) (xy 298.330112 -286.874966) (xy 298.66896 -286.874966)
			(xy 298.67292 -286.825912) (xy 298.684697 -286.778128) (xy 298.703988 -286.732852) (xy 298.730291 -286.691256)
			(xy 298.762926 -286.654419) (xy 298.801047 -286.623294) (xy 298.843668 -286.598687) (xy 298.889684 -286.581235)
			(xy 298.937903 -286.571391) (xy 298.987078 -286.56941) (xy 299.035933 -286.575342) (xy 299.083204 -286.589034)
			(xy 299.127666 -286.610132) (xy 299.168169 -286.638088) (xy 299.203662 -286.67218) (xy 299.233227 -286.711524)
			(xy 299.256098 -286.755101) (xy 299.271682 -286.801782) (xy 299.279577 -286.850359) (xy 299.280072 -286.874966)
			(xy 299.61892 -286.874966) (xy 299.62288 -286.825912) (xy 299.634657 -286.778128) (xy 299.653948 -286.732852)
			(xy 299.680251 -286.691256) (xy 299.712886 -286.654419) (xy 299.751007 -286.623294) (xy 299.793628 -286.598687)
			(xy 299.839644 -286.581235) (xy 299.887863 -286.571391) (xy 299.937038 -286.56941) (xy 299.985893 -286.575342)
			(xy 300.033164 -286.589034) (xy 300.077626 -286.610132) (xy 300.118129 -286.638088) (xy 300.153622 -286.67218)
			(xy 300.183187 -286.711524) (xy 300.206058 -286.755101) (xy 300.221642 -286.801782) (xy 300.229537 -286.850359)
			(xy 300.230032 -286.874966) (xy 300.56888 -286.874966) (xy 300.57284 -286.825912) (xy 300.584617 -286.778128)
			(xy 300.603908 -286.732852) (xy 300.630211 -286.691256) (xy 300.662846 -286.654419) (xy 300.700967 -286.623294)
			(xy 300.743588 -286.598687) (xy 300.789604 -286.581235) (xy 300.837823 -286.571391) (xy 300.886998 -286.56941)
			(xy 300.935853 -286.575342) (xy 300.983124 -286.589034) (xy 301.027586 -286.610132) (xy 301.068089 -286.638088)
			(xy 301.103582 -286.67218) (xy 301.133147 -286.711524) (xy 301.156018 -286.755101) (xy 301.171602 -286.801782)
			(xy 301.179497 -286.850359) (xy 301.179992 -286.874966) (xy 301.519094 -286.874966) (xy 301.523054 -286.825912)
			(xy 301.534831 -286.778128) (xy 301.554122 -286.732852) (xy 301.580425 -286.691256) (xy 301.61306 -286.654419)
			(xy 301.651181 -286.623294) (xy 301.693802 -286.598687) (xy 301.739818 -286.581235) (xy 301.788037 -286.571391)
			(xy 301.837212 -286.56941) (xy 301.886067 -286.575342) (xy 301.933338 -286.589034) (xy 301.9778 -286.610132)
			(xy 302.018303 -286.638088) (xy 302.053796 -286.67218) (xy 302.083361 -286.711524) (xy 302.106232 -286.755101)
			(xy 302.121816 -286.801782) (xy 302.129711 -286.850359) (xy 302.130206 -286.874966) (xy 302.469054 -286.874966)
			(xy 302.473014 -286.825912) (xy 302.484791 -286.778128) (xy 302.504082 -286.732852) (xy 302.530385 -286.691256)
			(xy 302.56302 -286.654419) (xy 302.601141 -286.623294) (xy 302.643762 -286.598687) (xy 302.689778 -286.581235)
			(xy 302.737997 -286.571391) (xy 302.787172 -286.56941) (xy 302.836027 -286.575342) (xy 302.883298 -286.589034)
			(xy 302.92776 -286.610132) (xy 302.968263 -286.638088) (xy 303.003756 -286.67218) (xy 303.033321 -286.711524)
			(xy 303.056192 -286.755101) (xy 303.071776 -286.801782) (xy 303.079671 -286.850359) (xy 303.080166 -286.874966)
			(xy 303.079671 -286.899573) (xy 303.071776 -286.94815) (xy 303.056192 -286.994831) (xy 303.033321 -287.038408)
			(xy 303.003756 -287.077752) (xy 302.968263 -287.111844) (xy 302.92776 -287.1398) (xy 302.883298 -287.160898)
			(xy 302.836027 -287.17459) (xy 302.787172 -287.180522) (xy 302.737997 -287.178541) (xy 302.689778 -287.168697)
			(xy 302.643762 -287.151245) (xy 302.601141 -287.126638) (xy 302.56302 -287.095513) (xy 302.530385 -287.058676)
			(xy 302.504082 -287.01708) (xy 302.484791 -286.971804) (xy 302.473014 -286.92402) (xy 302.469054 -286.874966)
			(xy 302.130206 -286.874966) (xy 302.129711 -286.899573) (xy 302.121816 -286.94815) (xy 302.106232 -286.994831)
			(xy 302.083361 -287.038408) (xy 302.053796 -287.077752) (xy 302.018303 -287.111844) (xy 301.9778 -287.1398)
			(xy 301.933338 -287.160898) (xy 301.886067 -287.17459) (xy 301.837212 -287.180522) (xy 301.788037 -287.178541)
			(xy 301.739818 -287.168697) (xy 301.693802 -287.151245) (xy 301.651181 -287.126638) (xy 301.61306 -287.095513)
			(xy 301.580425 -287.058676) (xy 301.554122 -287.01708) (xy 301.534831 -286.971804) (xy 301.523054 -286.92402)
			(xy 301.519094 -286.874966) (xy 301.179992 -286.874966) (xy 301.179497 -286.899573) (xy 301.171602 -286.94815)
			(xy 301.156018 -286.994831) (xy 301.133147 -287.038408) (xy 301.103582 -287.077752) (xy 301.068089 -287.111844)
			(xy 301.027586 -287.1398) (xy 300.983124 -287.160898) (xy 300.935853 -287.17459) (xy 300.886998 -287.180522)
			(xy 300.837823 -287.178541) (xy 300.789604 -287.168697) (xy 300.743588 -287.151245) (xy 300.700967 -287.126638)
			(xy 300.662846 -287.095513) (xy 300.630211 -287.058676) (xy 300.603908 -287.01708) (xy 300.584617 -286.971804)
			(xy 300.57284 -286.92402) (xy 300.56888 -286.874966) (xy 300.230032 -286.874966) (xy 300.229537 -286.899573)
			(xy 300.221642 -286.94815) (xy 300.206058 -286.994831) (xy 300.183187 -287.038408) (xy 300.153622 -287.077752)
			(xy 300.118129 -287.111844) (xy 300.077626 -287.1398) (xy 300.033164 -287.160898) (xy 299.985893 -287.17459)
			(xy 299.937038 -287.180522) (xy 299.887863 -287.178541) (xy 299.839644 -287.168697) (xy 299.793628 -287.151245)
			(xy 299.751007 -287.126638) (xy 299.712886 -287.095513) (xy 299.680251 -287.058676) (xy 299.653948 -287.01708)
			(xy 299.634657 -286.971804) (xy 299.62288 -286.92402) (xy 299.61892 -286.874966) (xy 299.280072 -286.874966)
			(xy 299.279577 -286.899573) (xy 299.271682 -286.94815) (xy 299.256098 -286.994831) (xy 299.233227 -287.038408)
			(xy 299.203662 -287.077752) (xy 299.168169 -287.111844) (xy 299.127666 -287.1398) (xy 299.083204 -287.160898)
			(xy 299.035933 -287.17459) (xy 298.987078 -287.180522) (xy 298.937903 -287.178541) (xy 298.889684 -287.168697)
			(xy 298.843668 -287.151245) (xy 298.801047 -287.126638) (xy 298.762926 -287.095513) (xy 298.730291 -287.058676)
			(xy 298.703988 -287.01708) (xy 298.684697 -286.971804) (xy 298.67292 -286.92402) (xy 298.66896 -286.874966)
			(xy 298.330112 -286.874966) (xy 298.329617 -286.899573) (xy 298.321722 -286.94815) (xy 298.306138 -286.994831)
			(xy 298.283267 -287.038408) (xy 298.253702 -287.077752) (xy 298.218209 -287.111844) (xy 298.177706 -287.1398)
			(xy 298.133244 -287.160898) (xy 298.085973 -287.17459) (xy 298.037118 -287.180522) (xy 297.987943 -287.178541)
			(xy 297.939724 -287.168697) (xy 297.893708 -287.151245) (xy 297.851087 -287.126638) (xy 297.812966 -287.095513)
			(xy 297.780331 -287.058676) (xy 297.754028 -287.01708) (xy 297.734737 -286.971804) (xy 297.72296 -286.92402)
			(xy 297.719 -286.874966) (xy 297.380152 -286.874966) (xy 297.379657 -286.899573) (xy 297.371762 -286.94815)
			(xy 297.356178 -286.994831) (xy 297.333307 -287.038408) (xy 297.303742 -287.077752) (xy 297.268249 -287.111844)
			(xy 297.227746 -287.1398) (xy 297.183284 -287.160898) (xy 297.136013 -287.17459) (xy 297.087158 -287.180522)
			(xy 297.037983 -287.178541) (xy 296.989764 -287.168697) (xy 296.943748 -287.151245) (xy 296.901127 -287.126638)
			(xy 296.863006 -287.095513) (xy 296.830371 -287.058676) (xy 296.804068 -287.01708) (xy 296.784777 -286.971804)
			(xy 296.773 -286.92402) (xy 296.76904 -286.874966) (xy 296.430192 -286.874966) (xy 296.429697 -286.899573)
			(xy 296.421802 -286.94815) (xy 296.406218 -286.994831) (xy 296.383347 -287.038408) (xy 296.353782 -287.077752)
			(xy 296.318289 -287.111844) (xy 296.277786 -287.1398) (xy 296.233324 -287.160898) (xy 296.186053 -287.17459)
			(xy 296.137198 -287.180522) (xy 296.088023 -287.178541) (xy 296.039804 -287.168697) (xy 295.993788 -287.151245)
			(xy 295.951167 -287.126638) (xy 295.913046 -287.095513) (xy 295.880411 -287.058676) (xy 295.854108 -287.01708)
			(xy 295.834817 -286.971804) (xy 295.82304 -286.92402) (xy 295.81908 -286.874966) (xy 295.480232 -286.874966)
			(xy 295.479737 -286.899573) (xy 295.471842 -286.94815) (xy 295.456258 -286.994831) (xy 295.433387 -287.038408)
			(xy 295.403822 -287.077752) (xy 295.368329 -287.111844) (xy 295.327826 -287.1398) (xy 295.283364 -287.160898)
			(xy 295.236093 -287.17459) (xy 295.187238 -287.180522) (xy 295.138063 -287.178541) (xy 295.089844 -287.168697)
			(xy 295.043828 -287.151245) (xy 295.001207 -287.126638) (xy 294.963086 -287.095513) (xy 294.930451 -287.058676)
			(xy 294.904148 -287.01708) (xy 294.884857 -286.971804) (xy 294.87308 -286.92402) (xy 294.86912 -286.874966)
			(xy 294.530018 -286.874966) (xy 294.529523 -286.899573) (xy 294.521628 -286.94815) (xy 294.506044 -286.994831)
			(xy 294.483173 -287.038408) (xy 294.453608 -287.077752) (xy 294.418115 -287.111844) (xy 294.377612 -287.1398)
			(xy 294.33315 -287.160898) (xy 294.285879 -287.17459) (xy 294.237024 -287.180522) (xy 294.187849 -287.178541)
			(xy 294.13963 -287.168697) (xy 294.093614 -287.151245) (xy 294.050993 -287.126638) (xy 294.012872 -287.095513)
			(xy 293.980237 -287.058676) (xy 293.953934 -287.01708) (xy 293.934643 -286.971804) (xy 293.922866 -286.92402)
			(xy 293.918906 -286.874966) (xy 293.580058 -286.874966) (xy 293.579563 -286.899573) (xy 293.571668 -286.94815)
			(xy 293.556084 -286.994831) (xy 293.533213 -287.038408) (xy 293.503648 -287.077752) (xy 293.468155 -287.111844)
			(xy 293.427652 -287.1398) (xy 293.38319 -287.160898) (xy 293.335919 -287.17459) (xy 293.287064 -287.180522)
			(xy 293.237889 -287.178541) (xy 293.18967 -287.168697) (xy 293.143654 -287.151245) (xy 293.101033 -287.126638)
			(xy 293.062912 -287.095513) (xy 293.030277 -287.058676) (xy 293.003974 -287.01708) (xy 292.984683 -286.971804)
			(xy 292.972906 -286.92402) (xy 292.968946 -286.874966) (xy 292.630098 -286.874966) (xy 292.629603 -286.899573)
			(xy 292.621708 -286.94815) (xy 292.606124 -286.994831) (xy 292.583253 -287.038408) (xy 292.553688 -287.077752)
			(xy 292.518195 -287.111844) (xy 292.477692 -287.1398) (xy 292.43323 -287.160898) (xy 292.385959 -287.17459)
			(xy 292.337104 -287.180522) (xy 292.287929 -287.178541) (xy 292.23971 -287.168697) (xy 292.193694 -287.151245)
			(xy 292.151073 -287.126638) (xy 292.112952 -287.095513) (xy 292.080317 -287.058676) (xy 292.054014 -287.01708)
			(xy 292.034723 -286.971804) (xy 292.022946 -286.92402) (xy 292.018986 -286.874966) (xy 290.730178 -286.874966)
			(xy 290.729683 -286.899573) (xy 290.721788 -286.94815) (xy 290.706204 -286.994831) (xy 290.683333 -287.038408)
			(xy 290.653768 -287.077752) (xy 290.618275 -287.111844) (xy 290.577772 -287.1398) (xy 290.53331 -287.160898)
			(xy 290.486039 -287.17459) (xy 290.437184 -287.180522) (xy 290.388009 -287.178541) (xy 290.33979 -287.168697)
			(xy 290.293774 -287.151245) (xy 290.251153 -287.126638) (xy 290.213032 -287.095513) (xy 290.180397 -287.058676)
			(xy 290.154094 -287.01708) (xy 290.134803 -286.971804) (xy 290.123026 -286.92402) (xy 290.119066 -286.874966)
			(xy 289.780218 -286.874966) (xy 289.779723 -286.899573) (xy 289.771828 -286.94815) (xy 289.756244 -286.994831)
			(xy 289.733373 -287.038408) (xy 289.703808 -287.077752) (xy 289.668315 -287.111844) (xy 289.627812 -287.1398)
			(xy 289.58335 -287.160898) (xy 289.536079 -287.17459) (xy 289.487224 -287.180522) (xy 289.438049 -287.178541)
			(xy 289.38983 -287.168697) (xy 289.343814 -287.151245) (xy 289.301193 -287.126638) (xy 289.263072 -287.095513)
			(xy 289.230437 -287.058676) (xy 289.204134 -287.01708) (xy 289.184843 -286.971804) (xy 289.173066 -286.92402)
			(xy 289.169106 -286.874966) (xy 288.830004 -286.874966) (xy 288.829509 -286.899573) (xy 288.821614 -286.94815)
			(xy 288.80603 -286.994831) (xy 288.783159 -287.038408) (xy 288.753594 -287.077752) (xy 288.718101 -287.111844)
			(xy 288.677598 -287.1398) (xy 288.633136 -287.160898) (xy 288.585865 -287.17459) (xy 288.53701 -287.180522)
			(xy 288.487835 -287.178541) (xy 288.439616 -287.168697) (xy 288.3936 -287.151245) (xy 288.350979 -287.126638)
			(xy 288.312858 -287.095513) (xy 288.280223 -287.058676) (xy 288.25392 -287.01708) (xy 288.234629 -286.971804)
			(xy 288.222852 -286.92402) (xy 288.218892 -286.874966) (xy 287.880044 -286.874966) (xy 287.879549 -286.899573)
			(xy 287.871654 -286.94815) (xy 287.85607 -286.994831) (xy 287.833199 -287.038408) (xy 287.803634 -287.077752)
			(xy 287.768141 -287.111844) (xy 287.727638 -287.1398) (xy 287.683176 -287.160898) (xy 287.635905 -287.17459)
			(xy 287.58705 -287.180522) (xy 287.537875 -287.178541) (xy 287.489656 -287.168697) (xy 287.44364 -287.151245)
			(xy 287.401019 -287.126638) (xy 287.362898 -287.095513) (xy 287.330263 -287.058676) (xy 287.30396 -287.01708)
			(xy 287.284669 -286.971804) (xy 287.272892 -286.92402) (xy 287.268932 -286.874966) (xy 286.930084 -286.874966)
			(xy 286.929589 -286.899573) (xy 286.921694 -286.94815) (xy 286.90611 -286.994831) (xy 286.883239 -287.038408)
			(xy 286.853674 -287.077752) (xy 286.818181 -287.111844) (xy 286.777678 -287.1398) (xy 286.733216 -287.160898)
			(xy 286.685945 -287.17459) (xy 286.63709 -287.180522) (xy 286.587915 -287.178541) (xy 286.539696 -287.168697)
			(xy 286.49368 -287.151245) (xy 286.451059 -287.126638) (xy 286.412938 -287.095513) (xy 286.380303 -287.058676)
			(xy 286.354 -287.01708) (xy 286.334709 -286.971804) (xy 286.322932 -286.92402) (xy 286.318972 -286.874966)
			(xy 285.980124 -286.874966) (xy 285.979629 -286.899573) (xy 285.971734 -286.94815) (xy 285.95615 -286.994831)
			(xy 285.933279 -287.038408) (xy 285.903714 -287.077752) (xy 285.868221 -287.111844) (xy 285.827718 -287.1398)
			(xy 285.783256 -287.160898) (xy 285.735985 -287.17459) (xy 285.68713 -287.180522) (xy 285.637955 -287.178541)
			(xy 285.589736 -287.168697) (xy 285.54372 -287.151245) (xy 285.501099 -287.126638) (xy 285.462978 -287.095513)
			(xy 285.430343 -287.058676) (xy 285.40404 -287.01708) (xy 285.384749 -286.971804) (xy 285.372972 -286.92402)
			(xy 285.369012 -286.874966) (xy 285.030164 -286.874966) (xy 285.029669 -286.899573) (xy 285.021774 -286.94815)
			(xy 285.00619 -286.994831) (xy 284.983319 -287.038408) (xy 284.953754 -287.077752) (xy 284.918261 -287.111844)
			(xy 284.877758 -287.1398) (xy 284.833296 -287.160898) (xy 284.786025 -287.17459) (xy 284.73717 -287.180522)
			(xy 284.687995 -287.178541) (xy 284.639776 -287.168697) (xy 284.59376 -287.151245) (xy 284.551139 -287.126638)
			(xy 284.513018 -287.095513) (xy 284.480383 -287.058676) (xy 284.45408 -287.01708) (xy 284.434789 -286.971804)
			(xy 284.423012 -286.92402) (xy 284.419052 -286.874966) (xy 284.080204 -286.874966) (xy 284.079709 -286.899573)
			(xy 284.071814 -286.94815) (xy 284.05623 -286.994831) (xy 284.033359 -287.038408) (xy 284.003794 -287.077752)
			(xy 283.968301 -287.111844) (xy 283.927798 -287.1398) (xy 283.883336 -287.160898) (xy 283.836065 -287.17459)
			(xy 283.78721 -287.180522) (xy 283.738035 -287.178541) (xy 283.689816 -287.168697) (xy 283.6438 -287.151245)
			(xy 283.601179 -287.126638) (xy 283.563058 -287.095513) (xy 283.530423 -287.058676) (xy 283.50412 -287.01708)
			(xy 283.484829 -286.971804) (xy 283.473052 -286.92402) (xy 283.469092 -286.874966) (xy 283.130244 -286.874966)
			(xy 283.129749 -286.899573) (xy 283.121854 -286.94815) (xy 283.10627 -286.994831) (xy 283.083399 -287.038408)
			(xy 283.053834 -287.077752) (xy 283.018341 -287.111844) (xy 282.977838 -287.1398) (xy 282.933376 -287.160898)
			(xy 282.886105 -287.17459) (xy 282.83725 -287.180522) (xy 282.788075 -287.178541) (xy 282.739856 -287.168697)
			(xy 282.69384 -287.151245) (xy 282.651219 -287.126638) (xy 282.613098 -287.095513) (xy 282.580463 -287.058676)
			(xy 282.55416 -287.01708) (xy 282.534869 -286.971804) (xy 282.523092 -286.92402) (xy 282.519132 -286.874966)
			(xy 282.180562 -286.874966) (xy 282.180565 -286.875) (xy 282.176394 -286.925341) (xy 282.163994 -286.97431)
			(xy 282.143704 -287.02057) (xy 282.116076 -287.062859) (xy 282.081865 -287.100024) (xy 282.042004 -287.131052)
			(xy 281.997579 -287.155096) (xy 281.949803 -287.171501) (xy 281.899979 -287.179819) (xy 281.874722 -287.180274)
			(xy 281.844648 -287.179581) (xy 281.785662 -287.167814) (xy 281.757628 -287.156906) (xy 281.745436 -287.151826)
			(xy 281.720544 -287.154366) (xy 281.639518 -287.208468) (xy 281.629456 -287.215985) (xy 281.617596 -287.238092)
			(xy 281.616912 -287.250632) (xy 281.616912 -287.349946) (xy 305.793914 -287.349946) (xy 305.797874 -287.300892)
			(xy 305.809651 -287.253108) (xy 305.828942 -287.207832) (xy 305.855245 -287.166236) (xy 305.88788 -287.129399)
			(xy 305.926001 -287.098274) (xy 305.968622 -287.073667) (xy 306.014638 -287.056215) (xy 306.062857 -287.046371)
			(xy 306.112032 -287.04439) (xy 306.160887 -287.050322) (xy 306.208158 -287.064014) (xy 306.25262 -287.085112)
			(xy 306.293123 -287.113068) (xy 306.328616 -287.14716) (xy 306.358181 -287.186504) (xy 306.381052 -287.230081)
			(xy 306.396636 -287.276762) (xy 306.404531 -287.325339) (xy 306.405026 -287.349946) (xy 306.404531 -287.374553)
			(xy 306.404352 -287.375654) (xy 306.72303 -287.375654) (xy 306.72303 -287.324238) (xy 306.731073 -287.273456)
			(xy 306.746961 -287.224557) (xy 306.770304 -287.178745) (xy 306.800525 -287.137149) (xy 306.836881 -287.100793)
			(xy 306.878477 -287.070572) (xy 306.924289 -287.047229) (xy 306.973188 -287.031341) (xy 307.02397 -287.023298)
			(xy 307.075386 -287.023298) (xy 307.126168 -287.031341) (xy 307.175067 -287.047229) (xy 307.220879 -287.070572)
			(xy 307.262475 -287.100793) (xy 307.298831 -287.137149) (xy 307.329052 -287.178745) (xy 307.352395 -287.224557)
			(xy 307.368283 -287.273456) (xy 307.376326 -287.324238) (xy 307.37683 -287.349946) (xy 307.376326 -287.375654)
			(xy 307.673244 -287.375654) (xy 307.673244 -287.324238) (xy 307.681287 -287.273456) (xy 307.697175 -287.224557)
			(xy 307.720518 -287.178745) (xy 307.750739 -287.137149) (xy 307.787095 -287.100793) (xy 307.828691 -287.070572)
			(xy 307.874503 -287.047229) (xy 307.923402 -287.031341) (xy 307.974184 -287.023298) (xy 308.0256 -287.023298)
			(xy 308.076382 -287.031341) (xy 308.125281 -287.047229) (xy 308.171093 -287.070572) (xy 308.212689 -287.100793)
			(xy 308.249045 -287.137149) (xy 308.279266 -287.178745) (xy 308.302609 -287.224557) (xy 308.318497 -287.273456)
			(xy 308.32654 -287.324238) (xy 308.327044 -287.349946) (xy 308.644048 -287.349946) (xy 308.648008 -287.300892)
			(xy 308.659785 -287.253108) (xy 308.679076 -287.207832) (xy 308.705379 -287.166236) (xy 308.738014 -287.129399)
			(xy 308.776135 -287.098274) (xy 308.818756 -287.073667) (xy 308.864772 -287.056215) (xy 308.912991 -287.046371)
			(xy 308.962166 -287.04439) (xy 309.011021 -287.050322) (xy 309.058292 -287.064014) (xy 309.102754 -287.085112)
			(xy 309.143257 -287.113068) (xy 309.17875 -287.14716) (xy 309.208315 -287.186504) (xy 309.231186 -287.230081)
			(xy 309.24677 -287.276762) (xy 309.254665 -287.325339) (xy 309.25516 -287.349946) (xy 309.594008 -287.349946)
			(xy 309.597968 -287.300892) (xy 309.609745 -287.253108) (xy 309.629036 -287.207832) (xy 309.655339 -287.166236)
			(xy 309.687974 -287.129399) (xy 309.726095 -287.098274) (xy 309.768716 -287.073667) (xy 309.814732 -287.056215)
			(xy 309.862951 -287.046371) (xy 309.912126 -287.04439) (xy 309.960981 -287.050322) (xy 310.008252 -287.064014)
			(xy 310.052714 -287.085112) (xy 310.093217 -287.113068) (xy 310.12871 -287.14716) (xy 310.158275 -287.186504)
			(xy 310.181146 -287.230081) (xy 310.19673 -287.276762) (xy 310.204625 -287.325339) (xy 310.20512 -287.349946)
			(xy 310.543968 -287.349946) (xy 310.547928 -287.300892) (xy 310.559705 -287.253108) (xy 310.578996 -287.207832)
			(xy 310.605299 -287.166236) (xy 310.637934 -287.129399) (xy 310.676055 -287.098274) (xy 310.718676 -287.073667)
			(xy 310.764692 -287.056215) (xy 310.812911 -287.046371) (xy 310.862086 -287.04439) (xy 310.910941 -287.050322)
			(xy 310.958212 -287.064014) (xy 311.002674 -287.085112) (xy 311.043177 -287.113068) (xy 311.07867 -287.14716)
			(xy 311.108235 -287.186504) (xy 311.131106 -287.230081) (xy 311.14669 -287.276762) (xy 311.154585 -287.325339)
			(xy 311.15508 -287.349946) (xy 311.493674 -287.349946) (xy 311.497634 -287.300892) (xy 311.509411 -287.253108)
			(xy 311.528702 -287.207832) (xy 311.555005 -287.166236) (xy 311.58764 -287.129399) (xy 311.625761 -287.098274)
			(xy 311.668382 -287.073667) (xy 311.714398 -287.056215) (xy 311.762617 -287.046371) (xy 311.811792 -287.04439)
			(xy 311.860647 -287.050322) (xy 311.907918 -287.064014) (xy 311.95238 -287.085112) (xy 311.992883 -287.113068)
			(xy 312.028376 -287.14716) (xy 312.057941 -287.186504) (xy 312.080812 -287.230081) (xy 312.096396 -287.276762)
			(xy 312.104291 -287.325339) (xy 312.104786 -287.349946) (xy 312.443888 -287.349946) (xy 312.447848 -287.300892)
			(xy 312.459625 -287.253108) (xy 312.478916 -287.207832) (xy 312.505219 -287.166236) (xy 312.537854 -287.129399)
			(xy 312.575975 -287.098274) (xy 312.618596 -287.073667) (xy 312.664612 -287.056215) (xy 312.712831 -287.046371)
			(xy 312.762006 -287.04439) (xy 312.810861 -287.050322) (xy 312.858132 -287.064014) (xy 312.902594 -287.085112)
			(xy 312.943097 -287.113068) (xy 312.97859 -287.14716) (xy 313.008155 -287.186504) (xy 313.031026 -287.230081)
			(xy 313.04661 -287.276762) (xy 313.054505 -287.325339) (xy 313.055 -287.349946) (xy 313.054505 -287.374553)
			(xy 313.054326 -287.375654) (xy 313.373258 -287.375654) (xy 313.373258 -287.324238) (xy 313.381301 -287.273456)
			(xy 313.397189 -287.224557) (xy 313.420532 -287.178745) (xy 313.450753 -287.137149) (xy 313.487109 -287.100793)
			(xy 313.528705 -287.070572) (xy 313.574517 -287.047229) (xy 313.623416 -287.031341) (xy 313.674198 -287.023298)
			(xy 313.725614 -287.023298) (xy 313.776396 -287.031341) (xy 313.825295 -287.047229) (xy 313.871107 -287.070572)
			(xy 313.912703 -287.100793) (xy 313.949059 -287.137149) (xy 313.97928 -287.178745) (xy 314.002623 -287.224557)
			(xy 314.018511 -287.273456) (xy 314.026554 -287.324238) (xy 314.027058 -287.349946) (xy 314.026554 -287.375654)
			(xy 314.323218 -287.375654) (xy 314.323218 -287.324238) (xy 314.331261 -287.273456) (xy 314.347149 -287.224557)
			(xy 314.370492 -287.178745) (xy 314.400713 -287.137149) (xy 314.437069 -287.100793) (xy 314.478665 -287.070572)
			(xy 314.524477 -287.047229) (xy 314.573376 -287.031341) (xy 314.624158 -287.023298) (xy 314.675574 -287.023298)
			(xy 314.726356 -287.031341) (xy 314.775255 -287.047229) (xy 314.821067 -287.070572) (xy 314.862663 -287.100793)
			(xy 314.899019 -287.137149) (xy 314.92924 -287.178745) (xy 314.952583 -287.224557) (xy 314.968471 -287.273456)
			(xy 314.976514 -287.324238) (xy 314.977018 -287.349946) (xy 314.977013 -287.3502) (xy 315.294276 -287.3502)
			(xy 315.298236 -287.301146) (xy 315.310013 -287.253362) (xy 315.329304 -287.208086) (xy 315.355607 -287.16649)
			(xy 315.388242 -287.129653) (xy 315.426363 -287.098528) (xy 315.468984 -287.073921) (xy 315.515 -287.056469)
			(xy 315.563219 -287.046625) (xy 315.612394 -287.044644) (xy 315.661249 -287.050576) (xy 315.70852 -287.064268)
			(xy 315.752982 -287.085366) (xy 315.793485 -287.113322) (xy 315.828978 -287.147414) (xy 315.858543 -287.186758)
			(xy 315.881414 -287.230335) (xy 315.896998 -287.277016) (xy 315.904893 -287.325593) (xy 315.905388 -287.3502)
			(xy 315.904893 -287.374807) (xy 315.896998 -287.423384) (xy 315.881414 -287.470065) (xy 315.858543 -287.513642)
			(xy 315.828978 -287.552986) (xy 315.793485 -287.587078) (xy 315.752982 -287.615034) (xy 315.70852 -287.636132)
			(xy 315.661249 -287.649824) (xy 315.612394 -287.655756) (xy 315.563219 -287.653775) (xy 315.515 -287.643931)
			(xy 315.468984 -287.626479) (xy 315.426363 -287.601872) (xy 315.388242 -287.570747) (xy 315.355607 -287.53391)
			(xy 315.329304 -287.492314) (xy 315.310013 -287.447038) (xy 315.298236 -287.399254) (xy 315.294276 -287.3502)
			(xy 314.977013 -287.3502) (xy 314.976514 -287.375654) (xy 314.968471 -287.426436) (xy 314.952583 -287.475335)
			(xy 314.92924 -287.521147) (xy 314.899019 -287.562743) (xy 314.862663 -287.599099) (xy 314.821067 -287.62932)
			(xy 314.775255 -287.652663) (xy 314.726356 -287.668551) (xy 314.675574 -287.676594) (xy 314.624158 -287.676594)
			(xy 314.573376 -287.668551) (xy 314.524477 -287.652663) (xy 314.478665 -287.62932) (xy 314.437069 -287.599099)
			(xy 314.400713 -287.562743) (xy 314.370492 -287.521147) (xy 314.347149 -287.475335) (xy 314.331261 -287.426436)
			(xy 314.323218 -287.375654) (xy 314.026554 -287.375654) (xy 314.018511 -287.426436) (xy 314.002623 -287.475335)
			(xy 313.97928 -287.521147) (xy 313.949059 -287.562743) (xy 313.912703 -287.599099) (xy 313.871107 -287.62932)
			(xy 313.825295 -287.652663) (xy 313.776396 -287.668551) (xy 313.725614 -287.676594) (xy 313.674198 -287.676594)
			(xy 313.623416 -287.668551) (xy 313.574517 -287.652663) (xy 313.528705 -287.62932) (xy 313.487109 -287.599099)
			(xy 313.450753 -287.562743) (xy 313.420532 -287.521147) (xy 313.397189 -287.475335) (xy 313.381301 -287.426436)
			(xy 313.373258 -287.375654) (xy 313.054326 -287.375654) (xy 313.04661 -287.42313) (xy 313.031026 -287.469811)
			(xy 313.008155 -287.513388) (xy 312.97859 -287.552732) (xy 312.943097 -287.586824) (xy 312.902594 -287.61478)
			(xy 312.858132 -287.635878) (xy 312.810861 -287.64957) (xy 312.762006 -287.655502) (xy 312.712831 -287.653521)
			(xy 312.664612 -287.643677) (xy 312.618596 -287.626225) (xy 312.575975 -287.601618) (xy 312.537854 -287.570493)
			(xy 312.505219 -287.533656) (xy 312.478916 -287.49206) (xy 312.459625 -287.446784) (xy 312.447848 -287.399)
			(xy 312.443888 -287.349946) (xy 312.104786 -287.349946) (xy 312.104291 -287.374553) (xy 312.096396 -287.42313)
			(xy 312.080812 -287.469811) (xy 312.057941 -287.513388) (xy 312.028376 -287.552732) (xy 311.992883 -287.586824)
			(xy 311.95238 -287.61478) (xy 311.907918 -287.635878) (xy 311.860647 -287.64957) (xy 311.811792 -287.655502)
			(xy 311.762617 -287.653521) (xy 311.714398 -287.643677) (xy 311.668382 -287.626225) (xy 311.625761 -287.601618)
			(xy 311.58764 -287.570493) (xy 311.555005 -287.533656) (xy 311.528702 -287.49206) (xy 311.509411 -287.446784)
			(xy 311.497634 -287.399) (xy 311.493674 -287.349946) (xy 311.15508 -287.349946) (xy 311.154585 -287.374553)
			(xy 311.14669 -287.42313) (xy 311.131106 -287.469811) (xy 311.108235 -287.513388) (xy 311.07867 -287.552732)
			(xy 311.043177 -287.586824) (xy 311.002674 -287.61478) (xy 310.958212 -287.635878) (xy 310.910941 -287.64957)
			(xy 310.862086 -287.655502) (xy 310.812911 -287.653521) (xy 310.764692 -287.643677) (xy 310.718676 -287.626225)
			(xy 310.676055 -287.601618) (xy 310.637934 -287.570493) (xy 310.605299 -287.533656) (xy 310.578996 -287.49206)
			(xy 310.559705 -287.446784) (xy 310.547928 -287.399) (xy 310.543968 -287.349946) (xy 310.20512 -287.349946)
			(xy 310.204625 -287.374553) (xy 310.19673 -287.42313) (xy 310.181146 -287.469811) (xy 310.158275 -287.513388)
			(xy 310.12871 -287.552732) (xy 310.093217 -287.586824) (xy 310.052714 -287.61478) (xy 310.008252 -287.635878)
			(xy 309.960981 -287.64957) (xy 309.912126 -287.655502) (xy 309.862951 -287.653521) (xy 309.814732 -287.643677)
			(xy 309.768716 -287.626225) (xy 309.726095 -287.601618) (xy 309.687974 -287.570493) (xy 309.655339 -287.533656)
			(xy 309.629036 -287.49206) (xy 309.609745 -287.446784) (xy 309.597968 -287.399) (xy 309.594008 -287.349946)
			(xy 309.25516 -287.349946) (xy 309.254665 -287.374553) (xy 309.24677 -287.42313) (xy 309.231186 -287.469811)
			(xy 309.208315 -287.513388) (xy 309.17875 -287.552732) (xy 309.143257 -287.586824) (xy 309.102754 -287.61478)
			(xy 309.058292 -287.635878) (xy 309.011021 -287.64957) (xy 308.962166 -287.655502) (xy 308.912991 -287.653521)
			(xy 308.864772 -287.643677) (xy 308.818756 -287.626225) (xy 308.776135 -287.601618) (xy 308.738014 -287.570493)
			(xy 308.705379 -287.533656) (xy 308.679076 -287.49206) (xy 308.659785 -287.446784) (xy 308.648008 -287.399)
			(xy 308.644048 -287.349946) (xy 308.327044 -287.349946) (xy 308.32654 -287.375654) (xy 308.318497 -287.426436)
			(xy 308.302609 -287.475335) (xy 308.279266 -287.521147) (xy 308.249045 -287.562743) (xy 308.212689 -287.599099)
			(xy 308.171093 -287.62932) (xy 308.125281 -287.652663) (xy 308.076382 -287.668551) (xy 308.0256 -287.676594)
			(xy 307.974184 -287.676594) (xy 307.923402 -287.668551) (xy 307.874503 -287.652663) (xy 307.828691 -287.62932)
			(xy 307.787095 -287.599099) (xy 307.750739 -287.562743) (xy 307.720518 -287.521147) (xy 307.697175 -287.475335)
			(xy 307.681287 -287.426436) (xy 307.673244 -287.375654) (xy 307.376326 -287.375654) (xy 307.368283 -287.426436)
			(xy 307.352395 -287.475335) (xy 307.329052 -287.521147) (xy 307.298831 -287.562743) (xy 307.262475 -287.599099)
			(xy 307.220879 -287.62932) (xy 307.175067 -287.652663) (xy 307.126168 -287.668551) (xy 307.075386 -287.676594)
			(xy 307.02397 -287.676594) (xy 306.973188 -287.668551) (xy 306.924289 -287.652663) (xy 306.878477 -287.62932)
			(xy 306.836881 -287.599099) (xy 306.800525 -287.562743) (xy 306.770304 -287.521147) (xy 306.746961 -287.475335)
			(xy 306.731073 -287.426436) (xy 306.72303 -287.375654) (xy 306.404352 -287.375654) (xy 306.396636 -287.42313)
			(xy 306.381052 -287.469811) (xy 306.358181 -287.513388) (xy 306.328616 -287.552732) (xy 306.293123 -287.586824)
			(xy 306.25262 -287.61478) (xy 306.208158 -287.635878) (xy 306.160887 -287.64957) (xy 306.112032 -287.655502)
			(xy 306.062857 -287.653521) (xy 306.014638 -287.643677) (xy 305.968622 -287.626225) (xy 305.926001 -287.601618)
			(xy 305.88788 -287.570493) (xy 305.855245 -287.533656) (xy 305.828942 -287.49206) (xy 305.809651 -287.446784)
			(xy 305.797874 -287.399) (xy 305.793914 -287.349946) (xy 281.616912 -287.349946) (xy 281.616912 -287.44926)
			(xy 281.617567 -287.461809) (xy 281.629437 -287.48392) (xy 281.639518 -287.491424) (xy 281.720544 -287.545526)
			(xy 281.745436 -287.548066) (xy 281.757628 -287.542986) (xy 281.785665 -287.532088) (xy 281.844649 -287.520322)
			(xy 281.874722 -287.519618) (xy 281.899974 -287.520141) (xy 281.949789 -287.528457) (xy 281.997555 -287.544858)
			(xy 282.041971 -287.568898) (xy 282.081825 -287.59992) (xy 282.116029 -287.637078) (xy 282.143651 -287.679359)
			(xy 282.163937 -287.72561) (xy 282.176335 -287.774568) (xy 282.180505 -287.8249) (xy 282.180503 -287.824926)
			(xy 282.519132 -287.824926) (xy 282.523092 -287.775872) (xy 282.534869 -287.728088) (xy 282.55416 -287.682812)
			(xy 282.580463 -287.641216) (xy 282.613098 -287.604379) (xy 282.651219 -287.573254) (xy 282.69384 -287.548647)
			(xy 282.739856 -287.531195) (xy 282.788075 -287.521351) (xy 282.83725 -287.51937) (xy 282.886105 -287.525302)
			(xy 282.933376 -287.538994) (xy 282.977838 -287.560092) (xy 283.018341 -287.588048) (xy 283.053834 -287.62214)
			(xy 283.083399 -287.661484) (xy 283.10627 -287.705061) (xy 283.121854 -287.751742) (xy 283.129749 -287.800319)
			(xy 283.130244 -287.824926) (xy 283.469092 -287.824926) (xy 283.473052 -287.775872) (xy 283.484829 -287.728088)
			(xy 283.50412 -287.682812) (xy 283.530423 -287.641216) (xy 283.563058 -287.604379) (xy 283.601179 -287.573254)
			(xy 283.6438 -287.548647) (xy 283.689816 -287.531195) (xy 283.738035 -287.521351) (xy 283.78721 -287.51937)
			(xy 283.836065 -287.525302) (xy 283.883336 -287.538994) (xy 283.927798 -287.560092) (xy 283.968301 -287.588048)
			(xy 284.003794 -287.62214) (xy 284.033359 -287.661484) (xy 284.05623 -287.705061) (xy 284.071814 -287.751742)
			(xy 284.079709 -287.800319) (xy 284.080204 -287.824926) (xy 284.419052 -287.824926) (xy 284.423012 -287.775872)
			(xy 284.434789 -287.728088) (xy 284.45408 -287.682812) (xy 284.480383 -287.641216) (xy 284.513018 -287.604379)
			(xy 284.551139 -287.573254) (xy 284.59376 -287.548647) (xy 284.639776 -287.531195) (xy 284.687995 -287.521351)
			(xy 284.73717 -287.51937) (xy 284.786025 -287.525302) (xy 284.833296 -287.538994) (xy 284.877758 -287.560092)
			(xy 284.918261 -287.588048) (xy 284.953754 -287.62214) (xy 284.983319 -287.661484) (xy 285.00619 -287.705061)
			(xy 285.021774 -287.751742) (xy 285.029669 -287.800319) (xy 285.030164 -287.824926) (xy 285.369012 -287.824926)
			(xy 285.372972 -287.775872) (xy 285.384749 -287.728088) (xy 285.40404 -287.682812) (xy 285.430343 -287.641216)
			(xy 285.462978 -287.604379) (xy 285.501099 -287.573254) (xy 285.54372 -287.548647) (xy 285.589736 -287.531195)
			(xy 285.637955 -287.521351) (xy 285.68713 -287.51937) (xy 285.735985 -287.525302) (xy 285.783256 -287.538994)
			(xy 285.827718 -287.560092) (xy 285.868221 -287.588048) (xy 285.903714 -287.62214) (xy 285.933279 -287.661484)
			(xy 285.95615 -287.705061) (xy 285.971734 -287.751742) (xy 285.979629 -287.800319) (xy 285.980124 -287.824926)
			(xy 286.318972 -287.824926) (xy 286.322932 -287.775872) (xy 286.334709 -287.728088) (xy 286.354 -287.682812)
			(xy 286.380303 -287.641216) (xy 286.412938 -287.604379) (xy 286.451059 -287.573254) (xy 286.49368 -287.548647)
			(xy 286.539696 -287.531195) (xy 286.587915 -287.521351) (xy 286.63709 -287.51937) (xy 286.685945 -287.525302)
			(xy 286.733216 -287.538994) (xy 286.777678 -287.560092) (xy 286.818181 -287.588048) (xy 286.853674 -287.62214)
			(xy 286.883239 -287.661484) (xy 286.90611 -287.705061) (xy 286.921694 -287.751742) (xy 286.929589 -287.800319)
			(xy 286.930084 -287.824926) (xy 287.268932 -287.824926) (xy 287.272892 -287.775872) (xy 287.284669 -287.728088)
			(xy 287.30396 -287.682812) (xy 287.330263 -287.641216) (xy 287.362898 -287.604379) (xy 287.401019 -287.573254)
			(xy 287.44364 -287.548647) (xy 287.489656 -287.531195) (xy 287.537875 -287.521351) (xy 287.58705 -287.51937)
			(xy 287.635905 -287.525302) (xy 287.683176 -287.538994) (xy 287.727638 -287.560092) (xy 287.768141 -287.588048)
			(xy 287.803634 -287.62214) (xy 287.833199 -287.661484) (xy 287.85607 -287.705061) (xy 287.871654 -287.751742)
			(xy 287.879549 -287.800319) (xy 287.880044 -287.824926) (xy 288.218892 -287.824926) (xy 288.222852 -287.775872)
			(xy 288.234629 -287.728088) (xy 288.25392 -287.682812) (xy 288.280223 -287.641216) (xy 288.312858 -287.604379)
			(xy 288.350979 -287.573254) (xy 288.3936 -287.548647) (xy 288.439616 -287.531195) (xy 288.487835 -287.521351)
			(xy 288.53701 -287.51937) (xy 288.585865 -287.525302) (xy 288.633136 -287.538994) (xy 288.677598 -287.560092)
			(xy 288.718101 -287.588048) (xy 288.753594 -287.62214) (xy 288.783159 -287.661484) (xy 288.80603 -287.705061)
			(xy 288.821614 -287.751742) (xy 288.829509 -287.800319) (xy 288.830004 -287.824926) (xy 289.169106 -287.824926)
			(xy 289.173066 -287.775872) (xy 289.184843 -287.728088) (xy 289.204134 -287.682812) (xy 289.230437 -287.641216)
			(xy 289.263072 -287.604379) (xy 289.301193 -287.573254) (xy 289.343814 -287.548647) (xy 289.38983 -287.531195)
			(xy 289.438049 -287.521351) (xy 289.487224 -287.51937) (xy 289.536079 -287.525302) (xy 289.58335 -287.538994)
			(xy 289.627812 -287.560092) (xy 289.668315 -287.588048) (xy 289.703808 -287.62214) (xy 289.733373 -287.661484)
			(xy 289.753566 -287.699958) (xy 290.143958 -287.699958) (xy 290.147918 -287.650904) (xy 290.159695 -287.60312)
			(xy 290.178986 -287.557844) (xy 290.205289 -287.516248) (xy 290.237924 -287.479411) (xy 290.276045 -287.448286)
			(xy 290.318666 -287.423679) (xy 290.364682 -287.406227) (xy 290.412901 -287.396383) (xy 290.462076 -287.394402)
			(xy 290.510931 -287.400334) (xy 290.558202 -287.414026) (xy 290.602664 -287.435124) (xy 290.643167 -287.46308)
			(xy 290.67866 -287.497172) (xy 290.708225 -287.536516) (xy 290.731096 -287.580093) (xy 290.74668 -287.626774)
			(xy 290.754575 -287.675351) (xy 290.75507 -287.699958) (xy 290.754575 -287.724565) (xy 290.74668 -287.773142)
			(xy 290.731096 -287.819823) (xy 290.708225 -287.8634) (xy 290.68083 -287.899856) (xy 292.018986 -287.899856)
			(xy 292.022946 -287.850802) (xy 292.034723 -287.803018) (xy 292.054014 -287.757742) (xy 292.080317 -287.716146)
			(xy 292.112952 -287.679309) (xy 292.151073 -287.648184) (xy 292.193694 -287.623577) (xy 292.23971 -287.606125)
			(xy 292.287929 -287.596281) (xy 292.337104 -287.5943) (xy 292.385959 -287.600232) (xy 292.43323 -287.613924)
			(xy 292.477692 -287.635022) (xy 292.518195 -287.662978) (xy 292.553688 -287.69707) (xy 292.583253 -287.736414)
			(xy 292.606124 -287.779991) (xy 292.621125 -287.824926) (xy 292.968946 -287.824926) (xy 292.972906 -287.775872)
			(xy 292.984683 -287.728088) (xy 293.003974 -287.682812) (xy 293.030277 -287.641216) (xy 293.062912 -287.604379)
			(xy 293.101033 -287.573254) (xy 293.143654 -287.548647) (xy 293.18967 -287.531195) (xy 293.237889 -287.521351)
			(xy 293.287064 -287.51937) (xy 293.335919 -287.525302) (xy 293.38319 -287.538994) (xy 293.427652 -287.560092)
			(xy 293.468155 -287.588048) (xy 293.503648 -287.62214) (xy 293.533213 -287.661484) (xy 293.556084 -287.705061)
			(xy 293.571668 -287.751742) (xy 293.579563 -287.800319) (xy 293.580058 -287.824926) (xy 293.918906 -287.824926)
			(xy 293.922866 -287.775872) (xy 293.934643 -287.728088) (xy 293.953934 -287.682812) (xy 293.980237 -287.641216)
			(xy 294.012872 -287.604379) (xy 294.050993 -287.573254) (xy 294.093614 -287.548647) (xy 294.13963 -287.531195)
			(xy 294.187849 -287.521351) (xy 294.237024 -287.51937) (xy 294.285879 -287.525302) (xy 294.33315 -287.538994)
			(xy 294.377612 -287.560092) (xy 294.418115 -287.588048) (xy 294.453608 -287.62214) (xy 294.483173 -287.661484)
			(xy 294.506044 -287.705061) (xy 294.521628 -287.751742) (xy 294.529523 -287.800319) (xy 294.530018 -287.824926)
			(xy 294.86912 -287.824926) (xy 294.87308 -287.775872) (xy 294.884857 -287.728088) (xy 294.904148 -287.682812)
			(xy 294.930451 -287.641216) (xy 294.963086 -287.604379) (xy 295.001207 -287.573254) (xy 295.043828 -287.548647)
			(xy 295.089844 -287.531195) (xy 295.138063 -287.521351) (xy 295.187238 -287.51937) (xy 295.236093 -287.525302)
			(xy 295.283364 -287.538994) (xy 295.327826 -287.560092) (xy 295.368329 -287.588048) (xy 295.403822 -287.62214)
			(xy 295.433387 -287.661484) (xy 295.456258 -287.705061) (xy 295.471842 -287.751742) (xy 295.479737 -287.800319)
			(xy 295.480232 -287.824926) (xy 295.81908 -287.824926) (xy 295.82304 -287.775872) (xy 295.834817 -287.728088)
			(xy 295.854108 -287.682812) (xy 295.880411 -287.641216) (xy 295.913046 -287.604379) (xy 295.951167 -287.573254)
			(xy 295.993788 -287.548647) (xy 296.039804 -287.531195) (xy 296.088023 -287.521351) (xy 296.137198 -287.51937)
			(xy 296.186053 -287.525302) (xy 296.233324 -287.538994) (xy 296.277786 -287.560092) (xy 296.318289 -287.588048)
			(xy 296.353782 -287.62214) (xy 296.383347 -287.661484) (xy 296.406218 -287.705061) (xy 296.421802 -287.751742)
			(xy 296.429697 -287.800319) (xy 296.430192 -287.824926) (xy 296.76904 -287.824926) (xy 296.773 -287.775872)
			(xy 296.784777 -287.728088) (xy 296.804068 -287.682812) (xy 296.830371 -287.641216) (xy 296.863006 -287.604379)
			(xy 296.901127 -287.573254) (xy 296.943748 -287.548647) (xy 296.989764 -287.531195) (xy 297.037983 -287.521351)
			(xy 297.087158 -287.51937) (xy 297.136013 -287.525302) (xy 297.183284 -287.538994) (xy 297.227746 -287.560092)
			(xy 297.268249 -287.588048) (xy 297.303742 -287.62214) (xy 297.333307 -287.661484) (xy 297.356178 -287.705061)
			(xy 297.371762 -287.751742) (xy 297.379657 -287.800319) (xy 297.380152 -287.824926) (xy 297.719 -287.824926)
			(xy 297.72296 -287.775872) (xy 297.734737 -287.728088) (xy 297.754028 -287.682812) (xy 297.780331 -287.641216)
			(xy 297.812966 -287.604379) (xy 297.851087 -287.573254) (xy 297.893708 -287.548647) (xy 297.939724 -287.531195)
			(xy 297.987943 -287.521351) (xy 298.037118 -287.51937) (xy 298.085973 -287.525302) (xy 298.133244 -287.538994)
			(xy 298.177706 -287.560092) (xy 298.218209 -287.588048) (xy 298.253702 -287.62214) (xy 298.283267 -287.661484)
			(xy 298.306138 -287.705061) (xy 298.321722 -287.751742) (xy 298.329617 -287.800319) (xy 298.330112 -287.824926)
			(xy 298.66896 -287.824926) (xy 298.67292 -287.775872) (xy 298.684697 -287.728088) (xy 298.703988 -287.682812)
			(xy 298.730291 -287.641216) (xy 298.762926 -287.604379) (xy 298.801047 -287.573254) (xy 298.843668 -287.548647)
			(xy 298.889684 -287.531195) (xy 298.937903 -287.521351) (xy 298.987078 -287.51937) (xy 299.035933 -287.525302)
			(xy 299.083204 -287.538994) (xy 299.127666 -287.560092) (xy 299.168169 -287.588048) (xy 299.203662 -287.62214)
			(xy 299.233227 -287.661484) (xy 299.256098 -287.705061) (xy 299.271682 -287.751742) (xy 299.279577 -287.800319)
			(xy 299.280072 -287.824926) (xy 299.61892 -287.824926) (xy 299.62288 -287.775872) (xy 299.634657 -287.728088)
			(xy 299.653948 -287.682812) (xy 299.680251 -287.641216) (xy 299.712886 -287.604379) (xy 299.751007 -287.573254)
			(xy 299.793628 -287.548647) (xy 299.839644 -287.531195) (xy 299.887863 -287.521351) (xy 299.937038 -287.51937)
			(xy 299.985893 -287.525302) (xy 300.033164 -287.538994) (xy 300.077626 -287.560092) (xy 300.118129 -287.588048)
			(xy 300.153622 -287.62214) (xy 300.183187 -287.661484) (xy 300.206058 -287.705061) (xy 300.221642 -287.751742)
			(xy 300.229537 -287.800319) (xy 300.230032 -287.824926) (xy 300.56888 -287.824926) (xy 300.57284 -287.775872)
			(xy 300.584617 -287.728088) (xy 300.603908 -287.682812) (xy 300.630211 -287.641216) (xy 300.662846 -287.604379)
			(xy 300.700967 -287.573254) (xy 300.743588 -287.548647) (xy 300.789604 -287.531195) (xy 300.837823 -287.521351)
			(xy 300.886998 -287.51937) (xy 300.935853 -287.525302) (xy 300.983124 -287.538994) (xy 301.027586 -287.560092)
			(xy 301.068089 -287.588048) (xy 301.103582 -287.62214) (xy 301.133147 -287.661484) (xy 301.156018 -287.705061)
			(xy 301.171602 -287.751742) (xy 301.179497 -287.800319) (xy 301.179992 -287.824926) (xy 302.469054 -287.824926)
			(xy 302.473014 -287.775872) (xy 302.484791 -287.728088) (xy 302.504082 -287.682812) (xy 302.530385 -287.641216)
			(xy 302.56302 -287.604379) (xy 302.601141 -287.573254) (xy 302.643762 -287.548647) (xy 302.689778 -287.531195)
			(xy 302.737997 -287.521351) (xy 302.787172 -287.51937) (xy 302.836027 -287.525302) (xy 302.883298 -287.538994)
			(xy 302.92776 -287.560092) (xy 302.968263 -287.588048) (xy 303.003756 -287.62214) (xy 303.033321 -287.661484)
			(xy 303.056192 -287.705061) (xy 303.071776 -287.751742) (xy 303.079671 -287.800319) (xy 303.080166 -287.824926)
			(xy 303.079671 -287.849533) (xy 303.071776 -287.89811) (xy 303.056192 -287.944791) (xy 303.033321 -287.988368)
			(xy 303.003756 -288.027712) (xy 302.968263 -288.061804) (xy 302.92776 -288.08976) (xy 302.883298 -288.110858)
			(xy 302.836027 -288.12455) (xy 302.787172 -288.130482) (xy 302.737997 -288.128501) (xy 302.689778 -288.118657)
			(xy 302.643762 -288.101205) (xy 302.601141 -288.076598) (xy 302.56302 -288.045473) (xy 302.530385 -288.008636)
			(xy 302.504082 -287.96704) (xy 302.484791 -287.921764) (xy 302.473014 -287.87398) (xy 302.469054 -287.824926)
			(xy 301.179992 -287.824926) (xy 301.179497 -287.849533) (xy 301.171602 -287.89811) (xy 301.156018 -287.944791)
			(xy 301.133147 -287.988368) (xy 301.103582 -288.027712) (xy 301.068089 -288.061804) (xy 301.027586 -288.08976)
			(xy 300.983124 -288.110858) (xy 300.935853 -288.12455) (xy 300.886998 -288.130482) (xy 300.837823 -288.128501)
			(xy 300.789604 -288.118657) (xy 300.743588 -288.101205) (xy 300.700967 -288.076598) (xy 300.662846 -288.045473)
			(xy 300.630211 -288.008636) (xy 300.603908 -287.96704) (xy 300.584617 -287.921764) (xy 300.57284 -287.87398)
			(xy 300.56888 -287.824926) (xy 300.230032 -287.824926) (xy 300.229537 -287.849533) (xy 300.221642 -287.89811)
			(xy 300.206058 -287.944791) (xy 300.183187 -287.988368) (xy 300.153622 -288.027712) (xy 300.118129 -288.061804)
			(xy 300.077626 -288.08976) (xy 300.033164 -288.110858) (xy 299.985893 -288.12455) (xy 299.937038 -288.130482)
			(xy 299.887863 -288.128501) (xy 299.839644 -288.118657) (xy 299.793628 -288.101205) (xy 299.751007 -288.076598)
			(xy 299.712886 -288.045473) (xy 299.680251 -288.008636) (xy 299.653948 -287.96704) (xy 299.634657 -287.921764)
			(xy 299.62288 -287.87398) (xy 299.61892 -287.824926) (xy 299.280072 -287.824926) (xy 299.279577 -287.849533)
			(xy 299.271682 -287.89811) (xy 299.256098 -287.944791) (xy 299.233227 -287.988368) (xy 299.203662 -288.027712)
			(xy 299.168169 -288.061804) (xy 299.127666 -288.08976) (xy 299.083204 -288.110858) (xy 299.035933 -288.12455)
			(xy 298.987078 -288.130482) (xy 298.937903 -288.128501) (xy 298.889684 -288.118657) (xy 298.843668 -288.101205)
			(xy 298.801047 -288.076598) (xy 298.762926 -288.045473) (xy 298.730291 -288.008636) (xy 298.703988 -287.96704)
			(xy 298.684697 -287.921764) (xy 298.67292 -287.87398) (xy 298.66896 -287.824926) (xy 298.330112 -287.824926)
			(xy 298.329617 -287.849533) (xy 298.321722 -287.89811) (xy 298.306138 -287.944791) (xy 298.283267 -287.988368)
			(xy 298.253702 -288.027712) (xy 298.218209 -288.061804) (xy 298.177706 -288.08976) (xy 298.133244 -288.110858)
			(xy 298.085973 -288.12455) (xy 298.037118 -288.130482) (xy 297.987943 -288.128501) (xy 297.939724 -288.118657)
			(xy 297.893708 -288.101205) (xy 297.851087 -288.076598) (xy 297.812966 -288.045473) (xy 297.780331 -288.008636)
			(xy 297.754028 -287.96704) (xy 297.734737 -287.921764) (xy 297.72296 -287.87398) (xy 297.719 -287.824926)
			(xy 297.380152 -287.824926) (xy 297.379657 -287.849533) (xy 297.371762 -287.89811) (xy 297.356178 -287.944791)
			(xy 297.333307 -287.988368) (xy 297.303742 -288.027712) (xy 297.268249 -288.061804) (xy 297.227746 -288.08976)
			(xy 297.183284 -288.110858) (xy 297.136013 -288.12455) (xy 297.087158 -288.130482) (xy 297.037983 -288.128501)
			(xy 296.989764 -288.118657) (xy 296.943748 -288.101205) (xy 296.901127 -288.076598) (xy 296.863006 -288.045473)
			(xy 296.830371 -288.008636) (xy 296.804068 -287.96704) (xy 296.784777 -287.921764) (xy 296.773 -287.87398)
			(xy 296.76904 -287.824926) (xy 296.430192 -287.824926) (xy 296.429697 -287.849533) (xy 296.421802 -287.89811)
			(xy 296.406218 -287.944791) (xy 296.383347 -287.988368) (xy 296.353782 -288.027712) (xy 296.318289 -288.061804)
			(xy 296.277786 -288.08976) (xy 296.233324 -288.110858) (xy 296.186053 -288.12455) (xy 296.137198 -288.130482)
			(xy 296.088023 -288.128501) (xy 296.039804 -288.118657) (xy 295.993788 -288.101205) (xy 295.951167 -288.076598)
			(xy 295.913046 -288.045473) (xy 295.880411 -288.008636) (xy 295.854108 -287.96704) (xy 295.834817 -287.921764)
			(xy 295.82304 -287.87398) (xy 295.81908 -287.824926) (xy 295.480232 -287.824926) (xy 295.479737 -287.849533)
			(xy 295.471842 -287.89811) (xy 295.456258 -287.944791) (xy 295.433387 -287.988368) (xy 295.403822 -288.027712)
			(xy 295.368329 -288.061804) (xy 295.327826 -288.08976) (xy 295.283364 -288.110858) (xy 295.236093 -288.12455)
			(xy 295.187238 -288.130482) (xy 295.138063 -288.128501) (xy 295.089844 -288.118657) (xy 295.043828 -288.101205)
			(xy 295.001207 -288.076598) (xy 294.963086 -288.045473) (xy 294.930451 -288.008636) (xy 294.904148 -287.96704)
			(xy 294.884857 -287.921764) (xy 294.87308 -287.87398) (xy 294.86912 -287.824926) (xy 294.530018 -287.824926)
			(xy 294.529523 -287.849533) (xy 294.521628 -287.89811) (xy 294.506044 -287.944791) (xy 294.483173 -287.988368)
			(xy 294.453608 -288.027712) (xy 294.418115 -288.061804) (xy 294.377612 -288.08976) (xy 294.33315 -288.110858)
			(xy 294.285879 -288.12455) (xy 294.237024 -288.130482) (xy 294.187849 -288.128501) (xy 294.13963 -288.118657)
			(xy 294.093614 -288.101205) (xy 294.050993 -288.076598) (xy 294.012872 -288.045473) (xy 293.980237 -288.008636)
			(xy 293.953934 -287.96704) (xy 293.934643 -287.921764) (xy 293.922866 -287.87398) (xy 293.918906 -287.824926)
			(xy 293.580058 -287.824926) (xy 293.579563 -287.849533) (xy 293.571668 -287.89811) (xy 293.556084 -287.944791)
			(xy 293.533213 -287.988368) (xy 293.503648 -288.027712) (xy 293.468155 -288.061804) (xy 293.427652 -288.08976)
			(xy 293.38319 -288.110858) (xy 293.335919 -288.12455) (xy 293.287064 -288.130482) (xy 293.237889 -288.128501)
			(xy 293.18967 -288.118657) (xy 293.143654 -288.101205) (xy 293.101033 -288.076598) (xy 293.062912 -288.045473)
			(xy 293.030277 -288.008636) (xy 293.003974 -287.96704) (xy 292.984683 -287.921764) (xy 292.972906 -287.87398)
			(xy 292.968946 -287.824926) (xy 292.621125 -287.824926) (xy 292.621708 -287.826672) (xy 292.629603 -287.875249)
			(xy 292.630098 -287.899856) (xy 292.629603 -287.924463) (xy 292.621708 -287.97304) (xy 292.606124 -288.019721)
			(xy 292.583253 -288.063298) (xy 292.553688 -288.102642) (xy 292.518195 -288.136734) (xy 292.477692 -288.16469)
			(xy 292.43323 -288.185788) (xy 292.385959 -288.19948) (xy 292.337104 -288.205412) (xy 292.287929 -288.203431)
			(xy 292.23971 -288.193587) (xy 292.193694 -288.176135) (xy 292.151073 -288.151528) (xy 292.112952 -288.120403)
			(xy 292.080317 -288.083566) (xy 292.054014 -288.04197) (xy 292.034723 -287.996694) (xy 292.022946 -287.94891)
			(xy 292.018986 -287.899856) (xy 290.68083 -287.899856) (xy 290.67866 -287.902744) (xy 290.643167 -287.936836)
			(xy 290.602664 -287.964792) (xy 290.558202 -287.98589) (xy 290.510931 -287.999582) (xy 290.462076 -288.005514)
			(xy 290.412901 -288.003533) (xy 290.364682 -287.993689) (xy 290.318666 -287.976237) (xy 290.276045 -287.95163)
			(xy 290.237924 -287.920505) (xy 290.205289 -287.883668) (xy 290.178986 -287.842072) (xy 290.159695 -287.796796)
			(xy 290.147918 -287.749012) (xy 290.143958 -287.699958) (xy 289.753566 -287.699958) (xy 289.756244 -287.705061)
			(xy 289.771828 -287.751742) (xy 289.779723 -287.800319) (xy 289.780218 -287.824926) (xy 289.779723 -287.849533)
			(xy 289.771828 -287.89811) (xy 289.756244 -287.944791) (xy 289.733373 -287.988368) (xy 289.703808 -288.027712)
			(xy 289.668315 -288.061804) (xy 289.627812 -288.08976) (xy 289.58335 -288.110858) (xy 289.536079 -288.12455)
			(xy 289.487224 -288.130482) (xy 289.438049 -288.128501) (xy 289.38983 -288.118657) (xy 289.343814 -288.101205)
			(xy 289.301193 -288.076598) (xy 289.263072 -288.045473) (xy 289.230437 -288.008636) (xy 289.204134 -287.96704)
			(xy 289.184843 -287.921764) (xy 289.173066 -287.87398) (xy 289.169106 -287.824926) (xy 288.830004 -287.824926)
			(xy 288.829509 -287.849533) (xy 288.821614 -287.89811) (xy 288.80603 -287.944791) (xy 288.783159 -287.988368)
			(xy 288.753594 -288.027712) (xy 288.718101 -288.061804) (xy 288.677598 -288.08976) (xy 288.633136 -288.110858)
			(xy 288.585865 -288.12455) (xy 288.53701 -288.130482) (xy 288.487835 -288.128501) (xy 288.439616 -288.118657)
			(xy 288.3936 -288.101205) (xy 288.350979 -288.076598) (xy 288.312858 -288.045473) (xy 288.280223 -288.008636)
			(xy 288.25392 -287.96704) (xy 288.234629 -287.921764) (xy 288.222852 -287.87398) (xy 288.218892 -287.824926)
			(xy 287.880044 -287.824926) (xy 287.879549 -287.849533) (xy 287.871654 -287.89811) (xy 287.85607 -287.944791)
			(xy 287.833199 -287.988368) (xy 287.803634 -288.027712) (xy 287.768141 -288.061804) (xy 287.727638 -288.08976)
			(xy 287.683176 -288.110858) (xy 287.635905 -288.12455) (xy 287.58705 -288.130482) (xy 287.537875 -288.128501)
			(xy 287.489656 -288.118657) (xy 287.44364 -288.101205) (xy 287.401019 -288.076598) (xy 287.362898 -288.045473)
			(xy 287.330263 -288.008636) (xy 287.30396 -287.96704) (xy 287.284669 -287.921764) (xy 287.272892 -287.87398)
			(xy 287.268932 -287.824926) (xy 286.930084 -287.824926) (xy 286.929589 -287.849533) (xy 286.921694 -287.89811)
			(xy 286.90611 -287.944791) (xy 286.883239 -287.988368) (xy 286.853674 -288.027712) (xy 286.818181 -288.061804)
			(xy 286.777678 -288.08976) (xy 286.733216 -288.110858) (xy 286.685945 -288.12455) (xy 286.63709 -288.130482)
			(xy 286.587915 -288.128501) (xy 286.539696 -288.118657) (xy 286.49368 -288.101205) (xy 286.451059 -288.076598)
			(xy 286.412938 -288.045473) (xy 286.380303 -288.008636) (xy 286.354 -287.96704) (xy 286.334709 -287.921764)
			(xy 286.322932 -287.87398) (xy 286.318972 -287.824926) (xy 285.980124 -287.824926) (xy 285.979629 -287.849533)
			(xy 285.971734 -287.89811) (xy 285.95615 -287.944791) (xy 285.933279 -287.988368) (xy 285.903714 -288.027712)
			(xy 285.868221 -288.061804) (xy 285.827718 -288.08976) (xy 285.783256 -288.110858) (xy 285.735985 -288.12455)
			(xy 285.68713 -288.130482) (xy 285.637955 -288.128501) (xy 285.589736 -288.118657) (xy 285.54372 -288.101205)
			(xy 285.501099 -288.076598) (xy 285.462978 -288.045473) (xy 285.430343 -288.008636) (xy 285.40404 -287.96704)
			(xy 285.384749 -287.921764) (xy 285.372972 -287.87398) (xy 285.369012 -287.824926) (xy 285.030164 -287.824926)
			(xy 285.029669 -287.849533) (xy 285.021774 -287.89811) (xy 285.00619 -287.944791) (xy 284.983319 -287.988368)
			(xy 284.953754 -288.027712) (xy 284.918261 -288.061804) (xy 284.877758 -288.08976) (xy 284.833296 -288.110858)
			(xy 284.786025 -288.12455) (xy 284.73717 -288.130482) (xy 284.687995 -288.128501) (xy 284.639776 -288.118657)
			(xy 284.59376 -288.101205) (xy 284.551139 -288.076598) (xy 284.513018 -288.045473) (xy 284.480383 -288.008636)
			(xy 284.45408 -287.96704) (xy 284.434789 -287.921764) (xy 284.423012 -287.87398) (xy 284.419052 -287.824926)
			(xy 284.080204 -287.824926) (xy 284.079709 -287.849533) (xy 284.071814 -287.89811) (xy 284.05623 -287.944791)
			(xy 284.033359 -287.988368) (xy 284.003794 -288.027712) (xy 283.968301 -288.061804) (xy 283.927798 -288.08976)
			(xy 283.883336 -288.110858) (xy 283.836065 -288.12455) (xy 283.78721 -288.130482) (xy 283.738035 -288.128501)
			(xy 283.689816 -288.118657) (xy 283.6438 -288.101205) (xy 283.601179 -288.076598) (xy 283.563058 -288.045473)
			(xy 283.530423 -288.008636) (xy 283.50412 -287.96704) (xy 283.484829 -287.921764) (xy 283.473052 -287.87398)
			(xy 283.469092 -287.824926) (xy 283.130244 -287.824926) (xy 283.129749 -287.849533) (xy 283.121854 -287.89811)
			(xy 283.10627 -287.944791) (xy 283.083399 -287.988368) (xy 283.053834 -288.027712) (xy 283.018341 -288.061804)
			(xy 282.977838 -288.08976) (xy 282.933376 -288.110858) (xy 282.886105 -288.12455) (xy 282.83725 -288.130482)
			(xy 282.788075 -288.128501) (xy 282.739856 -288.118657) (xy 282.69384 -288.101205) (xy 282.651219 -288.076598)
			(xy 282.613098 -288.045473) (xy 282.580463 -288.008636) (xy 282.55416 -287.96704) (xy 282.534869 -287.921764)
			(xy 282.523092 -287.87398) (xy 282.519132 -287.824926) (xy 282.180503 -287.824926) (xy 282.176335 -287.875232)
			(xy 282.163937 -287.92419) (xy 282.143651 -287.970441) (xy 282.116029 -288.012722) (xy 282.081825 -288.04988)
			(xy 282.041971 -288.080902) (xy 281.997555 -288.104942) (xy 281.949789 -288.121343) (xy 281.899974 -288.129659)
			(xy 281.874722 -288.130234) (xy 281.844648 -288.12954) (xy 281.785663 -288.117772) (xy 281.757628 -288.106866)
			(xy 281.745436 -288.101786) (xy 281.720544 -288.104326) (xy 281.639518 -288.158428) (xy 281.629467 -288.16595)
			(xy 281.617632 -288.188057) (xy 281.616912 -288.200592) (xy 281.616912 -288.308192) (xy 305.793963 -288.308192)
			(xy 305.79665 -288.25862) (xy 305.80732 -288.210135) (xy 305.825695 -288.164015) (xy 305.851289 -288.121475)
			(xy 305.883428 -288.083636) (xy 305.921265 -288.051496) (xy 305.963804 -288.0259) (xy 306.009923 -288.007524)
			(xy 306.058408 -287.996851) (xy 306.10798 -287.994163) (xy 306.157335 -287.99953) (xy 306.205171 -288.012812)
			(xy 306.250228 -288.033658) (xy 306.291319 -288.061518) (xy 306.327361 -288.095659) (xy 306.357405 -288.135182)
			(xy 306.380658 -288.179045) (xy 306.39651 -288.226092) (xy 306.404541 -288.275083) (xy 306.405026 -288.299906)
			(xy 306.40485 -288.314089) (xy 306.402177 -288.342329) (xy 306.399692 -288.356294) (xy 306.397406 -288.36874)
			(xy 306.404772 -288.392362) (xy 306.482242 -288.469832) (xy 306.505864 -288.477198) (xy 306.51831 -288.474912)
			(xy 306.532276 -288.472438) (xy 306.560516 -288.469765) (xy 306.574698 -288.469578) (xy 306.588945 -288.469746)
			(xy 306.617313 -288.472414) (xy 306.63134 -288.474912) (xy 306.643532 -288.477198) (xy 306.667662 -288.469832)
			(xy 306.744878 -288.392616) (xy 306.752244 -288.36874) (xy 306.749958 -288.356294) (xy 306.747485 -288.342328)
			(xy 306.744811 -288.314088) (xy 306.744624 -288.299906) (xy 306.745071 -288.275085) (xy 306.753101 -288.226097)
			(xy 306.768951 -288.179053) (xy 306.792202 -288.135194) (xy 306.822243 -288.095673) (xy 306.858282 -288.061533)
			(xy 306.899368 -288.033674) (xy 306.944421 -288.012828) (xy 306.992253 -287.999545) (xy 307.041604 -287.994176)
			(xy 307.091173 -287.996861) (xy 307.139654 -288.00753) (xy 307.185772 -288.025901) (xy 307.228309 -288.051492)
			(xy 307.266146 -288.083627) (xy 307.298286 -288.12146) (xy 307.323882 -288.163994) (xy 307.342259 -288.210109)
			(xy 307.352934 -288.25859) (xy 307.355177 -288.299906) (xy 307.694088 -288.299906) (xy 307.698048 -288.250852)
			(xy 307.709825 -288.203068) (xy 307.729116 -288.157792) (xy 307.755419 -288.116196) (xy 307.788054 -288.079359)
			(xy 307.826175 -288.048234) (xy 307.868796 -288.023627) (xy 307.914812 -288.006175) (xy 307.963031 -287.996331)
			(xy 308.012206 -287.99435) (xy 308.061061 -288.000282) (xy 308.108332 -288.013974) (xy 308.152794 -288.035072)
			(xy 308.193297 -288.063028) (xy 308.22879 -288.09712) (xy 308.258355 -288.136464) (xy 308.281226 -288.180041)
			(xy 308.29681 -288.226722) (xy 308.304705 -288.275299) (xy 308.3052 -288.299906) (xy 308.304705 -288.324513)
			(xy 308.304526 -288.325614) (xy 308.623204 -288.325614) (xy 308.623204 -288.274198) (xy 308.631247 -288.223416)
			(xy 308.647135 -288.174517) (xy 308.670478 -288.128705) (xy 308.700699 -288.087109) (xy 308.737055 -288.050753)
			(xy 308.778651 -288.020532) (xy 308.824463 -287.997189) (xy 308.873362 -287.981301) (xy 308.924144 -287.973258)
			(xy 308.97556 -287.973258) (xy 309.026342 -287.981301) (xy 309.075241 -287.997189) (xy 309.121053 -288.020532)
			(xy 309.162649 -288.050753) (xy 309.199005 -288.087109) (xy 309.229226 -288.128705) (xy 309.252569 -288.174517)
			(xy 309.268457 -288.223416) (xy 309.2765 -288.274198) (xy 309.277004 -288.299906) (xy 309.2765 -288.325614)
			(xy 309.573164 -288.325614) (xy 309.573164 -288.274198) (xy 309.581207 -288.223416) (xy 309.597095 -288.174517)
			(xy 309.620438 -288.128705) (xy 309.650659 -288.087109) (xy 309.687015 -288.050753) (xy 309.728611 -288.020532)
			(xy 309.774423 -287.997189) (xy 309.823322 -287.981301) (xy 309.874104 -287.973258) (xy 309.92552 -287.973258)
			(xy 309.976302 -287.981301) (xy 310.025201 -287.997189) (xy 310.071013 -288.020532) (xy 310.112609 -288.050753)
			(xy 310.148965 -288.087109) (xy 310.179186 -288.128705) (xy 310.202529 -288.174517) (xy 310.218417 -288.223416)
			(xy 310.22646 -288.274198) (xy 310.226964 -288.299906) (xy 310.543968 -288.299906) (xy 310.547928 -288.250852)
			(xy 310.559705 -288.203068) (xy 310.578996 -288.157792) (xy 310.605299 -288.116196) (xy 310.637934 -288.079359)
			(xy 310.676055 -288.048234) (xy 310.718676 -288.023627) (xy 310.764692 -288.006175) (xy 310.812911 -287.996331)
			(xy 310.862086 -287.99435) (xy 310.910941 -288.000282) (xy 310.958212 -288.013974) (xy 311.002674 -288.035072)
			(xy 311.043177 -288.063028) (xy 311.07867 -288.09712) (xy 311.108235 -288.136464) (xy 311.131106 -288.180041)
			(xy 311.14669 -288.226722) (xy 311.154585 -288.275299) (xy 311.15508 -288.299906) (xy 311.154585 -288.324513)
			(xy 311.154446 -288.325369) (xy 311.472991 -288.325369) (xy 311.472998 -288.273936) (xy 311.481053 -288.223139)
			(xy 311.496956 -288.174226) (xy 311.520315 -288.128405) (xy 311.550557 -288.086802) (xy 311.586935 -288.050444)
			(xy 311.628553 -288.020224) (xy 311.674387 -287.996889) (xy 311.723308 -287.981012) (xy 311.77411 -287.972985)
			(xy 311.825543 -287.973004) (xy 311.876339 -287.981071) (xy 311.925247 -287.996986) (xy 311.971063 -288.020357)
			(xy 312.012658 -288.050608) (xy 312.049008 -288.086995) (xy 312.079217 -288.128621) (xy 312.102541 -288.174461)
			(xy 312.118407 -288.223385) (xy 312.126422 -288.274189) (xy 312.126884 -288.299906) (xy 312.126671 -288.313629)
			(xy 312.124258 -288.340969) (xy 312.122058 -288.354516) (xy 312.12028 -288.366454) (xy 312.127138 -288.389314)
			(xy 312.200798 -288.465768) (xy 312.223404 -288.473642) (xy 312.235342 -288.472118) (xy 312.245141 -288.470931)
			(xy 312.264841 -288.469659) (xy 312.274712 -288.469578) (xy 312.284583 -288.469649) (xy 312.304284 -288.470922)
			(xy 312.314082 -288.472118) (xy 312.32602 -288.473642) (xy 312.348626 -288.465768) (xy 312.422286 -288.389314)
			(xy 312.429144 -288.366454) (xy 312.427366 -288.354516) (xy 312.425145 -288.340972) (xy 312.422731 -288.31363)
			(xy 312.42254 -288.299906) (xy 312.423044 -288.274198) (xy 312.431087 -288.223416) (xy 312.446975 -288.174517)
			(xy 312.470318 -288.128705) (xy 312.500539 -288.087109) (xy 312.536895 -288.050753) (xy 312.578491 -288.020532)
			(xy 312.624303 -287.997189) (xy 312.673202 -287.981301) (xy 312.723984 -287.973258) (xy 312.7754 -287.973258)
			(xy 312.826182 -287.981301) (xy 312.875081 -287.997189) (xy 312.920893 -288.020532) (xy 312.962489 -288.050753)
			(xy 312.998845 -288.087109) (xy 313.029066 -288.128705) (xy 313.052409 -288.174517) (xy 313.068297 -288.223416)
			(xy 313.07634 -288.274198) (xy 313.076844 -288.299906) (xy 313.076631 -288.313629) (xy 313.074218 -288.340969)
			(xy 313.072018 -288.354516) (xy 313.069986 -288.366454) (xy 313.077098 -288.389314) (xy 313.150758 -288.465768)
			(xy 313.173364 -288.473642) (xy 313.185556 -288.472118) (xy 313.195355 -288.470929) (xy 313.215055 -288.469658)
			(xy 313.224926 -288.469578) (xy 313.239109 -288.469751) (xy 313.267349 -288.472426) (xy 313.281314 -288.474912)
			(xy 313.29376 -288.477198) (xy 313.317382 -288.469832) (xy 313.394852 -288.392362) (xy 313.402218 -288.36874)
			(xy 313.399932 -288.356294) (xy 313.397459 -288.342328) (xy 313.394785 -288.314088) (xy 313.394598 -288.299906)
			(xy 313.39512 -288.274651) (xy 313.403433 -288.224829) (xy 313.419834 -288.177055) (xy 313.443875 -288.132632)
			(xy 313.474899 -288.092772) (xy 313.512061 -288.058562) (xy 313.554347 -288.030936) (xy 313.600603 -288.010646)
			(xy 313.649568 -287.998246) (xy 313.699906 -287.994075) (xy 313.750244 -287.998246) (xy 313.799209 -288.010646)
			(xy 313.845465 -288.030936) (xy 313.887751 -288.058562) (xy 313.924913 -288.092772) (xy 313.955937 -288.132632)
			(xy 313.979978 -288.177055) (xy 313.996379 -288.224829) (xy 314.004692 -288.274651) (xy 314.005214 -288.299906)
			(xy 314.005038 -288.314089) (xy 314.002365 -288.342329) (xy 313.99988 -288.356294) (xy 313.997594 -288.36874)
			(xy 314.00496 -288.392362) (xy 314.08243 -288.469832) (xy 314.106052 -288.477198) (xy 314.118498 -288.474912)
			(xy 314.132465 -288.47244) (xy 314.160704 -288.469765) (xy 314.174886 -288.469578) (xy 314.189069 -288.469757)
			(xy 314.217309 -288.472427) (xy 314.231274 -288.474912) (xy 314.24372 -288.477198) (xy 314.267342 -288.469832)
			(xy 314.344812 -288.392362) (xy 314.352178 -288.36874) (xy 314.349892 -288.356294) (xy 314.347419 -288.342328)
			(xy 314.344745 -288.314088) (xy 314.344558 -288.299906) (xy 314.34508 -288.274651) (xy 314.353393 -288.224829)
			(xy 314.369794 -288.177055) (xy 314.393835 -288.132632) (xy 314.424859 -288.092772) (xy 314.462021 -288.058562)
			(xy 314.504307 -288.030936) (xy 314.550563 -288.010646) (xy 314.599528 -287.998246) (xy 314.649866 -287.994075)
			(xy 314.700204 -287.998246) (xy 314.749169 -288.010646) (xy 314.795425 -288.030936) (xy 314.837711 -288.058562)
			(xy 314.874873 -288.092772) (xy 314.905897 -288.132632) (xy 314.929938 -288.177055) (xy 314.946339 -288.224829)
			(xy 314.950281 -288.248456) (xy 319.795821 -288.248456) (xy 319.795821 -288.193944) (xy 319.803579 -288.139988)
			(xy 319.818936 -288.087685) (xy 319.841581 -288.0381) (xy 319.871053 -287.992243) (xy 319.90675 -287.951046)
			(xy 319.947947 -287.915349) (xy 319.993805 -287.885879) (xy 320.043391 -287.863234) (xy 320.095694 -287.847877)
			(xy 320.14965 -287.840121) (xy 320.176906 -287.839658) (xy 320.203022 -287.840108) (xy 320.254766 -287.847246)
			(xy 320.305052 -287.861374) (xy 320.352941 -287.882229) (xy 320.397539 -287.90942) (xy 320.438012 -287.942439)
			(xy 320.473603 -287.98067) (xy 320.503648 -288.023397) (xy 320.515996 -288.046414) (xy 320.522763 -288.058628)
			(xy 320.541766 -288.079074) (xy 320.565592 -288.093616) (xy 320.592463 -288.101168) (xy 320.620377 -288.101168)
			(xy 320.647248 -288.093616) (xy 320.671074 -288.079074) (xy 320.690077 -288.058628) (xy 320.696844 -288.046414)
			(xy 320.709203 -288.0234) (xy 320.739231 -287.980657) (xy 320.774814 -287.942413) (xy 320.815283 -287.909383)
			(xy 320.859881 -287.882187) (xy 320.907775 -287.861332) (xy 320.958067 -287.84721) (xy 321.009815 -287.840085)
			(xy 321.035934 -287.839658) (xy 321.063181 -287.840215) (xy 321.11712 -287.847974) (xy 321.169406 -287.863331)
			(xy 321.218975 -287.885972) (xy 321.264817 -287.915437) (xy 321.305999 -287.951125) (xy 321.341684 -287.99231)
			(xy 321.371144 -288.038155) (xy 321.393781 -288.087726) (xy 321.409133 -288.140013) (xy 321.416888 -288.193953)
			(xy 321.416888 -288.248445) (xy 321.67082 -288.248445) (xy 321.670822 -288.193932) (xy 321.678582 -288.139975)
			(xy 321.693942 -288.087671) (xy 321.716589 -288.038085) (xy 321.746064 -287.992228) (xy 321.781764 -287.951032)
			(xy 321.822964 -287.915336) (xy 321.868825 -287.885868) (xy 321.918413 -287.863226) (xy 321.970719 -287.847872)
			(xy 322.024678 -287.840119) (xy 322.051934 -287.839658) (xy 322.076572 -287.84042) (xy 322.089272 -287.841182)
			(xy 322.11137 -287.83153) (xy 322.179442 -287.74771) (xy 322.184522 -287.723834) (xy 322.180966 -287.711642)
			(xy 322.17443 -287.686493) (xy 322.16742 -287.635007) (xy 322.166996 -287.609026) (xy 322.167482 -287.581775)
			(xy 322.175238 -287.527827) (xy 322.190593 -287.475532) (xy 322.213235 -287.425955) (xy 322.242701 -287.380105)
			(xy 322.278392 -287.338914) (xy 322.319583 -287.303223) (xy 322.365433 -287.273757) (xy 322.41501 -287.251115)
			(xy 322.467305 -287.23576) (xy 322.521253 -287.228004) (xy 322.575755 -287.228004) (xy 322.629703 -287.23576)
			(xy 322.681998 -287.251115) (xy 322.731575 -287.273757) (xy 322.777425 -287.303223) (xy 322.818616 -287.338914)
			(xy 322.854307 -287.380105) (xy 322.883773 -287.425955) (xy 322.906415 -287.475532) (xy 322.92177 -287.527827)
			(xy 322.929526 -287.581775) (xy 322.930012 -287.609026) (xy 322.929581 -287.63547) (xy 322.922318 -287.687857)
			(xy 322.915534 -287.71342) (xy 322.911978 -287.725866) (xy 322.917312 -287.75025) (xy 322.988432 -287.834324)
			(xy 323.0118 -287.843468) (xy 323.024754 -287.842198) (xy 323.035511 -287.841027) (xy 323.057114 -287.839756)
			(xy 323.067934 -287.839658) (xy 323.082158 -287.839912) (xy 323.093842 -287.84042) (xy 323.114924 -287.831276)
			(xy 323.18198 -287.75406) (xy 323.188076 -287.732216) (xy 323.186044 -287.720786) (xy 323.183307 -287.704285)
			(xy 323.180382 -287.670963) (xy 323.180202 -287.654238) (xy 323.180688 -287.626987) (xy 323.188444 -287.573039)
			(xy 323.203799 -287.520744) (xy 323.226441 -287.471167) (xy 323.255907 -287.425317) (xy 323.291598 -287.384126)
			(xy 323.332789 -287.348435) (xy 323.378639 -287.318969) (xy 323.428216 -287.296327) (xy 323.480511 -287.280972)
			(xy 323.534459 -287.273216) (xy 323.588961 -287.273216) (xy 323.642909 -287.280972) (xy 323.695204 -287.296327)
			(xy 323.744781 -287.318969) (xy 323.790631 -287.348435) (xy 323.831822 -287.384126) (xy 323.867513 -287.425317)
			(xy 323.896979 -287.471167) (xy 323.919621 -287.520744) (xy 323.934976 -287.573039) (xy 323.942732 -287.626987)
			(xy 323.943218 -287.654238) (xy 323.943035 -287.6709) (xy 323.940109 -287.704095) (xy 323.937376 -287.720532)
			(xy 323.935344 -287.732216) (xy 323.94144 -287.753806) (xy 324.008242 -287.831022) (xy 324.028816 -287.840166)
			(xy 324.0405 -287.839912) (xy 324.051676 -287.839658) (xy 324.078932 -287.840129) (xy 324.132888 -287.847884)
			(xy 324.185192 -287.863239) (xy 324.234778 -287.885881) (xy 324.280637 -287.91535) (xy 324.321835 -287.951045)
			(xy 324.357533 -287.99224) (xy 324.387005 -288.038097) (xy 324.409651 -288.087681) (xy 324.42501 -288.139984)
			(xy 324.432769 -288.19394) (xy 324.432769 -288.248451) (xy 324.425012 -288.302407) (xy 324.409655 -288.35471)
			(xy 324.38701 -288.404295) (xy 324.357539 -288.450152) (xy 324.321841 -288.491348) (xy 324.280644 -288.527045)
			(xy 324.234786 -288.556515) (xy 324.185201 -288.579158) (xy 324.132897 -288.594514) (xy 324.078941 -288.60227)
			(xy 324.02443 -288.602268) (xy 323.970474 -288.594508) (xy 323.918172 -288.579148) (xy 323.868588 -288.556501)
			(xy 323.822732 -288.527027) (xy 323.781538 -288.491328) (xy 323.745844 -288.450129) (xy 323.716376 -288.404269)
			(xy 323.693735 -288.354682) (xy 323.678382 -288.302378) (xy 323.670629 -288.248422) (xy 323.670168 -288.221166)
			(xy 323.670351 -288.204504) (xy 323.673277 -288.171309) (xy 323.67601 -288.154872) (xy 323.678042 -288.143188)
			(xy 323.671946 -288.121598) (xy 323.605144 -288.044382) (xy 323.58457 -288.035238) (xy 323.572886 -288.035492)
			(xy 323.56171 -288.035746) (xy 323.547486 -288.035492) (xy 323.535802 -288.034984) (xy 323.51472 -288.044128)
			(xy 323.447664 -288.121344) (xy 323.441568 -288.143188) (xy 323.4436 -288.154618) (xy 323.446338 -288.171119)
			(xy 323.449262 -288.204441) (xy 323.449442 -288.221166) (xy 323.448956 -288.248417) (xy 323.4412 -288.302365)
			(xy 323.425845 -288.35466) (xy 323.403203 -288.404237) (xy 323.373737 -288.450087) (xy 323.338046 -288.491278)
			(xy 323.296855 -288.526969) (xy 323.251005 -288.556435) (xy 323.201428 -288.579077) (xy 323.149133 -288.594432)
			(xy 323.095185 -288.602188) (xy 323.040683 -288.602188) (xy 322.986735 -288.594432) (xy 322.93444 -288.579077)
			(xy 322.884863 -288.556435) (xy 322.839013 -288.526969) (xy 322.797822 -288.491278) (xy 322.762131 -288.450087)
			(xy 322.732665 -288.404237) (xy 322.710023 -288.35466) (xy 322.694668 -288.302365) (xy 322.686912 -288.248417)
			(xy 322.686426 -288.221166) (xy 322.686854 -288.194722) (xy 322.694119 -288.142335) (xy 322.700904 -288.116772)
			(xy 322.70446 -288.104326) (xy 322.699126 -288.079942) (xy 322.628006 -287.995868) (xy 322.604638 -287.986724)
			(xy 322.591684 -287.987994) (xy 322.580927 -287.989162) (xy 322.559324 -287.990435) (xy 322.548504 -287.990534)
			(xy 322.523866 -287.989772) (xy 322.511166 -287.98901) (xy 322.489068 -287.998662) (xy 322.420996 -288.082482)
			(xy 322.415916 -288.106358) (xy 322.419472 -288.11855) (xy 322.426007 -288.143699) (xy 322.433018 -288.195185)
			(xy 322.433442 -288.221166) (xy 322.432981 -288.248422) (xy 322.425228 -288.302381) (xy 322.409874 -288.354687)
			(xy 322.387232 -288.404275) (xy 322.357764 -288.450136) (xy 322.322068 -288.491336) (xy 322.280872 -288.527036)
			(xy 322.235015 -288.556511) (xy 322.185429 -288.579158) (xy 322.133125 -288.594518) (xy 322.079168 -288.602278)
			(xy 322.024655 -288.60228) (xy 321.970697 -288.594523) (xy 321.918392 -288.579166) (xy 321.868805 -288.556521)
			(xy 321.822946 -288.52705) (xy 321.781748 -288.491352) (xy 321.74605 -288.450154) (xy 321.716579 -288.404295)
			(xy 321.693934 -288.354708) (xy 321.678577 -288.302403) (xy 321.67082 -288.248445) (xy 321.416888 -288.248445)
			(xy 321.416888 -288.248447) (xy 321.409133 -288.302387) (xy 321.393781 -288.354674) (xy 321.371144 -288.404245)
			(xy 321.341684 -288.45009) (xy 321.305999 -288.491275) (xy 321.264817 -288.526963) (xy 321.218975 -288.556428)
			(xy 321.169406 -288.579069) (xy 321.11712 -288.594426) (xy 321.063181 -288.602185) (xy 321.035934 -288.602674)
			(xy 321.009817 -288.602228) (xy 320.958072 -288.595094) (xy 320.907784 -288.580968) (xy 320.859893 -288.560114)
			(xy 320.815294 -288.532922) (xy 320.774822 -288.499901) (xy 320.739232 -288.461667) (xy 320.70919 -288.418937)
			(xy 320.696844 -288.395918) (xy 320.690077 -288.383704) (xy 320.671074 -288.363258) (xy 320.647248 -288.348716)
			(xy 320.620377 -288.341164) (xy 320.592463 -288.341164) (xy 320.565592 -288.348716) (xy 320.541766 -288.363258)
			(xy 320.522763 -288.383704) (xy 320.515996 -288.395918) (xy 320.503621 -288.418923) (xy 320.473593 -288.461664)
			(xy 320.438012 -288.499907) (xy 320.397545 -288.532936) (xy 320.352949 -288.560133) (xy 320.305059 -288.58099)
			(xy 320.25477 -288.595115) (xy 320.203024 -288.602245) (xy 320.176906 -288.602674) (xy 320.14965 -288.602279)
			(xy 320.095694 -288.594523) (xy 320.043391 -288.579166) (xy 319.993805 -288.556521) (xy 319.947947 -288.527051)
			(xy 319.90675 -288.491354) (xy 319.871053 -288.450157) (xy 319.841581 -288.4043) (xy 319.818936 -288.354715)
			(xy 319.803579 -288.302412) (xy 319.795821 -288.248456) (xy 314.950281 -288.248456) (xy 314.954652 -288.274651)
			(xy 314.955174 -288.299906) (xy 314.954999 -288.314089) (xy 314.952326 -288.342329) (xy 314.94984 -288.356294)
			(xy 314.947554 -288.36874) (xy 314.95492 -288.392362) (xy 315.03239 -288.469832) (xy 315.056012 -288.477198)
			(xy 315.068458 -288.474912) (xy 315.082423 -288.472432) (xy 315.110663 -288.469762) (xy 315.124846 -288.469578)
			(xy 315.147629 -288.469993) (xy 315.192686 -288.476777) (xy 315.236238 -288.490173) (xy 315.277319 -288.509884)
			(xy 315.31502 -288.535474) (xy 315.348506 -288.566376) (xy 315.363098 -288.583878) (xy 315.370664 -288.592477)
			(xy 315.391281 -288.602401) (xy 315.402722 -288.602928) (xy 315.48197 -288.602928) (xy 315.493383 -288.60227)
			(xy 315.51396 -288.592386) (xy 315.521594 -288.583878) (xy 315.53619 -288.566378) (xy 315.569664 -288.535461)
			(xy 315.607361 -288.509862) (xy 315.648444 -288.49015) (xy 315.692 -288.476762) (xy 315.737062 -288.469997)
			(xy 315.759846 -288.469578) (xy 315.785098 -288.470131) (xy 315.834911 -288.47845) (xy 315.882676 -288.494855)
			(xy 315.92709 -288.518896) (xy 315.966942 -288.54992) (xy 316.001145 -288.587079) (xy 316.028765 -288.62936)
			(xy 316.04905 -288.675611) (xy 316.061447 -288.724569) (xy 316.065617 -288.7749) (xy 316.061447 -288.825231)
			(xy 316.04905 -288.874189) (xy 316.028765 -288.92044) (xy 316.001145 -288.962721) (xy 315.966942 -288.99988)
			(xy 315.92709 -289.030904) (xy 315.882676 -289.054945) (xy 315.834911 -289.07135) (xy 315.785098 -289.079669)
			(xy 315.759846 -289.080194) (xy 315.737063 -289.079795) (xy 315.692004 -289.073009) (xy 315.648451 -289.059611)
			(xy 315.60737 -289.039896) (xy 315.569669 -289.014303) (xy 315.536185 -288.983397) (xy 315.521594 -288.965894)
			(xy 315.514036 -288.957287) (xy 315.493412 -288.947369) (xy 315.48197 -288.946844) (xy 315.402722 -288.946844)
			(xy 315.39131 -288.947507) (xy 315.370733 -288.957388) (xy 315.363098 -288.965894) (xy 315.348524 -288.983413)
			(xy 315.315044 -289.014326) (xy 315.277341 -289.03992) (xy 315.236254 -289.059629) (xy 315.192695 -289.073013)
			(xy 315.147631 -289.079776) (xy 315.124846 -289.080194) (xy 315.100853 -289.079719) (xy 315.053458 -289.072219)
			(xy 315.00782 -289.057396) (xy 314.965063 -289.035615) (xy 314.92624 -289.007413) (xy 314.892308 -288.973484)
			(xy 314.864102 -288.934664) (xy 314.842316 -288.89191) (xy 314.827488 -288.846273) (xy 314.819983 -288.798879)
			(xy 314.819538 -288.774886) (xy 314.819712 -288.760703) (xy 314.822386 -288.732463) (xy 314.824872 -288.718498)
			(xy 314.827158 -288.706052) (xy 314.819792 -288.68243) (xy 314.742322 -288.60496) (xy 314.7187 -288.597594)
			(xy 314.706254 -288.59988) (xy 314.692288 -288.602359) (xy 314.664049 -288.605029) (xy 314.649866 -288.605214)
			(xy 314.635683 -288.605042) (xy 314.607443 -288.602367) (xy 314.593478 -288.59988) (xy 314.581032 -288.597594)
			(xy 314.55741 -288.60496) (xy 314.47994 -288.68243) (xy 314.472574 -288.706052) (xy 314.47486 -288.718498)
			(xy 314.477332 -288.732465) (xy 314.480007 -288.760704) (xy 314.480194 -288.774886) (xy 314.479672 -288.800141)
			(xy 314.471359 -288.849963) (xy 314.454958 -288.897737) (xy 314.430917 -288.94216) (xy 314.399893 -288.98202)
			(xy 314.362731 -289.01623) (xy 314.320445 -289.043856) (xy 314.274189 -289.064146) (xy 314.225224 -289.076546)
			(xy 314.174886 -289.080717) (xy 314.124548 -289.076546) (xy 314.075583 -289.064146) (xy 314.029327 -289.043856)
			(xy 313.987041 -289.01623) (xy 313.949879 -288.98202) (xy 313.918855 -288.94216) (xy 313.894814 -288.897737)
			(xy 313.878413 -288.849963) (xy 313.8701 -288.800141) (xy 313.869578 -288.774886) (xy 313.869753 -288.760703)
			(xy 313.872426 -288.732463) (xy 313.874912 -288.718498) (xy 313.877198 -288.706052) (xy 313.869832 -288.68243)
			(xy 313.792362 -288.60496) (xy 313.76874 -288.597594) (xy 313.756294 -288.59988) (xy 313.742328 -288.602353)
			(xy 313.714088 -288.605027) (xy 313.699906 -288.605214) (xy 313.685723 -288.605036) (xy 313.657483 -288.602365)
			(xy 313.643518 -288.59988) (xy 313.631072 -288.597594) (xy 313.60745 -288.60496) (xy 313.52998 -288.68243)
			(xy 313.522614 -288.706052) (xy 313.5249 -288.718498) (xy 313.527372 -288.732465) (xy 313.530047 -288.760704)
			(xy 313.530234 -288.774886) (xy 313.529712 -288.800141) (xy 313.521399 -288.849963) (xy 313.504998 -288.897737)
			(xy 313.480957 -288.94216) (xy 313.449933 -288.98202) (xy 313.412771 -289.01623) (xy 313.370485 -289.043856)
			(xy 313.324229 -289.064146) (xy 313.275264 -289.076546) (xy 313.224926 -289.080717) (xy 313.174588 -289.076546)
			(xy 313.125623 -289.064146) (xy 313.079367 -289.043856) (xy 313.037081 -289.01623) (xy 312.999919 -288.98202)
			(xy 312.968895 -288.94216) (xy 312.944854 -288.897737) (xy 312.928453 -288.849963) (xy 312.92014 -288.800141)
			(xy 312.919618 -288.774886) (xy 312.919689 -288.765015) (xy 312.920961 -288.745314) (xy 312.922158 -288.735516)
			(xy 312.923682 -288.723578) (xy 312.915808 -288.700718) (xy 312.839354 -288.627312) (xy 312.816494 -288.6202)
			(xy 312.804302 -288.622232) (xy 312.790753 -288.62439) (xy 312.763411 -288.626677) (xy 312.749692 -288.626804)
			(xy 312.735974 -288.626658) (xy 312.708633 -288.62437) (xy 312.695082 -288.622232) (xy 312.683144 -288.620454)
			(xy 312.660284 -288.627312) (xy 312.58383 -288.700972) (xy 312.575956 -288.723578) (xy 312.57748 -288.735516)
			(xy 312.578665 -288.745316) (xy 312.579938 -288.765015) (xy 312.58002 -288.774886) (xy 312.579498 -288.800141)
			(xy 312.571185 -288.849963) (xy 312.554784 -288.897737) (xy 312.530743 -288.94216) (xy 312.499719 -288.98202)
			(xy 312.462557 -289.01623) (xy 312.420271 -289.043856) (xy 312.374015 -289.064146) (xy 312.32505 -289.076546)
			(xy 312.274712 -289.080717) (xy 312.224374 -289.076546) (xy 312.175409 -289.064146) (xy 312.129153 -289.043856)
			(xy 312.086867 -289.01623) (xy 312.049705 -288.98202) (xy 312.018681 -288.94216) (xy 311.99464 -288.897737)
			(xy 311.978239 -288.849963) (xy 311.969926 -288.800141) (xy 311.969404 -288.774886) (xy 311.969475 -288.765015)
			(xy 311.970747 -288.745314) (xy 311.971944 -288.735516) (xy 311.973468 -288.723578) (xy 311.965594 -288.700972)
			(xy 311.88914 -288.627312) (xy 311.86628 -288.620454) (xy 311.854342 -288.622232) (xy 311.840793 -288.624385)
			(xy 311.813451 -288.626675) (xy 311.799732 -288.626804) (xy 311.774016 -288.626408) (xy 311.723216 -288.618366)
			(xy 311.6743 -288.602475) (xy 311.628472 -288.579126) (xy 311.586863 -288.548895) (xy 311.550495 -288.512526)
			(xy 311.520266 -288.470914) (xy 311.496919 -288.425086) (xy 311.48103 -288.376169) (xy 311.472991 -288.325369)
			(xy 311.154446 -288.325369) (xy 311.14669 -288.37309) (xy 311.131106 -288.419771) (xy 311.108235 -288.463348)
			(xy 311.07867 -288.502692) (xy 311.043177 -288.536784) (xy 311.002674 -288.56474) (xy 310.958212 -288.585838)
			(xy 310.910941 -288.59953) (xy 310.862086 -288.605462) (xy 310.812911 -288.603481) (xy 310.764692 -288.593637)
			(xy 310.718676 -288.576185) (xy 310.676055 -288.551578) (xy 310.637934 -288.520453) (xy 310.605299 -288.483616)
			(xy 310.578996 -288.44202) (xy 310.559705 -288.396744) (xy 310.547928 -288.34896) (xy 310.543968 -288.299906)
			(xy 310.226964 -288.299906) (xy 310.22646 -288.325614) (xy 310.218417 -288.376396) (xy 310.202529 -288.425295)
			(xy 310.179186 -288.471107) (xy 310.148965 -288.512703) (xy 310.112609 -288.549059) (xy 310.071013 -288.57928)
			(xy 310.025201 -288.602623) (xy 309.976302 -288.618511) (xy 309.92552 -288.626554) (xy 309.874104 -288.626554)
			(xy 309.823322 -288.618511) (xy 309.774423 -288.602623) (xy 309.728611 -288.57928) (xy 309.687015 -288.549059)
			(xy 309.650659 -288.512703) (xy 309.620438 -288.471107) (xy 309.597095 -288.425295) (xy 309.581207 -288.376396)
			(xy 309.573164 -288.325614) (xy 309.2765 -288.325614) (xy 309.268457 -288.376396) (xy 309.252569 -288.425295)
			(xy 309.229226 -288.471107) (xy 309.199005 -288.512703) (xy 309.162649 -288.549059) (xy 309.121053 -288.57928)
			(xy 309.075241 -288.602623) (xy 309.026342 -288.618511) (xy 308.97556 -288.626554) (xy 308.924144 -288.626554)
			(xy 308.873362 -288.618511) (xy 308.824463 -288.602623) (xy 308.778651 -288.57928) (xy 308.737055 -288.549059)
			(xy 308.700699 -288.512703) (xy 308.670478 -288.471107) (xy 308.647135 -288.425295) (xy 308.631247 -288.376396)
			(xy 308.623204 -288.325614) (xy 308.304526 -288.325614) (xy 308.29681 -288.37309) (xy 308.281226 -288.419771)
			(xy 308.258355 -288.463348) (xy 308.22879 -288.502692) (xy 308.193297 -288.536784) (xy 308.152794 -288.56474)
			(xy 308.108332 -288.585838) (xy 308.061061 -288.59953) (xy 308.012206 -288.605462) (xy 307.963031 -288.603481)
			(xy 307.914812 -288.593637) (xy 307.868796 -288.576185) (xy 307.826175 -288.551578) (xy 307.788054 -288.520453)
			(xy 307.755419 -288.483616) (xy 307.729116 -288.44202) (xy 307.709825 -288.396744) (xy 307.698048 -288.34896)
			(xy 307.694088 -288.299906) (xy 307.355177 -288.299906) (xy 307.355625 -288.308158) (xy 307.350262 -288.35751)
			(xy 307.336985 -288.405343) (xy 307.316145 -288.450398) (xy 307.28829 -288.491489) (xy 307.254155 -288.527532)
			(xy 307.214638 -288.557577) (xy 307.170781 -288.580834) (xy 307.12374 -288.596689) (xy 307.074753 -288.604726)
			(xy 307.049932 -288.605214) (xy 307.035685 -288.605049) (xy 307.007318 -288.602375) (xy 306.99329 -288.59988)
			(xy 306.981098 -288.597594) (xy 306.956968 -288.60496) (xy 306.879752 -288.682176) (xy 306.872386 -288.706052)
			(xy 306.874672 -288.718498) (xy 306.877144 -288.732465) (xy 306.879819 -288.760704) (xy 306.880006 -288.774886)
			(xy 306.879484 -288.800141) (xy 306.871171 -288.849963) (xy 306.85477 -288.897737) (xy 306.830729 -288.94216)
			(xy 306.799705 -288.98202) (xy 306.762543 -289.01623) (xy 306.720257 -289.043856) (xy 306.674001 -289.064146)
			(xy 306.625036 -289.076546) (xy 306.574698 -289.080717) (xy 306.52436 -289.076546) (xy 306.475395 -289.064146)
			(xy 306.429139 -289.043856) (xy 306.386853 -289.01623) (xy 306.349691 -288.98202) (xy 306.318667 -288.94216)
			(xy 306.294626 -288.897737) (xy 306.278225 -288.849963) (xy 306.269912 -288.800141) (xy 306.26939 -288.774886)
			(xy 306.269565 -288.760703) (xy 306.272238 -288.732463) (xy 306.274724 -288.718498) (xy 306.27701 -288.706052)
			(xy 306.269644 -288.68243) (xy 306.192174 -288.60496) (xy 306.168552 -288.597594) (xy 306.156106 -288.59988)
			(xy 306.142139 -288.602352) (xy 306.1139 -288.605027) (xy 306.099718 -288.605214) (xy 306.074895 -288.604741)
			(xy 306.025903 -288.596713) (xy 305.978856 -288.580863) (xy 305.934992 -288.557611) (xy 305.895468 -288.527569)
			(xy 305.861326 -288.491528) (xy 305.833463 -288.450438) (xy 305.812616 -288.405382) (xy 305.799333 -288.357547)
			(xy 305.793963 -288.308192) (xy 281.616912 -288.308192) (xy 281.616912 -288.39922) (xy 281.617559 -288.411774)
			(xy 281.629419 -288.4339) (xy 281.639518 -288.441384) (xy 281.720544 -288.495486) (xy 281.745436 -288.498026)
			(xy 281.757628 -288.492946) (xy 281.785665 -288.482046) (xy 281.844649 -288.470278) (xy 281.874722 -288.469578)
			(xy 281.899977 -288.470101) (xy 281.949798 -288.478418) (xy 281.997571 -288.494822) (xy 282.041993 -288.518864)
			(xy 282.081852 -288.54989) (xy 282.11606 -288.587053) (xy 282.143686 -288.62934) (xy 282.163975 -288.675597)
			(xy 282.176374 -288.724562) (xy 282.180544 -288.774886) (xy 282.519132 -288.774886) (xy 282.523092 -288.725832)
			(xy 282.534869 -288.678048) (xy 282.55416 -288.632772) (xy 282.580463 -288.591176) (xy 282.613098 -288.554339)
			(xy 282.651219 -288.523214) (xy 282.69384 -288.498607) (xy 282.739856 -288.481155) (xy 282.788075 -288.471311)
			(xy 282.83725 -288.46933) (xy 282.886105 -288.475262) (xy 282.933376 -288.488954) (xy 282.977838 -288.510052)
			(xy 283.018341 -288.538008) (xy 283.053834 -288.5721) (xy 283.083399 -288.611444) (xy 283.10627 -288.655021)
			(xy 283.121854 -288.701702) (xy 283.129749 -288.750279) (xy 283.130244 -288.774886) (xy 283.469092 -288.774886)
			(xy 283.473052 -288.725832) (xy 283.484829 -288.678048) (xy 283.50412 -288.632772) (xy 283.530423 -288.591176)
			(xy 283.563058 -288.554339) (xy 283.601179 -288.523214) (xy 283.6438 -288.498607) (xy 283.689816 -288.481155)
			(xy 283.738035 -288.471311) (xy 283.78721 -288.46933) (xy 283.836065 -288.475262) (xy 283.883336 -288.488954)
			(xy 283.927798 -288.510052) (xy 283.968301 -288.538008) (xy 284.003794 -288.5721) (xy 284.033359 -288.611444)
			(xy 284.05623 -288.655021) (xy 284.071814 -288.701702) (xy 284.079709 -288.750279) (xy 284.080204 -288.774886)
			(xy 284.419052 -288.774886) (xy 284.423012 -288.725832) (xy 284.434789 -288.678048) (xy 284.45408 -288.632772)
			(xy 284.480383 -288.591176) (xy 284.513018 -288.554339) (xy 284.551139 -288.523214) (xy 284.59376 -288.498607)
			(xy 284.639776 -288.481155) (xy 284.687995 -288.471311) (xy 284.73717 -288.46933) (xy 284.786025 -288.475262)
			(xy 284.833296 -288.488954) (xy 284.877758 -288.510052) (xy 284.918261 -288.538008) (xy 284.953754 -288.5721)
			(xy 284.983319 -288.611444) (xy 285.00619 -288.655021) (xy 285.021774 -288.701702) (xy 285.029669 -288.750279)
			(xy 285.030164 -288.774886) (xy 285.369012 -288.774886) (xy 285.372972 -288.725832) (xy 285.384749 -288.678048)
			(xy 285.40404 -288.632772) (xy 285.430343 -288.591176) (xy 285.462978 -288.554339) (xy 285.501099 -288.523214)
			(xy 285.54372 -288.498607) (xy 285.589736 -288.481155) (xy 285.637955 -288.471311) (xy 285.68713 -288.46933)
			(xy 285.735985 -288.475262) (xy 285.783256 -288.488954) (xy 285.827718 -288.510052) (xy 285.868221 -288.538008)
			(xy 285.903714 -288.5721) (xy 285.933279 -288.611444) (xy 285.95615 -288.655021) (xy 285.971734 -288.701702)
			(xy 285.979629 -288.750279) (xy 285.980124 -288.774886) (xy 286.318972 -288.774886) (xy 286.322932 -288.725832)
			(xy 286.334709 -288.678048) (xy 286.354 -288.632772) (xy 286.380303 -288.591176) (xy 286.412938 -288.554339)
			(xy 286.451059 -288.523214) (xy 286.49368 -288.498607) (xy 286.539696 -288.481155) (xy 286.587915 -288.471311)
			(xy 286.63709 -288.46933) (xy 286.685945 -288.475262) (xy 286.733216 -288.488954) (xy 286.777678 -288.510052)
			(xy 286.818181 -288.538008) (xy 286.853674 -288.5721) (xy 286.883239 -288.611444) (xy 286.90611 -288.655021)
			(xy 286.921694 -288.701702) (xy 286.929589 -288.750279) (xy 286.930084 -288.774886) (xy 287.268932 -288.774886)
			(xy 287.272892 -288.725832) (xy 287.284669 -288.678048) (xy 287.30396 -288.632772) (xy 287.330263 -288.591176)
			(xy 287.362898 -288.554339) (xy 287.401019 -288.523214) (xy 287.44364 -288.498607) (xy 287.489656 -288.481155)
			(xy 287.537875 -288.471311) (xy 287.58705 -288.46933) (xy 287.635905 -288.475262) (xy 287.683176 -288.488954)
			(xy 287.727638 -288.510052) (xy 287.768141 -288.538008) (xy 287.803634 -288.5721) (xy 287.833199 -288.611444)
			(xy 287.85607 -288.655021) (xy 287.871654 -288.701702) (xy 287.879549 -288.750279) (xy 287.880044 -288.774886)
			(xy 288.218892 -288.774886) (xy 288.222852 -288.725832) (xy 288.234629 -288.678048) (xy 288.25392 -288.632772)
			(xy 288.280223 -288.591176) (xy 288.312858 -288.554339) (xy 288.350979 -288.523214) (xy 288.3936 -288.498607)
			(xy 288.439616 -288.481155) (xy 288.487835 -288.471311) (xy 288.53701 -288.46933) (xy 288.585865 -288.475262)
			(xy 288.633136 -288.488954) (xy 288.677598 -288.510052) (xy 288.718101 -288.538008) (xy 288.753594 -288.5721)
			(xy 288.783159 -288.611444) (xy 288.80603 -288.655021) (xy 288.821614 -288.701702) (xy 288.829509 -288.750279)
			(xy 288.830004 -288.774886) (xy 289.169106 -288.774886) (xy 289.173066 -288.725832) (xy 289.184843 -288.678048)
			(xy 289.204134 -288.632772) (xy 289.230437 -288.591176) (xy 289.263072 -288.554339) (xy 289.301193 -288.523214)
			(xy 289.343814 -288.498607) (xy 289.38983 -288.481155) (xy 289.438049 -288.471311) (xy 289.487224 -288.46933)
			(xy 289.536079 -288.475262) (xy 289.58335 -288.488954) (xy 289.627812 -288.510052) (xy 289.668315 -288.538008)
			(xy 289.703808 -288.5721) (xy 289.733373 -288.611444) (xy 289.756244 -288.655021) (xy 289.771828 -288.701702)
			(xy 289.779723 -288.750279) (xy 289.780218 -288.774886) (xy 290.119066 -288.774886) (xy 290.123026 -288.725832)
			(xy 290.134803 -288.678048) (xy 290.154094 -288.632772) (xy 290.180397 -288.591176) (xy 290.213032 -288.554339)
			(xy 290.251153 -288.523214) (xy 290.293774 -288.498607) (xy 290.33979 -288.481155) (xy 290.388009 -288.471311)
			(xy 290.437184 -288.46933) (xy 290.486039 -288.475262) (xy 290.53331 -288.488954) (xy 290.577772 -288.510052)
			(xy 290.618275 -288.538008) (xy 290.653768 -288.5721) (xy 290.683333 -288.611444) (xy 290.706204 -288.655021)
			(xy 290.721788 -288.701702) (xy 290.729683 -288.750279) (xy 290.730178 -288.774886) (xy 292.018986 -288.774886)
			(xy 292.022946 -288.725832) (xy 292.034723 -288.678048) (xy 292.054014 -288.632772) (xy 292.080317 -288.591176)
			(xy 292.112952 -288.554339) (xy 292.151073 -288.523214) (xy 292.193694 -288.498607) (xy 292.23971 -288.481155)
			(xy 292.287929 -288.471311) (xy 292.337104 -288.46933) (xy 292.385959 -288.475262) (xy 292.43323 -288.488954)
			(xy 292.477692 -288.510052) (xy 292.518195 -288.538008) (xy 292.553688 -288.5721) (xy 292.583253 -288.611444)
			(xy 292.606124 -288.655021) (xy 292.621708 -288.701702) (xy 292.629603 -288.750279) (xy 292.630098 -288.774886)
			(xy 292.968946 -288.774886) (xy 292.972906 -288.725832) (xy 292.984683 -288.678048) (xy 293.003974 -288.632772)
			(xy 293.030277 -288.591176) (xy 293.062912 -288.554339) (xy 293.101033 -288.523214) (xy 293.143654 -288.498607)
			(xy 293.18967 -288.481155) (xy 293.237889 -288.471311) (xy 293.287064 -288.46933) (xy 293.335919 -288.475262)
			(xy 293.38319 -288.488954) (xy 293.427652 -288.510052) (xy 293.468155 -288.538008) (xy 293.503648 -288.5721)
			(xy 293.533213 -288.611444) (xy 293.556084 -288.655021) (xy 293.571668 -288.701702) (xy 293.579563 -288.750279)
			(xy 293.580058 -288.774886) (xy 293.918906 -288.774886) (xy 293.922866 -288.725832) (xy 293.934643 -288.678048)
			(xy 293.953934 -288.632772) (xy 293.980237 -288.591176) (xy 294.012872 -288.554339) (xy 294.050993 -288.523214)
			(xy 294.093614 -288.498607) (xy 294.13963 -288.481155) (xy 294.187849 -288.471311) (xy 294.237024 -288.46933)
			(xy 294.285879 -288.475262) (xy 294.33315 -288.488954) (xy 294.377612 -288.510052) (xy 294.418115 -288.538008)
			(xy 294.453608 -288.5721) (xy 294.483173 -288.611444) (xy 294.506044 -288.655021) (xy 294.521628 -288.701702)
			(xy 294.529523 -288.750279) (xy 294.530018 -288.774886) (xy 294.86912 -288.774886) (xy 294.87308 -288.725832)
			(xy 294.884857 -288.678048) (xy 294.904148 -288.632772) (xy 294.930451 -288.591176) (xy 294.963086 -288.554339)
			(xy 295.001207 -288.523214) (xy 295.043828 -288.498607) (xy 295.089844 -288.481155) (xy 295.138063 -288.471311)
			(xy 295.187238 -288.46933) (xy 295.236093 -288.475262) (xy 295.283364 -288.488954) (xy 295.327826 -288.510052)
			(xy 295.368329 -288.538008) (xy 295.403822 -288.5721) (xy 295.433387 -288.611444) (xy 295.456258 -288.655021)
			(xy 295.471842 -288.701702) (xy 295.479737 -288.750279) (xy 295.480232 -288.774886) (xy 295.81908 -288.774886)
			(xy 295.82304 -288.725832) (xy 295.834817 -288.678048) (xy 295.854108 -288.632772) (xy 295.880411 -288.591176)
			(xy 295.913046 -288.554339) (xy 295.951167 -288.523214) (xy 295.993788 -288.498607) (xy 296.039804 -288.481155)
			(xy 296.088023 -288.471311) (xy 296.137198 -288.46933) (xy 296.186053 -288.475262) (xy 296.233324 -288.488954)
			(xy 296.277786 -288.510052) (xy 296.318289 -288.538008) (xy 296.353782 -288.5721) (xy 296.383347 -288.611444)
			(xy 296.406218 -288.655021) (xy 296.421802 -288.701702) (xy 296.429697 -288.750279) (xy 296.430192 -288.774886)
			(xy 296.76904 -288.774886) (xy 296.773 -288.725832) (xy 296.784777 -288.678048) (xy 296.804068 -288.632772)
			(xy 296.830371 -288.591176) (xy 296.863006 -288.554339) (xy 296.901127 -288.523214) (xy 296.943748 -288.498607)
			(xy 296.989764 -288.481155) (xy 297.037983 -288.471311) (xy 297.087158 -288.46933) (xy 297.136013 -288.475262)
			(xy 297.183284 -288.488954) (xy 297.227746 -288.510052) (xy 297.268249 -288.538008) (xy 297.303742 -288.5721)
			(xy 297.333307 -288.611444) (xy 297.356178 -288.655021) (xy 297.371762 -288.701702) (xy 297.379657 -288.750279)
			(xy 297.380152 -288.774886) (xy 297.719 -288.774886) (xy 297.72296 -288.725832) (xy 297.734737 -288.678048)
			(xy 297.754028 -288.632772) (xy 297.780331 -288.591176) (xy 297.812966 -288.554339) (xy 297.851087 -288.523214)
			(xy 297.893708 -288.498607) (xy 297.939724 -288.481155) (xy 297.987943 -288.471311) (xy 298.037118 -288.46933)
			(xy 298.085973 -288.475262) (xy 298.133244 -288.488954) (xy 298.177706 -288.510052) (xy 298.218209 -288.538008)
			(xy 298.253702 -288.5721) (xy 298.283267 -288.611444) (xy 298.306138 -288.655021) (xy 298.321722 -288.701702)
			(xy 298.329617 -288.750279) (xy 298.330112 -288.774886) (xy 298.66896 -288.774886) (xy 298.67292 -288.725832)
			(xy 298.684697 -288.678048) (xy 298.703988 -288.632772) (xy 298.730291 -288.591176) (xy 298.762926 -288.554339)
			(xy 298.801047 -288.523214) (xy 298.843668 -288.498607) (xy 298.889684 -288.481155) (xy 298.937903 -288.471311)
			(xy 298.987078 -288.46933) (xy 299.035933 -288.475262) (xy 299.083204 -288.488954) (xy 299.127666 -288.510052)
			(xy 299.168169 -288.538008) (xy 299.203662 -288.5721) (xy 299.233227 -288.611444) (xy 299.256098 -288.655021)
			(xy 299.271682 -288.701702) (xy 299.279577 -288.750279) (xy 299.280072 -288.774886) (xy 299.61892 -288.774886)
			(xy 299.62288 -288.725832) (xy 299.634657 -288.678048) (xy 299.653948 -288.632772) (xy 299.680251 -288.591176)
			(xy 299.712886 -288.554339) (xy 299.751007 -288.523214) (xy 299.793628 -288.498607) (xy 299.839644 -288.481155)
			(xy 299.887863 -288.471311) (xy 299.937038 -288.46933) (xy 299.985893 -288.475262) (xy 300.033164 -288.488954)
			(xy 300.077626 -288.510052) (xy 300.118129 -288.538008) (xy 300.153622 -288.5721) (xy 300.183187 -288.611444)
			(xy 300.206058 -288.655021) (xy 300.221642 -288.701702) (xy 300.229537 -288.750279) (xy 300.230032 -288.774886)
			(xy 300.56888 -288.774886) (xy 300.57284 -288.725832) (xy 300.584617 -288.678048) (xy 300.603908 -288.632772)
			(xy 300.630211 -288.591176) (xy 300.662846 -288.554339) (xy 300.700967 -288.523214) (xy 300.743588 -288.498607)
			(xy 300.789604 -288.481155) (xy 300.837823 -288.471311) (xy 300.886998 -288.46933) (xy 300.935853 -288.475262)
			(xy 300.983124 -288.488954) (xy 301.027586 -288.510052) (xy 301.068089 -288.538008) (xy 301.103582 -288.5721)
			(xy 301.133147 -288.611444) (xy 301.156018 -288.655021) (xy 301.171602 -288.701702) (xy 301.179497 -288.750279)
			(xy 301.179992 -288.774886) (xy 301.519094 -288.774886) (xy 301.523054 -288.725832) (xy 301.534831 -288.678048)
			(xy 301.554122 -288.632772) (xy 301.580425 -288.591176) (xy 301.61306 -288.554339) (xy 301.651181 -288.523214)
			(xy 301.693802 -288.498607) (xy 301.739818 -288.481155) (xy 301.788037 -288.471311) (xy 301.837212 -288.46933)
			(xy 301.886067 -288.475262) (xy 301.933338 -288.488954) (xy 301.9778 -288.510052) (xy 302.018303 -288.538008)
			(xy 302.053796 -288.5721) (xy 302.083361 -288.611444) (xy 302.106232 -288.655021) (xy 302.121816 -288.701702)
			(xy 302.129711 -288.750279) (xy 302.130206 -288.774886) (xy 302.469054 -288.774886) (xy 302.473014 -288.725832)
			(xy 302.484791 -288.678048) (xy 302.504082 -288.632772) (xy 302.530385 -288.591176) (xy 302.56302 -288.554339)
			(xy 302.601141 -288.523214) (xy 302.643762 -288.498607) (xy 302.689778 -288.481155) (xy 302.737997 -288.471311)
			(xy 302.787172 -288.46933) (xy 302.836027 -288.475262) (xy 302.883298 -288.488954) (xy 302.92776 -288.510052)
			(xy 302.968263 -288.538008) (xy 303.003756 -288.5721) (xy 303.033321 -288.611444) (xy 303.056192 -288.655021)
			(xy 303.071776 -288.701702) (xy 303.079671 -288.750279) (xy 303.080166 -288.774886) (xy 303.419014 -288.774886)
			(xy 303.422974 -288.725832) (xy 303.434751 -288.678048) (xy 303.454042 -288.632772) (xy 303.480345 -288.591176)
			(xy 303.51298 -288.554339) (xy 303.551101 -288.523214) (xy 303.593722 -288.498607) (xy 303.639738 -288.481155)
			(xy 303.687957 -288.471311) (xy 303.737132 -288.46933) (xy 303.785987 -288.475262) (xy 303.833258 -288.488954)
			(xy 303.87772 -288.510052) (xy 303.918223 -288.538008) (xy 303.953716 -288.5721) (xy 303.983281 -288.611444)
			(xy 304.006152 -288.655021) (xy 304.021736 -288.701702) (xy 304.029631 -288.750279) (xy 304.030126 -288.774886)
			(xy 304.368974 -288.774886) (xy 304.372934 -288.725832) (xy 304.384711 -288.678048) (xy 304.404002 -288.632772)
			(xy 304.430305 -288.591176) (xy 304.46294 -288.554339) (xy 304.501061 -288.523214) (xy 304.543682 -288.498607)
			(xy 304.589698 -288.481155) (xy 304.637917 -288.471311) (xy 304.687092 -288.46933) (xy 304.735947 -288.475262)
			(xy 304.783218 -288.488954) (xy 304.82768 -288.510052) (xy 304.868183 -288.538008) (xy 304.903676 -288.5721)
			(xy 304.933241 -288.611444) (xy 304.956112 -288.655021) (xy 304.971696 -288.701702) (xy 304.979591 -288.750279)
			(xy 304.980086 -288.774886) (xy 304.979591 -288.799493) (xy 304.971696 -288.84807) (xy 304.956112 -288.894751)
			(xy 304.933241 -288.938328) (xy 304.903676 -288.977672) (xy 304.868183 -289.011764) (xy 304.82768 -289.03972)
			(xy 304.783218 -289.060818) (xy 304.735947 -289.07451) (xy 304.687092 -289.080442) (xy 304.637917 -289.078461)
			(xy 304.589698 -289.068617) (xy 304.543682 -289.051165) (xy 304.501061 -289.026558) (xy 304.46294 -288.995433)
			(xy 304.430305 -288.958596) (xy 304.404002 -288.917) (xy 304.384711 -288.871724) (xy 304.372934 -288.82394)
			(xy 304.368974 -288.774886) (xy 304.030126 -288.774886) (xy 304.029631 -288.799493) (xy 304.021736 -288.84807)
			(xy 304.006152 -288.894751) (xy 303.983281 -288.938328) (xy 303.953716 -288.977672) (xy 303.918223 -289.011764)
			(xy 303.87772 -289.03972) (xy 303.833258 -289.060818) (xy 303.785987 -289.07451) (xy 303.737132 -289.080442)
			(xy 303.687957 -289.078461) (xy 303.639738 -289.068617) (xy 303.593722 -289.051165) (xy 303.551101 -289.026558)
			(xy 303.51298 -288.995433) (xy 303.480345 -288.958596) (xy 303.454042 -288.917) (xy 303.434751 -288.871724)
			(xy 303.422974 -288.82394) (xy 303.419014 -288.774886) (xy 303.080166 -288.774886) (xy 303.079671 -288.799493)
			(xy 303.071776 -288.84807) (xy 303.056192 -288.894751) (xy 303.033321 -288.938328) (xy 303.003756 -288.977672)
			(xy 302.968263 -289.011764) (xy 302.92776 -289.03972) (xy 302.883298 -289.060818) (xy 302.836027 -289.07451)
			(xy 302.787172 -289.080442) (xy 302.737997 -289.078461) (xy 302.689778 -289.068617) (xy 302.643762 -289.051165)
			(xy 302.601141 -289.026558) (xy 302.56302 -288.995433) (xy 302.530385 -288.958596) (xy 302.504082 -288.917)
			(xy 302.484791 -288.871724) (xy 302.473014 -288.82394) (xy 302.469054 -288.774886) (xy 302.130206 -288.774886)
			(xy 302.129711 -288.799493) (xy 302.121816 -288.84807) (xy 302.106232 -288.894751) (xy 302.083361 -288.938328)
			(xy 302.053796 -288.977672) (xy 302.018303 -289.011764) (xy 301.9778 -289.03972) (xy 301.933338 -289.060818)
			(xy 301.886067 -289.07451) (xy 301.837212 -289.080442) (xy 301.788037 -289.078461) (xy 301.739818 -289.068617)
			(xy 301.693802 -289.051165) (xy 301.651181 -289.026558) (xy 301.61306 -288.995433) (xy 301.580425 -288.958596)
			(xy 301.554122 -288.917) (xy 301.534831 -288.871724) (xy 301.523054 -288.82394) (xy 301.519094 -288.774886)
			(xy 301.179992 -288.774886) (xy 301.179497 -288.799493) (xy 301.171602 -288.84807) (xy 301.156018 -288.894751)
			(xy 301.133147 -288.938328) (xy 301.103582 -288.977672) (xy 301.068089 -289.011764) (xy 301.027586 -289.03972)
			(xy 300.983124 -289.060818) (xy 300.935853 -289.07451) (xy 300.886998 -289.080442) (xy 300.837823 -289.078461)
			(xy 300.789604 -289.068617) (xy 300.743588 -289.051165) (xy 300.700967 -289.026558) (xy 300.662846 -288.995433)
			(xy 300.630211 -288.958596) (xy 300.603908 -288.917) (xy 300.584617 -288.871724) (xy 300.57284 -288.82394)
			(xy 300.56888 -288.774886) (xy 300.230032 -288.774886) (xy 300.229537 -288.799493) (xy 300.221642 -288.84807)
			(xy 300.206058 -288.894751) (xy 300.183187 -288.938328) (xy 300.153622 -288.977672) (xy 300.118129 -289.011764)
			(xy 300.077626 -289.03972) (xy 300.033164 -289.060818) (xy 299.985893 -289.07451) (xy 299.937038 -289.080442)
			(xy 299.887863 -289.078461) (xy 299.839644 -289.068617) (xy 299.793628 -289.051165) (xy 299.751007 -289.026558)
			(xy 299.712886 -288.995433) (xy 299.680251 -288.958596) (xy 299.653948 -288.917) (xy 299.634657 -288.871724)
			(xy 299.62288 -288.82394) (xy 299.61892 -288.774886) (xy 299.280072 -288.774886) (xy 299.279577 -288.799493)
			(xy 299.271682 -288.84807) (xy 299.256098 -288.894751) (xy 299.233227 -288.938328) (xy 299.203662 -288.977672)
			(xy 299.168169 -289.011764) (xy 299.127666 -289.03972) (xy 299.083204 -289.060818) (xy 299.035933 -289.07451)
			(xy 298.987078 -289.080442) (xy 298.937903 -289.078461) (xy 298.889684 -289.068617) (xy 298.843668 -289.051165)
			(xy 298.801047 -289.026558) (xy 298.762926 -288.995433) (xy 298.730291 -288.958596) (xy 298.703988 -288.917)
			(xy 298.684697 -288.871724) (xy 298.67292 -288.82394) (xy 298.66896 -288.774886) (xy 298.330112 -288.774886)
			(xy 298.329617 -288.799493) (xy 298.321722 -288.84807) (xy 298.306138 -288.894751) (xy 298.283267 -288.938328)
			(xy 298.253702 -288.977672) (xy 298.218209 -289.011764) (xy 298.177706 -289.03972) (xy 298.133244 -289.060818)
			(xy 298.085973 -289.07451) (xy 298.037118 -289.080442) (xy 297.987943 -289.078461) (xy 297.939724 -289.068617)
			(xy 297.893708 -289.051165) (xy 297.851087 -289.026558) (xy 297.812966 -288.995433) (xy 297.780331 -288.958596)
			(xy 297.754028 -288.917) (xy 297.734737 -288.871724) (xy 297.72296 -288.82394) (xy 297.719 -288.774886)
			(xy 297.380152 -288.774886) (xy 297.379657 -288.799493) (xy 297.371762 -288.84807) (xy 297.356178 -288.894751)
			(xy 297.333307 -288.938328) (xy 297.303742 -288.977672) (xy 297.268249 -289.011764) (xy 297.227746 -289.03972)
			(xy 297.183284 -289.060818) (xy 297.136013 -289.07451) (xy 297.087158 -289.080442) (xy 297.037983 -289.078461)
			(xy 296.989764 -289.068617) (xy 296.943748 -289.051165) (xy 296.901127 -289.026558) (xy 296.863006 -288.995433)
			(xy 296.830371 -288.958596) (xy 296.804068 -288.917) (xy 296.784777 -288.871724) (xy 296.773 -288.82394)
			(xy 296.76904 -288.774886) (xy 296.430192 -288.774886) (xy 296.429697 -288.799493) (xy 296.421802 -288.84807)
			(xy 296.406218 -288.894751) (xy 296.383347 -288.938328) (xy 296.353782 -288.977672) (xy 296.318289 -289.011764)
			(xy 296.277786 -289.03972) (xy 296.233324 -289.060818) (xy 296.186053 -289.07451) (xy 296.137198 -289.080442)
			(xy 296.088023 -289.078461) (xy 296.039804 -289.068617) (xy 295.993788 -289.051165) (xy 295.951167 -289.026558)
			(xy 295.913046 -288.995433) (xy 295.880411 -288.958596) (xy 295.854108 -288.917) (xy 295.834817 -288.871724)
			(xy 295.82304 -288.82394) (xy 295.81908 -288.774886) (xy 295.480232 -288.774886) (xy 295.479737 -288.799493)
			(xy 295.471842 -288.84807) (xy 295.456258 -288.894751) (xy 295.433387 -288.938328) (xy 295.403822 -288.977672)
			(xy 295.368329 -289.011764) (xy 295.327826 -289.03972) (xy 295.283364 -289.060818) (xy 295.236093 -289.07451)
			(xy 295.187238 -289.080442) (xy 295.138063 -289.078461) (xy 295.089844 -289.068617) (xy 295.043828 -289.051165)
			(xy 295.001207 -289.026558) (xy 294.963086 -288.995433) (xy 294.930451 -288.958596) (xy 294.904148 -288.917)
			(xy 294.884857 -288.871724) (xy 294.87308 -288.82394) (xy 294.86912 -288.774886) (xy 294.530018 -288.774886)
			(xy 294.529523 -288.799493) (xy 294.521628 -288.84807) (xy 294.506044 -288.894751) (xy 294.483173 -288.938328)
			(xy 294.453608 -288.977672) (xy 294.418115 -289.011764) (xy 294.377612 -289.03972) (xy 294.33315 -289.060818)
			(xy 294.285879 -289.07451) (xy 294.237024 -289.080442) (xy 294.187849 -289.078461) (xy 294.13963 -289.068617)
			(xy 294.093614 -289.051165) (xy 294.050993 -289.026558) (xy 294.012872 -288.995433) (xy 293.980237 -288.958596)
			(xy 293.953934 -288.917) (xy 293.934643 -288.871724) (xy 293.922866 -288.82394) (xy 293.918906 -288.774886)
			(xy 293.580058 -288.774886) (xy 293.579563 -288.799493) (xy 293.571668 -288.84807) (xy 293.556084 -288.894751)
			(xy 293.533213 -288.938328) (xy 293.503648 -288.977672) (xy 293.468155 -289.011764) (xy 293.427652 -289.03972)
			(xy 293.38319 -289.060818) (xy 293.335919 -289.07451) (xy 293.287064 -289.080442) (xy 293.237889 -289.078461)
			(xy 293.18967 -289.068617) (xy 293.143654 -289.051165) (xy 293.101033 -289.026558) (xy 293.062912 -288.995433)
			(xy 293.030277 -288.958596) (xy 293.003974 -288.917) (xy 292.984683 -288.871724) (xy 292.972906 -288.82394)
			(xy 292.968946 -288.774886) (xy 292.630098 -288.774886) (xy 292.629603 -288.799493) (xy 292.621708 -288.84807)
			(xy 292.606124 -288.894751) (xy 292.583253 -288.938328) (xy 292.553688 -288.977672) (xy 292.518195 -289.011764)
			(xy 292.477692 -289.03972) (xy 292.43323 -289.060818) (xy 292.385959 -289.07451) (xy 292.337104 -289.080442)
			(xy 292.287929 -289.078461) (xy 292.23971 -289.068617) (xy 292.193694 -289.051165) (xy 292.151073 -289.026558)
			(xy 292.112952 -288.995433) (xy 292.080317 -288.958596) (xy 292.054014 -288.917) (xy 292.034723 -288.871724)
			(xy 292.022946 -288.82394) (xy 292.018986 -288.774886) (xy 290.730178 -288.774886) (xy 290.729683 -288.799493)
			(xy 290.721788 -288.84807) (xy 290.706204 -288.894751) (xy 290.683333 -288.938328) (xy 290.653768 -288.977672)
			(xy 290.618275 -289.011764) (xy 290.577772 -289.03972) (xy 290.53331 -289.060818) (xy 290.486039 -289.07451)
			(xy 290.437184 -289.080442) (xy 290.388009 -289.078461) (xy 290.33979 -289.068617) (xy 290.293774 -289.051165)
			(xy 290.251153 -289.026558) (xy 290.213032 -288.995433) (xy 290.180397 -288.958596) (xy 290.154094 -288.917)
			(xy 290.134803 -288.871724) (xy 290.123026 -288.82394) (xy 290.119066 -288.774886) (xy 289.780218 -288.774886)
			(xy 289.779723 -288.799493) (xy 289.771828 -288.84807) (xy 289.756244 -288.894751) (xy 289.733373 -288.938328)
			(xy 289.703808 -288.977672) (xy 289.668315 -289.011764) (xy 289.627812 -289.03972) (xy 289.58335 -289.060818)
			(xy 289.536079 -289.07451) (xy 289.487224 -289.080442) (xy 289.438049 -289.078461) (xy 289.38983 -289.068617)
			(xy 289.343814 -289.051165) (xy 289.301193 -289.026558) (xy 289.263072 -288.995433) (xy 289.230437 -288.958596)
			(xy 289.204134 -288.917) (xy 289.184843 -288.871724) (xy 289.173066 -288.82394) (xy 289.169106 -288.774886)
			(xy 288.830004 -288.774886) (xy 288.829509 -288.799493) (xy 288.821614 -288.84807) (xy 288.80603 -288.894751)
			(xy 288.783159 -288.938328) (xy 288.753594 -288.977672) (xy 288.718101 -289.011764) (xy 288.677598 -289.03972)
			(xy 288.633136 -289.060818) (xy 288.585865 -289.07451) (xy 288.53701 -289.080442) (xy 288.487835 -289.078461)
			(xy 288.439616 -289.068617) (xy 288.3936 -289.051165) (xy 288.350979 -289.026558) (xy 288.312858 -288.995433)
			(xy 288.280223 -288.958596) (xy 288.25392 -288.917) (xy 288.234629 -288.871724) (xy 288.222852 -288.82394)
			(xy 288.218892 -288.774886) (xy 287.880044 -288.774886) (xy 287.879549 -288.799493) (xy 287.871654 -288.84807)
			(xy 287.85607 -288.894751) (xy 287.833199 -288.938328) (xy 287.803634 -288.977672) (xy 287.768141 -289.011764)
			(xy 287.727638 -289.03972) (xy 287.683176 -289.060818) (xy 287.635905 -289.07451) (xy 287.58705 -289.080442)
			(xy 287.537875 -289.078461) (xy 287.489656 -289.068617) (xy 287.44364 -289.051165) (xy 287.401019 -289.026558)
			(xy 287.362898 -288.995433) (xy 287.330263 -288.958596) (xy 287.30396 -288.917) (xy 287.284669 -288.871724)
			(xy 287.272892 -288.82394) (xy 287.268932 -288.774886) (xy 286.930084 -288.774886) (xy 286.929589 -288.799493)
			(xy 286.921694 -288.84807) (xy 286.90611 -288.894751) (xy 286.883239 -288.938328) (xy 286.853674 -288.977672)
			(xy 286.818181 -289.011764) (xy 286.777678 -289.03972) (xy 286.733216 -289.060818) (xy 286.685945 -289.07451)
			(xy 286.63709 -289.080442) (xy 286.587915 -289.078461) (xy 286.539696 -289.068617) (xy 286.49368 -289.051165)
			(xy 286.451059 -289.026558) (xy 286.412938 -288.995433) (xy 286.380303 -288.958596) (xy 286.354 -288.917)
			(xy 286.334709 -288.871724) (xy 286.322932 -288.82394) (xy 286.318972 -288.774886) (xy 285.980124 -288.774886)
			(xy 285.979629 -288.799493) (xy 285.971734 -288.84807) (xy 285.95615 -288.894751) (xy 285.933279 -288.938328)
			(xy 285.903714 -288.977672) (xy 285.868221 -289.011764) (xy 285.827718 -289.03972) (xy 285.783256 -289.060818)
			(xy 285.735985 -289.07451) (xy 285.68713 -289.080442) (xy 285.637955 -289.078461) (xy 285.589736 -289.068617)
			(xy 285.54372 -289.051165) (xy 285.501099 -289.026558) (xy 285.462978 -288.995433) (xy 285.430343 -288.958596)
			(xy 285.40404 -288.917) (xy 285.384749 -288.871724) (xy 285.372972 -288.82394) (xy 285.369012 -288.774886)
			(xy 285.030164 -288.774886) (xy 285.029669 -288.799493) (xy 285.021774 -288.84807) (xy 285.00619 -288.894751)
			(xy 284.983319 -288.938328) (xy 284.953754 -288.977672) (xy 284.918261 -289.011764) (xy 284.877758 -289.03972)
			(xy 284.833296 -289.060818) (xy 284.786025 -289.07451) (xy 284.73717 -289.080442) (xy 284.687995 -289.078461)
			(xy 284.639776 -289.068617) (xy 284.59376 -289.051165) (xy 284.551139 -289.026558) (xy 284.513018 -288.995433)
			(xy 284.480383 -288.958596) (xy 284.45408 -288.917) (xy 284.434789 -288.871724) (xy 284.423012 -288.82394)
			(xy 284.419052 -288.774886) (xy 284.080204 -288.774886) (xy 284.079709 -288.799493) (xy 284.071814 -288.84807)
			(xy 284.05623 -288.894751) (xy 284.033359 -288.938328) (xy 284.003794 -288.977672) (xy 283.968301 -289.011764)
			(xy 283.927798 -289.03972) (xy 283.883336 -289.060818) (xy 283.836065 -289.07451) (xy 283.78721 -289.080442)
			(xy 283.738035 -289.078461) (xy 283.689816 -289.068617) (xy 283.6438 -289.051165) (xy 283.601179 -289.026558)
			(xy 283.563058 -288.995433) (xy 283.530423 -288.958596) (xy 283.50412 -288.917) (xy 283.484829 -288.871724)
			(xy 283.473052 -288.82394) (xy 283.469092 -288.774886) (xy 283.130244 -288.774886) (xy 283.129749 -288.799493)
			(xy 283.121854 -288.84807) (xy 283.10627 -288.894751) (xy 283.083399 -288.938328) (xy 283.053834 -288.977672)
			(xy 283.018341 -289.011764) (xy 282.977838 -289.03972) (xy 282.933376 -289.060818) (xy 282.886105 -289.07451)
			(xy 282.83725 -289.080442) (xy 282.788075 -289.078461) (xy 282.739856 -289.068617) (xy 282.69384 -289.051165)
			(xy 282.651219 -289.026558) (xy 282.613098 -288.995433) (xy 282.580463 -288.958596) (xy 282.55416 -288.917)
			(xy 282.534869 -288.871724) (xy 282.523092 -288.82394) (xy 282.519132 -288.774886) (xy 282.180544 -288.774886)
			(xy 282.180545 -288.7749) (xy 282.176374 -288.825238) (xy 282.163975 -288.874203) (xy 282.143686 -288.92046)
			(xy 282.11606 -288.962747) (xy 282.081852 -288.99991) (xy 282.041993 -289.030936) (xy 281.997571 -289.054978)
			(xy 281.949799 -289.071382) (xy 281.899977 -289.079699) (xy 281.874722 -289.080194) (xy 281.844648 -289.079501)
			(xy 281.785662 -289.067735) (xy 281.757628 -289.056826) (xy 281.745436 -289.051746) (xy 281.720544 -289.054286)
			(xy 281.674515 -289.08502) (xy 317.987678 -289.08502) (xy 317.991749 -289.029398) (xy 318.003875 -288.974961)
			(xy 318.023798 -288.92287) (xy 318.051094 -288.874235) (xy 318.08518 -288.830092) (xy 318.125329 -288.791383)
			(xy 318.170687 -288.758932) (xy 318.220287 -288.733431) (xy 318.273071 -288.715424) (xy 318.327914 -288.705294)
			(xy 318.383648 -288.703257) (xy 318.439085 -288.709357) (xy 318.493042 -288.723463) (xy 318.544371 -288.745275)
			(xy 318.591977 -288.774329) (xy 318.634845 -288.810004) (xy 318.653448 -288.830766) (xy 325.352916 -288.830766)
			(xy 325.356987 -288.775144) (xy 325.369113 -288.720707) (xy 325.389036 -288.668616) (xy 325.416332 -288.619981)
			(xy 325.450418 -288.575838) (xy 325.490567 -288.537129) (xy 325.535925 -288.504678) (xy 325.585525 -288.479177)
			(xy 325.638309 -288.46117) (xy 325.693152 -288.45104) (xy 325.748886 -288.449003) (xy 325.804323 -288.455103)
			(xy 325.85828 -288.469209) (xy 325.909609 -288.491021) (xy 325.957215 -288.520075) (xy 326.000083 -288.55575)
			(xy 326.0373 -288.597287) (xy 326.068073 -288.6438) (xy 326.091745 -288.694297) (xy 326.107813 -288.747704)
			(xy 326.115933 -288.80288) (xy 326.116442 -288.830766) (xy 326.115933 -288.858652) (xy 326.107813 -288.913828)
			(xy 326.091745 -288.967235) (xy 326.068073 -289.017732) (xy 326.0373 -289.064245) (xy 326.000083 -289.105782)
			(xy 325.957215 -289.141457) (xy 325.909609 -289.170511) (xy 325.85828 -289.192323) (xy 325.804323 -289.206429)
			(xy 325.748886 -289.212529) (xy 325.693152 -289.210492) (xy 325.638309 -289.200362) (xy 325.585525 -289.182355)
			(xy 325.535925 -289.156854) (xy 325.490567 -289.124403) (xy 325.450418 -289.085694) (xy 325.416332 -289.041551)
			(xy 325.389036 -288.992916) (xy 325.369113 -288.940825) (xy 325.356987 -288.886388) (xy 325.352916 -288.830766)
			(xy 318.653448 -288.830766) (xy 318.672062 -288.851541) (xy 318.702835 -288.898054) (xy 318.726507 -288.948551)
			(xy 318.742575 -289.001958) (xy 318.750695 -289.057134) (xy 318.751204 -289.08502) (xy 318.750695 -289.112906)
			(xy 318.742575 -289.168082) (xy 318.726507 -289.221489) (xy 318.702835 -289.271986) (xy 318.672062 -289.318499)
			(xy 318.634845 -289.360036) (xy 318.591977 -289.395711) (xy 318.544371 -289.424765) (xy 318.493042 -289.446577)
			(xy 318.439085 -289.460683) (xy 318.383648 -289.466783) (xy 318.327914 -289.464746) (xy 318.273071 -289.454616)
			(xy 318.220287 -289.436609) (xy 318.170687 -289.411108) (xy 318.125329 -289.378657) (xy 318.08518 -289.339948)
			(xy 318.051094 -289.295805) (xy 318.023798 -289.24717) (xy 318.003875 -289.195079) (xy 317.991749 -289.140642)
			(xy 317.987678 -289.08502) (xy 281.674515 -289.08502) (xy 281.639518 -289.108388) (xy 281.62946 -289.115907)
			(xy 281.617608 -289.138013) (xy 281.616912 -289.150552) (xy 281.616912 -289.34918) (xy 281.61755 -289.361738)
			(xy 281.6294 -289.38388) (xy 281.639518 -289.391344) (xy 281.720544 -289.445446) (xy 281.745436 -289.447986)
			(xy 281.757628 -289.442906) (xy 281.785665 -289.432007) (xy 281.844649 -289.42024) (xy 281.874722 -289.419538)
			(xy 281.899972 -289.420061) (xy 281.949784 -289.428376) (xy 281.997547 -289.444777) (xy 282.04196 -289.468815)
			(xy 282.081811 -289.499835) (xy 282.116013 -289.53699) (xy 282.143633 -289.579269) (xy 282.163918 -289.625516)
			(xy 282.176315 -289.674472) (xy 282.180485 -289.7248) (xy 282.180481 -289.724846) (xy 282.519132 -289.724846)
			(xy 282.523092 -289.675792) (xy 282.534869 -289.628008) (xy 282.55416 -289.582732) (xy 282.580463 -289.541136)
			(xy 282.613098 -289.504299) (xy 282.651219 -289.473174) (xy 282.69384 -289.448567) (xy 282.739856 -289.431115)
			(xy 282.788075 -289.421271) (xy 282.83725 -289.41929) (xy 282.886105 -289.425222) (xy 282.933376 -289.438914)
			(xy 282.977838 -289.460012) (xy 283.018341 -289.487968) (xy 283.053834 -289.52206) (xy 283.083399 -289.561404)
			(xy 283.10627 -289.604981) (xy 283.121854 -289.651662) (xy 283.129749 -289.700239) (xy 283.130244 -289.724846)
			(xy 283.469092 -289.724846) (xy 283.473052 -289.675792) (xy 283.484829 -289.628008) (xy 283.50412 -289.582732)
			(xy 283.530423 -289.541136) (xy 283.563058 -289.504299) (xy 283.601179 -289.473174) (xy 283.6438 -289.448567)
			(xy 283.689816 -289.431115) (xy 283.738035 -289.421271) (xy 283.78721 -289.41929) (xy 283.836065 -289.425222)
			(xy 283.883336 -289.438914) (xy 283.927798 -289.460012) (xy 283.968301 -289.487968) (xy 284.003794 -289.52206)
			(xy 284.033359 -289.561404) (xy 284.05623 -289.604981) (xy 284.071814 -289.651662) (xy 284.079709 -289.700239)
			(xy 284.080204 -289.724846) (xy 284.419052 -289.724846) (xy 284.423012 -289.675792) (xy 284.434789 -289.628008)
			(xy 284.45408 -289.582732) (xy 284.480383 -289.541136) (xy 284.513018 -289.504299) (xy 284.551139 -289.473174)
			(xy 284.59376 -289.448567) (xy 284.639776 -289.431115) (xy 284.687995 -289.421271) (xy 284.73717 -289.41929)
			(xy 284.786025 -289.425222) (xy 284.833296 -289.438914) (xy 284.877758 -289.460012) (xy 284.918261 -289.487968)
			(xy 284.953754 -289.52206) (xy 284.983319 -289.561404) (xy 285.00619 -289.604981) (xy 285.021774 -289.651662)
			(xy 285.029669 -289.700239) (xy 285.030164 -289.724846) (xy 285.369012 -289.724846) (xy 285.372972 -289.675792)
			(xy 285.384749 -289.628008) (xy 285.40404 -289.582732) (xy 285.430343 -289.541136) (xy 285.462978 -289.504299)
			(xy 285.501099 -289.473174) (xy 285.54372 -289.448567) (xy 285.589736 -289.431115) (xy 285.637955 -289.421271)
			(xy 285.68713 -289.41929) (xy 285.735985 -289.425222) (xy 285.783256 -289.438914) (xy 285.827718 -289.460012)
			(xy 285.868221 -289.487968) (xy 285.903714 -289.52206) (xy 285.933279 -289.561404) (xy 285.95615 -289.604981)
			(xy 285.971734 -289.651662) (xy 285.979629 -289.700239) (xy 285.980124 -289.724846) (xy 286.318972 -289.724846)
			(xy 286.322932 -289.675792) (xy 286.334709 -289.628008) (xy 286.354 -289.582732) (xy 286.380303 -289.541136)
			(xy 286.412938 -289.504299) (xy 286.451059 -289.473174) (xy 286.49368 -289.448567) (xy 286.539696 -289.431115)
			(xy 286.587915 -289.421271) (xy 286.63709 -289.41929) (xy 286.685945 -289.425222) (xy 286.733216 -289.438914)
			(xy 286.777678 -289.460012) (xy 286.818181 -289.487968) (xy 286.853674 -289.52206) (xy 286.883239 -289.561404)
			(xy 286.90611 -289.604981) (xy 286.921694 -289.651662) (xy 286.929589 -289.700239) (xy 286.930084 -289.724846)
			(xy 287.268932 -289.724846) (xy 287.272892 -289.675792) (xy 287.284669 -289.628008) (xy 287.30396 -289.582732)
			(xy 287.330263 -289.541136) (xy 287.362898 -289.504299) (xy 287.401019 -289.473174) (xy 287.44364 -289.448567)
			(xy 287.489656 -289.431115) (xy 287.537875 -289.421271) (xy 287.58705 -289.41929) (xy 287.635905 -289.425222)
			(xy 287.683176 -289.438914) (xy 287.727638 -289.460012) (xy 287.768141 -289.487968) (xy 287.803634 -289.52206)
			(xy 287.833199 -289.561404) (xy 287.85607 -289.604981) (xy 287.871654 -289.651662) (xy 287.879549 -289.700239)
			(xy 287.880044 -289.724846) (xy 288.218892 -289.724846) (xy 288.222852 -289.675792) (xy 288.234629 -289.628008)
			(xy 288.25392 -289.582732) (xy 288.280223 -289.541136) (xy 288.312858 -289.504299) (xy 288.350979 -289.473174)
			(xy 288.3936 -289.448567) (xy 288.439616 -289.431115) (xy 288.487835 -289.421271) (xy 288.53701 -289.41929)
			(xy 288.585865 -289.425222) (xy 288.633136 -289.438914) (xy 288.677598 -289.460012) (xy 288.718101 -289.487968)
			(xy 288.753594 -289.52206) (xy 288.783159 -289.561404) (xy 288.80603 -289.604981) (xy 288.821614 -289.651662)
			(xy 288.829509 -289.700239) (xy 288.830004 -289.724846) (xy 289.169106 -289.724846) (xy 289.173066 -289.675792)
			(xy 289.184843 -289.628008) (xy 289.204134 -289.582732) (xy 289.230437 -289.541136) (xy 289.263072 -289.504299)
			(xy 289.301193 -289.473174) (xy 289.343814 -289.448567) (xy 289.38983 -289.431115) (xy 289.438049 -289.421271)
			(xy 289.487224 -289.41929) (xy 289.536079 -289.425222) (xy 289.58335 -289.438914) (xy 289.627812 -289.460012)
			(xy 289.668315 -289.487968) (xy 289.703808 -289.52206) (xy 289.733373 -289.561404) (xy 289.756244 -289.604981)
			(xy 289.771828 -289.651662) (xy 289.779723 -289.700239) (xy 289.780218 -289.724846) (xy 290.119066 -289.724846)
			(xy 290.123026 -289.675792) (xy 290.134803 -289.628008) (xy 290.154094 -289.582732) (xy 290.180397 -289.541136)
			(xy 290.213032 -289.504299) (xy 290.251153 -289.473174) (xy 290.293774 -289.448567) (xy 290.33979 -289.431115)
			(xy 290.388009 -289.421271) (xy 290.437184 -289.41929) (xy 290.486039 -289.425222) (xy 290.53331 -289.438914)
			(xy 290.577772 -289.460012) (xy 290.618275 -289.487968) (xy 290.653768 -289.52206) (xy 290.683333 -289.561404)
			(xy 290.706204 -289.604981) (xy 290.721788 -289.651662) (xy 290.729683 -289.700239) (xy 290.730178 -289.724846)
			(xy 292.018986 -289.724846) (xy 292.022946 -289.675792) (xy 292.034723 -289.628008) (xy 292.054014 -289.582732)
			(xy 292.080317 -289.541136) (xy 292.112952 -289.504299) (xy 292.151073 -289.473174) (xy 292.193694 -289.448567)
			(xy 292.23971 -289.431115) (xy 292.287929 -289.421271) (xy 292.337104 -289.41929) (xy 292.385959 -289.425222)
			(xy 292.43323 -289.438914) (xy 292.477692 -289.460012) (xy 292.518195 -289.487968) (xy 292.553688 -289.52206)
			(xy 292.583253 -289.561404) (xy 292.606124 -289.604981) (xy 292.621708 -289.651662) (xy 292.629603 -289.700239)
			(xy 292.630098 -289.724846) (xy 292.968946 -289.724846) (xy 292.972906 -289.675792) (xy 292.984683 -289.628008)
			(xy 293.003974 -289.582732) (xy 293.030277 -289.541136) (xy 293.062912 -289.504299) (xy 293.101033 -289.473174)
			(xy 293.143654 -289.448567) (xy 293.18967 -289.431115) (xy 293.237889 -289.421271) (xy 293.287064 -289.41929)
			(xy 293.335919 -289.425222) (xy 293.38319 -289.438914) (xy 293.427652 -289.460012) (xy 293.468155 -289.487968)
			(xy 293.503648 -289.52206) (xy 293.533213 -289.561404) (xy 293.556084 -289.604981) (xy 293.571668 -289.651662)
			(xy 293.579563 -289.700239) (xy 293.580058 -289.724846) (xy 293.918906 -289.724846) (xy 293.922866 -289.675792)
			(xy 293.934643 -289.628008) (xy 293.953934 -289.582732) (xy 293.980237 -289.541136) (xy 294.012872 -289.504299)
			(xy 294.050993 -289.473174) (xy 294.093614 -289.448567) (xy 294.13963 -289.431115) (xy 294.187849 -289.421271)
			(xy 294.237024 -289.41929) (xy 294.285879 -289.425222) (xy 294.33315 -289.438914) (xy 294.377612 -289.460012)
			(xy 294.418115 -289.487968) (xy 294.453608 -289.52206) (xy 294.483173 -289.561404) (xy 294.506044 -289.604981)
			(xy 294.521628 -289.651662) (xy 294.529523 -289.700239) (xy 294.530018 -289.724846) (xy 294.86912 -289.724846)
			(xy 294.87308 -289.675792) (xy 294.884857 -289.628008) (xy 294.904148 -289.582732) (xy 294.930451 -289.541136)
			(xy 294.963086 -289.504299) (xy 295.001207 -289.473174) (xy 295.043828 -289.448567) (xy 295.089844 -289.431115)
			(xy 295.138063 -289.421271) (xy 295.187238 -289.41929) (xy 295.236093 -289.425222) (xy 295.283364 -289.438914)
			(xy 295.327826 -289.460012) (xy 295.368329 -289.487968) (xy 295.403822 -289.52206) (xy 295.433387 -289.561404)
			(xy 295.456258 -289.604981) (xy 295.471842 -289.651662) (xy 295.479737 -289.700239) (xy 295.480232 -289.724846)
			(xy 295.81908 -289.724846) (xy 295.82304 -289.675792) (xy 295.834817 -289.628008) (xy 295.854108 -289.582732)
			(xy 295.880411 -289.541136) (xy 295.913046 -289.504299) (xy 295.951167 -289.473174) (xy 295.993788 -289.448567)
			(xy 296.039804 -289.431115) (xy 296.088023 -289.421271) (xy 296.137198 -289.41929) (xy 296.186053 -289.425222)
			(xy 296.233324 -289.438914) (xy 296.277786 -289.460012) (xy 296.318289 -289.487968) (xy 296.353782 -289.52206)
			(xy 296.383347 -289.561404) (xy 296.406218 -289.604981) (xy 296.421802 -289.651662) (xy 296.429697 -289.700239)
			(xy 296.430192 -289.724846) (xy 296.76904 -289.724846) (xy 296.773 -289.675792) (xy 296.784777 -289.628008)
			(xy 296.804068 -289.582732) (xy 296.830371 -289.541136) (xy 296.863006 -289.504299) (xy 296.901127 -289.473174)
			(xy 296.943748 -289.448567) (xy 296.989764 -289.431115) (xy 297.037983 -289.421271) (xy 297.087158 -289.41929)
			(xy 297.136013 -289.425222) (xy 297.183284 -289.438914) (xy 297.227746 -289.460012) (xy 297.268249 -289.487968)
			(xy 297.303742 -289.52206) (xy 297.333307 -289.561404) (xy 297.356178 -289.604981) (xy 297.371762 -289.651662)
			(xy 297.379657 -289.700239) (xy 297.380152 -289.724846) (xy 297.719 -289.724846) (xy 297.72296 -289.675792)
			(xy 297.734737 -289.628008) (xy 297.754028 -289.582732) (xy 297.780331 -289.541136) (xy 297.812966 -289.504299)
			(xy 297.851087 -289.473174) (xy 297.893708 -289.448567) (xy 297.939724 -289.431115) (xy 297.987943 -289.421271)
			(xy 298.037118 -289.41929) (xy 298.085973 -289.425222) (xy 298.133244 -289.438914) (xy 298.177706 -289.460012)
			(xy 298.218209 -289.487968) (xy 298.253702 -289.52206) (xy 298.283267 -289.561404) (xy 298.306138 -289.604981)
			(xy 298.321722 -289.651662) (xy 298.329617 -289.700239) (xy 298.330112 -289.724846) (xy 298.66896 -289.724846)
			(xy 298.67292 -289.675792) (xy 298.684697 -289.628008) (xy 298.703988 -289.582732) (xy 298.730291 -289.541136)
			(xy 298.762926 -289.504299) (xy 298.801047 -289.473174) (xy 298.843668 -289.448567) (xy 298.889684 -289.431115)
			(xy 298.937903 -289.421271) (xy 298.987078 -289.41929) (xy 299.035933 -289.425222) (xy 299.083204 -289.438914)
			(xy 299.127666 -289.460012) (xy 299.168169 -289.487968) (xy 299.203662 -289.52206) (xy 299.233227 -289.561404)
			(xy 299.256098 -289.604981) (xy 299.271682 -289.651662) (xy 299.279577 -289.700239) (xy 299.280072 -289.724846)
			(xy 299.61892 -289.724846) (xy 299.62288 -289.675792) (xy 299.634657 -289.628008) (xy 299.653948 -289.582732)
			(xy 299.680251 -289.541136) (xy 299.712886 -289.504299) (xy 299.751007 -289.473174) (xy 299.793628 -289.448567)
			(xy 299.839644 -289.431115) (xy 299.887863 -289.421271) (xy 299.937038 -289.41929) (xy 299.985893 -289.425222)
			(xy 300.033164 -289.438914) (xy 300.077626 -289.460012) (xy 300.118129 -289.487968) (xy 300.153622 -289.52206)
			(xy 300.183187 -289.561404) (xy 300.206058 -289.604981) (xy 300.221642 -289.651662) (xy 300.229537 -289.700239)
			(xy 300.230032 -289.724846) (xy 300.56888 -289.724846) (xy 300.57284 -289.675792) (xy 300.584617 -289.628008)
			(xy 300.603908 -289.582732) (xy 300.630211 -289.541136) (xy 300.662846 -289.504299) (xy 300.700967 -289.473174)
			(xy 300.743588 -289.448567) (xy 300.789604 -289.431115) (xy 300.837823 -289.421271) (xy 300.886998 -289.41929)
			(xy 300.935853 -289.425222) (xy 300.983124 -289.438914) (xy 301.027586 -289.460012) (xy 301.068089 -289.487968)
			(xy 301.103582 -289.52206) (xy 301.133147 -289.561404) (xy 301.156018 -289.604981) (xy 301.171602 -289.651662)
			(xy 301.179497 -289.700239) (xy 301.179992 -289.724846) (xy 301.519094 -289.724846) (xy 301.523054 -289.675792)
			(xy 301.534831 -289.628008) (xy 301.554122 -289.582732) (xy 301.580425 -289.541136) (xy 301.61306 -289.504299)
			(xy 301.651181 -289.473174) (xy 301.693802 -289.448567) (xy 301.739818 -289.431115) (xy 301.788037 -289.421271)
			(xy 301.837212 -289.41929) (xy 301.886067 -289.425222) (xy 301.933338 -289.438914) (xy 301.9778 -289.460012)
			(xy 302.018303 -289.487968) (xy 302.053796 -289.52206) (xy 302.083361 -289.561404) (xy 302.106232 -289.604981)
			(xy 302.121816 -289.651662) (xy 302.129711 -289.700239) (xy 302.130206 -289.724846) (xy 302.469054 -289.724846)
			(xy 302.473014 -289.675792) (xy 302.484791 -289.628008) (xy 302.504082 -289.582732) (xy 302.530385 -289.541136)
			(xy 302.56302 -289.504299) (xy 302.601141 -289.473174) (xy 302.643762 -289.448567) (xy 302.689778 -289.431115)
			(xy 302.737997 -289.421271) (xy 302.787172 -289.41929) (xy 302.836027 -289.425222) (xy 302.883298 -289.438914)
			(xy 302.92776 -289.460012) (xy 302.968263 -289.487968) (xy 303.003756 -289.52206) (xy 303.033321 -289.561404)
			(xy 303.056192 -289.604981) (xy 303.071776 -289.651662) (xy 303.079671 -289.700239) (xy 303.080166 -289.724846)
			(xy 303.419014 -289.724846) (xy 303.422974 -289.675792) (xy 303.434751 -289.628008) (xy 303.454042 -289.582732)
			(xy 303.480345 -289.541136) (xy 303.51298 -289.504299) (xy 303.551101 -289.473174) (xy 303.593722 -289.448567)
			(xy 303.639738 -289.431115) (xy 303.687957 -289.421271) (xy 303.737132 -289.41929) (xy 303.785987 -289.425222)
			(xy 303.833258 -289.438914) (xy 303.87772 -289.460012) (xy 303.918223 -289.487968) (xy 303.953716 -289.52206)
			(xy 303.983281 -289.561404) (xy 304.006152 -289.604981) (xy 304.021736 -289.651662) (xy 304.029631 -289.700239)
			(xy 304.030126 -289.724846) (xy 304.368974 -289.724846) (xy 304.372934 -289.675792) (xy 304.384711 -289.628008)
			(xy 304.404002 -289.582732) (xy 304.430305 -289.541136) (xy 304.46294 -289.504299) (xy 304.501061 -289.473174)
			(xy 304.543682 -289.448567) (xy 304.589698 -289.431115) (xy 304.637917 -289.421271) (xy 304.687092 -289.41929)
			(xy 304.735947 -289.425222) (xy 304.783218 -289.438914) (xy 304.82768 -289.460012) (xy 304.868183 -289.487968)
			(xy 304.903676 -289.52206) (xy 304.933241 -289.561404) (xy 304.956112 -289.604981) (xy 304.971696 -289.651662)
			(xy 304.979591 -289.700239) (xy 304.980086 -289.724846) (xy 305.318934 -289.724846) (xy 305.322894 -289.675792)
			(xy 305.334671 -289.628008) (xy 305.353962 -289.582732) (xy 305.380265 -289.541136) (xy 305.4129 -289.504299)
			(xy 305.451021 -289.473174) (xy 305.493642 -289.448567) (xy 305.539658 -289.431115) (xy 305.587877 -289.421271)
			(xy 305.637052 -289.41929) (xy 305.685907 -289.425222) (xy 305.733178 -289.438914) (xy 305.77764 -289.460012)
			(xy 305.818143 -289.487968) (xy 305.853636 -289.52206) (xy 305.883201 -289.561404) (xy 305.906072 -289.604981)
			(xy 305.921656 -289.651662) (xy 305.929551 -289.700239) (xy 305.930046 -289.724846) (xy 306.269148 -289.724846)
			(xy 306.273108 -289.675792) (xy 306.284885 -289.628008) (xy 306.304176 -289.582732) (xy 306.330479 -289.541136)
			(xy 306.363114 -289.504299) (xy 306.401235 -289.473174) (xy 306.443856 -289.448567) (xy 306.489872 -289.431115)
			(xy 306.538091 -289.421271) (xy 306.587266 -289.41929) (xy 306.636121 -289.425222) (xy 306.683392 -289.438914)
			(xy 306.727854 -289.460012) (xy 306.768357 -289.487968) (xy 306.80385 -289.52206) (xy 306.833415 -289.561404)
			(xy 306.856286 -289.604981) (xy 306.87187 -289.651662) (xy 306.879765 -289.700239) (xy 306.88026 -289.724846)
			(xy 308.169068 -289.724846) (xy 308.173028 -289.675792) (xy 308.184805 -289.628008) (xy 308.204096 -289.582732)
			(xy 308.230399 -289.541136) (xy 308.263034 -289.504299) (xy 308.301155 -289.473174) (xy 308.343776 -289.448567)
			(xy 308.389792 -289.431115) (xy 308.438011 -289.421271) (xy 308.487186 -289.41929) (xy 308.536041 -289.425222)
			(xy 308.583312 -289.438914) (xy 308.627774 -289.460012) (xy 308.668277 -289.487968) (xy 308.70377 -289.52206)
			(xy 308.733335 -289.561404) (xy 308.756206 -289.604981) (xy 308.77179 -289.651662) (xy 308.779685 -289.700239)
			(xy 308.78018 -289.724846) (xy 309.119028 -289.724846) (xy 309.122988 -289.675792) (xy 309.134765 -289.628008)
			(xy 309.154056 -289.582732) (xy 309.180359 -289.541136) (xy 309.212994 -289.504299) (xy 309.251115 -289.473174)
			(xy 309.293736 -289.448567) (xy 309.339752 -289.431115) (xy 309.387971 -289.421271) (xy 309.437146 -289.41929)
			(xy 309.486001 -289.425222) (xy 309.533272 -289.438914) (xy 309.577734 -289.460012) (xy 309.618237 -289.487968)
			(xy 309.65373 -289.52206) (xy 309.683295 -289.561404) (xy 309.706166 -289.604981) (xy 309.72175 -289.651662)
			(xy 309.729645 -289.700239) (xy 309.73014 -289.724846) (xy 310.068988 -289.724846) (xy 310.072948 -289.675792)
			(xy 310.084725 -289.628008) (xy 310.104016 -289.582732) (xy 310.130319 -289.541136) (xy 310.162954 -289.504299)
			(xy 310.201075 -289.473174) (xy 310.243696 -289.448567) (xy 310.289712 -289.431115) (xy 310.337931 -289.421271)
			(xy 310.387106 -289.41929) (xy 310.435961 -289.425222) (xy 310.483232 -289.438914) (xy 310.527694 -289.460012)
			(xy 310.568197 -289.487968) (xy 310.60369 -289.52206) (xy 310.633255 -289.561404) (xy 310.656126 -289.604981)
			(xy 310.67171 -289.651662) (xy 310.679605 -289.700239) (xy 310.6801 -289.724846) (xy 311.018948 -289.724846)
			(xy 311.022908 -289.675792) (xy 311.034685 -289.628008) (xy 311.053976 -289.582732) (xy 311.080279 -289.541136)
			(xy 311.112914 -289.504299) (xy 311.151035 -289.473174) (xy 311.193656 -289.448567) (xy 311.239672 -289.431115)
			(xy 311.287891 -289.421271) (xy 311.337066 -289.41929) (xy 311.385921 -289.425222) (xy 311.433192 -289.438914)
			(xy 311.477654 -289.460012) (xy 311.518157 -289.487968) (xy 311.55365 -289.52206) (xy 311.583215 -289.561404)
			(xy 311.606086 -289.604981) (xy 311.62167 -289.651662) (xy 311.629565 -289.700239) (xy 311.63006 -289.724846)
			(xy 311.968908 -289.724846) (xy 311.972868 -289.675792) (xy 311.984645 -289.628008) (xy 312.003936 -289.582732)
			(xy 312.030239 -289.541136) (xy 312.062874 -289.504299) (xy 312.100995 -289.473174) (xy 312.143616 -289.448567)
			(xy 312.189632 -289.431115) (xy 312.237851 -289.421271) (xy 312.287026 -289.41929) (xy 312.335881 -289.425222)
			(xy 312.383152 -289.438914) (xy 312.427614 -289.460012) (xy 312.468117 -289.487968) (xy 312.50361 -289.52206)
			(xy 312.533175 -289.561404) (xy 312.556046 -289.604981) (xy 312.57163 -289.651662) (xy 312.579525 -289.700239)
			(xy 312.58002 -289.724846) (xy 312.919122 -289.724846) (xy 312.923082 -289.675792) (xy 312.934859 -289.628008)
			(xy 312.95415 -289.582732) (xy 312.980453 -289.541136) (xy 313.013088 -289.504299) (xy 313.051209 -289.473174)
			(xy 313.09383 -289.448567) (xy 313.139846 -289.431115) (xy 313.188065 -289.421271) (xy 313.23724 -289.41929)
			(xy 313.286095 -289.425222) (xy 313.333366 -289.438914) (xy 313.377828 -289.460012) (xy 313.418331 -289.487968)
			(xy 313.453824 -289.52206) (xy 313.483389 -289.561404) (xy 313.50626 -289.604981) (xy 313.521844 -289.651662)
			(xy 313.529739 -289.700239) (xy 313.530234 -289.724846) (xy 313.869082 -289.724846) (xy 313.873042 -289.675792)
			(xy 313.884819 -289.628008) (xy 313.90411 -289.582732) (xy 313.930413 -289.541136) (xy 313.963048 -289.504299)
			(xy 314.001169 -289.473174) (xy 314.04379 -289.448567) (xy 314.089806 -289.431115) (xy 314.138025 -289.421271)
			(xy 314.1872 -289.41929) (xy 314.236055 -289.425222) (xy 314.283326 -289.438914) (xy 314.327788 -289.460012)
			(xy 314.368291 -289.487968) (xy 314.403784 -289.52206) (xy 314.433349 -289.561404) (xy 314.45622 -289.604981)
			(xy 314.471804 -289.651662) (xy 314.479699 -289.700239) (xy 314.480194 -289.724846) (xy 314.819042 -289.724846)
			(xy 314.823002 -289.675792) (xy 314.834779 -289.628008) (xy 314.85407 -289.582732) (xy 314.880373 -289.541136)
			(xy 314.913008 -289.504299) (xy 314.951129 -289.473174) (xy 314.99375 -289.448567) (xy 315.039766 -289.431115)
			(xy 315.087985 -289.421271) (xy 315.13716 -289.41929) (xy 315.186015 -289.425222) (xy 315.233286 -289.438914)
			(xy 315.277748 -289.460012) (xy 315.318251 -289.487968) (xy 315.353744 -289.52206) (xy 315.383309 -289.561404)
			(xy 315.40618 -289.604981) (xy 315.421764 -289.651662) (xy 315.429659 -289.700239) (xy 315.430154 -289.724846)
			(xy 315.429659 -289.749453) (xy 315.421764 -289.79803) (xy 315.40618 -289.844711) (xy 315.383309 -289.888288)
			(xy 315.353744 -289.927632) (xy 315.318251 -289.961724) (xy 315.277748 -289.98968) (xy 315.233286 -290.010778)
			(xy 315.186015 -290.02447) (xy 315.13716 -290.030402) (xy 315.087985 -290.028421) (xy 315.039766 -290.018577)
			(xy 314.99375 -290.001125) (xy 314.951129 -289.976518) (xy 314.913008 -289.945393) (xy 314.880373 -289.908556)
			(xy 314.85407 -289.86696) (xy 314.834779 -289.821684) (xy 314.823002 -289.7739) (xy 314.819042 -289.724846)
			(xy 314.480194 -289.724846) (xy 314.479699 -289.749453) (xy 314.471804 -289.79803) (xy 314.45622 -289.844711)
			(xy 314.433349 -289.888288) (xy 314.403784 -289.927632) (xy 314.368291 -289.961724) (xy 314.327788 -289.98968)
			(xy 314.283326 -290.010778) (xy 314.236055 -290.02447) (xy 314.1872 -290.030402) (xy 314.138025 -290.028421)
			(xy 314.089806 -290.018577) (xy 314.04379 -290.001125) (xy 314.001169 -289.976518) (xy 313.963048 -289.945393)
			(xy 313.930413 -289.908556) (xy 313.90411 -289.86696) (xy 313.884819 -289.821684) (xy 313.873042 -289.7739)
			(xy 313.869082 -289.724846) (xy 313.530234 -289.724846) (xy 313.529739 -289.749453) (xy 313.521844 -289.79803)
			(xy 313.50626 -289.844711) (xy 313.483389 -289.888288) (xy 313.453824 -289.927632) (xy 313.418331 -289.961724)
			(xy 313.377828 -289.98968) (xy 313.333366 -290.010778) (xy 313.286095 -290.02447) (xy 313.23724 -290.030402)
			(xy 313.188065 -290.028421) (xy 313.139846 -290.018577) (xy 313.09383 -290.001125) (xy 313.051209 -289.976518)
			(xy 313.013088 -289.945393) (xy 312.980453 -289.908556) (xy 312.95415 -289.86696) (xy 312.934859 -289.821684)
			(xy 312.923082 -289.7739) (xy 312.919122 -289.724846) (xy 312.58002 -289.724846) (xy 312.579525 -289.749453)
			(xy 312.57163 -289.79803) (xy 312.556046 -289.844711) (xy 312.533175 -289.888288) (xy 312.50361 -289.927632)
			(xy 312.468117 -289.961724) (xy 312.427614 -289.98968) (xy 312.383152 -290.010778) (xy 312.335881 -290.02447)
			(xy 312.287026 -290.030402) (xy 312.237851 -290.028421) (xy 312.189632 -290.018577) (xy 312.143616 -290.001125)
			(xy 312.100995 -289.976518) (xy 312.062874 -289.945393) (xy 312.030239 -289.908556) (xy 312.003936 -289.86696)
			(xy 311.984645 -289.821684) (xy 311.972868 -289.7739) (xy 311.968908 -289.724846) (xy 311.63006 -289.724846)
			(xy 311.629565 -289.749453) (xy 311.62167 -289.79803) (xy 311.606086 -289.844711) (xy 311.583215 -289.888288)
			(xy 311.55365 -289.927632) (xy 311.518157 -289.961724) (xy 311.477654 -289.98968) (xy 311.433192 -290.010778)
			(xy 311.385921 -290.02447) (xy 311.337066 -290.030402) (xy 311.287891 -290.028421) (xy 311.239672 -290.018577)
			(xy 311.193656 -290.001125) (xy 311.151035 -289.976518) (xy 311.112914 -289.945393) (xy 311.080279 -289.908556)
			(xy 311.053976 -289.86696) (xy 311.034685 -289.821684) (xy 311.022908 -289.7739) (xy 311.018948 -289.724846)
			(xy 310.6801 -289.724846) (xy 310.679605 -289.749453) (xy 310.67171 -289.79803) (xy 310.656126 -289.844711)
			(xy 310.633255 -289.888288) (xy 310.60369 -289.927632) (xy 310.568197 -289.961724) (xy 310.527694 -289.98968)
			(xy 310.483232 -290.010778) (xy 310.435961 -290.02447) (xy 310.387106 -290.030402) (xy 310.337931 -290.028421)
			(xy 310.289712 -290.018577) (xy 310.243696 -290.001125) (xy 310.201075 -289.976518) (xy 310.162954 -289.945393)
			(xy 310.130319 -289.908556) (xy 310.104016 -289.86696) (xy 310.084725 -289.821684) (xy 310.072948 -289.7739)
			(xy 310.068988 -289.724846) (xy 309.73014 -289.724846) (xy 309.729645 -289.749453) (xy 309.72175 -289.79803)
			(xy 309.706166 -289.844711) (xy 309.683295 -289.888288) (xy 309.65373 -289.927632) (xy 309.618237 -289.961724)
			(xy 309.577734 -289.98968) (xy 309.533272 -290.010778) (xy 309.486001 -290.02447) (xy 309.437146 -290.030402)
			(xy 309.387971 -290.028421) (xy 309.339752 -290.018577) (xy 309.293736 -290.001125) (xy 309.251115 -289.976518)
			(xy 309.212994 -289.945393) (xy 309.180359 -289.908556) (xy 309.154056 -289.86696) (xy 309.134765 -289.821684)
			(xy 309.122988 -289.7739) (xy 309.119028 -289.724846) (xy 308.78018 -289.724846) (xy 308.779685 -289.749453)
			(xy 308.77179 -289.79803) (xy 308.756206 -289.844711) (xy 308.733335 -289.888288) (xy 308.70377 -289.927632)
			(xy 308.668277 -289.961724) (xy 308.627774 -289.98968) (xy 308.583312 -290.010778) (xy 308.536041 -290.02447)
			(xy 308.487186 -290.030402) (xy 308.438011 -290.028421) (xy 308.389792 -290.018577) (xy 308.343776 -290.001125)
			(xy 308.301155 -289.976518) (xy 308.263034 -289.945393) (xy 308.230399 -289.908556) (xy 308.204096 -289.86696)
			(xy 308.184805 -289.821684) (xy 308.173028 -289.7739) (xy 308.169068 -289.724846) (xy 306.88026 -289.724846)
			(xy 306.879765 -289.749453) (xy 306.87187 -289.79803) (xy 306.856286 -289.844711) (xy 306.833415 -289.888288)
			(xy 306.80385 -289.927632) (xy 306.768357 -289.961724) (xy 306.727854 -289.98968) (xy 306.683392 -290.010778)
			(xy 306.636121 -290.02447) (xy 306.587266 -290.030402) (xy 306.538091 -290.028421) (xy 306.489872 -290.018577)
			(xy 306.443856 -290.001125) (xy 306.401235 -289.976518) (xy 306.363114 -289.945393) (xy 306.330479 -289.908556)
			(xy 306.304176 -289.86696) (xy 306.284885 -289.821684) (xy 306.273108 -289.7739) (xy 306.269148 -289.724846)
			(xy 305.930046 -289.724846) (xy 305.929551 -289.749453) (xy 305.921656 -289.79803) (xy 305.906072 -289.844711)
			(xy 305.883201 -289.888288) (xy 305.853636 -289.927632) (xy 305.818143 -289.961724) (xy 305.77764 -289.98968)
			(xy 305.733178 -290.010778) (xy 305.685907 -290.02447) (xy 305.637052 -290.030402) (xy 305.587877 -290.028421)
			(xy 305.539658 -290.018577) (xy 305.493642 -290.001125) (xy 305.451021 -289.976518) (xy 305.4129 -289.945393)
			(xy 305.380265 -289.908556) (xy 305.353962 -289.86696) (xy 305.334671 -289.821684) (xy 305.322894 -289.7739)
			(xy 305.318934 -289.724846) (xy 304.980086 -289.724846) (xy 304.979591 -289.749453) (xy 304.971696 -289.79803)
			(xy 304.956112 -289.844711) (xy 304.933241 -289.888288) (xy 304.903676 -289.927632) (xy 304.868183 -289.961724)
			(xy 304.82768 -289.98968) (xy 304.783218 -290.010778) (xy 304.735947 -290.02447) (xy 304.687092 -290.030402)
			(xy 304.637917 -290.028421) (xy 304.589698 -290.018577) (xy 304.543682 -290.001125) (xy 304.501061 -289.976518)
			(xy 304.46294 -289.945393) (xy 304.430305 -289.908556) (xy 304.404002 -289.86696) (xy 304.384711 -289.821684)
			(xy 304.372934 -289.7739) (xy 304.368974 -289.724846) (xy 304.030126 -289.724846) (xy 304.029631 -289.749453)
			(xy 304.021736 -289.79803) (xy 304.006152 -289.844711) (xy 303.983281 -289.888288) (xy 303.953716 -289.927632)
			(xy 303.918223 -289.961724) (xy 303.87772 -289.98968) (xy 303.833258 -290.010778) (xy 303.785987 -290.02447)
			(xy 303.737132 -290.030402) (xy 303.687957 -290.028421) (xy 303.639738 -290.018577) (xy 303.593722 -290.001125)
			(xy 303.551101 -289.976518) (xy 303.51298 -289.945393) (xy 303.480345 -289.908556) (xy 303.454042 -289.86696)
			(xy 303.434751 -289.821684) (xy 303.422974 -289.7739) (xy 303.419014 -289.724846) (xy 303.080166 -289.724846)
			(xy 303.079671 -289.749453) (xy 303.071776 -289.79803) (xy 303.056192 -289.844711) (xy 303.033321 -289.888288)
			(xy 303.003756 -289.927632) (xy 302.968263 -289.961724) (xy 302.92776 -289.98968) (xy 302.883298 -290.010778)
			(xy 302.836027 -290.02447) (xy 302.787172 -290.030402) (xy 302.737997 -290.028421) (xy 302.689778 -290.018577)
			(xy 302.643762 -290.001125) (xy 302.601141 -289.976518) (xy 302.56302 -289.945393) (xy 302.530385 -289.908556)
			(xy 302.504082 -289.86696) (xy 302.484791 -289.821684) (xy 302.473014 -289.7739) (xy 302.469054 -289.724846)
			(xy 302.130206 -289.724846) (xy 302.129711 -289.749453) (xy 302.121816 -289.79803) (xy 302.106232 -289.844711)
			(xy 302.083361 -289.888288) (xy 302.053796 -289.927632) (xy 302.018303 -289.961724) (xy 301.9778 -289.98968)
			(xy 301.933338 -290.010778) (xy 301.886067 -290.02447) (xy 301.837212 -290.030402) (xy 301.788037 -290.028421)
			(xy 301.739818 -290.018577) (xy 301.693802 -290.001125) (xy 301.651181 -289.976518) (xy 301.61306 -289.945393)
			(xy 301.580425 -289.908556) (xy 301.554122 -289.86696) (xy 301.534831 -289.821684) (xy 301.523054 -289.7739)
			(xy 301.519094 -289.724846) (xy 301.179992 -289.724846) (xy 301.179497 -289.749453) (xy 301.171602 -289.79803)
			(xy 301.156018 -289.844711) (xy 301.133147 -289.888288) (xy 301.103582 -289.927632) (xy 301.068089 -289.961724)
			(xy 301.027586 -289.98968) (xy 300.983124 -290.010778) (xy 300.935853 -290.02447) (xy 300.886998 -290.030402)
			(xy 300.837823 -290.028421) (xy 300.789604 -290.018577) (xy 300.743588 -290.001125) (xy 300.700967 -289.976518)
			(xy 300.662846 -289.945393) (xy 300.630211 -289.908556) (xy 300.603908 -289.86696) (xy 300.584617 -289.821684)
			(xy 300.57284 -289.7739) (xy 300.56888 -289.724846) (xy 300.230032 -289.724846) (xy 300.229537 -289.749453)
			(xy 300.221642 -289.79803) (xy 300.206058 -289.844711) (xy 300.183187 -289.888288) (xy 300.153622 -289.927632)
			(xy 300.118129 -289.961724) (xy 300.077626 -289.98968) (xy 300.033164 -290.010778) (xy 299.985893 -290.02447)
			(xy 299.937038 -290.030402) (xy 299.887863 -290.028421) (xy 299.839644 -290.018577) (xy 299.793628 -290.001125)
			(xy 299.751007 -289.976518) (xy 299.712886 -289.945393) (xy 299.680251 -289.908556) (xy 299.653948 -289.86696)
			(xy 299.634657 -289.821684) (xy 299.62288 -289.7739) (xy 299.61892 -289.724846) (xy 299.280072 -289.724846)
			(xy 299.279577 -289.749453) (xy 299.271682 -289.79803) (xy 299.256098 -289.844711) (xy 299.233227 -289.888288)
			(xy 299.203662 -289.927632) (xy 299.168169 -289.961724) (xy 299.127666 -289.98968) (xy 299.083204 -290.010778)
			(xy 299.035933 -290.02447) (xy 298.987078 -290.030402) (xy 298.937903 -290.028421) (xy 298.889684 -290.018577)
			(xy 298.843668 -290.001125) (xy 298.801047 -289.976518) (xy 298.762926 -289.945393) (xy 298.730291 -289.908556)
			(xy 298.703988 -289.86696) (xy 298.684697 -289.821684) (xy 298.67292 -289.7739) (xy 298.66896 -289.724846)
			(xy 298.330112 -289.724846) (xy 298.329617 -289.749453) (xy 298.321722 -289.79803) (xy 298.306138 -289.844711)
			(xy 298.283267 -289.888288) (xy 298.253702 -289.927632) (xy 298.218209 -289.961724) (xy 298.177706 -289.98968)
			(xy 298.133244 -290.010778) (xy 298.085973 -290.02447) (xy 298.037118 -290.030402) (xy 297.987943 -290.028421)
			(xy 297.939724 -290.018577) (xy 297.893708 -290.001125) (xy 297.851087 -289.976518) (xy 297.812966 -289.945393)
			(xy 297.780331 -289.908556) (xy 297.754028 -289.86696) (xy 297.734737 -289.821684) (xy 297.72296 -289.7739)
			(xy 297.719 -289.724846) (xy 297.380152 -289.724846) (xy 297.379657 -289.749453) (xy 297.371762 -289.79803)
			(xy 297.356178 -289.844711) (xy 297.333307 -289.888288) (xy 297.303742 -289.927632) (xy 297.268249 -289.961724)
			(xy 297.227746 -289.98968) (xy 297.183284 -290.010778) (xy 297.136013 -290.02447) (xy 297.087158 -290.030402)
			(xy 297.037983 -290.028421) (xy 296.989764 -290.018577) (xy 296.943748 -290.001125) (xy 296.901127 -289.976518)
			(xy 296.863006 -289.945393) (xy 296.830371 -289.908556) (xy 296.804068 -289.86696) (xy 296.784777 -289.821684)
			(xy 296.773 -289.7739) (xy 296.76904 -289.724846) (xy 296.430192 -289.724846) (xy 296.429697 -289.749453)
			(xy 296.421802 -289.79803) (xy 296.406218 -289.844711) (xy 296.383347 -289.888288) (xy 296.353782 -289.927632)
			(xy 296.318289 -289.961724) (xy 296.277786 -289.98968) (xy 296.233324 -290.010778) (xy 296.186053 -290.02447)
			(xy 296.137198 -290.030402) (xy 296.088023 -290.028421) (xy 296.039804 -290.018577) (xy 295.993788 -290.001125)
			(xy 295.951167 -289.976518) (xy 295.913046 -289.945393) (xy 295.880411 -289.908556) (xy 295.854108 -289.86696)
			(xy 295.834817 -289.821684) (xy 295.82304 -289.7739) (xy 295.81908 -289.724846) (xy 295.480232 -289.724846)
			(xy 295.479737 -289.749453) (xy 295.471842 -289.79803) (xy 295.456258 -289.844711) (xy 295.433387 -289.888288)
			(xy 295.403822 -289.927632) (xy 295.368329 -289.961724) (xy 295.327826 -289.98968) (xy 295.283364 -290.010778)
			(xy 295.236093 -290.02447) (xy 295.187238 -290.030402) (xy 295.138063 -290.028421) (xy 295.089844 -290.018577)
			(xy 295.043828 -290.001125) (xy 295.001207 -289.976518) (xy 294.963086 -289.945393) (xy 294.930451 -289.908556)
			(xy 294.904148 -289.86696) (xy 294.884857 -289.821684) (xy 294.87308 -289.7739) (xy 294.86912 -289.724846)
			(xy 294.530018 -289.724846) (xy 294.529523 -289.749453) (xy 294.521628 -289.79803) (xy 294.506044 -289.844711)
			(xy 294.483173 -289.888288) (xy 294.453608 -289.927632) (xy 294.418115 -289.961724) (xy 294.377612 -289.98968)
			(xy 294.33315 -290.010778) (xy 294.285879 -290.02447) (xy 294.237024 -290.030402) (xy 294.187849 -290.028421)
			(xy 294.13963 -290.018577) (xy 294.093614 -290.001125) (xy 294.050993 -289.976518) (xy 294.012872 -289.945393)
			(xy 293.980237 -289.908556) (xy 293.953934 -289.86696) (xy 293.934643 -289.821684) (xy 293.922866 -289.7739)
			(xy 293.918906 -289.724846) (xy 293.580058 -289.724846) (xy 293.579563 -289.749453) (xy 293.571668 -289.79803)
			(xy 293.556084 -289.844711) (xy 293.533213 -289.888288) (xy 293.503648 -289.927632) (xy 293.468155 -289.961724)
			(xy 293.427652 -289.98968) (xy 293.38319 -290.010778) (xy 293.335919 -290.02447) (xy 293.287064 -290.030402)
			(xy 293.237889 -290.028421) (xy 293.18967 -290.018577) (xy 293.143654 -290.001125) (xy 293.101033 -289.976518)
			(xy 293.062912 -289.945393) (xy 293.030277 -289.908556) (xy 293.003974 -289.86696) (xy 292.984683 -289.821684)
			(xy 292.972906 -289.7739) (xy 292.968946 -289.724846) (xy 292.630098 -289.724846) (xy 292.629603 -289.749453)
			(xy 292.621708 -289.79803) (xy 292.606124 -289.844711) (xy 292.583253 -289.888288) (xy 292.553688 -289.927632)
			(xy 292.518195 -289.961724) (xy 292.477692 -289.98968) (xy 292.43323 -290.010778) (xy 292.385959 -290.02447)
			(xy 292.337104 -290.030402) (xy 292.287929 -290.028421) (xy 292.23971 -290.018577) (xy 292.193694 -290.001125)
			(xy 292.151073 -289.976518) (xy 292.112952 -289.945393) (xy 292.080317 -289.908556) (xy 292.054014 -289.86696)
			(xy 292.034723 -289.821684) (xy 292.022946 -289.7739) (xy 292.018986 -289.724846) (xy 290.730178 -289.724846)
			(xy 290.729683 -289.749453) (xy 290.721788 -289.79803) (xy 290.706204 -289.844711) (xy 290.683333 -289.888288)
			(xy 290.653768 -289.927632) (xy 290.618275 -289.961724) (xy 290.577772 -289.98968) (xy 290.53331 -290.010778)
			(xy 290.486039 -290.02447) (xy 290.437184 -290.030402) (xy 290.388009 -290.028421) (xy 290.33979 -290.018577)
			(xy 290.293774 -290.001125) (xy 290.251153 -289.976518) (xy 290.213032 -289.945393) (xy 290.180397 -289.908556)
			(xy 290.154094 -289.86696) (xy 290.134803 -289.821684) (xy 290.123026 -289.7739) (xy 290.119066 -289.724846)
			(xy 289.780218 -289.724846) (xy 289.779723 -289.749453) (xy 289.771828 -289.79803) (xy 289.756244 -289.844711)
			(xy 289.733373 -289.888288) (xy 289.703808 -289.927632) (xy 289.668315 -289.961724) (xy 289.627812 -289.98968)
			(xy 289.58335 -290.010778) (xy 289.536079 -290.02447) (xy 289.487224 -290.030402) (xy 289.438049 -290.028421)
			(xy 289.38983 -290.018577) (xy 289.343814 -290.001125) (xy 289.301193 -289.976518) (xy 289.263072 -289.945393)
			(xy 289.230437 -289.908556) (xy 289.204134 -289.86696) (xy 289.184843 -289.821684) (xy 289.173066 -289.7739)
			(xy 289.169106 -289.724846) (xy 288.830004 -289.724846) (xy 288.829509 -289.749453) (xy 288.821614 -289.79803)
			(xy 288.80603 -289.844711) (xy 288.783159 -289.888288) (xy 288.753594 -289.927632) (xy 288.718101 -289.961724)
			(xy 288.677598 -289.98968) (xy 288.633136 -290.010778) (xy 288.585865 -290.02447) (xy 288.53701 -290.030402)
			(xy 288.487835 -290.028421) (xy 288.439616 -290.018577) (xy 288.3936 -290.001125) (xy 288.350979 -289.976518)
			(xy 288.312858 -289.945393) (xy 288.280223 -289.908556) (xy 288.25392 -289.86696) (xy 288.234629 -289.821684)
			(xy 288.222852 -289.7739) (xy 288.218892 -289.724846) (xy 287.880044 -289.724846) (xy 287.879549 -289.749453)
			(xy 287.871654 -289.79803) (xy 287.85607 -289.844711) (xy 287.833199 -289.888288) (xy 287.803634 -289.927632)
			(xy 287.768141 -289.961724) (xy 287.727638 -289.98968) (xy 287.683176 -290.010778) (xy 287.635905 -290.02447)
			(xy 287.58705 -290.030402) (xy 287.537875 -290.028421) (xy 287.489656 -290.018577) (xy 287.44364 -290.001125)
			(xy 287.401019 -289.976518) (xy 287.362898 -289.945393) (xy 287.330263 -289.908556) (xy 287.30396 -289.86696)
			(xy 287.284669 -289.821684) (xy 287.272892 -289.7739) (xy 287.268932 -289.724846) (xy 286.930084 -289.724846)
			(xy 286.929589 -289.749453) (xy 286.921694 -289.79803) (xy 286.90611 -289.844711) (xy 286.883239 -289.888288)
			(xy 286.853674 -289.927632) (xy 286.818181 -289.961724) (xy 286.777678 -289.98968) (xy 286.733216 -290.010778)
			(xy 286.685945 -290.02447) (xy 286.63709 -290.030402) (xy 286.587915 -290.028421) (xy 286.539696 -290.018577)
			(xy 286.49368 -290.001125) (xy 286.451059 -289.976518) (xy 286.412938 -289.945393) (xy 286.380303 -289.908556)
			(xy 286.354 -289.86696) (xy 286.334709 -289.821684) (xy 286.322932 -289.7739) (xy 286.318972 -289.724846)
			(xy 285.980124 -289.724846) (xy 285.979629 -289.749453) (xy 285.971734 -289.79803) (xy 285.95615 -289.844711)
			(xy 285.933279 -289.888288) (xy 285.903714 -289.927632) (xy 285.868221 -289.961724) (xy 285.827718 -289.98968)
			(xy 285.783256 -290.010778) (xy 285.735985 -290.02447) (xy 285.68713 -290.030402) (xy 285.637955 -290.028421)
			(xy 285.589736 -290.018577) (xy 285.54372 -290.001125) (xy 285.501099 -289.976518) (xy 285.462978 -289.945393)
			(xy 285.430343 -289.908556) (xy 285.40404 -289.86696) (xy 285.384749 -289.821684) (xy 285.372972 -289.7739)
			(xy 285.369012 -289.724846) (xy 285.030164 -289.724846) (xy 285.029669 -289.749453) (xy 285.021774 -289.79803)
			(xy 285.00619 -289.844711) (xy 284.983319 -289.888288) (xy 284.953754 -289.927632) (xy 284.918261 -289.961724)
			(xy 284.877758 -289.98968) (xy 284.833296 -290.010778) (xy 284.786025 -290.02447) (xy 284.73717 -290.030402)
			(xy 284.687995 -290.028421) (xy 284.639776 -290.018577) (xy 284.59376 -290.001125) (xy 284.551139 -289.976518)
			(xy 284.513018 -289.945393) (xy 284.480383 -289.908556) (xy 284.45408 -289.86696) (xy 284.434789 -289.821684)
			(xy 284.423012 -289.7739) (xy 284.419052 -289.724846) (xy 284.080204 -289.724846) (xy 284.079709 -289.749453)
			(xy 284.071814 -289.79803) (xy 284.05623 -289.844711) (xy 284.033359 -289.888288) (xy 284.003794 -289.927632)
			(xy 283.968301 -289.961724) (xy 283.927798 -289.98968) (xy 283.883336 -290.010778) (xy 283.836065 -290.02447)
			(xy 283.78721 -290.030402) (xy 283.738035 -290.028421) (xy 283.689816 -290.018577) (xy 283.6438 -290.001125)
			(xy 283.601179 -289.976518) (xy 283.563058 -289.945393) (xy 283.530423 -289.908556) (xy 283.50412 -289.86696)
			(xy 283.484829 -289.821684) (xy 283.473052 -289.7739) (xy 283.469092 -289.724846) (xy 283.130244 -289.724846)
			(xy 283.129749 -289.749453) (xy 283.121854 -289.79803) (xy 283.10627 -289.844711) (xy 283.083399 -289.888288)
			(xy 283.053834 -289.927632) (xy 283.018341 -289.961724) (xy 282.977838 -289.98968) (xy 282.933376 -290.010778)
			(xy 282.886105 -290.02447) (xy 282.83725 -290.030402) (xy 282.788075 -290.028421) (xy 282.739856 -290.018577)
			(xy 282.69384 -290.001125) (xy 282.651219 -289.976518) (xy 282.613098 -289.945393) (xy 282.580463 -289.908556)
			(xy 282.55416 -289.86696) (xy 282.534869 -289.821684) (xy 282.523092 -289.7739) (xy 282.519132 -289.724846)
			(xy 282.180481 -289.724846) (xy 282.176315 -289.775128) (xy 282.163918 -289.824084) (xy 282.143633 -289.870331)
			(xy 282.116013 -289.91261) (xy 282.081811 -289.949765) (xy 282.04196 -289.980785) (xy 281.997547 -290.004823)
			(xy 281.949784 -290.021224) (xy 281.899972 -290.029539) (xy 281.874722 -290.030154) (xy 281.844648 -290.02946)
			(xy 281.785663 -290.017693) (xy 281.757628 -290.006786) (xy 281.745436 -290.001706) (xy 281.720544 -290.004246)
			(xy 281.639518 -290.058348) (xy 281.62947 -290.065871) (xy 281.617644 -290.087979) (xy 281.616912 -290.100512)
			(xy 281.616912 -290.278312) (xy 317.353694 -290.278312) (xy 317.357765 -290.22269) (xy 317.369891 -290.168253)
			(xy 317.389814 -290.116162) (xy 317.41711 -290.067527) (xy 317.451196 -290.023384) (xy 317.491345 -289.984675)
			(xy 317.536703 -289.952224) (xy 317.586303 -289.926723) (xy 317.639087 -289.908716) (xy 317.69393 -289.898586)
			(xy 317.749664 -289.896549) (xy 317.805101 -289.902649) (xy 317.859058 -289.916755) (xy 317.910387 -289.938567)
			(xy 317.957993 -289.967621) (xy 318.000861 -290.003296) (xy 318.038078 -290.044833) (xy 318.068851 -290.091346)
			(xy 318.092523 -290.141843) (xy 318.108591 -290.19525) (xy 318.114759 -290.237164) (xy 321.364354 -290.237164)
			(xy 321.368425 -290.181542) (xy 321.380551 -290.127105) (xy 321.400474 -290.075014) (xy 321.42777 -290.026379)
			(xy 321.461856 -289.982236) (xy 321.502005 -289.943527) (xy 321.547363 -289.911076) (xy 321.596963 -289.885575)
			(xy 321.649747 -289.867568) (xy 321.70459 -289.857438) (xy 321.760324 -289.855401) (xy 321.815761 -289.861501)
			(xy 321.869718 -289.875607) (xy 321.921047 -289.897419) (xy 321.968653 -289.926473) (xy 322.011521 -289.962148)
			(xy 322.048738 -290.003685) (xy 322.079511 -290.050198) (xy 322.103183 -290.100695) (xy 322.119251 -290.154102)
			(xy 322.127371 -290.209278) (xy 322.12788 -290.237164) (xy 322.127371 -290.26505) (xy 322.119251 -290.320226)
			(xy 322.103183 -290.373633) (xy 322.079511 -290.42413) (xy 322.048738 -290.470643) (xy 322.011521 -290.51218)
			(xy 321.968653 -290.547855) (xy 321.921047 -290.576909) (xy 321.869718 -290.598721) (xy 321.815761 -290.612827)
			(xy 321.760324 -290.618927) (xy 321.70459 -290.61689) (xy 321.649747 -290.60676) (xy 321.596963 -290.588753)
			(xy 321.547363 -290.563252) (xy 321.502005 -290.530801) (xy 321.461856 -290.492092) (xy 321.42777 -290.447949)
			(xy 321.400474 -290.399314) (xy 321.380551 -290.347223) (xy 321.368425 -290.292786) (xy 321.364354 -290.237164)
			(xy 318.114759 -290.237164) (xy 318.116711 -290.250426) (xy 318.11722 -290.278312) (xy 318.116711 -290.306198)
			(xy 318.108591 -290.361374) (xy 318.092523 -290.414781) (xy 318.068851 -290.465278) (xy 318.038078 -290.511791)
			(xy 318.000861 -290.553328) (xy 317.957993 -290.589003) (xy 317.910387 -290.618057) (xy 317.859058 -290.639869)
			(xy 317.805101 -290.653975) (xy 317.749664 -290.660075) (xy 317.69393 -290.658038) (xy 317.639087 -290.647908)
			(xy 317.586303 -290.629901) (xy 317.536703 -290.6044) (xy 317.491345 -290.571949) (xy 317.451196 -290.53324)
			(xy 317.41711 -290.489097) (xy 317.389814 -290.440462) (xy 317.369891 -290.388371) (xy 317.357765 -290.333934)
			(xy 317.353694 -290.278312) (xy 281.616912 -290.278312) (xy 281.616912 -290.29914) (xy 281.617563 -290.311691)
			(xy 281.629428 -290.33381) (xy 281.639518 -290.341304) (xy 281.720544 -290.395406) (xy 281.745436 -290.397946)
			(xy 281.757628 -290.392866) (xy 281.785665 -290.381968) (xy 281.844649 -290.370203) (xy 281.874722 -290.369498)
			(xy 281.899976 -290.370021) (xy 281.949794 -290.378338) (xy 281.997563 -290.39474) (xy 282.041982 -290.418781)
			(xy 282.081838 -290.449805) (xy 282.116045 -290.486966) (xy 282.143668 -290.52925) (xy 282.163956 -290.575503)
			(xy 282.176354 -290.624465) (xy 282.180525 -290.6748) (xy 282.180525 -290.674806) (xy 282.519132 -290.674806)
			(xy 282.523092 -290.625752) (xy 282.534869 -290.577968) (xy 282.55416 -290.532692) (xy 282.580463 -290.491096)
			(xy 282.613098 -290.454259) (xy 282.651219 -290.423134) (xy 282.69384 -290.398527) (xy 282.739856 -290.381075)
			(xy 282.788075 -290.371231) (xy 282.83725 -290.36925) (xy 282.886105 -290.375182) (xy 282.933376 -290.388874)
			(xy 282.977838 -290.409972) (xy 283.018341 -290.437928) (xy 283.053834 -290.47202) (xy 283.083399 -290.511364)
			(xy 283.10627 -290.554941) (xy 283.121854 -290.601622) (xy 283.129749 -290.650199) (xy 283.130244 -290.674806)
			(xy 283.469092 -290.674806) (xy 283.473052 -290.625752) (xy 283.484829 -290.577968) (xy 283.50412 -290.532692)
			(xy 283.530423 -290.491096) (xy 283.563058 -290.454259) (xy 283.601179 -290.423134) (xy 283.6438 -290.398527)
			(xy 283.689816 -290.381075) (xy 283.738035 -290.371231) (xy 283.78721 -290.36925) (xy 283.836065 -290.375182)
			(xy 283.883336 -290.388874) (xy 283.927798 -290.409972) (xy 283.968301 -290.437928) (xy 284.003794 -290.47202)
			(xy 284.033359 -290.511364) (xy 284.05623 -290.554941) (xy 284.071814 -290.601622) (xy 284.079709 -290.650199)
			(xy 284.080204 -290.674806) (xy 284.419052 -290.674806) (xy 284.423012 -290.625752) (xy 284.434789 -290.577968)
			(xy 284.45408 -290.532692) (xy 284.480383 -290.491096) (xy 284.513018 -290.454259) (xy 284.551139 -290.423134)
			(xy 284.59376 -290.398527) (xy 284.639776 -290.381075) (xy 284.687995 -290.371231) (xy 284.73717 -290.36925)
			(xy 284.786025 -290.375182) (xy 284.833296 -290.388874) (xy 284.877758 -290.409972) (xy 284.918261 -290.437928)
			(xy 284.953754 -290.47202) (xy 284.983319 -290.511364) (xy 285.00619 -290.554941) (xy 285.021774 -290.601622)
			(xy 285.029669 -290.650199) (xy 285.030164 -290.674806) (xy 285.369012 -290.674806) (xy 285.372972 -290.625752)
			(xy 285.384749 -290.577968) (xy 285.40404 -290.532692) (xy 285.430343 -290.491096) (xy 285.462978 -290.454259)
			(xy 285.501099 -290.423134) (xy 285.54372 -290.398527) (xy 285.589736 -290.381075) (xy 285.637955 -290.371231)
			(xy 285.68713 -290.36925) (xy 285.735985 -290.375182) (xy 285.783256 -290.388874) (xy 285.827718 -290.409972)
			(xy 285.868221 -290.437928) (xy 285.903714 -290.47202) (xy 285.933279 -290.511364) (xy 285.95615 -290.554941)
			(xy 285.971734 -290.601622) (xy 285.979629 -290.650199) (xy 285.980124 -290.674806) (xy 286.318972 -290.674806)
			(xy 286.322932 -290.625752) (xy 286.334709 -290.577968) (xy 286.354 -290.532692) (xy 286.380303 -290.491096)
			(xy 286.412938 -290.454259) (xy 286.451059 -290.423134) (xy 286.49368 -290.398527) (xy 286.539696 -290.381075)
			(xy 286.587915 -290.371231) (xy 286.63709 -290.36925) (xy 286.685945 -290.375182) (xy 286.733216 -290.388874)
			(xy 286.777678 -290.409972) (xy 286.818181 -290.437928) (xy 286.853674 -290.47202) (xy 286.883239 -290.511364)
			(xy 286.90611 -290.554941) (xy 286.921694 -290.601622) (xy 286.929589 -290.650199) (xy 286.930084 -290.674806)
			(xy 287.268932 -290.674806) (xy 287.272892 -290.625752) (xy 287.284669 -290.577968) (xy 287.30396 -290.532692)
			(xy 287.330263 -290.491096) (xy 287.362898 -290.454259) (xy 287.401019 -290.423134) (xy 287.44364 -290.398527)
			(xy 287.489656 -290.381075) (xy 287.537875 -290.371231) (xy 287.58705 -290.36925) (xy 287.635905 -290.375182)
			(xy 287.683176 -290.388874) (xy 287.727638 -290.409972) (xy 287.768141 -290.437928) (xy 287.803634 -290.47202)
			(xy 287.833199 -290.511364) (xy 287.85607 -290.554941) (xy 287.871654 -290.601622) (xy 287.879549 -290.650199)
			(xy 287.880044 -290.674806) (xy 288.218892 -290.674806) (xy 288.222852 -290.625752) (xy 288.234629 -290.577968)
			(xy 288.25392 -290.532692) (xy 288.280223 -290.491096) (xy 288.312858 -290.454259) (xy 288.350979 -290.423134)
			(xy 288.3936 -290.398527) (xy 288.439616 -290.381075) (xy 288.487835 -290.371231) (xy 288.53701 -290.36925)
			(xy 288.585865 -290.375182) (xy 288.633136 -290.388874) (xy 288.677598 -290.409972) (xy 288.718101 -290.437928)
			(xy 288.753594 -290.47202) (xy 288.783159 -290.511364) (xy 288.80603 -290.554941) (xy 288.821614 -290.601622)
			(xy 288.829509 -290.650199) (xy 288.830004 -290.674806) (xy 289.169106 -290.674806) (xy 289.173066 -290.625752)
			(xy 289.184843 -290.577968) (xy 289.204134 -290.532692) (xy 289.230437 -290.491096) (xy 289.263072 -290.454259)
			(xy 289.301193 -290.423134) (xy 289.343814 -290.398527) (xy 289.38983 -290.381075) (xy 289.438049 -290.371231)
			(xy 289.487224 -290.36925) (xy 289.536079 -290.375182) (xy 289.58335 -290.388874) (xy 289.627812 -290.409972)
			(xy 289.668315 -290.437928) (xy 289.703808 -290.47202) (xy 289.733373 -290.511364) (xy 289.756244 -290.554941)
			(xy 289.771828 -290.601622) (xy 289.779723 -290.650199) (xy 289.780218 -290.674806) (xy 290.119066 -290.674806)
			(xy 290.123026 -290.625752) (xy 290.134803 -290.577968) (xy 290.154094 -290.532692) (xy 290.180397 -290.491096)
			(xy 290.213032 -290.454259) (xy 290.251153 -290.423134) (xy 290.293774 -290.398527) (xy 290.33979 -290.381075)
			(xy 290.388009 -290.371231) (xy 290.437184 -290.36925) (xy 290.486039 -290.375182) (xy 290.53331 -290.388874)
			(xy 290.577772 -290.409972) (xy 290.618275 -290.437928) (xy 290.653768 -290.47202) (xy 290.683333 -290.511364)
			(xy 290.706204 -290.554941) (xy 290.721788 -290.601622) (xy 290.729683 -290.650199) (xy 290.730178 -290.674806)
			(xy 292.018986 -290.674806) (xy 292.022946 -290.625752) (xy 292.034723 -290.577968) (xy 292.054014 -290.532692)
			(xy 292.080317 -290.491096) (xy 292.112952 -290.454259) (xy 292.151073 -290.423134) (xy 292.193694 -290.398527)
			(xy 292.23971 -290.381075) (xy 292.287929 -290.371231) (xy 292.337104 -290.36925) (xy 292.385959 -290.375182)
			(xy 292.43323 -290.388874) (xy 292.477692 -290.409972) (xy 292.518195 -290.437928) (xy 292.553688 -290.47202)
			(xy 292.583253 -290.511364) (xy 292.606124 -290.554941) (xy 292.621708 -290.601622) (xy 292.629603 -290.650199)
			(xy 292.630098 -290.674806) (xy 292.968946 -290.674806) (xy 292.972906 -290.625752) (xy 292.984683 -290.577968)
			(xy 293.003974 -290.532692) (xy 293.030277 -290.491096) (xy 293.062912 -290.454259) (xy 293.101033 -290.423134)
			(xy 293.143654 -290.398527) (xy 293.18967 -290.381075) (xy 293.237889 -290.371231) (xy 293.287064 -290.36925)
			(xy 293.335919 -290.375182) (xy 293.38319 -290.388874) (xy 293.427652 -290.409972) (xy 293.468155 -290.437928)
			(xy 293.503648 -290.47202) (xy 293.533213 -290.511364) (xy 293.556084 -290.554941) (xy 293.571668 -290.601622)
			(xy 293.579563 -290.650199) (xy 293.580058 -290.674806) (xy 293.918906 -290.674806) (xy 293.922866 -290.625752)
			(xy 293.934643 -290.577968) (xy 293.953934 -290.532692) (xy 293.980237 -290.491096) (xy 294.012872 -290.454259)
			(xy 294.050993 -290.423134) (xy 294.093614 -290.398527) (xy 294.13963 -290.381075) (xy 294.187849 -290.371231)
			(xy 294.237024 -290.36925) (xy 294.285879 -290.375182) (xy 294.33315 -290.388874) (xy 294.377612 -290.409972)
			(xy 294.418115 -290.437928) (xy 294.453608 -290.47202) (xy 294.483173 -290.511364) (xy 294.506044 -290.554941)
			(xy 294.521628 -290.601622) (xy 294.529523 -290.650199) (xy 294.530018 -290.674806) (xy 294.86912 -290.674806)
			(xy 294.87308 -290.625752) (xy 294.884857 -290.577968) (xy 294.904148 -290.532692) (xy 294.930451 -290.491096)
			(xy 294.963086 -290.454259) (xy 295.001207 -290.423134) (xy 295.043828 -290.398527) (xy 295.089844 -290.381075)
			(xy 295.138063 -290.371231) (xy 295.187238 -290.36925) (xy 295.236093 -290.375182) (xy 295.283364 -290.388874)
			(xy 295.327826 -290.409972) (xy 295.368329 -290.437928) (xy 295.403822 -290.47202) (xy 295.433387 -290.511364)
			(xy 295.456258 -290.554941) (xy 295.471842 -290.601622) (xy 295.479737 -290.650199) (xy 295.480232 -290.674806)
			(xy 295.81908 -290.674806) (xy 295.82304 -290.625752) (xy 295.834817 -290.577968) (xy 295.854108 -290.532692)
			(xy 295.880411 -290.491096) (xy 295.913046 -290.454259) (xy 295.951167 -290.423134) (xy 295.993788 -290.398527)
			(xy 296.039804 -290.381075) (xy 296.088023 -290.371231) (xy 296.137198 -290.36925) (xy 296.186053 -290.375182)
			(xy 296.233324 -290.388874) (xy 296.277786 -290.409972) (xy 296.318289 -290.437928) (xy 296.353782 -290.47202)
			(xy 296.383347 -290.511364) (xy 296.406218 -290.554941) (xy 296.421802 -290.601622) (xy 296.429697 -290.650199)
			(xy 296.430192 -290.674806) (xy 296.76904 -290.674806) (xy 296.773 -290.625752) (xy 296.784777 -290.577968)
			(xy 296.804068 -290.532692) (xy 296.830371 -290.491096) (xy 296.863006 -290.454259) (xy 296.901127 -290.423134)
			(xy 296.943748 -290.398527) (xy 296.989764 -290.381075) (xy 297.037983 -290.371231) (xy 297.087158 -290.36925)
			(xy 297.136013 -290.375182) (xy 297.183284 -290.388874) (xy 297.227746 -290.409972) (xy 297.268249 -290.437928)
			(xy 297.303742 -290.47202) (xy 297.333307 -290.511364) (xy 297.356178 -290.554941) (xy 297.371762 -290.601622)
			(xy 297.379657 -290.650199) (xy 297.380152 -290.674806) (xy 297.719 -290.674806) (xy 297.72296 -290.625752)
			(xy 297.734737 -290.577968) (xy 297.754028 -290.532692) (xy 297.780331 -290.491096) (xy 297.812966 -290.454259)
			(xy 297.851087 -290.423134) (xy 297.893708 -290.398527) (xy 297.939724 -290.381075) (xy 297.987943 -290.371231)
			(xy 298.037118 -290.36925) (xy 298.085973 -290.375182) (xy 298.133244 -290.388874) (xy 298.177706 -290.409972)
			(xy 298.218209 -290.437928) (xy 298.253702 -290.47202) (xy 298.283267 -290.511364) (xy 298.306138 -290.554941)
			(xy 298.321722 -290.601622) (xy 298.329617 -290.650199) (xy 298.330112 -290.674806) (xy 298.66896 -290.674806)
			(xy 298.67292 -290.625752) (xy 298.684697 -290.577968) (xy 298.703988 -290.532692) (xy 298.730291 -290.491096)
			(xy 298.762926 -290.454259) (xy 298.801047 -290.423134) (xy 298.843668 -290.398527) (xy 298.889684 -290.381075)
			(xy 298.937903 -290.371231) (xy 298.987078 -290.36925) (xy 299.035933 -290.375182) (xy 299.083204 -290.388874)
			(xy 299.127666 -290.409972) (xy 299.168169 -290.437928) (xy 299.203662 -290.47202) (xy 299.233227 -290.511364)
			(xy 299.256098 -290.554941) (xy 299.271682 -290.601622) (xy 299.279577 -290.650199) (xy 299.280072 -290.674806)
			(xy 299.61892 -290.674806) (xy 299.62288 -290.625752) (xy 299.634657 -290.577968) (xy 299.653948 -290.532692)
			(xy 299.680251 -290.491096) (xy 299.712886 -290.454259) (xy 299.751007 -290.423134) (xy 299.793628 -290.398527)
			(xy 299.839644 -290.381075) (xy 299.887863 -290.371231) (xy 299.937038 -290.36925) (xy 299.985893 -290.375182)
			(xy 300.033164 -290.388874) (xy 300.077626 -290.409972) (xy 300.118129 -290.437928) (xy 300.153622 -290.47202)
			(xy 300.183187 -290.511364) (xy 300.206058 -290.554941) (xy 300.221642 -290.601622) (xy 300.229537 -290.650199)
			(xy 300.230032 -290.674806) (xy 300.56888 -290.674806) (xy 300.57284 -290.625752) (xy 300.584617 -290.577968)
			(xy 300.603908 -290.532692) (xy 300.630211 -290.491096) (xy 300.662846 -290.454259) (xy 300.700967 -290.423134)
			(xy 300.743588 -290.398527) (xy 300.789604 -290.381075) (xy 300.837823 -290.371231) (xy 300.886998 -290.36925)
			(xy 300.935853 -290.375182) (xy 300.983124 -290.388874) (xy 301.027586 -290.409972) (xy 301.068089 -290.437928)
			(xy 301.103582 -290.47202) (xy 301.133147 -290.511364) (xy 301.156018 -290.554941) (xy 301.171602 -290.601622)
			(xy 301.179497 -290.650199) (xy 301.179992 -290.674806) (xy 301.519094 -290.674806) (xy 301.523054 -290.625752)
			(xy 301.534831 -290.577968) (xy 301.554122 -290.532692) (xy 301.580425 -290.491096) (xy 301.61306 -290.454259)
			(xy 301.651181 -290.423134) (xy 301.693802 -290.398527) (xy 301.739818 -290.381075) (xy 301.788037 -290.371231)
			(xy 301.837212 -290.36925) (xy 301.886067 -290.375182) (xy 301.933338 -290.388874) (xy 301.9778 -290.409972)
			(xy 302.018303 -290.437928) (xy 302.053796 -290.47202) (xy 302.083361 -290.511364) (xy 302.106232 -290.554941)
			(xy 302.121816 -290.601622) (xy 302.129711 -290.650199) (xy 302.130206 -290.674806) (xy 302.469054 -290.674806)
			(xy 302.473014 -290.625752) (xy 302.484791 -290.577968) (xy 302.504082 -290.532692) (xy 302.530385 -290.491096)
			(xy 302.56302 -290.454259) (xy 302.601141 -290.423134) (xy 302.643762 -290.398527) (xy 302.689778 -290.381075)
			(xy 302.737997 -290.371231) (xy 302.787172 -290.36925) (xy 302.836027 -290.375182) (xy 302.883298 -290.388874)
			(xy 302.92776 -290.409972) (xy 302.968263 -290.437928) (xy 303.003756 -290.47202) (xy 303.033321 -290.511364)
			(xy 303.056192 -290.554941) (xy 303.071776 -290.601622) (xy 303.079671 -290.650199) (xy 303.080166 -290.674806)
			(xy 303.419014 -290.674806) (xy 303.422974 -290.625752) (xy 303.434751 -290.577968) (xy 303.454042 -290.532692)
			(xy 303.480345 -290.491096) (xy 303.51298 -290.454259) (xy 303.551101 -290.423134) (xy 303.593722 -290.398527)
			(xy 303.639738 -290.381075) (xy 303.687957 -290.371231) (xy 303.737132 -290.36925) (xy 303.785987 -290.375182)
			(xy 303.833258 -290.388874) (xy 303.87772 -290.409972) (xy 303.918223 -290.437928) (xy 303.953716 -290.47202)
			(xy 303.983281 -290.511364) (xy 304.006152 -290.554941) (xy 304.021736 -290.601622) (xy 304.029631 -290.650199)
			(xy 304.030126 -290.674806) (xy 304.368974 -290.674806) (xy 304.372934 -290.625752) (xy 304.384711 -290.577968)
			(xy 304.404002 -290.532692) (xy 304.430305 -290.491096) (xy 304.46294 -290.454259) (xy 304.501061 -290.423134)
			(xy 304.543682 -290.398527) (xy 304.589698 -290.381075) (xy 304.637917 -290.371231) (xy 304.687092 -290.36925)
			(xy 304.735947 -290.375182) (xy 304.783218 -290.388874) (xy 304.82768 -290.409972) (xy 304.868183 -290.437928)
			(xy 304.903676 -290.47202) (xy 304.933241 -290.511364) (xy 304.956112 -290.554941) (xy 304.971696 -290.601622)
			(xy 304.979591 -290.650199) (xy 304.980086 -290.674806) (xy 305.318934 -290.674806) (xy 305.322894 -290.625752)
			(xy 305.334671 -290.577968) (xy 305.353962 -290.532692) (xy 305.380265 -290.491096) (xy 305.4129 -290.454259)
			(xy 305.451021 -290.423134) (xy 305.493642 -290.398527) (xy 305.539658 -290.381075) (xy 305.587877 -290.371231)
			(xy 305.637052 -290.36925) (xy 305.685907 -290.375182) (xy 305.733178 -290.388874) (xy 305.77764 -290.409972)
			(xy 305.818143 -290.437928) (xy 305.853636 -290.47202) (xy 305.883201 -290.511364) (xy 305.906072 -290.554941)
			(xy 305.921656 -290.601622) (xy 305.929551 -290.650199) (xy 305.930046 -290.674806) (xy 306.268894 -290.674806)
			(xy 306.272854 -290.625752) (xy 306.284631 -290.577968) (xy 306.303922 -290.532692) (xy 306.330225 -290.491096)
			(xy 306.36286 -290.454259) (xy 306.400981 -290.423134) (xy 306.443602 -290.398527) (xy 306.489618 -290.381075)
			(xy 306.537837 -290.371231) (xy 306.587012 -290.36925) (xy 306.635867 -290.375182) (xy 306.683138 -290.388874)
			(xy 306.7276 -290.409972) (xy 306.768103 -290.437928) (xy 306.803596 -290.47202) (xy 306.833161 -290.511364)
			(xy 306.856032 -290.554941) (xy 306.871616 -290.601622) (xy 306.879511 -290.650199) (xy 306.880006 -290.674806)
			(xy 307.219108 -290.674806) (xy 307.223068 -290.625752) (xy 307.234845 -290.577968) (xy 307.254136 -290.532692)
			(xy 307.280439 -290.491096) (xy 307.313074 -290.454259) (xy 307.351195 -290.423134) (xy 307.393816 -290.398527)
			(xy 307.439832 -290.381075) (xy 307.488051 -290.371231) (xy 307.537226 -290.36925) (xy 307.586081 -290.375182)
			(xy 307.633352 -290.388874) (xy 307.677814 -290.409972) (xy 307.718317 -290.437928) (xy 307.75381 -290.47202)
			(xy 307.783375 -290.511364) (xy 307.806246 -290.554941) (xy 307.82183 -290.601622) (xy 307.829725 -290.650199)
			(xy 307.83022 -290.674806) (xy 308.169068 -290.674806) (xy 308.173028 -290.625752) (xy 308.184805 -290.577968)
			(xy 308.204096 -290.532692) (xy 308.230399 -290.491096) (xy 308.263034 -290.454259) (xy 308.301155 -290.423134)
			(xy 308.343776 -290.398527) (xy 308.389792 -290.381075) (xy 308.438011 -290.371231) (xy 308.487186 -290.36925)
			(xy 308.536041 -290.375182) (xy 308.583312 -290.388874) (xy 308.627774 -290.409972) (xy 308.668277 -290.437928)
			(xy 308.70377 -290.47202) (xy 308.733335 -290.511364) (xy 308.756206 -290.554941) (xy 308.77179 -290.601622)
			(xy 308.779685 -290.650199) (xy 308.78018 -290.674806) (xy 309.119028 -290.674806) (xy 309.122988 -290.625752)
			(xy 309.134765 -290.577968) (xy 309.154056 -290.532692) (xy 309.180359 -290.491096) (xy 309.212994 -290.454259)
			(xy 309.251115 -290.423134) (xy 309.293736 -290.398527) (xy 309.339752 -290.381075) (xy 309.387971 -290.371231)
			(xy 309.437146 -290.36925) (xy 309.486001 -290.375182) (xy 309.533272 -290.388874) (xy 309.577734 -290.409972)
			(xy 309.618237 -290.437928) (xy 309.65373 -290.47202) (xy 309.683295 -290.511364) (xy 309.706166 -290.554941)
			(xy 309.72175 -290.601622) (xy 309.729645 -290.650199) (xy 309.73014 -290.674806) (xy 310.068988 -290.674806)
			(xy 310.072948 -290.625752) (xy 310.084725 -290.577968) (xy 310.104016 -290.532692) (xy 310.130319 -290.491096)
			(xy 310.162954 -290.454259) (xy 310.201075 -290.423134) (xy 310.243696 -290.398527) (xy 310.289712 -290.381075)
			(xy 310.337931 -290.371231) (xy 310.387106 -290.36925) (xy 310.435961 -290.375182) (xy 310.483232 -290.388874)
			(xy 310.527694 -290.409972) (xy 310.568197 -290.437928) (xy 310.60369 -290.47202) (xy 310.633255 -290.511364)
			(xy 310.656126 -290.554941) (xy 310.67171 -290.601622) (xy 310.679605 -290.650199) (xy 310.6801 -290.674806)
			(xy 311.018948 -290.674806) (xy 311.022908 -290.625752) (xy 311.034685 -290.577968) (xy 311.053976 -290.532692)
			(xy 311.080279 -290.491096) (xy 311.112914 -290.454259) (xy 311.151035 -290.423134) (xy 311.193656 -290.398527)
			(xy 311.239672 -290.381075) (xy 311.287891 -290.371231) (xy 311.337066 -290.36925) (xy 311.385921 -290.375182)
			(xy 311.433192 -290.388874) (xy 311.477654 -290.409972) (xy 311.518157 -290.437928) (xy 311.55365 -290.47202)
			(xy 311.583215 -290.511364) (xy 311.606086 -290.554941) (xy 311.62167 -290.601622) (xy 311.629565 -290.650199)
			(xy 311.63006 -290.674806) (xy 311.968908 -290.674806) (xy 311.972868 -290.625752) (xy 311.984645 -290.577968)
			(xy 312.003936 -290.532692) (xy 312.030239 -290.491096) (xy 312.062874 -290.454259) (xy 312.100995 -290.423134)
			(xy 312.143616 -290.398527) (xy 312.189632 -290.381075) (xy 312.237851 -290.371231) (xy 312.287026 -290.36925)
			(xy 312.335881 -290.375182) (xy 312.383152 -290.388874) (xy 312.427614 -290.409972) (xy 312.468117 -290.437928)
			(xy 312.50361 -290.47202) (xy 312.533175 -290.511364) (xy 312.556046 -290.554941) (xy 312.57163 -290.601622)
			(xy 312.579525 -290.650199) (xy 312.58002 -290.674806) (xy 312.919122 -290.674806) (xy 312.923082 -290.625752)
			(xy 312.934859 -290.577968) (xy 312.95415 -290.532692) (xy 312.980453 -290.491096) (xy 313.013088 -290.454259)
			(xy 313.051209 -290.423134) (xy 313.09383 -290.398527) (xy 313.139846 -290.381075) (xy 313.188065 -290.371231)
			(xy 313.23724 -290.36925) (xy 313.286095 -290.375182) (xy 313.333366 -290.388874) (xy 313.377828 -290.409972)
			(xy 313.418331 -290.437928) (xy 313.453824 -290.47202) (xy 313.483389 -290.511364) (xy 313.50626 -290.554941)
			(xy 313.521844 -290.601622) (xy 313.529739 -290.650199) (xy 313.530234 -290.674806) (xy 313.869082 -290.674806)
			(xy 313.873042 -290.625752) (xy 313.884819 -290.577968) (xy 313.90411 -290.532692) (xy 313.930413 -290.491096)
			(xy 313.963048 -290.454259) (xy 314.001169 -290.423134) (xy 314.04379 -290.398527) (xy 314.089806 -290.381075)
			(xy 314.138025 -290.371231) (xy 314.1872 -290.36925) (xy 314.236055 -290.375182) (xy 314.283326 -290.388874)
			(xy 314.327788 -290.409972) (xy 314.368291 -290.437928) (xy 314.403784 -290.47202) (xy 314.433349 -290.511364)
			(xy 314.45622 -290.554941) (xy 314.471804 -290.601622) (xy 314.479699 -290.650199) (xy 314.480194 -290.674806)
			(xy 314.819042 -290.674806) (xy 314.823002 -290.625752) (xy 314.834779 -290.577968) (xy 314.85407 -290.532692)
			(xy 314.880373 -290.491096) (xy 314.913008 -290.454259) (xy 314.951129 -290.423134) (xy 314.99375 -290.398527)
			(xy 315.039766 -290.381075) (xy 315.087985 -290.371231) (xy 315.13716 -290.36925) (xy 315.186015 -290.375182)
			(xy 315.233286 -290.388874) (xy 315.277748 -290.409972) (xy 315.318251 -290.437928) (xy 315.353744 -290.47202)
			(xy 315.383309 -290.511364) (xy 315.40618 -290.554941) (xy 315.421764 -290.601622) (xy 315.429659 -290.650199)
			(xy 315.430154 -290.674806) (xy 315.429659 -290.699413) (xy 315.421764 -290.74799) (xy 315.40618 -290.794671)
			(xy 315.383309 -290.838248) (xy 315.353744 -290.877592) (xy 315.318251 -290.911684) (xy 315.277748 -290.93964)
			(xy 315.233286 -290.960738) (xy 315.186015 -290.97443) (xy 315.13716 -290.980362) (xy 315.087985 -290.978381)
			(xy 315.039766 -290.968537) (xy 314.99375 -290.951085) (xy 314.951129 -290.926478) (xy 314.913008 -290.895353)
			(xy 314.880373 -290.858516) (xy 314.85407 -290.81692) (xy 314.834779 -290.771644) (xy 314.823002 -290.72386)
			(xy 314.819042 -290.674806) (xy 314.480194 -290.674806) (xy 314.479699 -290.699413) (xy 314.471804 -290.74799)
			(xy 314.45622 -290.794671) (xy 314.433349 -290.838248) (xy 314.403784 -290.877592) (xy 314.368291 -290.911684)
			(xy 314.327788 -290.93964) (xy 314.283326 -290.960738) (xy 314.236055 -290.97443) (xy 314.1872 -290.980362)
			(xy 314.138025 -290.978381) (xy 314.089806 -290.968537) (xy 314.04379 -290.951085) (xy 314.001169 -290.926478)
			(xy 313.963048 -290.895353) (xy 313.930413 -290.858516) (xy 313.90411 -290.81692) (xy 313.884819 -290.771644)
			(xy 313.873042 -290.72386) (xy 313.869082 -290.674806) (xy 313.530234 -290.674806) (xy 313.529739 -290.699413)
			(xy 313.521844 -290.74799) (xy 313.50626 -290.794671) (xy 313.483389 -290.838248) (xy 313.453824 -290.877592)
			(xy 313.418331 -290.911684) (xy 313.377828 -290.93964) (xy 313.333366 -290.960738) (xy 313.286095 -290.97443)
			(xy 313.23724 -290.980362) (xy 313.188065 -290.978381) (xy 313.139846 -290.968537) (xy 313.09383 -290.951085)
			(xy 313.051209 -290.926478) (xy 313.013088 -290.895353) (xy 312.980453 -290.858516) (xy 312.95415 -290.81692)
			(xy 312.934859 -290.771644) (xy 312.923082 -290.72386) (xy 312.919122 -290.674806) (xy 312.58002 -290.674806)
			(xy 312.579525 -290.699413) (xy 312.57163 -290.74799) (xy 312.556046 -290.794671) (xy 312.533175 -290.838248)
			(xy 312.50361 -290.877592) (xy 312.468117 -290.911684) (xy 312.427614 -290.93964) (xy 312.383152 -290.960738)
			(xy 312.335881 -290.97443) (xy 312.287026 -290.980362) (xy 312.237851 -290.978381) (xy 312.189632 -290.968537)
			(xy 312.143616 -290.951085) (xy 312.100995 -290.926478) (xy 312.062874 -290.895353) (xy 312.030239 -290.858516)
			(xy 312.003936 -290.81692) (xy 311.984645 -290.771644) (xy 311.972868 -290.72386) (xy 311.968908 -290.674806)
			(xy 311.63006 -290.674806) (xy 311.629565 -290.699413) (xy 311.62167 -290.74799) (xy 311.606086 -290.794671)
			(xy 311.583215 -290.838248) (xy 311.55365 -290.877592) (xy 311.518157 -290.911684) (xy 311.477654 -290.93964)
			(xy 311.433192 -290.960738) (xy 311.385921 -290.97443) (xy 311.337066 -290.980362) (xy 311.287891 -290.978381)
			(xy 311.239672 -290.968537) (xy 311.193656 -290.951085) (xy 311.151035 -290.926478) (xy 311.112914 -290.895353)
			(xy 311.080279 -290.858516) (xy 311.053976 -290.81692) (xy 311.034685 -290.771644) (xy 311.022908 -290.72386)
			(xy 311.018948 -290.674806) (xy 310.6801 -290.674806) (xy 310.679605 -290.699413) (xy 310.67171 -290.74799)
			(xy 310.656126 -290.794671) (xy 310.633255 -290.838248) (xy 310.60369 -290.877592) (xy 310.568197 -290.911684)
			(xy 310.527694 -290.93964) (xy 310.483232 -290.960738) (xy 310.435961 -290.97443) (xy 310.387106 -290.980362)
			(xy 310.337931 -290.978381) (xy 310.289712 -290.968537) (xy 310.243696 -290.951085) (xy 310.201075 -290.926478)
			(xy 310.162954 -290.895353) (xy 310.130319 -290.858516) (xy 310.104016 -290.81692) (xy 310.084725 -290.771644)
			(xy 310.072948 -290.72386) (xy 310.068988 -290.674806) (xy 309.73014 -290.674806) (xy 309.729645 -290.699413)
			(xy 309.72175 -290.74799) (xy 309.706166 -290.794671) (xy 309.683295 -290.838248) (xy 309.65373 -290.877592)
			(xy 309.618237 -290.911684) (xy 309.577734 -290.93964) (xy 309.533272 -290.960738) (xy 309.486001 -290.97443)
			(xy 309.437146 -290.980362) (xy 309.387971 -290.978381) (xy 309.339752 -290.968537) (xy 309.293736 -290.951085)
			(xy 309.251115 -290.926478) (xy 309.212994 -290.895353) (xy 309.180359 -290.858516) (xy 309.154056 -290.81692)
			(xy 309.134765 -290.771644) (xy 309.122988 -290.72386) (xy 309.119028 -290.674806) (xy 308.78018 -290.674806)
			(xy 308.779685 -290.699413) (xy 308.77179 -290.74799) (xy 308.756206 -290.794671) (xy 308.733335 -290.838248)
			(xy 308.70377 -290.877592) (xy 308.668277 -290.911684) (xy 308.627774 -290.93964) (xy 308.583312 -290.960738)
			(xy 308.536041 -290.97443) (xy 308.487186 -290.980362) (xy 308.438011 -290.978381) (xy 308.389792 -290.968537)
			(xy 308.343776 -290.951085) (xy 308.301155 -290.926478) (xy 308.263034 -290.895353) (xy 308.230399 -290.858516)
			(xy 308.204096 -290.81692) (xy 308.184805 -290.771644) (xy 308.173028 -290.72386) (xy 308.169068 -290.674806)
			(xy 307.83022 -290.674806) (xy 307.829725 -290.699413) (xy 307.82183 -290.74799) (xy 307.806246 -290.794671)
			(xy 307.783375 -290.838248) (xy 307.75381 -290.877592) (xy 307.718317 -290.911684) (xy 307.677814 -290.93964)
			(xy 307.633352 -290.960738) (xy 307.586081 -290.97443) (xy 307.537226 -290.980362) (xy 307.488051 -290.978381)
			(xy 307.439832 -290.968537) (xy 307.393816 -290.951085) (xy 307.351195 -290.926478) (xy 307.313074 -290.895353)
			(xy 307.280439 -290.858516) (xy 307.254136 -290.81692) (xy 307.234845 -290.771644) (xy 307.223068 -290.72386)
			(xy 307.219108 -290.674806) (xy 306.880006 -290.674806) (xy 306.879511 -290.699413) (xy 306.871616 -290.74799)
			(xy 306.856032 -290.794671) (xy 306.833161 -290.838248) (xy 306.803596 -290.877592) (xy 306.768103 -290.911684)
			(xy 306.7276 -290.93964) (xy 306.683138 -290.960738) (xy 306.635867 -290.97443) (xy 306.587012 -290.980362)
			(xy 306.537837 -290.978381) (xy 306.489618 -290.968537) (xy 306.443602 -290.951085) (xy 306.400981 -290.926478)
			(xy 306.36286 -290.895353) (xy 306.330225 -290.858516) (xy 306.303922 -290.81692) (xy 306.284631 -290.771644)
			(xy 306.272854 -290.72386) (xy 306.268894 -290.674806) (xy 305.930046 -290.674806) (xy 305.929551 -290.699413)
			(xy 305.921656 -290.74799) (xy 305.906072 -290.794671) (xy 305.883201 -290.838248) (xy 305.853636 -290.877592)
			(xy 305.818143 -290.911684) (xy 305.77764 -290.93964) (xy 305.733178 -290.960738) (xy 305.685907 -290.97443)
			(xy 305.637052 -290.980362) (xy 305.587877 -290.978381) (xy 305.539658 -290.968537) (xy 305.493642 -290.951085)
			(xy 305.451021 -290.926478) (xy 305.4129 -290.895353) (xy 305.380265 -290.858516) (xy 305.353962 -290.81692)
			(xy 305.334671 -290.771644) (xy 305.322894 -290.72386) (xy 305.318934 -290.674806) (xy 304.980086 -290.674806)
			(xy 304.979591 -290.699413) (xy 304.971696 -290.74799) (xy 304.956112 -290.794671) (xy 304.933241 -290.838248)
			(xy 304.903676 -290.877592) (xy 304.868183 -290.911684) (xy 304.82768 -290.93964) (xy 304.783218 -290.960738)
			(xy 304.735947 -290.97443) (xy 304.687092 -290.980362) (xy 304.637917 -290.978381) (xy 304.589698 -290.968537)
			(xy 304.543682 -290.951085) (xy 304.501061 -290.926478) (xy 304.46294 -290.895353) (xy 304.430305 -290.858516)
			(xy 304.404002 -290.81692) (xy 304.384711 -290.771644) (xy 304.372934 -290.72386) (xy 304.368974 -290.674806)
			(xy 304.030126 -290.674806) (xy 304.029631 -290.699413) (xy 304.021736 -290.74799) (xy 304.006152 -290.794671)
			(xy 303.983281 -290.838248) (xy 303.953716 -290.877592) (xy 303.918223 -290.911684) (xy 303.87772 -290.93964)
			(xy 303.833258 -290.960738) (xy 303.785987 -290.97443) (xy 303.737132 -290.980362) (xy 303.687957 -290.978381)
			(xy 303.639738 -290.968537) (xy 303.593722 -290.951085) (xy 303.551101 -290.926478) (xy 303.51298 -290.895353)
			(xy 303.480345 -290.858516) (xy 303.454042 -290.81692) (xy 303.434751 -290.771644) (xy 303.422974 -290.72386)
			(xy 303.419014 -290.674806) (xy 303.080166 -290.674806) (xy 303.079671 -290.699413) (xy 303.071776 -290.74799)
			(xy 303.056192 -290.794671) (xy 303.033321 -290.838248) (xy 303.003756 -290.877592) (xy 302.968263 -290.911684)
			(xy 302.92776 -290.93964) (xy 302.883298 -290.960738) (xy 302.836027 -290.97443) (xy 302.787172 -290.980362)
			(xy 302.737997 -290.978381) (xy 302.689778 -290.968537) (xy 302.643762 -290.951085) (xy 302.601141 -290.926478)
			(xy 302.56302 -290.895353) (xy 302.530385 -290.858516) (xy 302.504082 -290.81692) (xy 302.484791 -290.771644)
			(xy 302.473014 -290.72386) (xy 302.469054 -290.674806) (xy 302.130206 -290.674806) (xy 302.129711 -290.699413)
			(xy 302.121816 -290.74799) (xy 302.106232 -290.794671) (xy 302.083361 -290.838248) (xy 302.053796 -290.877592)
			(xy 302.018303 -290.911684) (xy 301.9778 -290.93964) (xy 301.933338 -290.960738) (xy 301.886067 -290.97443)
			(xy 301.837212 -290.980362) (xy 301.788037 -290.978381) (xy 301.739818 -290.968537) (xy 301.693802 -290.951085)
			(xy 301.651181 -290.926478) (xy 301.61306 -290.895353) (xy 301.580425 -290.858516) (xy 301.554122 -290.81692)
			(xy 301.534831 -290.771644) (xy 301.523054 -290.72386) (xy 301.519094 -290.674806) (xy 301.179992 -290.674806)
			(xy 301.179497 -290.699413) (xy 301.171602 -290.74799) (xy 301.156018 -290.794671) (xy 301.133147 -290.838248)
			(xy 301.103582 -290.877592) (xy 301.068089 -290.911684) (xy 301.027586 -290.93964) (xy 300.983124 -290.960738)
			(xy 300.935853 -290.97443) (xy 300.886998 -290.980362) (xy 300.837823 -290.978381) (xy 300.789604 -290.968537)
			(xy 300.743588 -290.951085) (xy 300.700967 -290.926478) (xy 300.662846 -290.895353) (xy 300.630211 -290.858516)
			(xy 300.603908 -290.81692) (xy 300.584617 -290.771644) (xy 300.57284 -290.72386) (xy 300.56888 -290.674806)
			(xy 300.230032 -290.674806) (xy 300.229537 -290.699413) (xy 300.221642 -290.74799) (xy 300.206058 -290.794671)
			(xy 300.183187 -290.838248) (xy 300.153622 -290.877592) (xy 300.118129 -290.911684) (xy 300.077626 -290.93964)
			(xy 300.033164 -290.960738) (xy 299.985893 -290.97443) (xy 299.937038 -290.980362) (xy 299.887863 -290.978381)
			(xy 299.839644 -290.968537) (xy 299.793628 -290.951085) (xy 299.751007 -290.926478) (xy 299.712886 -290.895353)
			(xy 299.680251 -290.858516) (xy 299.653948 -290.81692) (xy 299.634657 -290.771644) (xy 299.62288 -290.72386)
			(xy 299.61892 -290.674806) (xy 299.280072 -290.674806) (xy 299.279577 -290.699413) (xy 299.271682 -290.74799)
			(xy 299.256098 -290.794671) (xy 299.233227 -290.838248) (xy 299.203662 -290.877592) (xy 299.168169 -290.911684)
			(xy 299.127666 -290.93964) (xy 299.083204 -290.960738) (xy 299.035933 -290.97443) (xy 298.987078 -290.980362)
			(xy 298.937903 -290.978381) (xy 298.889684 -290.968537) (xy 298.843668 -290.951085) (xy 298.801047 -290.926478)
			(xy 298.762926 -290.895353) (xy 298.730291 -290.858516) (xy 298.703988 -290.81692) (xy 298.684697 -290.771644)
			(xy 298.67292 -290.72386) (xy 298.66896 -290.674806) (xy 298.330112 -290.674806) (xy 298.329617 -290.699413)
			(xy 298.321722 -290.74799) (xy 298.306138 -290.794671) (xy 298.283267 -290.838248) (xy 298.253702 -290.877592)
			(xy 298.218209 -290.911684) (xy 298.177706 -290.93964) (xy 298.133244 -290.960738) (xy 298.085973 -290.97443)
			(xy 298.037118 -290.980362) (xy 297.987943 -290.978381) (xy 297.939724 -290.968537) (xy 297.893708 -290.951085)
			(xy 297.851087 -290.926478) (xy 297.812966 -290.895353) (xy 297.780331 -290.858516) (xy 297.754028 -290.81692)
			(xy 297.734737 -290.771644) (xy 297.72296 -290.72386) (xy 297.719 -290.674806) (xy 297.380152 -290.674806)
			(xy 297.379657 -290.699413) (xy 297.371762 -290.74799) (xy 297.356178 -290.794671) (xy 297.333307 -290.838248)
			(xy 297.303742 -290.877592) (xy 297.268249 -290.911684) (xy 297.227746 -290.93964) (xy 297.183284 -290.960738)
			(xy 297.136013 -290.97443) (xy 297.087158 -290.980362) (xy 297.037983 -290.978381) (xy 296.989764 -290.968537)
			(xy 296.943748 -290.951085) (xy 296.901127 -290.926478) (xy 296.863006 -290.895353) (xy 296.830371 -290.858516)
			(xy 296.804068 -290.81692) (xy 296.784777 -290.771644) (xy 296.773 -290.72386) (xy 296.76904 -290.674806)
			(xy 296.430192 -290.674806) (xy 296.429697 -290.699413) (xy 296.421802 -290.74799) (xy 296.406218 -290.794671)
			(xy 296.383347 -290.838248) (xy 296.353782 -290.877592) (xy 296.318289 -290.911684) (xy 296.277786 -290.93964)
			(xy 296.233324 -290.960738) (xy 296.186053 -290.97443) (xy 296.137198 -290.980362) (xy 296.088023 -290.978381)
			(xy 296.039804 -290.968537) (xy 295.993788 -290.951085) (xy 295.951167 -290.926478) (xy 295.913046 -290.895353)
			(xy 295.880411 -290.858516) (xy 295.854108 -290.81692) (xy 295.834817 -290.771644) (xy 295.82304 -290.72386)
			(xy 295.81908 -290.674806) (xy 295.480232 -290.674806) (xy 295.479737 -290.699413) (xy 295.471842 -290.74799)
			(xy 295.456258 -290.794671) (xy 295.433387 -290.838248) (xy 295.403822 -290.877592) (xy 295.368329 -290.911684)
			(xy 295.327826 -290.93964) (xy 295.283364 -290.960738) (xy 295.236093 -290.97443) (xy 295.187238 -290.980362)
			(xy 295.138063 -290.978381) (xy 295.089844 -290.968537) (xy 295.043828 -290.951085) (xy 295.001207 -290.926478)
			(xy 294.963086 -290.895353) (xy 294.930451 -290.858516) (xy 294.904148 -290.81692) (xy 294.884857 -290.771644)
			(xy 294.87308 -290.72386) (xy 294.86912 -290.674806) (xy 294.530018 -290.674806) (xy 294.529523 -290.699413)
			(xy 294.521628 -290.74799) (xy 294.506044 -290.794671) (xy 294.483173 -290.838248) (xy 294.453608 -290.877592)
			(xy 294.418115 -290.911684) (xy 294.377612 -290.93964) (xy 294.33315 -290.960738) (xy 294.285879 -290.97443)
			(xy 294.237024 -290.980362) (xy 294.187849 -290.978381) (xy 294.13963 -290.968537) (xy 294.093614 -290.951085)
			(xy 294.050993 -290.926478) (xy 294.012872 -290.895353) (xy 293.980237 -290.858516) (xy 293.953934 -290.81692)
			(xy 293.934643 -290.771644) (xy 293.922866 -290.72386) (xy 293.918906 -290.674806) (xy 293.580058 -290.674806)
			(xy 293.579563 -290.699413) (xy 293.571668 -290.74799) (xy 293.556084 -290.794671) (xy 293.533213 -290.838248)
			(xy 293.503648 -290.877592) (xy 293.468155 -290.911684) (xy 293.427652 -290.93964) (xy 293.38319 -290.960738)
			(xy 293.335919 -290.97443) (xy 293.287064 -290.980362) (xy 293.237889 -290.978381) (xy 293.18967 -290.968537)
			(xy 293.143654 -290.951085) (xy 293.101033 -290.926478) (xy 293.062912 -290.895353) (xy 293.030277 -290.858516)
			(xy 293.003974 -290.81692) (xy 292.984683 -290.771644) (xy 292.972906 -290.72386) (xy 292.968946 -290.674806)
			(xy 292.630098 -290.674806) (xy 292.629603 -290.699413) (xy 292.621708 -290.74799) (xy 292.606124 -290.794671)
			(xy 292.583253 -290.838248) (xy 292.553688 -290.877592) (xy 292.518195 -290.911684) (xy 292.477692 -290.93964)
			(xy 292.43323 -290.960738) (xy 292.385959 -290.97443) (xy 292.337104 -290.980362) (xy 292.287929 -290.978381)
			(xy 292.23971 -290.968537) (xy 292.193694 -290.951085) (xy 292.151073 -290.926478) (xy 292.112952 -290.895353)
			(xy 292.080317 -290.858516) (xy 292.054014 -290.81692) (xy 292.034723 -290.771644) (xy 292.022946 -290.72386)
			(xy 292.018986 -290.674806) (xy 290.730178 -290.674806) (xy 290.729683 -290.699413) (xy 290.721788 -290.74799)
			(xy 290.706204 -290.794671) (xy 290.683333 -290.838248) (xy 290.653768 -290.877592) (xy 290.618275 -290.911684)
			(xy 290.577772 -290.93964) (xy 290.53331 -290.960738) (xy 290.486039 -290.97443) (xy 290.437184 -290.980362)
			(xy 290.388009 -290.978381) (xy 290.33979 -290.968537) (xy 290.293774 -290.951085) (xy 290.251153 -290.926478)
			(xy 290.213032 -290.895353) (xy 290.180397 -290.858516) (xy 290.154094 -290.81692) (xy 290.134803 -290.771644)
			(xy 290.123026 -290.72386) (xy 290.119066 -290.674806) (xy 289.780218 -290.674806) (xy 289.779723 -290.699413)
			(xy 289.771828 -290.74799) (xy 289.756244 -290.794671) (xy 289.733373 -290.838248) (xy 289.703808 -290.877592)
			(xy 289.668315 -290.911684) (xy 289.627812 -290.93964) (xy 289.58335 -290.960738) (xy 289.536079 -290.97443)
			(xy 289.487224 -290.980362) (xy 289.438049 -290.978381) (xy 289.38983 -290.968537) (xy 289.343814 -290.951085)
			(xy 289.301193 -290.926478) (xy 289.263072 -290.895353) (xy 289.230437 -290.858516) (xy 289.204134 -290.81692)
			(xy 289.184843 -290.771644) (xy 289.173066 -290.72386) (xy 289.169106 -290.674806) (xy 288.830004 -290.674806)
			(xy 288.829509 -290.699413) (xy 288.821614 -290.74799) (xy 288.80603 -290.794671) (xy 288.783159 -290.838248)
			(xy 288.753594 -290.877592) (xy 288.718101 -290.911684) (xy 288.677598 -290.93964) (xy 288.633136 -290.960738)
			(xy 288.585865 -290.97443) (xy 288.53701 -290.980362) (xy 288.487835 -290.978381) (xy 288.439616 -290.968537)
			(xy 288.3936 -290.951085) (xy 288.350979 -290.926478) (xy 288.312858 -290.895353) (xy 288.280223 -290.858516)
			(xy 288.25392 -290.81692) (xy 288.234629 -290.771644) (xy 288.222852 -290.72386) (xy 288.218892 -290.674806)
			(xy 287.880044 -290.674806) (xy 287.879549 -290.699413) (xy 287.871654 -290.74799) (xy 287.85607 -290.794671)
			(xy 287.833199 -290.838248) (xy 287.803634 -290.877592) (xy 287.768141 -290.911684) (xy 287.727638 -290.93964)
			(xy 287.683176 -290.960738) (xy 287.635905 -290.97443) (xy 287.58705 -290.980362) (xy 287.537875 -290.978381)
			(xy 287.489656 -290.968537) (xy 287.44364 -290.951085) (xy 287.401019 -290.926478) (xy 287.362898 -290.895353)
			(xy 287.330263 -290.858516) (xy 287.30396 -290.81692) (xy 287.284669 -290.771644) (xy 287.272892 -290.72386)
			(xy 287.268932 -290.674806) (xy 286.930084 -290.674806) (xy 286.929589 -290.699413) (xy 286.921694 -290.74799)
			(xy 286.90611 -290.794671) (xy 286.883239 -290.838248) (xy 286.853674 -290.877592) (xy 286.818181 -290.911684)
			(xy 286.777678 -290.93964) (xy 286.733216 -290.960738) (xy 286.685945 -290.97443) (xy 286.63709 -290.980362)
			(xy 286.587915 -290.978381) (xy 286.539696 -290.968537) (xy 286.49368 -290.951085) (xy 286.451059 -290.926478)
			(xy 286.412938 -290.895353) (xy 286.380303 -290.858516) (xy 286.354 -290.81692) (xy 286.334709 -290.771644)
			(xy 286.322932 -290.72386) (xy 286.318972 -290.674806) (xy 285.980124 -290.674806) (xy 285.979629 -290.699413)
			(xy 285.971734 -290.74799) (xy 285.95615 -290.794671) (xy 285.933279 -290.838248) (xy 285.903714 -290.877592)
			(xy 285.868221 -290.911684) (xy 285.827718 -290.93964) (xy 285.783256 -290.960738) (xy 285.735985 -290.97443)
			(xy 285.68713 -290.980362) (xy 285.637955 -290.978381) (xy 285.589736 -290.968537) (xy 285.54372 -290.951085)
			(xy 285.501099 -290.926478) (xy 285.462978 -290.895353) (xy 285.430343 -290.858516) (xy 285.40404 -290.81692)
			(xy 285.384749 -290.771644) (xy 285.372972 -290.72386) (xy 285.369012 -290.674806) (xy 285.030164 -290.674806)
			(xy 285.029669 -290.699413) (xy 285.021774 -290.74799) (xy 285.00619 -290.794671) (xy 284.983319 -290.838248)
			(xy 284.953754 -290.877592) (xy 284.918261 -290.911684) (xy 284.877758 -290.93964) (xy 284.833296 -290.960738)
			(xy 284.786025 -290.97443) (xy 284.73717 -290.980362) (xy 284.687995 -290.978381) (xy 284.639776 -290.968537)
			(xy 284.59376 -290.951085) (xy 284.551139 -290.926478) (xy 284.513018 -290.895353) (xy 284.480383 -290.858516)
			(xy 284.45408 -290.81692) (xy 284.434789 -290.771644) (xy 284.423012 -290.72386) (xy 284.419052 -290.674806)
			(xy 284.080204 -290.674806) (xy 284.079709 -290.699413) (xy 284.071814 -290.74799) (xy 284.05623 -290.794671)
			(xy 284.033359 -290.838248) (xy 284.003794 -290.877592) (xy 283.968301 -290.911684) (xy 283.927798 -290.93964)
			(xy 283.883336 -290.960738) (xy 283.836065 -290.97443) (xy 283.78721 -290.980362) (xy 283.738035 -290.978381)
			(xy 283.689816 -290.968537) (xy 283.6438 -290.951085) (xy 283.601179 -290.926478) (xy 283.563058 -290.895353)
			(xy 283.530423 -290.858516) (xy 283.50412 -290.81692) (xy 283.484829 -290.771644) (xy 283.473052 -290.72386)
			(xy 283.469092 -290.674806) (xy 283.130244 -290.674806) (xy 283.129749 -290.699413) (xy 283.121854 -290.74799)
			(xy 283.10627 -290.794671) (xy 283.083399 -290.838248) (xy 283.053834 -290.877592) (xy 283.018341 -290.911684)
			(xy 282.977838 -290.93964) (xy 282.933376 -290.960738) (xy 282.886105 -290.97443) (xy 282.83725 -290.980362)
			(xy 282.788075 -290.978381) (xy 282.739856 -290.968537) (xy 282.69384 -290.951085) (xy 282.651219 -290.926478)
			(xy 282.613098 -290.895353) (xy 282.580463 -290.858516) (xy 282.55416 -290.81692) (xy 282.534869 -290.771644)
			(xy 282.523092 -290.72386) (xy 282.519132 -290.674806) (xy 282.180525 -290.674806) (xy 282.176354 -290.725135)
			(xy 282.163956 -290.774097) (xy 282.143668 -290.82035) (xy 282.116045 -290.862634) (xy 282.081838 -290.899795)
			(xy 282.041982 -290.930819) (xy 281.997563 -290.95486) (xy 281.949794 -290.971262) (xy 281.899976 -290.979579)
			(xy 281.874722 -290.980114) (xy 281.844648 -290.97942) (xy 281.785663 -290.967652) (xy 281.757628 -290.956746)
			(xy 281.745436 -290.951666) (xy 281.720544 -290.954206) (xy 281.639518 -291.008308) (xy 281.629463 -291.015828)
			(xy 281.617619 -291.037935) (xy 281.616912 -291.050472) (xy 281.616912 -291.2364) (xy 318.184782 -291.2364)
			(xy 318.188853 -291.180778) (xy 318.200979 -291.126341) (xy 318.220902 -291.07425) (xy 318.248198 -291.025615)
			(xy 318.282284 -290.981472) (xy 318.322433 -290.942763) (xy 318.367791 -290.910312) (xy 318.417391 -290.884811)
			(xy 318.470175 -290.866804) (xy 318.525018 -290.856674) (xy 318.580752 -290.854637) (xy 318.636189 -290.860737)
			(xy 318.690146 -290.874843) (xy 318.741475 -290.896655) (xy 318.789081 -290.925709) (xy 318.831949 -290.961384)
			(xy 318.869166 -291.002921) (xy 318.899939 -291.049434) (xy 318.923611 -291.099931) (xy 318.939679 -291.153338)
			(xy 318.947799 -291.208514) (xy 318.948308 -291.2364) (xy 318.947799 -291.264286) (xy 318.939679 -291.319462)
			(xy 318.923611 -291.372869) (xy 318.899939 -291.423366) (xy 318.869166 -291.469879) (xy 318.831949 -291.511416)
			(xy 318.789081 -291.547091) (xy 318.741475 -291.576145) (xy 318.704164 -291.592) (xy 320.641724 -291.592)
			(xy 320.645795 -291.536378) (xy 320.657921 -291.481941) (xy 320.677844 -291.42985) (xy 320.70514 -291.381215)
			(xy 320.739226 -291.337072) (xy 320.779375 -291.298363) (xy 320.824733 -291.265912) (xy 320.874333 -291.240411)
			(xy 320.927117 -291.222404) (xy 320.98196 -291.212274) (xy 321.037694 -291.210237) (xy 321.093131 -291.216337)
			(xy 321.147088 -291.230443) (xy 321.198417 -291.252255) (xy 321.246023 -291.281309) (xy 321.288891 -291.316984)
			(xy 321.326108 -291.358521) (xy 321.356881 -291.405034) (xy 321.380553 -291.455531) (xy 321.396621 -291.508938)
			(xy 321.404741 -291.564114) (xy 321.40525 -291.592) (xy 321.404741 -291.619886) (xy 321.396621 -291.675062)
			(xy 321.380553 -291.728469) (xy 321.356881 -291.778966) (xy 321.326108 -291.825479) (xy 321.288891 -291.867016)
			(xy 321.246023 -291.902691) (xy 321.198417 -291.931745) (xy 321.147088 -291.953557) (xy 321.093131 -291.967663)
			(xy 321.037694 -291.973763) (xy 320.98196 -291.971726) (xy 320.927117 -291.961596) (xy 320.874333 -291.943589)
			(xy 320.824733 -291.918088) (xy 320.779375 -291.885637) (xy 320.739226 -291.846928) (xy 320.70514 -291.802785)
			(xy 320.677844 -291.75415) (xy 320.657921 -291.702059) (xy 320.645795 -291.647622) (xy 320.641724 -291.592)
			(xy 318.704164 -291.592) (xy 318.690146 -291.597957) (xy 318.636189 -291.612063) (xy 318.580752 -291.618163)
			(xy 318.525018 -291.616126) (xy 318.470175 -291.605996) (xy 318.417391 -291.587989) (xy 318.367791 -291.562488)
			(xy 318.322433 -291.530037) (xy 318.282284 -291.491328) (xy 318.248198 -291.447185) (xy 318.220902 -291.39855)
			(xy 318.200979 -291.346459) (xy 318.188853 -291.292022) (xy 318.184782 -291.2364) (xy 281.616912 -291.2364)
			(xy 281.616912 -291.624766) (xy 282.519132 -291.624766) (xy 282.523092 -291.575712) (xy 282.534869 -291.527928)
			(xy 282.55416 -291.482652) (xy 282.580463 -291.441056) (xy 282.613098 -291.404219) (xy 282.651219 -291.373094)
			(xy 282.69384 -291.348487) (xy 282.739856 -291.331035) (xy 282.788075 -291.321191) (xy 282.83725 -291.31921)
			(xy 282.886105 -291.325142) (xy 282.933376 -291.338834) (xy 282.977838 -291.359932) (xy 283.018341 -291.387888)
			(xy 283.053834 -291.42198) (xy 283.083399 -291.461324) (xy 283.10627 -291.504901) (xy 283.121854 -291.551582)
			(xy 283.129749 -291.600159) (xy 283.130244 -291.624766) (xy 283.469092 -291.624766) (xy 283.473052 -291.575712)
			(xy 283.484829 -291.527928) (xy 283.50412 -291.482652) (xy 283.530423 -291.441056) (xy 283.563058 -291.404219)
			(xy 283.601179 -291.373094) (xy 283.6438 -291.348487) (xy 283.689816 -291.331035) (xy 283.738035 -291.321191)
			(xy 283.78721 -291.31921) (xy 283.836065 -291.325142) (xy 283.883336 -291.338834) (xy 283.927798 -291.359932)
			(xy 283.968301 -291.387888) (xy 284.003794 -291.42198) (xy 284.033359 -291.461324) (xy 284.05623 -291.504901)
			(xy 284.071814 -291.551582) (xy 284.079709 -291.600159) (xy 284.080204 -291.624766) (xy 284.419052 -291.624766)
			(xy 284.423012 -291.575712) (xy 284.434789 -291.527928) (xy 284.45408 -291.482652) (xy 284.480383 -291.441056)
			(xy 284.513018 -291.404219) (xy 284.551139 -291.373094) (xy 284.59376 -291.348487) (xy 284.639776 -291.331035)
			(xy 284.687995 -291.321191) (xy 284.73717 -291.31921) (xy 284.786025 -291.325142) (xy 284.833296 -291.338834)
			(xy 284.877758 -291.359932) (xy 284.918261 -291.387888) (xy 284.953754 -291.42198) (xy 284.983319 -291.461324)
			(xy 285.00619 -291.504901) (xy 285.021774 -291.551582) (xy 285.029669 -291.600159) (xy 285.030164 -291.624766)
			(xy 285.369012 -291.624766) (xy 285.372972 -291.575712) (xy 285.384749 -291.527928) (xy 285.40404 -291.482652)
			(xy 285.430343 -291.441056) (xy 285.462978 -291.404219) (xy 285.501099 -291.373094) (xy 285.54372 -291.348487)
			(xy 285.589736 -291.331035) (xy 285.637955 -291.321191) (xy 285.68713 -291.31921) (xy 285.735985 -291.325142)
			(xy 285.783256 -291.338834) (xy 285.827718 -291.359932) (xy 285.868221 -291.387888) (xy 285.903714 -291.42198)
			(xy 285.933279 -291.461324) (xy 285.95615 -291.504901) (xy 285.971734 -291.551582) (xy 285.979629 -291.600159)
			(xy 285.980124 -291.624766) (xy 286.318972 -291.624766) (xy 286.322932 -291.575712) (xy 286.334709 -291.527928)
			(xy 286.354 -291.482652) (xy 286.380303 -291.441056) (xy 286.412938 -291.404219) (xy 286.451059 -291.373094)
			(xy 286.49368 -291.348487) (xy 286.539696 -291.331035) (xy 286.587915 -291.321191) (xy 286.63709 -291.31921)
			(xy 286.685945 -291.325142) (xy 286.733216 -291.338834) (xy 286.777678 -291.359932) (xy 286.818181 -291.387888)
			(xy 286.853674 -291.42198) (xy 286.883239 -291.461324) (xy 286.90611 -291.504901) (xy 286.921694 -291.551582)
			(xy 286.929589 -291.600159) (xy 286.930084 -291.624766) (xy 287.268932 -291.624766) (xy 287.272892 -291.575712)
			(xy 287.284669 -291.527928) (xy 287.30396 -291.482652) (xy 287.330263 -291.441056) (xy 287.362898 -291.404219)
			(xy 287.401019 -291.373094) (xy 287.44364 -291.348487) (xy 287.489656 -291.331035) (xy 287.537875 -291.321191)
			(xy 287.58705 -291.31921) (xy 287.635905 -291.325142) (xy 287.683176 -291.338834) (xy 287.727638 -291.359932)
			(xy 287.768141 -291.387888) (xy 287.803634 -291.42198) (xy 287.833199 -291.461324) (xy 287.85607 -291.504901)
			(xy 287.871654 -291.551582) (xy 287.879549 -291.600159) (xy 287.880044 -291.624766) (xy 288.218892 -291.624766)
			(xy 288.222852 -291.575712) (xy 288.234629 -291.527928) (xy 288.25392 -291.482652) (xy 288.280223 -291.441056)
			(xy 288.312858 -291.404219) (xy 288.350979 -291.373094) (xy 288.3936 -291.348487) (xy 288.439616 -291.331035)
			(xy 288.487835 -291.321191) (xy 288.53701 -291.31921) (xy 288.585865 -291.325142) (xy 288.633136 -291.338834)
			(xy 288.677598 -291.359932) (xy 288.718101 -291.387888) (xy 288.753594 -291.42198) (xy 288.783159 -291.461324)
			(xy 288.80603 -291.504901) (xy 288.821614 -291.551582) (xy 288.829509 -291.600159) (xy 288.830004 -291.624766)
			(xy 289.169106 -291.624766) (xy 289.173066 -291.575712) (xy 289.184843 -291.527928) (xy 289.204134 -291.482652)
			(xy 289.230437 -291.441056) (xy 289.263072 -291.404219) (xy 289.301193 -291.373094) (xy 289.343814 -291.348487)
			(xy 289.38983 -291.331035) (xy 289.438049 -291.321191) (xy 289.487224 -291.31921) (xy 289.536079 -291.325142)
			(xy 289.58335 -291.338834) (xy 289.627812 -291.359932) (xy 289.668315 -291.387888) (xy 289.703808 -291.42198)
			(xy 289.733373 -291.461324) (xy 289.756244 -291.504901) (xy 289.771828 -291.551582) (xy 289.779723 -291.600159)
			(xy 289.780218 -291.624766) (xy 290.119066 -291.624766) (xy 290.123026 -291.575712) (xy 290.134803 -291.527928)
			(xy 290.154094 -291.482652) (xy 290.180397 -291.441056) (xy 290.213032 -291.404219) (xy 290.251153 -291.373094)
			(xy 290.293774 -291.348487) (xy 290.33979 -291.331035) (xy 290.388009 -291.321191) (xy 290.437184 -291.31921)
			(xy 290.486039 -291.325142) (xy 290.53331 -291.338834) (xy 290.577772 -291.359932) (xy 290.618275 -291.387888)
			(xy 290.653768 -291.42198) (xy 290.683333 -291.461324) (xy 290.706204 -291.504901) (xy 290.721788 -291.551582)
			(xy 290.729683 -291.600159) (xy 290.730178 -291.624766) (xy 292.018986 -291.624766) (xy 292.022946 -291.575712)
			(xy 292.034723 -291.527928) (xy 292.054014 -291.482652) (xy 292.080317 -291.441056) (xy 292.112952 -291.404219)
			(xy 292.151073 -291.373094) (xy 292.193694 -291.348487) (xy 292.23971 -291.331035) (xy 292.287929 -291.321191)
			(xy 292.337104 -291.31921) (xy 292.385959 -291.325142) (xy 292.43323 -291.338834) (xy 292.477692 -291.359932)
			(xy 292.518195 -291.387888) (xy 292.553688 -291.42198) (xy 292.583253 -291.461324) (xy 292.606124 -291.504901)
			(xy 292.621708 -291.551582) (xy 292.629603 -291.600159) (xy 292.630098 -291.624766) (xy 292.968946 -291.624766)
			(xy 292.972906 -291.575712) (xy 292.984683 -291.527928) (xy 293.003974 -291.482652) (xy 293.030277 -291.441056)
			(xy 293.062912 -291.404219) (xy 293.101033 -291.373094) (xy 293.143654 -291.348487) (xy 293.18967 -291.331035)
			(xy 293.237889 -291.321191) (xy 293.287064 -291.31921) (xy 293.335919 -291.325142) (xy 293.38319 -291.338834)
			(xy 293.427652 -291.359932) (xy 293.468155 -291.387888) (xy 293.503648 -291.42198) (xy 293.533213 -291.461324)
			(xy 293.556084 -291.504901) (xy 293.571668 -291.551582) (xy 293.579563 -291.600159) (xy 293.580058 -291.624766)
			(xy 293.918906 -291.624766) (xy 293.922866 -291.575712) (xy 293.934643 -291.527928) (xy 293.953934 -291.482652)
			(xy 293.980237 -291.441056) (xy 294.012872 -291.404219) (xy 294.050993 -291.373094) (xy 294.093614 -291.348487)
			(xy 294.13963 -291.331035) (xy 294.187849 -291.321191) (xy 294.237024 -291.31921) (xy 294.285879 -291.325142)
			(xy 294.33315 -291.338834) (xy 294.377612 -291.359932) (xy 294.418115 -291.387888) (xy 294.453608 -291.42198)
			(xy 294.483173 -291.461324) (xy 294.506044 -291.504901) (xy 294.521628 -291.551582) (xy 294.529523 -291.600159)
			(xy 294.530018 -291.624766) (xy 294.86912 -291.624766) (xy 294.87308 -291.575712) (xy 294.884857 -291.527928)
			(xy 294.904148 -291.482652) (xy 294.930451 -291.441056) (xy 294.963086 -291.404219) (xy 295.001207 -291.373094)
			(xy 295.043828 -291.348487) (xy 295.089844 -291.331035) (xy 295.138063 -291.321191) (xy 295.187238 -291.31921)
			(xy 295.236093 -291.325142) (xy 295.283364 -291.338834) (xy 295.327826 -291.359932) (xy 295.368329 -291.387888)
			(xy 295.403822 -291.42198) (xy 295.433387 -291.461324) (xy 295.456258 -291.504901) (xy 295.471842 -291.551582)
			(xy 295.479737 -291.600159) (xy 295.480232 -291.624766) (xy 295.81908 -291.624766) (xy 295.82304 -291.575712)
			(xy 295.834817 -291.527928) (xy 295.854108 -291.482652) (xy 295.880411 -291.441056) (xy 295.913046 -291.404219)
			(xy 295.951167 -291.373094) (xy 295.993788 -291.348487) (xy 296.039804 -291.331035) (xy 296.088023 -291.321191)
			(xy 296.137198 -291.31921) (xy 296.186053 -291.325142) (xy 296.233324 -291.338834) (xy 296.277786 -291.359932)
			(xy 296.318289 -291.387888) (xy 296.353782 -291.42198) (xy 296.383347 -291.461324) (xy 296.406218 -291.504901)
			(xy 296.421802 -291.551582) (xy 296.429697 -291.600159) (xy 296.430192 -291.624766) (xy 296.76904 -291.624766)
			(xy 296.773 -291.575712) (xy 296.784777 -291.527928) (xy 296.804068 -291.482652) (xy 296.830371 -291.441056)
			(xy 296.863006 -291.404219) (xy 296.901127 -291.373094) (xy 296.943748 -291.348487) (xy 296.989764 -291.331035)
			(xy 297.037983 -291.321191) (xy 297.087158 -291.31921) (xy 297.136013 -291.325142) (xy 297.183284 -291.338834)
			(xy 297.227746 -291.359932) (xy 297.268249 -291.387888) (xy 297.303742 -291.42198) (xy 297.333307 -291.461324)
			(xy 297.356178 -291.504901) (xy 297.371762 -291.551582) (xy 297.379657 -291.600159) (xy 297.380152 -291.624766)
			(xy 297.719 -291.624766) (xy 297.72296 -291.575712) (xy 297.734737 -291.527928) (xy 297.754028 -291.482652)
			(xy 297.780331 -291.441056) (xy 297.812966 -291.404219) (xy 297.851087 -291.373094) (xy 297.893708 -291.348487)
			(xy 297.939724 -291.331035) (xy 297.987943 -291.321191) (xy 298.037118 -291.31921) (xy 298.085973 -291.325142)
			(xy 298.133244 -291.338834) (xy 298.177706 -291.359932) (xy 298.218209 -291.387888) (xy 298.253702 -291.42198)
			(xy 298.283267 -291.461324) (xy 298.306138 -291.504901) (xy 298.321722 -291.551582) (xy 298.329617 -291.600159)
			(xy 298.330112 -291.624766) (xy 298.66896 -291.624766) (xy 298.67292 -291.575712) (xy 298.684697 -291.527928)
			(xy 298.703988 -291.482652) (xy 298.730291 -291.441056) (xy 298.762926 -291.404219) (xy 298.801047 -291.373094)
			(xy 298.843668 -291.348487) (xy 298.889684 -291.331035) (xy 298.937903 -291.321191) (xy 298.987078 -291.31921)
			(xy 299.035933 -291.325142) (xy 299.083204 -291.338834) (xy 299.127666 -291.359932) (xy 299.168169 -291.387888)
			(xy 299.203662 -291.42198) (xy 299.233227 -291.461324) (xy 299.256098 -291.504901) (xy 299.271682 -291.551582)
			(xy 299.279577 -291.600159) (xy 299.280072 -291.624766) (xy 299.61892 -291.624766) (xy 299.62288 -291.575712)
			(xy 299.634657 -291.527928) (xy 299.653948 -291.482652) (xy 299.680251 -291.441056) (xy 299.712886 -291.404219)
			(xy 299.751007 -291.373094) (xy 299.793628 -291.348487) (xy 299.839644 -291.331035) (xy 299.887863 -291.321191)
			(xy 299.937038 -291.31921) (xy 299.985893 -291.325142) (xy 300.033164 -291.338834) (xy 300.077626 -291.359932)
			(xy 300.118129 -291.387888) (xy 300.153622 -291.42198) (xy 300.183187 -291.461324) (xy 300.206058 -291.504901)
			(xy 300.221642 -291.551582) (xy 300.229537 -291.600159) (xy 300.230032 -291.624766) (xy 300.56888 -291.624766)
			(xy 300.57284 -291.575712) (xy 300.584617 -291.527928) (xy 300.603908 -291.482652) (xy 300.630211 -291.441056)
			(xy 300.662846 -291.404219) (xy 300.700967 -291.373094) (xy 300.743588 -291.348487) (xy 300.789604 -291.331035)
			(xy 300.837823 -291.321191) (xy 300.886998 -291.31921) (xy 300.935853 -291.325142) (xy 300.983124 -291.338834)
			(xy 301.027586 -291.359932) (xy 301.068089 -291.387888) (xy 301.103582 -291.42198) (xy 301.133147 -291.461324)
			(xy 301.156018 -291.504901) (xy 301.171602 -291.551582) (xy 301.179497 -291.600159) (xy 301.179992 -291.624766)
			(xy 301.519094 -291.624766) (xy 301.523054 -291.575712) (xy 301.534831 -291.527928) (xy 301.554122 -291.482652)
			(xy 301.580425 -291.441056) (xy 301.61306 -291.404219) (xy 301.651181 -291.373094) (xy 301.693802 -291.348487)
			(xy 301.739818 -291.331035) (xy 301.788037 -291.321191) (xy 301.837212 -291.31921) (xy 301.886067 -291.325142)
			(xy 301.933338 -291.338834) (xy 301.9778 -291.359932) (xy 302.018303 -291.387888) (xy 302.053796 -291.42198)
			(xy 302.083361 -291.461324) (xy 302.106232 -291.504901) (xy 302.121816 -291.551582) (xy 302.129711 -291.600159)
			(xy 302.130206 -291.624766) (xy 302.469054 -291.624766) (xy 302.473014 -291.575712) (xy 302.484791 -291.527928)
			(xy 302.504082 -291.482652) (xy 302.530385 -291.441056) (xy 302.56302 -291.404219) (xy 302.601141 -291.373094)
			(xy 302.643762 -291.348487) (xy 302.689778 -291.331035) (xy 302.737997 -291.321191) (xy 302.787172 -291.31921)
			(xy 302.836027 -291.325142) (xy 302.883298 -291.338834) (xy 302.92776 -291.359932) (xy 302.968263 -291.387888)
			(xy 303.003756 -291.42198) (xy 303.033321 -291.461324) (xy 303.056192 -291.504901) (xy 303.071776 -291.551582)
			(xy 303.079671 -291.600159) (xy 303.080166 -291.624766) (xy 303.419014 -291.624766) (xy 303.422974 -291.575712)
			(xy 303.434751 -291.527928) (xy 303.454042 -291.482652) (xy 303.480345 -291.441056) (xy 303.51298 -291.404219)
			(xy 303.551101 -291.373094) (xy 303.593722 -291.348487) (xy 303.639738 -291.331035) (xy 303.687957 -291.321191)
			(xy 303.737132 -291.31921) (xy 303.785987 -291.325142) (xy 303.833258 -291.338834) (xy 303.87772 -291.359932)
			(xy 303.918223 -291.387888) (xy 303.953716 -291.42198) (xy 303.983281 -291.461324) (xy 304.006152 -291.504901)
			(xy 304.021736 -291.551582) (xy 304.029631 -291.600159) (xy 304.030126 -291.624766) (xy 304.368974 -291.624766)
			(xy 304.372934 -291.575712) (xy 304.384711 -291.527928) (xy 304.404002 -291.482652) (xy 304.430305 -291.441056)
			(xy 304.46294 -291.404219) (xy 304.501061 -291.373094) (xy 304.543682 -291.348487) (xy 304.589698 -291.331035)
			(xy 304.637917 -291.321191) (xy 304.687092 -291.31921) (xy 304.735947 -291.325142) (xy 304.783218 -291.338834)
			(xy 304.82768 -291.359932) (xy 304.868183 -291.387888) (xy 304.903676 -291.42198) (xy 304.933241 -291.461324)
			(xy 304.956112 -291.504901) (xy 304.971696 -291.551582) (xy 304.979591 -291.600159) (xy 304.980086 -291.624766)
			(xy 305.318934 -291.624766) (xy 305.322894 -291.575712) (xy 305.334671 -291.527928) (xy 305.353962 -291.482652)
			(xy 305.380265 -291.441056) (xy 305.4129 -291.404219) (xy 305.451021 -291.373094) (xy 305.493642 -291.348487)
			(xy 305.539658 -291.331035) (xy 305.587877 -291.321191) (xy 305.637052 -291.31921) (xy 305.685907 -291.325142)
			(xy 305.733178 -291.338834) (xy 305.77764 -291.359932) (xy 305.818143 -291.387888) (xy 305.853636 -291.42198)
			(xy 305.883201 -291.461324) (xy 305.906072 -291.504901) (xy 305.921656 -291.551582) (xy 305.929551 -291.600159)
			(xy 305.930046 -291.624766) (xy 306.269148 -291.624766) (xy 306.273108 -291.575712) (xy 306.284885 -291.527928)
			(xy 306.304176 -291.482652) (xy 306.330479 -291.441056) (xy 306.363114 -291.404219) (xy 306.401235 -291.373094)
			(xy 306.443856 -291.348487) (xy 306.489872 -291.331035) (xy 306.538091 -291.321191) (xy 306.587266 -291.31921)
			(xy 306.636121 -291.325142) (xy 306.683392 -291.338834) (xy 306.727854 -291.359932) (xy 306.768357 -291.387888)
			(xy 306.80385 -291.42198) (xy 306.833415 -291.461324) (xy 306.856286 -291.504901) (xy 306.87187 -291.551582)
			(xy 306.879765 -291.600159) (xy 306.88026 -291.624766) (xy 308.169068 -291.624766) (xy 308.173028 -291.575712)
			(xy 308.184805 -291.527928) (xy 308.204096 -291.482652) (xy 308.230399 -291.441056) (xy 308.263034 -291.404219)
			(xy 308.301155 -291.373094) (xy 308.343776 -291.348487) (xy 308.389792 -291.331035) (xy 308.438011 -291.321191)
			(xy 308.487186 -291.31921) (xy 308.536041 -291.325142) (xy 308.583312 -291.338834) (xy 308.627774 -291.359932)
			(xy 308.668277 -291.387888) (xy 308.70377 -291.42198) (xy 308.733335 -291.461324) (xy 308.756206 -291.504901)
			(xy 308.77179 -291.551582) (xy 308.779685 -291.600159) (xy 308.78018 -291.624766) (xy 309.119028 -291.624766)
			(xy 309.122988 -291.575712) (xy 309.134765 -291.527928) (xy 309.154056 -291.482652) (xy 309.180359 -291.441056)
			(xy 309.212994 -291.404219) (xy 309.251115 -291.373094) (xy 309.293736 -291.348487) (xy 309.339752 -291.331035)
			(xy 309.387971 -291.321191) (xy 309.437146 -291.31921) (xy 309.486001 -291.325142) (xy 309.533272 -291.338834)
			(xy 309.577734 -291.359932) (xy 309.618237 -291.387888) (xy 309.65373 -291.42198) (xy 309.683295 -291.461324)
			(xy 309.706166 -291.504901) (xy 309.72175 -291.551582) (xy 309.729645 -291.600159) (xy 309.73014 -291.624766)
			(xy 310.068988 -291.624766) (xy 310.072948 -291.575712) (xy 310.084725 -291.527928) (xy 310.104016 -291.482652)
			(xy 310.130319 -291.441056) (xy 310.162954 -291.404219) (xy 310.201075 -291.373094) (xy 310.243696 -291.348487)
			(xy 310.289712 -291.331035) (xy 310.337931 -291.321191) (xy 310.387106 -291.31921) (xy 310.435961 -291.325142)
			(xy 310.483232 -291.338834) (xy 310.527694 -291.359932) (xy 310.568197 -291.387888) (xy 310.60369 -291.42198)
			(xy 310.633255 -291.461324) (xy 310.656126 -291.504901) (xy 310.67171 -291.551582) (xy 310.679605 -291.600159)
			(xy 310.6801 -291.624766) (xy 311.018948 -291.624766) (xy 311.022908 -291.575712) (xy 311.034685 -291.527928)
			(xy 311.053976 -291.482652) (xy 311.080279 -291.441056) (xy 311.112914 -291.404219) (xy 311.151035 -291.373094)
			(xy 311.193656 -291.348487) (xy 311.239672 -291.331035) (xy 311.287891 -291.321191) (xy 311.337066 -291.31921)
			(xy 311.385921 -291.325142) (xy 311.433192 -291.338834) (xy 311.477654 -291.359932) (xy 311.518157 -291.387888)
			(xy 311.55365 -291.42198) (xy 311.583215 -291.461324) (xy 311.606086 -291.504901) (xy 311.62167 -291.551582)
			(xy 311.629565 -291.600159) (xy 311.63006 -291.624766) (xy 311.968908 -291.624766) (xy 311.972868 -291.575712)
			(xy 311.984645 -291.527928) (xy 312.003936 -291.482652) (xy 312.030239 -291.441056) (xy 312.062874 -291.404219)
			(xy 312.100995 -291.373094) (xy 312.143616 -291.348487) (xy 312.189632 -291.331035) (xy 312.237851 -291.321191)
			(xy 312.287026 -291.31921) (xy 312.335881 -291.325142) (xy 312.383152 -291.338834) (xy 312.427614 -291.359932)
			(xy 312.468117 -291.387888) (xy 312.50361 -291.42198) (xy 312.533175 -291.461324) (xy 312.556046 -291.504901)
			(xy 312.57163 -291.551582) (xy 312.579525 -291.600159) (xy 312.58002 -291.624766) (xy 312.919122 -291.624766)
			(xy 312.923082 -291.575712) (xy 312.934859 -291.527928) (xy 312.95415 -291.482652) (xy 312.980453 -291.441056)
			(xy 313.013088 -291.404219) (xy 313.051209 -291.373094) (xy 313.09383 -291.348487) (xy 313.139846 -291.331035)
			(xy 313.188065 -291.321191) (xy 313.23724 -291.31921) (xy 313.286095 -291.325142) (xy 313.333366 -291.338834)
			(xy 313.377828 -291.359932) (xy 313.418331 -291.387888) (xy 313.453824 -291.42198) (xy 313.483389 -291.461324)
			(xy 313.50626 -291.504901) (xy 313.521844 -291.551582) (xy 313.529739 -291.600159) (xy 313.530234 -291.624766)
			(xy 313.869082 -291.624766) (xy 313.873042 -291.575712) (xy 313.884819 -291.527928) (xy 313.90411 -291.482652)
			(xy 313.930413 -291.441056) (xy 313.963048 -291.404219) (xy 314.001169 -291.373094) (xy 314.04379 -291.348487)
			(xy 314.089806 -291.331035) (xy 314.138025 -291.321191) (xy 314.1872 -291.31921) (xy 314.236055 -291.325142)
			(xy 314.283326 -291.338834) (xy 314.327788 -291.359932) (xy 314.368291 -291.387888) (xy 314.403784 -291.42198)
			(xy 314.433349 -291.461324) (xy 314.45622 -291.504901) (xy 314.471804 -291.551582) (xy 314.479699 -291.600159)
			(xy 314.480194 -291.624766) (xy 314.819042 -291.624766) (xy 314.823002 -291.575712) (xy 314.834779 -291.527928)
			(xy 314.85407 -291.482652) (xy 314.880373 -291.441056) (xy 314.913008 -291.404219) (xy 314.951129 -291.373094)
			(xy 314.99375 -291.348487) (xy 315.039766 -291.331035) (xy 315.087985 -291.321191) (xy 315.13716 -291.31921)
			(xy 315.186015 -291.325142) (xy 315.233286 -291.338834) (xy 315.277748 -291.359932) (xy 315.318251 -291.387888)
			(xy 315.353744 -291.42198) (xy 315.383309 -291.461324) (xy 315.40618 -291.504901) (xy 315.421764 -291.551582)
			(xy 315.429659 -291.600159) (xy 315.430154 -291.624766) (xy 315.429659 -291.649373) (xy 315.421764 -291.69795)
			(xy 315.40618 -291.744631) (xy 315.383309 -291.788208) (xy 315.353744 -291.827552) (xy 315.318251 -291.861644)
			(xy 315.277748 -291.8896) (xy 315.233286 -291.910698) (xy 315.186015 -291.92439) (xy 315.13716 -291.930322)
			(xy 315.087985 -291.928341) (xy 315.039766 -291.918497) (xy 314.99375 -291.901045) (xy 314.951129 -291.876438)
			(xy 314.913008 -291.845313) (xy 314.880373 -291.808476) (xy 314.85407 -291.76688) (xy 314.834779 -291.721604)
			(xy 314.823002 -291.67382) (xy 314.819042 -291.624766) (xy 314.480194 -291.624766) (xy 314.479699 -291.649373)
			(xy 314.471804 -291.69795) (xy 314.45622 -291.744631) (xy 314.433349 -291.788208) (xy 314.403784 -291.827552)
			(xy 314.368291 -291.861644) (xy 314.327788 -291.8896) (xy 314.283326 -291.910698) (xy 314.236055 -291.92439)
			(xy 314.1872 -291.930322) (xy 314.138025 -291.928341) (xy 314.089806 -291.918497) (xy 314.04379 -291.901045)
			(xy 314.001169 -291.876438) (xy 313.963048 -291.845313) (xy 313.930413 -291.808476) (xy 313.90411 -291.76688)
			(xy 313.884819 -291.721604) (xy 313.873042 -291.67382) (xy 313.869082 -291.624766) (xy 313.530234 -291.624766)
			(xy 313.529739 -291.649373) (xy 313.521844 -291.69795) (xy 313.50626 -291.744631) (xy 313.483389 -291.788208)
			(xy 313.453824 -291.827552) (xy 313.418331 -291.861644) (xy 313.377828 -291.8896) (xy 313.333366 -291.910698)
			(xy 313.286095 -291.92439) (xy 313.23724 -291.930322) (xy 313.188065 -291.928341) (xy 313.139846 -291.918497)
			(xy 313.09383 -291.901045) (xy 313.051209 -291.876438) (xy 313.013088 -291.845313) (xy 312.980453 -291.808476)
			(xy 312.95415 -291.76688) (xy 312.934859 -291.721604) (xy 312.923082 -291.67382) (xy 312.919122 -291.624766)
			(xy 312.58002 -291.624766) (xy 312.579525 -291.649373) (xy 312.57163 -291.69795) (xy 312.556046 -291.744631)
			(xy 312.533175 -291.788208) (xy 312.50361 -291.827552) (xy 312.468117 -291.861644) (xy 312.427614 -291.8896)
			(xy 312.383152 -291.910698) (xy 312.335881 -291.92439) (xy 312.287026 -291.930322) (xy 312.237851 -291.928341)
			(xy 312.189632 -291.918497) (xy 312.143616 -291.901045) (xy 312.100995 -291.876438) (xy 312.062874 -291.845313)
			(xy 312.030239 -291.808476) (xy 312.003936 -291.76688) (xy 311.984645 -291.721604) (xy 311.972868 -291.67382)
			(xy 311.968908 -291.624766) (xy 311.63006 -291.624766) (xy 311.629565 -291.649373) (xy 311.62167 -291.69795)
			(xy 311.606086 -291.744631) (xy 311.583215 -291.788208) (xy 311.55365 -291.827552) (xy 311.518157 -291.861644)
			(xy 311.477654 -291.8896) (xy 311.433192 -291.910698) (xy 311.385921 -291.92439) (xy 311.337066 -291.930322)
			(xy 311.287891 -291.928341) (xy 311.239672 -291.918497) (xy 311.193656 -291.901045) (xy 311.151035 -291.876438)
			(xy 311.112914 -291.845313) (xy 311.080279 -291.808476) (xy 311.053976 -291.76688) (xy 311.034685 -291.721604)
			(xy 311.022908 -291.67382) (xy 311.018948 -291.624766) (xy 310.6801 -291.624766) (xy 310.679605 -291.649373)
			(xy 310.67171 -291.69795) (xy 310.656126 -291.744631) (xy 310.633255 -291.788208) (xy 310.60369 -291.827552)
			(xy 310.568197 -291.861644) (xy 310.527694 -291.8896) (xy 310.483232 -291.910698) (xy 310.435961 -291.92439)
			(xy 310.387106 -291.930322) (xy 310.337931 -291.928341) (xy 310.289712 -291.918497) (xy 310.243696 -291.901045)
			(xy 310.201075 -291.876438) (xy 310.162954 -291.845313) (xy 310.130319 -291.808476) (xy 310.104016 -291.76688)
			(xy 310.084725 -291.721604) (xy 310.072948 -291.67382) (xy 310.068988 -291.624766) (xy 309.73014 -291.624766)
			(xy 309.729645 -291.649373) (xy 309.72175 -291.69795) (xy 309.706166 -291.744631) (xy 309.683295 -291.788208)
			(xy 309.65373 -291.827552) (xy 309.618237 -291.861644) (xy 309.577734 -291.8896) (xy 309.533272 -291.910698)
			(xy 309.486001 -291.92439) (xy 309.437146 -291.930322) (xy 309.387971 -291.928341) (xy 309.339752 -291.918497)
			(xy 309.293736 -291.901045) (xy 309.251115 -291.876438) (xy 309.212994 -291.845313) (xy 309.180359 -291.808476)
			(xy 309.154056 -291.76688) (xy 309.134765 -291.721604) (xy 309.122988 -291.67382) (xy 309.119028 -291.624766)
			(xy 308.78018 -291.624766) (xy 308.779685 -291.649373) (xy 308.77179 -291.69795) (xy 308.756206 -291.744631)
			(xy 308.733335 -291.788208) (xy 308.70377 -291.827552) (xy 308.668277 -291.861644) (xy 308.627774 -291.8896)
			(xy 308.583312 -291.910698) (xy 308.536041 -291.92439) (xy 308.487186 -291.930322) (xy 308.438011 -291.928341)
			(xy 308.389792 -291.918497) (xy 308.343776 -291.901045) (xy 308.301155 -291.876438) (xy 308.263034 -291.845313)
			(xy 308.230399 -291.808476) (xy 308.204096 -291.76688) (xy 308.184805 -291.721604) (xy 308.173028 -291.67382)
			(xy 308.169068 -291.624766) (xy 306.88026 -291.624766) (xy 306.879765 -291.649373) (xy 306.87187 -291.69795)
			(xy 306.856286 -291.744631) (xy 306.833415 -291.788208) (xy 306.80385 -291.827552) (xy 306.768357 -291.861644)
			(xy 306.727854 -291.8896) (xy 306.683392 -291.910698) (xy 306.636121 -291.92439) (xy 306.587266 -291.930322)
			(xy 306.538091 -291.928341) (xy 306.489872 -291.918497) (xy 306.443856 -291.901045) (xy 306.401235 -291.876438)
			(xy 306.363114 -291.845313) (xy 306.330479 -291.808476) (xy 306.304176 -291.76688) (xy 306.284885 -291.721604)
			(xy 306.273108 -291.67382) (xy 306.269148 -291.624766) (xy 305.930046 -291.624766) (xy 305.929551 -291.649373)
			(xy 305.921656 -291.69795) (xy 305.906072 -291.744631) (xy 305.883201 -291.788208) (xy 305.853636 -291.827552)
			(xy 305.818143 -291.861644) (xy 305.77764 -291.8896) (xy 305.733178 -291.910698) (xy 305.685907 -291.92439)
			(xy 305.637052 -291.930322) (xy 305.587877 -291.928341) (xy 305.539658 -291.918497) (xy 305.493642 -291.901045)
			(xy 305.451021 -291.876438) (xy 305.4129 -291.845313) (xy 305.380265 -291.808476) (xy 305.353962 -291.76688)
			(xy 305.334671 -291.721604) (xy 305.322894 -291.67382) (xy 305.318934 -291.624766) (xy 304.980086 -291.624766)
			(xy 304.979591 -291.649373) (xy 304.971696 -291.69795) (xy 304.956112 -291.744631) (xy 304.933241 -291.788208)
			(xy 304.903676 -291.827552) (xy 304.868183 -291.861644) (xy 304.82768 -291.8896) (xy 304.783218 -291.910698)
			(xy 304.735947 -291.92439) (xy 304.687092 -291.930322) (xy 304.637917 -291.928341) (xy 304.589698 -291.918497)
			(xy 304.543682 -291.901045) (xy 304.501061 -291.876438) (xy 304.46294 -291.845313) (xy 304.430305 -291.808476)
			(xy 304.404002 -291.76688) (xy 304.384711 -291.721604) (xy 304.372934 -291.67382) (xy 304.368974 -291.624766)
			(xy 304.030126 -291.624766) (xy 304.029631 -291.649373) (xy 304.021736 -291.69795) (xy 304.006152 -291.744631)
			(xy 303.983281 -291.788208) (xy 303.953716 -291.827552) (xy 303.918223 -291.861644) (xy 303.87772 -291.8896)
			(xy 303.833258 -291.910698) (xy 303.785987 -291.92439) (xy 303.737132 -291.930322) (xy 303.687957 -291.928341)
			(xy 303.639738 -291.918497) (xy 303.593722 -291.901045) (xy 303.551101 -291.876438) (xy 303.51298 -291.845313)
			(xy 303.480345 -291.808476) (xy 303.454042 -291.76688) (xy 303.434751 -291.721604) (xy 303.422974 -291.67382)
			(xy 303.419014 -291.624766) (xy 303.080166 -291.624766) (xy 303.079671 -291.649373) (xy 303.071776 -291.69795)
			(xy 303.056192 -291.744631) (xy 303.033321 -291.788208) (xy 303.003756 -291.827552) (xy 302.968263 -291.861644)
			(xy 302.92776 -291.8896) (xy 302.883298 -291.910698) (xy 302.836027 -291.92439) (xy 302.787172 -291.930322)
			(xy 302.737997 -291.928341) (xy 302.689778 -291.918497) (xy 302.643762 -291.901045) (xy 302.601141 -291.876438)
			(xy 302.56302 -291.845313) (xy 302.530385 -291.808476) (xy 302.504082 -291.76688) (xy 302.484791 -291.721604)
			(xy 302.473014 -291.67382) (xy 302.469054 -291.624766) (xy 302.130206 -291.624766) (xy 302.129711 -291.649373)
			(xy 302.121816 -291.69795) (xy 302.106232 -291.744631) (xy 302.083361 -291.788208) (xy 302.053796 -291.827552)
			(xy 302.018303 -291.861644) (xy 301.9778 -291.8896) (xy 301.933338 -291.910698) (xy 301.886067 -291.92439)
			(xy 301.837212 -291.930322) (xy 301.788037 -291.928341) (xy 301.739818 -291.918497) (xy 301.693802 -291.901045)
			(xy 301.651181 -291.876438) (xy 301.61306 -291.845313) (xy 301.580425 -291.808476) (xy 301.554122 -291.76688)
			(xy 301.534831 -291.721604) (xy 301.523054 -291.67382) (xy 301.519094 -291.624766) (xy 301.179992 -291.624766)
			(xy 301.179497 -291.649373) (xy 301.171602 -291.69795) (xy 301.156018 -291.744631) (xy 301.133147 -291.788208)
			(xy 301.103582 -291.827552) (xy 301.068089 -291.861644) (xy 301.027586 -291.8896) (xy 300.983124 -291.910698)
			(xy 300.935853 -291.92439) (xy 300.886998 -291.930322) (xy 300.837823 -291.928341) (xy 300.789604 -291.918497)
			(xy 300.743588 -291.901045) (xy 300.700967 -291.876438) (xy 300.662846 -291.845313) (xy 300.630211 -291.808476)
			(xy 300.603908 -291.76688) (xy 300.584617 -291.721604) (xy 300.57284 -291.67382) (xy 300.56888 -291.624766)
			(xy 300.230032 -291.624766) (xy 300.229537 -291.649373) (xy 300.221642 -291.69795) (xy 300.206058 -291.744631)
			(xy 300.183187 -291.788208) (xy 300.153622 -291.827552) (xy 300.118129 -291.861644) (xy 300.077626 -291.8896)
			(xy 300.033164 -291.910698) (xy 299.985893 -291.92439) (xy 299.937038 -291.930322) (xy 299.887863 -291.928341)
			(xy 299.839644 -291.918497) (xy 299.793628 -291.901045) (xy 299.751007 -291.876438) (xy 299.712886 -291.845313)
			(xy 299.680251 -291.808476) (xy 299.653948 -291.76688) (xy 299.634657 -291.721604) (xy 299.62288 -291.67382)
			(xy 299.61892 -291.624766) (xy 299.280072 -291.624766) (xy 299.279577 -291.649373) (xy 299.271682 -291.69795)
			(xy 299.256098 -291.744631) (xy 299.233227 -291.788208) (xy 299.203662 -291.827552) (xy 299.168169 -291.861644)
			(xy 299.127666 -291.8896) (xy 299.083204 -291.910698) (xy 299.035933 -291.92439) (xy 298.987078 -291.930322)
			(xy 298.937903 -291.928341) (xy 298.889684 -291.918497) (xy 298.843668 -291.901045) (xy 298.801047 -291.876438)
			(xy 298.762926 -291.845313) (xy 298.730291 -291.808476) (xy 298.703988 -291.76688) (xy 298.684697 -291.721604)
			(xy 298.67292 -291.67382) (xy 298.66896 -291.624766) (xy 298.330112 -291.624766) (xy 298.329617 -291.649373)
			(xy 298.321722 -291.69795) (xy 298.306138 -291.744631) (xy 298.283267 -291.788208) (xy 298.253702 -291.827552)
			(xy 298.218209 -291.861644) (xy 298.177706 -291.8896) (xy 298.133244 -291.910698) (xy 298.085973 -291.92439)
			(xy 298.037118 -291.930322) (xy 297.987943 -291.928341) (xy 297.939724 -291.918497) (xy 297.893708 -291.901045)
			(xy 297.851087 -291.876438) (xy 297.812966 -291.845313) (xy 297.780331 -291.808476) (xy 297.754028 -291.76688)
			(xy 297.734737 -291.721604) (xy 297.72296 -291.67382) (xy 297.719 -291.624766) (xy 297.380152 -291.624766)
			(xy 297.379657 -291.649373) (xy 297.371762 -291.69795) (xy 297.356178 -291.744631) (xy 297.333307 -291.788208)
			(xy 297.303742 -291.827552) (xy 297.268249 -291.861644) (xy 297.227746 -291.8896) (xy 297.183284 -291.910698)
			(xy 297.136013 -291.92439) (xy 297.087158 -291.930322) (xy 297.037983 -291.928341) (xy 296.989764 -291.918497)
			(xy 296.943748 -291.901045) (xy 296.901127 -291.876438) (xy 296.863006 -291.845313) (xy 296.830371 -291.808476)
			(xy 296.804068 -291.76688) (xy 296.784777 -291.721604) (xy 296.773 -291.67382) (xy 296.76904 -291.624766)
			(xy 296.430192 -291.624766) (xy 296.429697 -291.649373) (xy 296.421802 -291.69795) (xy 296.406218 -291.744631)
			(xy 296.383347 -291.788208) (xy 296.353782 -291.827552) (xy 296.318289 -291.861644) (xy 296.277786 -291.8896)
			(xy 296.233324 -291.910698) (xy 296.186053 -291.92439) (xy 296.137198 -291.930322) (xy 296.088023 -291.928341)
			(xy 296.039804 -291.918497) (xy 295.993788 -291.901045) (xy 295.951167 -291.876438) (xy 295.913046 -291.845313)
			(xy 295.880411 -291.808476) (xy 295.854108 -291.76688) (xy 295.834817 -291.721604) (xy 295.82304 -291.67382)
			(xy 295.81908 -291.624766) (xy 295.480232 -291.624766) (xy 295.479737 -291.649373) (xy 295.471842 -291.69795)
			(xy 295.456258 -291.744631) (xy 295.433387 -291.788208) (xy 295.403822 -291.827552) (xy 295.368329 -291.861644)
			(xy 295.327826 -291.8896) (xy 295.283364 -291.910698) (xy 295.236093 -291.92439) (xy 295.187238 -291.930322)
			(xy 295.138063 -291.928341) (xy 295.089844 -291.918497) (xy 295.043828 -291.901045) (xy 295.001207 -291.876438)
			(xy 294.963086 -291.845313) (xy 294.930451 -291.808476) (xy 294.904148 -291.76688) (xy 294.884857 -291.721604)
			(xy 294.87308 -291.67382) (xy 294.86912 -291.624766) (xy 294.530018 -291.624766) (xy 294.529523 -291.649373)
			(xy 294.521628 -291.69795) (xy 294.506044 -291.744631) (xy 294.483173 -291.788208) (xy 294.453608 -291.827552)
			(xy 294.418115 -291.861644) (xy 294.377612 -291.8896) (xy 294.33315 -291.910698) (xy 294.285879 -291.92439)
			(xy 294.237024 -291.930322) (xy 294.187849 -291.928341) (xy 294.13963 -291.918497) (xy 294.093614 -291.901045)
			(xy 294.050993 -291.876438) (xy 294.012872 -291.845313) (xy 293.980237 -291.808476) (xy 293.953934 -291.76688)
			(xy 293.934643 -291.721604) (xy 293.922866 -291.67382) (xy 293.918906 -291.624766) (xy 293.580058 -291.624766)
			(xy 293.579563 -291.649373) (xy 293.571668 -291.69795) (xy 293.556084 -291.744631) (xy 293.533213 -291.788208)
			(xy 293.503648 -291.827552) (xy 293.468155 -291.861644) (xy 293.427652 -291.8896) (xy 293.38319 -291.910698)
			(xy 293.335919 -291.92439) (xy 293.287064 -291.930322) (xy 293.237889 -291.928341) (xy 293.18967 -291.918497)
			(xy 293.143654 -291.901045) (xy 293.101033 -291.876438) (xy 293.062912 -291.845313) (xy 293.030277 -291.808476)
			(xy 293.003974 -291.76688) (xy 292.984683 -291.721604) (xy 292.972906 -291.67382) (xy 292.968946 -291.624766)
			(xy 292.630098 -291.624766) (xy 292.629603 -291.649373) (xy 292.621708 -291.69795) (xy 292.606124 -291.744631)
			(xy 292.583253 -291.788208) (xy 292.553688 -291.827552) (xy 292.518195 -291.861644) (xy 292.477692 -291.8896)
			(xy 292.43323 -291.910698) (xy 292.385959 -291.92439) (xy 292.337104 -291.930322) (xy 292.287929 -291.928341)
			(xy 292.23971 -291.918497) (xy 292.193694 -291.901045) (xy 292.151073 -291.876438) (xy 292.112952 -291.845313)
			(xy 292.080317 -291.808476) (xy 292.054014 -291.76688) (xy 292.034723 -291.721604) (xy 292.022946 -291.67382)
			(xy 292.018986 -291.624766) (xy 290.730178 -291.624766) (xy 290.729683 -291.649373) (xy 290.721788 -291.69795)
			(xy 290.706204 -291.744631) (xy 290.683333 -291.788208) (xy 290.653768 -291.827552) (xy 290.618275 -291.861644)
			(xy 290.577772 -291.8896) (xy 290.53331 -291.910698) (xy 290.486039 -291.92439) (xy 290.437184 -291.930322)
			(xy 290.388009 -291.928341) (xy 290.33979 -291.918497) (xy 290.293774 -291.901045) (xy 290.251153 -291.876438)
			(xy 290.213032 -291.845313) (xy 290.180397 -291.808476) (xy 290.154094 -291.76688) (xy 290.134803 -291.721604)
			(xy 290.123026 -291.67382) (xy 290.119066 -291.624766) (xy 289.780218 -291.624766) (xy 289.779723 -291.649373)
			(xy 289.771828 -291.69795) (xy 289.756244 -291.744631) (xy 289.733373 -291.788208) (xy 289.703808 -291.827552)
			(xy 289.668315 -291.861644) (xy 289.627812 -291.8896) (xy 289.58335 -291.910698) (xy 289.536079 -291.92439)
			(xy 289.487224 -291.930322) (xy 289.438049 -291.928341) (xy 289.38983 -291.918497) (xy 289.343814 -291.901045)
			(xy 289.301193 -291.876438) (xy 289.263072 -291.845313) (xy 289.230437 -291.808476) (xy 289.204134 -291.76688)
			(xy 289.184843 -291.721604) (xy 289.173066 -291.67382) (xy 289.169106 -291.624766) (xy 288.830004 -291.624766)
			(xy 288.829509 -291.649373) (xy 288.821614 -291.69795) (xy 288.80603 -291.744631) (xy 288.783159 -291.788208)
			(xy 288.753594 -291.827552) (xy 288.718101 -291.861644) (xy 288.677598 -291.8896) (xy 288.633136 -291.910698)
			(xy 288.585865 -291.92439) (xy 288.53701 -291.930322) (xy 288.487835 -291.928341) (xy 288.439616 -291.918497)
			(xy 288.3936 -291.901045) (xy 288.350979 -291.876438) (xy 288.312858 -291.845313) (xy 288.280223 -291.808476)
			(xy 288.25392 -291.76688) (xy 288.234629 -291.721604) (xy 288.222852 -291.67382) (xy 288.218892 -291.624766)
			(xy 287.880044 -291.624766) (xy 287.879549 -291.649373) (xy 287.871654 -291.69795) (xy 287.85607 -291.744631)
			(xy 287.833199 -291.788208) (xy 287.803634 -291.827552) (xy 287.768141 -291.861644) (xy 287.727638 -291.8896)
			(xy 287.683176 -291.910698) (xy 287.635905 -291.92439) (xy 287.58705 -291.930322) (xy 287.537875 -291.928341)
			(xy 287.489656 -291.918497) (xy 287.44364 -291.901045) (xy 287.401019 -291.876438) (xy 287.362898 -291.845313)
			(xy 287.330263 -291.808476) (xy 287.30396 -291.76688) (xy 287.284669 -291.721604) (xy 287.272892 -291.67382)
			(xy 287.268932 -291.624766) (xy 286.930084 -291.624766) (xy 286.929589 -291.649373) (xy 286.921694 -291.69795)
			(xy 286.90611 -291.744631) (xy 286.883239 -291.788208) (xy 286.853674 -291.827552) (xy 286.818181 -291.861644)
			(xy 286.777678 -291.8896) (xy 286.733216 -291.910698) (xy 286.685945 -291.92439) (xy 286.63709 -291.930322)
			(xy 286.587915 -291.928341) (xy 286.539696 -291.918497) (xy 286.49368 -291.901045) (xy 286.451059 -291.876438)
			(xy 286.412938 -291.845313) (xy 286.380303 -291.808476) (xy 286.354 -291.76688) (xy 286.334709 -291.721604)
			(xy 286.322932 -291.67382) (xy 286.318972 -291.624766) (xy 285.980124 -291.624766) (xy 285.979629 -291.649373)
			(xy 285.971734 -291.69795) (xy 285.95615 -291.744631) (xy 285.933279 -291.788208) (xy 285.903714 -291.827552)
			(xy 285.868221 -291.861644) (xy 285.827718 -291.8896) (xy 285.783256 -291.910698) (xy 285.735985 -291.92439)
			(xy 285.68713 -291.930322) (xy 285.637955 -291.928341) (xy 285.589736 -291.918497) (xy 285.54372 -291.901045)
			(xy 285.501099 -291.876438) (xy 285.462978 -291.845313) (xy 285.430343 -291.808476) (xy 285.40404 -291.76688)
			(xy 285.384749 -291.721604) (xy 285.372972 -291.67382) (xy 285.369012 -291.624766) (xy 285.030164 -291.624766)
			(xy 285.029669 -291.649373) (xy 285.021774 -291.69795) (xy 285.00619 -291.744631) (xy 284.983319 -291.788208)
			(xy 284.953754 -291.827552) (xy 284.918261 -291.861644) (xy 284.877758 -291.8896) (xy 284.833296 -291.910698)
			(xy 284.786025 -291.92439) (xy 284.73717 -291.930322) (xy 284.687995 -291.928341) (xy 284.639776 -291.918497)
			(xy 284.59376 -291.901045) (xy 284.551139 -291.876438) (xy 284.513018 -291.845313) (xy 284.480383 -291.808476)
			(xy 284.45408 -291.76688) (xy 284.434789 -291.721604) (xy 284.423012 -291.67382) (xy 284.419052 -291.624766)
			(xy 284.080204 -291.624766) (xy 284.079709 -291.649373) (xy 284.071814 -291.69795) (xy 284.05623 -291.744631)
			(xy 284.033359 -291.788208) (xy 284.003794 -291.827552) (xy 283.968301 -291.861644) (xy 283.927798 -291.8896)
			(xy 283.883336 -291.910698) (xy 283.836065 -291.92439) (xy 283.78721 -291.930322) (xy 283.738035 -291.928341)
			(xy 283.689816 -291.918497) (xy 283.6438 -291.901045) (xy 283.601179 -291.876438) (xy 283.563058 -291.845313)
			(xy 283.530423 -291.808476) (xy 283.50412 -291.76688) (xy 283.484829 -291.721604) (xy 283.473052 -291.67382)
			(xy 283.469092 -291.624766) (xy 283.130244 -291.624766) (xy 283.129749 -291.649373) (xy 283.121854 -291.69795)
			(xy 283.10627 -291.744631) (xy 283.083399 -291.788208) (xy 283.053834 -291.827552) (xy 283.018341 -291.861644)
			(xy 282.977838 -291.8896) (xy 282.933376 -291.910698) (xy 282.886105 -291.92439) (xy 282.83725 -291.930322)
			(xy 282.788075 -291.928341) (xy 282.739856 -291.918497) (xy 282.69384 -291.901045) (xy 282.651219 -291.876438)
			(xy 282.613098 -291.845313) (xy 282.580463 -291.808476) (xy 282.55416 -291.76688) (xy 282.534869 -291.721604)
			(xy 282.523092 -291.67382) (xy 282.519132 -291.624766) (xy 281.616912 -291.624766) (xy 281.616912 -292.122098)
			(xy 325.457312 -292.122098) (xy 325.457754 -292.095494) (xy 325.465136 -292.0428) (xy 325.479771 -291.991644)
			(xy 325.501375 -291.943019) (xy 325.529528 -291.897869) (xy 325.563683 -291.85707) (xy 325.603177 -291.821415)
			(xy 325.624952 -291.806122) (xy 325.63639 -291.797731) (xy 325.6546 -291.776003) (xy 325.666125 -291.750101)
			(xy 325.670074 -291.722027) (xy 325.66614 -291.693951) (xy 325.654629 -291.668043) (xy 325.63643 -291.646306)
			(xy 325.624952 -291.637974) (xy 325.603163 -291.622704) (xy 325.563684 -291.587034) (xy 325.529542 -291.546226)
			(xy 325.501398 -291.501072) (xy 325.479799 -291.452447) (xy 325.465163 -291.401293) (xy 325.457773 -291.348601)
			(xy 325.457312 -291.321998) (xy 325.457798 -291.294747) (xy 325.465554 -291.240799) (xy 325.480909 -291.188504)
			(xy 325.503551 -291.138927) (xy 325.533017 -291.093077) (xy 325.568708 -291.051886) (xy 325.609899 -291.016195)
			(xy 325.655749 -290.986729) (xy 325.705326 -290.964087) (xy 325.757621 -290.948732) (xy 325.811569 -290.940976)
			(xy 325.866071 -290.940976) (xy 325.920019 -290.948732) (xy 325.972314 -290.964087) (xy 326.021891 -290.986729)
			(xy 326.067741 -291.016195) (xy 326.108932 -291.051886) (xy 326.144623 -291.093077) (xy 326.174089 -291.138927)
			(xy 326.196731 -291.188504) (xy 326.212086 -291.240799) (xy 326.219842 -291.294747) (xy 326.220328 -291.321998)
			(xy 326.219909 -291.348603) (xy 326.212526 -291.401299) (xy 326.197889 -291.452457) (xy 326.176282 -291.501083)
			(xy 326.148125 -291.546233) (xy 326.113965 -291.587031) (xy 326.074465 -291.622683) (xy 326.052688 -291.637974)
			(xy 326.041162 -291.64625) (xy 326.02296 -291.668007) (xy 326.011447 -291.693934) (xy 326.007513 -291.722027)
			(xy 326.011462 -291.750118) (xy 326.022988 -291.776039) (xy 326.041202 -291.797786) (xy 326.052688 -291.806122)
			(xy 326.074484 -291.821382) (xy 326.113961 -291.857055) (xy 326.148101 -291.897865) (xy 326.176243 -291.943021)
			(xy 326.197842 -291.991648) (xy 326.212477 -292.042803) (xy 326.219867 -292.095494) (xy 326.220328 -292.122098)
			(xy 326.219842 -292.149349) (xy 326.212086 -292.203297) (xy 326.196731 -292.255592) (xy 326.174089 -292.305169)
			(xy 326.144623 -292.351019) (xy 326.108932 -292.39221) (xy 326.067741 -292.427901) (xy 326.021891 -292.457367)
			(xy 325.972314 -292.480009) (xy 325.920019 -292.495364) (xy 325.866071 -292.50312) (xy 325.811569 -292.50312)
			(xy 325.757621 -292.495364) (xy 325.705326 -292.480009) (xy 325.655749 -292.457367) (xy 325.609899 -292.427901)
			(xy 325.568708 -292.39221) (xy 325.533017 -292.351019) (xy 325.503551 -292.305169) (xy 325.480909 -292.255592)
			(xy 325.465554 -292.203297) (xy 325.457798 -292.149349) (xy 325.457312 -292.122098) (xy 281.616912 -292.122098)
			(xy 281.616912 -292.19906) (xy 281.617567 -292.211609) (xy 281.629437 -292.23372) (xy 281.639518 -292.241224)
			(xy 281.720544 -292.295326) (xy 281.745436 -292.297866) (xy 281.757628 -292.292786) (xy 281.785665 -292.281888)
			(xy 281.844649 -292.270122) (xy 281.874722 -292.269418) (xy 281.899974 -292.269941) (xy 281.949789 -292.278257)
			(xy 281.997555 -292.294658) (xy 282.041971 -292.318698) (xy 282.081825 -292.34972) (xy 282.116029 -292.386878)
			(xy 282.143651 -292.429159) (xy 282.163937 -292.47541) (xy 282.176335 -292.524368) (xy 282.180505 -292.5747)
			(xy 282.180482 -292.57498) (xy 282.519132 -292.57498) (xy 282.523092 -292.525926) (xy 282.534869 -292.478142)
			(xy 282.55416 -292.432866) (xy 282.580463 -292.39127) (xy 282.613098 -292.354433) (xy 282.651219 -292.323308)
			(xy 282.69384 -292.298701) (xy 282.739856 -292.281249) (xy 282.788075 -292.271405) (xy 282.83725 -292.269424)
			(xy 282.886105 -292.275356) (xy 282.933376 -292.289048) (xy 282.977838 -292.310146) (xy 283.018341 -292.338102)
			(xy 283.053834 -292.372194) (xy 283.083399 -292.411538) (xy 283.10627 -292.455115) (xy 283.121854 -292.501796)
			(xy 283.129749 -292.550373) (xy 283.130244 -292.57498) (xy 283.469092 -292.57498) (xy 283.473052 -292.525926)
			(xy 283.484829 -292.478142) (xy 283.50412 -292.432866) (xy 283.530423 -292.39127) (xy 283.563058 -292.354433)
			(xy 283.601179 -292.323308) (xy 283.6438 -292.298701) (xy 283.689816 -292.281249) (xy 283.738035 -292.271405)
			(xy 283.78721 -292.269424) (xy 283.836065 -292.275356) (xy 283.883336 -292.289048) (xy 283.927798 -292.310146)
			(xy 283.968301 -292.338102) (xy 284.003794 -292.372194) (xy 284.033359 -292.411538) (xy 284.05623 -292.455115)
			(xy 284.071814 -292.501796) (xy 284.079709 -292.550373) (xy 284.080204 -292.57498) (xy 284.419052 -292.57498)
			(xy 284.423012 -292.525926) (xy 284.434789 -292.478142) (xy 284.45408 -292.432866) (xy 284.480383 -292.39127)
			(xy 284.513018 -292.354433) (xy 284.551139 -292.323308) (xy 284.59376 -292.298701) (xy 284.639776 -292.281249)
			(xy 284.687995 -292.271405) (xy 284.73717 -292.269424) (xy 284.786025 -292.275356) (xy 284.833296 -292.289048)
			(xy 284.877758 -292.310146) (xy 284.918261 -292.338102) (xy 284.953754 -292.372194) (xy 284.983319 -292.411538)
			(xy 285.00619 -292.455115) (xy 285.021774 -292.501796) (xy 285.029669 -292.550373) (xy 285.030164 -292.57498)
			(xy 285.369012 -292.57498) (xy 285.372972 -292.525926) (xy 285.384749 -292.478142) (xy 285.40404 -292.432866)
			(xy 285.430343 -292.39127) (xy 285.462978 -292.354433) (xy 285.501099 -292.323308) (xy 285.54372 -292.298701)
			(xy 285.589736 -292.281249) (xy 285.637955 -292.271405) (xy 285.68713 -292.269424) (xy 285.735985 -292.275356)
			(xy 285.783256 -292.289048) (xy 285.827718 -292.310146) (xy 285.868221 -292.338102) (xy 285.903714 -292.372194)
			(xy 285.933279 -292.411538) (xy 285.95615 -292.455115) (xy 285.971734 -292.501796) (xy 285.979629 -292.550373)
			(xy 285.980124 -292.57498) (xy 286.318972 -292.57498) (xy 286.322932 -292.525926) (xy 286.334709 -292.478142)
			(xy 286.354 -292.432866) (xy 286.380303 -292.39127) (xy 286.412938 -292.354433) (xy 286.451059 -292.323308)
			(xy 286.49368 -292.298701) (xy 286.539696 -292.281249) (xy 286.587915 -292.271405) (xy 286.63709 -292.269424)
			(xy 286.685945 -292.275356) (xy 286.733216 -292.289048) (xy 286.777678 -292.310146) (xy 286.818181 -292.338102)
			(xy 286.853674 -292.372194) (xy 286.883239 -292.411538) (xy 286.90611 -292.455115) (xy 286.921694 -292.501796)
			(xy 286.929589 -292.550373) (xy 286.930084 -292.57498) (xy 287.268932 -292.57498) (xy 287.272892 -292.525926)
			(xy 287.284669 -292.478142) (xy 287.30396 -292.432866) (xy 287.330263 -292.39127) (xy 287.362898 -292.354433)
			(xy 287.401019 -292.323308) (xy 287.44364 -292.298701) (xy 287.489656 -292.281249) (xy 287.537875 -292.271405)
			(xy 287.58705 -292.269424) (xy 287.635905 -292.275356) (xy 287.683176 -292.289048) (xy 287.727638 -292.310146)
			(xy 287.768141 -292.338102) (xy 287.803634 -292.372194) (xy 287.833199 -292.411538) (xy 287.85607 -292.455115)
			(xy 287.871654 -292.501796) (xy 287.879549 -292.550373) (xy 287.880044 -292.57498) (xy 288.219146 -292.57498)
			(xy 288.223106 -292.525926) (xy 288.234883 -292.478142) (xy 288.254174 -292.432866) (xy 288.280477 -292.39127)
			(xy 288.313112 -292.354433) (xy 288.351233 -292.323308) (xy 288.393854 -292.298701) (xy 288.43987 -292.281249)
			(xy 288.488089 -292.271405) (xy 288.537264 -292.269424) (xy 288.586119 -292.275356) (xy 288.63339 -292.289048)
			(xy 288.677852 -292.310146) (xy 288.718355 -292.338102) (xy 288.753848 -292.372194) (xy 288.783413 -292.411538)
			(xy 288.806284 -292.455115) (xy 288.821868 -292.501796) (xy 288.829763 -292.550373) (xy 288.830258 -292.57498)
			(xy 289.169106 -292.57498) (xy 289.173066 -292.525926) (xy 289.184843 -292.478142) (xy 289.204134 -292.432866)
			(xy 289.230437 -292.39127) (xy 289.263072 -292.354433) (xy 289.301193 -292.323308) (xy 289.343814 -292.298701)
			(xy 289.38983 -292.281249) (xy 289.438049 -292.271405) (xy 289.487224 -292.269424) (xy 289.536079 -292.275356)
			(xy 289.58335 -292.289048) (xy 289.627812 -292.310146) (xy 289.668315 -292.338102) (xy 289.703808 -292.372194)
			(xy 289.733373 -292.411538) (xy 289.756244 -292.455115) (xy 289.771828 -292.501796) (xy 289.779723 -292.550373)
			(xy 289.780218 -292.57498) (xy 290.119066 -292.57498) (xy 290.123026 -292.525926) (xy 290.134803 -292.478142)
			(xy 290.154094 -292.432866) (xy 290.180397 -292.39127) (xy 290.213032 -292.354433) (xy 290.251153 -292.323308)
			(xy 290.293774 -292.298701) (xy 290.33979 -292.281249) (xy 290.388009 -292.271405) (xy 290.437184 -292.269424)
			(xy 290.486039 -292.275356) (xy 290.53331 -292.289048) (xy 290.577772 -292.310146) (xy 290.618275 -292.338102)
			(xy 290.653768 -292.372194) (xy 290.683333 -292.411538) (xy 290.706204 -292.455115) (xy 290.721788 -292.501796)
			(xy 290.729683 -292.550373) (xy 290.730173 -292.574726) (xy 292.018986 -292.574726) (xy 292.022946 -292.525672)
			(xy 292.034723 -292.477888) (xy 292.054014 -292.432612) (xy 292.080317 -292.391016) (xy 292.112952 -292.354179)
			(xy 292.151073 -292.323054) (xy 292.193694 -292.298447) (xy 292.23971 -292.280995) (xy 292.287929 -292.271151)
			(xy 292.337104 -292.26917) (xy 292.385959 -292.275102) (xy 292.43323 -292.288794) (xy 292.477692 -292.309892)
			(xy 292.518195 -292.337848) (xy 292.553688 -292.37194) (xy 292.583253 -292.411284) (xy 292.606124 -292.454861)
			(xy 292.621708 -292.501542) (xy 292.629603 -292.550119) (xy 292.630098 -292.574726) (xy 292.968946 -292.574726)
			(xy 292.972906 -292.525672) (xy 292.984683 -292.477888) (xy 293.003974 -292.432612) (xy 293.030277 -292.391016)
			(xy 293.062912 -292.354179) (xy 293.101033 -292.323054) (xy 293.143654 -292.298447) (xy 293.18967 -292.280995)
			(xy 293.237889 -292.271151) (xy 293.287064 -292.26917) (xy 293.335919 -292.275102) (xy 293.38319 -292.288794)
			(xy 293.427652 -292.309892) (xy 293.468155 -292.337848) (xy 293.503648 -292.37194) (xy 293.533213 -292.411284)
			(xy 293.556084 -292.454861) (xy 293.571668 -292.501542) (xy 293.579563 -292.550119) (xy 293.580058 -292.574726)
			(xy 293.918906 -292.574726) (xy 293.922866 -292.525672) (xy 293.934643 -292.477888) (xy 293.953934 -292.432612)
			(xy 293.980237 -292.391016) (xy 294.012872 -292.354179) (xy 294.050993 -292.323054) (xy 294.093614 -292.298447)
			(xy 294.13963 -292.280995) (xy 294.187849 -292.271151) (xy 294.237024 -292.26917) (xy 294.285879 -292.275102)
			(xy 294.33315 -292.288794) (xy 294.377612 -292.309892) (xy 294.418115 -292.337848) (xy 294.453608 -292.37194)
			(xy 294.483173 -292.411284) (xy 294.506044 -292.454861) (xy 294.521628 -292.501542) (xy 294.529523 -292.550119)
			(xy 294.530018 -292.574726) (xy 294.86912 -292.574726) (xy 294.87308 -292.525672) (xy 294.884857 -292.477888)
			(xy 294.904148 -292.432612) (xy 294.930451 -292.391016) (xy 294.963086 -292.354179) (xy 295.001207 -292.323054)
			(xy 295.043828 -292.298447) (xy 295.089844 -292.280995) (xy 295.138063 -292.271151) (xy 295.187238 -292.26917)
			(xy 295.236093 -292.275102) (xy 295.283364 -292.288794) (xy 295.327826 -292.309892) (xy 295.368329 -292.337848)
			(xy 295.403822 -292.37194) (xy 295.433387 -292.411284) (xy 295.456258 -292.454861) (xy 295.471842 -292.501542)
			(xy 295.479737 -292.550119) (xy 295.480232 -292.574726) (xy 295.81908 -292.574726) (xy 295.82304 -292.525672)
			(xy 295.834817 -292.477888) (xy 295.854108 -292.432612) (xy 295.880411 -292.391016) (xy 295.913046 -292.354179)
			(xy 295.951167 -292.323054) (xy 295.993788 -292.298447) (xy 296.039804 -292.280995) (xy 296.088023 -292.271151)
			(xy 296.137198 -292.26917) (xy 296.186053 -292.275102) (xy 296.233324 -292.288794) (xy 296.277786 -292.309892)
			(xy 296.318289 -292.337848) (xy 296.353782 -292.37194) (xy 296.383347 -292.411284) (xy 296.406218 -292.454861)
			(xy 296.421802 -292.501542) (xy 296.429697 -292.550119) (xy 296.430192 -292.574726) (xy 296.76904 -292.574726)
			(xy 296.773 -292.525672) (xy 296.784777 -292.477888) (xy 296.804068 -292.432612) (xy 296.830371 -292.391016)
			(xy 296.863006 -292.354179) (xy 296.901127 -292.323054) (xy 296.943748 -292.298447) (xy 296.989764 -292.280995)
			(xy 297.037983 -292.271151) (xy 297.087158 -292.26917) (xy 297.136013 -292.275102) (xy 297.183284 -292.288794)
			(xy 297.227746 -292.309892) (xy 297.268249 -292.337848) (xy 297.303742 -292.37194) (xy 297.333307 -292.411284)
			(xy 297.356178 -292.454861) (xy 297.371762 -292.501542) (xy 297.379657 -292.550119) (xy 297.380152 -292.574726)
			(xy 297.719 -292.574726) (xy 297.72296 -292.525672) (xy 297.734737 -292.477888) (xy 297.754028 -292.432612)
			(xy 297.780331 -292.391016) (xy 297.812966 -292.354179) (xy 297.851087 -292.323054) (xy 297.893708 -292.298447)
			(xy 297.939724 -292.280995) (xy 297.987943 -292.271151) (xy 298.037118 -292.26917) (xy 298.085973 -292.275102)
			(xy 298.133244 -292.288794) (xy 298.177706 -292.309892) (xy 298.218209 -292.337848) (xy 298.253702 -292.37194)
			(xy 298.283267 -292.411284) (xy 298.306138 -292.454861) (xy 298.321722 -292.501542) (xy 298.329617 -292.550119)
			(xy 298.330112 -292.574726) (xy 298.66896 -292.574726) (xy 298.67292 -292.525672) (xy 298.684697 -292.477888)
			(xy 298.703988 -292.432612) (xy 298.730291 -292.391016) (xy 298.762926 -292.354179) (xy 298.801047 -292.323054)
			(xy 298.843668 -292.298447) (xy 298.889684 -292.280995) (xy 298.937903 -292.271151) (xy 298.987078 -292.26917)
			(xy 299.035933 -292.275102) (xy 299.083204 -292.288794) (xy 299.127666 -292.309892) (xy 299.168169 -292.337848)
			(xy 299.203662 -292.37194) (xy 299.233227 -292.411284) (xy 299.256098 -292.454861) (xy 299.271682 -292.501542)
			(xy 299.279577 -292.550119) (xy 299.280072 -292.574726) (xy 299.61892 -292.574726) (xy 299.62288 -292.525672)
			(xy 299.634657 -292.477888) (xy 299.653948 -292.432612) (xy 299.680251 -292.391016) (xy 299.712886 -292.354179)
			(xy 299.751007 -292.323054) (xy 299.793628 -292.298447) (xy 299.839644 -292.280995) (xy 299.887863 -292.271151)
			(xy 299.937038 -292.26917) (xy 299.985893 -292.275102) (xy 300.033164 -292.288794) (xy 300.077626 -292.309892)
			(xy 300.118129 -292.337848) (xy 300.153622 -292.37194) (xy 300.183187 -292.411284) (xy 300.206058 -292.454861)
			(xy 300.221642 -292.501542) (xy 300.229537 -292.550119) (xy 300.230032 -292.574726) (xy 300.56888 -292.574726)
			(xy 300.57284 -292.525672) (xy 300.584617 -292.477888) (xy 300.603908 -292.432612) (xy 300.630211 -292.391016)
			(xy 300.662846 -292.354179) (xy 300.700967 -292.323054) (xy 300.743588 -292.298447) (xy 300.789604 -292.280995)
			(xy 300.837823 -292.271151) (xy 300.886998 -292.26917) (xy 300.935853 -292.275102) (xy 300.983124 -292.288794)
			(xy 301.027586 -292.309892) (xy 301.068089 -292.337848) (xy 301.103582 -292.37194) (xy 301.133147 -292.411284)
			(xy 301.156018 -292.454861) (xy 301.171602 -292.501542) (xy 301.179497 -292.550119) (xy 301.179992 -292.574726)
			(xy 301.519094 -292.574726) (xy 301.523054 -292.525672) (xy 301.534831 -292.477888) (xy 301.554122 -292.432612)
			(xy 301.580425 -292.391016) (xy 301.61306 -292.354179) (xy 301.651181 -292.323054) (xy 301.693802 -292.298447)
			(xy 301.739818 -292.280995) (xy 301.788037 -292.271151) (xy 301.837212 -292.26917) (xy 301.886067 -292.275102)
			(xy 301.933338 -292.288794) (xy 301.9778 -292.309892) (xy 302.018303 -292.337848) (xy 302.053796 -292.37194)
			(xy 302.083361 -292.411284) (xy 302.106232 -292.454861) (xy 302.121816 -292.501542) (xy 302.129711 -292.550119)
			(xy 302.130206 -292.574726) (xy 302.130201 -292.57498) (xy 302.469054 -292.57498) (xy 302.473014 -292.525926)
			(xy 302.484791 -292.478142) (xy 302.504082 -292.432866) (xy 302.530385 -292.39127) (xy 302.56302 -292.354433)
			(xy 302.601141 -292.323308) (xy 302.643762 -292.298701) (xy 302.689778 -292.281249) (xy 302.737997 -292.271405)
			(xy 302.787172 -292.269424) (xy 302.836027 -292.275356) (xy 302.883298 -292.289048) (xy 302.92776 -292.310146)
			(xy 302.968263 -292.338102) (xy 303.003756 -292.372194) (xy 303.033321 -292.411538) (xy 303.056192 -292.455115)
			(xy 303.071776 -292.501796) (xy 303.079671 -292.550373) (xy 303.080161 -292.574726) (xy 303.419014 -292.574726)
			(xy 303.422974 -292.525672) (xy 303.434751 -292.477888) (xy 303.454042 -292.432612) (xy 303.480345 -292.391016)
			(xy 303.51298 -292.354179) (xy 303.551101 -292.323054) (xy 303.593722 -292.298447) (xy 303.639738 -292.280995)
			(xy 303.687957 -292.271151) (xy 303.737132 -292.26917) (xy 303.785987 -292.275102) (xy 303.833258 -292.288794)
			(xy 303.87772 -292.309892) (xy 303.918223 -292.337848) (xy 303.953716 -292.37194) (xy 303.983281 -292.411284)
			(xy 304.006152 -292.454861) (xy 304.021736 -292.501542) (xy 304.029631 -292.550119) (xy 304.030126 -292.574726)
			(xy 304.368974 -292.574726) (xy 304.372934 -292.525672) (xy 304.384711 -292.477888) (xy 304.404002 -292.432612)
			(xy 304.430305 -292.391016) (xy 304.46294 -292.354179) (xy 304.501061 -292.323054) (xy 304.543682 -292.298447)
			(xy 304.589698 -292.280995) (xy 304.637917 -292.271151) (xy 304.687092 -292.26917) (xy 304.735947 -292.275102)
			(xy 304.783218 -292.288794) (xy 304.82768 -292.309892) (xy 304.868183 -292.337848) (xy 304.903676 -292.37194)
			(xy 304.933241 -292.411284) (xy 304.956112 -292.454861) (xy 304.971696 -292.501542) (xy 304.979591 -292.550119)
			(xy 304.980086 -292.574726) (xy 305.318934 -292.574726) (xy 305.322894 -292.525672) (xy 305.334671 -292.477888)
			(xy 305.353962 -292.432612) (xy 305.380265 -292.391016) (xy 305.4129 -292.354179) (xy 305.451021 -292.323054)
			(xy 305.493642 -292.298447) (xy 305.539658 -292.280995) (xy 305.587877 -292.271151) (xy 305.637052 -292.26917)
			(xy 305.685907 -292.275102) (xy 305.733178 -292.288794) (xy 305.77764 -292.309892) (xy 305.818143 -292.337848)
			(xy 305.853636 -292.37194) (xy 305.883201 -292.411284) (xy 305.906072 -292.454861) (xy 305.921656 -292.501542)
			(xy 305.929551 -292.550119) (xy 305.930046 -292.574726) (xy 306.268894 -292.574726) (xy 306.272854 -292.525672)
			(xy 306.284631 -292.477888) (xy 306.303922 -292.432612) (xy 306.330225 -292.391016) (xy 306.36286 -292.354179)
			(xy 306.400981 -292.323054) (xy 306.443602 -292.298447) (xy 306.489618 -292.280995) (xy 306.537837 -292.271151)
			(xy 306.587012 -292.26917) (xy 306.635867 -292.275102) (xy 306.683138 -292.288794) (xy 306.7276 -292.309892)
			(xy 306.768103 -292.337848) (xy 306.803596 -292.37194) (xy 306.833161 -292.411284) (xy 306.856032 -292.454861)
			(xy 306.871616 -292.501542) (xy 306.879511 -292.550119) (xy 306.880006 -292.574726) (xy 307.219108 -292.574726)
			(xy 307.223068 -292.525672) (xy 307.234845 -292.477888) (xy 307.254136 -292.432612) (xy 307.280439 -292.391016)
			(xy 307.313074 -292.354179) (xy 307.351195 -292.323054) (xy 307.393816 -292.298447) (xy 307.439832 -292.280995)
			(xy 307.488051 -292.271151) (xy 307.537226 -292.26917) (xy 307.586081 -292.275102) (xy 307.633352 -292.288794)
			(xy 307.677814 -292.309892) (xy 307.718317 -292.337848) (xy 307.75381 -292.37194) (xy 307.783375 -292.411284)
			(xy 307.806246 -292.454861) (xy 307.82183 -292.501542) (xy 307.829725 -292.550119) (xy 307.83022 -292.574726)
			(xy 308.169068 -292.574726) (xy 308.173028 -292.525672) (xy 308.184805 -292.477888) (xy 308.204096 -292.432612)
			(xy 308.230399 -292.391016) (xy 308.263034 -292.354179) (xy 308.301155 -292.323054) (xy 308.343776 -292.298447)
			(xy 308.389792 -292.280995) (xy 308.438011 -292.271151) (xy 308.487186 -292.26917) (xy 308.536041 -292.275102)
			(xy 308.583312 -292.288794) (xy 308.627774 -292.309892) (xy 308.668277 -292.337848) (xy 308.70377 -292.37194)
			(xy 308.733335 -292.411284) (xy 308.756206 -292.454861) (xy 308.77179 -292.501542) (xy 308.779685 -292.550119)
			(xy 308.78018 -292.574726) (xy 309.119028 -292.574726) (xy 309.122988 -292.525672) (xy 309.134765 -292.477888)
			(xy 309.154056 -292.432612) (xy 309.180359 -292.391016) (xy 309.212994 -292.354179) (xy 309.251115 -292.323054)
			(xy 309.293736 -292.298447) (xy 309.339752 -292.280995) (xy 309.387971 -292.271151) (xy 309.437146 -292.26917)
			(xy 309.486001 -292.275102) (xy 309.533272 -292.288794) (xy 309.577734 -292.309892) (xy 309.618237 -292.337848)
			(xy 309.65373 -292.37194) (xy 309.683295 -292.411284) (xy 309.706166 -292.454861) (xy 309.72175 -292.501542)
			(xy 309.729645 -292.550119) (xy 309.73014 -292.574726) (xy 310.068988 -292.574726) (xy 310.072948 -292.525672)
			(xy 310.084725 -292.477888) (xy 310.104016 -292.432612) (xy 310.130319 -292.391016) (xy 310.162954 -292.354179)
			(xy 310.201075 -292.323054) (xy 310.243696 -292.298447) (xy 310.289712 -292.280995) (xy 310.337931 -292.271151)
			(xy 310.387106 -292.26917) (xy 310.435961 -292.275102) (xy 310.483232 -292.288794) (xy 310.527694 -292.309892)
			(xy 310.568197 -292.337848) (xy 310.60369 -292.37194) (xy 310.633255 -292.411284) (xy 310.656126 -292.454861)
			(xy 310.67171 -292.501542) (xy 310.679605 -292.550119) (xy 310.6801 -292.574726) (xy 311.018948 -292.574726)
			(xy 311.022908 -292.525672) (xy 311.034685 -292.477888) (xy 311.053976 -292.432612) (xy 311.080279 -292.391016)
			(xy 311.112914 -292.354179) (xy 311.151035 -292.323054) (xy 311.193656 -292.298447) (xy 311.239672 -292.280995)
			(xy 311.287891 -292.271151) (xy 311.337066 -292.26917) (xy 311.385921 -292.275102) (xy 311.433192 -292.288794)
			(xy 311.477654 -292.309892) (xy 311.518157 -292.337848) (xy 311.55365 -292.37194) (xy 311.583215 -292.411284)
			(xy 311.606086 -292.454861) (xy 311.62167 -292.501542) (xy 311.629565 -292.550119) (xy 311.63006 -292.574726)
			(xy 311.968908 -292.574726) (xy 311.972868 -292.525672) (xy 311.984645 -292.477888) (xy 312.003936 -292.432612)
			(xy 312.030239 -292.391016) (xy 312.062874 -292.354179) (xy 312.100995 -292.323054) (xy 312.143616 -292.298447)
			(xy 312.189632 -292.280995) (xy 312.237851 -292.271151) (xy 312.287026 -292.26917) (xy 312.335881 -292.275102)
			(xy 312.383152 -292.288794) (xy 312.427614 -292.309892) (xy 312.468117 -292.337848) (xy 312.50361 -292.37194)
			(xy 312.533175 -292.411284) (xy 312.556046 -292.454861) (xy 312.57163 -292.501542) (xy 312.579525 -292.550119)
			(xy 312.58002 -292.574726) (xy 312.919122 -292.574726) (xy 312.923082 -292.525672) (xy 312.934859 -292.477888)
			(xy 312.95415 -292.432612) (xy 312.980453 -292.391016) (xy 313.013088 -292.354179) (xy 313.051209 -292.323054)
			(xy 313.09383 -292.298447) (xy 313.139846 -292.280995) (xy 313.188065 -292.271151) (xy 313.23724 -292.26917)
			(xy 313.286095 -292.275102) (xy 313.333366 -292.288794) (xy 313.377828 -292.309892) (xy 313.418331 -292.337848)
			(xy 313.453824 -292.37194) (xy 313.483389 -292.411284) (xy 313.50626 -292.454861) (xy 313.521844 -292.501542)
			(xy 313.529739 -292.550119) (xy 313.530234 -292.574726) (xy 313.530229 -292.57498) (xy 313.869082 -292.57498)
			(xy 313.873042 -292.525926) (xy 313.884819 -292.478142) (xy 313.90411 -292.432866) (xy 313.930413 -292.39127)
			(xy 313.963048 -292.354433) (xy 314.001169 -292.323308) (xy 314.04379 -292.298701) (xy 314.089806 -292.281249)
			(xy 314.138025 -292.271405) (xy 314.1872 -292.269424) (xy 314.236055 -292.275356) (xy 314.283326 -292.289048)
			(xy 314.327788 -292.310146) (xy 314.368291 -292.338102) (xy 314.403784 -292.372194) (xy 314.433349 -292.411538)
			(xy 314.45622 -292.455115) (xy 314.471804 -292.501796) (xy 314.479699 -292.550373) (xy 314.480194 -292.57498)
			(xy 314.819042 -292.57498) (xy 314.823002 -292.525926) (xy 314.834779 -292.478142) (xy 314.85407 -292.432866)
			(xy 314.880373 -292.39127) (xy 314.913008 -292.354433) (xy 314.951129 -292.323308) (xy 314.99375 -292.298701)
			(xy 315.039766 -292.281249) (xy 315.087985 -292.271405) (xy 315.13716 -292.269424) (xy 315.186015 -292.275356)
			(xy 315.233286 -292.289048) (xy 315.277748 -292.310146) (xy 315.318251 -292.338102) (xy 315.353744 -292.372194)
			(xy 315.383309 -292.411538) (xy 315.40618 -292.455115) (xy 315.421764 -292.501796) (xy 315.429659 -292.550373)
			(xy 315.430154 -292.57498) (xy 315.429659 -292.599587) (xy 315.421764 -292.648164) (xy 315.40618 -292.694845)
			(xy 315.383309 -292.738422) (xy 315.353744 -292.777766) (xy 315.318251 -292.811858) (xy 315.277748 -292.839814)
			(xy 315.233286 -292.860912) (xy 315.186015 -292.874604) (xy 315.13716 -292.880536) (xy 315.087985 -292.878555)
			(xy 315.039766 -292.868711) (xy 314.99375 -292.851259) (xy 314.951129 -292.826652) (xy 314.913008 -292.795527)
			(xy 314.880373 -292.75869) (xy 314.85407 -292.717094) (xy 314.834779 -292.671818) (xy 314.823002 -292.624034)
			(xy 314.819042 -292.57498) (xy 314.480194 -292.57498) (xy 314.479699 -292.599587) (xy 314.471804 -292.648164)
			(xy 314.45622 -292.694845) (xy 314.433349 -292.738422) (xy 314.403784 -292.777766) (xy 314.368291 -292.811858)
			(xy 314.327788 -292.839814) (xy 314.283326 -292.860912) (xy 314.236055 -292.874604) (xy 314.1872 -292.880536)
			(xy 314.138025 -292.878555) (xy 314.089806 -292.868711) (xy 314.04379 -292.851259) (xy 314.001169 -292.826652)
			(xy 313.963048 -292.795527) (xy 313.930413 -292.75869) (xy 313.90411 -292.717094) (xy 313.884819 -292.671818)
			(xy 313.873042 -292.624034) (xy 313.869082 -292.57498) (xy 313.530229 -292.57498) (xy 313.529739 -292.599333)
			(xy 313.521844 -292.64791) (xy 313.50626 -292.694591) (xy 313.483389 -292.738168) (xy 313.453824 -292.777512)
			(xy 313.418331 -292.811604) (xy 313.377828 -292.83956) (xy 313.333366 -292.860658) (xy 313.286095 -292.87435)
			(xy 313.23724 -292.880282) (xy 313.188065 -292.878301) (xy 313.139846 -292.868457) (xy 313.09383 -292.851005)
			(xy 313.051209 -292.826398) (xy 313.013088 -292.795273) (xy 312.980453 -292.758436) (xy 312.95415 -292.71684)
			(xy 312.934859 -292.671564) (xy 312.923082 -292.62378) (xy 312.919122 -292.574726) (xy 312.58002 -292.574726)
			(xy 312.579525 -292.599333) (xy 312.57163 -292.64791) (xy 312.556046 -292.694591) (xy 312.533175 -292.738168)
			(xy 312.50361 -292.777512) (xy 312.468117 -292.811604) (xy 312.427614 -292.83956) (xy 312.383152 -292.860658)
			(xy 312.335881 -292.87435) (xy 312.287026 -292.880282) (xy 312.237851 -292.878301) (xy 312.189632 -292.868457)
			(xy 312.143616 -292.851005) (xy 312.100995 -292.826398) (xy 312.062874 -292.795273) (xy 312.030239 -292.758436)
			(xy 312.003936 -292.71684) (xy 311.984645 -292.671564) (xy 311.972868 -292.62378) (xy 311.968908 -292.574726)
			(xy 311.63006 -292.574726) (xy 311.629565 -292.599333) (xy 311.62167 -292.64791) (xy 311.606086 -292.694591)
			(xy 311.583215 -292.738168) (xy 311.55365 -292.777512) (xy 311.518157 -292.811604) (xy 311.477654 -292.83956)
			(xy 311.433192 -292.860658) (xy 311.385921 -292.87435) (xy 311.337066 -292.880282) (xy 311.287891 -292.878301)
			(xy 311.239672 -292.868457) (xy 311.193656 -292.851005) (xy 311.151035 -292.826398) (xy 311.112914 -292.795273)
			(xy 311.080279 -292.758436) (xy 311.053976 -292.71684) (xy 311.034685 -292.671564) (xy 311.022908 -292.62378)
			(xy 311.018948 -292.574726) (xy 310.6801 -292.574726) (xy 310.679605 -292.599333) (xy 310.67171 -292.64791)
			(xy 310.656126 -292.694591) (xy 310.633255 -292.738168) (xy 310.60369 -292.777512) (xy 310.568197 -292.811604)
			(xy 310.527694 -292.83956) (xy 310.483232 -292.860658) (xy 310.435961 -292.87435) (xy 310.387106 -292.880282)
			(xy 310.337931 -292.878301) (xy 310.289712 -292.868457) (xy 310.243696 -292.851005) (xy 310.201075 -292.826398)
			(xy 310.162954 -292.795273) (xy 310.130319 -292.758436) (xy 310.104016 -292.71684) (xy 310.084725 -292.671564)
			(xy 310.072948 -292.62378) (xy 310.068988 -292.574726) (xy 309.73014 -292.574726) (xy 309.729645 -292.599333)
			(xy 309.72175 -292.64791) (xy 309.706166 -292.694591) (xy 309.683295 -292.738168) (xy 309.65373 -292.777512)
			(xy 309.618237 -292.811604) (xy 309.577734 -292.83956) (xy 309.533272 -292.860658) (xy 309.486001 -292.87435)
			(xy 309.437146 -292.880282) (xy 309.387971 -292.878301) (xy 309.339752 -292.868457) (xy 309.293736 -292.851005)
			(xy 309.251115 -292.826398) (xy 309.212994 -292.795273) (xy 309.180359 -292.758436) (xy 309.154056 -292.71684)
			(xy 309.134765 -292.671564) (xy 309.122988 -292.62378) (xy 309.119028 -292.574726) (xy 308.78018 -292.574726)
			(xy 308.779685 -292.599333) (xy 308.77179 -292.64791) (xy 308.756206 -292.694591) (xy 308.733335 -292.738168)
			(xy 308.70377 -292.777512) (xy 308.668277 -292.811604) (xy 308.627774 -292.83956) (xy 308.583312 -292.860658)
			(xy 308.536041 -292.87435) (xy 308.487186 -292.880282) (xy 308.438011 -292.878301) (xy 308.389792 -292.868457)
			(xy 308.343776 -292.851005) (xy 308.301155 -292.826398) (xy 308.263034 -292.795273) (xy 308.230399 -292.758436)
			(xy 308.204096 -292.71684) (xy 308.184805 -292.671564) (xy 308.173028 -292.62378) (xy 308.169068 -292.574726)
			(xy 307.83022 -292.574726) (xy 307.829725 -292.599333) (xy 307.82183 -292.64791) (xy 307.806246 -292.694591)
			(xy 307.783375 -292.738168) (xy 307.75381 -292.777512) (xy 307.718317 -292.811604) (xy 307.677814 -292.83956)
			(xy 307.633352 -292.860658) (xy 307.586081 -292.87435) (xy 307.537226 -292.880282) (xy 307.488051 -292.878301)
			(xy 307.439832 -292.868457) (xy 307.393816 -292.851005) (xy 307.351195 -292.826398) (xy 307.313074 -292.795273)
			(xy 307.280439 -292.758436) (xy 307.254136 -292.71684) (xy 307.234845 -292.671564) (xy 307.223068 -292.62378)
			(xy 307.219108 -292.574726) (xy 306.880006 -292.574726) (xy 306.879511 -292.599333) (xy 306.871616 -292.64791)
			(xy 306.856032 -292.694591) (xy 306.833161 -292.738168) (xy 306.803596 -292.777512) (xy 306.768103 -292.811604)
			(xy 306.7276 -292.83956) (xy 306.683138 -292.860658) (xy 306.635867 -292.87435) (xy 306.587012 -292.880282)
			(xy 306.537837 -292.878301) (xy 306.489618 -292.868457) (xy 306.443602 -292.851005) (xy 306.400981 -292.826398)
			(xy 306.36286 -292.795273) (xy 306.330225 -292.758436) (xy 306.303922 -292.71684) (xy 306.284631 -292.671564)
			(xy 306.272854 -292.62378) (xy 306.268894 -292.574726) (xy 305.930046 -292.574726) (xy 305.929551 -292.599333)
			(xy 305.921656 -292.64791) (xy 305.906072 -292.694591) (xy 305.883201 -292.738168) (xy 305.853636 -292.777512)
			(xy 305.818143 -292.811604) (xy 305.77764 -292.83956) (xy 305.733178 -292.860658) (xy 305.685907 -292.87435)
			(xy 305.637052 -292.880282) (xy 305.587877 -292.878301) (xy 305.539658 -292.868457) (xy 305.493642 -292.851005)
			(xy 305.451021 -292.826398) (xy 305.4129 -292.795273) (xy 305.380265 -292.758436) (xy 305.353962 -292.71684)
			(xy 305.334671 -292.671564) (xy 305.322894 -292.62378) (xy 305.318934 -292.574726) (xy 304.980086 -292.574726)
			(xy 304.979591 -292.599333) (xy 304.971696 -292.64791) (xy 304.956112 -292.694591) (xy 304.933241 -292.738168)
			(xy 304.903676 -292.777512) (xy 304.868183 -292.811604) (xy 304.82768 -292.83956) (xy 304.783218 -292.860658)
			(xy 304.735947 -292.87435) (xy 304.687092 -292.880282) (xy 304.637917 -292.878301) (xy 304.589698 -292.868457)
			(xy 304.543682 -292.851005) (xy 304.501061 -292.826398) (xy 304.46294 -292.795273) (xy 304.430305 -292.758436)
			(xy 304.404002 -292.71684) (xy 304.384711 -292.671564) (xy 304.372934 -292.62378) (xy 304.368974 -292.574726)
			(xy 304.030126 -292.574726) (xy 304.029631 -292.599333) (xy 304.021736 -292.64791) (xy 304.006152 -292.694591)
			(xy 303.983281 -292.738168) (xy 303.953716 -292.777512) (xy 303.918223 -292.811604) (xy 303.87772 -292.83956)
			(xy 303.833258 -292.860658) (xy 303.785987 -292.87435) (xy 303.737132 -292.880282) (xy 303.687957 -292.878301)
			(xy 303.639738 -292.868457) (xy 303.593722 -292.851005) (xy 303.551101 -292.826398) (xy 303.51298 -292.795273)
			(xy 303.480345 -292.758436) (xy 303.454042 -292.71684) (xy 303.434751 -292.671564) (xy 303.422974 -292.62378)
			(xy 303.419014 -292.574726) (xy 303.080161 -292.574726) (xy 303.080166 -292.57498) (xy 303.079671 -292.599587)
			(xy 303.071776 -292.648164) (xy 303.056192 -292.694845) (xy 303.033321 -292.738422) (xy 303.003756 -292.777766)
			(xy 302.968263 -292.811858) (xy 302.92776 -292.839814) (xy 302.883298 -292.860912) (xy 302.836027 -292.874604)
			(xy 302.787172 -292.880536) (xy 302.737997 -292.878555) (xy 302.689778 -292.868711) (xy 302.643762 -292.851259)
			(xy 302.601141 -292.826652) (xy 302.56302 -292.795527) (xy 302.530385 -292.75869) (xy 302.504082 -292.717094)
			(xy 302.484791 -292.671818) (xy 302.473014 -292.624034) (xy 302.469054 -292.57498) (xy 302.130201 -292.57498)
			(xy 302.129711 -292.599333) (xy 302.121816 -292.64791) (xy 302.106232 -292.694591) (xy 302.083361 -292.738168)
			(xy 302.053796 -292.777512) (xy 302.018303 -292.811604) (xy 301.9778 -292.83956) (xy 301.933338 -292.860658)
			(xy 301.886067 -292.87435) (xy 301.837212 -292.880282) (xy 301.788037 -292.878301) (xy 301.739818 -292.868457)
			(xy 301.693802 -292.851005) (xy 301.651181 -292.826398) (xy 301.61306 -292.795273) (xy 301.580425 -292.758436)
			(xy 301.554122 -292.71684) (xy 301.534831 -292.671564) (xy 301.523054 -292.62378) (xy 301.519094 -292.574726)
			(xy 301.179992 -292.574726) (xy 301.179497 -292.599333) (xy 301.171602 -292.64791) (xy 301.156018 -292.694591)
			(xy 301.133147 -292.738168) (xy 301.103582 -292.777512) (xy 301.068089 -292.811604) (xy 301.027586 -292.83956)
			(xy 300.983124 -292.860658) (xy 300.935853 -292.87435) (xy 300.886998 -292.880282) (xy 300.837823 -292.878301)
			(xy 300.789604 -292.868457) (xy 300.743588 -292.851005) (xy 300.700967 -292.826398) (xy 300.662846 -292.795273)
			(xy 300.630211 -292.758436) (xy 300.603908 -292.71684) (xy 300.584617 -292.671564) (xy 300.57284 -292.62378)
			(xy 300.56888 -292.574726) (xy 300.230032 -292.574726) (xy 300.229537 -292.599333) (xy 300.221642 -292.64791)
			(xy 300.206058 -292.694591) (xy 300.183187 -292.738168) (xy 300.153622 -292.777512) (xy 300.118129 -292.811604)
			(xy 300.077626 -292.83956) (xy 300.033164 -292.860658) (xy 299.985893 -292.87435) (xy 299.937038 -292.880282)
			(xy 299.887863 -292.878301) (xy 299.839644 -292.868457) (xy 299.793628 -292.851005) (xy 299.751007 -292.826398)
			(xy 299.712886 -292.795273) (xy 299.680251 -292.758436) (xy 299.653948 -292.71684) (xy 299.634657 -292.671564)
			(xy 299.62288 -292.62378) (xy 299.61892 -292.574726) (xy 299.280072 -292.574726) (xy 299.279577 -292.599333)
			(xy 299.271682 -292.64791) (xy 299.256098 -292.694591) (xy 299.233227 -292.738168) (xy 299.203662 -292.777512)
			(xy 299.168169 -292.811604) (xy 299.127666 -292.83956) (xy 299.083204 -292.860658) (xy 299.035933 -292.87435)
			(xy 298.987078 -292.880282) (xy 298.937903 -292.878301) (xy 298.889684 -292.868457) (xy 298.843668 -292.851005)
			(xy 298.801047 -292.826398) (xy 298.762926 -292.795273) (xy 298.730291 -292.758436) (xy 298.703988 -292.71684)
			(xy 298.684697 -292.671564) (xy 298.67292 -292.62378) (xy 298.66896 -292.574726) (xy 298.330112 -292.574726)
			(xy 298.329617 -292.599333) (xy 298.321722 -292.64791) (xy 298.306138 -292.694591) (xy 298.283267 -292.738168)
			(xy 298.253702 -292.777512) (xy 298.218209 -292.811604) (xy 298.177706 -292.83956) (xy 298.133244 -292.860658)
			(xy 298.085973 -292.87435) (xy 298.037118 -292.880282) (xy 297.987943 -292.878301) (xy 297.939724 -292.868457)
			(xy 297.893708 -292.851005) (xy 297.851087 -292.826398) (xy 297.812966 -292.795273) (xy 297.780331 -292.758436)
			(xy 297.754028 -292.71684) (xy 297.734737 -292.671564) (xy 297.72296 -292.62378) (xy 297.719 -292.574726)
			(xy 297.380152 -292.574726) (xy 297.379657 -292.599333) (xy 297.371762 -292.64791) (xy 297.356178 -292.694591)
			(xy 297.333307 -292.738168) (xy 297.303742 -292.777512) (xy 297.268249 -292.811604) (xy 297.227746 -292.83956)
			(xy 297.183284 -292.860658) (xy 297.136013 -292.87435) (xy 297.087158 -292.880282) (xy 297.037983 -292.878301)
			(xy 296.989764 -292.868457) (xy 296.943748 -292.851005) (xy 296.901127 -292.826398) (xy 296.863006 -292.795273)
			(xy 296.830371 -292.758436) (xy 296.804068 -292.71684) (xy 296.784777 -292.671564) (xy 296.773 -292.62378)
			(xy 296.76904 -292.574726) (xy 296.430192 -292.574726) (xy 296.429697 -292.599333) (xy 296.421802 -292.64791)
			(xy 296.406218 -292.694591) (xy 296.383347 -292.738168) (xy 296.353782 -292.777512) (xy 296.318289 -292.811604)
			(xy 296.277786 -292.83956) (xy 296.233324 -292.860658) (xy 296.186053 -292.87435) (xy 296.137198 -292.880282)
			(xy 296.088023 -292.878301) (xy 296.039804 -292.868457) (xy 295.993788 -292.851005) (xy 295.951167 -292.826398)
			(xy 295.913046 -292.795273) (xy 295.880411 -292.758436) (xy 295.854108 -292.71684) (xy 295.834817 -292.671564)
			(xy 295.82304 -292.62378) (xy 295.81908 -292.574726) (xy 295.480232 -292.574726) (xy 295.479737 -292.599333)
			(xy 295.471842 -292.64791) (xy 295.456258 -292.694591) (xy 295.433387 -292.738168) (xy 295.403822 -292.777512)
			(xy 295.368329 -292.811604) (xy 295.327826 -292.83956) (xy 295.283364 -292.860658) (xy 295.236093 -292.87435)
			(xy 295.187238 -292.880282) (xy 295.138063 -292.878301) (xy 295.089844 -292.868457) (xy 295.043828 -292.851005)
			(xy 295.001207 -292.826398) (xy 294.963086 -292.795273) (xy 294.930451 -292.758436) (xy 294.904148 -292.71684)
			(xy 294.884857 -292.671564) (xy 294.87308 -292.62378) (xy 294.86912 -292.574726) (xy 294.530018 -292.574726)
			(xy 294.529523 -292.599333) (xy 294.521628 -292.64791) (xy 294.506044 -292.694591) (xy 294.483173 -292.738168)
			(xy 294.453608 -292.777512) (xy 294.418115 -292.811604) (xy 294.377612 -292.83956) (xy 294.33315 -292.860658)
			(xy 294.285879 -292.87435) (xy 294.237024 -292.880282) (xy 294.187849 -292.878301) (xy 294.13963 -292.868457)
			(xy 294.093614 -292.851005) (xy 294.050993 -292.826398) (xy 294.012872 -292.795273) (xy 293.980237 -292.758436)
			(xy 293.953934 -292.71684) (xy 293.934643 -292.671564) (xy 293.922866 -292.62378) (xy 293.918906 -292.574726)
			(xy 293.580058 -292.574726) (xy 293.579563 -292.599333) (xy 293.571668 -292.64791) (xy 293.556084 -292.694591)
			(xy 293.533213 -292.738168) (xy 293.503648 -292.777512) (xy 293.468155 -292.811604) (xy 293.427652 -292.83956)
			(xy 293.38319 -292.860658) (xy 293.335919 -292.87435) (xy 293.287064 -292.880282) (xy 293.237889 -292.878301)
			(xy 293.18967 -292.868457) (xy 293.143654 -292.851005) (xy 293.101033 -292.826398) (xy 293.062912 -292.795273)
			(xy 293.030277 -292.758436) (xy 293.003974 -292.71684) (xy 292.984683 -292.671564) (xy 292.972906 -292.62378)
			(xy 292.968946 -292.574726) (xy 292.630098 -292.574726) (xy 292.629603 -292.599333) (xy 292.621708 -292.64791)
			(xy 292.606124 -292.694591) (xy 292.583253 -292.738168) (xy 292.553688 -292.777512) (xy 292.518195 -292.811604)
			(xy 292.477692 -292.83956) (xy 292.43323 -292.860658) (xy 292.385959 -292.87435) (xy 292.337104 -292.880282)
			(xy 292.287929 -292.878301) (xy 292.23971 -292.868457) (xy 292.193694 -292.851005) (xy 292.151073 -292.826398)
			(xy 292.112952 -292.795273) (xy 292.080317 -292.758436) (xy 292.054014 -292.71684) (xy 292.034723 -292.671564)
			(xy 292.022946 -292.62378) (xy 292.018986 -292.574726) (xy 290.730173 -292.574726) (xy 290.730178 -292.57498)
			(xy 290.729683 -292.599587) (xy 290.721788 -292.648164) (xy 290.706204 -292.694845) (xy 290.683333 -292.738422)
			(xy 290.653768 -292.777766) (xy 290.618275 -292.811858) (xy 290.577772 -292.839814) (xy 290.53331 -292.860912)
			(xy 290.486039 -292.874604) (xy 290.437184 -292.880536) (xy 290.388009 -292.878555) (xy 290.33979 -292.868711)
			(xy 290.293774 -292.851259) (xy 290.251153 -292.826652) (xy 290.213032 -292.795527) (xy 290.180397 -292.75869)
			(xy 290.154094 -292.717094) (xy 290.134803 -292.671818) (xy 290.123026 -292.624034) (xy 290.119066 -292.57498)
			(xy 289.780218 -292.57498) (xy 289.779723 -292.599587) (xy 289.771828 -292.648164) (xy 289.756244 -292.694845)
			(xy 289.733373 -292.738422) (xy 289.703808 -292.777766) (xy 289.668315 -292.811858) (xy 289.627812 -292.839814)
			(xy 289.58335 -292.860912) (xy 289.536079 -292.874604) (xy 289.487224 -292.880536) (xy 289.438049 -292.878555)
			(xy 289.38983 -292.868711) (xy 289.343814 -292.851259) (xy 289.301193 -292.826652) (xy 289.263072 -292.795527)
			(xy 289.230437 -292.75869) (xy 289.204134 -292.717094) (xy 289.184843 -292.671818) (xy 289.173066 -292.624034)
			(xy 289.169106 -292.57498) (xy 288.830258 -292.57498) (xy 288.829763 -292.599587) (xy 288.821868 -292.648164)
			(xy 288.806284 -292.694845) (xy 288.783413 -292.738422) (xy 288.753848 -292.777766) (xy 288.718355 -292.811858)
			(xy 288.677852 -292.839814) (xy 288.63339 -292.860912) (xy 288.586119 -292.874604) (xy 288.537264 -292.880536)
			(xy 288.488089 -292.878555) (xy 288.43987 -292.868711) (xy 288.393854 -292.851259) (xy 288.351233 -292.826652)
			(xy 288.313112 -292.795527) (xy 288.280477 -292.75869) (xy 288.254174 -292.717094) (xy 288.234883 -292.671818)
			(xy 288.223106 -292.624034) (xy 288.219146 -292.57498) (xy 287.880044 -292.57498) (xy 287.879549 -292.599587)
			(xy 287.871654 -292.648164) (xy 287.85607 -292.694845) (xy 287.833199 -292.738422) (xy 287.803634 -292.777766)
			(xy 287.768141 -292.811858) (xy 287.727638 -292.839814) (xy 287.683176 -292.860912) (xy 287.635905 -292.874604)
			(xy 287.58705 -292.880536) (xy 287.537875 -292.878555) (xy 287.489656 -292.868711) (xy 287.44364 -292.851259)
			(xy 287.401019 -292.826652) (xy 287.362898 -292.795527) (xy 287.330263 -292.75869) (xy 287.30396 -292.717094)
			(xy 287.284669 -292.671818) (xy 287.272892 -292.624034) (xy 287.268932 -292.57498) (xy 286.930084 -292.57498)
			(xy 286.929589 -292.599587) (xy 286.921694 -292.648164) (xy 286.90611 -292.694845) (xy 286.883239 -292.738422)
			(xy 286.853674 -292.777766) (xy 286.818181 -292.811858) (xy 286.777678 -292.839814) (xy 286.733216 -292.860912)
			(xy 286.685945 -292.874604) (xy 286.63709 -292.880536) (xy 286.587915 -292.878555) (xy 286.539696 -292.868711)
			(xy 286.49368 -292.851259) (xy 286.451059 -292.826652) (xy 286.412938 -292.795527) (xy 286.380303 -292.75869)
			(xy 286.354 -292.717094) (xy 286.334709 -292.671818) (xy 286.322932 -292.624034) (xy 286.318972 -292.57498)
			(xy 285.980124 -292.57498) (xy 285.979629 -292.599587) (xy 285.971734 -292.648164) (xy 285.95615 -292.694845)
			(xy 285.933279 -292.738422) (xy 285.903714 -292.777766) (xy 285.868221 -292.811858) (xy 285.827718 -292.839814)
			(xy 285.783256 -292.860912) (xy 285.735985 -292.874604) (xy 285.68713 -292.880536) (xy 285.637955 -292.878555)
			(xy 285.589736 -292.868711) (xy 285.54372 -292.851259) (xy 285.501099 -292.826652) (xy 285.462978 -292.795527)
			(xy 285.430343 -292.75869) (xy 285.40404 -292.717094) (xy 285.384749 -292.671818) (xy 285.372972 -292.624034)
			(xy 285.369012 -292.57498) (xy 285.030164 -292.57498) (xy 285.029669 -292.599587) (xy 285.021774 -292.648164)
			(xy 285.00619 -292.694845) (xy 284.983319 -292.738422) (xy 284.953754 -292.777766) (xy 284.918261 -292.811858)
			(xy 284.877758 -292.839814) (xy 284.833296 -292.860912) (xy 284.786025 -292.874604) (xy 284.73717 -292.880536)
			(xy 284.687995 -292.878555) (xy 284.639776 -292.868711) (xy 284.59376 -292.851259) (xy 284.551139 -292.826652)
			(xy 284.513018 -292.795527) (xy 284.480383 -292.75869) (xy 284.45408 -292.717094) (xy 284.434789 -292.671818)
			(xy 284.423012 -292.624034) (xy 284.419052 -292.57498) (xy 284.080204 -292.57498) (xy 284.079709 -292.599587)
			(xy 284.071814 -292.648164) (xy 284.05623 -292.694845) (xy 284.033359 -292.738422) (xy 284.003794 -292.777766)
			(xy 283.968301 -292.811858) (xy 283.927798 -292.839814) (xy 283.883336 -292.860912) (xy 283.836065 -292.874604)
			(xy 283.78721 -292.880536) (xy 283.738035 -292.878555) (xy 283.689816 -292.868711) (xy 283.6438 -292.851259)
			(xy 283.601179 -292.826652) (xy 283.563058 -292.795527) (xy 283.530423 -292.75869) (xy 283.50412 -292.717094)
			(xy 283.484829 -292.671818) (xy 283.473052 -292.624034) (xy 283.469092 -292.57498) (xy 283.130244 -292.57498)
			(xy 283.129749 -292.599587) (xy 283.121854 -292.648164) (xy 283.10627 -292.694845) (xy 283.083399 -292.738422)
			(xy 283.053834 -292.777766) (xy 283.018341 -292.811858) (xy 282.977838 -292.839814) (xy 282.933376 -292.860912)
			(xy 282.886105 -292.874604) (xy 282.83725 -292.880536) (xy 282.788075 -292.878555) (xy 282.739856 -292.868711)
			(xy 282.69384 -292.851259) (xy 282.651219 -292.826652) (xy 282.613098 -292.795527) (xy 282.580463 -292.75869)
			(xy 282.55416 -292.717094) (xy 282.534869 -292.671818) (xy 282.523092 -292.624034) (xy 282.519132 -292.57498)
			(xy 282.180482 -292.57498) (xy 282.176335 -292.625032) (xy 282.163937 -292.67399) (xy 282.143651 -292.720241)
			(xy 282.116029 -292.762522) (xy 282.081825 -292.79968) (xy 282.041971 -292.830702) (xy 281.997555 -292.854742)
			(xy 281.949789 -292.871143) (xy 281.899974 -292.879459) (xy 281.874722 -292.880034) (xy 281.844648 -292.87934)
			(xy 281.785663 -292.867572) (xy 281.757628 -292.856666) (xy 281.745436 -292.851586) (xy 281.720544 -292.854126)
			(xy 281.639518 -292.908228) (xy 281.629467 -292.91575) (xy 281.617632 -292.937857) (xy 281.616912 -292.950392)
			(xy 281.616912 -293.52494) (xy 282.519132 -293.52494) (xy 282.523092 -293.475886) (xy 282.534869 -293.428102)
			(xy 282.55416 -293.382826) (xy 282.580463 -293.34123) (xy 282.613098 -293.304393) (xy 282.651219 -293.273268)
			(xy 282.69384 -293.248661) (xy 282.739856 -293.231209) (xy 282.788075 -293.221365) (xy 282.83725 -293.219384)
			(xy 282.886105 -293.225316) (xy 282.933376 -293.239008) (xy 282.977838 -293.260106) (xy 283.018341 -293.288062)
			(xy 283.053834 -293.322154) (xy 283.083399 -293.361498) (xy 283.10627 -293.405075) (xy 283.121854 -293.451756)
			(xy 283.129749 -293.500333) (xy 283.130244 -293.52494) (xy 284.419052 -293.52494) (xy 284.423012 -293.475886)
			(xy 284.434789 -293.428102) (xy 284.45408 -293.382826) (xy 284.480383 -293.34123) (xy 284.513018 -293.304393)
			(xy 284.551139 -293.273268) (xy 284.59376 -293.248661) (xy 284.639776 -293.231209) (xy 284.687995 -293.221365)
			(xy 284.73717 -293.219384) (xy 284.786025 -293.225316) (xy 284.833296 -293.239008) (xy 284.877758 -293.260106)
			(xy 284.918261 -293.288062) (xy 284.953754 -293.322154) (xy 284.983319 -293.361498) (xy 285.00619 -293.405075)
			(xy 285.021774 -293.451756) (xy 285.029669 -293.500333) (xy 285.030164 -293.52494) (xy 286.318972 -293.52494)
			(xy 286.322932 -293.475886) (xy 286.334709 -293.428102) (xy 286.354 -293.382826) (xy 286.380303 -293.34123)
			(xy 286.412938 -293.304393) (xy 286.451059 -293.273268) (xy 286.49368 -293.248661) (xy 286.539696 -293.231209)
			(xy 286.587915 -293.221365) (xy 286.63709 -293.219384) (xy 286.685945 -293.225316) (xy 286.733216 -293.239008)
			(xy 286.777678 -293.260106) (xy 286.818181 -293.288062) (xy 286.853674 -293.322154) (xy 286.883239 -293.361498)
			(xy 286.90611 -293.405075) (xy 286.921694 -293.451756) (xy 286.929589 -293.500333) (xy 286.930084 -293.52494)
			(xy 288.218892 -293.52494) (xy 288.222852 -293.475886) (xy 288.234629 -293.428102) (xy 288.25392 -293.382826)
			(xy 288.280223 -293.34123) (xy 288.312858 -293.304393) (xy 288.350979 -293.273268) (xy 288.3936 -293.248661)
			(xy 288.439616 -293.231209) (xy 288.487835 -293.221365) (xy 288.53701 -293.219384) (xy 288.585865 -293.225316)
			(xy 288.633136 -293.239008) (xy 288.677598 -293.260106) (xy 288.718101 -293.288062) (xy 288.753594 -293.322154)
			(xy 288.783159 -293.361498) (xy 288.80603 -293.405075) (xy 288.821614 -293.451756) (xy 288.829509 -293.500333)
			(xy 288.830004 -293.52494) (xy 290.119066 -293.52494) (xy 290.123026 -293.475886) (xy 290.134803 -293.428102)
			(xy 290.154094 -293.382826) (xy 290.180397 -293.34123) (xy 290.213032 -293.304393) (xy 290.251153 -293.273268)
			(xy 290.293774 -293.248661) (xy 290.33979 -293.231209) (xy 290.388009 -293.221365) (xy 290.437184 -293.219384)
			(xy 290.486039 -293.225316) (xy 290.53331 -293.239008) (xy 290.577772 -293.260106) (xy 290.618275 -293.288062)
			(xy 290.653768 -293.322154) (xy 290.683333 -293.361498) (xy 290.706204 -293.405075) (xy 290.721788 -293.451756)
			(xy 290.729683 -293.500333) (xy 290.730178 -293.52494) (xy 292.968946 -293.52494) (xy 292.972906 -293.475886)
			(xy 292.984683 -293.428102) (xy 293.003974 -293.382826) (xy 293.030277 -293.34123) (xy 293.062912 -293.304393)
			(xy 293.101033 -293.273268) (xy 293.143654 -293.248661) (xy 293.18967 -293.231209) (xy 293.237889 -293.221365)
			(xy 293.287064 -293.219384) (xy 293.335919 -293.225316) (xy 293.38319 -293.239008) (xy 293.427652 -293.260106)
			(xy 293.468155 -293.288062) (xy 293.503648 -293.322154) (xy 293.533213 -293.361498) (xy 293.556084 -293.405075)
			(xy 293.571668 -293.451756) (xy 293.579563 -293.500333) (xy 293.580058 -293.52494) (xy 294.86912 -293.52494)
			(xy 294.87308 -293.475886) (xy 294.884857 -293.428102) (xy 294.904148 -293.382826) (xy 294.930451 -293.34123)
			(xy 294.963086 -293.304393) (xy 295.001207 -293.273268) (xy 295.043828 -293.248661) (xy 295.089844 -293.231209)
			(xy 295.138063 -293.221365) (xy 295.187238 -293.219384) (xy 295.236093 -293.225316) (xy 295.283364 -293.239008)
			(xy 295.327826 -293.260106) (xy 295.368329 -293.288062) (xy 295.403822 -293.322154) (xy 295.433387 -293.361498)
			(xy 295.456258 -293.405075) (xy 295.471842 -293.451756) (xy 295.479737 -293.500333) (xy 295.480232 -293.52494)
			(xy 296.76904 -293.52494) (xy 296.773 -293.475886) (xy 296.784777 -293.428102) (xy 296.804068 -293.382826)
			(xy 296.830371 -293.34123) (xy 296.863006 -293.304393) (xy 296.901127 -293.273268) (xy 296.943748 -293.248661)
			(xy 296.989764 -293.231209) (xy 297.037983 -293.221365) (xy 297.087158 -293.219384) (xy 297.136013 -293.225316)
			(xy 297.183284 -293.239008) (xy 297.227746 -293.260106) (xy 297.268249 -293.288062) (xy 297.303742 -293.322154)
			(xy 297.333307 -293.361498) (xy 297.356178 -293.405075) (xy 297.371762 -293.451756) (xy 297.379657 -293.500333)
			(xy 297.380152 -293.52494) (xy 298.66896 -293.52494) (xy 298.67292 -293.475886) (xy 298.684697 -293.428102)
			(xy 298.703988 -293.382826) (xy 298.730291 -293.34123) (xy 298.762926 -293.304393) (xy 298.801047 -293.273268)
			(xy 298.843668 -293.248661) (xy 298.889684 -293.231209) (xy 298.937903 -293.221365) (xy 298.987078 -293.219384)
			(xy 299.035933 -293.225316) (xy 299.083204 -293.239008) (xy 299.127666 -293.260106) (xy 299.168169 -293.288062)
			(xy 299.203662 -293.322154) (xy 299.233227 -293.361498) (xy 299.256098 -293.405075) (xy 299.271682 -293.451756)
			(xy 299.279577 -293.500333) (xy 299.280072 -293.52494) (xy 300.56888 -293.52494) (xy 300.57284 -293.475886)
			(xy 300.584617 -293.428102) (xy 300.603908 -293.382826) (xy 300.630211 -293.34123) (xy 300.662846 -293.304393)
			(xy 300.700967 -293.273268) (xy 300.743588 -293.248661) (xy 300.789604 -293.231209) (xy 300.837823 -293.221365)
			(xy 300.886998 -293.219384) (xy 300.935853 -293.225316) (xy 300.983124 -293.239008) (xy 301.027586 -293.260106)
			(xy 301.068089 -293.288062) (xy 301.103582 -293.322154) (xy 301.133147 -293.361498) (xy 301.156018 -293.405075)
			(xy 301.171602 -293.451756) (xy 301.179497 -293.500333) (xy 301.179992 -293.52494) (xy 301.519094 -293.52494)
			(xy 301.523054 -293.475886) (xy 301.534831 -293.428102) (xy 301.554122 -293.382826) (xy 301.580425 -293.34123)
			(xy 301.61306 -293.304393) (xy 301.651181 -293.273268) (xy 301.693802 -293.248661) (xy 301.739818 -293.231209)
			(xy 301.788037 -293.221365) (xy 301.837212 -293.219384) (xy 301.886067 -293.225316) (xy 301.933338 -293.239008)
			(xy 301.9778 -293.260106) (xy 302.018303 -293.288062) (xy 302.053796 -293.322154) (xy 302.083361 -293.361498)
			(xy 302.106232 -293.405075) (xy 302.121816 -293.451756) (xy 302.129711 -293.500333) (xy 302.130206 -293.52494)
			(xy 302.469054 -293.52494) (xy 302.473014 -293.475886) (xy 302.484791 -293.428102) (xy 302.504082 -293.382826)
			(xy 302.530385 -293.34123) (xy 302.56302 -293.304393) (xy 302.601141 -293.273268) (xy 302.643762 -293.248661)
			(xy 302.689778 -293.231209) (xy 302.737997 -293.221365) (xy 302.787172 -293.219384) (xy 302.836027 -293.225316)
			(xy 302.883298 -293.239008) (xy 302.92776 -293.260106) (xy 302.968263 -293.288062) (xy 303.003756 -293.322154)
			(xy 303.033321 -293.361498) (xy 303.056192 -293.405075) (xy 303.071776 -293.451756) (xy 303.079671 -293.500333)
			(xy 303.080166 -293.52494) (xy 303.419014 -293.52494) (xy 303.422974 -293.475886) (xy 303.434751 -293.428102)
			(xy 303.454042 -293.382826) (xy 303.480345 -293.34123) (xy 303.51298 -293.304393) (xy 303.551101 -293.273268)
			(xy 303.593722 -293.248661) (xy 303.639738 -293.231209) (xy 303.687957 -293.221365) (xy 303.737132 -293.219384)
			(xy 303.785987 -293.225316) (xy 303.833258 -293.239008) (xy 303.87772 -293.260106) (xy 303.918223 -293.288062)
			(xy 303.953716 -293.322154) (xy 303.983281 -293.361498) (xy 304.006152 -293.405075) (xy 304.021736 -293.451756)
			(xy 304.029631 -293.500333) (xy 304.030126 -293.52494) (xy 304.368974 -293.52494) (xy 304.372934 -293.475886)
			(xy 304.384711 -293.428102) (xy 304.404002 -293.382826) (xy 304.430305 -293.34123) (xy 304.46294 -293.304393)
			(xy 304.501061 -293.273268) (xy 304.543682 -293.248661) (xy 304.589698 -293.231209) (xy 304.637917 -293.221365)
			(xy 304.687092 -293.219384) (xy 304.735947 -293.225316) (xy 304.783218 -293.239008) (xy 304.82768 -293.260106)
			(xy 304.868183 -293.288062) (xy 304.903676 -293.322154) (xy 304.933241 -293.361498) (xy 304.956112 -293.405075)
			(xy 304.971696 -293.451756) (xy 304.979591 -293.500333) (xy 304.980086 -293.52494) (xy 305.318934 -293.52494)
			(xy 305.322894 -293.475886) (xy 305.334671 -293.428102) (xy 305.353962 -293.382826) (xy 305.380265 -293.34123)
			(xy 305.4129 -293.304393) (xy 305.451021 -293.273268) (xy 305.493642 -293.248661) (xy 305.539658 -293.231209)
			(xy 305.587877 -293.221365) (xy 305.637052 -293.219384) (xy 305.685907 -293.225316) (xy 305.733178 -293.239008)
			(xy 305.77764 -293.260106) (xy 305.818143 -293.288062) (xy 305.853636 -293.322154) (xy 305.883201 -293.361498)
			(xy 305.906072 -293.405075) (xy 305.921656 -293.451756) (xy 305.929551 -293.500333) (xy 305.930046 -293.52494)
			(xy 306.269148 -293.52494) (xy 306.273108 -293.475886) (xy 306.284885 -293.428102) (xy 306.304176 -293.382826)
			(xy 306.330479 -293.34123) (xy 306.363114 -293.304393) (xy 306.401235 -293.273268) (xy 306.443856 -293.248661)
			(xy 306.489872 -293.231209) (xy 306.538091 -293.221365) (xy 306.587266 -293.219384) (xy 306.636121 -293.225316)
			(xy 306.683392 -293.239008) (xy 306.727854 -293.260106) (xy 306.768357 -293.288062) (xy 306.80385 -293.322154)
			(xy 306.833415 -293.361498) (xy 306.856286 -293.405075) (xy 306.87187 -293.451756) (xy 306.879765 -293.500333)
			(xy 306.88026 -293.52494) (xy 307.219108 -293.52494) (xy 307.223068 -293.475886) (xy 307.234845 -293.428102)
			(xy 307.254136 -293.382826) (xy 307.280439 -293.34123) (xy 307.313074 -293.304393) (xy 307.351195 -293.273268)
			(xy 307.393816 -293.248661) (xy 307.439832 -293.231209) (xy 307.488051 -293.221365) (xy 307.537226 -293.219384)
			(xy 307.586081 -293.225316) (xy 307.633352 -293.239008) (xy 307.677814 -293.260106) (xy 307.718317 -293.288062)
			(xy 307.75381 -293.322154) (xy 307.783375 -293.361498) (xy 307.806246 -293.405075) (xy 307.82183 -293.451756)
			(xy 307.829725 -293.500333) (xy 307.83022 -293.52494) (xy 308.169068 -293.52494) (xy 308.173028 -293.475886)
			(xy 308.184805 -293.428102) (xy 308.204096 -293.382826) (xy 308.230399 -293.34123) (xy 308.263034 -293.304393)
			(xy 308.301155 -293.273268) (xy 308.343776 -293.248661) (xy 308.389792 -293.231209) (xy 308.438011 -293.221365)
			(xy 308.487186 -293.219384) (xy 308.536041 -293.225316) (xy 308.583312 -293.239008) (xy 308.627774 -293.260106)
			(xy 308.668277 -293.288062) (xy 308.70377 -293.322154) (xy 308.733335 -293.361498) (xy 308.756206 -293.405075)
			(xy 308.77179 -293.451756) (xy 308.779685 -293.500333) (xy 308.78018 -293.52494) (xy 309.119028 -293.52494)
			(xy 309.122988 -293.475886) (xy 309.134765 -293.428102) (xy 309.154056 -293.382826) (xy 309.180359 -293.34123)
			(xy 309.212994 -293.304393) (xy 309.251115 -293.273268) (xy 309.293736 -293.248661) (xy 309.339752 -293.231209)
			(xy 309.387971 -293.221365) (xy 309.437146 -293.219384) (xy 309.486001 -293.225316) (xy 309.533272 -293.239008)
			(xy 309.577734 -293.260106) (xy 309.618237 -293.288062) (xy 309.65373 -293.322154) (xy 309.683295 -293.361498)
			(xy 309.706166 -293.405075) (xy 309.72175 -293.451756) (xy 309.729645 -293.500333) (xy 309.73014 -293.52494)
			(xy 310.068988 -293.52494) (xy 310.072948 -293.475886) (xy 310.084725 -293.428102) (xy 310.104016 -293.382826)
			(xy 310.130319 -293.34123) (xy 310.162954 -293.304393) (xy 310.201075 -293.273268) (xy 310.243696 -293.248661)
			(xy 310.289712 -293.231209) (xy 310.337931 -293.221365) (xy 310.387106 -293.219384) (xy 310.435961 -293.225316)
			(xy 310.483232 -293.239008) (xy 310.527694 -293.260106) (xy 310.568197 -293.288062) (xy 310.60369 -293.322154)
			(xy 310.633255 -293.361498) (xy 310.656126 -293.405075) (xy 310.67171 -293.451756) (xy 310.679605 -293.500333)
			(xy 310.6801 -293.52494) (xy 311.018948 -293.52494) (xy 311.022908 -293.475886) (xy 311.034685 -293.428102)
			(xy 311.053976 -293.382826) (xy 311.080279 -293.34123) (xy 311.112914 -293.304393) (xy 311.151035 -293.273268)
			(xy 311.193656 -293.248661) (xy 311.239672 -293.231209) (xy 311.287891 -293.221365) (xy 311.337066 -293.219384)
			(xy 311.385921 -293.225316) (xy 311.433192 -293.239008) (xy 311.477654 -293.260106) (xy 311.518157 -293.288062)
			(xy 311.55365 -293.322154) (xy 311.583215 -293.361498) (xy 311.606086 -293.405075) (xy 311.62167 -293.451756)
			(xy 311.629565 -293.500333) (xy 311.63006 -293.52494) (xy 311.968908 -293.52494) (xy 311.972868 -293.475886)
			(xy 311.984645 -293.428102) (xy 312.003936 -293.382826) (xy 312.030239 -293.34123) (xy 312.062874 -293.304393)
			(xy 312.100995 -293.273268) (xy 312.143616 -293.248661) (xy 312.189632 -293.231209) (xy 312.237851 -293.221365)
			(xy 312.287026 -293.219384) (xy 312.335881 -293.225316) (xy 312.383152 -293.239008) (xy 312.427614 -293.260106)
			(xy 312.468117 -293.288062) (xy 312.50361 -293.322154) (xy 312.533175 -293.361498) (xy 312.556046 -293.405075)
			(xy 312.57163 -293.451756) (xy 312.579525 -293.500333) (xy 312.58002 -293.52494) (xy 312.919122 -293.52494)
			(xy 312.923082 -293.475886) (xy 312.934859 -293.428102) (xy 312.95415 -293.382826) (xy 312.980453 -293.34123)
			(xy 313.013088 -293.304393) (xy 313.051209 -293.273268) (xy 313.09383 -293.248661) (xy 313.139846 -293.231209)
			(xy 313.188065 -293.221365) (xy 313.23724 -293.219384) (xy 313.286095 -293.225316) (xy 313.333366 -293.239008)
			(xy 313.377828 -293.260106) (xy 313.418331 -293.288062) (xy 313.453824 -293.322154) (xy 313.483389 -293.361498)
			(xy 313.50626 -293.405075) (xy 313.521844 -293.451756) (xy 313.529739 -293.500333) (xy 313.530234 -293.52494)
			(xy 313.869082 -293.52494) (xy 313.873042 -293.475886) (xy 313.884819 -293.428102) (xy 313.90411 -293.382826)
			(xy 313.930413 -293.34123) (xy 313.963048 -293.304393) (xy 314.001169 -293.273268) (xy 314.04379 -293.248661)
			(xy 314.089806 -293.231209) (xy 314.138025 -293.221365) (xy 314.1872 -293.219384) (xy 314.236055 -293.225316)
			(xy 314.283326 -293.239008) (xy 314.327788 -293.260106) (xy 314.368291 -293.288062) (xy 314.403784 -293.322154)
			(xy 314.433349 -293.361498) (xy 314.45622 -293.405075) (xy 314.471804 -293.451756) (xy 314.479699 -293.500333)
			(xy 314.480194 -293.52494) (xy 314.819042 -293.52494) (xy 314.823002 -293.475886) (xy 314.834779 -293.428102)
			(xy 314.85407 -293.382826) (xy 314.880373 -293.34123) (xy 314.913008 -293.304393) (xy 314.951129 -293.273268)
			(xy 314.99375 -293.248661) (xy 315.039766 -293.231209) (xy 315.087985 -293.221365) (xy 315.13716 -293.219384)
			(xy 315.186015 -293.225316) (xy 315.233286 -293.239008) (xy 315.277748 -293.260106) (xy 315.318251 -293.288062)
			(xy 315.353744 -293.322154) (xy 315.383309 -293.361498) (xy 315.40618 -293.405075) (xy 315.421764 -293.451756)
			(xy 315.429659 -293.500333) (xy 315.430154 -293.52494) (xy 315.429659 -293.549547) (xy 315.421764 -293.598124)
			(xy 315.40618 -293.644805) (xy 315.383309 -293.688382) (xy 315.353744 -293.727726) (xy 315.318251 -293.761818)
			(xy 315.277748 -293.789774) (xy 315.233286 -293.810872) (xy 315.186015 -293.824564) (xy 315.13716 -293.830496)
			(xy 315.087985 -293.828515) (xy 315.039766 -293.818671) (xy 314.99375 -293.801219) (xy 314.951129 -293.776612)
			(xy 314.913008 -293.745487) (xy 314.880373 -293.70865) (xy 314.85407 -293.667054) (xy 314.834779 -293.621778)
			(xy 314.823002 -293.573994) (xy 314.819042 -293.52494) (xy 314.480194 -293.52494) (xy 314.479699 -293.549547)
			(xy 314.471804 -293.598124) (xy 314.45622 -293.644805) (xy 314.433349 -293.688382) (xy 314.403784 -293.727726)
			(xy 314.368291 -293.761818) (xy 314.327788 -293.789774) (xy 314.283326 -293.810872) (xy 314.236055 -293.824564)
			(xy 314.1872 -293.830496) (xy 314.138025 -293.828515) (xy 314.089806 -293.818671) (xy 314.04379 -293.801219)
			(xy 314.001169 -293.776612) (xy 313.963048 -293.745487) (xy 313.930413 -293.70865) (xy 313.90411 -293.667054)
			(xy 313.884819 -293.621778) (xy 313.873042 -293.573994) (xy 313.869082 -293.52494) (xy 313.530234 -293.52494)
			(xy 313.529739 -293.549547) (xy 313.521844 -293.598124) (xy 313.50626 -293.644805) (xy 313.483389 -293.688382)
			(xy 313.453824 -293.727726) (xy 313.418331 -293.761818) (xy 313.377828 -293.789774) (xy 313.333366 -293.810872)
			(xy 313.286095 -293.824564) (xy 313.23724 -293.830496) (xy 313.188065 -293.828515) (xy 313.139846 -293.818671)
			(xy 313.09383 -293.801219) (xy 313.051209 -293.776612) (xy 313.013088 -293.745487) (xy 312.980453 -293.70865)
			(xy 312.95415 -293.667054) (xy 312.934859 -293.621778) (xy 312.923082 -293.573994) (xy 312.919122 -293.52494)
			(xy 312.58002 -293.52494) (xy 312.579525 -293.549547) (xy 312.57163 -293.598124) (xy 312.556046 -293.644805)
			(xy 312.533175 -293.688382) (xy 312.50361 -293.727726) (xy 312.468117 -293.761818) (xy 312.427614 -293.789774)
			(xy 312.383152 -293.810872) (xy 312.335881 -293.824564) (xy 312.287026 -293.830496) (xy 312.237851 -293.828515)
			(xy 312.189632 -293.818671) (xy 312.143616 -293.801219) (xy 312.100995 -293.776612) (xy 312.062874 -293.745487)
			(xy 312.030239 -293.70865) (xy 312.003936 -293.667054) (xy 311.984645 -293.621778) (xy 311.972868 -293.573994)
			(xy 311.968908 -293.52494) (xy 311.63006 -293.52494) (xy 311.629565 -293.549547) (xy 311.62167 -293.598124)
			(xy 311.606086 -293.644805) (xy 311.583215 -293.688382) (xy 311.55365 -293.727726) (xy 311.518157 -293.761818)
			(xy 311.477654 -293.789774) (xy 311.433192 -293.810872) (xy 311.385921 -293.824564) (xy 311.337066 -293.830496)
			(xy 311.287891 -293.828515) (xy 311.239672 -293.818671) (xy 311.193656 -293.801219) (xy 311.151035 -293.776612)
			(xy 311.112914 -293.745487) (xy 311.080279 -293.70865) (xy 311.053976 -293.667054) (xy 311.034685 -293.621778)
			(xy 311.022908 -293.573994) (xy 311.018948 -293.52494) (xy 310.6801 -293.52494) (xy 310.679605 -293.549547)
			(xy 310.67171 -293.598124) (xy 310.656126 -293.644805) (xy 310.633255 -293.688382) (xy 310.60369 -293.727726)
			(xy 310.568197 -293.761818) (xy 310.527694 -293.789774) (xy 310.483232 -293.810872) (xy 310.435961 -293.824564)
			(xy 310.387106 -293.830496) (xy 310.337931 -293.828515) (xy 310.289712 -293.818671) (xy 310.243696 -293.801219)
			(xy 310.201075 -293.776612) (xy 310.162954 -293.745487) (xy 310.130319 -293.70865) (xy 310.104016 -293.667054)
			(xy 310.084725 -293.621778) (xy 310.072948 -293.573994) (xy 310.068988 -293.52494) (xy 309.73014 -293.52494)
			(xy 309.729645 -293.549547) (xy 309.72175 -293.598124) (xy 309.706166 -293.644805) (xy 309.683295 -293.688382)
			(xy 309.65373 -293.727726) (xy 309.618237 -293.761818) (xy 309.577734 -293.789774) (xy 309.533272 -293.810872)
			(xy 309.486001 -293.824564) (xy 309.437146 -293.830496) (xy 309.387971 -293.828515) (xy 309.339752 -293.818671)
			(xy 309.293736 -293.801219) (xy 309.251115 -293.776612) (xy 309.212994 -293.745487) (xy 309.180359 -293.70865)
			(xy 309.154056 -293.667054) (xy 309.134765 -293.621778) (xy 309.122988 -293.573994) (xy 309.119028 -293.52494)
			(xy 308.78018 -293.52494) (xy 308.779685 -293.549547) (xy 308.77179 -293.598124) (xy 308.756206 -293.644805)
			(xy 308.733335 -293.688382) (xy 308.70377 -293.727726) (xy 308.668277 -293.761818) (xy 308.627774 -293.789774)
			(xy 308.583312 -293.810872) (xy 308.536041 -293.824564) (xy 308.487186 -293.830496) (xy 308.438011 -293.828515)
			(xy 308.389792 -293.818671) (xy 308.343776 -293.801219) (xy 308.301155 -293.776612) (xy 308.263034 -293.745487)
			(xy 308.230399 -293.70865) (xy 308.204096 -293.667054) (xy 308.184805 -293.621778) (xy 308.173028 -293.573994)
			(xy 308.169068 -293.52494) (xy 307.83022 -293.52494) (xy 307.829725 -293.549547) (xy 307.82183 -293.598124)
			(xy 307.806246 -293.644805) (xy 307.783375 -293.688382) (xy 307.75381 -293.727726) (xy 307.718317 -293.761818)
			(xy 307.677814 -293.789774) (xy 307.633352 -293.810872) (xy 307.586081 -293.824564) (xy 307.537226 -293.830496)
			(xy 307.488051 -293.828515) (xy 307.439832 -293.818671) (xy 307.393816 -293.801219) (xy 307.351195 -293.776612)
			(xy 307.313074 -293.745487) (xy 307.280439 -293.70865) (xy 307.254136 -293.667054) (xy 307.234845 -293.621778)
			(xy 307.223068 -293.573994) (xy 307.219108 -293.52494) (xy 306.88026 -293.52494) (xy 306.879765 -293.549547)
			(xy 306.87187 -293.598124) (xy 306.856286 -293.644805) (xy 306.833415 -293.688382) (xy 306.80385 -293.727726)
			(xy 306.768357 -293.761818) (xy 306.727854 -293.789774) (xy 306.683392 -293.810872) (xy 306.636121 -293.824564)
			(xy 306.587266 -293.830496) (xy 306.538091 -293.828515) (xy 306.489872 -293.818671) (xy 306.443856 -293.801219)
			(xy 306.401235 -293.776612) (xy 306.363114 -293.745487) (xy 306.330479 -293.70865) (xy 306.304176 -293.667054)
			(xy 306.284885 -293.621778) (xy 306.273108 -293.573994) (xy 306.269148 -293.52494) (xy 305.930046 -293.52494)
			(xy 305.929551 -293.549547) (xy 305.921656 -293.598124) (xy 305.906072 -293.644805) (xy 305.883201 -293.688382)
			(xy 305.853636 -293.727726) (xy 305.818143 -293.761818) (xy 305.77764 -293.789774) (xy 305.733178 -293.810872)
			(xy 305.685907 -293.824564) (xy 305.637052 -293.830496) (xy 305.587877 -293.828515) (xy 305.539658 -293.818671)
			(xy 305.493642 -293.801219) (xy 305.451021 -293.776612) (xy 305.4129 -293.745487) (xy 305.380265 -293.70865)
			(xy 305.353962 -293.667054) (xy 305.334671 -293.621778) (xy 305.322894 -293.573994) (xy 305.318934 -293.52494)
			(xy 304.980086 -293.52494) (xy 304.979591 -293.549547) (xy 304.971696 -293.598124) (xy 304.956112 -293.644805)
			(xy 304.933241 -293.688382) (xy 304.903676 -293.727726) (xy 304.868183 -293.761818) (xy 304.82768 -293.789774)
			(xy 304.783218 -293.810872) (xy 304.735947 -293.824564) (xy 304.687092 -293.830496) (xy 304.637917 -293.828515)
			(xy 304.589698 -293.818671) (xy 304.543682 -293.801219) (xy 304.501061 -293.776612) (xy 304.46294 -293.745487)
			(xy 304.430305 -293.70865) (xy 304.404002 -293.667054) (xy 304.384711 -293.621778) (xy 304.372934 -293.573994)
			(xy 304.368974 -293.52494) (xy 304.030126 -293.52494) (xy 304.029631 -293.549547) (xy 304.021736 -293.598124)
			(xy 304.006152 -293.644805) (xy 303.983281 -293.688382) (xy 303.953716 -293.727726) (xy 303.918223 -293.761818)
			(xy 303.87772 -293.789774) (xy 303.833258 -293.810872) (xy 303.785987 -293.824564) (xy 303.737132 -293.830496)
			(xy 303.687957 -293.828515) (xy 303.639738 -293.818671) (xy 303.593722 -293.801219) (xy 303.551101 -293.776612)
			(xy 303.51298 -293.745487) (xy 303.480345 -293.70865) (xy 303.454042 -293.667054) (xy 303.434751 -293.621778)
			(xy 303.422974 -293.573994) (xy 303.419014 -293.52494) (xy 303.080166 -293.52494) (xy 303.079671 -293.549547)
			(xy 303.071776 -293.598124) (xy 303.056192 -293.644805) (xy 303.033321 -293.688382) (xy 303.003756 -293.727726)
			(xy 302.968263 -293.761818) (xy 302.92776 -293.789774) (xy 302.883298 -293.810872) (xy 302.836027 -293.824564)
			(xy 302.787172 -293.830496) (xy 302.737997 -293.828515) (xy 302.689778 -293.818671) (xy 302.643762 -293.801219)
			(xy 302.601141 -293.776612) (xy 302.56302 -293.745487) (xy 302.530385 -293.70865) (xy 302.504082 -293.667054)
			(xy 302.484791 -293.621778) (xy 302.473014 -293.573994) (xy 302.469054 -293.52494) (xy 302.130206 -293.52494)
			(xy 302.129711 -293.549547) (xy 302.121816 -293.598124) (xy 302.106232 -293.644805) (xy 302.083361 -293.688382)
			(xy 302.053796 -293.727726) (xy 302.018303 -293.761818) (xy 301.9778 -293.789774) (xy 301.933338 -293.810872)
			(xy 301.886067 -293.824564) (xy 301.837212 -293.830496) (xy 301.788037 -293.828515) (xy 301.739818 -293.818671)
			(xy 301.693802 -293.801219) (xy 301.651181 -293.776612) (xy 301.61306 -293.745487) (xy 301.580425 -293.70865)
			(xy 301.554122 -293.667054) (xy 301.534831 -293.621778) (xy 301.523054 -293.573994) (xy 301.519094 -293.52494)
			(xy 301.179992 -293.52494) (xy 301.179497 -293.549547) (xy 301.171602 -293.598124) (xy 301.156018 -293.644805)
			(xy 301.133147 -293.688382) (xy 301.103582 -293.727726) (xy 301.068089 -293.761818) (xy 301.027586 -293.789774)
			(xy 300.983124 -293.810872) (xy 300.935853 -293.824564) (xy 300.886998 -293.830496) (xy 300.837823 -293.828515)
			(xy 300.789604 -293.818671) (xy 300.743588 -293.801219) (xy 300.700967 -293.776612) (xy 300.662846 -293.745487)
			(xy 300.630211 -293.70865) (xy 300.603908 -293.667054) (xy 300.584617 -293.621778) (xy 300.57284 -293.573994)
			(xy 300.56888 -293.52494) (xy 299.280072 -293.52494) (xy 299.279577 -293.549547) (xy 299.271682 -293.598124)
			(xy 299.256098 -293.644805) (xy 299.233227 -293.688382) (xy 299.203662 -293.727726) (xy 299.168169 -293.761818)
			(xy 299.127666 -293.789774) (xy 299.083204 -293.810872) (xy 299.035933 -293.824564) (xy 298.987078 -293.830496)
			(xy 298.937903 -293.828515) (xy 298.889684 -293.818671) (xy 298.843668 -293.801219) (xy 298.801047 -293.776612)
			(xy 298.762926 -293.745487) (xy 298.730291 -293.70865) (xy 298.703988 -293.667054) (xy 298.684697 -293.621778)
			(xy 298.67292 -293.573994) (xy 298.66896 -293.52494) (xy 297.380152 -293.52494) (xy 297.379657 -293.549547)
			(xy 297.371762 -293.598124) (xy 297.356178 -293.644805) (xy 297.333307 -293.688382) (xy 297.303742 -293.727726)
			(xy 297.268249 -293.761818) (xy 297.227746 -293.789774) (xy 297.183284 -293.810872) (xy 297.136013 -293.824564)
			(xy 297.087158 -293.830496) (xy 297.037983 -293.828515) (xy 296.989764 -293.818671) (xy 296.943748 -293.801219)
			(xy 296.901127 -293.776612) (xy 296.863006 -293.745487) (xy 296.830371 -293.70865) (xy 296.804068 -293.667054)
			(xy 296.784777 -293.621778) (xy 296.773 -293.573994) (xy 296.76904 -293.52494) (xy 295.480232 -293.52494)
			(xy 295.479737 -293.549547) (xy 295.471842 -293.598124) (xy 295.456258 -293.644805) (xy 295.433387 -293.688382)
			(xy 295.403822 -293.727726) (xy 295.368329 -293.761818) (xy 295.327826 -293.789774) (xy 295.283364 -293.810872)
			(xy 295.236093 -293.824564) (xy 295.187238 -293.830496) (xy 295.138063 -293.828515) (xy 295.089844 -293.818671)
			(xy 295.043828 -293.801219) (xy 295.001207 -293.776612) (xy 294.963086 -293.745487) (xy 294.930451 -293.70865)
			(xy 294.904148 -293.667054) (xy 294.884857 -293.621778) (xy 294.87308 -293.573994) (xy 294.86912 -293.52494)
			(xy 293.580058 -293.52494) (xy 293.579563 -293.549547) (xy 293.571668 -293.598124) (xy 293.556084 -293.644805)
			(xy 293.533213 -293.688382) (xy 293.503648 -293.727726) (xy 293.468155 -293.761818) (xy 293.427652 -293.789774)
			(xy 293.38319 -293.810872) (xy 293.335919 -293.824564) (xy 293.287064 -293.830496) (xy 293.237889 -293.828515)
			(xy 293.18967 -293.818671) (xy 293.143654 -293.801219) (xy 293.101033 -293.776612) (xy 293.062912 -293.745487)
			(xy 293.030277 -293.70865) (xy 293.003974 -293.667054) (xy 292.984683 -293.621778) (xy 292.972906 -293.573994)
			(xy 292.968946 -293.52494) (xy 290.730178 -293.52494) (xy 290.729683 -293.549547) (xy 290.721788 -293.598124)
			(xy 290.706204 -293.644805) (xy 290.683333 -293.688382) (xy 290.653768 -293.727726) (xy 290.618275 -293.761818)
			(xy 290.577772 -293.789774) (xy 290.53331 -293.810872) (xy 290.486039 -293.824564) (xy 290.437184 -293.830496)
			(xy 290.388009 -293.828515) (xy 290.33979 -293.818671) (xy 290.293774 -293.801219) (xy 290.251153 -293.776612)
			(xy 290.213032 -293.745487) (xy 290.180397 -293.70865) (xy 290.154094 -293.667054) (xy 290.134803 -293.621778)
			(xy 290.123026 -293.573994) (xy 290.119066 -293.52494) (xy 288.830004 -293.52494) (xy 288.829509 -293.549547)
			(xy 288.821614 -293.598124) (xy 288.80603 -293.644805) (xy 288.783159 -293.688382) (xy 288.753594 -293.727726)
			(xy 288.718101 -293.761818) (xy 288.677598 -293.789774) (xy 288.633136 -293.810872) (xy 288.585865 -293.824564)
			(xy 288.53701 -293.830496) (xy 288.487835 -293.828515) (xy 288.439616 -293.818671) (xy 288.3936 -293.801219)
			(xy 288.350979 -293.776612) (xy 288.312858 -293.745487) (xy 288.280223 -293.70865) (xy 288.25392 -293.667054)
			(xy 288.234629 -293.621778) (xy 288.222852 -293.573994) (xy 288.218892 -293.52494) (xy 286.930084 -293.52494)
			(xy 286.929589 -293.549547) (xy 286.921694 -293.598124) (xy 286.90611 -293.644805) (xy 286.883239 -293.688382)
			(xy 286.853674 -293.727726) (xy 286.818181 -293.761818) (xy 286.777678 -293.789774) (xy 286.733216 -293.810872)
			(xy 286.685945 -293.824564) (xy 286.63709 -293.830496) (xy 286.587915 -293.828515) (xy 286.539696 -293.818671)
			(xy 286.49368 -293.801219) (xy 286.451059 -293.776612) (xy 286.412938 -293.745487) (xy 286.380303 -293.70865)
			(xy 286.354 -293.667054) (xy 286.334709 -293.621778) (xy 286.322932 -293.573994) (xy 286.318972 -293.52494)
			(xy 285.030164 -293.52494) (xy 285.029669 -293.549547) (xy 285.021774 -293.598124) (xy 285.00619 -293.644805)
			(xy 284.983319 -293.688382) (xy 284.953754 -293.727726) (xy 284.918261 -293.761818) (xy 284.877758 -293.789774)
			(xy 284.833296 -293.810872) (xy 284.786025 -293.824564) (xy 284.73717 -293.830496) (xy 284.687995 -293.828515)
			(xy 284.639776 -293.818671) (xy 284.59376 -293.801219) (xy 284.551139 -293.776612) (xy 284.513018 -293.745487)
			(xy 284.480383 -293.70865) (xy 284.45408 -293.667054) (xy 284.434789 -293.621778) (xy 284.423012 -293.573994)
			(xy 284.419052 -293.52494) (xy 283.130244 -293.52494) (xy 283.129749 -293.549547) (xy 283.121854 -293.598124)
			(xy 283.10627 -293.644805) (xy 283.083399 -293.688382) (xy 283.053834 -293.727726) (xy 283.018341 -293.761818)
			(xy 282.977838 -293.789774) (xy 282.933376 -293.810872) (xy 282.886105 -293.824564) (xy 282.83725 -293.830496)
			(xy 282.788075 -293.828515) (xy 282.739856 -293.818671) (xy 282.69384 -293.801219) (xy 282.651219 -293.776612)
			(xy 282.613098 -293.745487) (xy 282.580463 -293.70865) (xy 282.55416 -293.667054) (xy 282.534869 -293.621778)
			(xy 282.523092 -293.573994) (xy 282.519132 -293.52494) (xy 281.616912 -293.52494) (xy 281.616912 -294.099234)
			(xy 281.617562 -294.111786) (xy 281.629425 -294.133907) (xy 281.639518 -294.141398) (xy 281.720544 -294.1955)
			(xy 281.745436 -294.19804) (xy 281.757628 -294.19296) (xy 281.785665 -294.182063) (xy 281.844649 -294.170298)
			(xy 281.874722 -294.169592) (xy 281.899976 -294.170115) (xy 281.949795 -294.178432) (xy 281.997566 -294.194835)
			(xy 282.041985 -294.218876) (xy 282.081842 -294.249901) (xy 282.116049 -294.287062) (xy 282.143674 -294.329347)
			(xy 282.163962 -294.375601) (xy 282.17636 -294.424564) (xy 282.180531 -294.4749) (xy 283.469092 -294.4749)
			(xy 283.473052 -294.425846) (xy 283.484829 -294.378062) (xy 283.50412 -294.332786) (xy 283.530423 -294.29119)
			(xy 283.563058 -294.254353) (xy 283.601179 -294.223228) (xy 283.6438 -294.198621) (xy 283.689816 -294.181169)
			(xy 283.738035 -294.171325) (xy 283.78721 -294.169344) (xy 283.836065 -294.175276) (xy 283.883336 -294.188968)
			(xy 283.927798 -294.210066) (xy 283.968301 -294.238022) (xy 284.003794 -294.272114) (xy 284.033359 -294.311458)
			(xy 284.05623 -294.355035) (xy 284.071814 -294.401716) (xy 284.079709 -294.450293) (xy 284.080204 -294.4749)
			(xy 285.369012 -294.4749) (xy 285.372972 -294.425846) (xy 285.384749 -294.378062) (xy 285.40404 -294.332786)
			(xy 285.430343 -294.29119) (xy 285.462978 -294.254353) (xy 285.501099 -294.223228) (xy 285.54372 -294.198621)
			(xy 285.589736 -294.181169) (xy 285.637955 -294.171325) (xy 285.68713 -294.169344) (xy 285.735985 -294.175276)
			(xy 285.783256 -294.188968) (xy 285.827718 -294.210066) (xy 285.868221 -294.238022) (xy 285.903714 -294.272114)
			(xy 285.933279 -294.311458) (xy 285.95615 -294.355035) (xy 285.971734 -294.401716) (xy 285.979629 -294.450293)
			(xy 285.980124 -294.4749) (xy 287.268932 -294.4749) (xy 287.272892 -294.425846) (xy 287.284669 -294.378062)
			(xy 287.30396 -294.332786) (xy 287.330263 -294.29119) (xy 287.362898 -294.254353) (xy 287.401019 -294.223228)
			(xy 287.44364 -294.198621) (xy 287.489656 -294.181169) (xy 287.537875 -294.171325) (xy 287.58705 -294.169344)
			(xy 287.635905 -294.175276) (xy 287.683176 -294.188968) (xy 287.727638 -294.210066) (xy 287.768141 -294.238022)
			(xy 287.803634 -294.272114) (xy 287.833199 -294.311458) (xy 287.85607 -294.355035) (xy 287.871654 -294.401716)
			(xy 287.879549 -294.450293) (xy 287.880044 -294.4749) (xy 289.169106 -294.4749) (xy 289.173066 -294.425846)
			(xy 289.184843 -294.378062) (xy 289.204134 -294.332786) (xy 289.230437 -294.29119) (xy 289.263072 -294.254353)
			(xy 289.301193 -294.223228) (xy 289.343814 -294.198621) (xy 289.38983 -294.181169) (xy 289.438049 -294.171325)
			(xy 289.487224 -294.169344) (xy 289.536079 -294.175276) (xy 289.58335 -294.188968) (xy 289.627812 -294.210066)
			(xy 289.668315 -294.238022) (xy 289.703808 -294.272114) (xy 289.733373 -294.311458) (xy 289.756244 -294.355035)
			(xy 289.771828 -294.401716) (xy 289.779723 -294.450293) (xy 289.780218 -294.4749) (xy 292.018986 -294.4749)
			(xy 292.022946 -294.425846) (xy 292.034723 -294.378062) (xy 292.054014 -294.332786) (xy 292.080317 -294.29119)
			(xy 292.112952 -294.254353) (xy 292.151073 -294.223228) (xy 292.193694 -294.198621) (xy 292.23971 -294.181169)
			(xy 292.287929 -294.171325) (xy 292.337104 -294.169344) (xy 292.385959 -294.175276) (xy 292.43323 -294.188968)
			(xy 292.477692 -294.210066) (xy 292.518195 -294.238022) (xy 292.553688 -294.272114) (xy 292.583253 -294.311458)
			(xy 292.606124 -294.355035) (xy 292.621708 -294.401716) (xy 292.629603 -294.450293) (xy 292.630098 -294.4749)
			(xy 293.918906 -294.4749) (xy 293.922866 -294.425846) (xy 293.934643 -294.378062) (xy 293.953934 -294.332786)
			(xy 293.980237 -294.29119) (xy 294.012872 -294.254353) (xy 294.050993 -294.223228) (xy 294.093614 -294.198621)
			(xy 294.13963 -294.181169) (xy 294.187849 -294.171325) (xy 294.237024 -294.169344) (xy 294.285879 -294.175276)
			(xy 294.33315 -294.188968) (xy 294.377612 -294.210066) (xy 294.418115 -294.238022) (xy 294.453608 -294.272114)
			(xy 294.483173 -294.311458) (xy 294.506044 -294.355035) (xy 294.521628 -294.401716) (xy 294.529523 -294.450293)
			(xy 294.530018 -294.4749) (xy 295.81908 -294.4749) (xy 295.82304 -294.425846) (xy 295.834817 -294.378062)
			(xy 295.854108 -294.332786) (xy 295.880411 -294.29119) (xy 295.913046 -294.254353) (xy 295.951167 -294.223228)
			(xy 295.993788 -294.198621) (xy 296.039804 -294.181169) (xy 296.088023 -294.171325) (xy 296.137198 -294.169344)
			(xy 296.186053 -294.175276) (xy 296.233324 -294.188968) (xy 296.277786 -294.210066) (xy 296.318289 -294.238022)
			(xy 296.353782 -294.272114) (xy 296.383347 -294.311458) (xy 296.406218 -294.355035) (xy 296.421802 -294.401716)
			(xy 296.429697 -294.450293) (xy 296.430192 -294.4749) (xy 297.719 -294.4749) (xy 297.72296 -294.425846)
			(xy 297.734737 -294.378062) (xy 297.754028 -294.332786) (xy 297.780331 -294.29119) (xy 297.812966 -294.254353)
			(xy 297.851087 -294.223228) (xy 297.893708 -294.198621) (xy 297.939724 -294.181169) (xy 297.987943 -294.171325)
			(xy 298.037118 -294.169344) (xy 298.085973 -294.175276) (xy 298.133244 -294.188968) (xy 298.177706 -294.210066)
			(xy 298.218209 -294.238022) (xy 298.253702 -294.272114) (xy 298.283267 -294.311458) (xy 298.306138 -294.355035)
			(xy 298.321722 -294.401716) (xy 298.329617 -294.450293) (xy 298.330112 -294.4749) (xy 298.66896 -294.4749)
			(xy 298.67292 -294.425846) (xy 298.684697 -294.378062) (xy 298.703988 -294.332786) (xy 298.730291 -294.29119)
			(xy 298.762926 -294.254353) (xy 298.801047 -294.223228) (xy 298.843668 -294.198621) (xy 298.889684 -294.181169)
			(xy 298.937903 -294.171325) (xy 298.987078 -294.169344) (xy 299.035933 -294.175276) (xy 299.083204 -294.188968)
			(xy 299.127666 -294.210066) (xy 299.168169 -294.238022) (xy 299.203662 -294.272114) (xy 299.233227 -294.311458)
			(xy 299.256098 -294.355035) (xy 299.271682 -294.401716) (xy 299.279577 -294.450293) (xy 299.280072 -294.4749)
			(xy 299.61892 -294.4749) (xy 299.62288 -294.425846) (xy 299.634657 -294.378062) (xy 299.653948 -294.332786)
			(xy 299.680251 -294.29119) (xy 299.712886 -294.254353) (xy 299.751007 -294.223228) (xy 299.793628 -294.198621)
			(xy 299.839644 -294.181169) (xy 299.887863 -294.171325) (xy 299.937038 -294.169344) (xy 299.985893 -294.175276)
			(xy 300.033164 -294.188968) (xy 300.077626 -294.210066) (xy 300.118129 -294.238022) (xy 300.153622 -294.272114)
			(xy 300.183187 -294.311458) (xy 300.206058 -294.355035) (xy 300.221642 -294.401716) (xy 300.229537 -294.450293)
			(xy 300.230032 -294.4749) (xy 300.56888 -294.4749) (xy 300.57284 -294.425846) (xy 300.584617 -294.378062)
			(xy 300.603908 -294.332786) (xy 300.630211 -294.29119) (xy 300.662846 -294.254353) (xy 300.700967 -294.223228)
			(xy 300.743588 -294.198621) (xy 300.789604 -294.181169) (xy 300.837823 -294.171325) (xy 300.886998 -294.169344)
			(xy 300.935853 -294.175276) (xy 300.983124 -294.188968) (xy 301.027586 -294.210066) (xy 301.068089 -294.238022)
			(xy 301.103582 -294.272114) (xy 301.133147 -294.311458) (xy 301.156018 -294.355035) (xy 301.171602 -294.401716)
			(xy 301.179497 -294.450293) (xy 301.179992 -294.4749) (xy 301.519094 -294.4749) (xy 301.523054 -294.425846)
			(xy 301.534831 -294.378062) (xy 301.554122 -294.332786) (xy 301.580425 -294.29119) (xy 301.61306 -294.254353)
			(xy 301.651181 -294.223228) (xy 301.693802 -294.198621) (xy 301.739818 -294.181169) (xy 301.788037 -294.171325)
			(xy 301.837212 -294.169344) (xy 301.886067 -294.175276) (xy 301.933338 -294.188968) (xy 301.9778 -294.210066)
			(xy 302.018303 -294.238022) (xy 302.053796 -294.272114) (xy 302.083361 -294.311458) (xy 302.106232 -294.355035)
			(xy 302.121816 -294.401716) (xy 302.129711 -294.450293) (xy 302.130206 -294.4749) (xy 302.469054 -294.4749)
			(xy 302.473014 -294.425846) (xy 302.484791 -294.378062) (xy 302.504082 -294.332786) (xy 302.530385 -294.29119)
			(xy 302.56302 -294.254353) (xy 302.601141 -294.223228) (xy 302.643762 -294.198621) (xy 302.689778 -294.181169)
			(xy 302.737997 -294.171325) (xy 302.787172 -294.169344) (xy 302.836027 -294.175276) (xy 302.883298 -294.188968)
			(xy 302.92776 -294.210066) (xy 302.968263 -294.238022) (xy 303.003756 -294.272114) (xy 303.033321 -294.311458)
			(xy 303.056192 -294.355035) (xy 303.071776 -294.401716) (xy 303.079671 -294.450293) (xy 303.080166 -294.4749)
			(xy 303.419014 -294.4749) (xy 303.422974 -294.425846) (xy 303.434751 -294.378062) (xy 303.454042 -294.332786)
			(xy 303.480345 -294.29119) (xy 303.51298 -294.254353) (xy 303.551101 -294.223228) (xy 303.593722 -294.198621)
			(xy 303.639738 -294.181169) (xy 303.687957 -294.171325) (xy 303.737132 -294.169344) (xy 303.785987 -294.175276)
			(xy 303.833258 -294.188968) (xy 303.87772 -294.210066) (xy 303.918223 -294.238022) (xy 303.953716 -294.272114)
			(xy 303.983281 -294.311458) (xy 304.006152 -294.355035) (xy 304.021736 -294.401716) (xy 304.029631 -294.450293)
			(xy 304.030126 -294.4749) (xy 304.368974 -294.4749) (xy 304.372934 -294.425846) (xy 304.384711 -294.378062)
			(xy 304.404002 -294.332786) (xy 304.430305 -294.29119) (xy 304.46294 -294.254353) (xy 304.501061 -294.223228)
			(xy 304.543682 -294.198621) (xy 304.589698 -294.181169) (xy 304.637917 -294.171325) (xy 304.687092 -294.169344)
			(xy 304.735947 -294.175276) (xy 304.783218 -294.188968) (xy 304.82768 -294.210066) (xy 304.868183 -294.238022)
			(xy 304.903676 -294.272114) (xy 304.933241 -294.311458) (xy 304.956112 -294.355035) (xy 304.971696 -294.401716)
			(xy 304.979591 -294.450293) (xy 304.980086 -294.4749) (xy 305.318934 -294.4749) (xy 305.322894 -294.425846)
			(xy 305.334671 -294.378062) (xy 305.353962 -294.332786) (xy 305.380265 -294.29119) (xy 305.4129 -294.254353)
			(xy 305.451021 -294.223228) (xy 305.493642 -294.198621) (xy 305.539658 -294.181169) (xy 305.587877 -294.171325)
			(xy 305.637052 -294.169344) (xy 305.685907 -294.175276) (xy 305.733178 -294.188968) (xy 305.77764 -294.210066)
			(xy 305.818143 -294.238022) (xy 305.853636 -294.272114) (xy 305.883201 -294.311458) (xy 305.906072 -294.355035)
			(xy 305.921656 -294.401716) (xy 305.929551 -294.450293) (xy 305.930046 -294.4749) (xy 306.268894 -294.4749)
			(xy 306.272854 -294.425846) (xy 306.284631 -294.378062) (xy 306.303922 -294.332786) (xy 306.330225 -294.29119)
			(xy 306.36286 -294.254353) (xy 306.400981 -294.223228) (xy 306.443602 -294.198621) (xy 306.489618 -294.181169)
			(xy 306.537837 -294.171325) (xy 306.587012 -294.169344) (xy 306.635867 -294.175276) (xy 306.683138 -294.188968)
			(xy 306.7276 -294.210066) (xy 306.768103 -294.238022) (xy 306.803596 -294.272114) (xy 306.833161 -294.311458)
			(xy 306.856032 -294.355035) (xy 306.871616 -294.401716) (xy 306.879511 -294.450293) (xy 306.880006 -294.4749)
			(xy 307.219108 -294.4749) (xy 307.223068 -294.425846) (xy 307.234845 -294.378062) (xy 307.254136 -294.332786)
			(xy 307.280439 -294.29119) (xy 307.313074 -294.254353) (xy 307.351195 -294.223228) (xy 307.393816 -294.198621)
			(xy 307.439832 -294.181169) (xy 307.488051 -294.171325) (xy 307.537226 -294.169344) (xy 307.586081 -294.175276)
			(xy 307.633352 -294.188968) (xy 307.677814 -294.210066) (xy 307.718317 -294.238022) (xy 307.75381 -294.272114)
			(xy 307.783375 -294.311458) (xy 307.806246 -294.355035) (xy 307.82183 -294.401716) (xy 307.829725 -294.450293)
			(xy 307.83022 -294.4749) (xy 308.169068 -294.4749) (xy 308.173028 -294.425846) (xy 308.184805 -294.378062)
			(xy 308.204096 -294.332786) (xy 308.230399 -294.29119) (xy 308.263034 -294.254353) (xy 308.301155 -294.223228)
			(xy 308.343776 -294.198621) (xy 308.389792 -294.181169) (xy 308.438011 -294.171325) (xy 308.487186 -294.169344)
			(xy 308.536041 -294.175276) (xy 308.583312 -294.188968) (xy 308.627774 -294.210066) (xy 308.668277 -294.238022)
			(xy 308.70377 -294.272114) (xy 308.733335 -294.311458) (xy 308.756206 -294.355035) (xy 308.77179 -294.401716)
			(xy 308.779685 -294.450293) (xy 308.78018 -294.4749) (xy 309.119028 -294.4749) (xy 309.122988 -294.425846)
			(xy 309.134765 -294.378062) (xy 309.154056 -294.332786) (xy 309.180359 -294.29119) (xy 309.212994 -294.254353)
			(xy 309.251115 -294.223228) (xy 309.293736 -294.198621) (xy 309.339752 -294.181169) (xy 309.387971 -294.171325)
			(xy 309.437146 -294.169344) (xy 309.486001 -294.175276) (xy 309.533272 -294.188968) (xy 309.577734 -294.210066)
			(xy 309.618237 -294.238022) (xy 309.65373 -294.272114) (xy 309.683295 -294.311458) (xy 309.706166 -294.355035)
			(xy 309.72175 -294.401716) (xy 309.729645 -294.450293) (xy 309.73014 -294.4749) (xy 310.068988 -294.4749)
			(xy 310.072948 -294.425846) (xy 310.084725 -294.378062) (xy 310.104016 -294.332786) (xy 310.130319 -294.29119)
			(xy 310.162954 -294.254353) (xy 310.201075 -294.223228) (xy 310.243696 -294.198621) (xy 310.289712 -294.181169)
			(xy 310.337931 -294.171325) (xy 310.387106 -294.169344) (xy 310.435961 -294.175276) (xy 310.483232 -294.188968)
			(xy 310.527694 -294.210066) (xy 310.568197 -294.238022) (xy 310.60369 -294.272114) (xy 310.633255 -294.311458)
			(xy 310.656126 -294.355035) (xy 310.67171 -294.401716) (xy 310.679605 -294.450293) (xy 310.6801 -294.4749)
			(xy 311.018948 -294.4749) (xy 311.022908 -294.425846) (xy 311.034685 -294.378062) (xy 311.053976 -294.332786)
			(xy 311.080279 -294.29119) (xy 311.112914 -294.254353) (xy 311.151035 -294.223228) (xy 311.193656 -294.198621)
			(xy 311.239672 -294.181169) (xy 311.287891 -294.171325) (xy 311.337066 -294.169344) (xy 311.385921 -294.175276)
			(xy 311.433192 -294.188968) (xy 311.477654 -294.210066) (xy 311.518157 -294.238022) (xy 311.55365 -294.272114)
			(xy 311.583215 -294.311458) (xy 311.606086 -294.355035) (xy 311.62167 -294.401716) (xy 311.629565 -294.450293)
			(xy 311.63006 -294.4749) (xy 311.968908 -294.4749) (xy 311.972868 -294.425846) (xy 311.984645 -294.378062)
			(xy 312.003936 -294.332786) (xy 312.030239 -294.29119) (xy 312.062874 -294.254353) (xy 312.100995 -294.223228)
			(xy 312.143616 -294.198621) (xy 312.189632 -294.181169) (xy 312.237851 -294.171325) (xy 312.287026 -294.169344)
			(xy 312.335881 -294.175276) (xy 312.383152 -294.188968) (xy 312.427614 -294.210066) (xy 312.468117 -294.238022)
			(xy 312.50361 -294.272114) (xy 312.533175 -294.311458) (xy 312.556046 -294.355035) (xy 312.57163 -294.401716)
			(xy 312.579525 -294.450293) (xy 312.58002 -294.4749) (xy 312.919122 -294.4749) (xy 312.923082 -294.425846)
			(xy 312.934859 -294.378062) (xy 312.95415 -294.332786) (xy 312.980453 -294.29119) (xy 313.013088 -294.254353)
			(xy 313.051209 -294.223228) (xy 313.09383 -294.198621) (xy 313.139846 -294.181169) (xy 313.188065 -294.171325)
			(xy 313.23724 -294.169344) (xy 313.286095 -294.175276) (xy 313.333366 -294.188968) (xy 313.377828 -294.210066)
			(xy 313.418331 -294.238022) (xy 313.453824 -294.272114) (xy 313.483389 -294.311458) (xy 313.50626 -294.355035)
			(xy 313.521844 -294.401716) (xy 313.529739 -294.450293) (xy 313.530234 -294.4749) (xy 313.869082 -294.4749)
			(xy 313.873042 -294.425846) (xy 313.884819 -294.378062) (xy 313.90411 -294.332786) (xy 313.930413 -294.29119)
			(xy 313.963048 -294.254353) (xy 314.001169 -294.223228) (xy 314.04379 -294.198621) (xy 314.089806 -294.181169)
			(xy 314.138025 -294.171325) (xy 314.1872 -294.169344) (xy 314.236055 -294.175276) (xy 314.283326 -294.188968)
			(xy 314.327788 -294.210066) (xy 314.368291 -294.238022) (xy 314.403784 -294.272114) (xy 314.433349 -294.311458)
			(xy 314.45622 -294.355035) (xy 314.471804 -294.401716) (xy 314.479699 -294.450293) (xy 314.480194 -294.4749)
			(xy 314.819042 -294.4749) (xy 314.823002 -294.425846) (xy 314.834779 -294.378062) (xy 314.85407 -294.332786)
			(xy 314.880373 -294.29119) (xy 314.913008 -294.254353) (xy 314.951129 -294.223228) (xy 314.99375 -294.198621)
			(xy 315.039766 -294.181169) (xy 315.087985 -294.171325) (xy 315.13716 -294.169344) (xy 315.186015 -294.175276)
			(xy 315.233286 -294.188968) (xy 315.277748 -294.210066) (xy 315.318251 -294.238022) (xy 315.353744 -294.272114)
			(xy 315.383309 -294.311458) (xy 315.40618 -294.355035) (xy 315.421764 -294.401716) (xy 315.429659 -294.450293)
			(xy 315.430154 -294.4749) (xy 315.429659 -294.499507) (xy 315.421764 -294.548084) (xy 315.40618 -294.594765)
			(xy 315.383309 -294.638342) (xy 315.370443 -294.655464) (xy 321.363026 -294.655464) (xy 321.370781 -294.601508)
			(xy 321.386135 -294.549205) (xy 321.408778 -294.49962) (xy 321.438246 -294.453761) (xy 321.473941 -294.412564)
			(xy 321.515135 -294.376866) (xy 321.560991 -294.347393) (xy 321.610574 -294.324747) (xy 321.662876 -294.309388)
			(xy 321.716831 -294.301628) (xy 321.744086 -294.301164) (xy 321.769486 -294.301926) (xy 321.784217 -294.302451)
			(xy 321.812948 -294.295898) (xy 321.838614 -294.281417) (xy 321.859079 -294.260214) (xy 321.872642 -294.234052)
			(xy 321.878174 -294.205107) (xy 321.875215 -294.175788) (xy 321.87007 -294.161972) (xy 321.860908 -294.13877)
			(xy 321.848018 -294.090579) (xy 321.841518 -294.041119) (xy 321.841114 -294.016176) (xy 321.841604 -293.988927)
			(xy 321.849363 -293.934985) (xy 321.86472 -293.882696) (xy 321.887361 -293.833124) (xy 321.916827 -293.787279)
			(xy 321.952517 -293.746094) (xy 321.993705 -293.710407) (xy 322.039553 -293.680946) (xy 322.089126 -293.658308)
			(xy 322.141417 -293.642956) (xy 322.19536 -293.635202) (xy 322.249857 -293.635203) (xy 322.3038 -293.64296)
			(xy 322.35609 -293.658314) (xy 322.405663 -293.680954) (xy 322.451509 -293.710418) (xy 322.492695 -293.746106)
			(xy 322.528383 -293.787293) (xy 322.557847 -293.833139) (xy 322.580487 -293.882712) (xy 322.595841 -293.935002)
			(xy 322.602399 -293.980616) (xy 323.480682 -293.980616) (xy 323.484753 -293.924994) (xy 323.496879 -293.870557)
			(xy 323.516802 -293.818466) (xy 323.544098 -293.769831) (xy 323.578184 -293.725688) (xy 323.618333 -293.686979)
			(xy 323.663691 -293.654528) (xy 323.713291 -293.629027) (xy 323.766075 -293.61102) (xy 323.820918 -293.60089)
			(xy 323.876652 -293.598853) (xy 323.932089 -293.604953) (xy 323.986046 -293.619059) (xy 324.037375 -293.640871)
			(xy 324.084981 -293.669925) (xy 324.127849 -293.7056) (xy 324.165066 -293.747137) (xy 324.195839 -293.79365)
			(xy 324.219511 -293.844147) (xy 324.235579 -293.897554) (xy 324.243699 -293.95273) (xy 324.244208 -293.980616)
			(xy 324.243699 -294.008502) (xy 324.235579 -294.063678) (xy 324.219511 -294.117085) (xy 324.195839 -294.167582)
			(xy 324.165066 -294.214095) (xy 324.127849 -294.255632) (xy 324.084981 -294.291307) (xy 324.037375 -294.320361)
			(xy 323.986046 -294.342173) (xy 323.932089 -294.356279) (xy 323.876652 -294.362379) (xy 323.820918 -294.360342)
			(xy 323.766075 -294.350212) (xy 323.713291 -294.332205) (xy 323.663691 -294.306704) (xy 323.618333 -294.274253)
			(xy 323.578184 -294.235544) (xy 323.544098 -294.191401) (xy 323.516802 -294.142766) (xy 323.496879 -294.090675)
			(xy 323.484753 -294.036238) (xy 323.480682 -293.980616) (xy 322.602399 -293.980616) (xy 322.603597 -293.988945)
			(xy 322.603598 -294.043442) (xy 322.595844 -294.097385) (xy 322.580491 -294.149676) (xy 322.557853 -294.199249)
			(xy 322.528391 -294.245096) (xy 322.492704 -294.286284) (xy 322.451519 -294.321974) (xy 322.405674 -294.35144)
			(xy 322.356103 -294.374081) (xy 322.303813 -294.389438) (xy 322.249871 -294.397196) (xy 322.222622 -294.397684)
			(xy 322.197222 -294.396922) (xy 322.182492 -294.396476) (xy 322.153774 -294.403023) (xy 322.128118 -294.417493)
			(xy 322.107658 -294.438682) (xy 322.094094 -294.464828) (xy 322.088555 -294.493757) (xy 322.08934 -294.50157)
			(xy 322.736462 -294.50157) (xy 322.740533 -294.445948) (xy 322.752659 -294.391511) (xy 322.772582 -294.33942)
			(xy 322.799878 -294.290785) (xy 322.833964 -294.246642) (xy 322.874113 -294.207933) (xy 322.919471 -294.175482)
			(xy 322.969071 -294.149981) (xy 323.021855 -294.131974) (xy 323.076698 -294.121844) (xy 323.132432 -294.119807)
			(xy 323.187869 -294.125907) (xy 323.241826 -294.140013) (xy 323.293155 -294.161825) (xy 323.340761 -294.190879)
			(xy 323.383629 -294.226554) (xy 323.420846 -294.268091) (xy 323.451619 -294.314604) (xy 323.475291 -294.365101)
			(xy 323.491359 -294.418508) (xy 323.499479 -294.473684) (xy 323.499988 -294.50157) (xy 323.499479 -294.529456)
			(xy 323.491359 -294.584632) (xy 323.475291 -294.638039) (xy 323.451619 -294.688536) (xy 323.420846 -294.735049)
			(xy 323.383629 -294.776586) (xy 323.340761 -294.812261) (xy 323.293155 -294.841315) (xy 323.241826 -294.863127)
			(xy 323.187869 -294.877233) (xy 323.132432 -294.883333) (xy 323.076698 -294.881296) (xy 323.021855 -294.871166)
			(xy 322.969071 -294.853159) (xy 322.919471 -294.827658) (xy 322.874113 -294.795207) (xy 322.833964 -294.756498)
			(xy 322.799878 -294.712355) (xy 322.772582 -294.66372) (xy 322.752659 -294.611629) (xy 322.740533 -294.557192)
			(xy 322.736462 -294.50157) (xy 322.08934 -294.50157) (xy 322.091501 -294.523064) (xy 322.096638 -294.536876)
			(xy 322.105784 -294.560084) (xy 322.118681 -294.608272) (xy 322.125186 -294.65773) (xy 322.125594 -294.682672)
			(xy 322.125175 -294.709927) (xy 322.117421 -294.763883) (xy 322.102068 -294.816186) (xy 322.079427 -294.865772)
			(xy 322.04996 -294.911631) (xy 322.014266 -294.952829) (xy 321.973072 -294.988529) (xy 321.927217 -295.018002)
			(xy 321.877634 -295.04065) (xy 321.825333 -295.05601) (xy 321.771378 -295.063771) (xy 321.716868 -295.063775)
			(xy 321.662912 -295.05602) (xy 321.610609 -295.040666) (xy 321.561024 -295.018025) (xy 321.515165 -294.988557)
			(xy 321.473967 -294.952863) (xy 321.438268 -294.911668) (xy 321.408795 -294.865813) (xy 321.386149 -294.81623)
			(xy 321.370789 -294.763929) (xy 321.363028 -294.709974) (xy 321.363026 -294.655464) (xy 315.370443 -294.655464)
			(xy 315.353744 -294.677686) (xy 315.318251 -294.711778) (xy 315.277748 -294.739734) (xy 315.233286 -294.760832)
			(xy 315.186015 -294.774524) (xy 315.13716 -294.780456) (xy 315.087985 -294.778475) (xy 315.039766 -294.768631)
			(xy 314.99375 -294.751179) (xy 314.951129 -294.726572) (xy 314.913008 -294.695447) (xy 314.880373 -294.65861)
			(xy 314.85407 -294.617014) (xy 314.834779 -294.571738) (xy 314.823002 -294.523954) (xy 314.819042 -294.4749)
			(xy 314.480194 -294.4749) (xy 314.479699 -294.499507) (xy 314.471804 -294.548084) (xy 314.45622 -294.594765)
			(xy 314.433349 -294.638342) (xy 314.403784 -294.677686) (xy 314.368291 -294.711778) (xy 314.327788 -294.739734)
			(xy 314.283326 -294.760832) (xy 314.236055 -294.774524) (xy 314.1872 -294.780456) (xy 314.138025 -294.778475)
			(xy 314.089806 -294.768631) (xy 314.04379 -294.751179) (xy 314.001169 -294.726572) (xy 313.963048 -294.695447)
			(xy 313.930413 -294.65861) (xy 313.90411 -294.617014) (xy 313.884819 -294.571738) (xy 313.873042 -294.523954)
			(xy 313.869082 -294.4749) (xy 313.530234 -294.4749) (xy 313.529739 -294.499507) (xy 313.521844 -294.548084)
			(xy 313.50626 -294.594765) (xy 313.483389 -294.638342) (xy 313.453824 -294.677686) (xy 313.418331 -294.711778)
			(xy 313.377828 -294.739734) (xy 313.333366 -294.760832) (xy 313.286095 -294.774524) (xy 313.23724 -294.780456)
			(xy 313.188065 -294.778475) (xy 313.139846 -294.768631) (xy 313.09383 -294.751179) (xy 313.051209 -294.726572)
			(xy 313.013088 -294.695447) (xy 312.980453 -294.65861) (xy 312.95415 -294.617014) (xy 312.934859 -294.571738)
			(xy 312.923082 -294.523954) (xy 312.919122 -294.4749) (xy 312.58002 -294.4749) (xy 312.579525 -294.499507)
			(xy 312.57163 -294.548084) (xy 312.556046 -294.594765) (xy 312.533175 -294.638342) (xy 312.50361 -294.677686)
			(xy 312.468117 -294.711778) (xy 312.427614 -294.739734) (xy 312.383152 -294.760832) (xy 312.335881 -294.774524)
			(xy 312.287026 -294.780456) (xy 312.237851 -294.778475) (xy 312.189632 -294.768631) (xy 312.143616 -294.751179)
			(xy 312.100995 -294.726572) (xy 312.062874 -294.695447) (xy 312.030239 -294.65861) (xy 312.003936 -294.617014)
			(xy 311.984645 -294.571738) (xy 311.972868 -294.523954) (xy 311.968908 -294.4749) (xy 311.63006 -294.4749)
			(xy 311.629565 -294.499507) (xy 311.62167 -294.548084) (xy 311.606086 -294.594765) (xy 311.583215 -294.638342)
			(xy 311.55365 -294.677686) (xy 311.518157 -294.711778) (xy 311.477654 -294.739734) (xy 311.433192 -294.760832)
			(xy 311.385921 -294.774524) (xy 311.337066 -294.780456) (xy 311.287891 -294.778475) (xy 311.239672 -294.768631)
			(xy 311.193656 -294.751179) (xy 311.151035 -294.726572) (xy 311.112914 -294.695447) (xy 311.080279 -294.65861)
			(xy 311.053976 -294.617014) (xy 311.034685 -294.571738) (xy 311.022908 -294.523954) (xy 311.018948 -294.4749)
			(xy 310.6801 -294.4749) (xy 310.679605 -294.499507) (xy 310.67171 -294.548084) (xy 310.656126 -294.594765)
			(xy 310.633255 -294.638342) (xy 310.60369 -294.677686) (xy 310.568197 -294.711778) (xy 310.527694 -294.739734)
			(xy 310.483232 -294.760832) (xy 310.435961 -294.774524) (xy 310.387106 -294.780456) (xy 310.337931 -294.778475)
			(xy 310.289712 -294.768631) (xy 310.243696 -294.751179) (xy 310.201075 -294.726572) (xy 310.162954 -294.695447)
			(xy 310.130319 -294.65861) (xy 310.104016 -294.617014) (xy 310.084725 -294.571738) (xy 310.072948 -294.523954)
			(xy 310.068988 -294.4749) (xy 309.73014 -294.4749) (xy 309.729645 -294.499507) (xy 309.72175 -294.548084)
			(xy 309.706166 -294.594765) (xy 309.683295 -294.638342) (xy 309.65373 -294.677686) (xy 309.618237 -294.711778)
			(xy 309.577734 -294.739734) (xy 309.533272 -294.760832) (xy 309.486001 -294.774524) (xy 309.437146 -294.780456)
			(xy 309.387971 -294.778475) (xy 309.339752 -294.768631) (xy 309.293736 -294.751179) (xy 309.251115 -294.726572)
			(xy 309.212994 -294.695447) (xy 309.180359 -294.65861) (xy 309.154056 -294.617014) (xy 309.134765 -294.571738)
			(xy 309.122988 -294.523954) (xy 309.119028 -294.4749) (xy 308.78018 -294.4749) (xy 308.779685 -294.499507)
			(xy 308.77179 -294.548084) (xy 308.756206 -294.594765) (xy 308.733335 -294.638342) (xy 308.70377 -294.677686)
			(xy 308.668277 -294.711778) (xy 308.627774 -294.739734) (xy 308.583312 -294.760832) (xy 308.536041 -294.774524)
			(xy 308.487186 -294.780456) (xy 308.438011 -294.778475) (xy 308.389792 -294.768631) (xy 308.343776 -294.751179)
			(xy 308.301155 -294.726572) (xy 308.263034 -294.695447) (xy 308.230399 -294.65861) (xy 308.204096 -294.617014)
			(xy 308.184805 -294.571738) (xy 308.173028 -294.523954) (xy 308.169068 -294.4749) (xy 307.83022 -294.4749)
			(xy 307.829725 -294.499507) (xy 307.82183 -294.548084) (xy 307.806246 -294.594765) (xy 307.783375 -294.638342)
			(xy 307.75381 -294.677686) (xy 307.718317 -294.711778) (xy 307.677814 -294.739734) (xy 307.633352 -294.760832)
			(xy 307.586081 -294.774524) (xy 307.537226 -294.780456) (xy 307.488051 -294.778475) (xy 307.439832 -294.768631)
			(xy 307.393816 -294.751179) (xy 307.351195 -294.726572) (xy 307.313074 -294.695447) (xy 307.280439 -294.65861)
			(xy 307.254136 -294.617014) (xy 307.234845 -294.571738) (xy 307.223068 -294.523954) (xy 307.219108 -294.4749)
			(xy 306.880006 -294.4749) (xy 306.879511 -294.499507) (xy 306.871616 -294.548084) (xy 306.856032 -294.594765)
			(xy 306.833161 -294.638342) (xy 306.803596 -294.677686) (xy 306.768103 -294.711778) (xy 306.7276 -294.739734)
			(xy 306.683138 -294.760832) (xy 306.635867 -294.774524) (xy 306.587012 -294.780456) (xy 306.537837 -294.778475)
			(xy 306.489618 -294.768631) (xy 306.443602 -294.751179) (xy 306.400981 -294.726572) (xy 306.36286 -294.695447)
			(xy 306.330225 -294.65861) (xy 306.303922 -294.617014) (xy 306.284631 -294.571738) (xy 306.272854 -294.523954)
			(xy 306.268894 -294.4749) (xy 305.930046 -294.4749) (xy 305.929551 -294.499507) (xy 305.921656 -294.548084)
			(xy 305.906072 -294.594765) (xy 305.883201 -294.638342) (xy 305.853636 -294.677686) (xy 305.818143 -294.711778)
			(xy 305.77764 -294.739734) (xy 305.733178 -294.760832) (xy 305.685907 -294.774524) (xy 305.637052 -294.780456)
			(xy 305.587877 -294.778475) (xy 305.539658 -294.768631) (xy 305.493642 -294.751179) (xy 305.451021 -294.726572)
			(xy 305.4129 -294.695447) (xy 305.380265 -294.65861) (xy 305.353962 -294.617014) (xy 305.334671 -294.571738)
			(xy 305.322894 -294.523954) (xy 305.318934 -294.4749) (xy 304.980086 -294.4749) (xy 304.979591 -294.499507)
			(xy 304.971696 -294.548084) (xy 304.956112 -294.594765) (xy 304.933241 -294.638342) (xy 304.903676 -294.677686)
			(xy 304.868183 -294.711778) (xy 304.82768 -294.739734) (xy 304.783218 -294.760832) (xy 304.735947 -294.774524)
			(xy 304.687092 -294.780456) (xy 304.637917 -294.778475) (xy 304.589698 -294.768631) (xy 304.543682 -294.751179)
			(xy 304.501061 -294.726572) (xy 304.46294 -294.695447) (xy 304.430305 -294.65861) (xy 304.404002 -294.617014)
			(xy 304.384711 -294.571738) (xy 304.372934 -294.523954) (xy 304.368974 -294.4749) (xy 304.030126 -294.4749)
			(xy 304.029631 -294.499507) (xy 304.021736 -294.548084) (xy 304.006152 -294.594765) (xy 303.983281 -294.638342)
			(xy 303.953716 -294.677686) (xy 303.918223 -294.711778) (xy 303.87772 -294.739734) (xy 303.833258 -294.760832)
			(xy 303.785987 -294.774524) (xy 303.737132 -294.780456) (xy 303.687957 -294.778475) (xy 303.639738 -294.768631)
			(xy 303.593722 -294.751179) (xy 303.551101 -294.726572) (xy 303.51298 -294.695447) (xy 303.480345 -294.65861)
			(xy 303.454042 -294.617014) (xy 303.434751 -294.571738) (xy 303.422974 -294.523954) (xy 303.419014 -294.4749)
			(xy 303.080166 -294.4749) (xy 303.079671 -294.499507) (xy 303.071776 -294.548084) (xy 303.056192 -294.594765)
			(xy 303.033321 -294.638342) (xy 303.003756 -294.677686) (xy 302.968263 -294.711778) (xy 302.92776 -294.739734)
			(xy 302.883298 -294.760832) (xy 302.836027 -294.774524) (xy 302.787172 -294.780456) (xy 302.737997 -294.778475)
			(xy 302.689778 -294.768631) (xy 302.643762 -294.751179) (xy 302.601141 -294.726572) (xy 302.56302 -294.695447)
			(xy 302.530385 -294.65861) (xy 302.504082 -294.617014) (xy 302.484791 -294.571738) (xy 302.473014 -294.523954)
			(xy 302.469054 -294.4749) (xy 302.130206 -294.4749) (xy 302.129711 -294.499507) (xy 302.121816 -294.548084)
			(xy 302.106232 -294.594765) (xy 302.083361 -294.638342) (xy 302.053796 -294.677686) (xy 302.018303 -294.711778)
			(xy 301.9778 -294.739734) (xy 301.933338 -294.760832) (xy 301.886067 -294.774524) (xy 301.837212 -294.780456)
			(xy 301.788037 -294.778475) (xy 301.739818 -294.768631) (xy 301.693802 -294.751179) (xy 301.651181 -294.726572)
			(xy 301.61306 -294.695447) (xy 301.580425 -294.65861) (xy 301.554122 -294.617014) (xy 301.534831 -294.571738)
			(xy 301.523054 -294.523954) (xy 301.519094 -294.4749) (xy 301.179992 -294.4749) (xy 301.179497 -294.499507)
			(xy 301.171602 -294.548084) (xy 301.156018 -294.594765) (xy 301.133147 -294.638342) (xy 301.103582 -294.677686)
			(xy 301.068089 -294.711778) (xy 301.027586 -294.739734) (xy 300.983124 -294.760832) (xy 300.935853 -294.774524)
			(xy 300.886998 -294.780456) (xy 300.837823 -294.778475) (xy 300.789604 -294.768631) (xy 300.743588 -294.751179)
			(xy 300.700967 -294.726572) (xy 300.662846 -294.695447) (xy 300.630211 -294.65861) (xy 300.603908 -294.617014)
			(xy 300.584617 -294.571738) (xy 300.57284 -294.523954) (xy 300.56888 -294.4749) (xy 300.230032 -294.4749)
			(xy 300.229537 -294.499507) (xy 300.221642 -294.548084) (xy 300.206058 -294.594765) (xy 300.183187 -294.638342)
			(xy 300.153622 -294.677686) (xy 300.118129 -294.711778) (xy 300.077626 -294.739734) (xy 300.033164 -294.760832)
			(xy 299.985893 -294.774524) (xy 299.937038 -294.780456) (xy 299.887863 -294.778475) (xy 299.839644 -294.768631)
			(xy 299.793628 -294.751179) (xy 299.751007 -294.726572) (xy 299.712886 -294.695447) (xy 299.680251 -294.65861)
			(xy 299.653948 -294.617014) (xy 299.634657 -294.571738) (xy 299.62288 -294.523954) (xy 299.61892 -294.4749)
			(xy 299.280072 -294.4749) (xy 299.279577 -294.499507) (xy 299.271682 -294.548084) (xy 299.256098 -294.594765)
			(xy 299.233227 -294.638342) (xy 299.203662 -294.677686) (xy 299.168169 -294.711778) (xy 299.127666 -294.739734)
			(xy 299.083204 -294.760832) (xy 299.035933 -294.774524) (xy 298.987078 -294.780456) (xy 298.937903 -294.778475)
			(xy 298.889684 -294.768631) (xy 298.843668 -294.751179) (xy 298.801047 -294.726572) (xy 298.762926 -294.695447)
			(xy 298.730291 -294.65861) (xy 298.703988 -294.617014) (xy 298.684697 -294.571738) (xy 298.67292 -294.523954)
			(xy 298.66896 -294.4749) (xy 298.330112 -294.4749) (xy 298.329617 -294.499507) (xy 298.321722 -294.548084)
			(xy 298.306138 -294.594765) (xy 298.283267 -294.638342) (xy 298.253702 -294.677686) (xy 298.218209 -294.711778)
			(xy 298.177706 -294.739734) (xy 298.133244 -294.760832) (xy 298.085973 -294.774524) (xy 298.037118 -294.780456)
			(xy 297.987943 -294.778475) (xy 297.939724 -294.768631) (xy 297.893708 -294.751179) (xy 297.851087 -294.726572)
			(xy 297.812966 -294.695447) (xy 297.780331 -294.65861) (xy 297.754028 -294.617014) (xy 297.734737 -294.571738)
			(xy 297.72296 -294.523954) (xy 297.719 -294.4749) (xy 296.430192 -294.4749) (xy 296.429697 -294.499507)
			(xy 296.421802 -294.548084) (xy 296.406218 -294.594765) (xy 296.383347 -294.638342) (xy 296.353782 -294.677686)
			(xy 296.318289 -294.711778) (xy 296.277786 -294.739734) (xy 296.233324 -294.760832) (xy 296.186053 -294.774524)
			(xy 296.137198 -294.780456) (xy 296.088023 -294.778475) (xy 296.039804 -294.768631) (xy 295.993788 -294.751179)
			(xy 295.951167 -294.726572) (xy 295.913046 -294.695447) (xy 295.880411 -294.65861) (xy 295.854108 -294.617014)
			(xy 295.834817 -294.571738) (xy 295.82304 -294.523954) (xy 295.81908 -294.4749) (xy 294.530018 -294.4749)
			(xy 294.529523 -294.499507) (xy 294.521628 -294.548084) (xy 294.506044 -294.594765) (xy 294.483173 -294.638342)
			(xy 294.453608 -294.677686) (xy 294.418115 -294.711778) (xy 294.377612 -294.739734) (xy 294.33315 -294.760832)
			(xy 294.285879 -294.774524) (xy 294.237024 -294.780456) (xy 294.187849 -294.778475) (xy 294.13963 -294.768631)
			(xy 294.093614 -294.751179) (xy 294.050993 -294.726572) (xy 294.012872 -294.695447) (xy 293.980237 -294.65861)
			(xy 293.953934 -294.617014) (xy 293.934643 -294.571738) (xy 293.922866 -294.523954) (xy 293.918906 -294.4749)
			(xy 292.630098 -294.4749) (xy 292.629603 -294.499507) (xy 292.621708 -294.548084) (xy 292.606124 -294.594765)
			(xy 292.583253 -294.638342) (xy 292.553688 -294.677686) (xy 292.518195 -294.711778) (xy 292.477692 -294.739734)
			(xy 292.43323 -294.760832) (xy 292.385959 -294.774524) (xy 292.337104 -294.780456) (xy 292.287929 -294.778475)
			(xy 292.23971 -294.768631) (xy 292.193694 -294.751179) (xy 292.151073 -294.726572) (xy 292.112952 -294.695447)
			(xy 292.080317 -294.65861) (xy 292.054014 -294.617014) (xy 292.034723 -294.571738) (xy 292.022946 -294.523954)
			(xy 292.018986 -294.4749) (xy 289.780218 -294.4749) (xy 289.779723 -294.499507) (xy 289.771828 -294.548084)
			(xy 289.756244 -294.594765) (xy 289.733373 -294.638342) (xy 289.703808 -294.677686) (xy 289.668315 -294.711778)
			(xy 289.627812 -294.739734) (xy 289.58335 -294.760832) (xy 289.536079 -294.774524) (xy 289.487224 -294.780456)
			(xy 289.438049 -294.778475) (xy 289.38983 -294.768631) (xy 289.343814 -294.751179) (xy 289.301193 -294.726572)
			(xy 289.263072 -294.695447) (xy 289.230437 -294.65861) (xy 289.204134 -294.617014) (xy 289.184843 -294.571738)
			(xy 289.173066 -294.523954) (xy 289.169106 -294.4749) (xy 287.880044 -294.4749) (xy 287.879549 -294.499507)
			(xy 287.871654 -294.548084) (xy 287.85607 -294.594765) (xy 287.833199 -294.638342) (xy 287.803634 -294.677686)
			(xy 287.768141 -294.711778) (xy 287.727638 -294.739734) (xy 287.683176 -294.760832) (xy 287.635905 -294.774524)
			(xy 287.58705 -294.780456) (xy 287.537875 -294.778475) (xy 287.489656 -294.768631) (xy 287.44364 -294.751179)
			(xy 287.401019 -294.726572) (xy 287.362898 -294.695447) (xy 287.330263 -294.65861) (xy 287.30396 -294.617014)
			(xy 287.284669 -294.571738) (xy 287.272892 -294.523954) (xy 287.268932 -294.4749) (xy 285.980124 -294.4749)
			(xy 285.979629 -294.499507) (xy 285.971734 -294.548084) (xy 285.95615 -294.594765) (xy 285.933279 -294.638342)
			(xy 285.903714 -294.677686) (xy 285.868221 -294.711778) (xy 285.827718 -294.739734) (xy 285.783256 -294.760832)
			(xy 285.735985 -294.774524) (xy 285.68713 -294.780456) (xy 285.637955 -294.778475) (xy 285.589736 -294.768631)
			(xy 285.54372 -294.751179) (xy 285.501099 -294.726572) (xy 285.462978 -294.695447) (xy 285.430343 -294.65861)
			(xy 285.40404 -294.617014) (xy 285.384749 -294.571738) (xy 285.372972 -294.523954) (xy 285.369012 -294.4749)
			(xy 284.080204 -294.4749) (xy 284.079709 -294.499507) (xy 284.071814 -294.548084) (xy 284.05623 -294.594765)
			(xy 284.033359 -294.638342) (xy 284.003794 -294.677686) (xy 283.968301 -294.711778) (xy 283.927798 -294.739734)
			(xy 283.883336 -294.760832) (xy 283.836065 -294.774524) (xy 283.78721 -294.780456) (xy 283.738035 -294.778475)
			(xy 283.689816 -294.768631) (xy 283.6438 -294.751179) (xy 283.601179 -294.726572) (xy 283.563058 -294.695447)
			(xy 283.530423 -294.65861) (xy 283.50412 -294.617014) (xy 283.484829 -294.571738) (xy 283.473052 -294.523954)
			(xy 283.469092 -294.4749) (xy 282.180531 -294.4749) (xy 282.17636 -294.525236) (xy 282.163962 -294.574199)
			(xy 282.143674 -294.620453) (xy 282.116049 -294.662738) (xy 282.081842 -294.699899) (xy 282.041985 -294.730924)
			(xy 281.997566 -294.754965) (xy 281.949795 -294.771368) (xy 281.899976 -294.779685) (xy 281.874722 -294.780208)
			(xy 281.844648 -294.779515) (xy 281.785662 -294.767749) (xy 281.757628 -294.75684) (xy 281.745436 -294.75176)
			(xy 281.720544 -294.7543) (xy 281.639518 -294.808402) (xy 281.629462 -294.815922) (xy 281.617616 -294.838029)
			(xy 281.616912 -294.850566) (xy 281.616912 -295.355518) (xy 324.815706 -295.355518) (xy 324.819777 -295.299896)
			(xy 324.831903 -295.245459) (xy 324.851826 -295.193368) (xy 324.879122 -295.144733) (xy 324.913208 -295.10059)
			(xy 324.953357 -295.061881) (xy 324.998715 -295.02943) (xy 325.048315 -295.003929) (xy 325.101099 -294.985922)
			(xy 325.155942 -294.975792) (xy 325.211676 -294.973755) (xy 325.267113 -294.979855) (xy 325.32107 -294.993961)
			(xy 325.372399 -295.015773) (xy 325.420005 -295.044827) (xy 325.462873 -295.080502) (xy 325.50009 -295.122039)
			(xy 325.530863 -295.168552) (xy 325.554535 -295.219049) (xy 325.570603 -295.272456) (xy 325.578723 -295.327632)
			(xy 325.579232 -295.355518) (xy 325.578723 -295.383404) (xy 325.570603 -295.43858) (xy 325.554535 -295.491987)
			(xy 325.530863 -295.542484) (xy 325.50009 -295.588997) (xy 325.462873 -295.630534) (xy 325.420005 -295.666209)
			(xy 325.372399 -295.695263) (xy 325.32107 -295.717075) (xy 325.267113 -295.731181) (xy 325.211676 -295.737281)
			(xy 325.155942 -295.735244) (xy 325.101099 -295.725114) (xy 325.048315 -295.707107) (xy 324.998715 -295.681606)
			(xy 324.953357 -295.649155) (xy 324.913208 -295.610446) (xy 324.879122 -295.566303) (xy 324.851826 -295.517668)
			(xy 324.831903 -295.465577) (xy 324.819777 -295.41114) (xy 324.815706 -295.355518) (xy 281.616912 -295.355518)
			(xy 281.616912 -296.37482) (xy 282.519132 -296.37482) (xy 282.523092 -296.325766) (xy 282.534869 -296.277982)
			(xy 282.55416 -296.232706) (xy 282.580463 -296.19111) (xy 282.613098 -296.154273) (xy 282.651219 -296.123148)
			(xy 282.69384 -296.098541) (xy 282.739856 -296.081089) (xy 282.788075 -296.071245) (xy 282.83725 -296.069264)
			(xy 282.886105 -296.075196) (xy 282.933376 -296.088888) (xy 282.977838 -296.109986) (xy 283.018341 -296.137942)
			(xy 283.053834 -296.172034) (xy 283.083399 -296.211378) (xy 283.10627 -296.254955) (xy 283.121854 -296.301636)
			(xy 283.129749 -296.350213) (xy 283.130244 -296.37482) (xy 284.419052 -296.37482) (xy 284.423012 -296.325766)
			(xy 284.434789 -296.277982) (xy 284.45408 -296.232706) (xy 284.480383 -296.19111) (xy 284.513018 -296.154273)
			(xy 284.551139 -296.123148) (xy 284.59376 -296.098541) (xy 284.639776 -296.081089) (xy 284.687995 -296.071245)
			(xy 284.73717 -296.069264) (xy 284.786025 -296.075196) (xy 284.833296 -296.088888) (xy 284.877758 -296.109986)
			(xy 284.918261 -296.137942) (xy 284.953754 -296.172034) (xy 284.983319 -296.211378) (xy 285.00619 -296.254955)
			(xy 285.021774 -296.301636) (xy 285.029669 -296.350213) (xy 285.030164 -296.37482) (xy 286.318972 -296.37482)
			(xy 286.322932 -296.325766) (xy 286.334709 -296.277982) (xy 286.354 -296.232706) (xy 286.380303 -296.19111)
			(xy 286.412938 -296.154273) (xy 286.451059 -296.123148) (xy 286.49368 -296.098541) (xy 286.539696 -296.081089)
			(xy 286.587915 -296.071245) (xy 286.63709 -296.069264) (xy 286.685945 -296.075196) (xy 286.733216 -296.088888)
			(xy 286.777678 -296.109986) (xy 286.818181 -296.137942) (xy 286.853674 -296.172034) (xy 286.883239 -296.211378)
			(xy 286.90611 -296.254955) (xy 286.921694 -296.301636) (xy 286.929589 -296.350213) (xy 286.930084 -296.37482)
			(xy 288.219146 -296.37482) (xy 288.223106 -296.325766) (xy 288.234883 -296.277982) (xy 288.254174 -296.232706)
			(xy 288.280477 -296.19111) (xy 288.313112 -296.154273) (xy 288.351233 -296.123148) (xy 288.393854 -296.098541)
			(xy 288.43987 -296.081089) (xy 288.488089 -296.071245) (xy 288.537264 -296.069264) (xy 288.586119 -296.075196)
			(xy 288.63339 -296.088888) (xy 288.677852 -296.109986) (xy 288.718355 -296.137942) (xy 288.753848 -296.172034)
			(xy 288.783413 -296.211378) (xy 288.806284 -296.254955) (xy 288.821868 -296.301636) (xy 288.829763 -296.350213)
			(xy 288.830258 -296.37482) (xy 290.119066 -296.37482) (xy 290.123026 -296.325766) (xy 290.134803 -296.277982)
			(xy 290.154094 -296.232706) (xy 290.180397 -296.19111) (xy 290.213032 -296.154273) (xy 290.251153 -296.123148)
			(xy 290.293774 -296.098541) (xy 290.33979 -296.081089) (xy 290.388009 -296.071245) (xy 290.437184 -296.069264)
			(xy 290.486039 -296.075196) (xy 290.53331 -296.088888) (xy 290.577772 -296.109986) (xy 290.618275 -296.137942)
			(xy 290.653768 -296.172034) (xy 290.683333 -296.211378) (xy 290.706204 -296.254955) (xy 290.721788 -296.301636)
			(xy 290.729683 -296.350213) (xy 290.730178 -296.37482) (xy 292.968946 -296.37482) (xy 292.972906 -296.325766)
			(xy 292.984683 -296.277982) (xy 293.003974 -296.232706) (xy 293.030277 -296.19111) (xy 293.062912 -296.154273)
			(xy 293.101033 -296.123148) (xy 293.143654 -296.098541) (xy 293.18967 -296.081089) (xy 293.237889 -296.071245)
			(xy 293.287064 -296.069264) (xy 293.335919 -296.075196) (xy 293.38319 -296.088888) (xy 293.427652 -296.109986)
			(xy 293.468155 -296.137942) (xy 293.503648 -296.172034) (xy 293.533213 -296.211378) (xy 293.556084 -296.254955)
			(xy 293.571668 -296.301636) (xy 293.579563 -296.350213) (xy 293.580058 -296.37482) (xy 294.86912 -296.37482)
			(xy 294.87308 -296.325766) (xy 294.884857 -296.277982) (xy 294.904148 -296.232706) (xy 294.930451 -296.19111)
			(xy 294.963086 -296.154273) (xy 295.001207 -296.123148) (xy 295.043828 -296.098541) (xy 295.089844 -296.081089)
			(xy 295.138063 -296.071245) (xy 295.187238 -296.069264) (xy 295.236093 -296.075196) (xy 295.283364 -296.088888)
			(xy 295.327826 -296.109986) (xy 295.368329 -296.137942) (xy 295.403822 -296.172034) (xy 295.433387 -296.211378)
			(xy 295.456258 -296.254955) (xy 295.471842 -296.301636) (xy 295.479737 -296.350213) (xy 295.480232 -296.37482)
			(xy 296.76904 -296.37482) (xy 296.773 -296.325766) (xy 296.784777 -296.277982) (xy 296.804068 -296.232706)
			(xy 296.830371 -296.19111) (xy 296.863006 -296.154273) (xy 296.901127 -296.123148) (xy 296.943748 -296.098541)
			(xy 296.989764 -296.081089) (xy 297.037983 -296.071245) (xy 297.087158 -296.069264) (xy 297.136013 -296.075196)
			(xy 297.183284 -296.088888) (xy 297.227746 -296.109986) (xy 297.268249 -296.137942) (xy 297.303742 -296.172034)
			(xy 297.333307 -296.211378) (xy 297.356178 -296.254955) (xy 297.371762 -296.301636) (xy 297.379657 -296.350213)
			(xy 297.380152 -296.37482) (xy 298.66896 -296.37482) (xy 298.67292 -296.325766) (xy 298.684697 -296.277982)
			(xy 298.703988 -296.232706) (xy 298.730291 -296.19111) (xy 298.762926 -296.154273) (xy 298.801047 -296.123148)
			(xy 298.843668 -296.098541) (xy 298.889684 -296.081089) (xy 298.937903 -296.071245) (xy 298.987078 -296.069264)
			(xy 299.035933 -296.075196) (xy 299.083204 -296.088888) (xy 299.127666 -296.109986) (xy 299.168169 -296.137942)
			(xy 299.203662 -296.172034) (xy 299.233227 -296.211378) (xy 299.256098 -296.254955) (xy 299.271682 -296.301636)
			(xy 299.279577 -296.350213) (xy 299.280072 -296.37482) (xy 299.61892 -296.37482) (xy 299.62288 -296.325766)
			(xy 299.634657 -296.277982) (xy 299.653948 -296.232706) (xy 299.680251 -296.19111) (xy 299.712886 -296.154273)
			(xy 299.751007 -296.123148) (xy 299.793628 -296.098541) (xy 299.839644 -296.081089) (xy 299.887863 -296.071245)
			(xy 299.937038 -296.069264) (xy 299.985893 -296.075196) (xy 300.033164 -296.088888) (xy 300.077626 -296.109986)
			(xy 300.118129 -296.137942) (xy 300.153622 -296.172034) (xy 300.183187 -296.211378) (xy 300.206058 -296.254955)
			(xy 300.221642 -296.301636) (xy 300.229537 -296.350213) (xy 300.230032 -296.37482) (xy 300.56888 -296.37482)
			(xy 300.57284 -296.325766) (xy 300.584617 -296.277982) (xy 300.603908 -296.232706) (xy 300.630211 -296.19111)
			(xy 300.662846 -296.154273) (xy 300.700967 -296.123148) (xy 300.743588 -296.098541) (xy 300.789604 -296.081089)
			(xy 300.837823 -296.071245) (xy 300.886998 -296.069264) (xy 300.935853 -296.075196) (xy 300.983124 -296.088888)
			(xy 301.027586 -296.109986) (xy 301.068089 -296.137942) (xy 301.103582 -296.172034) (xy 301.133147 -296.211378)
			(xy 301.156018 -296.254955) (xy 301.171602 -296.301636) (xy 301.179497 -296.350213) (xy 301.179992 -296.37482)
			(xy 301.519094 -296.37482) (xy 301.523054 -296.325766) (xy 301.534831 -296.277982) (xy 301.554122 -296.232706)
			(xy 301.580425 -296.19111) (xy 301.61306 -296.154273) (xy 301.651181 -296.123148) (xy 301.693802 -296.098541)
			(xy 301.739818 -296.081089) (xy 301.788037 -296.071245) (xy 301.837212 -296.069264) (xy 301.886067 -296.075196)
			(xy 301.933338 -296.088888) (xy 301.9778 -296.109986) (xy 302.018303 -296.137942) (xy 302.053796 -296.172034)
			(xy 302.083361 -296.211378) (xy 302.106232 -296.254955) (xy 302.121816 -296.301636) (xy 302.129711 -296.350213)
			(xy 302.130206 -296.37482) (xy 302.469054 -296.37482) (xy 302.473014 -296.325766) (xy 302.484791 -296.277982)
			(xy 302.504082 -296.232706) (xy 302.530385 -296.19111) (xy 302.56302 -296.154273) (xy 302.601141 -296.123148)
			(xy 302.643762 -296.098541) (xy 302.689778 -296.081089) (xy 302.737997 -296.071245) (xy 302.787172 -296.069264)
			(xy 302.836027 -296.075196) (xy 302.883298 -296.088888) (xy 302.92776 -296.109986) (xy 302.968263 -296.137942)
			(xy 303.003756 -296.172034) (xy 303.033321 -296.211378) (xy 303.056192 -296.254955) (xy 303.071776 -296.301636)
			(xy 303.079671 -296.350213) (xy 303.080166 -296.37482) (xy 303.419014 -296.37482) (xy 303.422974 -296.325766)
			(xy 303.434751 -296.277982) (xy 303.454042 -296.232706) (xy 303.480345 -296.19111) (xy 303.51298 -296.154273)
			(xy 303.551101 -296.123148) (xy 303.593722 -296.098541) (xy 303.639738 -296.081089) (xy 303.687957 -296.071245)
			(xy 303.737132 -296.069264) (xy 303.785987 -296.075196) (xy 303.833258 -296.088888) (xy 303.87772 -296.109986)
			(xy 303.918223 -296.137942) (xy 303.953716 -296.172034) (xy 303.983281 -296.211378) (xy 304.006152 -296.254955)
			(xy 304.021736 -296.301636) (xy 304.029631 -296.350213) (xy 304.030126 -296.37482) (xy 304.368974 -296.37482)
			(xy 304.372934 -296.325766) (xy 304.384711 -296.277982) (xy 304.404002 -296.232706) (xy 304.430305 -296.19111)
			(xy 304.46294 -296.154273) (xy 304.501061 -296.123148) (xy 304.543682 -296.098541) (xy 304.589698 -296.081089)
			(xy 304.637917 -296.071245) (xy 304.687092 -296.069264) (xy 304.735947 -296.075196) (xy 304.783218 -296.088888)
			(xy 304.82768 -296.109986) (xy 304.868183 -296.137942) (xy 304.903676 -296.172034) (xy 304.933241 -296.211378)
			(xy 304.956112 -296.254955) (xy 304.971696 -296.301636) (xy 304.979591 -296.350213) (xy 304.980086 -296.37482)
			(xy 305.318934 -296.37482) (xy 305.322894 -296.325766) (xy 305.334671 -296.277982) (xy 305.353962 -296.232706)
			(xy 305.380265 -296.19111) (xy 305.4129 -296.154273) (xy 305.451021 -296.123148) (xy 305.493642 -296.098541)
			(xy 305.539658 -296.081089) (xy 305.587877 -296.071245) (xy 305.637052 -296.069264) (xy 305.685907 -296.075196)
			(xy 305.733178 -296.088888) (xy 305.77764 -296.109986) (xy 305.818143 -296.137942) (xy 305.853636 -296.172034)
			(xy 305.883201 -296.211378) (xy 305.906072 -296.254955) (xy 305.921656 -296.301636) (xy 305.929551 -296.350213)
			(xy 305.930046 -296.37482) (xy 306.268894 -296.37482) (xy 306.272854 -296.325766) (xy 306.284631 -296.277982)
			(xy 306.303922 -296.232706) (xy 306.330225 -296.19111) (xy 306.36286 -296.154273) (xy 306.400981 -296.123148)
			(xy 306.443602 -296.098541) (xy 306.489618 -296.081089) (xy 306.537837 -296.071245) (xy 306.587012 -296.069264)
			(xy 306.635867 -296.075196) (xy 306.683138 -296.088888) (xy 306.7276 -296.109986) (xy 306.768103 -296.137942)
			(xy 306.803596 -296.172034) (xy 306.833161 -296.211378) (xy 306.856032 -296.254955) (xy 306.871616 -296.301636)
			(xy 306.879511 -296.350213) (xy 306.880006 -296.37482) (xy 307.219108 -296.37482) (xy 307.223068 -296.325766)
			(xy 307.234845 -296.277982) (xy 307.254136 -296.232706) (xy 307.280439 -296.19111) (xy 307.313074 -296.154273)
			(xy 307.351195 -296.123148) (xy 307.393816 -296.098541) (xy 307.439832 -296.081089) (xy 307.488051 -296.071245)
			(xy 307.537226 -296.069264) (xy 307.586081 -296.075196) (xy 307.633352 -296.088888) (xy 307.677814 -296.109986)
			(xy 307.718317 -296.137942) (xy 307.75381 -296.172034) (xy 307.783375 -296.211378) (xy 307.806246 -296.254955)
			(xy 307.82183 -296.301636) (xy 307.829725 -296.350213) (xy 307.83022 -296.37482) (xy 308.169068 -296.37482)
			(xy 308.173028 -296.325766) (xy 308.184805 -296.277982) (xy 308.204096 -296.232706) (xy 308.230399 -296.19111)
			(xy 308.263034 -296.154273) (xy 308.301155 -296.123148) (xy 308.343776 -296.098541) (xy 308.389792 -296.081089)
			(xy 308.438011 -296.071245) (xy 308.487186 -296.069264) (xy 308.536041 -296.075196) (xy 308.583312 -296.088888)
			(xy 308.627774 -296.109986) (xy 308.668277 -296.137942) (xy 308.70377 -296.172034) (xy 308.733335 -296.211378)
			(xy 308.756206 -296.254955) (xy 308.77179 -296.301636) (xy 308.779685 -296.350213) (xy 308.78018 -296.37482)
			(xy 309.119028 -296.37482) (xy 309.122988 -296.325766) (xy 309.134765 -296.277982) (xy 309.154056 -296.232706)
			(xy 309.180359 -296.19111) (xy 309.212994 -296.154273) (xy 309.251115 -296.123148) (xy 309.293736 -296.098541)
			(xy 309.339752 -296.081089) (xy 309.387971 -296.071245) (xy 309.437146 -296.069264) (xy 309.486001 -296.075196)
			(xy 309.533272 -296.088888) (xy 309.577734 -296.109986) (xy 309.618237 -296.137942) (xy 309.65373 -296.172034)
			(xy 309.683295 -296.211378) (xy 309.706166 -296.254955) (xy 309.72175 -296.301636) (xy 309.729645 -296.350213)
			(xy 309.73014 -296.37482) (xy 310.068988 -296.37482) (xy 310.072948 -296.325766) (xy 310.084725 -296.277982)
			(xy 310.104016 -296.232706) (xy 310.130319 -296.19111) (xy 310.162954 -296.154273) (xy 310.201075 -296.123148)
			(xy 310.243696 -296.098541) (xy 310.289712 -296.081089) (xy 310.337931 -296.071245) (xy 310.387106 -296.069264)
			(xy 310.435961 -296.075196) (xy 310.483232 -296.088888) (xy 310.527694 -296.109986) (xy 310.568197 -296.137942)
			(xy 310.60369 -296.172034) (xy 310.633255 -296.211378) (xy 310.656126 -296.254955) (xy 310.67171 -296.301636)
			(xy 310.679605 -296.350213) (xy 310.6801 -296.37482) (xy 311.018948 -296.37482) (xy 311.022908 -296.325766)
			(xy 311.034685 -296.277982) (xy 311.053976 -296.232706) (xy 311.080279 -296.19111) (xy 311.112914 -296.154273)
			(xy 311.151035 -296.123148) (xy 311.193656 -296.098541) (xy 311.239672 -296.081089) (xy 311.287891 -296.071245)
			(xy 311.337066 -296.069264) (xy 311.385921 -296.075196) (xy 311.433192 -296.088888) (xy 311.477654 -296.109986)
			(xy 311.518157 -296.137942) (xy 311.55365 -296.172034) (xy 311.583215 -296.211378) (xy 311.606086 -296.254955)
			(xy 311.62167 -296.301636) (xy 311.629565 -296.350213) (xy 311.63006 -296.37482) (xy 311.968908 -296.37482)
			(xy 311.972868 -296.325766) (xy 311.984645 -296.277982) (xy 312.003936 -296.232706) (xy 312.030239 -296.19111)
			(xy 312.062874 -296.154273) (xy 312.100995 -296.123148) (xy 312.143616 -296.098541) (xy 312.189632 -296.081089)
			(xy 312.237851 -296.071245) (xy 312.287026 -296.069264) (xy 312.335881 -296.075196) (xy 312.383152 -296.088888)
			(xy 312.427614 -296.109986) (xy 312.468117 -296.137942) (xy 312.50361 -296.172034) (xy 312.533175 -296.211378)
			(xy 312.556046 -296.254955) (xy 312.57163 -296.301636) (xy 312.579525 -296.350213) (xy 312.58002 -296.37482)
			(xy 312.919122 -296.37482) (xy 312.923082 -296.325766) (xy 312.934859 -296.277982) (xy 312.95415 -296.232706)
			(xy 312.980453 -296.19111) (xy 313.013088 -296.154273) (xy 313.051209 -296.123148) (xy 313.09383 -296.098541)
			(xy 313.139846 -296.081089) (xy 313.188065 -296.071245) (xy 313.23724 -296.069264) (xy 313.286095 -296.075196)
			(xy 313.333366 -296.088888) (xy 313.377828 -296.109986) (xy 313.418331 -296.137942) (xy 313.453824 -296.172034)
			(xy 313.483389 -296.211378) (xy 313.50626 -296.254955) (xy 313.521844 -296.301636) (xy 313.529739 -296.350213)
			(xy 313.530234 -296.37482) (xy 313.869082 -296.37482) (xy 313.873042 -296.325766) (xy 313.884819 -296.277982)
			(xy 313.90411 -296.232706) (xy 313.930413 -296.19111) (xy 313.963048 -296.154273) (xy 314.001169 -296.123148)
			(xy 314.04379 -296.098541) (xy 314.089806 -296.081089) (xy 314.138025 -296.071245) (xy 314.1872 -296.069264)
			(xy 314.236055 -296.075196) (xy 314.283326 -296.088888) (xy 314.327788 -296.109986) (xy 314.368291 -296.137942)
			(xy 314.403784 -296.172034) (xy 314.433349 -296.211378) (xy 314.45622 -296.254955) (xy 314.471804 -296.301636)
			(xy 314.479699 -296.350213) (xy 314.480194 -296.37482) (xy 314.819042 -296.37482) (xy 314.823002 -296.325766)
			(xy 314.834779 -296.277982) (xy 314.85407 -296.232706) (xy 314.880373 -296.19111) (xy 314.913008 -296.154273)
			(xy 314.951129 -296.123148) (xy 314.99375 -296.098541) (xy 315.039766 -296.081089) (xy 315.087985 -296.071245)
			(xy 315.13716 -296.069264) (xy 315.186015 -296.075196) (xy 315.233286 -296.088888) (xy 315.277748 -296.109986)
			(xy 315.318251 -296.137942) (xy 315.353744 -296.172034) (xy 315.360113 -296.18051) (xy 316.956184 -296.18051)
			(xy 316.960255 -296.124888) (xy 316.972381 -296.070451) (xy 316.992304 -296.01836) (xy 317.0196 -295.969725)
			(xy 317.053686 -295.925582) (xy 317.093835 -295.886873) (xy 317.139193 -295.854422) (xy 317.188793 -295.828921)
			(xy 317.241577 -295.810914) (xy 317.29642 -295.800784) (xy 317.352154 -295.798747) (xy 317.407591 -295.804847)
			(xy 317.461548 -295.818953) (xy 317.512877 -295.840765) (xy 317.560483 -295.869819) (xy 317.603351 -295.905494)
			(xy 317.640568 -295.947031) (xy 317.671341 -295.993544) (xy 317.695013 -296.044041) (xy 317.711081 -296.097448)
			(xy 317.719201 -296.152624) (xy 317.71971 -296.18051) (xy 317.719201 -296.208396) (xy 317.711081 -296.263572)
			(xy 317.695013 -296.316979) (xy 317.671341 -296.367476) (xy 317.640568 -296.413989) (xy 317.603351 -296.455526)
			(xy 317.560483 -296.491201) (xy 317.512877 -296.520255) (xy 317.461548 -296.542067) (xy 317.407591 -296.556173)
			(xy 317.352154 -296.562273) (xy 317.29642 -296.560236) (xy 317.241577 -296.550106) (xy 317.188793 -296.532099)
			(xy 317.139193 -296.506598) (xy 317.093835 -296.474147) (xy 317.053686 -296.435438) (xy 317.0196 -296.391295)
			(xy 316.992304 -296.34266) (xy 316.972381 -296.290569) (xy 316.960255 -296.236132) (xy 316.956184 -296.18051)
			(xy 315.360113 -296.18051) (xy 315.383309 -296.211378) (xy 315.40618 -296.254955) (xy 315.421764 -296.301636)
			(xy 315.429659 -296.350213) (xy 315.430154 -296.37482) (xy 315.429659 -296.399427) (xy 315.421764 -296.448004)
			(xy 315.40618 -296.494685) (xy 315.383309 -296.538262) (xy 315.353744 -296.577606) (xy 315.318251 -296.611698)
			(xy 315.31626 -296.613072) (xy 321.462398 -296.613072) (xy 321.466469 -296.55745) (xy 321.478595 -296.503013)
			(xy 321.498518 -296.450922) (xy 321.525814 -296.402287) (xy 321.5599 -296.358144) (xy 321.600049 -296.319435)
			(xy 321.645407 -296.286984) (xy 321.695007 -296.261483) (xy 321.747791 -296.243476) (xy 321.802634 -296.233346)
			(xy 321.858368 -296.231309) (xy 321.913805 -296.237409) (xy 321.967762 -296.251515) (xy 322.019091 -296.273327)
			(xy 322.066697 -296.302381) (xy 322.109565 -296.338056) (xy 322.146782 -296.379593) (xy 322.177555 -296.426106)
			(xy 322.201227 -296.476603) (xy 322.217295 -296.53001) (xy 322.225415 -296.585186) (xy 322.225924 -296.613072)
			(xy 322.737224 -296.613072) (xy 322.741295 -296.55745) (xy 322.753421 -296.503013) (xy 322.773344 -296.450922)
			(xy 322.80064 -296.402287) (xy 322.834726 -296.358144) (xy 322.874875 -296.319435) (xy 322.920233 -296.286984)
			(xy 322.969833 -296.261483) (xy 323.022617 -296.243476) (xy 323.07746 -296.233346) (xy 323.133194 -296.231309)
			(xy 323.188631 -296.237409) (xy 323.242588 -296.251515) (xy 323.293917 -296.273327) (xy 323.341523 -296.302381)
			(xy 323.384391 -296.338056) (xy 323.421608 -296.379593) (xy 323.452381 -296.426106) (xy 323.476053 -296.476603)
			(xy 323.492121 -296.53001) (xy 323.500241 -296.585186) (xy 323.50075 -296.613072) (xy 323.500241 -296.640958)
			(xy 323.492121 -296.696134) (xy 323.476053 -296.749541) (xy 323.452381 -296.800038) (xy 323.421608 -296.846551)
			(xy 323.384391 -296.888088) (xy 323.341523 -296.923763) (xy 323.293917 -296.952817) (xy 323.242588 -296.974629)
			(xy 323.188631 -296.988735) (xy 323.133194 -296.994835) (xy 323.07746 -296.992798) (xy 323.022617 -296.982668)
			(xy 322.969833 -296.964661) (xy 322.920233 -296.93916) (xy 322.874875 -296.906709) (xy 322.834726 -296.868)
			(xy 322.80064 -296.823857) (xy 322.773344 -296.775222) (xy 322.753421 -296.723131) (xy 322.741295 -296.668694)
			(xy 322.737224 -296.613072) (xy 322.225924 -296.613072) (xy 322.225415 -296.640958) (xy 322.217295 -296.696134)
			(xy 322.201227 -296.749541) (xy 322.177555 -296.800038) (xy 322.146782 -296.846551) (xy 322.109565 -296.888088)
			(xy 322.066697 -296.923763) (xy 322.019091 -296.952817) (xy 321.967762 -296.974629) (xy 321.913805 -296.988735)
			(xy 321.858368 -296.994835) (xy 321.802634 -296.992798) (xy 321.747791 -296.982668) (xy 321.695007 -296.964661)
			(xy 321.645407 -296.93916) (xy 321.600049 -296.906709) (xy 321.5599 -296.868) (xy 321.525814 -296.823857)
			(xy 321.498518 -296.775222) (xy 321.478595 -296.723131) (xy 321.466469 -296.668694) (xy 321.462398 -296.613072)
			(xy 315.31626 -296.613072) (xy 315.277748 -296.639654) (xy 315.233286 -296.660752) (xy 315.186015 -296.674444)
			(xy 315.13716 -296.680376) (xy 315.087985 -296.678395) (xy 315.039766 -296.668551) (xy 314.99375 -296.651099)
			(xy 314.951129 -296.626492) (xy 314.913008 -296.595367) (xy 314.880373 -296.55853) (xy 314.85407 -296.516934)
			(xy 314.834779 -296.471658) (xy 314.823002 -296.423874) (xy 314.819042 -296.37482) (xy 314.480194 -296.37482)
			(xy 314.479699 -296.399427) (xy 314.471804 -296.448004) (xy 314.45622 -296.494685) (xy 314.433349 -296.538262)
			(xy 314.403784 -296.577606) (xy 314.368291 -296.611698) (xy 314.327788 -296.639654) (xy 314.283326 -296.660752)
			(xy 314.236055 -296.674444) (xy 314.1872 -296.680376) (xy 314.138025 -296.678395) (xy 314.089806 -296.668551)
			(xy 314.04379 -296.651099) (xy 314.001169 -296.626492) (xy 313.963048 -296.595367) (xy 313.930413 -296.55853)
			(xy 313.90411 -296.516934) (xy 313.884819 -296.471658) (xy 313.873042 -296.423874) (xy 313.869082 -296.37482)
			(xy 313.530234 -296.37482) (xy 313.529739 -296.399427) (xy 313.521844 -296.448004) (xy 313.50626 -296.494685)
			(xy 313.483389 -296.538262) (xy 313.453824 -296.577606) (xy 313.418331 -296.611698) (xy 313.377828 -296.639654)
			(xy 313.333366 -296.660752) (xy 313.286095 -296.674444) (xy 313.23724 -296.680376) (xy 313.188065 -296.678395)
			(xy 313.139846 -296.668551) (xy 313.09383 -296.651099) (xy 313.051209 -296.626492) (xy 313.013088 -296.595367)
			(xy 312.980453 -296.55853) (xy 312.95415 -296.516934) (xy 312.934859 -296.471658) (xy 312.923082 -296.423874)
			(xy 312.919122 -296.37482) (xy 312.58002 -296.37482) (xy 312.579525 -296.399427) (xy 312.57163 -296.448004)
			(xy 312.556046 -296.494685) (xy 312.533175 -296.538262) (xy 312.50361 -296.577606) (xy 312.468117 -296.611698)
			(xy 312.427614 -296.639654) (xy 312.383152 -296.660752) (xy 312.335881 -296.674444) (xy 312.287026 -296.680376)
			(xy 312.237851 -296.678395) (xy 312.189632 -296.668551) (xy 312.143616 -296.651099) (xy 312.100995 -296.626492)
			(xy 312.062874 -296.595367) (xy 312.030239 -296.55853) (xy 312.003936 -296.516934) (xy 311.984645 -296.471658)
			(xy 311.972868 -296.423874) (xy 311.968908 -296.37482) (xy 311.63006 -296.37482) (xy 311.629565 -296.399427)
			(xy 311.62167 -296.448004) (xy 311.606086 -296.494685) (xy 311.583215 -296.538262) (xy 311.55365 -296.577606)
			(xy 311.518157 -296.611698) (xy 311.477654 -296.639654) (xy 311.433192 -296.660752) (xy 311.385921 -296.674444)
			(xy 311.337066 -296.680376) (xy 311.287891 -296.678395) (xy 311.239672 -296.668551) (xy 311.193656 -296.651099)
			(xy 311.151035 -296.626492) (xy 311.112914 -296.595367) (xy 311.080279 -296.55853) (xy 311.053976 -296.516934)
			(xy 311.034685 -296.471658) (xy 311.022908 -296.423874) (xy 311.018948 -296.37482) (xy 310.6801 -296.37482)
			(xy 310.679605 -296.399427) (xy 310.67171 -296.448004) (xy 310.656126 -296.494685) (xy 310.633255 -296.538262)
			(xy 310.60369 -296.577606) (xy 310.568197 -296.611698) (xy 310.527694 -296.639654) (xy 310.483232 -296.660752)
			(xy 310.435961 -296.674444) (xy 310.387106 -296.680376) (xy 310.337931 -296.678395) (xy 310.289712 -296.668551)
			(xy 310.243696 -296.651099) (xy 310.201075 -296.626492) (xy 310.162954 -296.595367) (xy 310.130319 -296.55853)
			(xy 310.104016 -296.516934) (xy 310.084725 -296.471658) (xy 310.072948 -296.423874) (xy 310.068988 -296.37482)
			(xy 309.73014 -296.37482) (xy 309.729645 -296.399427) (xy 309.72175 -296.448004) (xy 309.706166 -296.494685)
			(xy 309.683295 -296.538262) (xy 309.65373 -296.577606) (xy 309.618237 -296.611698) (xy 309.577734 -296.639654)
			(xy 309.533272 -296.660752) (xy 309.486001 -296.674444) (xy 309.437146 -296.680376) (xy 309.387971 -296.678395)
			(xy 309.339752 -296.668551) (xy 309.293736 -296.651099) (xy 309.251115 -296.626492) (xy 309.212994 -296.595367)
			(xy 309.180359 -296.55853) (xy 309.154056 -296.516934) (xy 309.134765 -296.471658) (xy 309.122988 -296.423874)
			(xy 309.119028 -296.37482) (xy 308.78018 -296.37482) (xy 308.779685 -296.399427) (xy 308.77179 -296.448004)
			(xy 308.756206 -296.494685) (xy 308.733335 -296.538262) (xy 308.70377 -296.577606) (xy 308.668277 -296.611698)
			(xy 308.627774 -296.639654) (xy 308.583312 -296.660752) (xy 308.536041 -296.674444) (xy 308.487186 -296.680376)
			(xy 308.438011 -296.678395) (xy 308.389792 -296.668551) (xy 308.343776 -296.651099) (xy 308.301155 -296.626492)
			(xy 308.263034 -296.595367) (xy 308.230399 -296.55853) (xy 308.204096 -296.516934) (xy 308.184805 -296.471658)
			(xy 308.173028 -296.423874) (xy 308.169068 -296.37482) (xy 307.83022 -296.37482) (xy 307.829725 -296.399427)
			(xy 307.82183 -296.448004) (xy 307.806246 -296.494685) (xy 307.783375 -296.538262) (xy 307.75381 -296.577606)
			(xy 307.718317 -296.611698) (xy 307.677814 -296.639654) (xy 307.633352 -296.660752) (xy 307.586081 -296.674444)
			(xy 307.537226 -296.680376) (xy 307.488051 -296.678395) (xy 307.439832 -296.668551) (xy 307.393816 -296.651099)
			(xy 307.351195 -296.626492) (xy 307.313074 -296.595367) (xy 307.280439 -296.55853) (xy 307.254136 -296.516934)
			(xy 307.234845 -296.471658) (xy 307.223068 -296.423874) (xy 307.219108 -296.37482) (xy 306.880006 -296.37482)
			(xy 306.879511 -296.399427) (xy 306.871616 -296.448004) (xy 306.856032 -296.494685) (xy 306.833161 -296.538262)
			(xy 306.803596 -296.577606) (xy 306.768103 -296.611698) (xy 306.7276 -296.639654) (xy 306.683138 -296.660752)
			(xy 306.635867 -296.674444) (xy 306.587012 -296.680376) (xy 306.537837 -296.678395) (xy 306.489618 -296.668551)
			(xy 306.443602 -296.651099) (xy 306.400981 -296.626492) (xy 306.36286 -296.595367) (xy 306.330225 -296.55853)
			(xy 306.303922 -296.516934) (xy 306.284631 -296.471658) (xy 306.272854 -296.423874) (xy 306.268894 -296.37482)
			(xy 305.930046 -296.37482) (xy 305.929551 -296.399427) (xy 305.921656 -296.448004) (xy 305.906072 -296.494685)
			(xy 305.883201 -296.538262) (xy 305.853636 -296.577606) (xy 305.818143 -296.611698) (xy 305.77764 -296.639654)
			(xy 305.733178 -296.660752) (xy 305.685907 -296.674444) (xy 305.637052 -296.680376) (xy 305.587877 -296.678395)
			(xy 305.539658 -296.668551) (xy 305.493642 -296.651099) (xy 305.451021 -296.626492) (xy 305.4129 -296.595367)
			(xy 305.380265 -296.55853) (xy 305.353962 -296.516934) (xy 305.334671 -296.471658) (xy 305.322894 -296.423874)
			(xy 305.318934 -296.37482) (xy 304.980086 -296.37482) (xy 304.979591 -296.399427) (xy 304.971696 -296.448004)
			(xy 304.956112 -296.494685) (xy 304.933241 -296.538262) (xy 304.903676 -296.577606) (xy 304.868183 -296.611698)
			(xy 304.82768 -296.639654) (xy 304.783218 -296.660752) (xy 304.735947 -296.674444) (xy 304.687092 -296.680376)
			(xy 304.637917 -296.678395) (xy 304.589698 -296.668551) (xy 304.543682 -296.651099) (xy 304.501061 -296.626492)
			(xy 304.46294 -296.595367) (xy 304.430305 -296.55853) (xy 304.404002 -296.516934) (xy 304.384711 -296.471658)
			(xy 304.372934 -296.423874) (xy 304.368974 -296.37482) (xy 304.030126 -296.37482) (xy 304.029631 -296.399427)
			(xy 304.021736 -296.448004) (xy 304.006152 -296.494685) (xy 303.983281 -296.538262) (xy 303.953716 -296.577606)
			(xy 303.918223 -296.611698) (xy 303.87772 -296.639654) (xy 303.833258 -296.660752) (xy 303.785987 -296.674444)
			(xy 303.737132 -296.680376) (xy 303.687957 -296.678395) (xy 303.639738 -296.668551) (xy 303.593722 -296.651099)
			(xy 303.551101 -296.626492) (xy 303.51298 -296.595367) (xy 303.480345 -296.55853) (xy 303.454042 -296.516934)
			(xy 303.434751 -296.471658) (xy 303.422974 -296.423874) (xy 303.419014 -296.37482) (xy 303.080166 -296.37482)
			(xy 303.079671 -296.399427) (xy 303.071776 -296.448004) (xy 303.056192 -296.494685) (xy 303.033321 -296.538262)
			(xy 303.003756 -296.577606) (xy 302.968263 -296.611698) (xy 302.92776 -296.639654) (xy 302.883298 -296.660752)
			(xy 302.836027 -296.674444) (xy 302.787172 -296.680376) (xy 302.737997 -296.678395) (xy 302.689778 -296.668551)
			(xy 302.643762 -296.651099) (xy 302.601141 -296.626492) (xy 302.56302 -296.595367) (xy 302.530385 -296.55853)
			(xy 302.504082 -296.516934) (xy 302.484791 -296.471658) (xy 302.473014 -296.423874) (xy 302.469054 -296.37482)
			(xy 302.130206 -296.37482) (xy 302.129711 -296.399427) (xy 302.121816 -296.448004) (xy 302.106232 -296.494685)
			(xy 302.083361 -296.538262) (xy 302.053796 -296.577606) (xy 302.018303 -296.611698) (xy 301.9778 -296.639654)
			(xy 301.933338 -296.660752) (xy 301.886067 -296.674444) (xy 301.837212 -296.680376) (xy 301.788037 -296.678395)
			(xy 301.739818 -296.668551) (xy 301.693802 -296.651099) (xy 301.651181 -296.626492) (xy 301.61306 -296.595367)
			(xy 301.580425 -296.55853) (xy 301.554122 -296.516934) (xy 301.534831 -296.471658) (xy 301.523054 -296.423874)
			(xy 301.519094 -296.37482) (xy 301.179992 -296.37482) (xy 301.179497 -296.399427) (xy 301.171602 -296.448004)
			(xy 301.156018 -296.494685) (xy 301.133147 -296.538262) (xy 301.103582 -296.577606) (xy 301.068089 -296.611698)
			(xy 301.027586 -296.639654) (xy 300.983124 -296.660752) (xy 300.935853 -296.674444) (xy 300.886998 -296.680376)
			(xy 300.837823 -296.678395) (xy 300.789604 -296.668551) (xy 300.743588 -296.651099) (xy 300.700967 -296.626492)
			(xy 300.662846 -296.595367) (xy 300.630211 -296.55853) (xy 300.603908 -296.516934) (xy 300.584617 -296.471658)
			(xy 300.57284 -296.423874) (xy 300.56888 -296.37482) (xy 300.230032 -296.37482) (xy 300.229537 -296.399427)
			(xy 300.221642 -296.448004) (xy 300.206058 -296.494685) (xy 300.183187 -296.538262) (xy 300.153622 -296.577606)
			(xy 300.118129 -296.611698) (xy 300.077626 -296.639654) (xy 300.033164 -296.660752) (xy 299.985893 -296.674444)
			(xy 299.937038 -296.680376) (xy 299.887863 -296.678395) (xy 299.839644 -296.668551) (xy 299.793628 -296.651099)
			(xy 299.751007 -296.626492) (xy 299.712886 -296.595367) (xy 299.680251 -296.55853) (xy 299.653948 -296.516934)
			(xy 299.634657 -296.471658) (xy 299.62288 -296.423874) (xy 299.61892 -296.37482) (xy 299.280072 -296.37482)
			(xy 299.279577 -296.399427) (xy 299.271682 -296.448004) (xy 299.256098 -296.494685) (xy 299.233227 -296.538262)
			(xy 299.203662 -296.577606) (xy 299.168169 -296.611698) (xy 299.127666 -296.639654) (xy 299.083204 -296.660752)
			(xy 299.035933 -296.674444) (xy 298.987078 -296.680376) (xy 298.937903 -296.678395) (xy 298.889684 -296.668551)
			(xy 298.843668 -296.651099) (xy 298.801047 -296.626492) (xy 298.762926 -296.595367) (xy 298.730291 -296.55853)
			(xy 298.703988 -296.516934) (xy 298.684697 -296.471658) (xy 298.67292 -296.423874) (xy 298.66896 -296.37482)
			(xy 297.380152 -296.37482) (xy 297.379657 -296.399427) (xy 297.371762 -296.448004) (xy 297.356178 -296.494685)
			(xy 297.333307 -296.538262) (xy 297.303742 -296.577606) (xy 297.268249 -296.611698) (xy 297.227746 -296.639654)
			(xy 297.183284 -296.660752) (xy 297.136013 -296.674444) (xy 297.087158 -296.680376) (xy 297.037983 -296.678395)
			(xy 296.989764 -296.668551) (xy 296.943748 -296.651099) (xy 296.901127 -296.626492) (xy 296.863006 -296.595367)
			(xy 296.830371 -296.55853) (xy 296.804068 -296.516934) (xy 296.784777 -296.471658) (xy 296.773 -296.423874)
			(xy 296.76904 -296.37482) (xy 295.480232 -296.37482) (xy 295.479737 -296.399427) (xy 295.471842 -296.448004)
			(xy 295.456258 -296.494685) (xy 295.433387 -296.538262) (xy 295.403822 -296.577606) (xy 295.368329 -296.611698)
			(xy 295.327826 -296.639654) (xy 295.283364 -296.660752) (xy 295.236093 -296.674444) (xy 295.187238 -296.680376)
			(xy 295.138063 -296.678395) (xy 295.089844 -296.668551) (xy 295.043828 -296.651099) (xy 295.001207 -296.626492)
			(xy 294.963086 -296.595367) (xy 294.930451 -296.55853) (xy 294.904148 -296.516934) (xy 294.884857 -296.471658)
			(xy 294.87308 -296.423874) (xy 294.86912 -296.37482) (xy 293.580058 -296.37482) (xy 293.579563 -296.399427)
			(xy 293.571668 -296.448004) (xy 293.556084 -296.494685) (xy 293.533213 -296.538262) (xy 293.503648 -296.577606)
			(xy 293.468155 -296.611698) (xy 293.427652 -296.639654) (xy 293.38319 -296.660752) (xy 293.335919 -296.674444)
			(xy 293.287064 -296.680376) (xy 293.237889 -296.678395) (xy 293.18967 -296.668551) (xy 293.143654 -296.651099)
			(xy 293.101033 -296.626492) (xy 293.062912 -296.595367) (xy 293.030277 -296.55853) (xy 293.003974 -296.516934)
			(xy 292.984683 -296.471658) (xy 292.972906 -296.423874) (xy 292.968946 -296.37482) (xy 290.730178 -296.37482)
			(xy 290.729683 -296.399427) (xy 290.721788 -296.448004) (xy 290.706204 -296.494685) (xy 290.683333 -296.538262)
			(xy 290.653768 -296.577606) (xy 290.618275 -296.611698) (xy 290.577772 -296.639654) (xy 290.53331 -296.660752)
			(xy 290.486039 -296.674444) (xy 290.437184 -296.680376) (xy 290.388009 -296.678395) (xy 290.33979 -296.668551)
			(xy 290.293774 -296.651099) (xy 290.251153 -296.626492) (xy 290.213032 -296.595367) (xy 290.180397 -296.55853)
			(xy 290.154094 -296.516934) (xy 290.134803 -296.471658) (xy 290.123026 -296.423874) (xy 290.119066 -296.37482)
			(xy 288.830258 -296.37482) (xy 288.829763 -296.399427) (xy 288.821868 -296.448004) (xy 288.806284 -296.494685)
			(xy 288.783413 -296.538262) (xy 288.753848 -296.577606) (xy 288.718355 -296.611698) (xy 288.677852 -296.639654)
			(xy 288.63339 -296.660752) (xy 288.586119 -296.674444) (xy 288.537264 -296.680376) (xy 288.488089 -296.678395)
			(xy 288.43987 -296.668551) (xy 288.393854 -296.651099) (xy 288.351233 -296.626492) (xy 288.313112 -296.595367)
			(xy 288.280477 -296.55853) (xy 288.254174 -296.516934) (xy 288.234883 -296.471658) (xy 288.223106 -296.423874)
			(xy 288.219146 -296.37482) (xy 286.930084 -296.37482) (xy 286.929589 -296.399427) (xy 286.921694 -296.448004)
			(xy 286.90611 -296.494685) (xy 286.883239 -296.538262) (xy 286.853674 -296.577606) (xy 286.818181 -296.611698)
			(xy 286.777678 -296.639654) (xy 286.733216 -296.660752) (xy 286.685945 -296.674444) (xy 286.63709 -296.680376)
			(xy 286.587915 -296.678395) (xy 286.539696 -296.668551) (xy 286.49368 -296.651099) (xy 286.451059 -296.626492)
			(xy 286.412938 -296.595367) (xy 286.380303 -296.55853) (xy 286.354 -296.516934) (xy 286.334709 -296.471658)
			(xy 286.322932 -296.423874) (xy 286.318972 -296.37482) (xy 285.030164 -296.37482) (xy 285.029669 -296.399427)
			(xy 285.021774 -296.448004) (xy 285.00619 -296.494685) (xy 284.983319 -296.538262) (xy 284.953754 -296.577606)
			(xy 284.918261 -296.611698) (xy 284.877758 -296.639654) (xy 284.833296 -296.660752) (xy 284.786025 -296.674444)
			(xy 284.73717 -296.680376) (xy 284.687995 -296.678395) (xy 284.639776 -296.668551) (xy 284.59376 -296.651099)
			(xy 284.551139 -296.626492) (xy 284.513018 -296.595367) (xy 284.480383 -296.55853) (xy 284.45408 -296.516934)
			(xy 284.434789 -296.471658) (xy 284.423012 -296.423874) (xy 284.419052 -296.37482) (xy 283.130244 -296.37482)
			(xy 283.129749 -296.399427) (xy 283.121854 -296.448004) (xy 283.10627 -296.494685) (xy 283.083399 -296.538262)
			(xy 283.053834 -296.577606) (xy 283.018341 -296.611698) (xy 282.977838 -296.639654) (xy 282.933376 -296.660752)
			(xy 282.886105 -296.674444) (xy 282.83725 -296.680376) (xy 282.788075 -296.678395) (xy 282.739856 -296.668551)
			(xy 282.69384 -296.651099) (xy 282.651219 -296.626492) (xy 282.613098 -296.595367) (xy 282.580463 -296.55853)
			(xy 282.55416 -296.516934) (xy 282.534869 -296.471658) (xy 282.523092 -296.423874) (xy 282.519132 -296.37482)
			(xy 281.616912 -296.37482) (xy 281.616912 -296.949114) (xy 281.617557 -296.961668) (xy 281.629416 -296.983797)
			(xy 281.639518 -296.991278) (xy 281.720544 -297.04538) (xy 281.745436 -297.04792) (xy 281.757628 -297.04284)
			(xy 281.785665 -297.03194) (xy 281.844649 -297.020172) (xy 281.874722 -297.019472) (xy 281.899978 -297.019995)
			(xy 281.9498 -297.028313) (xy 281.997574 -297.044716) (xy 282.041996 -297.068759) (xy 282.081856 -297.099786)
			(xy 282.116065 -297.13695) (xy 282.143691 -297.179237) (xy 282.163981 -297.225495) (xy 282.17638 -297.274461)
			(xy 282.180549 -297.32478) (xy 283.469092 -297.32478) (xy 283.473052 -297.275726) (xy 283.484829 -297.227942)
			(xy 283.50412 -297.182666) (xy 283.530423 -297.14107) (xy 283.563058 -297.104233) (xy 283.601179 -297.073108)
			(xy 283.6438 -297.048501) (xy 283.689816 -297.031049) (xy 283.738035 -297.021205) (xy 283.78721 -297.019224)
			(xy 283.836065 -297.025156) (xy 283.883336 -297.038848) (xy 283.927798 -297.059946) (xy 283.968301 -297.087902)
			(xy 284.003794 -297.121994) (xy 284.033359 -297.161338) (xy 284.05623 -297.204915) (xy 284.071814 -297.251596)
			(xy 284.079709 -297.300173) (xy 284.080204 -297.32478) (xy 285.369012 -297.32478) (xy 285.372972 -297.275726)
			(xy 285.384749 -297.227942) (xy 285.40404 -297.182666) (xy 285.430343 -297.14107) (xy 285.462978 -297.104233)
			(xy 285.501099 -297.073108) (xy 285.54372 -297.048501) (xy 285.589736 -297.031049) (xy 285.637955 -297.021205)
			(xy 285.68713 -297.019224) (xy 285.735985 -297.025156) (xy 285.783256 -297.038848) (xy 285.827718 -297.059946)
			(xy 285.868221 -297.087902) (xy 285.903714 -297.121994) (xy 285.933279 -297.161338) (xy 285.95615 -297.204915)
			(xy 285.971734 -297.251596) (xy 285.979629 -297.300173) (xy 285.980124 -297.32478) (xy 287.268932 -297.32478)
			(xy 287.272892 -297.275726) (xy 287.284669 -297.227942) (xy 287.30396 -297.182666) (xy 287.330263 -297.14107)
			(xy 287.362898 -297.104233) (xy 287.401019 -297.073108) (xy 287.44364 -297.048501) (xy 287.489656 -297.031049)
			(xy 287.537875 -297.021205) (xy 287.58705 -297.019224) (xy 287.635905 -297.025156) (xy 287.683176 -297.038848)
			(xy 287.727638 -297.059946) (xy 287.768141 -297.087902) (xy 287.803634 -297.121994) (xy 287.833199 -297.161338)
			(xy 287.85607 -297.204915) (xy 287.871654 -297.251596) (xy 287.879549 -297.300173) (xy 287.880044 -297.32478)
			(xy 289.169106 -297.32478) (xy 289.173066 -297.275726) (xy 289.184843 -297.227942) (xy 289.204134 -297.182666)
			(xy 289.230437 -297.14107) (xy 289.263072 -297.104233) (xy 289.301193 -297.073108) (xy 289.343814 -297.048501)
			(xy 289.38983 -297.031049) (xy 289.438049 -297.021205) (xy 289.487224 -297.019224) (xy 289.536079 -297.025156)
			(xy 289.58335 -297.038848) (xy 289.627812 -297.059946) (xy 289.668315 -297.087902) (xy 289.703808 -297.121994)
			(xy 289.733373 -297.161338) (xy 289.756244 -297.204915) (xy 289.771828 -297.251596) (xy 289.779723 -297.300173)
			(xy 289.780218 -297.32478) (xy 292.018986 -297.32478) (xy 292.022946 -297.275726) (xy 292.034723 -297.227942)
			(xy 292.054014 -297.182666) (xy 292.080317 -297.14107) (xy 292.112952 -297.104233) (xy 292.151073 -297.073108)
			(xy 292.193694 -297.048501) (xy 292.23971 -297.031049) (xy 292.287929 -297.021205) (xy 292.337104 -297.019224)
			(xy 292.385959 -297.025156) (xy 292.43323 -297.038848) (xy 292.477692 -297.059946) (xy 292.518195 -297.087902)
			(xy 292.553688 -297.121994) (xy 292.583253 -297.161338) (xy 292.606124 -297.204915) (xy 292.621708 -297.251596)
			(xy 292.629603 -297.300173) (xy 292.630098 -297.32478) (xy 293.918906 -297.32478) (xy 293.922866 -297.275726)
			(xy 293.934643 -297.227942) (xy 293.953934 -297.182666) (xy 293.980237 -297.14107) (xy 294.012872 -297.104233)
			(xy 294.050993 -297.073108) (xy 294.093614 -297.048501) (xy 294.13963 -297.031049) (xy 294.187849 -297.021205)
			(xy 294.237024 -297.019224) (xy 294.285879 -297.025156) (xy 294.33315 -297.038848) (xy 294.377612 -297.059946)
			(xy 294.418115 -297.087902) (xy 294.453608 -297.121994) (xy 294.483173 -297.161338) (xy 294.506044 -297.204915)
			(xy 294.521628 -297.251596) (xy 294.529523 -297.300173) (xy 294.530018 -297.32478) (xy 295.81908 -297.32478)
			(xy 295.82304 -297.275726) (xy 295.834817 -297.227942) (xy 295.854108 -297.182666) (xy 295.880411 -297.14107)
			(xy 295.913046 -297.104233) (xy 295.951167 -297.073108) (xy 295.993788 -297.048501) (xy 296.039804 -297.031049)
			(xy 296.088023 -297.021205) (xy 296.137198 -297.019224) (xy 296.186053 -297.025156) (xy 296.233324 -297.038848)
			(xy 296.277786 -297.059946) (xy 296.318289 -297.087902) (xy 296.353782 -297.121994) (xy 296.383347 -297.161338)
			(xy 296.406218 -297.204915) (xy 296.421802 -297.251596) (xy 296.429697 -297.300173) (xy 296.430192 -297.32478)
			(xy 297.719 -297.32478) (xy 297.72296 -297.275726) (xy 297.734737 -297.227942) (xy 297.754028 -297.182666)
			(xy 297.780331 -297.14107) (xy 297.812966 -297.104233) (xy 297.851087 -297.073108) (xy 297.893708 -297.048501)
			(xy 297.939724 -297.031049) (xy 297.987943 -297.021205) (xy 298.037118 -297.019224) (xy 298.085973 -297.025156)
			(xy 298.133244 -297.038848) (xy 298.177706 -297.059946) (xy 298.218209 -297.087902) (xy 298.253702 -297.121994)
			(xy 298.283267 -297.161338) (xy 298.306138 -297.204915) (xy 298.321722 -297.251596) (xy 298.329617 -297.300173)
			(xy 298.330112 -297.32478) (xy 298.66896 -297.32478) (xy 298.67292 -297.275726) (xy 298.684697 -297.227942)
			(xy 298.703988 -297.182666) (xy 298.730291 -297.14107) (xy 298.762926 -297.104233) (xy 298.801047 -297.073108)
			(xy 298.843668 -297.048501) (xy 298.889684 -297.031049) (xy 298.937903 -297.021205) (xy 298.987078 -297.019224)
			(xy 299.035933 -297.025156) (xy 299.083204 -297.038848) (xy 299.127666 -297.059946) (xy 299.168169 -297.087902)
			(xy 299.203662 -297.121994) (xy 299.233227 -297.161338) (xy 299.256098 -297.204915) (xy 299.271682 -297.251596)
			(xy 299.279577 -297.300173) (xy 299.280072 -297.32478) (xy 299.61892 -297.32478) (xy 299.62288 -297.275726)
			(xy 299.634657 -297.227942) (xy 299.653948 -297.182666) (xy 299.680251 -297.14107) (xy 299.712886 -297.104233)
			(xy 299.751007 -297.073108) (xy 299.793628 -297.048501) (xy 299.839644 -297.031049) (xy 299.887863 -297.021205)
			(xy 299.937038 -297.019224) (xy 299.985893 -297.025156) (xy 300.033164 -297.038848) (xy 300.077626 -297.059946)
			(xy 300.118129 -297.087902) (xy 300.153622 -297.121994) (xy 300.183187 -297.161338) (xy 300.206058 -297.204915)
			(xy 300.221642 -297.251596) (xy 300.229537 -297.300173) (xy 300.230032 -297.32478) (xy 300.56888 -297.32478)
			(xy 300.57284 -297.275726) (xy 300.584617 -297.227942) (xy 300.603908 -297.182666) (xy 300.630211 -297.14107)
			(xy 300.662846 -297.104233) (xy 300.700967 -297.073108) (xy 300.743588 -297.048501) (xy 300.789604 -297.031049)
			(xy 300.837823 -297.021205) (xy 300.886998 -297.019224) (xy 300.935853 -297.025156) (xy 300.983124 -297.038848)
			(xy 301.027586 -297.059946) (xy 301.068089 -297.087902) (xy 301.103582 -297.121994) (xy 301.133147 -297.161338)
			(xy 301.156018 -297.204915) (xy 301.171602 -297.251596) (xy 301.179497 -297.300173) (xy 301.179992 -297.32478)
			(xy 301.519094 -297.32478) (xy 301.523054 -297.275726) (xy 301.534831 -297.227942) (xy 301.554122 -297.182666)
			(xy 301.580425 -297.14107) (xy 301.61306 -297.104233) (xy 301.651181 -297.073108) (xy 301.693802 -297.048501)
			(xy 301.739818 -297.031049) (xy 301.788037 -297.021205) (xy 301.837212 -297.019224) (xy 301.886067 -297.025156)
			(xy 301.933338 -297.038848) (xy 301.9778 -297.059946) (xy 302.018303 -297.087902) (xy 302.053796 -297.121994)
			(xy 302.083361 -297.161338) (xy 302.106232 -297.204915) (xy 302.121816 -297.251596) (xy 302.129711 -297.300173)
			(xy 302.130206 -297.32478) (xy 302.469054 -297.32478) (xy 302.473014 -297.275726) (xy 302.484791 -297.227942)
			(xy 302.504082 -297.182666) (xy 302.530385 -297.14107) (xy 302.56302 -297.104233) (xy 302.601141 -297.073108)
			(xy 302.643762 -297.048501) (xy 302.689778 -297.031049) (xy 302.737997 -297.021205) (xy 302.787172 -297.019224)
			(xy 302.836027 -297.025156) (xy 302.883298 -297.038848) (xy 302.92776 -297.059946) (xy 302.968263 -297.087902)
			(xy 303.003756 -297.121994) (xy 303.033321 -297.161338) (xy 303.056192 -297.204915) (xy 303.071776 -297.251596)
			(xy 303.079671 -297.300173) (xy 303.080166 -297.32478) (xy 303.419014 -297.32478) (xy 303.422974 -297.275726)
			(xy 303.434751 -297.227942) (xy 303.454042 -297.182666) (xy 303.480345 -297.14107) (xy 303.51298 -297.104233)
			(xy 303.551101 -297.073108) (xy 303.593722 -297.048501) (xy 303.639738 -297.031049) (xy 303.687957 -297.021205)
			(xy 303.737132 -297.019224) (xy 303.785987 -297.025156) (xy 303.833258 -297.038848) (xy 303.87772 -297.059946)
			(xy 303.918223 -297.087902) (xy 303.953716 -297.121994) (xy 303.983281 -297.161338) (xy 304.006152 -297.204915)
			(xy 304.021736 -297.251596) (xy 304.029631 -297.300173) (xy 304.030126 -297.32478) (xy 304.368974 -297.32478)
			(xy 304.372934 -297.275726) (xy 304.384711 -297.227942) (xy 304.404002 -297.182666) (xy 304.430305 -297.14107)
			(xy 304.46294 -297.104233) (xy 304.501061 -297.073108) (xy 304.543682 -297.048501) (xy 304.589698 -297.031049)
			(xy 304.637917 -297.021205) (xy 304.687092 -297.019224) (xy 304.735947 -297.025156) (xy 304.783218 -297.038848)
			(xy 304.82768 -297.059946) (xy 304.868183 -297.087902) (xy 304.903676 -297.121994) (xy 304.933241 -297.161338)
			(xy 304.956112 -297.204915) (xy 304.971696 -297.251596) (xy 304.979591 -297.300173) (xy 304.980086 -297.32478)
			(xy 305.318934 -297.32478) (xy 305.322894 -297.275726) (xy 305.334671 -297.227942) (xy 305.353962 -297.182666)
			(xy 305.380265 -297.14107) (xy 305.4129 -297.104233) (xy 305.451021 -297.073108) (xy 305.493642 -297.048501)
			(xy 305.539658 -297.031049) (xy 305.587877 -297.021205) (xy 305.637052 -297.019224) (xy 305.685907 -297.025156)
			(xy 305.733178 -297.038848) (xy 305.77764 -297.059946) (xy 305.818143 -297.087902) (xy 305.853636 -297.121994)
			(xy 305.883201 -297.161338) (xy 305.906072 -297.204915) (xy 305.921656 -297.251596) (xy 305.929551 -297.300173)
			(xy 305.930046 -297.32478) (xy 306.269148 -297.32478) (xy 306.273108 -297.275726) (xy 306.284885 -297.227942)
			(xy 306.304176 -297.182666) (xy 306.330479 -297.14107) (xy 306.363114 -297.104233) (xy 306.401235 -297.073108)
			(xy 306.443856 -297.048501) (xy 306.489872 -297.031049) (xy 306.538091 -297.021205) (xy 306.587266 -297.019224)
			(xy 306.636121 -297.025156) (xy 306.683392 -297.038848) (xy 306.727854 -297.059946) (xy 306.768357 -297.087902)
			(xy 306.80385 -297.121994) (xy 306.833415 -297.161338) (xy 306.856286 -297.204915) (xy 306.87187 -297.251596)
			(xy 306.879765 -297.300173) (xy 306.88026 -297.32478) (xy 307.219108 -297.32478) (xy 307.223068 -297.275726)
			(xy 307.234845 -297.227942) (xy 307.254136 -297.182666) (xy 307.280439 -297.14107) (xy 307.313074 -297.104233)
			(xy 307.351195 -297.073108) (xy 307.393816 -297.048501) (xy 307.439832 -297.031049) (xy 307.488051 -297.021205)
			(xy 307.537226 -297.019224) (xy 307.586081 -297.025156) (xy 307.633352 -297.038848) (xy 307.677814 -297.059946)
			(xy 307.718317 -297.087902) (xy 307.75381 -297.121994) (xy 307.783375 -297.161338) (xy 307.806246 -297.204915)
			(xy 307.82183 -297.251596) (xy 307.829725 -297.300173) (xy 307.83022 -297.32478) (xy 308.169068 -297.32478)
			(xy 308.173028 -297.275726) (xy 308.184805 -297.227942) (xy 308.204096 -297.182666) (xy 308.230399 -297.14107)
			(xy 308.263034 -297.104233) (xy 308.301155 -297.073108) (xy 308.343776 -297.048501) (xy 308.389792 -297.031049)
			(xy 308.438011 -297.021205) (xy 308.487186 -297.019224) (xy 308.536041 -297.025156) (xy 308.583312 -297.038848)
			(xy 308.627774 -297.059946) (xy 308.668277 -297.087902) (xy 308.70377 -297.121994) (xy 308.733335 -297.161338)
			(xy 308.756206 -297.204915) (xy 308.77179 -297.251596) (xy 308.779685 -297.300173) (xy 308.78018 -297.32478)
			(xy 309.119028 -297.32478) (xy 309.122988 -297.275726) (xy 309.134765 -297.227942) (xy 309.154056 -297.182666)
			(xy 309.180359 -297.14107) (xy 309.212994 -297.104233) (xy 309.251115 -297.073108) (xy 309.293736 -297.048501)
			(xy 309.339752 -297.031049) (xy 309.387971 -297.021205) (xy 309.437146 -297.019224) (xy 309.486001 -297.025156)
			(xy 309.533272 -297.038848) (xy 309.577734 -297.059946) (xy 309.618237 -297.087902) (xy 309.65373 -297.121994)
			(xy 309.683295 -297.161338) (xy 309.706166 -297.204915) (xy 309.72175 -297.251596) (xy 309.729645 -297.300173)
			(xy 309.73014 -297.32478) (xy 310.068988 -297.32478) (xy 310.072948 -297.275726) (xy 310.084725 -297.227942)
			(xy 310.104016 -297.182666) (xy 310.130319 -297.14107) (xy 310.162954 -297.104233) (xy 310.201075 -297.073108)
			(xy 310.243696 -297.048501) (xy 310.289712 -297.031049) (xy 310.337931 -297.021205) (xy 310.387106 -297.019224)
			(xy 310.435961 -297.025156) (xy 310.483232 -297.038848) (xy 310.527694 -297.059946) (xy 310.568197 -297.087902)
			(xy 310.60369 -297.121994) (xy 310.633255 -297.161338) (xy 310.656126 -297.204915) (xy 310.67171 -297.251596)
			(xy 310.679605 -297.300173) (xy 310.6801 -297.32478) (xy 311.018948 -297.32478) (xy 311.022908 -297.275726)
			(xy 311.034685 -297.227942) (xy 311.053976 -297.182666) (xy 311.080279 -297.14107) (xy 311.112914 -297.104233)
			(xy 311.151035 -297.073108) (xy 311.193656 -297.048501) (xy 311.239672 -297.031049) (xy 311.287891 -297.021205)
			(xy 311.337066 -297.019224) (xy 311.385921 -297.025156) (xy 311.433192 -297.038848) (xy 311.477654 -297.059946)
			(xy 311.518157 -297.087902) (xy 311.55365 -297.121994) (xy 311.583215 -297.161338) (xy 311.606086 -297.204915)
			(xy 311.62167 -297.251596) (xy 311.629565 -297.300173) (xy 311.63006 -297.32478) (xy 311.968908 -297.32478)
			(xy 311.972868 -297.275726) (xy 311.984645 -297.227942) (xy 312.003936 -297.182666) (xy 312.030239 -297.14107)
			(xy 312.062874 -297.104233) (xy 312.100995 -297.073108) (xy 312.143616 -297.048501) (xy 312.189632 -297.031049)
			(xy 312.237851 -297.021205) (xy 312.287026 -297.019224) (xy 312.335881 -297.025156) (xy 312.383152 -297.038848)
			(xy 312.427614 -297.059946) (xy 312.468117 -297.087902) (xy 312.50361 -297.121994) (xy 312.533175 -297.161338)
			(xy 312.556046 -297.204915) (xy 312.57163 -297.251596) (xy 312.579525 -297.300173) (xy 312.58002 -297.32478)
			(xy 312.919122 -297.32478) (xy 312.923082 -297.275726) (xy 312.934859 -297.227942) (xy 312.95415 -297.182666)
			(xy 312.980453 -297.14107) (xy 313.013088 -297.104233) (xy 313.051209 -297.073108) (xy 313.09383 -297.048501)
			(xy 313.139846 -297.031049) (xy 313.188065 -297.021205) (xy 313.23724 -297.019224) (xy 313.286095 -297.025156)
			(xy 313.333366 -297.038848) (xy 313.377828 -297.059946) (xy 313.418331 -297.087902) (xy 313.453824 -297.121994)
			(xy 313.483389 -297.161338) (xy 313.50626 -297.204915) (xy 313.521844 -297.251596) (xy 313.529739 -297.300173)
			(xy 313.530234 -297.32478) (xy 313.869082 -297.32478) (xy 313.873042 -297.275726) (xy 313.884819 -297.227942)
			(xy 313.90411 -297.182666) (xy 313.930413 -297.14107) (xy 313.963048 -297.104233) (xy 314.001169 -297.073108)
			(xy 314.04379 -297.048501) (xy 314.089806 -297.031049) (xy 314.138025 -297.021205) (xy 314.1872 -297.019224)
			(xy 314.236055 -297.025156) (xy 314.283326 -297.038848) (xy 314.327788 -297.059946) (xy 314.368291 -297.087902)
			(xy 314.403784 -297.121994) (xy 314.433349 -297.161338) (xy 314.45622 -297.204915) (xy 314.471804 -297.251596)
			(xy 314.479699 -297.300173) (xy 314.480194 -297.32478) (xy 314.819042 -297.32478) (xy 314.823002 -297.275726)
			(xy 314.834779 -297.227942) (xy 314.85407 -297.182666) (xy 314.880373 -297.14107) (xy 314.913008 -297.104233)
			(xy 314.951129 -297.073108) (xy 314.99375 -297.048501) (xy 315.039766 -297.031049) (xy 315.087985 -297.021205)
			(xy 315.13716 -297.019224) (xy 315.186015 -297.025156) (xy 315.233286 -297.038848) (xy 315.277748 -297.059946)
			(xy 315.318251 -297.087902) (xy 315.353744 -297.121994) (xy 315.383309 -297.161338) (xy 315.40618 -297.204915)
			(xy 315.421764 -297.251596) (xy 315.429659 -297.300173) (xy 315.430154 -297.32478) (xy 315.429659 -297.349387)
			(xy 315.421764 -297.397964) (xy 315.40618 -297.444645) (xy 315.383309 -297.488222) (xy 315.353744 -297.527566)
			(xy 315.318251 -297.561658) (xy 315.277748 -297.589614) (xy 315.233286 -297.610712) (xy 315.186015 -297.624404)
			(xy 315.13716 -297.630336) (xy 315.087985 -297.628355) (xy 315.039766 -297.618511) (xy 314.99375 -297.601059)
			(xy 314.951129 -297.576452) (xy 314.913008 -297.545327) (xy 314.880373 -297.50849) (xy 314.85407 -297.466894)
			(xy 314.834779 -297.421618) (xy 314.823002 -297.373834) (xy 314.819042 -297.32478) (xy 314.480194 -297.32478)
			(xy 314.479699 -297.349387) (xy 314.471804 -297.397964) (xy 314.45622 -297.444645) (xy 314.433349 -297.488222)
			(xy 314.403784 -297.527566) (xy 314.368291 -297.561658) (xy 314.327788 -297.589614) (xy 314.283326 -297.610712)
			(xy 314.236055 -297.624404) (xy 314.1872 -297.630336) (xy 314.138025 -297.628355) (xy 314.089806 -297.618511)
			(xy 314.04379 -297.601059) (xy 314.001169 -297.576452) (xy 313.963048 -297.545327) (xy 313.930413 -297.50849)
			(xy 313.90411 -297.466894) (xy 313.884819 -297.421618) (xy 313.873042 -297.373834) (xy 313.869082 -297.32478)
			(xy 313.530234 -297.32478) (xy 313.529739 -297.349387) (xy 313.521844 -297.397964) (xy 313.50626 -297.444645)
			(xy 313.483389 -297.488222) (xy 313.453824 -297.527566) (xy 313.418331 -297.561658) (xy 313.377828 -297.589614)
			(xy 313.333366 -297.610712) (xy 313.286095 -297.624404) (xy 313.23724 -297.630336) (xy 313.188065 -297.628355)
			(xy 313.139846 -297.618511) (xy 313.09383 -297.601059) (xy 313.051209 -297.576452) (xy 313.013088 -297.545327)
			(xy 312.980453 -297.50849) (xy 312.95415 -297.466894) (xy 312.934859 -297.421618) (xy 312.923082 -297.373834)
			(xy 312.919122 -297.32478) (xy 312.58002 -297.32478) (xy 312.579525 -297.349387) (xy 312.57163 -297.397964)
			(xy 312.556046 -297.444645) (xy 312.533175 -297.488222) (xy 312.50361 -297.527566) (xy 312.468117 -297.561658)
			(xy 312.427614 -297.589614) (xy 312.383152 -297.610712) (xy 312.335881 -297.624404) (xy 312.287026 -297.630336)
			(xy 312.237851 -297.628355) (xy 312.189632 -297.618511) (xy 312.143616 -297.601059) (xy 312.100995 -297.576452)
			(xy 312.062874 -297.545327) (xy 312.030239 -297.50849) (xy 312.003936 -297.466894) (xy 311.984645 -297.421618)
			(xy 311.972868 -297.373834) (xy 311.968908 -297.32478) (xy 311.63006 -297.32478) (xy 311.629565 -297.349387)
			(xy 311.62167 -297.397964) (xy 311.606086 -297.444645) (xy 311.583215 -297.488222) (xy 311.55365 -297.527566)
			(xy 311.518157 -297.561658) (xy 311.477654 -297.589614) (xy 311.433192 -297.610712) (xy 311.385921 -297.624404)
			(xy 311.337066 -297.630336) (xy 311.287891 -297.628355) (xy 311.239672 -297.618511) (xy 311.193656 -297.601059)
			(xy 311.151035 -297.576452) (xy 311.112914 -297.545327) (xy 311.080279 -297.50849) (xy 311.053976 -297.466894)
			(xy 311.034685 -297.421618) (xy 311.022908 -297.373834) (xy 311.018948 -297.32478) (xy 310.6801 -297.32478)
			(xy 310.679605 -297.349387) (xy 310.67171 -297.397964) (xy 310.656126 -297.444645) (xy 310.633255 -297.488222)
			(xy 310.60369 -297.527566) (xy 310.568197 -297.561658) (xy 310.527694 -297.589614) (xy 310.483232 -297.610712)
			(xy 310.435961 -297.624404) (xy 310.387106 -297.630336) (xy 310.337931 -297.628355) (xy 310.289712 -297.618511)
			(xy 310.243696 -297.601059) (xy 310.201075 -297.576452) (xy 310.162954 -297.545327) (xy 310.130319 -297.50849)
			(xy 310.104016 -297.466894) (xy 310.084725 -297.421618) (xy 310.072948 -297.373834) (xy 310.068988 -297.32478)
			(xy 309.73014 -297.32478) (xy 309.729645 -297.349387) (xy 309.72175 -297.397964) (xy 309.706166 -297.444645)
			(xy 309.683295 -297.488222) (xy 309.65373 -297.527566) (xy 309.618237 -297.561658) (xy 309.577734 -297.589614)
			(xy 309.533272 -297.610712) (xy 309.486001 -297.624404) (xy 309.437146 -297.630336) (xy 309.387971 -297.628355)
			(xy 309.339752 -297.618511) (xy 309.293736 -297.601059) (xy 309.251115 -297.576452) (xy 309.212994 -297.545327)
			(xy 309.180359 -297.50849) (xy 309.154056 -297.466894) (xy 309.134765 -297.421618) (xy 309.122988 -297.373834)
			(xy 309.119028 -297.32478) (xy 308.78018 -297.32478) (xy 308.779685 -297.349387) (xy 308.77179 -297.397964)
			(xy 308.756206 -297.444645) (xy 308.733335 -297.488222) (xy 308.70377 -297.527566) (xy 308.668277 -297.561658)
			(xy 308.627774 -297.589614) (xy 308.583312 -297.610712) (xy 308.536041 -297.624404) (xy 308.487186 -297.630336)
			(xy 308.438011 -297.628355) (xy 308.389792 -297.618511) (xy 308.343776 -297.601059) (xy 308.301155 -297.576452)
			(xy 308.263034 -297.545327) (xy 308.230399 -297.50849) (xy 308.204096 -297.466894) (xy 308.184805 -297.421618)
			(xy 308.173028 -297.373834) (xy 308.169068 -297.32478) (xy 307.83022 -297.32478) (xy 307.829725 -297.349387)
			(xy 307.82183 -297.397964) (xy 307.806246 -297.444645) (xy 307.783375 -297.488222) (xy 307.75381 -297.527566)
			(xy 307.718317 -297.561658) (xy 307.677814 -297.589614) (xy 307.633352 -297.610712) (xy 307.586081 -297.624404)
			(xy 307.537226 -297.630336) (xy 307.488051 -297.628355) (xy 307.439832 -297.618511) (xy 307.393816 -297.601059)
			(xy 307.351195 -297.576452) (xy 307.313074 -297.545327) (xy 307.280439 -297.50849) (xy 307.254136 -297.466894)
			(xy 307.234845 -297.421618) (xy 307.223068 -297.373834) (xy 307.219108 -297.32478) (xy 306.88026 -297.32478)
			(xy 306.879765 -297.349387) (xy 306.87187 -297.397964) (xy 306.856286 -297.444645) (xy 306.833415 -297.488222)
			(xy 306.80385 -297.527566) (xy 306.768357 -297.561658) (xy 306.727854 -297.589614) (xy 306.683392 -297.610712)
			(xy 306.636121 -297.624404) (xy 306.587266 -297.630336) (xy 306.538091 -297.628355) (xy 306.489872 -297.618511)
			(xy 306.443856 -297.601059) (xy 306.401235 -297.576452) (xy 306.363114 -297.545327) (xy 306.330479 -297.50849)
			(xy 306.304176 -297.466894) (xy 306.284885 -297.421618) (xy 306.273108 -297.373834) (xy 306.269148 -297.32478)
			(xy 305.930046 -297.32478) (xy 305.929551 -297.349387) (xy 305.921656 -297.397964) (xy 305.906072 -297.444645)
			(xy 305.883201 -297.488222) (xy 305.853636 -297.527566) (xy 305.818143 -297.561658) (xy 305.77764 -297.589614)
			(xy 305.733178 -297.610712) (xy 305.685907 -297.624404) (xy 305.637052 -297.630336) (xy 305.587877 -297.628355)
			(xy 305.539658 -297.618511) (xy 305.493642 -297.601059) (xy 305.451021 -297.576452) (xy 305.4129 -297.545327)
			(xy 305.380265 -297.50849) (xy 305.353962 -297.466894) (xy 305.334671 -297.421618) (xy 305.322894 -297.373834)
			(xy 305.318934 -297.32478) (xy 304.980086 -297.32478) (xy 304.979591 -297.349387) (xy 304.971696 -297.397964)
			(xy 304.956112 -297.444645) (xy 304.933241 -297.488222) (xy 304.903676 -297.527566) (xy 304.868183 -297.561658)
			(xy 304.82768 -297.589614) (xy 304.783218 -297.610712) (xy 304.735947 -297.624404) (xy 304.687092 -297.630336)
			(xy 304.637917 -297.628355) (xy 304.589698 -297.618511) (xy 304.543682 -297.601059) (xy 304.501061 -297.576452)
			(xy 304.46294 -297.545327) (xy 304.430305 -297.50849) (xy 304.404002 -297.466894) (xy 304.384711 -297.421618)
			(xy 304.372934 -297.373834) (xy 304.368974 -297.32478) (xy 304.030126 -297.32478) (xy 304.029631 -297.349387)
			(xy 304.021736 -297.397964) (xy 304.006152 -297.444645) (xy 303.983281 -297.488222) (xy 303.953716 -297.527566)
			(xy 303.918223 -297.561658) (xy 303.87772 -297.589614) (xy 303.833258 -297.610712) (xy 303.785987 -297.624404)
			(xy 303.737132 -297.630336) (xy 303.687957 -297.628355) (xy 303.639738 -297.618511) (xy 303.593722 -297.601059)
			(xy 303.551101 -297.576452) (xy 303.51298 -297.545327) (xy 303.480345 -297.50849) (xy 303.454042 -297.466894)
			(xy 303.434751 -297.421618) (xy 303.422974 -297.373834) (xy 303.419014 -297.32478) (xy 303.080166 -297.32478)
			(xy 303.079671 -297.349387) (xy 303.071776 -297.397964) (xy 303.056192 -297.444645) (xy 303.033321 -297.488222)
			(xy 303.003756 -297.527566) (xy 302.968263 -297.561658) (xy 302.92776 -297.589614) (xy 302.883298 -297.610712)
			(xy 302.836027 -297.624404) (xy 302.787172 -297.630336) (xy 302.737997 -297.628355) (xy 302.689778 -297.618511)
			(xy 302.643762 -297.601059) (xy 302.601141 -297.576452) (xy 302.56302 -297.545327) (xy 302.530385 -297.50849)
			(xy 302.504082 -297.466894) (xy 302.484791 -297.421618) (xy 302.473014 -297.373834) (xy 302.469054 -297.32478)
			(xy 302.130206 -297.32478) (xy 302.129711 -297.349387) (xy 302.121816 -297.397964) (xy 302.106232 -297.444645)
			(xy 302.083361 -297.488222) (xy 302.053796 -297.527566) (xy 302.018303 -297.561658) (xy 301.9778 -297.589614)
			(xy 301.933338 -297.610712) (xy 301.886067 -297.624404) (xy 301.837212 -297.630336) (xy 301.788037 -297.628355)
			(xy 301.739818 -297.618511) (xy 301.693802 -297.601059) (xy 301.651181 -297.576452) (xy 301.61306 -297.545327)
			(xy 301.580425 -297.50849) (xy 301.554122 -297.466894) (xy 301.534831 -297.421618) (xy 301.523054 -297.373834)
			(xy 301.519094 -297.32478) (xy 301.179992 -297.32478) (xy 301.179497 -297.349387) (xy 301.171602 -297.397964)
			(xy 301.156018 -297.444645) (xy 301.133147 -297.488222) (xy 301.103582 -297.527566) (xy 301.068089 -297.561658)
			(xy 301.027586 -297.589614) (xy 300.983124 -297.610712) (xy 300.935853 -297.624404) (xy 300.886998 -297.630336)
			(xy 300.837823 -297.628355) (xy 300.789604 -297.618511) (xy 300.743588 -297.601059) (xy 300.700967 -297.576452)
			(xy 300.662846 -297.545327) (xy 300.630211 -297.50849) (xy 300.603908 -297.466894) (xy 300.584617 -297.421618)
			(xy 300.57284 -297.373834) (xy 300.56888 -297.32478) (xy 300.230032 -297.32478) (xy 300.229537 -297.349387)
			(xy 300.221642 -297.397964) (xy 300.206058 -297.444645) (xy 300.183187 -297.488222) (xy 300.153622 -297.527566)
			(xy 300.118129 -297.561658) (xy 300.077626 -297.589614) (xy 300.033164 -297.610712) (xy 299.985893 -297.624404)
			(xy 299.937038 -297.630336) (xy 299.887863 -297.628355) (xy 299.839644 -297.618511) (xy 299.793628 -297.601059)
			(xy 299.751007 -297.576452) (xy 299.712886 -297.545327) (xy 299.680251 -297.50849) (xy 299.653948 -297.466894)
			(xy 299.634657 -297.421618) (xy 299.62288 -297.373834) (xy 299.61892 -297.32478) (xy 299.280072 -297.32478)
			(xy 299.279577 -297.349387) (xy 299.271682 -297.397964) (xy 299.256098 -297.444645) (xy 299.233227 -297.488222)
			(xy 299.203662 -297.527566) (xy 299.168169 -297.561658) (xy 299.127666 -297.589614) (xy 299.083204 -297.610712)
			(xy 299.035933 -297.624404) (xy 298.987078 -297.630336) (xy 298.937903 -297.628355) (xy 298.889684 -297.618511)
			(xy 298.843668 -297.601059) (xy 298.801047 -297.576452) (xy 298.762926 -297.545327) (xy 298.730291 -297.50849)
			(xy 298.703988 -297.466894) (xy 298.684697 -297.421618) (xy 298.67292 -297.373834) (xy 298.66896 -297.32478)
			(xy 298.330112 -297.32478) (xy 298.329617 -297.349387) (xy 298.321722 -297.397964) (xy 298.306138 -297.444645)
			(xy 298.283267 -297.488222) (xy 298.253702 -297.527566) (xy 298.218209 -297.561658) (xy 298.177706 -297.589614)
			(xy 298.133244 -297.610712) (xy 298.085973 -297.624404) (xy 298.037118 -297.630336) (xy 297.987943 -297.628355)
			(xy 297.939724 -297.618511) (xy 297.893708 -297.601059) (xy 297.851087 -297.576452) (xy 297.812966 -297.545327)
			(xy 297.780331 -297.50849) (xy 297.754028 -297.466894) (xy 297.734737 -297.421618) (xy 297.72296 -297.373834)
			(xy 297.719 -297.32478) (xy 296.430192 -297.32478) (xy 296.429697 -297.349387) (xy 296.421802 -297.397964)
			(xy 296.406218 -297.444645) (xy 296.383347 -297.488222) (xy 296.353782 -297.527566) (xy 296.318289 -297.561658)
			(xy 296.277786 -297.589614) (xy 296.233324 -297.610712) (xy 296.186053 -297.624404) (xy 296.137198 -297.630336)
			(xy 296.088023 -297.628355) (xy 296.039804 -297.618511) (xy 295.993788 -297.601059) (xy 295.951167 -297.576452)
			(xy 295.913046 -297.545327) (xy 295.880411 -297.50849) (xy 295.854108 -297.466894) (xy 295.834817 -297.421618)
			(xy 295.82304 -297.373834) (xy 295.81908 -297.32478) (xy 294.530018 -297.32478) (xy 294.529523 -297.349387)
			(xy 294.521628 -297.397964) (xy 294.506044 -297.444645) (xy 294.483173 -297.488222) (xy 294.453608 -297.527566)
			(xy 294.418115 -297.561658) (xy 294.377612 -297.589614) (xy 294.33315 -297.610712) (xy 294.285879 -297.624404)
			(xy 294.237024 -297.630336) (xy 294.187849 -297.628355) (xy 294.13963 -297.618511) (xy 294.093614 -297.601059)
			(xy 294.050993 -297.576452) (xy 294.012872 -297.545327) (xy 293.980237 -297.50849) (xy 293.953934 -297.466894)
			(xy 293.934643 -297.421618) (xy 293.922866 -297.373834) (xy 293.918906 -297.32478) (xy 292.630098 -297.32478)
			(xy 292.629603 -297.349387) (xy 292.621708 -297.397964) (xy 292.606124 -297.444645) (xy 292.583253 -297.488222)
			(xy 292.553688 -297.527566) (xy 292.518195 -297.561658) (xy 292.477692 -297.589614) (xy 292.43323 -297.610712)
			(xy 292.385959 -297.624404) (xy 292.337104 -297.630336) (xy 292.287929 -297.628355) (xy 292.23971 -297.618511)
			(xy 292.193694 -297.601059) (xy 292.151073 -297.576452) (xy 292.112952 -297.545327) (xy 292.080317 -297.50849)
			(xy 292.054014 -297.466894) (xy 292.034723 -297.421618) (xy 292.022946 -297.373834) (xy 292.018986 -297.32478)
			(xy 289.780218 -297.32478) (xy 289.779723 -297.349387) (xy 289.771828 -297.397964) (xy 289.756244 -297.444645)
			(xy 289.733373 -297.488222) (xy 289.703808 -297.527566) (xy 289.668315 -297.561658) (xy 289.627812 -297.589614)
			(xy 289.58335 -297.610712) (xy 289.536079 -297.624404) (xy 289.487224 -297.630336) (xy 289.438049 -297.628355)
			(xy 289.38983 -297.618511) (xy 289.343814 -297.601059) (xy 289.301193 -297.576452) (xy 289.263072 -297.545327)
			(xy 289.230437 -297.50849) (xy 289.204134 -297.466894) (xy 289.184843 -297.421618) (xy 289.173066 -297.373834)
			(xy 289.169106 -297.32478) (xy 287.880044 -297.32478) (xy 287.879549 -297.349387) (xy 287.871654 -297.397964)
			(xy 287.85607 -297.444645) (xy 287.833199 -297.488222) (xy 287.803634 -297.527566) (xy 287.768141 -297.561658)
			(xy 287.727638 -297.589614) (xy 287.683176 -297.610712) (xy 287.635905 -297.624404) (xy 287.58705 -297.630336)
			(xy 287.537875 -297.628355) (xy 287.489656 -297.618511) (xy 287.44364 -297.601059) (xy 287.401019 -297.576452)
			(xy 287.362898 -297.545327) (xy 287.330263 -297.50849) (xy 287.30396 -297.466894) (xy 287.284669 -297.421618)
			(xy 287.272892 -297.373834) (xy 287.268932 -297.32478) (xy 285.980124 -297.32478) (xy 285.979629 -297.349387)
			(xy 285.971734 -297.397964) (xy 285.95615 -297.444645) (xy 285.933279 -297.488222) (xy 285.903714 -297.527566)
			(xy 285.868221 -297.561658) (xy 285.827718 -297.589614) (xy 285.783256 -297.610712) (xy 285.735985 -297.624404)
			(xy 285.68713 -297.630336) (xy 285.637955 -297.628355) (xy 285.589736 -297.618511) (xy 285.54372 -297.601059)
			(xy 285.501099 -297.576452) (xy 285.462978 -297.545327) (xy 285.430343 -297.50849) (xy 285.40404 -297.466894)
			(xy 285.384749 -297.421618) (xy 285.372972 -297.373834) (xy 285.369012 -297.32478) (xy 284.080204 -297.32478)
			(xy 284.079709 -297.349387) (xy 284.071814 -297.397964) (xy 284.05623 -297.444645) (xy 284.033359 -297.488222)
			(xy 284.003794 -297.527566) (xy 283.968301 -297.561658) (xy 283.927798 -297.589614) (xy 283.883336 -297.610712)
			(xy 283.836065 -297.624404) (xy 283.78721 -297.630336) (xy 283.738035 -297.628355) (xy 283.689816 -297.618511)
			(xy 283.6438 -297.601059) (xy 283.601179 -297.576452) (xy 283.563058 -297.545327) (xy 283.530423 -297.50849)
			(xy 283.50412 -297.466894) (xy 283.484829 -297.421618) (xy 283.473052 -297.373834) (xy 283.469092 -297.32478)
			(xy 282.180549 -297.32478) (xy 282.180551 -297.3248) (xy 282.17638 -297.375139) (xy 282.163981 -297.424105)
			(xy 282.143691 -297.470363) (xy 282.116065 -297.51265) (xy 282.081856 -297.549814) (xy 282.041996 -297.580841)
			(xy 281.997574 -297.604884) (xy 281.9498 -297.621287) (xy 281.899978 -297.629605) (xy 281.874722 -297.630088)
			(xy 281.844648 -297.629395) (xy 281.785662 -297.617629) (xy 281.757628 -297.60672) (xy 281.745436 -297.60164)
			(xy 281.720544 -297.60418) (xy 281.639518 -297.658282) (xy 281.629459 -297.6658) (xy 281.617604 -297.687907)
			(xy 281.616912 -297.700446) (xy 281.616912 -297.95851) (xy 316.956184 -297.95851) (xy 316.960255 -297.902888)
			(xy 316.972381 -297.848451) (xy 316.992304 -297.79636) (xy 317.0196 -297.747725) (xy 317.053686 -297.703582)
			(xy 317.093835 -297.664873) (xy 317.139193 -297.632422) (xy 317.188793 -297.606921) (xy 317.241577 -297.588914)
			(xy 317.29642 -297.578784) (xy 317.352154 -297.576747) (xy 317.407591 -297.582847) (xy 317.461548 -297.596953)
			(xy 317.512877 -297.618765) (xy 317.560483 -297.647819) (xy 317.603351 -297.683494) (xy 317.609209 -297.690032)
			(xy 318.499488 -297.690032) (xy 318.503559 -297.63441) (xy 318.515685 -297.579973) (xy 318.535608 -297.527882)
			(xy 318.562904 -297.479247) (xy 318.59699 -297.435104) (xy 318.637139 -297.396395) (xy 318.682497 -297.363944)
			(xy 318.732097 -297.338443) (xy 318.784881 -297.320436) (xy 318.839724 -297.310306) (xy 318.895458 -297.308269)
			(xy 318.950895 -297.314369) (xy 319.004852 -297.328475) (xy 319.056181 -297.350287) (xy 319.096376 -297.374818)
			(xy 324.815706 -297.374818) (xy 324.819777 -297.319196) (xy 324.831903 -297.264759) (xy 324.851826 -297.212668)
			(xy 324.879122 -297.164033) (xy 324.913208 -297.11989) (xy 324.953357 -297.081181) (xy 324.998715 -297.04873)
			(xy 325.048315 -297.023229) (xy 325.101099 -297.005222) (xy 325.155942 -296.995092) (xy 325.211676 -296.993055)
			(xy 325.267113 -296.999155) (xy 325.32107 -297.013261) (xy 325.372399 -297.035073) (xy 325.420005 -297.064127)
			(xy 325.462873 -297.099802) (xy 325.50009 -297.141339) (xy 325.530863 -297.187852) (xy 325.554535 -297.238349)
			(xy 325.570603 -297.291756) (xy 325.578723 -297.346932) (xy 325.579232 -297.374818) (xy 325.578723 -297.402704)
			(xy 325.570603 -297.45788) (xy 325.554535 -297.511287) (xy 325.530863 -297.561784) (xy 325.50009 -297.608297)
			(xy 325.462873 -297.649834) (xy 325.420005 -297.685509) (xy 325.372399 -297.714563) (xy 325.32107 -297.736375)
			(xy 325.267113 -297.750481) (xy 325.211676 -297.756581) (xy 325.155942 -297.754544) (xy 325.101099 -297.744414)
			(xy 325.048315 -297.726407) (xy 324.998715 -297.700906) (xy 324.953357 -297.668455) (xy 324.913208 -297.629746)
			(xy 324.879122 -297.585603) (xy 324.851826 -297.536968) (xy 324.831903 -297.484877) (xy 324.819777 -297.43044)
			(xy 324.815706 -297.374818) (xy 319.096376 -297.374818) (xy 319.103787 -297.379341) (xy 319.146655 -297.415016)
			(xy 319.183872 -297.456553) (xy 319.214645 -297.503066) (xy 319.238317 -297.553563) (xy 319.254385 -297.60697)
			(xy 319.262505 -297.662146) (xy 319.263014 -297.690032) (xy 319.262505 -297.717918) (xy 319.254385 -297.773094)
			(xy 319.238317 -297.826501) (xy 319.214645 -297.876998) (xy 319.183872 -297.923511) (xy 319.146655 -297.965048)
			(xy 319.103787 -298.000723) (xy 319.056181 -298.029777) (xy 319.004852 -298.051589) (xy 318.950895 -298.065695)
			(xy 318.895458 -298.071795) (xy 318.839724 -298.069758) (xy 318.784881 -298.059628) (xy 318.732097 -298.041621)
			(xy 318.682497 -298.01612) (xy 318.637139 -297.983669) (xy 318.59699 -297.94496) (xy 318.562904 -297.900817)
			(xy 318.535608 -297.852182) (xy 318.515685 -297.800091) (xy 318.503559 -297.745654) (xy 318.499488 -297.690032)
			(xy 317.609209 -297.690032) (xy 317.640568 -297.725031) (xy 317.671341 -297.771544) (xy 317.695013 -297.822041)
			(xy 317.711081 -297.875448) (xy 317.719201 -297.930624) (xy 317.71971 -297.95851) (xy 317.719201 -297.986396)
			(xy 317.711081 -298.041572) (xy 317.695013 -298.094979) (xy 317.671341 -298.145476) (xy 317.640568 -298.191989)
			(xy 317.603351 -298.233526) (xy 317.560483 -298.269201) (xy 317.512877 -298.298255) (xy 317.461548 -298.320067)
			(xy 317.407591 -298.334173) (xy 317.352154 -298.340273) (xy 317.29642 -298.338236) (xy 317.241577 -298.328106)
			(xy 317.188793 -298.310099) (xy 317.139193 -298.284598) (xy 317.093835 -298.252147) (xy 317.053686 -298.213438)
			(xy 317.0196 -298.169295) (xy 316.992304 -298.12066) (xy 316.972381 -298.068569) (xy 316.960255 -298.014132)
			(xy 316.956184 -297.95851) (xy 281.616912 -297.95851) (xy 281.616912 -298.27474) (xy 282.519132 -298.27474)
			(xy 282.523092 -298.225686) (xy 282.534869 -298.177902) (xy 282.55416 -298.132626) (xy 282.580463 -298.09103)
			(xy 282.613098 -298.054193) (xy 282.651219 -298.023068) (xy 282.69384 -297.998461) (xy 282.739856 -297.981009)
			(xy 282.788075 -297.971165) (xy 282.83725 -297.969184) (xy 282.886105 -297.975116) (xy 282.933376 -297.988808)
			(xy 282.977838 -298.009906) (xy 283.018341 -298.037862) (xy 283.053834 -298.071954) (xy 283.083399 -298.111298)
			(xy 283.10627 -298.154875) (xy 283.121854 -298.201556) (xy 283.129749 -298.250133) (xy 283.130244 -298.27474)
			(xy 284.419052 -298.27474) (xy 284.423012 -298.225686) (xy 284.434789 -298.177902) (xy 284.45408 -298.132626)
			(xy 284.480383 -298.09103) (xy 284.513018 -298.054193) (xy 284.551139 -298.023068) (xy 284.59376 -297.998461)
			(xy 284.639776 -297.981009) (xy 284.687995 -297.971165) (xy 284.73717 -297.969184) (xy 284.786025 -297.975116)
			(xy 284.833296 -297.988808) (xy 284.877758 -298.009906) (xy 284.918261 -298.037862) (xy 284.953754 -298.071954)
			(xy 284.983319 -298.111298) (xy 285.00619 -298.154875) (xy 285.021774 -298.201556) (xy 285.029669 -298.250133)
			(xy 285.030164 -298.27474) (xy 286.318972 -298.27474) (xy 286.322932 -298.225686) (xy 286.334709 -298.177902)
			(xy 286.354 -298.132626) (xy 286.380303 -298.09103) (xy 286.412938 -298.054193) (xy 286.451059 -298.023068)
			(xy 286.49368 -297.998461) (xy 286.539696 -297.981009) (xy 286.587915 -297.971165) (xy 286.63709 -297.969184)
			(xy 286.685945 -297.975116) (xy 286.733216 -297.988808) (xy 286.777678 -298.009906) (xy 286.818181 -298.037862)
			(xy 286.853674 -298.071954) (xy 286.883239 -298.111298) (xy 286.90611 -298.154875) (xy 286.921694 -298.201556)
			(xy 286.929589 -298.250133) (xy 286.930084 -298.27474) (xy 288.218892 -298.27474) (xy 288.222852 -298.225686)
			(xy 288.234629 -298.177902) (xy 288.25392 -298.132626) (xy 288.280223 -298.09103) (xy 288.312858 -298.054193)
			(xy 288.350979 -298.023068) (xy 288.3936 -297.998461) (xy 288.439616 -297.981009) (xy 288.487835 -297.971165)
			(xy 288.53701 -297.969184) (xy 288.585865 -297.975116) (xy 288.633136 -297.988808) (xy 288.677598 -298.009906)
			(xy 288.718101 -298.037862) (xy 288.753594 -298.071954) (xy 288.783159 -298.111298) (xy 288.80603 -298.154875)
			(xy 288.821614 -298.201556) (xy 288.829509 -298.250133) (xy 288.830004 -298.27474) (xy 290.119066 -298.27474)
			(xy 290.123026 -298.225686) (xy 290.134803 -298.177902) (xy 290.154094 -298.132626) (xy 290.180397 -298.09103)
			(xy 290.213032 -298.054193) (xy 290.251153 -298.023068) (xy 290.293774 -297.998461) (xy 290.33979 -297.981009)
			(xy 290.388009 -297.971165) (xy 290.437184 -297.969184) (xy 290.486039 -297.975116) (xy 290.53331 -297.988808)
			(xy 290.577772 -298.009906) (xy 290.618275 -298.037862) (xy 290.653768 -298.071954) (xy 290.683333 -298.111298)
			(xy 290.706204 -298.154875) (xy 290.721788 -298.201556) (xy 290.729683 -298.250133) (xy 290.730178 -298.27474)
			(xy 292.968946 -298.27474) (xy 292.972906 -298.225686) (xy 292.984683 -298.177902) (xy 293.003974 -298.132626)
			(xy 293.030277 -298.09103) (xy 293.062912 -298.054193) (xy 293.101033 -298.023068) (xy 293.143654 -297.998461)
			(xy 293.18967 -297.981009) (xy 293.237889 -297.971165) (xy 293.287064 -297.969184) (xy 293.335919 -297.975116)
			(xy 293.38319 -297.988808) (xy 293.427652 -298.009906) (xy 293.468155 -298.037862) (xy 293.503648 -298.071954)
			(xy 293.533213 -298.111298) (xy 293.556084 -298.154875) (xy 293.571668 -298.201556) (xy 293.579563 -298.250133)
			(xy 293.580058 -298.27474) (xy 294.86912 -298.27474) (xy 294.87308 -298.225686) (xy 294.884857 -298.177902)
			(xy 294.904148 -298.132626) (xy 294.930451 -298.09103) (xy 294.963086 -298.054193) (xy 295.001207 -298.023068)
			(xy 295.043828 -297.998461) (xy 295.089844 -297.981009) (xy 295.138063 -297.971165) (xy 295.187238 -297.969184)
			(xy 295.236093 -297.975116) (xy 295.283364 -297.988808) (xy 295.327826 -298.009906) (xy 295.368329 -298.037862)
			(xy 295.403822 -298.071954) (xy 295.433387 -298.111298) (xy 295.456258 -298.154875) (xy 295.471842 -298.201556)
			(xy 295.479737 -298.250133) (xy 295.480232 -298.27474) (xy 296.76904 -298.27474) (xy 296.773 -298.225686)
			(xy 296.784777 -298.177902) (xy 296.804068 -298.132626) (xy 296.830371 -298.09103) (xy 296.863006 -298.054193)
			(xy 296.901127 -298.023068) (xy 296.943748 -297.998461) (xy 296.989764 -297.981009) (xy 297.037983 -297.971165)
			(xy 297.087158 -297.969184) (xy 297.136013 -297.975116) (xy 297.183284 -297.988808) (xy 297.227746 -298.009906)
			(xy 297.268249 -298.037862) (xy 297.303742 -298.071954) (xy 297.333307 -298.111298) (xy 297.356178 -298.154875)
			(xy 297.371762 -298.201556) (xy 297.379657 -298.250133) (xy 297.380152 -298.27474) (xy 298.66896 -298.27474)
			(xy 298.67292 -298.225686) (xy 298.684697 -298.177902) (xy 298.703988 -298.132626) (xy 298.730291 -298.09103)
			(xy 298.762926 -298.054193) (xy 298.801047 -298.023068) (xy 298.843668 -297.998461) (xy 298.889684 -297.981009)
			(xy 298.937903 -297.971165) (xy 298.987078 -297.969184) (xy 299.035933 -297.975116) (xy 299.083204 -297.988808)
			(xy 299.127666 -298.009906) (xy 299.168169 -298.037862) (xy 299.203662 -298.071954) (xy 299.233227 -298.111298)
			(xy 299.256098 -298.154875) (xy 299.271682 -298.201556) (xy 299.279577 -298.250133) (xy 299.280072 -298.27474)
			(xy 300.56888 -298.27474) (xy 300.57284 -298.225686) (xy 300.584617 -298.177902) (xy 300.603908 -298.132626)
			(xy 300.630211 -298.09103) (xy 300.662846 -298.054193) (xy 300.700967 -298.023068) (xy 300.743588 -297.998461)
			(xy 300.789604 -297.981009) (xy 300.837823 -297.971165) (xy 300.886998 -297.969184) (xy 300.935853 -297.975116)
			(xy 300.983124 -297.988808) (xy 301.027586 -298.009906) (xy 301.068089 -298.037862) (xy 301.103582 -298.071954)
			(xy 301.133147 -298.111298) (xy 301.156018 -298.154875) (xy 301.171602 -298.201556) (xy 301.179497 -298.250133)
			(xy 301.179992 -298.27474) (xy 301.519094 -298.27474) (xy 301.523054 -298.225686) (xy 301.534831 -298.177902)
			(xy 301.554122 -298.132626) (xy 301.580425 -298.09103) (xy 301.61306 -298.054193) (xy 301.651181 -298.023068)
			(xy 301.693802 -297.998461) (xy 301.739818 -297.981009) (xy 301.788037 -297.971165) (xy 301.837212 -297.969184)
			(xy 301.886067 -297.975116) (xy 301.933338 -297.988808) (xy 301.9778 -298.009906) (xy 302.018303 -298.037862)
			(xy 302.053796 -298.071954) (xy 302.083361 -298.111298) (xy 302.106232 -298.154875) (xy 302.121816 -298.201556)
			(xy 302.129711 -298.250133) (xy 302.130206 -298.27474) (xy 302.469054 -298.27474) (xy 302.473014 -298.225686)
			(xy 302.484791 -298.177902) (xy 302.504082 -298.132626) (xy 302.530385 -298.09103) (xy 302.56302 -298.054193)
			(xy 302.601141 -298.023068) (xy 302.643762 -297.998461) (xy 302.689778 -297.981009) (xy 302.737997 -297.971165)
			(xy 302.787172 -297.969184) (xy 302.836027 -297.975116) (xy 302.883298 -297.988808) (xy 302.92776 -298.009906)
			(xy 302.968263 -298.037862) (xy 303.003756 -298.071954) (xy 303.033321 -298.111298) (xy 303.056192 -298.154875)
			(xy 303.071776 -298.201556) (xy 303.079671 -298.250133) (xy 303.080166 -298.27474) (xy 303.419014 -298.27474)
			(xy 303.422974 -298.225686) (xy 303.434751 -298.177902) (xy 303.454042 -298.132626) (xy 303.480345 -298.09103)
			(xy 303.51298 -298.054193) (xy 303.551101 -298.023068) (xy 303.593722 -297.998461) (xy 303.639738 -297.981009)
			(xy 303.687957 -297.971165) (xy 303.737132 -297.969184) (xy 303.785987 -297.975116) (xy 303.833258 -297.988808)
			(xy 303.87772 -298.009906) (xy 303.918223 -298.037862) (xy 303.953716 -298.071954) (xy 303.983281 -298.111298)
			(xy 304.006152 -298.154875) (xy 304.021736 -298.201556) (xy 304.029631 -298.250133) (xy 304.030126 -298.27474)
			(xy 304.368974 -298.27474) (xy 304.372934 -298.225686) (xy 304.384711 -298.177902) (xy 304.404002 -298.132626)
			(xy 304.430305 -298.09103) (xy 304.46294 -298.054193) (xy 304.501061 -298.023068) (xy 304.543682 -297.998461)
			(xy 304.589698 -297.981009) (xy 304.637917 -297.971165) (xy 304.687092 -297.969184) (xy 304.735947 -297.975116)
			(xy 304.783218 -297.988808) (xy 304.82768 -298.009906) (xy 304.868183 -298.037862) (xy 304.903676 -298.071954)
			(xy 304.933241 -298.111298) (xy 304.956112 -298.154875) (xy 304.971696 -298.201556) (xy 304.979591 -298.250133)
			(xy 304.980086 -298.27474) (xy 305.318934 -298.27474) (xy 305.322894 -298.225686) (xy 305.334671 -298.177902)
			(xy 305.353962 -298.132626) (xy 305.380265 -298.09103) (xy 305.4129 -298.054193) (xy 305.451021 -298.023068)
			(xy 305.493642 -297.998461) (xy 305.539658 -297.981009) (xy 305.587877 -297.971165) (xy 305.637052 -297.969184)
			(xy 305.685907 -297.975116) (xy 305.733178 -297.988808) (xy 305.77764 -298.009906) (xy 305.818143 -298.037862)
			(xy 305.853636 -298.071954) (xy 305.883201 -298.111298) (xy 305.906072 -298.154875) (xy 305.921656 -298.201556)
			(xy 305.929551 -298.250133) (xy 305.930046 -298.27474) (xy 306.268894 -298.27474) (xy 306.272854 -298.225686)
			(xy 306.284631 -298.177902) (xy 306.303922 -298.132626) (xy 306.330225 -298.09103) (xy 306.36286 -298.054193)
			(xy 306.400981 -298.023068) (xy 306.443602 -297.998461) (xy 306.489618 -297.981009) (xy 306.537837 -297.971165)
			(xy 306.587012 -297.969184) (xy 306.635867 -297.975116) (xy 306.683138 -297.988808) (xy 306.7276 -298.009906)
			(xy 306.768103 -298.037862) (xy 306.803596 -298.071954) (xy 306.833161 -298.111298) (xy 306.856032 -298.154875)
			(xy 306.871616 -298.201556) (xy 306.879511 -298.250133) (xy 306.880006 -298.27474) (xy 307.219108 -298.27474)
			(xy 307.223068 -298.225686) (xy 307.234845 -298.177902) (xy 307.254136 -298.132626) (xy 307.280439 -298.09103)
			(xy 307.313074 -298.054193) (xy 307.351195 -298.023068) (xy 307.393816 -297.998461) (xy 307.439832 -297.981009)
			(xy 307.488051 -297.971165) (xy 307.537226 -297.969184) (xy 307.586081 -297.975116) (xy 307.633352 -297.988808)
			(xy 307.677814 -298.009906) (xy 307.718317 -298.037862) (xy 307.75381 -298.071954) (xy 307.783375 -298.111298)
			(xy 307.806246 -298.154875) (xy 307.82183 -298.201556) (xy 307.829725 -298.250133) (xy 307.83022 -298.27474)
			(xy 308.169068 -298.27474) (xy 308.173028 -298.225686) (xy 308.184805 -298.177902) (xy 308.204096 -298.132626)
			(xy 308.230399 -298.09103) (xy 308.263034 -298.054193) (xy 308.301155 -298.023068) (xy 308.343776 -297.998461)
			(xy 308.389792 -297.981009) (xy 308.438011 -297.971165) (xy 308.487186 -297.969184) (xy 308.536041 -297.975116)
			(xy 308.583312 -297.988808) (xy 308.627774 -298.009906) (xy 308.668277 -298.037862) (xy 308.70377 -298.071954)
			(xy 308.733335 -298.111298) (xy 308.756206 -298.154875) (xy 308.77179 -298.201556) (xy 308.779685 -298.250133)
			(xy 308.78018 -298.27474) (xy 309.119028 -298.27474) (xy 309.122988 -298.225686) (xy 309.134765 -298.177902)
			(xy 309.154056 -298.132626) (xy 309.180359 -298.09103) (xy 309.212994 -298.054193) (xy 309.251115 -298.023068)
			(xy 309.293736 -297.998461) (xy 309.339752 -297.981009) (xy 309.387971 -297.971165) (xy 309.437146 -297.969184)
			(xy 309.486001 -297.975116) (xy 309.533272 -297.988808) (xy 309.577734 -298.009906) (xy 309.618237 -298.037862)
			(xy 309.65373 -298.071954) (xy 309.683295 -298.111298) (xy 309.706166 -298.154875) (xy 309.72175 -298.201556)
			(xy 309.729645 -298.250133) (xy 309.73014 -298.27474) (xy 310.068988 -298.27474) (xy 310.072948 -298.225686)
			(xy 310.084725 -298.177902) (xy 310.104016 -298.132626) (xy 310.130319 -298.09103) (xy 310.162954 -298.054193)
			(xy 310.201075 -298.023068) (xy 310.243696 -297.998461) (xy 310.289712 -297.981009) (xy 310.337931 -297.971165)
			(xy 310.387106 -297.969184) (xy 310.435961 -297.975116) (xy 310.483232 -297.988808) (xy 310.527694 -298.009906)
			(xy 310.568197 -298.037862) (xy 310.60369 -298.071954) (xy 310.633255 -298.111298) (xy 310.656126 -298.154875)
			(xy 310.67171 -298.201556) (xy 310.679605 -298.250133) (xy 310.6801 -298.27474) (xy 311.018948 -298.27474)
			(xy 311.022908 -298.225686) (xy 311.034685 -298.177902) (xy 311.053976 -298.132626) (xy 311.080279 -298.09103)
			(xy 311.112914 -298.054193) (xy 311.151035 -298.023068) (xy 311.193656 -297.998461) (xy 311.239672 -297.981009)
			(xy 311.287891 -297.971165) (xy 311.337066 -297.969184) (xy 311.385921 -297.975116) (xy 311.433192 -297.988808)
			(xy 311.477654 -298.009906) (xy 311.518157 -298.037862) (xy 311.55365 -298.071954) (xy 311.583215 -298.111298)
			(xy 311.606086 -298.154875) (xy 311.62167 -298.201556) (xy 311.629565 -298.250133) (xy 311.63006 -298.27474)
			(xy 311.968908 -298.27474) (xy 311.972868 -298.225686) (xy 311.984645 -298.177902) (xy 312.003936 -298.132626)
			(xy 312.030239 -298.09103) (xy 312.062874 -298.054193) (xy 312.100995 -298.023068) (xy 312.143616 -297.998461)
			(xy 312.189632 -297.981009) (xy 312.237851 -297.971165) (xy 312.287026 -297.969184) (xy 312.335881 -297.975116)
			(xy 312.383152 -297.988808) (xy 312.427614 -298.009906) (xy 312.468117 -298.037862) (xy 312.50361 -298.071954)
			(xy 312.533175 -298.111298) (xy 312.556046 -298.154875) (xy 312.57163 -298.201556) (xy 312.579525 -298.250133)
			(xy 312.58002 -298.27474) (xy 312.919122 -298.27474) (xy 312.923082 -298.225686) (xy 312.934859 -298.177902)
			(xy 312.95415 -298.132626) (xy 312.980453 -298.09103) (xy 313.013088 -298.054193) (xy 313.051209 -298.023068)
			(xy 313.09383 -297.998461) (xy 313.139846 -297.981009) (xy 313.188065 -297.971165) (xy 313.23724 -297.969184)
			(xy 313.286095 -297.975116) (xy 313.333366 -297.988808) (xy 313.377828 -298.009906) (xy 313.418331 -298.037862)
			(xy 313.453824 -298.071954) (xy 313.483389 -298.111298) (xy 313.50626 -298.154875) (xy 313.521844 -298.201556)
			(xy 313.529739 -298.250133) (xy 313.530234 -298.27474) (xy 313.869082 -298.27474) (xy 313.873042 -298.225686)
			(xy 313.884819 -298.177902) (xy 313.90411 -298.132626) (xy 313.930413 -298.09103) (xy 313.963048 -298.054193)
			(xy 314.001169 -298.023068) (xy 314.04379 -297.998461) (xy 314.089806 -297.981009) (xy 314.138025 -297.971165)
			(xy 314.1872 -297.969184) (xy 314.236055 -297.975116) (xy 314.283326 -297.988808) (xy 314.327788 -298.009906)
			(xy 314.368291 -298.037862) (xy 314.403784 -298.071954) (xy 314.433349 -298.111298) (xy 314.45622 -298.154875)
			(xy 314.471804 -298.201556) (xy 314.479699 -298.250133) (xy 314.480194 -298.27474) (xy 314.819042 -298.27474)
			(xy 314.823002 -298.225686) (xy 314.834779 -298.177902) (xy 314.85407 -298.132626) (xy 314.880373 -298.09103)
			(xy 314.913008 -298.054193) (xy 314.951129 -298.023068) (xy 314.99375 -297.998461) (xy 315.039766 -297.981009)
			(xy 315.087985 -297.971165) (xy 315.13716 -297.969184) (xy 315.186015 -297.975116) (xy 315.233286 -297.988808)
			(xy 315.277748 -298.009906) (xy 315.318251 -298.037862) (xy 315.353744 -298.071954) (xy 315.383309 -298.111298)
			(xy 315.40618 -298.154875) (xy 315.421764 -298.201556) (xy 315.429659 -298.250133) (xy 315.430154 -298.27474)
			(xy 315.429659 -298.299347) (xy 315.421764 -298.347924) (xy 315.40618 -298.394605) (xy 315.383309 -298.438182)
			(xy 315.353744 -298.477526) (xy 315.318251 -298.511618) (xy 315.277748 -298.539574) (xy 315.233286 -298.560672)
			(xy 315.186015 -298.574364) (xy 315.13716 -298.580296) (xy 315.087985 -298.578315) (xy 315.039766 -298.568471)
			(xy 314.99375 -298.551019) (xy 314.951129 -298.526412) (xy 314.913008 -298.495287) (xy 314.880373 -298.45845)
			(xy 314.85407 -298.416854) (xy 314.834779 -298.371578) (xy 314.823002 -298.323794) (xy 314.819042 -298.27474)
			(xy 314.480194 -298.27474) (xy 314.479699 -298.299347) (xy 314.471804 -298.347924) (xy 314.45622 -298.394605)
			(xy 314.433349 -298.438182) (xy 314.403784 -298.477526) (xy 314.368291 -298.511618) (xy 314.327788 -298.539574)
			(xy 314.283326 -298.560672) (xy 314.236055 -298.574364) (xy 314.1872 -298.580296) (xy 314.138025 -298.578315)
			(xy 314.089806 -298.568471) (xy 314.04379 -298.551019) (xy 314.001169 -298.526412) (xy 313.963048 -298.495287)
			(xy 313.930413 -298.45845) (xy 313.90411 -298.416854) (xy 313.884819 -298.371578) (xy 313.873042 -298.323794)
			(xy 313.869082 -298.27474) (xy 313.530234 -298.27474) (xy 313.529739 -298.299347) (xy 313.521844 -298.347924)
			(xy 313.50626 -298.394605) (xy 313.483389 -298.438182) (xy 313.453824 -298.477526) (xy 313.418331 -298.511618)
			(xy 313.377828 -298.539574) (xy 313.333366 -298.560672) (xy 313.286095 -298.574364) (xy 313.23724 -298.580296)
			(xy 313.188065 -298.578315) (xy 313.139846 -298.568471) (xy 313.09383 -298.551019) (xy 313.051209 -298.526412)
			(xy 313.013088 -298.495287) (xy 312.980453 -298.45845) (xy 312.95415 -298.416854) (xy 312.934859 -298.371578)
			(xy 312.923082 -298.323794) (xy 312.919122 -298.27474) (xy 312.58002 -298.27474) (xy 312.579525 -298.299347)
			(xy 312.57163 -298.347924) (xy 312.556046 -298.394605) (xy 312.533175 -298.438182) (xy 312.50361 -298.477526)
			(xy 312.468117 -298.511618) (xy 312.427614 -298.539574) (xy 312.383152 -298.560672) (xy 312.335881 -298.574364)
			(xy 312.287026 -298.580296) (xy 312.237851 -298.578315) (xy 312.189632 -298.568471) (xy 312.143616 -298.551019)
			(xy 312.100995 -298.526412) (xy 312.062874 -298.495287) (xy 312.030239 -298.45845) (xy 312.003936 -298.416854)
			(xy 311.984645 -298.371578) (xy 311.972868 -298.323794) (xy 311.968908 -298.27474) (xy 311.63006 -298.27474)
			(xy 311.629565 -298.299347) (xy 311.62167 -298.347924) (xy 311.606086 -298.394605) (xy 311.583215 -298.438182)
			(xy 311.55365 -298.477526) (xy 311.518157 -298.511618) (xy 311.477654 -298.539574) (xy 311.433192 -298.560672)
			(xy 311.385921 -298.574364) (xy 311.337066 -298.580296) (xy 311.287891 -298.578315) (xy 311.239672 -298.568471)
			(xy 311.193656 -298.551019) (xy 311.151035 -298.526412) (xy 311.112914 -298.495287) (xy 311.080279 -298.45845)
			(xy 311.053976 -298.416854) (xy 311.034685 -298.371578) (xy 311.022908 -298.323794) (xy 311.018948 -298.27474)
			(xy 310.6801 -298.27474) (xy 310.679605 -298.299347) (xy 310.67171 -298.347924) (xy 310.656126 -298.394605)
			(xy 310.633255 -298.438182) (xy 310.60369 -298.477526) (xy 310.568197 -298.511618) (xy 310.527694 -298.539574)
			(xy 310.483232 -298.560672) (xy 310.435961 -298.574364) (xy 310.387106 -298.580296) (xy 310.337931 -298.578315)
			(xy 310.289712 -298.568471) (xy 310.243696 -298.551019) (xy 310.201075 -298.526412) (xy 310.162954 -298.495287)
			(xy 310.130319 -298.45845) (xy 310.104016 -298.416854) (xy 310.084725 -298.371578) (xy 310.072948 -298.323794)
			(xy 310.068988 -298.27474) (xy 309.73014 -298.27474) (xy 309.729645 -298.299347) (xy 309.72175 -298.347924)
			(xy 309.706166 -298.394605) (xy 309.683295 -298.438182) (xy 309.65373 -298.477526) (xy 309.618237 -298.511618)
			(xy 309.577734 -298.539574) (xy 309.533272 -298.560672) (xy 309.486001 -298.574364) (xy 309.437146 -298.580296)
			(xy 309.387971 -298.578315) (xy 309.339752 -298.568471) (xy 309.293736 -298.551019) (xy 309.251115 -298.526412)
			(xy 309.212994 -298.495287) (xy 309.180359 -298.45845) (xy 309.154056 -298.416854) (xy 309.134765 -298.371578)
			(xy 309.122988 -298.323794) (xy 309.119028 -298.27474) (xy 308.78018 -298.27474) (xy 308.779685 -298.299347)
			(xy 308.77179 -298.347924) (xy 308.756206 -298.394605) (xy 308.733335 -298.438182) (xy 308.70377 -298.477526)
			(xy 308.668277 -298.511618) (xy 308.627774 -298.539574) (xy 308.583312 -298.560672) (xy 308.536041 -298.574364)
			(xy 308.487186 -298.580296) (xy 308.438011 -298.578315) (xy 308.389792 -298.568471) (xy 308.343776 -298.551019)
			(xy 308.301155 -298.526412) (xy 308.263034 -298.495287) (xy 308.230399 -298.45845) (xy 308.204096 -298.416854)
			(xy 308.184805 -298.371578) (xy 308.173028 -298.323794) (xy 308.169068 -298.27474) (xy 307.83022 -298.27474)
			(xy 307.829725 -298.299347) (xy 307.82183 -298.347924) (xy 307.806246 -298.394605) (xy 307.783375 -298.438182)
			(xy 307.75381 -298.477526) (xy 307.718317 -298.511618) (xy 307.677814 -298.539574) (xy 307.633352 -298.560672)
			(xy 307.586081 -298.574364) (xy 307.537226 -298.580296) (xy 307.488051 -298.578315) (xy 307.439832 -298.568471)
			(xy 307.393816 -298.551019) (xy 307.351195 -298.526412) (xy 307.313074 -298.495287) (xy 307.280439 -298.45845)
			(xy 307.254136 -298.416854) (xy 307.234845 -298.371578) (xy 307.223068 -298.323794) (xy 307.219108 -298.27474)
			(xy 306.880006 -298.27474) (xy 306.879511 -298.299347) (xy 306.871616 -298.347924) (xy 306.856032 -298.394605)
			(xy 306.833161 -298.438182) (xy 306.803596 -298.477526) (xy 306.768103 -298.511618) (xy 306.7276 -298.539574)
			(xy 306.683138 -298.560672) (xy 306.635867 -298.574364) (xy 306.587012 -298.580296) (xy 306.537837 -298.578315)
			(xy 306.489618 -298.568471) (xy 306.443602 -298.551019) (xy 306.400981 -298.526412) (xy 306.36286 -298.495287)
			(xy 306.330225 -298.45845) (xy 306.303922 -298.416854) (xy 306.284631 -298.371578) (xy 306.272854 -298.323794)
			(xy 306.268894 -298.27474) (xy 305.930046 -298.27474) (xy 305.929551 -298.299347) (xy 305.921656 -298.347924)
			(xy 305.906072 -298.394605) (xy 305.883201 -298.438182) (xy 305.853636 -298.477526) (xy 305.818143 -298.511618)
			(xy 305.77764 -298.539574) (xy 305.733178 -298.560672) (xy 305.685907 -298.574364) (xy 305.637052 -298.580296)
			(xy 305.587877 -298.578315) (xy 305.539658 -298.568471) (xy 305.493642 -298.551019) (xy 305.451021 -298.526412)
			(xy 305.4129 -298.495287) (xy 305.380265 -298.45845) (xy 305.353962 -298.416854) (xy 305.334671 -298.371578)
			(xy 305.322894 -298.323794) (xy 305.318934 -298.27474) (xy 304.980086 -298.27474) (xy 304.979591 -298.299347)
			(xy 304.971696 -298.347924) (xy 304.956112 -298.394605) (xy 304.933241 -298.438182) (xy 304.903676 -298.477526)
			(xy 304.868183 -298.511618) (xy 304.82768 -298.539574) (xy 304.783218 -298.560672) (xy 304.735947 -298.574364)
			(xy 304.687092 -298.580296) (xy 304.637917 -298.578315) (xy 304.589698 -298.568471) (xy 304.543682 -298.551019)
			(xy 304.501061 -298.526412) (xy 304.46294 -298.495287) (xy 304.430305 -298.45845) (xy 304.404002 -298.416854)
			(xy 304.384711 -298.371578) (xy 304.372934 -298.323794) (xy 304.368974 -298.27474) (xy 304.030126 -298.27474)
			(xy 304.029631 -298.299347) (xy 304.021736 -298.347924) (xy 304.006152 -298.394605) (xy 303.983281 -298.438182)
			(xy 303.953716 -298.477526) (xy 303.918223 -298.511618) (xy 303.87772 -298.539574) (xy 303.833258 -298.560672)
			(xy 303.785987 -298.574364) (xy 303.737132 -298.580296) (xy 303.687957 -298.578315) (xy 303.639738 -298.568471)
			(xy 303.593722 -298.551019) (xy 303.551101 -298.526412) (xy 303.51298 -298.495287) (xy 303.480345 -298.45845)
			(xy 303.454042 -298.416854) (xy 303.434751 -298.371578) (xy 303.422974 -298.323794) (xy 303.419014 -298.27474)
			(xy 303.080166 -298.27474) (xy 303.079671 -298.299347) (xy 303.071776 -298.347924) (xy 303.056192 -298.394605)
			(xy 303.033321 -298.438182) (xy 303.003756 -298.477526) (xy 302.968263 -298.511618) (xy 302.92776 -298.539574)
			(xy 302.883298 -298.560672) (xy 302.836027 -298.574364) (xy 302.787172 -298.580296) (xy 302.737997 -298.578315)
			(xy 302.689778 -298.568471) (xy 302.643762 -298.551019) (xy 302.601141 -298.526412) (xy 302.56302 -298.495287)
			(xy 302.530385 -298.45845) (xy 302.504082 -298.416854) (xy 302.484791 -298.371578) (xy 302.473014 -298.323794)
			(xy 302.469054 -298.27474) (xy 302.130206 -298.27474) (xy 302.129711 -298.299347) (xy 302.121816 -298.347924)
			(xy 302.106232 -298.394605) (xy 302.083361 -298.438182) (xy 302.053796 -298.477526) (xy 302.018303 -298.511618)
			(xy 301.9778 -298.539574) (xy 301.933338 -298.560672) (xy 301.886067 -298.574364) (xy 301.837212 -298.580296)
			(xy 301.788037 -298.578315) (xy 301.739818 -298.568471) (xy 301.693802 -298.551019) (xy 301.651181 -298.526412)
			(xy 301.61306 -298.495287) (xy 301.580425 -298.45845) (xy 301.554122 -298.416854) (xy 301.534831 -298.371578)
			(xy 301.523054 -298.323794) (xy 301.519094 -298.27474) (xy 301.179992 -298.27474) (xy 301.179497 -298.299347)
			(xy 301.171602 -298.347924) (xy 301.156018 -298.394605) (xy 301.133147 -298.438182) (xy 301.103582 -298.477526)
			(xy 301.068089 -298.511618) (xy 301.027586 -298.539574) (xy 300.983124 -298.560672) (xy 300.935853 -298.574364)
			(xy 300.886998 -298.580296) (xy 300.837823 -298.578315) (xy 300.789604 -298.568471) (xy 300.743588 -298.551019)
			(xy 300.700967 -298.526412) (xy 300.662846 -298.495287) (xy 300.630211 -298.45845) (xy 300.603908 -298.416854)
			(xy 300.584617 -298.371578) (xy 300.57284 -298.323794) (xy 300.56888 -298.27474) (xy 299.280072 -298.27474)
			(xy 299.279577 -298.299347) (xy 299.271682 -298.347924) (xy 299.256098 -298.394605) (xy 299.233227 -298.438182)
			(xy 299.203662 -298.477526) (xy 299.168169 -298.511618) (xy 299.127666 -298.539574) (xy 299.083204 -298.560672)
			(xy 299.035933 -298.574364) (xy 298.987078 -298.580296) (xy 298.937903 -298.578315) (xy 298.889684 -298.568471)
			(xy 298.843668 -298.551019) (xy 298.801047 -298.526412) (xy 298.762926 -298.495287) (xy 298.730291 -298.45845)
			(xy 298.703988 -298.416854) (xy 298.684697 -298.371578) (xy 298.67292 -298.323794) (xy 298.66896 -298.27474)
			(xy 297.380152 -298.27474) (xy 297.379657 -298.299347) (xy 297.371762 -298.347924) (xy 297.356178 -298.394605)
			(xy 297.333307 -298.438182) (xy 297.303742 -298.477526) (xy 297.268249 -298.511618) (xy 297.227746 -298.539574)
			(xy 297.183284 -298.560672) (xy 297.136013 -298.574364) (xy 297.087158 -298.580296) (xy 297.037983 -298.578315)
			(xy 296.989764 -298.568471) (xy 296.943748 -298.551019) (xy 296.901127 -298.526412) (xy 296.863006 -298.495287)
			(xy 296.830371 -298.45845) (xy 296.804068 -298.416854) (xy 296.784777 -298.371578) (xy 296.773 -298.323794)
			(xy 296.76904 -298.27474) (xy 295.480232 -298.27474) (xy 295.479737 -298.299347) (xy 295.471842 -298.347924)
			(xy 295.456258 -298.394605) (xy 295.433387 -298.438182) (xy 295.403822 -298.477526) (xy 295.368329 -298.511618)
			(xy 295.327826 -298.539574) (xy 295.283364 -298.560672) (xy 295.236093 -298.574364) (xy 295.187238 -298.580296)
			(xy 295.138063 -298.578315) (xy 295.089844 -298.568471) (xy 295.043828 -298.551019) (xy 295.001207 -298.526412)
			(xy 294.963086 -298.495287) (xy 294.930451 -298.45845) (xy 294.904148 -298.416854) (xy 294.884857 -298.371578)
			(xy 294.87308 -298.323794) (xy 294.86912 -298.27474) (xy 293.580058 -298.27474) (xy 293.579563 -298.299347)
			(xy 293.571668 -298.347924) (xy 293.556084 -298.394605) (xy 293.533213 -298.438182) (xy 293.503648 -298.477526)
			(xy 293.468155 -298.511618) (xy 293.427652 -298.539574) (xy 293.38319 -298.560672) (xy 293.335919 -298.574364)
			(xy 293.287064 -298.580296) (xy 293.237889 -298.578315) (xy 293.18967 -298.568471) (xy 293.143654 -298.551019)
			(xy 293.101033 -298.526412) (xy 293.062912 -298.495287) (xy 293.030277 -298.45845) (xy 293.003974 -298.416854)
			(xy 292.984683 -298.371578) (xy 292.972906 -298.323794) (xy 292.968946 -298.27474) (xy 290.730178 -298.27474)
			(xy 290.729683 -298.299347) (xy 290.721788 -298.347924) (xy 290.706204 -298.394605) (xy 290.683333 -298.438182)
			(xy 290.653768 -298.477526) (xy 290.618275 -298.511618) (xy 290.577772 -298.539574) (xy 290.53331 -298.560672)
			(xy 290.486039 -298.574364) (xy 290.437184 -298.580296) (xy 290.388009 -298.578315) (xy 290.33979 -298.568471)
			(xy 290.293774 -298.551019) (xy 290.251153 -298.526412) (xy 290.213032 -298.495287) (xy 290.180397 -298.45845)
			(xy 290.154094 -298.416854) (xy 290.134803 -298.371578) (xy 290.123026 -298.323794) (xy 290.119066 -298.27474)
			(xy 288.830004 -298.27474) (xy 288.829509 -298.299347) (xy 288.821614 -298.347924) (xy 288.80603 -298.394605)
			(xy 288.783159 -298.438182) (xy 288.753594 -298.477526) (xy 288.718101 -298.511618) (xy 288.677598 -298.539574)
			(xy 288.633136 -298.560672) (xy 288.585865 -298.574364) (xy 288.53701 -298.580296) (xy 288.487835 -298.578315)
			(xy 288.439616 -298.568471) (xy 288.3936 -298.551019) (xy 288.350979 -298.526412) (xy 288.312858 -298.495287)
			(xy 288.280223 -298.45845) (xy 288.25392 -298.416854) (xy 288.234629 -298.371578) (xy 288.222852 -298.323794)
			(xy 288.218892 -298.27474) (xy 286.930084 -298.27474) (xy 286.929589 -298.299347) (xy 286.921694 -298.347924)
			(xy 286.90611 -298.394605) (xy 286.883239 -298.438182) (xy 286.853674 -298.477526) (xy 286.818181 -298.511618)
			(xy 286.777678 -298.539574) (xy 286.733216 -298.560672) (xy 286.685945 -298.574364) (xy 286.63709 -298.580296)
			(xy 286.587915 -298.578315) (xy 286.539696 -298.568471) (xy 286.49368 -298.551019) (xy 286.451059 -298.526412)
			(xy 286.412938 -298.495287) (xy 286.380303 -298.45845) (xy 286.354 -298.416854) (xy 286.334709 -298.371578)
			(xy 286.322932 -298.323794) (xy 286.318972 -298.27474) (xy 285.030164 -298.27474) (xy 285.029669 -298.299347)
			(xy 285.021774 -298.347924) (xy 285.00619 -298.394605) (xy 284.983319 -298.438182) (xy 284.953754 -298.477526)
			(xy 284.918261 -298.511618) (xy 284.877758 -298.539574) (xy 284.833296 -298.560672) (xy 284.786025 -298.574364)
			(xy 284.73717 -298.580296) (xy 284.687995 -298.578315) (xy 284.639776 -298.568471) (xy 284.59376 -298.551019)
			(xy 284.551139 -298.526412) (xy 284.513018 -298.495287) (xy 284.480383 -298.45845) (xy 284.45408 -298.416854)
			(xy 284.434789 -298.371578) (xy 284.423012 -298.323794) (xy 284.419052 -298.27474) (xy 283.130244 -298.27474)
			(xy 283.129749 -298.299347) (xy 283.121854 -298.347924) (xy 283.10627 -298.394605) (xy 283.083399 -298.438182)
			(xy 283.053834 -298.477526) (xy 283.018341 -298.511618) (xy 282.977838 -298.539574) (xy 282.933376 -298.560672)
			(xy 282.886105 -298.574364) (xy 282.83725 -298.580296) (xy 282.788075 -298.578315) (xy 282.739856 -298.568471)
			(xy 282.69384 -298.551019) (xy 282.651219 -298.526412) (xy 282.613098 -298.495287) (xy 282.580463 -298.45845)
			(xy 282.55416 -298.416854) (xy 282.534869 -298.371578) (xy 282.523092 -298.323794) (xy 282.519132 -298.27474)
			(xy 281.616912 -298.27474) (xy 281.616912 -298.700698) (xy 318.697354 -298.700698) (xy 318.701425 -298.645076)
			(xy 318.713551 -298.590639) (xy 318.733474 -298.538548) (xy 318.76077 -298.489913) (xy 318.794856 -298.44577)
			(xy 318.835005 -298.407061) (xy 318.880363 -298.37461) (xy 318.929963 -298.349109) (xy 318.982747 -298.331102)
			(xy 319.03759 -298.320972) (xy 319.093324 -298.318935) (xy 319.148761 -298.325035) (xy 319.202718 -298.339141)
			(xy 319.254047 -298.360953) (xy 319.301653 -298.390007) (xy 319.344521 -298.425682) (xy 319.381738 -298.467219)
			(xy 319.412511 -298.513732) (xy 319.436183 -298.564229) (xy 319.452251 -298.617636) (xy 319.460371 -298.672812)
			(xy 319.46088 -298.700698) (xy 319.460371 -298.728584) (xy 319.452251 -298.78376) (xy 319.436183 -298.837167)
			(xy 319.412511 -298.887664) (xy 319.381738 -298.934177) (xy 319.344521 -298.975714) (xy 319.301653 -299.011389)
			(xy 319.254047 -299.040443) (xy 319.202718 -299.062255) (xy 319.148761 -299.076361) (xy 319.093324 -299.082461)
			(xy 319.03759 -299.080424) (xy 318.982747 -299.070294) (xy 318.929963 -299.052287) (xy 318.880363 -299.026786)
			(xy 318.835005 -298.994335) (xy 318.794856 -298.955626) (xy 318.76077 -298.911483) (xy 318.733474 -298.862848)
			(xy 318.713551 -298.810757) (xy 318.701425 -298.75632) (xy 318.697354 -298.700698) (xy 281.616912 -298.700698)
			(xy 281.616912 -298.849288) (xy 281.617551 -298.861845) (xy 281.629404 -298.883984) (xy 281.639518 -298.891452)
			(xy 281.720544 -298.945554) (xy 281.745436 -298.948094) (xy 281.757628 -298.943014) (xy 281.785665 -298.932115)
			(xy 281.844649 -298.920348) (xy 281.874722 -298.919646) (xy 281.89998 -298.920169) (xy 281.949806 -298.928487)
			(xy 281.997584 -298.944892) (xy 282.042011 -298.968937) (xy 282.081874 -298.999966) (xy 282.116086 -299.037133)
			(xy 282.143715 -299.079425) (xy 282.164006 -299.125686) (xy 282.176406 -299.174657) (xy 282.180574 -299.224954)
			(xy 282.519132 -299.224954) (xy 282.523092 -299.1759) (xy 282.534869 -299.128116) (xy 282.55416 -299.08284)
			(xy 282.580463 -299.041244) (xy 282.613098 -299.004407) (xy 282.651219 -298.973282) (xy 282.69384 -298.948675)
			(xy 282.739856 -298.931223) (xy 282.788075 -298.921379) (xy 282.83725 -298.919398) (xy 282.886105 -298.92533)
			(xy 282.933376 -298.939022) (xy 282.977838 -298.96012) (xy 283.018341 -298.988076) (xy 283.053834 -299.022168)
			(xy 283.083399 -299.061512) (xy 283.10627 -299.105089) (xy 283.121854 -299.15177) (xy 283.129749 -299.200347)
			(xy 283.130244 -299.224954) (xy 283.469092 -299.224954) (xy 283.473052 -299.1759) (xy 283.484829 -299.128116)
			(xy 283.50412 -299.08284) (xy 283.530423 -299.041244) (xy 283.563058 -299.004407) (xy 283.601179 -298.973282)
			(xy 283.6438 -298.948675) (xy 283.689816 -298.931223) (xy 283.738035 -298.921379) (xy 283.78721 -298.919398)
			(xy 283.836065 -298.92533) (xy 283.883336 -298.939022) (xy 283.927798 -298.96012) (xy 283.968301 -298.988076)
			(xy 284.003794 -299.022168) (xy 284.033359 -299.061512) (xy 284.05623 -299.105089) (xy 284.071814 -299.15177)
			(xy 284.079709 -299.200347) (xy 284.080204 -299.224954) (xy 284.419052 -299.224954) (xy 284.423012 -299.1759)
			(xy 284.434789 -299.128116) (xy 284.45408 -299.08284) (xy 284.480383 -299.041244) (xy 284.513018 -299.004407)
			(xy 284.551139 -298.973282) (xy 284.59376 -298.948675) (xy 284.639776 -298.931223) (xy 284.687995 -298.921379)
			(xy 284.73717 -298.919398) (xy 284.786025 -298.92533) (xy 284.833296 -298.939022) (xy 284.877758 -298.96012)
			(xy 284.918261 -298.988076) (xy 284.953754 -299.022168) (xy 284.983319 -299.061512) (xy 285.00619 -299.105089)
			(xy 285.021774 -299.15177) (xy 285.029669 -299.200347) (xy 285.030164 -299.224954) (xy 285.369012 -299.224954)
			(xy 285.372972 -299.1759) (xy 285.384749 -299.128116) (xy 285.40404 -299.08284) (xy 285.430343 -299.041244)
			(xy 285.462978 -299.004407) (xy 285.501099 -298.973282) (xy 285.54372 -298.948675) (xy 285.589736 -298.931223)
			(xy 285.637955 -298.921379) (xy 285.68713 -298.919398) (xy 285.735985 -298.92533) (xy 285.783256 -298.939022)
			(xy 285.827718 -298.96012) (xy 285.868221 -298.988076) (xy 285.903714 -299.022168) (xy 285.933279 -299.061512)
			(xy 285.95615 -299.105089) (xy 285.971734 -299.15177) (xy 285.979629 -299.200347) (xy 285.980124 -299.224954)
			(xy 286.318972 -299.224954) (xy 286.322932 -299.1759) (xy 286.334709 -299.128116) (xy 286.354 -299.08284)
			(xy 286.380303 -299.041244) (xy 286.412938 -299.004407) (xy 286.451059 -298.973282) (xy 286.49368 -298.948675)
			(xy 286.539696 -298.931223) (xy 286.587915 -298.921379) (xy 286.63709 -298.919398) (xy 286.685945 -298.92533)
			(xy 286.733216 -298.939022) (xy 286.777678 -298.96012) (xy 286.818181 -298.988076) (xy 286.853674 -299.022168)
			(xy 286.883239 -299.061512) (xy 286.90611 -299.105089) (xy 286.921694 -299.15177) (xy 286.929589 -299.200347)
			(xy 286.930084 -299.224954) (xy 287.268932 -299.224954) (xy 287.272892 -299.1759) (xy 287.284669 -299.128116)
			(xy 287.30396 -299.08284) (xy 287.330263 -299.041244) (xy 287.362898 -299.004407) (xy 287.401019 -298.973282)
			(xy 287.44364 -298.948675) (xy 287.489656 -298.931223) (xy 287.537875 -298.921379) (xy 287.58705 -298.919398)
			(xy 287.635905 -298.92533) (xy 287.683176 -298.939022) (xy 287.727638 -298.96012) (xy 287.768141 -298.988076)
			(xy 287.803634 -299.022168) (xy 287.833199 -299.061512) (xy 287.85607 -299.105089) (xy 287.871654 -299.15177)
			(xy 287.879549 -299.200347) (xy 287.880044 -299.224954) (xy 288.218892 -299.224954) (xy 288.222852 -299.1759)
			(xy 288.234629 -299.128116) (xy 288.25392 -299.08284) (xy 288.280223 -299.041244) (xy 288.312858 -299.004407)
			(xy 288.350979 -298.973282) (xy 288.3936 -298.948675) (xy 288.439616 -298.931223) (xy 288.487835 -298.921379)
			(xy 288.53701 -298.919398) (xy 288.585865 -298.92533) (xy 288.633136 -298.939022) (xy 288.677598 -298.96012)
			(xy 288.718101 -298.988076) (xy 288.753594 -299.022168) (xy 288.783159 -299.061512) (xy 288.80603 -299.105089)
			(xy 288.821614 -299.15177) (xy 288.829509 -299.200347) (xy 288.830004 -299.224954) (xy 289.169106 -299.224954)
			(xy 289.173066 -299.1759) (xy 289.184843 -299.128116) (xy 289.204134 -299.08284) (xy 289.230437 -299.041244)
			(xy 289.263072 -299.004407) (xy 289.301193 -298.973282) (xy 289.343814 -298.948675) (xy 289.38983 -298.931223)
			(xy 289.438049 -298.921379) (xy 289.487224 -298.919398) (xy 289.536079 -298.92533) (xy 289.58335 -298.939022)
			(xy 289.627812 -298.96012) (xy 289.668315 -298.988076) (xy 289.703808 -299.022168) (xy 289.733373 -299.061512)
			(xy 289.756244 -299.105089) (xy 289.771828 -299.15177) (xy 289.779723 -299.200347) (xy 289.780218 -299.224954)
			(xy 290.119066 -299.224954) (xy 290.123026 -299.1759) (xy 290.134803 -299.128116) (xy 290.154094 -299.08284)
			(xy 290.180397 -299.041244) (xy 290.213032 -299.004407) (xy 290.251153 -298.973282) (xy 290.293774 -298.948675)
			(xy 290.33979 -298.931223) (xy 290.388009 -298.921379) (xy 290.437184 -298.919398) (xy 290.486039 -298.92533)
			(xy 290.53331 -298.939022) (xy 290.577772 -298.96012) (xy 290.618275 -298.988076) (xy 290.653768 -299.022168)
			(xy 290.683333 -299.061512) (xy 290.706204 -299.105089) (xy 290.721788 -299.15177) (xy 290.729683 -299.200347)
			(xy 290.730178 -299.224954) (xy 292.018986 -299.224954) (xy 292.022946 -299.1759) (xy 292.034723 -299.128116)
			(xy 292.054014 -299.08284) (xy 292.080317 -299.041244) (xy 292.112952 -299.004407) (xy 292.151073 -298.973282)
			(xy 292.193694 -298.948675) (xy 292.23971 -298.931223) (xy 292.287929 -298.921379) (xy 292.337104 -298.919398)
			(xy 292.385959 -298.92533) (xy 292.43323 -298.939022) (xy 292.477692 -298.96012) (xy 292.518195 -298.988076)
			(xy 292.553688 -299.022168) (xy 292.583253 -299.061512) (xy 292.606124 -299.105089) (xy 292.621708 -299.15177)
			(xy 292.629603 -299.200347) (xy 292.630098 -299.224954) (xy 292.968946 -299.224954) (xy 292.972906 -299.1759)
			(xy 292.984683 -299.128116) (xy 293.003974 -299.08284) (xy 293.030277 -299.041244) (xy 293.062912 -299.004407)
			(xy 293.101033 -298.973282) (xy 293.143654 -298.948675) (xy 293.18967 -298.931223) (xy 293.237889 -298.921379)
			(xy 293.287064 -298.919398) (xy 293.335919 -298.92533) (xy 293.38319 -298.939022) (xy 293.427652 -298.96012)
			(xy 293.468155 -298.988076) (xy 293.503648 -299.022168) (xy 293.533213 -299.061512) (xy 293.556084 -299.105089)
			(xy 293.571668 -299.15177) (xy 293.579563 -299.200347) (xy 293.580058 -299.224954) (xy 293.918906 -299.224954)
			(xy 293.922866 -299.1759) (xy 293.934643 -299.128116) (xy 293.953934 -299.08284) (xy 293.980237 -299.041244)
			(xy 294.012872 -299.004407) (xy 294.050993 -298.973282) (xy 294.093614 -298.948675) (xy 294.13963 -298.931223)
			(xy 294.187849 -298.921379) (xy 294.237024 -298.919398) (xy 294.285879 -298.92533) (xy 294.33315 -298.939022)
			(xy 294.377612 -298.96012) (xy 294.418115 -298.988076) (xy 294.453608 -299.022168) (xy 294.483173 -299.061512)
			(xy 294.506044 -299.105089) (xy 294.521628 -299.15177) (xy 294.529523 -299.200347) (xy 294.530018 -299.224954)
			(xy 294.86912 -299.224954) (xy 294.87308 -299.1759) (xy 294.884857 -299.128116) (xy 294.904148 -299.08284)
			(xy 294.930451 -299.041244) (xy 294.963086 -299.004407) (xy 295.001207 -298.973282) (xy 295.043828 -298.948675)
			(xy 295.089844 -298.931223) (xy 295.138063 -298.921379) (xy 295.187238 -298.919398) (xy 295.236093 -298.92533)
			(xy 295.283364 -298.939022) (xy 295.327826 -298.96012) (xy 295.368329 -298.988076) (xy 295.403822 -299.022168)
			(xy 295.433387 -299.061512) (xy 295.456258 -299.105089) (xy 295.471842 -299.15177) (xy 295.479737 -299.200347)
			(xy 295.480232 -299.224954) (xy 295.81908 -299.224954) (xy 295.82304 -299.1759) (xy 295.834817 -299.128116)
			(xy 295.854108 -299.08284) (xy 295.880411 -299.041244) (xy 295.913046 -299.004407) (xy 295.951167 -298.973282)
			(xy 295.993788 -298.948675) (xy 296.039804 -298.931223) (xy 296.088023 -298.921379) (xy 296.137198 -298.919398)
			(xy 296.186053 -298.92533) (xy 296.233324 -298.939022) (xy 296.277786 -298.96012) (xy 296.318289 -298.988076)
			(xy 296.353782 -299.022168) (xy 296.383347 -299.061512) (xy 296.406218 -299.105089) (xy 296.421802 -299.15177)
			(xy 296.429697 -299.200347) (xy 296.430192 -299.224954) (xy 296.76904 -299.224954) (xy 296.773 -299.1759)
			(xy 296.784777 -299.128116) (xy 296.804068 -299.08284) (xy 296.830371 -299.041244) (xy 296.863006 -299.004407)
			(xy 296.901127 -298.973282) (xy 296.943748 -298.948675) (xy 296.989764 -298.931223) (xy 297.037983 -298.921379)
			(xy 297.087158 -298.919398) (xy 297.136013 -298.92533) (xy 297.183284 -298.939022) (xy 297.227746 -298.96012)
			(xy 297.268249 -298.988076) (xy 297.303742 -299.022168) (xy 297.333307 -299.061512) (xy 297.356178 -299.105089)
			(xy 297.371762 -299.15177) (xy 297.379657 -299.200347) (xy 297.380152 -299.224954) (xy 297.719 -299.224954)
			(xy 297.72296 -299.1759) (xy 297.734737 -299.128116) (xy 297.754028 -299.08284) (xy 297.780331 -299.041244)
			(xy 297.812966 -299.004407) (xy 297.851087 -298.973282) (xy 297.893708 -298.948675) (xy 297.939724 -298.931223)
			(xy 297.987943 -298.921379) (xy 298.037118 -298.919398) (xy 298.085973 -298.92533) (xy 298.133244 -298.939022)
			(xy 298.177706 -298.96012) (xy 298.218209 -298.988076) (xy 298.253702 -299.022168) (xy 298.283267 -299.061512)
			(xy 298.306138 -299.105089) (xy 298.321722 -299.15177) (xy 298.329617 -299.200347) (xy 298.330112 -299.224954)
			(xy 298.66896 -299.224954) (xy 298.67292 -299.1759) (xy 298.684697 -299.128116) (xy 298.703988 -299.08284)
			(xy 298.730291 -299.041244) (xy 298.762926 -299.004407) (xy 298.801047 -298.973282) (xy 298.843668 -298.948675)
			(xy 298.889684 -298.931223) (xy 298.937903 -298.921379) (xy 298.987078 -298.919398) (xy 299.035933 -298.92533)
			(xy 299.083204 -298.939022) (xy 299.127666 -298.96012) (xy 299.168169 -298.988076) (xy 299.203662 -299.022168)
			(xy 299.233227 -299.061512) (xy 299.256098 -299.105089) (xy 299.271682 -299.15177) (xy 299.279577 -299.200347)
			(xy 299.280072 -299.224954) (xy 299.61892 -299.224954) (xy 299.62288 -299.1759) (xy 299.634657 -299.128116)
			(xy 299.653948 -299.08284) (xy 299.680251 -299.041244) (xy 299.712886 -299.004407) (xy 299.751007 -298.973282)
			(xy 299.793628 -298.948675) (xy 299.839644 -298.931223) (xy 299.887863 -298.921379) (xy 299.937038 -298.919398)
			(xy 299.985893 -298.92533) (xy 300.033164 -298.939022) (xy 300.077626 -298.96012) (xy 300.118129 -298.988076)
			(xy 300.153622 -299.022168) (xy 300.183187 -299.061512) (xy 300.206058 -299.105089) (xy 300.221642 -299.15177)
			(xy 300.229537 -299.200347) (xy 300.230032 -299.224954) (xy 300.56888 -299.224954) (xy 300.57284 -299.1759)
			(xy 300.584617 -299.128116) (xy 300.603908 -299.08284) (xy 300.630211 -299.041244) (xy 300.662846 -299.004407)
			(xy 300.700967 -298.973282) (xy 300.743588 -298.948675) (xy 300.789604 -298.931223) (xy 300.837823 -298.921379)
			(xy 300.886998 -298.919398) (xy 300.935853 -298.92533) (xy 300.983124 -298.939022) (xy 301.027586 -298.96012)
			(xy 301.068089 -298.988076) (xy 301.103582 -299.022168) (xy 301.133147 -299.061512) (xy 301.156018 -299.105089)
			(xy 301.171602 -299.15177) (xy 301.179497 -299.200347) (xy 301.179992 -299.224954) (xy 301.519094 -299.224954)
			(xy 301.523054 -299.1759) (xy 301.534831 -299.128116) (xy 301.554122 -299.08284) (xy 301.580425 -299.041244)
			(xy 301.61306 -299.004407) (xy 301.651181 -298.973282) (xy 301.693802 -298.948675) (xy 301.739818 -298.931223)
			(xy 301.788037 -298.921379) (xy 301.837212 -298.919398) (xy 301.886067 -298.92533) (xy 301.933338 -298.939022)
			(xy 301.9778 -298.96012) (xy 302.018303 -298.988076) (xy 302.053796 -299.022168) (xy 302.083361 -299.061512)
			(xy 302.106232 -299.105089) (xy 302.121816 -299.15177) (xy 302.129711 -299.200347) (xy 302.130206 -299.224954)
			(xy 302.469054 -299.224954) (xy 302.473014 -299.1759) (xy 302.484791 -299.128116) (xy 302.504082 -299.08284)
			(xy 302.530385 -299.041244) (xy 302.56302 -299.004407) (xy 302.601141 -298.973282) (xy 302.643762 -298.948675)
			(xy 302.689778 -298.931223) (xy 302.737997 -298.921379) (xy 302.787172 -298.919398) (xy 302.836027 -298.92533)
			(xy 302.883298 -298.939022) (xy 302.92776 -298.96012) (xy 302.968263 -298.988076) (xy 303.003756 -299.022168)
			(xy 303.033321 -299.061512) (xy 303.056192 -299.105089) (xy 303.071776 -299.15177) (xy 303.079671 -299.200347)
			(xy 303.080166 -299.224954) (xy 303.419014 -299.224954) (xy 303.422974 -299.1759) (xy 303.434751 -299.128116)
			(xy 303.454042 -299.08284) (xy 303.480345 -299.041244) (xy 303.51298 -299.004407) (xy 303.551101 -298.973282)
			(xy 303.593722 -298.948675) (xy 303.639738 -298.931223) (xy 303.687957 -298.921379) (xy 303.737132 -298.919398)
			(xy 303.785987 -298.92533) (xy 303.833258 -298.939022) (xy 303.87772 -298.96012) (xy 303.918223 -298.988076)
			(xy 303.953716 -299.022168) (xy 303.983281 -299.061512) (xy 304.006152 -299.105089) (xy 304.021736 -299.15177)
			(xy 304.029631 -299.200347) (xy 304.030126 -299.224954) (xy 304.368974 -299.224954) (xy 304.372934 -299.1759)
			(xy 304.384711 -299.128116) (xy 304.404002 -299.08284) (xy 304.430305 -299.041244) (xy 304.46294 -299.004407)
			(xy 304.501061 -298.973282) (xy 304.543682 -298.948675) (xy 304.589698 -298.931223) (xy 304.637917 -298.921379)
			(xy 304.687092 -298.919398) (xy 304.735947 -298.92533) (xy 304.783218 -298.939022) (xy 304.82768 -298.96012)
			(xy 304.868183 -298.988076) (xy 304.903676 -299.022168) (xy 304.933241 -299.061512) (xy 304.956112 -299.105089)
			(xy 304.971696 -299.15177) (xy 304.979591 -299.200347) (xy 304.980086 -299.224954) (xy 305.318934 -299.224954)
			(xy 305.322894 -299.1759) (xy 305.334671 -299.128116) (xy 305.353962 -299.08284) (xy 305.380265 -299.041244)
			(xy 305.4129 -299.004407) (xy 305.451021 -298.973282) (xy 305.493642 -298.948675) (xy 305.539658 -298.931223)
			(xy 305.587877 -298.921379) (xy 305.637052 -298.919398) (xy 305.685907 -298.92533) (xy 305.733178 -298.939022)
			(xy 305.77764 -298.96012) (xy 305.818143 -298.988076) (xy 305.853636 -299.022168) (xy 305.883201 -299.061512)
			(xy 305.906072 -299.105089) (xy 305.921656 -299.15177) (xy 305.929551 -299.200347) (xy 305.930046 -299.224954)
			(xy 308.169068 -299.224954) (xy 308.173028 -299.1759) (xy 308.184805 -299.128116) (xy 308.204096 -299.08284)
			(xy 308.230399 -299.041244) (xy 308.263034 -299.004407) (xy 308.301155 -298.973282) (xy 308.343776 -298.948675)
			(xy 308.389792 -298.931223) (xy 308.438011 -298.921379) (xy 308.487186 -298.919398) (xy 308.536041 -298.92533)
			(xy 308.583312 -298.939022) (xy 308.627774 -298.96012) (xy 308.668277 -298.988076) (xy 308.70377 -299.022168)
			(xy 308.733335 -299.061512) (xy 308.756206 -299.105089) (xy 308.77179 -299.15177) (xy 308.779685 -299.200347)
			(xy 308.78018 -299.224954) (xy 309.119028 -299.224954) (xy 309.122988 -299.1759) (xy 309.134765 -299.128116)
			(xy 309.154056 -299.08284) (xy 309.180359 -299.041244) (xy 309.212994 -299.004407) (xy 309.251115 -298.973282)
			(xy 309.293736 -298.948675) (xy 309.339752 -298.931223) (xy 309.387971 -298.921379) (xy 309.437146 -298.919398)
			(xy 309.486001 -298.92533) (xy 309.533272 -298.939022) (xy 309.577734 -298.96012) (xy 309.618237 -298.988076)
			(xy 309.65373 -299.022168) (xy 309.683295 -299.061512) (xy 309.706166 -299.105089) (xy 309.72175 -299.15177)
			(xy 309.729645 -299.200347) (xy 309.73014 -299.224954) (xy 310.068988 -299.224954) (xy 310.072948 -299.1759)
			(xy 310.084725 -299.128116) (xy 310.104016 -299.08284) (xy 310.130319 -299.041244) (xy 310.162954 -299.004407)
			(xy 310.201075 -298.973282) (xy 310.243696 -298.948675) (xy 310.289712 -298.931223) (xy 310.337931 -298.921379)
			(xy 310.387106 -298.919398) (xy 310.435961 -298.92533) (xy 310.483232 -298.939022) (xy 310.527694 -298.96012)
			(xy 310.568197 -298.988076) (xy 310.60369 -299.022168) (xy 310.633255 -299.061512) (xy 310.656126 -299.105089)
			(xy 310.67171 -299.15177) (xy 310.679605 -299.200347) (xy 310.6801 -299.224954) (xy 311.018948 -299.224954)
			(xy 311.022908 -299.1759) (xy 311.034685 -299.128116) (xy 311.053976 -299.08284) (xy 311.080279 -299.041244)
			(xy 311.112914 -299.004407) (xy 311.151035 -298.973282) (xy 311.193656 -298.948675) (xy 311.239672 -298.931223)
			(xy 311.287891 -298.921379) (xy 311.337066 -298.919398) (xy 311.385921 -298.92533) (xy 311.433192 -298.939022)
			(xy 311.477654 -298.96012) (xy 311.518157 -298.988076) (xy 311.55365 -299.022168) (xy 311.583215 -299.061512)
			(xy 311.606086 -299.105089) (xy 311.62167 -299.15177) (xy 311.629565 -299.200347) (xy 311.63006 -299.224954)
			(xy 311.968908 -299.224954) (xy 311.972868 -299.1759) (xy 311.984645 -299.128116) (xy 312.003936 -299.08284)
			(xy 312.030239 -299.041244) (xy 312.062874 -299.004407) (xy 312.100995 -298.973282) (xy 312.143616 -298.948675)
			(xy 312.189632 -298.931223) (xy 312.237851 -298.921379) (xy 312.287026 -298.919398) (xy 312.335881 -298.92533)
			(xy 312.383152 -298.939022) (xy 312.427614 -298.96012) (xy 312.468117 -298.988076) (xy 312.50361 -299.022168)
			(xy 312.533175 -299.061512) (xy 312.556046 -299.105089) (xy 312.57163 -299.15177) (xy 312.579525 -299.200347)
			(xy 312.58002 -299.224954) (xy 312.919122 -299.224954) (xy 312.923082 -299.1759) (xy 312.934859 -299.128116)
			(xy 312.95415 -299.08284) (xy 312.980453 -299.041244) (xy 313.013088 -299.004407) (xy 313.051209 -298.973282)
			(xy 313.09383 -298.948675) (xy 313.139846 -298.931223) (xy 313.188065 -298.921379) (xy 313.23724 -298.919398)
			(xy 313.286095 -298.92533) (xy 313.333366 -298.939022) (xy 313.377828 -298.96012) (xy 313.418331 -298.988076)
			(xy 313.453824 -299.022168) (xy 313.483389 -299.061512) (xy 313.50626 -299.105089) (xy 313.521844 -299.15177)
			(xy 313.529739 -299.200347) (xy 313.530234 -299.224954) (xy 313.869082 -299.224954) (xy 313.873042 -299.1759)
			(xy 313.884819 -299.128116) (xy 313.90411 -299.08284) (xy 313.930413 -299.041244) (xy 313.963048 -299.004407)
			(xy 314.001169 -298.973282) (xy 314.04379 -298.948675) (xy 314.089806 -298.931223) (xy 314.138025 -298.921379)
			(xy 314.1872 -298.919398) (xy 314.236055 -298.92533) (xy 314.283326 -298.939022) (xy 314.327788 -298.96012)
			(xy 314.368291 -298.988076) (xy 314.403784 -299.022168) (xy 314.433349 -299.061512) (xy 314.45622 -299.105089)
			(xy 314.471804 -299.15177) (xy 314.479699 -299.200347) (xy 314.480194 -299.224954) (xy 314.819042 -299.224954)
			(xy 314.823002 -299.1759) (xy 314.834779 -299.128116) (xy 314.85407 -299.08284) (xy 314.880373 -299.041244)
			(xy 314.913008 -299.004407) (xy 314.951129 -298.973282) (xy 314.99375 -298.948675) (xy 315.039766 -298.931223)
			(xy 315.087985 -298.921379) (xy 315.13716 -298.919398) (xy 315.186015 -298.92533) (xy 315.233286 -298.939022)
			(xy 315.277748 -298.96012) (xy 315.318251 -298.988076) (xy 315.353744 -299.022168) (xy 315.383309 -299.061512)
			(xy 315.40618 -299.105089) (xy 315.421764 -299.15177) (xy 315.429659 -299.200347) (xy 315.430154 -299.224954)
			(xy 315.429659 -299.249561) (xy 315.425856 -299.27296) (xy 322.514466 -299.27296) (xy 322.518537 -299.217338)
			(xy 322.530663 -299.162901) (xy 322.550586 -299.11081) (xy 322.577882 -299.062175) (xy 322.611968 -299.018032)
			(xy 322.652117 -298.979323) (xy 322.697475 -298.946872) (xy 322.747075 -298.921371) (xy 322.799859 -298.903364)
			(xy 322.854702 -298.893234) (xy 322.910436 -298.891197) (xy 322.965873 -298.897297) (xy 323.01983 -298.911403)
			(xy 323.071159 -298.933215) (xy 323.118765 -298.962269) (xy 323.161633 -298.997944) (xy 323.19885 -299.039481)
			(xy 323.229623 -299.085994) (xy 323.253295 -299.136491) (xy 323.269363 -299.189898) (xy 323.277483 -299.245074)
			(xy 323.277992 -299.27296) (xy 323.277483 -299.300846) (xy 323.269363 -299.356022) (xy 323.253295 -299.409429)
			(xy 323.229623 -299.459926) (xy 323.19885 -299.506439) (xy 323.161633 -299.547976) (xy 323.118765 -299.583651)
			(xy 323.071159 -299.612705) (xy 323.01983 -299.634517) (xy 322.965873 -299.648623) (xy 322.910436 -299.654723)
			(xy 322.854702 -299.652686) (xy 322.799859 -299.642556) (xy 322.747075 -299.624549) (xy 322.697475 -299.599048)
			(xy 322.652117 -299.566597) (xy 322.611968 -299.527888) (xy 322.577882 -299.483745) (xy 322.550586 -299.43511)
			(xy 322.530663 -299.383019) (xy 322.518537 -299.328582) (xy 322.514466 -299.27296) (xy 315.425856 -299.27296)
			(xy 315.421764 -299.298138) (xy 315.40618 -299.344819) (xy 315.383309 -299.388396) (xy 315.353744 -299.42774)
			(xy 315.318251 -299.461832) (xy 315.277748 -299.489788) (xy 315.233286 -299.510886) (xy 315.186015 -299.524578)
			(xy 315.13716 -299.53051) (xy 315.087985 -299.528529) (xy 315.039766 -299.518685) (xy 314.99375 -299.501233)
			(xy 314.951129 -299.476626) (xy 314.913008 -299.445501) (xy 314.880373 -299.408664) (xy 314.85407 -299.367068)
			(xy 314.834779 -299.321792) (xy 314.823002 -299.274008) (xy 314.819042 -299.224954) (xy 314.480194 -299.224954)
			(xy 314.479699 -299.249561) (xy 314.471804 -299.298138) (xy 314.45622 -299.344819) (xy 314.433349 -299.388396)
			(xy 314.403784 -299.42774) (xy 314.368291 -299.461832) (xy 314.327788 -299.489788) (xy 314.283326 -299.510886)
			(xy 314.236055 -299.524578) (xy 314.1872 -299.53051) (xy 314.138025 -299.528529) (xy 314.089806 -299.518685)
			(xy 314.04379 -299.501233) (xy 314.001169 -299.476626) (xy 313.963048 -299.445501) (xy 313.930413 -299.408664)
			(xy 313.90411 -299.367068) (xy 313.884819 -299.321792) (xy 313.873042 -299.274008) (xy 313.869082 -299.224954)
			(xy 313.530234 -299.224954) (xy 313.529739 -299.249561) (xy 313.521844 -299.298138) (xy 313.50626 -299.344819)
			(xy 313.483389 -299.388396) (xy 313.453824 -299.42774) (xy 313.418331 -299.461832) (xy 313.377828 -299.489788)
			(xy 313.333366 -299.510886) (xy 313.286095 -299.524578) (xy 313.23724 -299.53051) (xy 313.188065 -299.528529)
			(xy 313.139846 -299.518685) (xy 313.09383 -299.501233) (xy 313.051209 -299.476626) (xy 313.013088 -299.445501)
			(xy 312.980453 -299.408664) (xy 312.95415 -299.367068) (xy 312.934859 -299.321792) (xy 312.923082 -299.274008)
			(xy 312.919122 -299.224954) (xy 312.58002 -299.224954) (xy 312.579525 -299.249561) (xy 312.57163 -299.298138)
			(xy 312.556046 -299.344819) (xy 312.533175 -299.388396) (xy 312.50361 -299.42774) (xy 312.468117 -299.461832)
			(xy 312.427614 -299.489788) (xy 312.383152 -299.510886) (xy 312.335881 -299.524578) (xy 312.287026 -299.53051)
			(xy 312.237851 -299.528529) (xy 312.189632 -299.518685) (xy 312.143616 -299.501233) (xy 312.100995 -299.476626)
			(xy 312.062874 -299.445501) (xy 312.030239 -299.408664) (xy 312.003936 -299.367068) (xy 311.984645 -299.321792)
			(xy 311.972868 -299.274008) (xy 311.968908 -299.224954) (xy 311.63006 -299.224954) (xy 311.629565 -299.249561)
			(xy 311.62167 -299.298138) (xy 311.606086 -299.344819) (xy 311.583215 -299.388396) (xy 311.55365 -299.42774)
			(xy 311.518157 -299.461832) (xy 311.477654 -299.489788) (xy 311.433192 -299.510886) (xy 311.385921 -299.524578)
			(xy 311.337066 -299.53051) (xy 311.287891 -299.528529) (xy 311.239672 -299.518685) (xy 311.193656 -299.501233)
			(xy 311.151035 -299.476626) (xy 311.112914 -299.445501) (xy 311.080279 -299.408664) (xy 311.053976 -299.367068)
			(xy 311.034685 -299.321792) (xy 311.022908 -299.274008) (xy 311.018948 -299.224954) (xy 310.6801 -299.224954)
			(xy 310.679605 -299.249561) (xy 310.67171 -299.298138) (xy 310.656126 -299.344819) (xy 310.633255 -299.388396)
			(xy 310.60369 -299.42774) (xy 310.568197 -299.461832) (xy 310.527694 -299.489788) (xy 310.483232 -299.510886)
			(xy 310.435961 -299.524578) (xy 310.387106 -299.53051) (xy 310.337931 -299.528529) (xy 310.289712 -299.518685)
			(xy 310.243696 -299.501233) (xy 310.201075 -299.476626) (xy 310.162954 -299.445501) (xy 310.130319 -299.408664)
			(xy 310.104016 -299.367068) (xy 310.084725 -299.321792) (xy 310.072948 -299.274008) (xy 310.068988 -299.224954)
			(xy 309.73014 -299.224954) (xy 309.729645 -299.249561) (xy 309.72175 -299.298138) (xy 309.706166 -299.344819)
			(xy 309.683295 -299.388396) (xy 309.65373 -299.42774) (xy 309.618237 -299.461832) (xy 309.577734 -299.489788)
			(xy 309.533272 -299.510886) (xy 309.486001 -299.524578) (xy 309.437146 -299.53051) (xy 309.387971 -299.528529)
			(xy 309.339752 -299.518685) (xy 309.293736 -299.501233) (xy 309.251115 -299.476626) (xy 309.212994 -299.445501)
			(xy 309.180359 -299.408664) (xy 309.154056 -299.367068) (xy 309.134765 -299.321792) (xy 309.122988 -299.274008)
			(xy 309.119028 -299.224954) (xy 308.78018 -299.224954) (xy 308.779685 -299.249561) (xy 308.77179 -299.298138)
			(xy 308.756206 -299.344819) (xy 308.733335 -299.388396) (xy 308.70377 -299.42774) (xy 308.668277 -299.461832)
			(xy 308.627774 -299.489788) (xy 308.583312 -299.510886) (xy 308.536041 -299.524578) (xy 308.487186 -299.53051)
			(xy 308.438011 -299.528529) (xy 308.389792 -299.518685) (xy 308.343776 -299.501233) (xy 308.301155 -299.476626)
			(xy 308.263034 -299.445501) (xy 308.230399 -299.408664) (xy 308.204096 -299.367068) (xy 308.184805 -299.321792)
			(xy 308.173028 -299.274008) (xy 308.169068 -299.224954) (xy 305.930046 -299.224954) (xy 305.929551 -299.249561)
			(xy 305.921656 -299.298138) (xy 305.906072 -299.344819) (xy 305.883201 -299.388396) (xy 305.853636 -299.42774)
			(xy 305.818143 -299.461832) (xy 305.77764 -299.489788) (xy 305.733178 -299.510886) (xy 305.685907 -299.524578)
			(xy 305.637052 -299.53051) (xy 305.587877 -299.528529) (xy 305.539658 -299.518685) (xy 305.493642 -299.501233)
			(xy 305.451021 -299.476626) (xy 305.4129 -299.445501) (xy 305.380265 -299.408664) (xy 305.353962 -299.367068)
			(xy 305.334671 -299.321792) (xy 305.322894 -299.274008) (xy 305.318934 -299.224954) (xy 304.980086 -299.224954)
			(xy 304.979591 -299.249561) (xy 304.971696 -299.298138) (xy 304.956112 -299.344819) (xy 304.933241 -299.388396)
			(xy 304.903676 -299.42774) (xy 304.868183 -299.461832) (xy 304.82768 -299.489788) (xy 304.783218 -299.510886)
			(xy 304.735947 -299.524578) (xy 304.687092 -299.53051) (xy 304.637917 -299.528529) (xy 304.589698 -299.518685)
			(xy 304.543682 -299.501233) (xy 304.501061 -299.476626) (xy 304.46294 -299.445501) (xy 304.430305 -299.408664)
			(xy 304.404002 -299.367068) (xy 304.384711 -299.321792) (xy 304.372934 -299.274008) (xy 304.368974 -299.224954)
			(xy 304.030126 -299.224954) (xy 304.029631 -299.249561) (xy 304.021736 -299.298138) (xy 304.006152 -299.344819)
			(xy 303.983281 -299.388396) (xy 303.953716 -299.42774) (xy 303.918223 -299.461832) (xy 303.87772 -299.489788)
			(xy 303.833258 -299.510886) (xy 303.785987 -299.524578) (xy 303.737132 -299.53051) (xy 303.687957 -299.528529)
			(xy 303.639738 -299.518685) (xy 303.593722 -299.501233) (xy 303.551101 -299.476626) (xy 303.51298 -299.445501)
			(xy 303.480345 -299.408664) (xy 303.454042 -299.367068) (xy 303.434751 -299.321792) (xy 303.422974 -299.274008)
			(xy 303.419014 -299.224954) (xy 303.080166 -299.224954) (xy 303.079671 -299.249561) (xy 303.071776 -299.298138)
			(xy 303.056192 -299.344819) (xy 303.033321 -299.388396) (xy 303.003756 -299.42774) (xy 302.968263 -299.461832)
			(xy 302.92776 -299.489788) (xy 302.883298 -299.510886) (xy 302.836027 -299.524578) (xy 302.787172 -299.53051)
			(xy 302.737997 -299.528529) (xy 302.689778 -299.518685) (xy 302.643762 -299.501233) (xy 302.601141 -299.476626)
			(xy 302.56302 -299.445501) (xy 302.530385 -299.408664) (xy 302.504082 -299.367068) (xy 302.484791 -299.321792)
			(xy 302.473014 -299.274008) (xy 302.469054 -299.224954) (xy 302.130206 -299.224954) (xy 302.129711 -299.249561)
			(xy 302.121816 -299.298138) (xy 302.106232 -299.344819) (xy 302.083361 -299.388396) (xy 302.053796 -299.42774)
			(xy 302.018303 -299.461832) (xy 301.9778 -299.489788) (xy 301.933338 -299.510886) (xy 301.886067 -299.524578)
			(xy 301.837212 -299.53051) (xy 301.788037 -299.528529) (xy 301.739818 -299.518685) (xy 301.693802 -299.501233)
			(xy 301.651181 -299.476626) (xy 301.61306 -299.445501) (xy 301.580425 -299.408664) (xy 301.554122 -299.367068)
			(xy 301.534831 -299.321792) (xy 301.523054 -299.274008) (xy 301.519094 -299.224954) (xy 301.179992 -299.224954)
			(xy 301.179497 -299.249561) (xy 301.171602 -299.298138) (xy 301.156018 -299.344819) (xy 301.133147 -299.388396)
			(xy 301.103582 -299.42774) (xy 301.068089 -299.461832) (xy 301.027586 -299.489788) (xy 300.983124 -299.510886)
			(xy 300.935853 -299.524578) (xy 300.886998 -299.53051) (xy 300.837823 -299.528529) (xy 300.789604 -299.518685)
			(xy 300.743588 -299.501233) (xy 300.700967 -299.476626) (xy 300.662846 -299.445501) (xy 300.630211 -299.408664)
			(xy 300.603908 -299.367068) (xy 300.584617 -299.321792) (xy 300.57284 -299.274008) (xy 300.56888 -299.224954)
			(xy 300.230032 -299.224954) (xy 300.229537 -299.249561) (xy 300.221642 -299.298138) (xy 300.206058 -299.344819)
			(xy 300.183187 -299.388396) (xy 300.153622 -299.42774) (xy 300.118129 -299.461832) (xy 300.077626 -299.489788)
			(xy 300.033164 -299.510886) (xy 299.985893 -299.524578) (xy 299.937038 -299.53051) (xy 299.887863 -299.528529)
			(xy 299.839644 -299.518685) (xy 299.793628 -299.501233) (xy 299.751007 -299.476626) (xy 299.712886 -299.445501)
			(xy 299.680251 -299.408664) (xy 299.653948 -299.367068) (xy 299.634657 -299.321792) (xy 299.62288 -299.274008)
			(xy 299.61892 -299.224954) (xy 299.280072 -299.224954) (xy 299.279577 -299.249561) (xy 299.271682 -299.298138)
			(xy 299.256098 -299.344819) (xy 299.233227 -299.388396) (xy 299.203662 -299.42774) (xy 299.168169 -299.461832)
			(xy 299.127666 -299.489788) (xy 299.083204 -299.510886) (xy 299.035933 -299.524578) (xy 298.987078 -299.53051)
			(xy 298.937903 -299.528529) (xy 298.889684 -299.518685) (xy 298.843668 -299.501233) (xy 298.801047 -299.476626)
			(xy 298.762926 -299.445501) (xy 298.730291 -299.408664) (xy 298.703988 -299.367068) (xy 298.684697 -299.321792)
			(xy 298.67292 -299.274008) (xy 298.66896 -299.224954) (xy 298.330112 -299.224954) (xy 298.329617 -299.249561)
			(xy 298.321722 -299.298138) (xy 298.306138 -299.344819) (xy 298.283267 -299.388396) (xy 298.253702 -299.42774)
			(xy 298.218209 -299.461832) (xy 298.177706 -299.489788) (xy 298.133244 -299.510886) (xy 298.085973 -299.524578)
			(xy 298.037118 -299.53051) (xy 297.987943 -299.528529) (xy 297.939724 -299.518685) (xy 297.893708 -299.501233)
			(xy 297.851087 -299.476626) (xy 297.812966 -299.445501) (xy 297.780331 -299.408664) (xy 297.754028 -299.367068)
			(xy 297.734737 -299.321792) (xy 297.72296 -299.274008) (xy 297.719 -299.224954) (xy 297.380152 -299.224954)
			(xy 297.379657 -299.249561) (xy 297.371762 -299.298138) (xy 297.356178 -299.344819) (xy 297.333307 -299.388396)
			(xy 297.303742 -299.42774) (xy 297.268249 -299.461832) (xy 297.227746 -299.489788) (xy 297.183284 -299.510886)
			(xy 297.136013 -299.524578) (xy 297.087158 -299.53051) (xy 297.037983 -299.528529) (xy 296.989764 -299.518685)
			(xy 296.943748 -299.501233) (xy 296.901127 -299.476626) (xy 296.863006 -299.445501) (xy 296.830371 -299.408664)
			(xy 296.804068 -299.367068) (xy 296.784777 -299.321792) (xy 296.773 -299.274008) (xy 296.76904 -299.224954)
			(xy 296.430192 -299.224954) (xy 296.429697 -299.249561) (xy 296.421802 -299.298138) (xy 296.406218 -299.344819)
			(xy 296.383347 -299.388396) (xy 296.353782 -299.42774) (xy 296.318289 -299.461832) (xy 296.277786 -299.489788)
			(xy 296.233324 -299.510886) (xy 296.186053 -299.524578) (xy 296.137198 -299.53051) (xy 296.088023 -299.528529)
			(xy 296.039804 -299.518685) (xy 295.993788 -299.501233) (xy 295.951167 -299.476626) (xy 295.913046 -299.445501)
			(xy 295.880411 -299.408664) (xy 295.854108 -299.367068) (xy 295.834817 -299.321792) (xy 295.82304 -299.274008)
			(xy 295.81908 -299.224954) (xy 295.480232 -299.224954) (xy 295.479737 -299.249561) (xy 295.471842 -299.298138)
			(xy 295.456258 -299.344819) (xy 295.433387 -299.388396) (xy 295.403822 -299.42774) (xy 295.368329 -299.461832)
			(xy 295.327826 -299.489788) (xy 295.283364 -299.510886) (xy 295.236093 -299.524578) (xy 295.187238 -299.53051)
			(xy 295.138063 -299.528529) (xy 295.089844 -299.518685) (xy 295.043828 -299.501233) (xy 295.001207 -299.476626)
			(xy 294.963086 -299.445501) (xy 294.930451 -299.408664) (xy 294.904148 -299.367068) (xy 294.884857 -299.321792)
			(xy 294.87308 -299.274008) (xy 294.86912 -299.224954) (xy 294.530018 -299.224954) (xy 294.529523 -299.249561)
			(xy 294.521628 -299.298138) (xy 294.506044 -299.344819) (xy 294.483173 -299.388396) (xy 294.453608 -299.42774)
			(xy 294.418115 -299.461832) (xy 294.377612 -299.489788) (xy 294.33315 -299.510886) (xy 294.285879 -299.524578)
			(xy 294.237024 -299.53051) (xy 294.187849 -299.528529) (xy 294.13963 -299.518685) (xy 294.093614 -299.501233)
			(xy 294.050993 -299.476626) (xy 294.012872 -299.445501) (xy 293.980237 -299.408664) (xy 293.953934 -299.367068)
			(xy 293.934643 -299.321792) (xy 293.922866 -299.274008) (xy 293.918906 -299.224954) (xy 293.580058 -299.224954)
			(xy 293.579563 -299.249561) (xy 293.571668 -299.298138) (xy 293.556084 -299.344819) (xy 293.533213 -299.388396)
			(xy 293.503648 -299.42774) (xy 293.468155 -299.461832) (xy 293.427652 -299.489788) (xy 293.38319 -299.510886)
			(xy 293.335919 -299.524578) (xy 293.287064 -299.53051) (xy 293.237889 -299.528529) (xy 293.18967 -299.518685)
			(xy 293.143654 -299.501233) (xy 293.101033 -299.476626) (xy 293.062912 -299.445501) (xy 293.030277 -299.408664)
			(xy 293.003974 -299.367068) (xy 292.984683 -299.321792) (xy 292.972906 -299.274008) (xy 292.968946 -299.224954)
			(xy 292.630098 -299.224954) (xy 292.629603 -299.249561) (xy 292.621708 -299.298138) (xy 292.606124 -299.344819)
			(xy 292.583253 -299.388396) (xy 292.553688 -299.42774) (xy 292.518195 -299.461832) (xy 292.477692 -299.489788)
			(xy 292.43323 -299.510886) (xy 292.385959 -299.524578) (xy 292.337104 -299.53051) (xy 292.287929 -299.528529)
			(xy 292.23971 -299.518685) (xy 292.193694 -299.501233) (xy 292.151073 -299.476626) (xy 292.112952 -299.445501)
			(xy 292.080317 -299.408664) (xy 292.054014 -299.367068) (xy 292.034723 -299.321792) (xy 292.022946 -299.274008)
			(xy 292.018986 -299.224954) (xy 290.730178 -299.224954) (xy 290.729683 -299.249561) (xy 290.721788 -299.298138)
			(xy 290.706204 -299.344819) (xy 290.683333 -299.388396) (xy 290.653768 -299.42774) (xy 290.618275 -299.461832)
			(xy 290.577772 -299.489788) (xy 290.53331 -299.510886) (xy 290.486039 -299.524578) (xy 290.437184 -299.53051)
			(xy 290.388009 -299.528529) (xy 290.33979 -299.518685) (xy 290.293774 -299.501233) (xy 290.251153 -299.476626)
			(xy 290.213032 -299.445501) (xy 290.180397 -299.408664) (xy 290.154094 -299.367068) (xy 290.134803 -299.321792)
			(xy 290.123026 -299.274008) (xy 290.119066 -299.224954) (xy 289.780218 -299.224954) (xy 289.779723 -299.249561)
			(xy 289.771828 -299.298138) (xy 289.756244 -299.344819) (xy 289.733373 -299.388396) (xy 289.703808 -299.42774)
			(xy 289.668315 -299.461832) (xy 289.627812 -299.489788) (xy 289.58335 -299.510886) (xy 289.536079 -299.524578)
			(xy 289.487224 -299.53051) (xy 289.438049 -299.528529) (xy 289.38983 -299.518685) (xy 289.343814 -299.501233)
			(xy 289.301193 -299.476626) (xy 289.263072 -299.445501) (xy 289.230437 -299.408664) (xy 289.204134 -299.367068)
			(xy 289.184843 -299.321792) (xy 289.173066 -299.274008) (xy 289.169106 -299.224954) (xy 288.830004 -299.224954)
			(xy 288.829509 -299.249561) (xy 288.821614 -299.298138) (xy 288.80603 -299.344819) (xy 288.783159 -299.388396)
			(xy 288.753594 -299.42774) (xy 288.718101 -299.461832) (xy 288.677598 -299.489788) (xy 288.633136 -299.510886)
			(xy 288.585865 -299.524578) (xy 288.53701 -299.53051) (xy 288.487835 -299.528529) (xy 288.439616 -299.518685)
			(xy 288.3936 -299.501233) (xy 288.350979 -299.476626) (xy 288.312858 -299.445501) (xy 288.280223 -299.408664)
			(xy 288.25392 -299.367068) (xy 288.234629 -299.321792) (xy 288.222852 -299.274008) (xy 288.218892 -299.224954)
			(xy 287.880044 -299.224954) (xy 287.879549 -299.249561) (xy 287.871654 -299.298138) (xy 287.85607 -299.344819)
			(xy 287.833199 -299.388396) (xy 287.803634 -299.42774) (xy 287.768141 -299.461832) (xy 287.727638 -299.489788)
			(xy 287.683176 -299.510886) (xy 287.635905 -299.524578) (xy 287.58705 -299.53051) (xy 287.537875 -299.528529)
			(xy 287.489656 -299.518685) (xy 287.44364 -299.501233) (xy 287.401019 -299.476626) (xy 287.362898 -299.445501)
			(xy 287.330263 -299.408664) (xy 287.30396 -299.367068) (xy 287.284669 -299.321792) (xy 287.272892 -299.274008)
			(xy 287.268932 -299.224954) (xy 286.930084 -299.224954) (xy 286.929589 -299.249561) (xy 286.921694 -299.298138)
			(xy 286.90611 -299.344819) (xy 286.883239 -299.388396) (xy 286.853674 -299.42774) (xy 286.818181 -299.461832)
			(xy 286.777678 -299.489788) (xy 286.733216 -299.510886) (xy 286.685945 -299.524578) (xy 286.63709 -299.53051)
			(xy 286.587915 -299.528529) (xy 286.539696 -299.518685) (xy 286.49368 -299.501233) (xy 286.451059 -299.476626)
			(xy 286.412938 -299.445501) (xy 286.380303 -299.408664) (xy 286.354 -299.367068) (xy 286.334709 -299.321792)
			(xy 286.322932 -299.274008) (xy 286.318972 -299.224954) (xy 285.980124 -299.224954) (xy 285.979629 -299.249561)
			(xy 285.971734 -299.298138) (xy 285.95615 -299.344819) (xy 285.933279 -299.388396) (xy 285.903714 -299.42774)
			(xy 285.868221 -299.461832) (xy 285.827718 -299.489788) (xy 285.783256 -299.510886) (xy 285.735985 -299.524578)
			(xy 285.68713 -299.53051) (xy 285.637955 -299.528529) (xy 285.589736 -299.518685) (xy 285.54372 -299.501233)
			(xy 285.501099 -299.476626) (xy 285.462978 -299.445501) (xy 285.430343 -299.408664) (xy 285.40404 -299.367068)
			(xy 285.384749 -299.321792) (xy 285.372972 -299.274008) (xy 285.369012 -299.224954) (xy 285.030164 -299.224954)
			(xy 285.029669 -299.249561) (xy 285.021774 -299.298138) (xy 285.00619 -299.344819) (xy 284.983319 -299.388396)
			(xy 284.953754 -299.42774) (xy 284.918261 -299.461832) (xy 284.877758 -299.489788) (xy 284.833296 -299.510886)
			(xy 284.786025 -299.524578) (xy 284.73717 -299.53051) (xy 284.687995 -299.528529) (xy 284.639776 -299.518685)
			(xy 284.59376 -299.501233) (xy 284.551139 -299.476626) (xy 284.513018 -299.445501) (xy 284.480383 -299.408664)
			(xy 284.45408 -299.367068) (xy 284.434789 -299.321792) (xy 284.423012 -299.274008) (xy 284.419052 -299.224954)
			(xy 284.080204 -299.224954) (xy 284.079709 -299.249561) (xy 284.071814 -299.298138) (xy 284.05623 -299.344819)
			(xy 284.033359 -299.388396) (xy 284.003794 -299.42774) (xy 283.968301 -299.461832) (xy 283.927798 -299.489788)
			(xy 283.883336 -299.510886) (xy 283.836065 -299.524578) (xy 283.78721 -299.53051) (xy 283.738035 -299.528529)
			(xy 283.689816 -299.518685) (xy 283.6438 -299.501233) (xy 283.601179 -299.476626) (xy 283.563058 -299.445501)
			(xy 283.530423 -299.408664) (xy 283.50412 -299.367068) (xy 283.484829 -299.321792) (xy 283.473052 -299.274008)
			(xy 283.469092 -299.224954) (xy 283.130244 -299.224954) (xy 283.129749 -299.249561) (xy 283.121854 -299.298138)
			(xy 283.10627 -299.344819) (xy 283.083399 -299.388396) (xy 283.053834 -299.42774) (xy 283.018341 -299.461832)
			(xy 282.977838 -299.489788) (xy 282.933376 -299.510886) (xy 282.886105 -299.524578) (xy 282.83725 -299.53051)
			(xy 282.788075 -299.528529) (xy 282.739856 -299.518685) (xy 282.69384 -299.501233) (xy 282.651219 -299.476626)
			(xy 282.613098 -299.445501) (xy 282.580463 -299.408664) (xy 282.55416 -299.367068) (xy 282.534869 -299.321792)
			(xy 282.523092 -299.274008) (xy 282.519132 -299.224954) (xy 282.180574 -299.224954) (xy 282.180578 -299.225)
			(xy 282.176406 -299.275343) (xy 282.164006 -299.324314) (xy 282.143715 -299.370575) (xy 282.116086 -299.412867)
			(xy 282.081874 -299.450034) (xy 282.042011 -299.481063) (xy 281.997584 -299.505108) (xy 281.949806 -299.521513)
			(xy 281.89998 -299.529831) (xy 281.874722 -299.530262) (xy 281.844648 -299.529569) (xy 281.785663 -299.517802)
			(xy 281.757628 -299.506894) (xy 281.745436 -299.501814) (xy 281.720544 -299.504354) (xy 281.639518 -299.558456)
			(xy 281.629454 -299.565972) (xy 281.617589 -299.588079) (xy 281.616912 -299.60062) (xy 281.616912 -299.76445)
			(xy 320.241674 -299.76445) (xy 320.245745 -299.708828) (xy 320.257871 -299.654391) (xy 320.277794 -299.6023)
			(xy 320.30509 -299.553665) (xy 320.339176 -299.509522) (xy 320.379325 -299.470813) (xy 320.424683 -299.438362)
			(xy 320.474283 -299.412861) (xy 320.527067 -299.394854) (xy 320.58191 -299.384724) (xy 320.637644 -299.382687)
			(xy 320.693081 -299.388787) (xy 320.747038 -299.402893) (xy 320.798367 -299.424705) (xy 320.845973 -299.453759)
			(xy 320.888841 -299.489434) (xy 320.926058 -299.530971) (xy 320.956831 -299.577484) (xy 320.980503 -299.627981)
			(xy 320.996571 -299.681388) (xy 321.004691 -299.736564) (xy 321.0052 -299.76445) (xy 321.004922 -299.77969)
			(xy 324.838312 -299.77969) (xy 324.842383 -299.724068) (xy 324.854509 -299.669631) (xy 324.874432 -299.61754)
			(xy 324.901728 -299.568905) (xy 324.935814 -299.524762) (xy 324.975963 -299.486053) (xy 325.021321 -299.453602)
			(xy 325.070921 -299.428101) (xy 325.123705 -299.410094) (xy 325.178548 -299.399964) (xy 325.234282 -299.397927)
			(xy 325.289719 -299.404027) (xy 325.343676 -299.418133) (xy 325.395005 -299.439945) (xy 325.442611 -299.468999)
			(xy 325.485479 -299.504674) (xy 325.522696 -299.546211) (xy 325.553469 -299.592724) (xy 325.577141 -299.643221)
			(xy 325.593209 -299.696628) (xy 325.601329 -299.751804) (xy 325.601838 -299.77969) (xy 325.601329 -299.807576)
			(xy 325.593209 -299.862752) (xy 325.577141 -299.916159) (xy 325.553469 -299.966656) (xy 325.522696 -300.013169)
			(xy 325.485479 -300.054706) (xy 325.442611 -300.090381) (xy 325.395005 -300.119435) (xy 325.343676 -300.141247)
			(xy 325.289719 -300.155353) (xy 325.234282 -300.161453) (xy 325.178548 -300.159416) (xy 325.123705 -300.149286)
			(xy 325.070921 -300.131279) (xy 325.021321 -300.105778) (xy 324.975963 -300.073327) (xy 324.935814 -300.034618)
			(xy 324.901728 -299.990475) (xy 324.874432 -299.94184) (xy 324.854509 -299.889749) (xy 324.842383 -299.835312)
			(xy 324.838312 -299.77969) (xy 321.004922 -299.77969) (xy 321.004691 -299.792336) (xy 320.996571 -299.847512)
			(xy 320.980503 -299.900919) (xy 320.956831 -299.951416) (xy 320.926058 -299.997929) (xy 320.888841 -300.039466)
			(xy 320.845973 -300.075141) (xy 320.798367 -300.104195) (xy 320.747038 -300.126007) (xy 320.693081 -300.140113)
			(xy 320.637644 -300.146213) (xy 320.58191 -300.144176) (xy 320.527067 -300.134046) (xy 320.474283 -300.116039)
			(xy 320.424683 -300.090538) (xy 320.379325 -300.058087) (xy 320.339176 -300.019378) (xy 320.30509 -299.975235)
			(xy 320.277794 -299.9266) (xy 320.257871 -299.874509) (xy 320.245745 -299.820072) (xy 320.241674 -299.76445)
			(xy 281.616912 -299.76445) (xy 281.616912 -300.174914) (xy 282.519132 -300.174914) (xy 282.523092 -300.12586)
			(xy 282.534869 -300.078076) (xy 282.55416 -300.0328) (xy 282.580463 -299.991204) (xy 282.613098 -299.954367)
			(xy 282.651219 -299.923242) (xy 282.69384 -299.898635) (xy 282.739856 -299.881183) (xy 282.788075 -299.871339)
			(xy 282.83725 -299.869358) (xy 282.886105 -299.87529) (xy 282.933376 -299.888982) (xy 282.977838 -299.91008)
			(xy 283.018341 -299.938036) (xy 283.053834 -299.972128) (xy 283.083399 -300.011472) (xy 283.10627 -300.055049)
			(xy 283.121854 -300.10173) (xy 283.129749 -300.150307) (xy 283.130244 -300.174914) (xy 283.469092 -300.174914)
			(xy 283.473052 -300.12586) (xy 283.484829 -300.078076) (xy 283.50412 -300.0328) (xy 283.530423 -299.991204)
			(xy 283.563058 -299.954367) (xy 283.601179 -299.923242) (xy 283.6438 -299.898635) (xy 283.689816 -299.881183)
			(xy 283.738035 -299.871339) (xy 283.78721 -299.869358) (xy 283.836065 -299.87529) (xy 283.883336 -299.888982)
			(xy 283.927798 -299.91008) (xy 283.968301 -299.938036) (xy 284.003794 -299.972128) (xy 284.033359 -300.011472)
			(xy 284.05623 -300.055049) (xy 284.071814 -300.10173) (xy 284.079709 -300.150307) (xy 284.080204 -300.174914)
			(xy 284.419052 -300.174914) (xy 284.423012 -300.12586) (xy 284.434789 -300.078076) (xy 284.45408 -300.0328)
			(xy 284.480383 -299.991204) (xy 284.513018 -299.954367) (xy 284.551139 -299.923242) (xy 284.59376 -299.898635)
			(xy 284.639776 -299.881183) (xy 284.687995 -299.871339) (xy 284.73717 -299.869358) (xy 284.786025 -299.87529)
			(xy 284.833296 -299.888982) (xy 284.877758 -299.91008) (xy 284.918261 -299.938036) (xy 284.953754 -299.972128)
			(xy 284.983319 -300.011472) (xy 285.00619 -300.055049) (xy 285.021774 -300.10173) (xy 285.029669 -300.150307)
			(xy 285.030164 -300.174914) (xy 285.369012 -300.174914) (xy 285.372972 -300.12586) (xy 285.384749 -300.078076)
			(xy 285.40404 -300.0328) (xy 285.430343 -299.991204) (xy 285.462978 -299.954367) (xy 285.501099 -299.923242)
			(xy 285.54372 -299.898635) (xy 285.589736 -299.881183) (xy 285.637955 -299.871339) (xy 285.68713 -299.869358)
			(xy 285.735985 -299.87529) (xy 285.783256 -299.888982) (xy 285.827718 -299.91008) (xy 285.868221 -299.938036)
			(xy 285.903714 -299.972128) (xy 285.933279 -300.011472) (xy 285.95615 -300.055049) (xy 285.971734 -300.10173)
			(xy 285.979629 -300.150307) (xy 285.980124 -300.174914) (xy 286.318972 -300.174914) (xy 286.322932 -300.12586)
			(xy 286.334709 -300.078076) (xy 286.354 -300.0328) (xy 286.380303 -299.991204) (xy 286.412938 -299.954367)
			(xy 286.451059 -299.923242) (xy 286.49368 -299.898635) (xy 286.539696 -299.881183) (xy 286.587915 -299.871339)
			(xy 286.63709 -299.869358) (xy 286.685945 -299.87529) (xy 286.733216 -299.888982) (xy 286.777678 -299.91008)
			(xy 286.818181 -299.938036) (xy 286.853674 -299.972128) (xy 286.883239 -300.011472) (xy 286.90611 -300.055049)
			(xy 286.921694 -300.10173) (xy 286.929589 -300.150307) (xy 286.930084 -300.174914) (xy 287.268932 -300.174914)
			(xy 287.272892 -300.12586) (xy 287.284669 -300.078076) (xy 287.30396 -300.0328) (xy 287.330263 -299.991204)
			(xy 287.362898 -299.954367) (xy 287.401019 -299.923242) (xy 287.44364 -299.898635) (xy 287.489656 -299.881183)
			(xy 287.537875 -299.871339) (xy 287.58705 -299.869358) (xy 287.635905 -299.87529) (xy 287.683176 -299.888982)
			(xy 287.727638 -299.91008) (xy 287.768141 -299.938036) (xy 287.803634 -299.972128) (xy 287.833199 -300.011472)
			(xy 287.85607 -300.055049) (xy 287.871654 -300.10173) (xy 287.879549 -300.150307) (xy 287.880044 -300.174914)
			(xy 288.218892 -300.174914) (xy 288.222852 -300.12586) (xy 288.234629 -300.078076) (xy 288.25392 -300.0328)
			(xy 288.280223 -299.991204) (xy 288.312858 -299.954367) (xy 288.350979 -299.923242) (xy 288.3936 -299.898635)
			(xy 288.439616 -299.881183) (xy 288.487835 -299.871339) (xy 288.53701 -299.869358) (xy 288.585865 -299.87529)
			(xy 288.633136 -299.888982) (xy 288.677598 -299.91008) (xy 288.718101 -299.938036) (xy 288.753594 -299.972128)
			(xy 288.783159 -300.011472) (xy 288.80603 -300.055049) (xy 288.821614 -300.10173) (xy 288.829509 -300.150307)
			(xy 288.830004 -300.174914) (xy 289.169106 -300.174914) (xy 289.173066 -300.12586) (xy 289.184843 -300.078076)
			(xy 289.204134 -300.0328) (xy 289.230437 -299.991204) (xy 289.263072 -299.954367) (xy 289.301193 -299.923242)
			(xy 289.343814 -299.898635) (xy 289.38983 -299.881183) (xy 289.438049 -299.871339) (xy 289.487224 -299.869358)
			(xy 289.536079 -299.87529) (xy 289.58335 -299.888982) (xy 289.627812 -299.91008) (xy 289.668315 -299.938036)
			(xy 289.703808 -299.972128) (xy 289.733373 -300.011472) (xy 289.756244 -300.055049) (xy 289.771828 -300.10173)
			(xy 289.779723 -300.150307) (xy 289.780218 -300.174914) (xy 290.119066 -300.174914) (xy 290.123026 -300.12586)
			(xy 290.134803 -300.078076) (xy 290.154094 -300.0328) (xy 290.180397 -299.991204) (xy 290.213032 -299.954367)
			(xy 290.251153 -299.923242) (xy 290.293774 -299.898635) (xy 290.33979 -299.881183) (xy 290.388009 -299.871339)
			(xy 290.437184 -299.869358) (xy 290.486039 -299.87529) (xy 290.53331 -299.888982) (xy 290.577772 -299.91008)
			(xy 290.618275 -299.938036) (xy 290.653768 -299.972128) (xy 290.683333 -300.011472) (xy 290.706204 -300.055049)
			(xy 290.721788 -300.10173) (xy 290.729683 -300.150307) (xy 290.730178 -300.174914) (xy 292.018986 -300.174914)
			(xy 292.022946 -300.12586) (xy 292.034723 -300.078076) (xy 292.054014 -300.0328) (xy 292.080317 -299.991204)
			(xy 292.112952 -299.954367) (xy 292.151073 -299.923242) (xy 292.193694 -299.898635) (xy 292.23971 -299.881183)
			(xy 292.287929 -299.871339) (xy 292.337104 -299.869358) (xy 292.385959 -299.87529) (xy 292.43323 -299.888982)
			(xy 292.477692 -299.91008) (xy 292.518195 -299.938036) (xy 292.553688 -299.972128) (xy 292.583253 -300.011472)
			(xy 292.606124 -300.055049) (xy 292.621708 -300.10173) (xy 292.629603 -300.150307) (xy 292.630098 -300.174914)
			(xy 292.968946 -300.174914) (xy 292.972906 -300.12586) (xy 292.984683 -300.078076) (xy 293.003974 -300.0328)
			(xy 293.030277 -299.991204) (xy 293.062912 -299.954367) (xy 293.101033 -299.923242) (xy 293.143654 -299.898635)
			(xy 293.18967 -299.881183) (xy 293.237889 -299.871339) (xy 293.287064 -299.869358) (xy 293.335919 -299.87529)
			(xy 293.38319 -299.888982) (xy 293.427652 -299.91008) (xy 293.468155 -299.938036) (xy 293.503648 -299.972128)
			(xy 293.533213 -300.011472) (xy 293.556084 -300.055049) (xy 293.571668 -300.10173) (xy 293.579563 -300.150307)
			(xy 293.580058 -300.174914) (xy 293.918906 -300.174914) (xy 293.922866 -300.12586) (xy 293.934643 -300.078076)
			(xy 293.953934 -300.0328) (xy 293.980237 -299.991204) (xy 294.012872 -299.954367) (xy 294.050993 -299.923242)
			(xy 294.093614 -299.898635) (xy 294.13963 -299.881183) (xy 294.187849 -299.871339) (xy 294.237024 -299.869358)
			(xy 294.285879 -299.87529) (xy 294.33315 -299.888982) (xy 294.377612 -299.91008) (xy 294.418115 -299.938036)
			(xy 294.453608 -299.972128) (xy 294.483173 -300.011472) (xy 294.506044 -300.055049) (xy 294.521628 -300.10173)
			(xy 294.529523 -300.150307) (xy 294.530018 -300.174914) (xy 294.86912 -300.174914) (xy 294.87308 -300.12586)
			(xy 294.884857 -300.078076) (xy 294.904148 -300.0328) (xy 294.930451 -299.991204) (xy 294.963086 -299.954367)
			(xy 295.001207 -299.923242) (xy 295.043828 -299.898635) (xy 295.089844 -299.881183) (xy 295.138063 -299.871339)
			(xy 295.187238 -299.869358) (xy 295.236093 -299.87529) (xy 295.283364 -299.888982) (xy 295.327826 -299.91008)
			(xy 295.368329 -299.938036) (xy 295.403822 -299.972128) (xy 295.433387 -300.011472) (xy 295.456258 -300.055049)
			(xy 295.471842 -300.10173) (xy 295.479737 -300.150307) (xy 295.480232 -300.174914) (xy 295.81908 -300.174914)
			(xy 295.82304 -300.12586) (xy 295.834817 -300.078076) (xy 295.854108 -300.0328) (xy 295.880411 -299.991204)
			(xy 295.913046 -299.954367) (xy 295.951167 -299.923242) (xy 295.993788 -299.898635) (xy 296.039804 -299.881183)
			(xy 296.088023 -299.871339) (xy 296.137198 -299.869358) (xy 296.186053 -299.87529) (xy 296.233324 -299.888982)
			(xy 296.277786 -299.91008) (xy 296.318289 -299.938036) (xy 296.353782 -299.972128) (xy 296.383347 -300.011472)
			(xy 296.406218 -300.055049) (xy 296.421802 -300.10173) (xy 296.429697 -300.150307) (xy 296.430192 -300.174914)
			(xy 296.76904 -300.174914) (xy 296.773 -300.12586) (xy 296.784777 -300.078076) (xy 296.804068 -300.0328)
			(xy 296.830371 -299.991204) (xy 296.863006 -299.954367) (xy 296.901127 -299.923242) (xy 296.943748 -299.898635)
			(xy 296.989764 -299.881183) (xy 297.037983 -299.871339) (xy 297.087158 -299.869358) (xy 297.136013 -299.87529)
			(xy 297.183284 -299.888982) (xy 297.227746 -299.91008) (xy 297.268249 -299.938036) (xy 297.303742 -299.972128)
			(xy 297.333307 -300.011472) (xy 297.356178 -300.055049) (xy 297.371762 -300.10173) (xy 297.379657 -300.150307)
			(xy 297.380152 -300.174914) (xy 297.719 -300.174914) (xy 297.72296 -300.12586) (xy 297.734737 -300.078076)
			(xy 297.754028 -300.0328) (xy 297.780331 -299.991204) (xy 297.812966 -299.954367) (xy 297.851087 -299.923242)
			(xy 297.893708 -299.898635) (xy 297.939724 -299.881183) (xy 297.987943 -299.871339) (xy 298.037118 -299.869358)
			(xy 298.085973 -299.87529) (xy 298.133244 -299.888982) (xy 298.177706 -299.91008) (xy 298.218209 -299.938036)
			(xy 298.253702 -299.972128) (xy 298.283267 -300.011472) (xy 298.306138 -300.055049) (xy 298.321722 -300.10173)
			(xy 298.329617 -300.150307) (xy 298.330112 -300.174914) (xy 298.66896 -300.174914) (xy 298.67292 -300.12586)
			(xy 298.684697 -300.078076) (xy 298.703988 -300.0328) (xy 298.730291 -299.991204) (xy 298.762926 -299.954367)
			(xy 298.801047 -299.923242) (xy 298.843668 -299.898635) (xy 298.889684 -299.881183) (xy 298.937903 -299.871339)
			(xy 298.987078 -299.869358) (xy 299.035933 -299.87529) (xy 299.083204 -299.888982) (xy 299.127666 -299.91008)
			(xy 299.168169 -299.938036) (xy 299.203662 -299.972128) (xy 299.233227 -300.011472) (xy 299.256098 -300.055049)
			(xy 299.271682 -300.10173) (xy 299.279577 -300.150307) (xy 299.280072 -300.174914) (xy 299.61892 -300.174914)
			(xy 299.62288 -300.12586) (xy 299.634657 -300.078076) (xy 299.653948 -300.0328) (xy 299.680251 -299.991204)
			(xy 299.712886 -299.954367) (xy 299.751007 -299.923242) (xy 299.793628 -299.898635) (xy 299.839644 -299.881183)
			(xy 299.887863 -299.871339) (xy 299.937038 -299.869358) (xy 299.985893 -299.87529) (xy 300.033164 -299.888982)
			(xy 300.077626 -299.91008) (xy 300.118129 -299.938036) (xy 300.153622 -299.972128) (xy 300.183187 -300.011472)
			(xy 300.206058 -300.055049) (xy 300.221642 -300.10173) (xy 300.229537 -300.150307) (xy 300.230032 -300.174914)
			(xy 300.56888 -300.174914) (xy 300.57284 -300.12586) (xy 300.584617 -300.078076) (xy 300.603908 -300.0328)
			(xy 300.630211 -299.991204) (xy 300.662846 -299.954367) (xy 300.700967 -299.923242) (xy 300.743588 -299.898635)
			(xy 300.789604 -299.881183) (xy 300.837823 -299.871339) (xy 300.886998 -299.869358) (xy 300.935853 -299.87529)
			(xy 300.983124 -299.888982) (xy 301.027586 -299.91008) (xy 301.068089 -299.938036) (xy 301.103582 -299.972128)
			(xy 301.133147 -300.011472) (xy 301.156018 -300.055049) (xy 301.171602 -300.10173) (xy 301.179497 -300.150307)
			(xy 301.179992 -300.174914) (xy 301.519094 -300.174914) (xy 301.523054 -300.12586) (xy 301.534831 -300.078076)
			(xy 301.554122 -300.0328) (xy 301.580425 -299.991204) (xy 301.61306 -299.954367) (xy 301.651181 -299.923242)
			(xy 301.693802 -299.898635) (xy 301.739818 -299.881183) (xy 301.788037 -299.871339) (xy 301.837212 -299.869358)
			(xy 301.886067 -299.87529) (xy 301.933338 -299.888982) (xy 301.9778 -299.91008) (xy 302.018303 -299.938036)
			(xy 302.053796 -299.972128) (xy 302.083361 -300.011472) (xy 302.106232 -300.055049) (xy 302.121816 -300.10173)
			(xy 302.129711 -300.150307) (xy 302.130206 -300.174914) (xy 302.469054 -300.174914) (xy 302.473014 -300.12586)
			(xy 302.484791 -300.078076) (xy 302.504082 -300.0328) (xy 302.530385 -299.991204) (xy 302.56302 -299.954367)
			(xy 302.601141 -299.923242) (xy 302.643762 -299.898635) (xy 302.689778 -299.881183) (xy 302.737997 -299.871339)
			(xy 302.787172 -299.869358) (xy 302.836027 -299.87529) (xy 302.883298 -299.888982) (xy 302.92776 -299.91008)
			(xy 302.968263 -299.938036) (xy 303.003756 -299.972128) (xy 303.033321 -300.011472) (xy 303.056192 -300.055049)
			(xy 303.071776 -300.10173) (xy 303.079671 -300.150307) (xy 303.080166 -300.174914) (xy 303.419014 -300.174914)
			(xy 303.422974 -300.12586) (xy 303.434751 -300.078076) (xy 303.454042 -300.0328) (xy 303.480345 -299.991204)
			(xy 303.51298 -299.954367) (xy 303.551101 -299.923242) (xy 303.593722 -299.898635) (xy 303.639738 -299.881183)
			(xy 303.687957 -299.871339) (xy 303.737132 -299.869358) (xy 303.785987 -299.87529) (xy 303.833258 -299.888982)
			(xy 303.87772 -299.91008) (xy 303.918223 -299.938036) (xy 303.953716 -299.972128) (xy 303.983281 -300.011472)
			(xy 304.006152 -300.055049) (xy 304.021736 -300.10173) (xy 304.029631 -300.150307) (xy 304.030126 -300.174914)
			(xy 304.368974 -300.174914) (xy 304.372934 -300.12586) (xy 304.384711 -300.078076) (xy 304.404002 -300.0328)
			(xy 304.430305 -299.991204) (xy 304.46294 -299.954367) (xy 304.501061 -299.923242) (xy 304.543682 -299.898635)
			(xy 304.589698 -299.881183) (xy 304.637917 -299.871339) (xy 304.687092 -299.869358) (xy 304.735947 -299.87529)
			(xy 304.783218 -299.888982) (xy 304.82768 -299.91008) (xy 304.868183 -299.938036) (xy 304.903676 -299.972128)
			(xy 304.933241 -300.011472) (xy 304.956112 -300.055049) (xy 304.971696 -300.10173) (xy 304.979591 -300.150307)
			(xy 304.980086 -300.174914) (xy 305.318934 -300.174914) (xy 305.322894 -300.12586) (xy 305.334671 -300.078076)
			(xy 305.353962 -300.0328) (xy 305.380265 -299.991204) (xy 305.4129 -299.954367) (xy 305.451021 -299.923242)
			(xy 305.493642 -299.898635) (xy 305.539658 -299.881183) (xy 305.587877 -299.871339) (xy 305.637052 -299.869358)
			(xy 305.685907 -299.87529) (xy 305.733178 -299.888982) (xy 305.77764 -299.91008) (xy 305.818143 -299.938036)
			(xy 305.853636 -299.972128) (xy 305.883201 -300.011472) (xy 305.906072 -300.055049) (xy 305.921656 -300.10173)
			(xy 305.929551 -300.150307) (xy 305.930046 -300.174914) (xy 306.268894 -300.174914) (xy 306.272854 -300.12586)
			(xy 306.284631 -300.078076) (xy 306.303922 -300.0328) (xy 306.330225 -299.991204) (xy 306.36286 -299.954367)
			(xy 306.400981 -299.923242) (xy 306.443602 -299.898635) (xy 306.489618 -299.881183) (xy 306.537837 -299.871339)
			(xy 306.587012 -299.869358) (xy 306.635867 -299.87529) (xy 306.683138 -299.888982) (xy 306.7276 -299.91008)
			(xy 306.768103 -299.938036) (xy 306.803596 -299.972128) (xy 306.833161 -300.011472) (xy 306.856032 -300.055049)
			(xy 306.871616 -300.10173) (xy 306.879511 -300.150307) (xy 306.880006 -300.174914) (xy 307.219108 -300.174914)
			(xy 307.223068 -300.12586) (xy 307.234845 -300.078076) (xy 307.254136 -300.0328) (xy 307.280439 -299.991204)
			(xy 307.313074 -299.954367) (xy 307.351195 -299.923242) (xy 307.393816 -299.898635) (xy 307.439832 -299.881183)
			(xy 307.488051 -299.871339) (xy 307.537226 -299.869358) (xy 307.586081 -299.87529) (xy 307.633352 -299.888982)
			(xy 307.677814 -299.91008) (xy 307.718317 -299.938036) (xy 307.75381 -299.972128) (xy 307.783375 -300.011472)
			(xy 307.806246 -300.055049) (xy 307.82183 -300.10173) (xy 307.829725 -300.150307) (xy 307.83022 -300.174914)
			(xy 308.169068 -300.174914) (xy 308.173028 -300.12586) (xy 308.184805 -300.078076) (xy 308.204096 -300.0328)
			(xy 308.230399 -299.991204) (xy 308.263034 -299.954367) (xy 308.301155 -299.923242) (xy 308.343776 -299.898635)
			(xy 308.389792 -299.881183) (xy 308.438011 -299.871339) (xy 308.487186 -299.869358) (xy 308.536041 -299.87529)
			(xy 308.583312 -299.888982) (xy 308.627774 -299.91008) (xy 308.668277 -299.938036) (xy 308.70377 -299.972128)
			(xy 308.733335 -300.011472) (xy 308.756206 -300.055049) (xy 308.77179 -300.10173) (xy 308.779685 -300.150307)
			(xy 308.78018 -300.174914) (xy 309.119028 -300.174914) (xy 309.122988 -300.12586) (xy 309.134765 -300.078076)
			(xy 309.154056 -300.0328) (xy 309.180359 -299.991204) (xy 309.212994 -299.954367) (xy 309.251115 -299.923242)
			(xy 309.293736 -299.898635) (xy 309.339752 -299.881183) (xy 309.387971 -299.871339) (xy 309.437146 -299.869358)
			(xy 309.486001 -299.87529) (xy 309.533272 -299.888982) (xy 309.577734 -299.91008) (xy 309.618237 -299.938036)
			(xy 309.65373 -299.972128) (xy 309.683295 -300.011472) (xy 309.706166 -300.055049) (xy 309.72175 -300.10173)
			(xy 309.729645 -300.150307) (xy 309.73014 -300.174914) (xy 310.068988 -300.174914) (xy 310.072948 -300.12586)
			(xy 310.084725 -300.078076) (xy 310.104016 -300.0328) (xy 310.130319 -299.991204) (xy 310.162954 -299.954367)
			(xy 310.201075 -299.923242) (xy 310.243696 -299.898635) (xy 310.289712 -299.881183) (xy 310.337931 -299.871339)
			(xy 310.387106 -299.869358) (xy 310.435961 -299.87529) (xy 310.483232 -299.888982) (xy 310.527694 -299.91008)
			(xy 310.568197 -299.938036) (xy 310.60369 -299.972128) (xy 310.633255 -300.011472) (xy 310.656126 -300.055049)
			(xy 310.67171 -300.10173) (xy 310.679605 -300.150307) (xy 310.6801 -300.174914) (xy 311.018948 -300.174914)
			(xy 311.022908 -300.12586) (xy 311.034685 -300.078076) (xy 311.053976 -300.0328) (xy 311.080279 -299.991204)
			(xy 311.112914 -299.954367) (xy 311.151035 -299.923242) (xy 311.193656 -299.898635) (xy 311.239672 -299.881183)
			(xy 311.287891 -299.871339) (xy 311.337066 -299.869358) (xy 311.385921 -299.87529) (xy 311.433192 -299.888982)
			(xy 311.477654 -299.91008) (xy 311.518157 -299.938036) (xy 311.55365 -299.972128) (xy 311.583215 -300.011472)
			(xy 311.606086 -300.055049) (xy 311.62167 -300.10173) (xy 311.629565 -300.150307) (xy 311.63006 -300.174914)
			(xy 311.968908 -300.174914) (xy 311.972868 -300.12586) (xy 311.984645 -300.078076) (xy 312.003936 -300.0328)
			(xy 312.030239 -299.991204) (xy 312.062874 -299.954367) (xy 312.100995 -299.923242) (xy 312.143616 -299.898635)
			(xy 312.189632 -299.881183) (xy 312.237851 -299.871339) (xy 312.287026 -299.869358) (xy 312.335881 -299.87529)
			(xy 312.383152 -299.888982) (xy 312.427614 -299.91008) (xy 312.468117 -299.938036) (xy 312.50361 -299.972128)
			(xy 312.533175 -300.011472) (xy 312.556046 -300.055049) (xy 312.57163 -300.10173) (xy 312.579525 -300.150307)
			(xy 312.58002 -300.174914) (xy 312.919122 -300.174914) (xy 312.923082 -300.12586) (xy 312.934859 -300.078076)
			(xy 312.95415 -300.0328) (xy 312.980453 -299.991204) (xy 313.013088 -299.954367) (xy 313.051209 -299.923242)
			(xy 313.09383 -299.898635) (xy 313.139846 -299.881183) (xy 313.188065 -299.871339) (xy 313.23724 -299.869358)
			(xy 313.286095 -299.87529) (xy 313.333366 -299.888982) (xy 313.377828 -299.91008) (xy 313.418331 -299.938036)
			(xy 313.453824 -299.972128) (xy 313.483389 -300.011472) (xy 313.50626 -300.055049) (xy 313.521844 -300.10173)
			(xy 313.529739 -300.150307) (xy 313.530234 -300.174914) (xy 313.869082 -300.174914) (xy 313.873042 -300.12586)
			(xy 313.884819 -300.078076) (xy 313.90411 -300.0328) (xy 313.930413 -299.991204) (xy 313.963048 -299.954367)
			(xy 314.001169 -299.923242) (xy 314.04379 -299.898635) (xy 314.089806 -299.881183) (xy 314.138025 -299.871339)
			(xy 314.1872 -299.869358) (xy 314.236055 -299.87529) (xy 314.283326 -299.888982) (xy 314.327788 -299.91008)
			(xy 314.368291 -299.938036) (xy 314.403784 -299.972128) (xy 314.433349 -300.011472) (xy 314.45622 -300.055049)
			(xy 314.471804 -300.10173) (xy 314.479699 -300.150307) (xy 314.480194 -300.174914) (xy 314.819042 -300.174914)
			(xy 314.823002 -300.12586) (xy 314.834779 -300.078076) (xy 314.85407 -300.0328) (xy 314.880373 -299.991204)
			(xy 314.913008 -299.954367) (xy 314.951129 -299.923242) (xy 314.99375 -299.898635) (xy 315.039766 -299.881183)
			(xy 315.087985 -299.871339) (xy 315.13716 -299.869358) (xy 315.186015 -299.87529) (xy 315.233286 -299.888982)
			(xy 315.277748 -299.91008) (xy 315.318251 -299.938036) (xy 315.353744 -299.972128) (xy 315.383309 -300.011472)
			(xy 315.40618 -300.055049) (xy 315.421764 -300.10173) (xy 315.429659 -300.150307) (xy 315.430154 -300.174914)
			(xy 315.429659 -300.199521) (xy 315.421764 -300.248098) (xy 315.40618 -300.294779) (xy 315.383309 -300.338356)
			(xy 315.353744 -300.3777) (xy 315.318251 -300.411792) (xy 315.277748 -300.439748) (xy 315.233286 -300.460846)
			(xy 315.186015 -300.474538) (xy 315.13716 -300.48047) (xy 315.087985 -300.478489) (xy 315.039766 -300.468645)
			(xy 314.99375 -300.451193) (xy 314.951129 -300.426586) (xy 314.913008 -300.395461) (xy 314.880373 -300.358624)
			(xy 314.85407 -300.317028) (xy 314.834779 -300.271752) (xy 314.823002 -300.223968) (xy 314.819042 -300.174914)
			(xy 314.480194 -300.174914) (xy 314.479699 -300.199521) (xy 314.471804 -300.248098) (xy 314.45622 -300.294779)
			(xy 314.433349 -300.338356) (xy 314.403784 -300.3777) (xy 314.368291 -300.411792) (xy 314.327788 -300.439748)
			(xy 314.283326 -300.460846) (xy 314.236055 -300.474538) (xy 314.1872 -300.48047) (xy 314.138025 -300.478489)
			(xy 314.089806 -300.468645) (xy 314.04379 -300.451193) (xy 314.001169 -300.426586) (xy 313.963048 -300.395461)
			(xy 313.930413 -300.358624) (xy 313.90411 -300.317028) (xy 313.884819 -300.271752) (xy 313.873042 -300.223968)
			(xy 313.869082 -300.174914) (xy 313.530234 -300.174914) (xy 313.529739 -300.199521) (xy 313.521844 -300.248098)
			(xy 313.50626 -300.294779) (xy 313.483389 -300.338356) (xy 313.453824 -300.3777) (xy 313.418331 -300.411792)
			(xy 313.377828 -300.439748) (xy 313.333366 -300.460846) (xy 313.286095 -300.474538) (xy 313.23724 -300.48047)
			(xy 313.188065 -300.478489) (xy 313.139846 -300.468645) (xy 313.09383 -300.451193) (xy 313.051209 -300.426586)
			(xy 313.013088 -300.395461) (xy 312.980453 -300.358624) (xy 312.95415 -300.317028) (xy 312.934859 -300.271752)
			(xy 312.923082 -300.223968) (xy 312.919122 -300.174914) (xy 312.58002 -300.174914) (xy 312.579525 -300.199521)
			(xy 312.57163 -300.248098) (xy 312.556046 -300.294779) (xy 312.533175 -300.338356) (xy 312.50361 -300.3777)
			(xy 312.468117 -300.411792) (xy 312.427614 -300.439748) (xy 312.383152 -300.460846) (xy 312.335881 -300.474538)
			(xy 312.287026 -300.48047) (xy 312.237851 -300.478489) (xy 312.189632 -300.468645) (xy 312.143616 -300.451193)
			(xy 312.100995 -300.426586) (xy 312.062874 -300.395461) (xy 312.030239 -300.358624) (xy 312.003936 -300.317028)
			(xy 311.984645 -300.271752) (xy 311.972868 -300.223968) (xy 311.968908 -300.174914) (xy 311.63006 -300.174914)
			(xy 311.629565 -300.199521) (xy 311.62167 -300.248098) (xy 311.606086 -300.294779) (xy 311.583215 -300.338356)
			(xy 311.55365 -300.3777) (xy 311.518157 -300.411792) (xy 311.477654 -300.439748) (xy 311.433192 -300.460846)
			(xy 311.385921 -300.474538) (xy 311.337066 -300.48047) (xy 311.287891 -300.478489) (xy 311.239672 -300.468645)
			(xy 311.193656 -300.451193) (xy 311.151035 -300.426586) (xy 311.112914 -300.395461) (xy 311.080279 -300.358624)
			(xy 311.053976 -300.317028) (xy 311.034685 -300.271752) (xy 311.022908 -300.223968) (xy 311.018948 -300.174914)
			(xy 310.6801 -300.174914) (xy 310.679605 -300.199521) (xy 310.67171 -300.248098) (xy 310.656126 -300.294779)
			(xy 310.633255 -300.338356) (xy 310.60369 -300.3777) (xy 310.568197 -300.411792) (xy 310.527694 -300.439748)
			(xy 310.483232 -300.460846) (xy 310.435961 -300.474538) (xy 310.387106 -300.48047) (xy 310.337931 -300.478489)
			(xy 310.289712 -300.468645) (xy 310.243696 -300.451193) (xy 310.201075 -300.426586) (xy 310.162954 -300.395461)
			(xy 310.130319 -300.358624) (xy 310.104016 -300.317028) (xy 310.084725 -300.271752) (xy 310.072948 -300.223968)
			(xy 310.068988 -300.174914) (xy 309.73014 -300.174914) (xy 309.729645 -300.199521) (xy 309.72175 -300.248098)
			(xy 309.706166 -300.294779) (xy 309.683295 -300.338356) (xy 309.65373 -300.3777) (xy 309.618237 -300.411792)
			(xy 309.577734 -300.439748) (xy 309.533272 -300.460846) (xy 309.486001 -300.474538) (xy 309.437146 -300.48047)
			(xy 309.387971 -300.478489) (xy 309.339752 -300.468645) (xy 309.293736 -300.451193) (xy 309.251115 -300.426586)
			(xy 309.212994 -300.395461) (xy 309.180359 -300.358624) (xy 309.154056 -300.317028) (xy 309.134765 -300.271752)
			(xy 309.122988 -300.223968) (xy 309.119028 -300.174914) (xy 308.78018 -300.174914) (xy 308.779685 -300.199521)
			(xy 308.77179 -300.248098) (xy 308.756206 -300.294779) (xy 308.733335 -300.338356) (xy 308.70377 -300.3777)
			(xy 308.668277 -300.411792) (xy 308.627774 -300.439748) (xy 308.583312 -300.460846) (xy 308.536041 -300.474538)
			(xy 308.487186 -300.48047) (xy 308.438011 -300.478489) (xy 308.389792 -300.468645) (xy 308.343776 -300.451193)
			(xy 308.301155 -300.426586) (xy 308.263034 -300.395461) (xy 308.230399 -300.358624) (xy 308.204096 -300.317028)
			(xy 308.184805 -300.271752) (xy 308.173028 -300.223968) (xy 308.169068 -300.174914) (xy 307.83022 -300.174914)
			(xy 307.829725 -300.199521) (xy 307.82183 -300.248098) (xy 307.806246 -300.294779) (xy 307.783375 -300.338356)
			(xy 307.75381 -300.3777) (xy 307.718317 -300.411792) (xy 307.677814 -300.439748) (xy 307.633352 -300.460846)
			(xy 307.586081 -300.474538) (xy 307.537226 -300.48047) (xy 307.488051 -300.478489) (xy 307.439832 -300.468645)
			(xy 307.393816 -300.451193) (xy 307.351195 -300.426586) (xy 307.313074 -300.395461) (xy 307.280439 -300.358624)
			(xy 307.254136 -300.317028) (xy 307.234845 -300.271752) (xy 307.223068 -300.223968) (xy 307.219108 -300.174914)
			(xy 306.880006 -300.174914) (xy 306.879511 -300.199521) (xy 306.871616 -300.248098) (xy 306.856032 -300.294779)
			(xy 306.833161 -300.338356) (xy 306.803596 -300.3777) (xy 306.768103 -300.411792) (xy 306.7276 -300.439748)
			(xy 306.683138 -300.460846) (xy 306.635867 -300.474538) (xy 306.587012 -300.48047) (xy 306.537837 -300.478489)
			(xy 306.489618 -300.468645) (xy 306.443602 -300.451193) (xy 306.400981 -300.426586) (xy 306.36286 -300.395461)
			(xy 306.330225 -300.358624) (xy 306.303922 -300.317028) (xy 306.284631 -300.271752) (xy 306.272854 -300.223968)
			(xy 306.268894 -300.174914) (xy 305.930046 -300.174914) (xy 305.929551 -300.199521) (xy 305.921656 -300.248098)
			(xy 305.906072 -300.294779) (xy 305.883201 -300.338356) (xy 305.853636 -300.3777) (xy 305.818143 -300.411792)
			(xy 305.77764 -300.439748) (xy 305.733178 -300.460846) (xy 305.685907 -300.474538) (xy 305.637052 -300.48047)
			(xy 305.587877 -300.478489) (xy 305.539658 -300.468645) (xy 305.493642 -300.451193) (xy 305.451021 -300.426586)
			(xy 305.4129 -300.395461) (xy 305.380265 -300.358624) (xy 305.353962 -300.317028) (xy 305.334671 -300.271752)
			(xy 305.322894 -300.223968) (xy 305.318934 -300.174914) (xy 304.980086 -300.174914) (xy 304.979591 -300.199521)
			(xy 304.971696 -300.248098) (xy 304.956112 -300.294779) (xy 304.933241 -300.338356) (xy 304.903676 -300.3777)
			(xy 304.868183 -300.411792) (xy 304.82768 -300.439748) (xy 304.783218 -300.460846) (xy 304.735947 -300.474538)
			(xy 304.687092 -300.48047) (xy 304.637917 -300.478489) (xy 304.589698 -300.468645) (xy 304.543682 -300.451193)
			(xy 304.501061 -300.426586) (xy 304.46294 -300.395461) (xy 304.430305 -300.358624) (xy 304.404002 -300.317028)
			(xy 304.384711 -300.271752) (xy 304.372934 -300.223968) (xy 304.368974 -300.174914) (xy 304.030126 -300.174914)
			(xy 304.029631 -300.199521) (xy 304.021736 -300.248098) (xy 304.006152 -300.294779) (xy 303.983281 -300.338356)
			(xy 303.953716 -300.3777) (xy 303.918223 -300.411792) (xy 303.87772 -300.439748) (xy 303.833258 -300.460846)
			(xy 303.785987 -300.474538) (xy 303.737132 -300.48047) (xy 303.687957 -300.478489) (xy 303.639738 -300.468645)
			(xy 303.593722 -300.451193) (xy 303.551101 -300.426586) (xy 303.51298 -300.395461) (xy 303.480345 -300.358624)
			(xy 303.454042 -300.317028) (xy 303.434751 -300.271752) (xy 303.422974 -300.223968) (xy 303.419014 -300.174914)
			(xy 303.080166 -300.174914) (xy 303.079671 -300.199521) (xy 303.071776 -300.248098) (xy 303.056192 -300.294779)
			(xy 303.033321 -300.338356) (xy 303.003756 -300.3777) (xy 302.968263 -300.411792) (xy 302.92776 -300.439748)
			(xy 302.883298 -300.460846) (xy 302.836027 -300.474538) (xy 302.787172 -300.48047) (xy 302.737997 -300.478489)
			(xy 302.689778 -300.468645) (xy 302.643762 -300.451193) (xy 302.601141 -300.426586) (xy 302.56302 -300.395461)
			(xy 302.530385 -300.358624) (xy 302.504082 -300.317028) (xy 302.484791 -300.271752) (xy 302.473014 -300.223968)
			(xy 302.469054 -300.174914) (xy 302.130206 -300.174914) (xy 302.129711 -300.199521) (xy 302.121816 -300.248098)
			(xy 302.106232 -300.294779) (xy 302.083361 -300.338356) (xy 302.053796 -300.3777) (xy 302.018303 -300.411792)
			(xy 301.9778 -300.439748) (xy 301.933338 -300.460846) (xy 301.886067 -300.474538) (xy 301.837212 -300.48047)
			(xy 301.788037 -300.478489) (xy 301.739818 -300.468645) (xy 301.693802 -300.451193) (xy 301.651181 -300.426586)
			(xy 301.61306 -300.395461) (xy 301.580425 -300.358624) (xy 301.554122 -300.317028) (xy 301.534831 -300.271752)
			(xy 301.523054 -300.223968) (xy 301.519094 -300.174914) (xy 301.179992 -300.174914) (xy 301.179497 -300.199521)
			(xy 301.171602 -300.248098) (xy 301.156018 -300.294779) (xy 301.133147 -300.338356) (xy 301.103582 -300.3777)
			(xy 301.068089 -300.411792) (xy 301.027586 -300.439748) (xy 300.983124 -300.460846) (xy 300.935853 -300.474538)
			(xy 300.886998 -300.48047) (xy 300.837823 -300.478489) (xy 300.789604 -300.468645) (xy 300.743588 -300.451193)
			(xy 300.700967 -300.426586) (xy 300.662846 -300.395461) (xy 300.630211 -300.358624) (xy 300.603908 -300.317028)
			(xy 300.584617 -300.271752) (xy 300.57284 -300.223968) (xy 300.56888 -300.174914) (xy 300.230032 -300.174914)
			(xy 300.229537 -300.199521) (xy 300.221642 -300.248098) (xy 300.206058 -300.294779) (xy 300.183187 -300.338356)
			(xy 300.153622 -300.3777) (xy 300.118129 -300.411792) (xy 300.077626 -300.439748) (xy 300.033164 -300.460846)
			(xy 299.985893 -300.474538) (xy 299.937038 -300.48047) (xy 299.887863 -300.478489) (xy 299.839644 -300.468645)
			(xy 299.793628 -300.451193) (xy 299.751007 -300.426586) (xy 299.712886 -300.395461) (xy 299.680251 -300.358624)
			(xy 299.653948 -300.317028) (xy 299.634657 -300.271752) (xy 299.62288 -300.223968) (xy 299.61892 -300.174914)
			(xy 299.280072 -300.174914) (xy 299.279577 -300.199521) (xy 299.271682 -300.248098) (xy 299.256098 -300.294779)
			(xy 299.233227 -300.338356) (xy 299.203662 -300.3777) (xy 299.168169 -300.411792) (xy 299.127666 -300.439748)
			(xy 299.083204 -300.460846) (xy 299.035933 -300.474538) (xy 298.987078 -300.48047) (xy 298.937903 -300.478489)
			(xy 298.889684 -300.468645) (xy 298.843668 -300.451193) (xy 298.801047 -300.426586) (xy 298.762926 -300.395461)
			(xy 298.730291 -300.358624) (xy 298.703988 -300.317028) (xy 298.684697 -300.271752) (xy 298.67292 -300.223968)
			(xy 298.66896 -300.174914) (xy 298.330112 -300.174914) (xy 298.329617 -300.199521) (xy 298.321722 -300.248098)
			(xy 298.306138 -300.294779) (xy 298.283267 -300.338356) (xy 298.253702 -300.3777) (xy 298.218209 -300.411792)
			(xy 298.177706 -300.439748) (xy 298.133244 -300.460846) (xy 298.085973 -300.474538) (xy 298.037118 -300.48047)
			(xy 297.987943 -300.478489) (xy 297.939724 -300.468645) (xy 297.893708 -300.451193) (xy 297.851087 -300.426586)
			(xy 297.812966 -300.395461) (xy 297.780331 -300.358624) (xy 297.754028 -300.317028) (xy 297.734737 -300.271752)
			(xy 297.72296 -300.223968) (xy 297.719 -300.174914) (xy 297.380152 -300.174914) (xy 297.379657 -300.199521)
			(xy 297.371762 -300.248098) (xy 297.356178 -300.294779) (xy 297.333307 -300.338356) (xy 297.303742 -300.3777)
			(xy 297.268249 -300.411792) (xy 297.227746 -300.439748) (xy 297.183284 -300.460846) (xy 297.136013 -300.474538)
			(xy 297.087158 -300.48047) (xy 297.037983 -300.478489) (xy 296.989764 -300.468645) (xy 296.943748 -300.451193)
			(xy 296.901127 -300.426586) (xy 296.863006 -300.395461) (xy 296.830371 -300.358624) (xy 296.804068 -300.317028)
			(xy 296.784777 -300.271752) (xy 296.773 -300.223968) (xy 296.76904 -300.174914) (xy 296.430192 -300.174914)
			(xy 296.429697 -300.199521) (xy 296.421802 -300.248098) (xy 296.406218 -300.294779) (xy 296.383347 -300.338356)
			(xy 296.353782 -300.3777) (xy 296.318289 -300.411792) (xy 296.277786 -300.439748) (xy 296.233324 -300.460846)
			(xy 296.186053 -300.474538) (xy 296.137198 -300.48047) (xy 296.088023 -300.478489) (xy 296.039804 -300.468645)
			(xy 295.993788 -300.451193) (xy 295.951167 -300.426586) (xy 295.913046 -300.395461) (xy 295.880411 -300.358624)
			(xy 295.854108 -300.317028) (xy 295.834817 -300.271752) (xy 295.82304 -300.223968) (xy 295.81908 -300.174914)
			(xy 295.480232 -300.174914) (xy 295.479737 -300.199521) (xy 295.471842 -300.248098) (xy 295.456258 -300.294779)
			(xy 295.433387 -300.338356) (xy 295.403822 -300.3777) (xy 295.368329 -300.411792) (xy 295.327826 -300.439748)
			(xy 295.283364 -300.460846) (xy 295.236093 -300.474538) (xy 295.187238 -300.48047) (xy 295.138063 -300.478489)
			(xy 295.089844 -300.468645) (xy 295.043828 -300.451193) (xy 295.001207 -300.426586) (xy 294.963086 -300.395461)
			(xy 294.930451 -300.358624) (xy 294.904148 -300.317028) (xy 294.884857 -300.271752) (xy 294.87308 -300.223968)
			(xy 294.86912 -300.174914) (xy 294.530018 -300.174914) (xy 294.529523 -300.199521) (xy 294.521628 -300.248098)
			(xy 294.506044 -300.294779) (xy 294.483173 -300.338356) (xy 294.453608 -300.3777) (xy 294.418115 -300.411792)
			(xy 294.377612 -300.439748) (xy 294.33315 -300.460846) (xy 294.285879 -300.474538) (xy 294.237024 -300.48047)
			(xy 294.187849 -300.478489) (xy 294.13963 -300.468645) (xy 294.093614 -300.451193) (xy 294.050993 -300.426586)
			(xy 294.012872 -300.395461) (xy 293.980237 -300.358624) (xy 293.953934 -300.317028) (xy 293.934643 -300.271752)
			(xy 293.922866 -300.223968) (xy 293.918906 -300.174914) (xy 293.580058 -300.174914) (xy 293.579563 -300.199521)
			(xy 293.571668 -300.248098) (xy 293.556084 -300.294779) (xy 293.533213 -300.338356) (xy 293.503648 -300.3777)
			(xy 293.468155 -300.411792) (xy 293.427652 -300.439748) (xy 293.38319 -300.460846) (xy 293.335919 -300.474538)
			(xy 293.287064 -300.48047) (xy 293.237889 -300.478489) (xy 293.18967 -300.468645) (xy 293.143654 -300.451193)
			(xy 293.101033 -300.426586) (xy 293.062912 -300.395461) (xy 293.030277 -300.358624) (xy 293.003974 -300.317028)
			(xy 292.984683 -300.271752) (xy 292.972906 -300.223968) (xy 292.968946 -300.174914) (xy 292.630098 -300.174914)
			(xy 292.629603 -300.199521) (xy 292.621708 -300.248098) (xy 292.606124 -300.294779) (xy 292.583253 -300.338356)
			(xy 292.553688 -300.3777) (xy 292.518195 -300.411792) (xy 292.477692 -300.439748) (xy 292.43323 -300.460846)
			(xy 292.385959 -300.474538) (xy 292.337104 -300.48047) (xy 292.287929 -300.478489) (xy 292.23971 -300.468645)
			(xy 292.193694 -300.451193) (xy 292.151073 -300.426586) (xy 292.112952 -300.395461) (xy 292.080317 -300.358624)
			(xy 292.054014 -300.317028) (xy 292.034723 -300.271752) (xy 292.022946 -300.223968) (xy 292.018986 -300.174914)
			(xy 290.730178 -300.174914) (xy 290.729683 -300.199521) (xy 290.721788 -300.248098) (xy 290.706204 -300.294779)
			(xy 290.683333 -300.338356) (xy 290.653768 -300.3777) (xy 290.618275 -300.411792) (xy 290.577772 -300.439748)
			(xy 290.53331 -300.460846) (xy 290.486039 -300.474538) (xy 290.437184 -300.48047) (xy 290.388009 -300.478489)
			(xy 290.33979 -300.468645) (xy 290.293774 -300.451193) (xy 290.251153 -300.426586) (xy 290.213032 -300.395461)
			(xy 290.180397 -300.358624) (xy 290.154094 -300.317028) (xy 290.134803 -300.271752) (xy 290.123026 -300.223968)
			(xy 290.119066 -300.174914) (xy 289.780218 -300.174914) (xy 289.779723 -300.199521) (xy 289.771828 -300.248098)
			(xy 289.756244 -300.294779) (xy 289.733373 -300.338356) (xy 289.703808 -300.3777) (xy 289.668315 -300.411792)
			(xy 289.627812 -300.439748) (xy 289.58335 -300.460846) (xy 289.536079 -300.474538) (xy 289.487224 -300.48047)
			(xy 289.438049 -300.478489) (xy 289.38983 -300.468645) (xy 289.343814 -300.451193) (xy 289.301193 -300.426586)
			(xy 289.263072 -300.395461) (xy 289.230437 -300.358624) (xy 289.204134 -300.317028) (xy 289.184843 -300.271752)
			(xy 289.173066 -300.223968) (xy 289.169106 -300.174914) (xy 288.830004 -300.174914) (xy 288.829509 -300.199521)
			(xy 288.821614 -300.248098) (xy 288.80603 -300.294779) (xy 288.783159 -300.338356) (xy 288.753594 -300.3777)
			(xy 288.718101 -300.411792) (xy 288.677598 -300.439748) (xy 288.633136 -300.460846) (xy 288.585865 -300.474538)
			(xy 288.53701 -300.48047) (xy 288.487835 -300.478489) (xy 288.439616 -300.468645) (xy 288.3936 -300.451193)
			(xy 288.350979 -300.426586) (xy 288.312858 -300.395461) (xy 288.280223 -300.358624) (xy 288.25392 -300.317028)
			(xy 288.234629 -300.271752) (xy 288.222852 -300.223968) (xy 288.218892 -300.174914) (xy 287.880044 -300.174914)
			(xy 287.879549 -300.199521) (xy 287.871654 -300.248098) (xy 287.85607 -300.294779) (xy 287.833199 -300.338356)
			(xy 287.803634 -300.3777) (xy 287.768141 -300.411792) (xy 287.727638 -300.439748) (xy 287.683176 -300.460846)
			(xy 287.635905 -300.474538) (xy 287.58705 -300.48047) (xy 287.537875 -300.478489) (xy 287.489656 -300.468645)
			(xy 287.44364 -300.451193) (xy 287.401019 -300.426586) (xy 287.362898 -300.395461) (xy 287.330263 -300.358624)
			(xy 287.30396 -300.317028) (xy 287.284669 -300.271752) (xy 287.272892 -300.223968) (xy 287.268932 -300.174914)
			(xy 286.930084 -300.174914) (xy 286.929589 -300.199521) (xy 286.921694 -300.248098) (xy 286.90611 -300.294779)
			(xy 286.883239 -300.338356) (xy 286.853674 -300.3777) (xy 286.818181 -300.411792) (xy 286.777678 -300.439748)
			(xy 286.733216 -300.460846) (xy 286.685945 -300.474538) (xy 286.63709 -300.48047) (xy 286.587915 -300.478489)
			(xy 286.539696 -300.468645) (xy 286.49368 -300.451193) (xy 286.451059 -300.426586) (xy 286.412938 -300.395461)
			(xy 286.380303 -300.358624) (xy 286.354 -300.317028) (xy 286.334709 -300.271752) (xy 286.322932 -300.223968)
			(xy 286.318972 -300.174914) (xy 285.980124 -300.174914) (xy 285.979629 -300.199521) (xy 285.971734 -300.248098)
			(xy 285.95615 -300.294779) (xy 285.933279 -300.338356) (xy 285.903714 -300.3777) (xy 285.868221 -300.411792)
			(xy 285.827718 -300.439748) (xy 285.783256 -300.460846) (xy 285.735985 -300.474538) (xy 285.68713 -300.48047)
			(xy 285.637955 -300.478489) (xy 285.589736 -300.468645) (xy 285.54372 -300.451193) (xy 285.501099 -300.426586)
			(xy 285.462978 -300.395461) (xy 285.430343 -300.358624) (xy 285.40404 -300.317028) (xy 285.384749 -300.271752)
			(xy 285.372972 -300.223968) (xy 285.369012 -300.174914) (xy 285.030164 -300.174914) (xy 285.029669 -300.199521)
			(xy 285.021774 -300.248098) (xy 285.00619 -300.294779) (xy 284.983319 -300.338356) (xy 284.953754 -300.3777)
			(xy 284.918261 -300.411792) (xy 284.877758 -300.439748) (xy 284.833296 -300.460846) (xy 284.786025 -300.474538)
			(xy 284.73717 -300.48047) (xy 284.687995 -300.478489) (xy 284.639776 -300.468645) (xy 284.59376 -300.451193)
			(xy 284.551139 -300.426586) (xy 284.513018 -300.395461) (xy 284.480383 -300.358624) (xy 284.45408 -300.317028)
			(xy 284.434789 -300.271752) (xy 284.423012 -300.223968) (xy 284.419052 -300.174914) (xy 284.080204 -300.174914)
			(xy 284.079709 -300.199521) (xy 284.071814 -300.248098) (xy 284.05623 -300.294779) (xy 284.033359 -300.338356)
			(xy 284.003794 -300.3777) (xy 283.968301 -300.411792) (xy 283.927798 -300.439748) (xy 283.883336 -300.460846)
			(xy 283.836065 -300.474538) (xy 283.78721 -300.48047) (xy 283.738035 -300.478489) (xy 283.689816 -300.468645)
			(xy 283.6438 -300.451193) (xy 283.601179 -300.426586) (xy 283.563058 -300.395461) (xy 283.530423 -300.358624)
			(xy 283.50412 -300.317028) (xy 283.484829 -300.271752) (xy 283.473052 -300.223968) (xy 283.469092 -300.174914)
			(xy 283.130244 -300.174914) (xy 283.129749 -300.199521) (xy 283.121854 -300.248098) (xy 283.10627 -300.294779)
			(xy 283.083399 -300.338356) (xy 283.053834 -300.3777) (xy 283.018341 -300.411792) (xy 282.977838 -300.439748)
			(xy 282.933376 -300.460846) (xy 282.886105 -300.474538) (xy 282.83725 -300.48047) (xy 282.788075 -300.478489)
			(xy 282.739856 -300.468645) (xy 282.69384 -300.451193) (xy 282.651219 -300.426586) (xy 282.613098 -300.395461)
			(xy 282.580463 -300.358624) (xy 282.55416 -300.317028) (xy 282.534869 -300.271752) (xy 282.523092 -300.223968)
			(xy 282.519132 -300.174914) (xy 281.616912 -300.174914) (xy 281.616912 -300.749208) (xy 281.617556 -300.761763)
			(xy 281.629413 -300.783894) (xy 281.639518 -300.791372) (xy 281.720544 -300.845474) (xy 281.745436 -300.848014)
			(xy 281.757628 -300.842934) (xy 281.785665 -300.832034) (xy 281.844649 -300.820266) (xy 281.874722 -300.819566)
			(xy 281.899978 -300.820089) (xy 281.949801 -300.828407) (xy 281.997576 -300.844811) (xy 282.042 -300.868854)
			(xy 282.08186 -300.899882) (xy 282.11607 -300.937046) (xy 282.143697 -300.979334) (xy 282.163986 -301.025593)
			(xy 282.176386 -301.07456) (xy 282.180555 -301.124874) (xy 282.519132 -301.124874) (xy 282.523092 -301.07582)
			(xy 282.534869 -301.028036) (xy 282.55416 -300.98276) (xy 282.580463 -300.941164) (xy 282.613098 -300.904327)
			(xy 282.651219 -300.873202) (xy 282.69384 -300.848595) (xy 282.739856 -300.831143) (xy 282.788075 -300.821299)
			(xy 282.83725 -300.819318) (xy 282.886105 -300.82525) (xy 282.933376 -300.838942) (xy 282.977838 -300.86004)
			(xy 283.018341 -300.887996) (xy 283.053834 -300.922088) (xy 283.083399 -300.961432) (xy 283.10627 -301.005009)
			(xy 283.121854 -301.05169) (xy 283.129749 -301.100267) (xy 283.130244 -301.124874) (xy 283.469092 -301.124874)
			(xy 283.473052 -301.07582) (xy 283.484829 -301.028036) (xy 283.50412 -300.98276) (xy 283.530423 -300.941164)
			(xy 283.563058 -300.904327) (xy 283.601179 -300.873202) (xy 283.6438 -300.848595) (xy 283.689816 -300.831143)
			(xy 283.738035 -300.821299) (xy 283.78721 -300.819318) (xy 283.836065 -300.82525) (xy 283.883336 -300.838942)
			(xy 283.927798 -300.86004) (xy 283.968301 -300.887996) (xy 284.003794 -300.922088) (xy 284.033359 -300.961432)
			(xy 284.05623 -301.005009) (xy 284.071814 -301.05169) (xy 284.079709 -301.100267) (xy 284.080204 -301.124874)
			(xy 284.419052 -301.124874) (xy 284.423012 -301.07582) (xy 284.434789 -301.028036) (xy 284.45408 -300.98276)
			(xy 284.480383 -300.941164) (xy 284.513018 -300.904327) (xy 284.551139 -300.873202) (xy 284.59376 -300.848595)
			(xy 284.639776 -300.831143) (xy 284.687995 -300.821299) (xy 284.73717 -300.819318) (xy 284.786025 -300.82525)
			(xy 284.833296 -300.838942) (xy 284.877758 -300.86004) (xy 284.918261 -300.887996) (xy 284.953754 -300.922088)
			(xy 284.983319 -300.961432) (xy 285.00619 -301.005009) (xy 285.021774 -301.05169) (xy 285.029669 -301.100267)
			(xy 285.030164 -301.124874) (xy 285.369012 -301.124874) (xy 285.372972 -301.07582) (xy 285.384749 -301.028036)
			(xy 285.40404 -300.98276) (xy 285.430343 -300.941164) (xy 285.462978 -300.904327) (xy 285.501099 -300.873202)
			(xy 285.54372 -300.848595) (xy 285.589736 -300.831143) (xy 285.637955 -300.821299) (xy 285.68713 -300.819318)
			(xy 285.735985 -300.82525) (xy 285.783256 -300.838942) (xy 285.827718 -300.86004) (xy 285.868221 -300.887996)
			(xy 285.903714 -300.922088) (xy 285.933279 -300.961432) (xy 285.95615 -301.005009) (xy 285.971734 -301.05169)
			(xy 285.979629 -301.100267) (xy 285.980124 -301.124874) (xy 286.318972 -301.124874) (xy 286.322932 -301.07582)
			(xy 286.334709 -301.028036) (xy 286.354 -300.98276) (xy 286.380303 -300.941164) (xy 286.412938 -300.904327)
			(xy 286.451059 -300.873202) (xy 286.49368 -300.848595) (xy 286.539696 -300.831143) (xy 286.587915 -300.821299)
			(xy 286.63709 -300.819318) (xy 286.685945 -300.82525) (xy 286.733216 -300.838942) (xy 286.777678 -300.86004)
			(xy 286.818181 -300.887996) (xy 286.853674 -300.922088) (xy 286.883239 -300.961432) (xy 286.90611 -301.005009)
			(xy 286.921694 -301.05169) (xy 286.929589 -301.100267) (xy 286.930084 -301.124874) (xy 287.268932 -301.124874)
			(xy 287.272892 -301.07582) (xy 287.284669 -301.028036) (xy 287.30396 -300.98276) (xy 287.330263 -300.941164)
			(xy 287.362898 -300.904327) (xy 287.401019 -300.873202) (xy 287.44364 -300.848595) (xy 287.489656 -300.831143)
			(xy 287.537875 -300.821299) (xy 287.58705 -300.819318) (xy 287.635905 -300.82525) (xy 287.683176 -300.838942)
			(xy 287.727638 -300.86004) (xy 287.768141 -300.887996) (xy 287.803634 -300.922088) (xy 287.833199 -300.961432)
			(xy 287.85607 -301.005009) (xy 287.871654 -301.05169) (xy 287.879549 -301.100267) (xy 287.880044 -301.124874)
			(xy 288.218892 -301.124874) (xy 288.222852 -301.07582) (xy 288.234629 -301.028036) (xy 288.25392 -300.98276)
			(xy 288.280223 -300.941164) (xy 288.312858 -300.904327) (xy 288.350979 -300.873202) (xy 288.3936 -300.848595)
			(xy 288.439616 -300.831143) (xy 288.487835 -300.821299) (xy 288.53701 -300.819318) (xy 288.585865 -300.82525)
			(xy 288.633136 -300.838942) (xy 288.677598 -300.86004) (xy 288.718101 -300.887996) (xy 288.753594 -300.922088)
			(xy 288.783159 -300.961432) (xy 288.80603 -301.005009) (xy 288.821614 -301.05169) (xy 288.829509 -301.100267)
			(xy 288.830004 -301.124874) (xy 289.169106 -301.124874) (xy 289.173066 -301.07582) (xy 289.184843 -301.028036)
			(xy 289.204134 -300.98276) (xy 289.230437 -300.941164) (xy 289.263072 -300.904327) (xy 289.301193 -300.873202)
			(xy 289.343814 -300.848595) (xy 289.38983 -300.831143) (xy 289.438049 -300.821299) (xy 289.487224 -300.819318)
			(xy 289.536079 -300.82525) (xy 289.58335 -300.838942) (xy 289.627812 -300.86004) (xy 289.668315 -300.887996)
			(xy 289.703808 -300.922088) (xy 289.733373 -300.961432) (xy 289.756244 -301.005009) (xy 289.771828 -301.05169)
			(xy 289.779723 -301.100267) (xy 289.780218 -301.124874) (xy 290.119066 -301.124874) (xy 290.123026 -301.07582)
			(xy 290.134803 -301.028036) (xy 290.154094 -300.98276) (xy 290.180397 -300.941164) (xy 290.213032 -300.904327)
			(xy 290.251153 -300.873202) (xy 290.293774 -300.848595) (xy 290.33979 -300.831143) (xy 290.388009 -300.821299)
			(xy 290.437184 -300.819318) (xy 290.486039 -300.82525) (xy 290.53331 -300.838942) (xy 290.577772 -300.86004)
			(xy 290.618275 -300.887996) (xy 290.653768 -300.922088) (xy 290.683333 -300.961432) (xy 290.706204 -301.005009)
			(xy 290.721788 -301.05169) (xy 290.729683 -301.100267) (xy 290.730178 -301.124874) (xy 292.018986 -301.124874)
			(xy 292.022946 -301.07582) (xy 292.034723 -301.028036) (xy 292.054014 -300.98276) (xy 292.080317 -300.941164)
			(xy 292.112952 -300.904327) (xy 292.151073 -300.873202) (xy 292.193694 -300.848595) (xy 292.23971 -300.831143)
			(xy 292.287929 -300.821299) (xy 292.337104 -300.819318) (xy 292.385959 -300.82525) (xy 292.43323 -300.838942)
			(xy 292.477692 -300.86004) (xy 292.518195 -300.887996) (xy 292.553688 -300.922088) (xy 292.583253 -300.961432)
			(xy 292.606124 -301.005009) (xy 292.621708 -301.05169) (xy 292.629603 -301.100267) (xy 292.630098 -301.124874)
			(xy 292.968946 -301.124874) (xy 292.972906 -301.07582) (xy 292.984683 -301.028036) (xy 293.003974 -300.98276)
			(xy 293.030277 -300.941164) (xy 293.062912 -300.904327) (xy 293.101033 -300.873202) (xy 293.143654 -300.848595)
			(xy 293.18967 -300.831143) (xy 293.237889 -300.821299) (xy 293.287064 -300.819318) (xy 293.335919 -300.82525)
			(xy 293.38319 -300.838942) (xy 293.427652 -300.86004) (xy 293.468155 -300.887996) (xy 293.503648 -300.922088)
			(xy 293.533213 -300.961432) (xy 293.556084 -301.005009) (xy 293.571668 -301.05169) (xy 293.579563 -301.100267)
			(xy 293.580058 -301.124874) (xy 293.918906 -301.124874) (xy 293.922866 -301.07582) (xy 293.934643 -301.028036)
			(xy 293.953934 -300.98276) (xy 293.980237 -300.941164) (xy 294.012872 -300.904327) (xy 294.050993 -300.873202)
			(xy 294.093614 -300.848595) (xy 294.13963 -300.831143) (xy 294.187849 -300.821299) (xy 294.237024 -300.819318)
			(xy 294.285879 -300.82525) (xy 294.33315 -300.838942) (xy 294.377612 -300.86004) (xy 294.418115 -300.887996)
			(xy 294.453608 -300.922088) (xy 294.483173 -300.961432) (xy 294.506044 -301.005009) (xy 294.521628 -301.05169)
			(xy 294.529523 -301.100267) (xy 294.530018 -301.124874) (xy 294.86912 -301.124874) (xy 294.87308 -301.07582)
			(xy 294.884857 -301.028036) (xy 294.904148 -300.98276) (xy 294.930451 -300.941164) (xy 294.963086 -300.904327)
			(xy 295.001207 -300.873202) (xy 295.043828 -300.848595) (xy 295.089844 -300.831143) (xy 295.138063 -300.821299)
			(xy 295.187238 -300.819318) (xy 295.236093 -300.82525) (xy 295.283364 -300.838942) (xy 295.327826 -300.86004)
			(xy 295.368329 -300.887996) (xy 295.403822 -300.922088) (xy 295.433387 -300.961432) (xy 295.456258 -301.005009)
			(xy 295.471842 -301.05169) (xy 295.479737 -301.100267) (xy 295.480232 -301.124874) (xy 295.81908 -301.124874)
			(xy 295.82304 -301.07582) (xy 295.834817 -301.028036) (xy 295.854108 -300.98276) (xy 295.880411 -300.941164)
			(xy 295.913046 -300.904327) (xy 295.951167 -300.873202) (xy 295.993788 -300.848595) (xy 296.039804 -300.831143)
			(xy 296.088023 -300.821299) (xy 296.137198 -300.819318) (xy 296.186053 -300.82525) (xy 296.233324 -300.838942)
			(xy 296.277786 -300.86004) (xy 296.318289 -300.887996) (xy 296.353782 -300.922088) (xy 296.383347 -300.961432)
			(xy 296.406218 -301.005009) (xy 296.421802 -301.05169) (xy 296.429697 -301.100267) (xy 296.430192 -301.124874)
			(xy 296.76904 -301.124874) (xy 296.773 -301.07582) (xy 296.784777 -301.028036) (xy 296.804068 -300.98276)
			(xy 296.830371 -300.941164) (xy 296.863006 -300.904327) (xy 296.901127 -300.873202) (xy 296.943748 -300.848595)
			(xy 296.989764 -300.831143) (xy 297.037983 -300.821299) (xy 297.087158 -300.819318) (xy 297.136013 -300.82525)
			(xy 297.183284 -300.838942) (xy 297.227746 -300.86004) (xy 297.268249 -300.887996) (xy 297.303742 -300.922088)
			(xy 297.333307 -300.961432) (xy 297.356178 -301.005009) (xy 297.371762 -301.05169) (xy 297.379657 -301.100267)
			(xy 297.380152 -301.124874) (xy 297.719 -301.124874) (xy 297.72296 -301.07582) (xy 297.734737 -301.028036)
			(xy 297.754028 -300.98276) (xy 297.780331 -300.941164) (xy 297.812966 -300.904327) (xy 297.851087 -300.873202)
			(xy 297.893708 -300.848595) (xy 297.939724 -300.831143) (xy 297.987943 -300.821299) (xy 298.037118 -300.819318)
			(xy 298.085973 -300.82525) (xy 298.133244 -300.838942) (xy 298.177706 -300.86004) (xy 298.218209 -300.887996)
			(xy 298.253702 -300.922088) (xy 298.283267 -300.961432) (xy 298.306138 -301.005009) (xy 298.321722 -301.05169)
			(xy 298.329617 -301.100267) (xy 298.330112 -301.124874) (xy 298.66896 -301.124874) (xy 298.67292 -301.07582)
			(xy 298.684697 -301.028036) (xy 298.703988 -300.98276) (xy 298.730291 -300.941164) (xy 298.762926 -300.904327)
			(xy 298.801047 -300.873202) (xy 298.843668 -300.848595) (xy 298.889684 -300.831143) (xy 298.937903 -300.821299)
			(xy 298.987078 -300.819318) (xy 299.035933 -300.82525) (xy 299.083204 -300.838942) (xy 299.127666 -300.86004)
			(xy 299.168169 -300.887996) (xy 299.203662 -300.922088) (xy 299.233227 -300.961432) (xy 299.256098 -301.005009)
			(xy 299.271682 -301.05169) (xy 299.279577 -301.100267) (xy 299.280072 -301.124874) (xy 299.61892 -301.124874)
			(xy 299.62288 -301.07582) (xy 299.634657 -301.028036) (xy 299.653948 -300.98276) (xy 299.680251 -300.941164)
			(xy 299.712886 -300.904327) (xy 299.751007 -300.873202) (xy 299.793628 -300.848595) (xy 299.839644 -300.831143)
			(xy 299.887863 -300.821299) (xy 299.937038 -300.819318) (xy 299.985893 -300.82525) (xy 300.033164 -300.838942)
			(xy 300.077626 -300.86004) (xy 300.118129 -300.887996) (xy 300.153622 -300.922088) (xy 300.183187 -300.961432)
			(xy 300.206058 -301.005009) (xy 300.221642 -301.05169) (xy 300.229537 -301.100267) (xy 300.230032 -301.124874)
			(xy 300.56888 -301.124874) (xy 300.57284 -301.07582) (xy 300.584617 -301.028036) (xy 300.603908 -300.98276)
			(xy 300.630211 -300.941164) (xy 300.662846 -300.904327) (xy 300.700967 -300.873202) (xy 300.743588 -300.848595)
			(xy 300.789604 -300.831143) (xy 300.837823 -300.821299) (xy 300.886998 -300.819318) (xy 300.935853 -300.82525)
			(xy 300.983124 -300.838942) (xy 301.027586 -300.86004) (xy 301.068089 -300.887996) (xy 301.103582 -300.922088)
			(xy 301.133147 -300.961432) (xy 301.156018 -301.005009) (xy 301.171602 -301.05169) (xy 301.179497 -301.100267)
			(xy 301.179992 -301.124874) (xy 301.519094 -301.124874) (xy 301.523054 -301.07582) (xy 301.534831 -301.028036)
			(xy 301.554122 -300.98276) (xy 301.580425 -300.941164) (xy 301.61306 -300.904327) (xy 301.651181 -300.873202)
			(xy 301.693802 -300.848595) (xy 301.739818 -300.831143) (xy 301.788037 -300.821299) (xy 301.837212 -300.819318)
			(xy 301.886067 -300.82525) (xy 301.933338 -300.838942) (xy 301.9778 -300.86004) (xy 302.018303 -300.887996)
			(xy 302.053796 -300.922088) (xy 302.083361 -300.961432) (xy 302.106232 -301.005009) (xy 302.121816 -301.05169)
			(xy 302.129711 -301.100267) (xy 302.130206 -301.124874) (xy 302.469054 -301.124874) (xy 302.473014 -301.07582)
			(xy 302.484791 -301.028036) (xy 302.504082 -300.98276) (xy 302.530385 -300.941164) (xy 302.56302 -300.904327)
			(xy 302.601141 -300.873202) (xy 302.643762 -300.848595) (xy 302.689778 -300.831143) (xy 302.737997 -300.821299)
			(xy 302.787172 -300.819318) (xy 302.836027 -300.82525) (xy 302.883298 -300.838942) (xy 302.92776 -300.86004)
			(xy 302.968263 -300.887996) (xy 303.003756 -300.922088) (xy 303.033321 -300.961432) (xy 303.056192 -301.005009)
			(xy 303.071776 -301.05169) (xy 303.079671 -301.100267) (xy 303.080166 -301.124874) (xy 303.419014 -301.124874)
			(xy 303.422974 -301.07582) (xy 303.434751 -301.028036) (xy 303.454042 -300.98276) (xy 303.480345 -300.941164)
			(xy 303.51298 -300.904327) (xy 303.551101 -300.873202) (xy 303.593722 -300.848595) (xy 303.639738 -300.831143)
			(xy 303.687957 -300.821299) (xy 303.737132 -300.819318) (xy 303.785987 -300.82525) (xy 303.833258 -300.838942)
			(xy 303.87772 -300.86004) (xy 303.918223 -300.887996) (xy 303.953716 -300.922088) (xy 303.983281 -300.961432)
			(xy 304.006152 -301.005009) (xy 304.021736 -301.05169) (xy 304.029631 -301.100267) (xy 304.030126 -301.124874)
			(xy 304.368974 -301.124874) (xy 304.372934 -301.07582) (xy 304.384711 -301.028036) (xy 304.404002 -300.98276)
			(xy 304.430305 -300.941164) (xy 304.46294 -300.904327) (xy 304.501061 -300.873202) (xy 304.543682 -300.848595)
			(xy 304.589698 -300.831143) (xy 304.637917 -300.821299) (xy 304.687092 -300.819318) (xy 304.735947 -300.82525)
			(xy 304.783218 -300.838942) (xy 304.82768 -300.86004) (xy 304.868183 -300.887996) (xy 304.903676 -300.922088)
			(xy 304.933241 -300.961432) (xy 304.956112 -301.005009) (xy 304.971696 -301.05169) (xy 304.979591 -301.100267)
			(xy 304.980086 -301.124874) (xy 305.318934 -301.124874) (xy 305.322894 -301.07582) (xy 305.334671 -301.028036)
			(xy 305.353962 -300.98276) (xy 305.380265 -300.941164) (xy 305.4129 -300.904327) (xy 305.451021 -300.873202)
			(xy 305.493642 -300.848595) (xy 305.539658 -300.831143) (xy 305.587877 -300.821299) (xy 305.637052 -300.819318)
			(xy 305.685907 -300.82525) (xy 305.733178 -300.838942) (xy 305.77764 -300.86004) (xy 305.818143 -300.887996)
			(xy 305.853636 -300.922088) (xy 305.883201 -300.961432) (xy 305.906072 -301.005009) (xy 305.921656 -301.05169)
			(xy 305.929551 -301.100267) (xy 305.930046 -301.124874) (xy 308.169068 -301.124874) (xy 308.173028 -301.07582)
			(xy 308.184805 -301.028036) (xy 308.204096 -300.98276) (xy 308.230399 -300.941164) (xy 308.263034 -300.904327)
			(xy 308.301155 -300.873202) (xy 308.343776 -300.848595) (xy 308.389792 -300.831143) (xy 308.438011 -300.821299)
			(xy 308.487186 -300.819318) (xy 308.536041 -300.82525) (xy 308.583312 -300.838942) (xy 308.627774 -300.86004)
			(xy 308.668277 -300.887996) (xy 308.70377 -300.922088) (xy 308.733335 -300.961432) (xy 308.756206 -301.005009)
			(xy 308.77179 -301.05169) (xy 308.779685 -301.100267) (xy 308.78018 -301.124874) (xy 309.119028 -301.124874)
			(xy 309.122988 -301.07582) (xy 309.134765 -301.028036) (xy 309.154056 -300.98276) (xy 309.180359 -300.941164)
			(xy 309.212994 -300.904327) (xy 309.251115 -300.873202) (xy 309.293736 -300.848595) (xy 309.339752 -300.831143)
			(xy 309.387971 -300.821299) (xy 309.437146 -300.819318) (xy 309.486001 -300.82525) (xy 309.533272 -300.838942)
			(xy 309.577734 -300.86004) (xy 309.618237 -300.887996) (xy 309.65373 -300.922088) (xy 309.683295 -300.961432)
			(xy 309.706166 -301.005009) (xy 309.72175 -301.05169) (xy 309.729645 -301.100267) (xy 309.73014 -301.124874)
			(xy 310.068988 -301.124874) (xy 310.072948 -301.07582) (xy 310.084725 -301.028036) (xy 310.104016 -300.98276)
			(xy 310.130319 -300.941164) (xy 310.162954 -300.904327) (xy 310.201075 -300.873202) (xy 310.243696 -300.848595)
			(xy 310.289712 -300.831143) (xy 310.337931 -300.821299) (xy 310.387106 -300.819318) (xy 310.435961 -300.82525)
			(xy 310.483232 -300.838942) (xy 310.527694 -300.86004) (xy 310.568197 -300.887996) (xy 310.60369 -300.922088)
			(xy 310.633255 -300.961432) (xy 310.656126 -301.005009) (xy 310.67171 -301.05169) (xy 310.679605 -301.100267)
			(xy 310.6801 -301.124874) (xy 311.018948 -301.124874) (xy 311.022908 -301.07582) (xy 311.034685 -301.028036)
			(xy 311.053976 -300.98276) (xy 311.080279 -300.941164) (xy 311.112914 -300.904327) (xy 311.151035 -300.873202)
			(xy 311.193656 -300.848595) (xy 311.239672 -300.831143) (xy 311.287891 -300.821299) (xy 311.337066 -300.819318)
			(xy 311.385921 -300.82525) (xy 311.433192 -300.838942) (xy 311.477654 -300.86004) (xy 311.518157 -300.887996)
			(xy 311.55365 -300.922088) (xy 311.583215 -300.961432) (xy 311.606086 -301.005009) (xy 311.62167 -301.05169)
			(xy 311.629565 -301.100267) (xy 311.63006 -301.124874) (xy 311.968908 -301.124874) (xy 311.972868 -301.07582)
			(xy 311.984645 -301.028036) (xy 312.003936 -300.98276) (xy 312.030239 -300.941164) (xy 312.062874 -300.904327)
			(xy 312.100995 -300.873202) (xy 312.143616 -300.848595) (xy 312.189632 -300.831143) (xy 312.237851 -300.821299)
			(xy 312.287026 -300.819318) (xy 312.335881 -300.82525) (xy 312.383152 -300.838942) (xy 312.427614 -300.86004)
			(xy 312.468117 -300.887996) (xy 312.50361 -300.922088) (xy 312.533175 -300.961432) (xy 312.556046 -301.005009)
			(xy 312.57163 -301.05169) (xy 312.579525 -301.100267) (xy 312.58002 -301.124874) (xy 312.919122 -301.124874)
			(xy 312.923082 -301.07582) (xy 312.934859 -301.028036) (xy 312.95415 -300.98276) (xy 312.980453 -300.941164)
			(xy 313.013088 -300.904327) (xy 313.051209 -300.873202) (xy 313.09383 -300.848595) (xy 313.139846 -300.831143)
			(xy 313.188065 -300.821299) (xy 313.23724 -300.819318) (xy 313.286095 -300.82525) (xy 313.333366 -300.838942)
			(xy 313.377828 -300.86004) (xy 313.418331 -300.887996) (xy 313.453824 -300.922088) (xy 313.483389 -300.961432)
			(xy 313.50626 -301.005009) (xy 313.521844 -301.05169) (xy 313.529739 -301.100267) (xy 313.530234 -301.124874)
			(xy 313.869082 -301.124874) (xy 313.873042 -301.07582) (xy 313.884819 -301.028036) (xy 313.90411 -300.98276)
			(xy 313.930413 -300.941164) (xy 313.963048 -300.904327) (xy 314.001169 -300.873202) (xy 314.04379 -300.848595)
			(xy 314.089806 -300.831143) (xy 314.138025 -300.821299) (xy 314.1872 -300.819318) (xy 314.236055 -300.82525)
			(xy 314.283326 -300.838942) (xy 314.327788 -300.86004) (xy 314.368291 -300.887996) (xy 314.403784 -300.922088)
			(xy 314.433349 -300.961432) (xy 314.45622 -301.005009) (xy 314.471804 -301.05169) (xy 314.479699 -301.100267)
			(xy 314.480194 -301.124874) (xy 314.819042 -301.124874) (xy 314.823002 -301.07582) (xy 314.834779 -301.028036)
			(xy 314.85407 -300.98276) (xy 314.880373 -300.941164) (xy 314.913008 -300.904327) (xy 314.951129 -300.873202)
			(xy 314.99375 -300.848595) (xy 315.039766 -300.831143) (xy 315.087985 -300.821299) (xy 315.13716 -300.819318)
			(xy 315.186015 -300.82525) (xy 315.233286 -300.838942) (xy 315.277748 -300.86004) (xy 315.318251 -300.887996)
			(xy 315.353744 -300.922088) (xy 315.383309 -300.961432) (xy 315.40618 -301.005009) (xy 315.421764 -301.05169)
			(xy 315.429659 -301.100267) (xy 315.430154 -301.124874) (xy 315.429659 -301.149481) (xy 315.421764 -301.198058)
			(xy 315.40618 -301.244739) (xy 315.397103 -301.262034) (xy 317.57569 -301.262034) (xy 317.579761 -301.206412)
			(xy 317.591887 -301.151975) (xy 317.61181 -301.099884) (xy 317.639106 -301.051249) (xy 317.673192 -301.007106)
			(xy 317.713341 -300.968397) (xy 317.758699 -300.935946) (xy 317.808299 -300.910445) (xy 317.861083 -300.892438)
			(xy 317.915926 -300.882308) (xy 317.97166 -300.880271) (xy 318.027097 -300.886371) (xy 318.081054 -300.900477)
			(xy 318.132383 -300.922289) (xy 318.179989 -300.951343) (xy 318.222857 -300.987018) (xy 318.260074 -301.028555)
			(xy 318.269016 -301.04207) (xy 322.517006 -301.04207) (xy 322.521077 -300.986448) (xy 322.533203 -300.932011)
			(xy 322.553126 -300.87992) (xy 322.580422 -300.831285) (xy 322.614508 -300.787142) (xy 322.654657 -300.748433)
			(xy 322.700015 -300.715982) (xy 322.749615 -300.690481) (xy 322.802399 -300.672474) (xy 322.857242 -300.662344)
			(xy 322.912976 -300.660307) (xy 322.968413 -300.666407) (xy 323.02237 -300.680513) (xy 323.073699 -300.702325)
			(xy 323.121305 -300.731379) (xy 323.164173 -300.767054) (xy 323.20139 -300.808591) (xy 323.232163 -300.855104)
			(xy 323.255835 -300.905601) (xy 323.271903 -300.959008) (xy 323.280023 -301.014184) (xy 323.280532 -301.04207)
			(xy 323.280379 -301.050452) (xy 324.89089 -301.050452) (xy 324.894961 -300.99483) (xy 324.907087 -300.940393)
			(xy 324.92701 -300.888302) (xy 324.954306 -300.839667) (xy 324.988392 -300.795524) (xy 325.028541 -300.756815)
			(xy 325.073899 -300.724364) (xy 325.123499 -300.698863) (xy 325.176283 -300.680856) (xy 325.231126 -300.670726)
			(xy 325.28686 -300.668689) (xy 325.342297 -300.674789) (xy 325.396254 -300.688895) (xy 325.447583 -300.710707)
			(xy 325.495189 -300.739761) (xy 325.538057 -300.775436) (xy 325.575274 -300.816973) (xy 325.606047 -300.863486)
			(xy 325.629719 -300.913983) (xy 325.645787 -300.96739) (xy 325.653907 -301.022566) (xy 325.654416 -301.050452)
			(xy 325.653907 -301.078338) (xy 325.645787 -301.133514) (xy 325.629719 -301.186921) (xy 325.606047 -301.237418)
			(xy 325.575274 -301.283931) (xy 325.538057 -301.325468) (xy 325.495189 -301.361143) (xy 325.447583 -301.390197)
			(xy 325.396254 -301.412009) (xy 325.342297 -301.426115) (xy 325.28686 -301.432215) (xy 325.231126 -301.430178)
			(xy 325.176283 -301.420048) (xy 325.123499 -301.402041) (xy 325.073899 -301.37654) (xy 325.028541 -301.344089)
			(xy 324.988392 -301.30538) (xy 324.954306 -301.261237) (xy 324.92701 -301.212602) (xy 324.907087 -301.160511)
			(xy 324.894961 -301.106074) (xy 324.89089 -301.050452) (xy 323.280379 -301.050452) (xy 323.280023 -301.069956)
			(xy 323.271903 -301.125132) (xy 323.255835 -301.178539) (xy 323.232163 -301.229036) (xy 323.20139 -301.275549)
			(xy 323.164173 -301.317086) (xy 323.121305 -301.352761) (xy 323.073699 -301.381815) (xy 323.02237 -301.403627)
			(xy 322.968413 -301.417733) (xy 322.912976 -301.423833) (xy 322.857242 -301.421796) (xy 322.802399 -301.411666)
			(xy 322.749615 -301.393659) (xy 322.700015 -301.368158) (xy 322.654657 -301.335707) (xy 322.614508 -301.296998)
			(xy 322.580422 -301.252855) (xy 322.553126 -301.20422) (xy 322.533203 -301.152129) (xy 322.521077 -301.097692)
			(xy 322.517006 -301.04207) (xy 318.269016 -301.04207) (xy 318.290847 -301.075068) (xy 318.314519 -301.125565)
			(xy 318.330587 -301.178972) (xy 318.338707 -301.234148) (xy 318.339216 -301.262034) (xy 318.338707 -301.28992)
			(xy 318.330587 -301.345096) (xy 318.314519 -301.398503) (xy 318.290847 -301.449) (xy 318.260074 -301.495513)
			(xy 318.222857 -301.53705) (xy 318.179989 -301.572725) (xy 318.132383 -301.601779) (xy 318.081054 -301.623591)
			(xy 318.027097 -301.637697) (xy 317.97166 -301.643797) (xy 317.915926 -301.64176) (xy 317.861083 -301.63163)
			(xy 317.808299 -301.613623) (xy 317.758699 -301.588122) (xy 317.713341 -301.555671) (xy 317.673192 -301.516962)
			(xy 317.639106 -301.472819) (xy 317.61181 -301.424184) (xy 317.591887 -301.372093) (xy 317.579761 -301.317656)
			(xy 317.57569 -301.262034) (xy 315.397103 -301.262034) (xy 315.383309 -301.288316) (xy 315.353744 -301.32766)
			(xy 315.318251 -301.361752) (xy 315.277748 -301.389708) (xy 315.233286 -301.410806) (xy 315.186015 -301.424498)
			(xy 315.13716 -301.43043) (xy 315.087985 -301.428449) (xy 315.039766 -301.418605) (xy 314.99375 -301.401153)
			(xy 314.951129 -301.376546) (xy 314.913008 -301.345421) (xy 314.880373 -301.308584) (xy 314.85407 -301.266988)
			(xy 314.834779 -301.221712) (xy 314.823002 -301.173928) (xy 314.819042 -301.124874) (xy 314.480194 -301.124874)
			(xy 314.479699 -301.149481) (xy 314.471804 -301.198058) (xy 314.45622 -301.244739) (xy 314.433349 -301.288316)
			(xy 314.403784 -301.32766) (xy 314.368291 -301.361752) (xy 314.327788 -301.389708) (xy 314.283326 -301.410806)
			(xy 314.236055 -301.424498) (xy 314.1872 -301.43043) (xy 314.138025 -301.428449) (xy 314.089806 -301.418605)
			(xy 314.04379 -301.401153) (xy 314.001169 -301.376546) (xy 313.963048 -301.345421) (xy 313.930413 -301.308584)
			(xy 313.90411 -301.266988) (xy 313.884819 -301.221712) (xy 313.873042 -301.173928) (xy 313.869082 -301.124874)
			(xy 313.530234 -301.124874) (xy 313.529739 -301.149481) (xy 313.521844 -301.198058) (xy 313.50626 -301.244739)
			(xy 313.483389 -301.288316) (xy 313.453824 -301.32766) (xy 313.418331 -301.361752) (xy 313.377828 -301.389708)
			(xy 313.333366 -301.410806) (xy 313.286095 -301.424498) (xy 313.23724 -301.43043) (xy 313.188065 -301.428449)
			(xy 313.139846 -301.418605) (xy 313.09383 -301.401153) (xy 313.051209 -301.376546) (xy 313.013088 -301.345421)
			(xy 312.980453 -301.308584) (xy 312.95415 -301.266988) (xy 312.934859 -301.221712) (xy 312.923082 -301.173928)
			(xy 312.919122 -301.124874) (xy 312.58002 -301.124874) (xy 312.579525 -301.149481) (xy 312.57163 -301.198058)
			(xy 312.556046 -301.244739) (xy 312.533175 -301.288316) (xy 312.50361 -301.32766) (xy 312.468117 -301.361752)
			(xy 312.427614 -301.389708) (xy 312.383152 -301.410806) (xy 312.335881 -301.424498) (xy 312.287026 -301.43043)
			(xy 312.237851 -301.428449) (xy 312.189632 -301.418605) (xy 312.143616 -301.401153) (xy 312.100995 -301.376546)
			(xy 312.062874 -301.345421) (xy 312.030239 -301.308584) (xy 312.003936 -301.266988) (xy 311.984645 -301.221712)
			(xy 311.972868 -301.173928) (xy 311.968908 -301.124874) (xy 311.63006 -301.124874) (xy 311.629565 -301.149481)
			(xy 311.62167 -301.198058) (xy 311.606086 -301.244739) (xy 311.583215 -301.288316) (xy 311.55365 -301.32766)
			(xy 311.518157 -301.361752) (xy 311.477654 -301.389708) (xy 311.433192 -301.410806) (xy 311.385921 -301.424498)
			(xy 311.337066 -301.43043) (xy 311.287891 -301.428449) (xy 311.239672 -301.418605) (xy 311.193656 -301.401153)
			(xy 311.151035 -301.376546) (xy 311.112914 -301.345421) (xy 311.080279 -301.308584) (xy 311.053976 -301.266988)
			(xy 311.034685 -301.221712) (xy 311.022908 -301.173928) (xy 311.018948 -301.124874) (xy 310.6801 -301.124874)
			(xy 310.679605 -301.149481) (xy 310.67171 -301.198058) (xy 310.656126 -301.244739) (xy 310.633255 -301.288316)
			(xy 310.60369 -301.32766) (xy 310.568197 -301.361752) (xy 310.527694 -301.389708) (xy 310.483232 -301.410806)
			(xy 310.435961 -301.424498) (xy 310.387106 -301.43043) (xy 310.337931 -301.428449) (xy 310.289712 -301.418605)
			(xy 310.243696 -301.401153) (xy 310.201075 -301.376546) (xy 310.162954 -301.345421) (xy 310.130319 -301.308584)
			(xy 310.104016 -301.266988) (xy 310.084725 -301.221712) (xy 310.072948 -301.173928) (xy 310.068988 -301.124874)
			(xy 309.73014 -301.124874) (xy 309.729645 -301.149481) (xy 309.72175 -301.198058) (xy 309.706166 -301.244739)
			(xy 309.683295 -301.288316) (xy 309.65373 -301.32766) (xy 309.618237 -301.361752) (xy 309.577734 -301.389708)
			(xy 309.533272 -301.410806) (xy 309.486001 -301.424498) (xy 309.437146 -301.43043) (xy 309.387971 -301.428449)
			(xy 309.339752 -301.418605) (xy 309.293736 -301.401153) (xy 309.251115 -301.376546) (xy 309.212994 -301.345421)
			(xy 309.180359 -301.308584) (xy 309.154056 -301.266988) (xy 309.134765 -301.221712) (xy 309.122988 -301.173928)
			(xy 309.119028 -301.124874) (xy 308.78018 -301.124874) (xy 308.779685 -301.149481) (xy 308.77179 -301.198058)
			(xy 308.756206 -301.244739) (xy 308.733335 -301.288316) (xy 308.70377 -301.32766) (xy 308.668277 -301.361752)
			(xy 308.627774 -301.389708) (xy 308.583312 -301.410806) (xy 308.536041 -301.424498) (xy 308.487186 -301.43043)
			(xy 308.438011 -301.428449) (xy 308.389792 -301.418605) (xy 308.343776 -301.401153) (xy 308.301155 -301.376546)
			(xy 308.263034 -301.345421) (xy 308.230399 -301.308584) (xy 308.204096 -301.266988) (xy 308.184805 -301.221712)
			(xy 308.173028 -301.173928) (xy 308.169068 -301.124874) (xy 305.930046 -301.124874) (xy 305.929551 -301.149481)
			(xy 305.921656 -301.198058) (xy 305.906072 -301.244739) (xy 305.883201 -301.288316) (xy 305.853636 -301.32766)
			(xy 305.818143 -301.361752) (xy 305.77764 -301.389708) (xy 305.733178 -301.410806) (xy 305.685907 -301.424498)
			(xy 305.637052 -301.43043) (xy 305.587877 -301.428449) (xy 305.539658 -301.418605) (xy 305.493642 -301.401153)
			(xy 305.451021 -301.376546) (xy 305.4129 -301.345421) (xy 305.380265 -301.308584) (xy 305.353962 -301.266988)
			(xy 305.334671 -301.221712) (xy 305.322894 -301.173928) (xy 305.318934 -301.124874) (xy 304.980086 -301.124874)
			(xy 304.979591 -301.149481) (xy 304.971696 -301.198058) (xy 304.956112 -301.244739) (xy 304.933241 -301.288316)
			(xy 304.903676 -301.32766) (xy 304.868183 -301.361752) (xy 304.82768 -301.389708) (xy 304.783218 -301.410806)
			(xy 304.735947 -301.424498) (xy 304.687092 -301.43043) (xy 304.637917 -301.428449) (xy 304.589698 -301.418605)
			(xy 304.543682 -301.401153) (xy 304.501061 -301.376546) (xy 304.46294 -301.345421) (xy 304.430305 -301.308584)
			(xy 304.404002 -301.266988) (xy 304.384711 -301.221712) (xy 304.372934 -301.173928) (xy 304.368974 -301.124874)
			(xy 304.030126 -301.124874) (xy 304.029631 -301.149481) (xy 304.021736 -301.198058) (xy 304.006152 -301.244739)
			(xy 303.983281 -301.288316) (xy 303.953716 -301.32766) (xy 303.918223 -301.361752) (xy 303.87772 -301.389708)
			(xy 303.833258 -301.410806) (xy 303.785987 -301.424498) (xy 303.737132 -301.43043) (xy 303.687957 -301.428449)
			(xy 303.639738 -301.418605) (xy 303.593722 -301.401153) (xy 303.551101 -301.376546) (xy 303.51298 -301.345421)
			(xy 303.480345 -301.308584) (xy 303.454042 -301.266988) (xy 303.434751 -301.221712) (xy 303.422974 -301.173928)
			(xy 303.419014 -301.124874) (xy 303.080166 -301.124874) (xy 303.079671 -301.149481) (xy 303.071776 -301.198058)
			(xy 303.056192 -301.244739) (xy 303.033321 -301.288316) (xy 303.003756 -301.32766) (xy 302.968263 -301.361752)
			(xy 302.92776 -301.389708) (xy 302.883298 -301.410806) (xy 302.836027 -301.424498) (xy 302.787172 -301.43043)
			(xy 302.737997 -301.428449) (xy 302.689778 -301.418605) (xy 302.643762 -301.401153) (xy 302.601141 -301.376546)
			(xy 302.56302 -301.345421) (xy 302.530385 -301.308584) (xy 302.504082 -301.266988) (xy 302.484791 -301.221712)
			(xy 302.473014 -301.173928) (xy 302.469054 -301.124874) (xy 302.130206 -301.124874) (xy 302.129711 -301.149481)
			(xy 302.121816 -301.198058) (xy 302.106232 -301.244739) (xy 302.083361 -301.288316) (xy 302.053796 -301.32766)
			(xy 302.018303 -301.361752) (xy 301.9778 -301.389708) (xy 301.933338 -301.410806) (xy 301.886067 -301.424498)
			(xy 301.837212 -301.43043) (xy 301.788037 -301.428449) (xy 301.739818 -301.418605) (xy 301.693802 -301.401153)
			(xy 301.651181 -301.376546) (xy 301.61306 -301.345421) (xy 301.580425 -301.308584) (xy 301.554122 -301.266988)
			(xy 301.534831 -301.221712) (xy 301.523054 -301.173928) (xy 301.519094 -301.124874) (xy 301.179992 -301.124874)
			(xy 301.179497 -301.149481) (xy 301.171602 -301.198058) (xy 301.156018 -301.244739) (xy 301.133147 -301.288316)
			(xy 301.103582 -301.32766) (xy 301.068089 -301.361752) (xy 301.027586 -301.389708) (xy 300.983124 -301.410806)
			(xy 300.935853 -301.424498) (xy 300.886998 -301.43043) (xy 300.837823 -301.428449) (xy 300.789604 -301.418605)
			(xy 300.743588 -301.401153) (xy 300.700967 -301.376546) (xy 300.662846 -301.345421) (xy 300.630211 -301.308584)
			(xy 300.603908 -301.266988) (xy 300.584617 -301.221712) (xy 300.57284 -301.173928) (xy 300.56888 -301.124874)
			(xy 300.230032 -301.124874) (xy 300.229537 -301.149481) (xy 300.221642 -301.198058) (xy 300.206058 -301.244739)
			(xy 300.183187 -301.288316) (xy 300.153622 -301.32766) (xy 300.118129 -301.361752) (xy 300.077626 -301.389708)
			(xy 300.033164 -301.410806) (xy 299.985893 -301.424498) (xy 299.937038 -301.43043) (xy 299.887863 -301.428449)
			(xy 299.839644 -301.418605) (xy 299.793628 -301.401153) (xy 299.751007 -301.376546) (xy 299.712886 -301.345421)
			(xy 299.680251 -301.308584) (xy 299.653948 -301.266988) (xy 299.634657 -301.221712) (xy 299.62288 -301.173928)
			(xy 299.61892 -301.124874) (xy 299.280072 -301.124874) (xy 299.279577 -301.149481) (xy 299.271682 -301.198058)
			(xy 299.256098 -301.244739) (xy 299.233227 -301.288316) (xy 299.203662 -301.32766) (xy 299.168169 -301.361752)
			(xy 299.127666 -301.389708) (xy 299.083204 -301.410806) (xy 299.035933 -301.424498) (xy 298.987078 -301.43043)
			(xy 298.937903 -301.428449) (xy 298.889684 -301.418605) (xy 298.843668 -301.401153) (xy 298.801047 -301.376546)
			(xy 298.762926 -301.345421) (xy 298.730291 -301.308584) (xy 298.703988 -301.266988) (xy 298.684697 -301.221712)
			(xy 298.67292 -301.173928) (xy 298.66896 -301.124874) (xy 298.330112 -301.124874) (xy 298.329617 -301.149481)
			(xy 298.321722 -301.198058) (xy 298.306138 -301.244739) (xy 298.283267 -301.288316) (xy 298.253702 -301.32766)
			(xy 298.218209 -301.361752) (xy 298.177706 -301.389708) (xy 298.133244 -301.410806) (xy 298.085973 -301.424498)
			(xy 298.037118 -301.43043) (xy 297.987943 -301.428449) (xy 297.939724 -301.418605) (xy 297.893708 -301.401153)
			(xy 297.851087 -301.376546) (xy 297.812966 -301.345421) (xy 297.780331 -301.308584) (xy 297.754028 -301.266988)
			(xy 297.734737 -301.221712) (xy 297.72296 -301.173928) (xy 297.719 -301.124874) (xy 297.380152 -301.124874)
			(xy 297.379657 -301.149481) (xy 297.371762 -301.198058) (xy 297.356178 -301.244739) (xy 297.333307 -301.288316)
			(xy 297.303742 -301.32766) (xy 297.268249 -301.361752) (xy 297.227746 -301.389708) (xy 297.183284 -301.410806)
			(xy 297.136013 -301.424498) (xy 297.087158 -301.43043) (xy 297.037983 -301.428449) (xy 296.989764 -301.418605)
			(xy 296.943748 -301.401153) (xy 296.901127 -301.376546) (xy 296.863006 -301.345421) (xy 296.830371 -301.308584)
			(xy 296.804068 -301.266988) (xy 296.784777 -301.221712) (xy 296.773 -301.173928) (xy 296.76904 -301.124874)
			(xy 296.430192 -301.124874) (xy 296.429697 -301.149481) (xy 296.421802 -301.198058) (xy 296.406218 -301.244739)
			(xy 296.383347 -301.288316) (xy 296.353782 -301.32766) (xy 296.318289 -301.361752) (xy 296.277786 -301.389708)
			(xy 296.233324 -301.410806) (xy 296.186053 -301.424498) (xy 296.137198 -301.43043) (xy 296.088023 -301.428449)
			(xy 296.039804 -301.418605) (xy 295.993788 -301.401153) (xy 295.951167 -301.376546) (xy 295.913046 -301.345421)
			(xy 295.880411 -301.308584) (xy 295.854108 -301.266988) (xy 295.834817 -301.221712) (xy 295.82304 -301.173928)
			(xy 295.81908 -301.124874) (xy 295.480232 -301.124874) (xy 295.479737 -301.149481) (xy 295.471842 -301.198058)
			(xy 295.456258 -301.244739) (xy 295.433387 -301.288316) (xy 295.403822 -301.32766) (xy 295.368329 -301.361752)
			(xy 295.327826 -301.389708) (xy 295.283364 -301.410806) (xy 295.236093 -301.424498) (xy 295.187238 -301.43043)
			(xy 295.138063 -301.428449) (xy 295.089844 -301.418605) (xy 295.043828 -301.401153) (xy 295.001207 -301.376546)
			(xy 294.963086 -301.345421) (xy 294.930451 -301.308584) (xy 294.904148 -301.266988) (xy 294.884857 -301.221712)
			(xy 294.87308 -301.173928) (xy 294.86912 -301.124874) (xy 294.530018 -301.124874) (xy 294.529523 -301.149481)
			(xy 294.521628 -301.198058) (xy 294.506044 -301.244739) (xy 294.483173 -301.288316) (xy 294.453608 -301.32766)
			(xy 294.418115 -301.361752) (xy 294.377612 -301.389708) (xy 294.33315 -301.410806) (xy 294.285879 -301.424498)
			(xy 294.237024 -301.43043) (xy 294.187849 -301.428449) (xy 294.13963 -301.418605) (xy 294.093614 -301.401153)
			(xy 294.050993 -301.376546) (xy 294.012872 -301.345421) (xy 293.980237 -301.308584) (xy 293.953934 -301.266988)
			(xy 293.934643 -301.221712) (xy 293.922866 -301.173928) (xy 293.918906 -301.124874) (xy 293.580058 -301.124874)
			(xy 293.579563 -301.149481) (xy 293.571668 -301.198058) (xy 293.556084 -301.244739) (xy 293.533213 -301.288316)
			(xy 293.503648 -301.32766) (xy 293.468155 -301.361752) (xy 293.427652 -301.389708) (xy 293.38319 -301.410806)
			(xy 293.335919 -301.424498) (xy 293.287064 -301.43043) (xy 293.237889 -301.428449) (xy 293.18967 -301.418605)
			(xy 293.143654 -301.401153) (xy 293.101033 -301.376546) (xy 293.062912 -301.345421) (xy 293.030277 -301.308584)
			(xy 293.003974 -301.266988) (xy 292.984683 -301.221712) (xy 292.972906 -301.173928) (xy 292.968946 -301.124874)
			(xy 292.630098 -301.124874) (xy 292.629603 -301.149481) (xy 292.621708 -301.198058) (xy 292.606124 -301.244739)
			(xy 292.583253 -301.288316) (xy 292.553688 -301.32766) (xy 292.518195 -301.361752) (xy 292.477692 -301.389708)
			(xy 292.43323 -301.410806) (xy 292.385959 -301.424498) (xy 292.337104 -301.43043) (xy 292.287929 -301.428449)
			(xy 292.23971 -301.418605) (xy 292.193694 -301.401153) (xy 292.151073 -301.376546) (xy 292.112952 -301.345421)
			(xy 292.080317 -301.308584) (xy 292.054014 -301.266988) (xy 292.034723 -301.221712) (xy 292.022946 -301.173928)
			(xy 292.018986 -301.124874) (xy 290.730178 -301.124874) (xy 290.729683 -301.149481) (xy 290.721788 -301.198058)
			(xy 290.706204 -301.244739) (xy 290.683333 -301.288316) (xy 290.653768 -301.32766) (xy 290.618275 -301.361752)
			(xy 290.577772 -301.389708) (xy 290.53331 -301.410806) (xy 290.486039 -301.424498) (xy 290.437184 -301.43043)
			(xy 290.388009 -301.428449) (xy 290.33979 -301.418605) (xy 290.293774 -301.401153) (xy 290.251153 -301.376546)
			(xy 290.213032 -301.345421) (xy 290.180397 -301.308584) (xy 290.154094 -301.266988) (xy 290.134803 -301.221712)
			(xy 290.123026 -301.173928) (xy 290.119066 -301.124874) (xy 289.780218 -301.124874) (xy 289.779723 -301.149481)
			(xy 289.771828 -301.198058) (xy 289.756244 -301.244739) (xy 289.733373 -301.288316) (xy 289.703808 -301.32766)
			(xy 289.668315 -301.361752) (xy 289.627812 -301.389708) (xy 289.58335 -301.410806) (xy 289.536079 -301.424498)
			(xy 289.487224 -301.43043) (xy 289.438049 -301.428449) (xy 289.38983 -301.418605) (xy 289.343814 -301.401153)
			(xy 289.301193 -301.376546) (xy 289.263072 -301.345421) (xy 289.230437 -301.308584) (xy 289.204134 -301.266988)
			(xy 289.184843 -301.221712) (xy 289.173066 -301.173928) (xy 289.169106 -301.124874) (xy 288.830004 -301.124874)
			(xy 288.829509 -301.149481) (xy 288.821614 -301.198058) (xy 288.80603 -301.244739) (xy 288.783159 -301.288316)
			(xy 288.753594 -301.32766) (xy 288.718101 -301.361752) (xy 288.677598 -301.389708) (xy 288.633136 -301.410806)
			(xy 288.585865 -301.424498) (xy 288.53701 -301.43043) (xy 288.487835 -301.428449) (xy 288.439616 -301.418605)
			(xy 288.3936 -301.401153) (xy 288.350979 -301.376546) (xy 288.312858 -301.345421) (xy 288.280223 -301.308584)
			(xy 288.25392 -301.266988) (xy 288.234629 -301.221712) (xy 288.222852 -301.173928) (xy 288.218892 -301.124874)
			(xy 287.880044 -301.124874) (xy 287.879549 -301.149481) (xy 287.871654 -301.198058) (xy 287.85607 -301.244739)
			(xy 287.833199 -301.288316) (xy 287.803634 -301.32766) (xy 287.768141 -301.361752) (xy 287.727638 -301.389708)
			(xy 287.683176 -301.410806) (xy 287.635905 -301.424498) (xy 287.58705 -301.43043) (xy 287.537875 -301.428449)
			(xy 287.489656 -301.418605) (xy 287.44364 -301.401153) (xy 287.401019 -301.376546) (xy 287.362898 -301.345421)
			(xy 287.330263 -301.308584) (xy 287.30396 -301.266988) (xy 287.284669 -301.221712) (xy 287.272892 -301.173928)
			(xy 287.268932 -301.124874) (xy 286.930084 -301.124874) (xy 286.929589 -301.149481) (xy 286.921694 -301.198058)
			(xy 286.90611 -301.244739) (xy 286.883239 -301.288316) (xy 286.853674 -301.32766) (xy 286.818181 -301.361752)
			(xy 286.777678 -301.389708) (xy 286.733216 -301.410806) (xy 286.685945 -301.424498) (xy 286.63709 -301.43043)
			(xy 286.587915 -301.428449) (xy 286.539696 -301.418605) (xy 286.49368 -301.401153) (xy 286.451059 -301.376546)
			(xy 286.412938 -301.345421) (xy 286.380303 -301.308584) (xy 286.354 -301.266988) (xy 286.334709 -301.221712)
			(xy 286.322932 -301.173928) (xy 286.318972 -301.124874) (xy 285.980124 -301.124874) (xy 285.979629 -301.149481)
			(xy 285.971734 -301.198058) (xy 285.95615 -301.244739) (xy 285.933279 -301.288316) (xy 285.903714 -301.32766)
			(xy 285.868221 -301.361752) (xy 285.827718 -301.389708) (xy 285.783256 -301.410806) (xy 285.735985 -301.424498)
			(xy 285.68713 -301.43043) (xy 285.637955 -301.428449) (xy 285.589736 -301.418605) (xy 285.54372 -301.401153)
			(xy 285.501099 -301.376546) (xy 285.462978 -301.345421) (xy 285.430343 -301.308584) (xy 285.40404 -301.266988)
			(xy 285.384749 -301.221712) (xy 285.372972 -301.173928) (xy 285.369012 -301.124874) (xy 285.030164 -301.124874)
			(xy 285.029669 -301.149481) (xy 285.021774 -301.198058) (xy 285.00619 -301.244739) (xy 284.983319 -301.288316)
			(xy 284.953754 -301.32766) (xy 284.918261 -301.361752) (xy 284.877758 -301.389708) (xy 284.833296 -301.410806)
			(xy 284.786025 -301.424498) (xy 284.73717 -301.43043) (xy 284.687995 -301.428449) (xy 284.639776 -301.418605)
			(xy 284.59376 -301.401153) (xy 284.551139 -301.376546) (xy 284.513018 -301.345421) (xy 284.480383 -301.308584)
			(xy 284.45408 -301.266988) (xy 284.434789 -301.221712) (xy 284.423012 -301.173928) (xy 284.419052 -301.124874)
			(xy 284.080204 -301.124874) (xy 284.079709 -301.149481) (xy 284.071814 -301.198058) (xy 284.05623 -301.244739)
			(xy 284.033359 -301.288316) (xy 284.003794 -301.32766) (xy 283.968301 -301.361752) (xy 283.927798 -301.389708)
			(xy 283.883336 -301.410806) (xy 283.836065 -301.424498) (xy 283.78721 -301.43043) (xy 283.738035 -301.428449)
			(xy 283.689816 -301.418605) (xy 283.6438 -301.401153) (xy 283.601179 -301.376546) (xy 283.563058 -301.345421)
			(xy 283.530423 -301.308584) (xy 283.50412 -301.266988) (xy 283.484829 -301.221712) (xy 283.473052 -301.173928)
			(xy 283.469092 -301.124874) (xy 283.130244 -301.124874) (xy 283.129749 -301.149481) (xy 283.121854 -301.198058)
			(xy 283.10627 -301.244739) (xy 283.083399 -301.288316) (xy 283.053834 -301.32766) (xy 283.018341 -301.361752)
			(xy 282.977838 -301.389708) (xy 282.933376 -301.410806) (xy 282.886105 -301.424498) (xy 282.83725 -301.43043)
			(xy 282.788075 -301.428449) (xy 282.739856 -301.418605) (xy 282.69384 -301.401153) (xy 282.651219 -301.376546)
			(xy 282.613098 -301.345421) (xy 282.580463 -301.308584) (xy 282.55416 -301.266988) (xy 282.534869 -301.221712)
			(xy 282.523092 -301.173928) (xy 282.519132 -301.124874) (xy 282.180555 -301.124874) (xy 282.180557 -301.1249)
			(xy 282.176386 -301.17524) (xy 282.163986 -301.224207) (xy 282.143697 -301.270466) (xy 282.11607 -301.312754)
			(xy 282.08186 -301.349918) (xy 282.042 -301.380946) (xy 281.997576 -301.404989) (xy 281.949801 -301.421393)
			(xy 281.899978 -301.429711) (xy 281.874722 -301.430182) (xy 281.844648 -301.429489) (xy 281.785662 -301.417722)
			(xy 281.757628 -301.406814) (xy 281.745436 -301.401734) (xy 281.720544 -301.404274) (xy 281.639518 -301.458376)
			(xy 281.629458 -301.465894) (xy 281.6176 -301.488) (xy 281.616912 -301.50054) (xy 281.616912 -301.699168)
			(xy 281.617547 -301.711728) (xy 281.629395 -301.733874) (xy 281.639518 -301.741332) (xy 281.720544 -301.795434)
			(xy 281.745436 -301.797974) (xy 281.757628 -301.792894) (xy 281.785665 -301.781995) (xy 281.844649 -301.770229)
			(xy 281.874722 -301.769526) (xy 281.899973 -301.770049) (xy 281.949787 -301.778365) (xy 281.997552 -301.794766)
			(xy 282.041967 -301.818805) (xy 282.081819 -301.849826) (xy 282.116023 -301.886983) (xy 282.143644 -301.929263)
			(xy 282.16393 -301.975512) (xy 282.176327 -302.02447) (xy 282.180497 -302.0748) (xy 282.180494 -302.074834)
			(xy 282.519132 -302.074834) (xy 282.523092 -302.02578) (xy 282.534869 -301.977996) (xy 282.55416 -301.93272)
			(xy 282.580463 -301.891124) (xy 282.613098 -301.854287) (xy 282.651219 -301.823162) (xy 282.69384 -301.798555)
			(xy 282.739856 -301.781103) (xy 282.788075 -301.771259) (xy 282.83725 -301.769278) (xy 282.886105 -301.77521)
			(xy 282.933376 -301.788902) (xy 282.977838 -301.81) (xy 283.018341 -301.837956) (xy 283.053834 -301.872048)
			(xy 283.083399 -301.911392) (xy 283.10627 -301.954969) (xy 283.121854 -302.00165) (xy 283.129749 -302.050227)
			(xy 283.130244 -302.074834) (xy 283.469092 -302.074834) (xy 283.473052 -302.02578) (xy 283.484829 -301.977996)
			(xy 283.50412 -301.93272) (xy 283.530423 -301.891124) (xy 283.563058 -301.854287) (xy 283.601179 -301.823162)
			(xy 283.6438 -301.798555) (xy 283.689816 -301.781103) (xy 283.738035 -301.771259) (xy 283.78721 -301.769278)
			(xy 283.836065 -301.77521) (xy 283.883336 -301.788902) (xy 283.927798 -301.81) (xy 283.968301 -301.837956)
			(xy 284.003794 -301.872048) (xy 284.033359 -301.911392) (xy 284.05623 -301.954969) (xy 284.071814 -302.00165)
			(xy 284.079709 -302.050227) (xy 284.080204 -302.074834) (xy 284.419052 -302.074834) (xy 284.423012 -302.02578)
			(xy 284.434789 -301.977996) (xy 284.45408 -301.93272) (xy 284.480383 -301.891124) (xy 284.513018 -301.854287)
			(xy 284.551139 -301.823162) (xy 284.59376 -301.798555) (xy 284.639776 -301.781103) (xy 284.687995 -301.771259)
			(xy 284.73717 -301.769278) (xy 284.786025 -301.77521) (xy 284.833296 -301.788902) (xy 284.877758 -301.81)
			(xy 284.918261 -301.837956) (xy 284.953754 -301.872048) (xy 284.983319 -301.911392) (xy 285.00619 -301.954969)
			(xy 285.021774 -302.00165) (xy 285.029669 -302.050227) (xy 285.030164 -302.074834) (xy 285.369012 -302.074834)
			(xy 285.372972 -302.02578) (xy 285.384749 -301.977996) (xy 285.40404 -301.93272) (xy 285.430343 -301.891124)
			(xy 285.462978 -301.854287) (xy 285.501099 -301.823162) (xy 285.54372 -301.798555) (xy 285.589736 -301.781103)
			(xy 285.637955 -301.771259) (xy 285.68713 -301.769278) (xy 285.735985 -301.77521) (xy 285.783256 -301.788902)
			(xy 285.827718 -301.81) (xy 285.868221 -301.837956) (xy 285.903714 -301.872048) (xy 285.933279 -301.911392)
			(xy 285.95615 -301.954969) (xy 285.971734 -302.00165) (xy 285.979629 -302.050227) (xy 285.980124 -302.074834)
			(xy 286.318972 -302.074834) (xy 286.322932 -302.02578) (xy 286.334709 -301.977996) (xy 286.354 -301.93272)
			(xy 286.380303 -301.891124) (xy 286.412938 -301.854287) (xy 286.451059 -301.823162) (xy 286.49368 -301.798555)
			(xy 286.539696 -301.781103) (xy 286.587915 -301.771259) (xy 286.63709 -301.769278) (xy 286.685945 -301.77521)
			(xy 286.733216 -301.788902) (xy 286.777678 -301.81) (xy 286.818181 -301.837956) (xy 286.853674 -301.872048)
			(xy 286.883239 -301.911392) (xy 286.90611 -301.954969) (xy 286.921694 -302.00165) (xy 286.929589 -302.050227)
			(xy 286.930084 -302.074834) (xy 287.268932 -302.074834) (xy 287.272892 -302.02578) (xy 287.284669 -301.977996)
			(xy 287.30396 -301.93272) (xy 287.330263 -301.891124) (xy 287.362898 -301.854287) (xy 287.401019 -301.823162)
			(xy 287.44364 -301.798555) (xy 287.489656 -301.781103) (xy 287.537875 -301.771259) (xy 287.58705 -301.769278)
			(xy 287.635905 -301.77521) (xy 287.683176 -301.788902) (xy 287.727638 -301.81) (xy 287.768141 -301.837956)
			(xy 287.803634 -301.872048) (xy 287.833199 -301.911392) (xy 287.85607 -301.954969) (xy 287.871654 -302.00165)
			(xy 287.879549 -302.050227) (xy 287.880044 -302.074834) (xy 288.218892 -302.074834) (xy 288.222852 -302.02578)
			(xy 288.234629 -301.977996) (xy 288.25392 -301.93272) (xy 288.280223 -301.891124) (xy 288.312858 -301.854287)
			(xy 288.350979 -301.823162) (xy 288.3936 -301.798555) (xy 288.439616 -301.781103) (xy 288.487835 -301.771259)
			(xy 288.53701 -301.769278) (xy 288.585865 -301.77521) (xy 288.633136 -301.788902) (xy 288.677598 -301.81)
			(xy 288.718101 -301.837956) (xy 288.753594 -301.872048) (xy 288.783159 -301.911392) (xy 288.80603 -301.954969)
			(xy 288.821614 -302.00165) (xy 288.829509 -302.050227) (xy 288.830004 -302.074834) (xy 289.169106 -302.074834)
			(xy 289.173066 -302.02578) (xy 289.184843 -301.977996) (xy 289.204134 -301.93272) (xy 289.230437 -301.891124)
			(xy 289.263072 -301.854287) (xy 289.301193 -301.823162) (xy 289.343814 -301.798555) (xy 289.38983 -301.781103)
			(xy 289.438049 -301.771259) (xy 289.487224 -301.769278) (xy 289.536079 -301.77521) (xy 289.58335 -301.788902)
			(xy 289.627812 -301.81) (xy 289.668315 -301.837956) (xy 289.703808 -301.872048) (xy 289.733373 -301.911392)
			(xy 289.756244 -301.954969) (xy 289.771828 -302.00165) (xy 289.779723 -302.050227) (xy 289.780218 -302.074834)
			(xy 290.119066 -302.074834) (xy 290.123026 -302.02578) (xy 290.134803 -301.977996) (xy 290.154094 -301.93272)
			(xy 290.180397 -301.891124) (xy 290.213032 -301.854287) (xy 290.251153 -301.823162) (xy 290.293774 -301.798555)
			(xy 290.33979 -301.781103) (xy 290.388009 -301.771259) (xy 290.437184 -301.769278) (xy 290.486039 -301.77521)
			(xy 290.53331 -301.788902) (xy 290.577772 -301.81) (xy 290.618275 -301.837956) (xy 290.653768 -301.872048)
			(xy 290.683333 -301.911392) (xy 290.706204 -301.954969) (xy 290.721788 -302.00165) (xy 290.729683 -302.050227)
			(xy 290.730178 -302.074834) (xy 292.018986 -302.074834) (xy 292.022946 -302.02578) (xy 292.034723 -301.977996)
			(xy 292.054014 -301.93272) (xy 292.080317 -301.891124) (xy 292.112952 -301.854287) (xy 292.151073 -301.823162)
			(xy 292.193694 -301.798555) (xy 292.23971 -301.781103) (xy 292.287929 -301.771259) (xy 292.337104 -301.769278)
			(xy 292.385959 -301.77521) (xy 292.43323 -301.788902) (xy 292.477692 -301.81) (xy 292.518195 -301.837956)
			(xy 292.553688 -301.872048) (xy 292.583253 -301.911392) (xy 292.606124 -301.954969) (xy 292.621708 -302.00165)
			(xy 292.629603 -302.050227) (xy 292.630098 -302.074834) (xy 292.968946 -302.074834) (xy 292.972906 -302.02578)
			(xy 292.984683 -301.977996) (xy 293.003974 -301.93272) (xy 293.030277 -301.891124) (xy 293.062912 -301.854287)
			(xy 293.101033 -301.823162) (xy 293.143654 -301.798555) (xy 293.18967 -301.781103) (xy 293.237889 -301.771259)
			(xy 293.287064 -301.769278) (xy 293.335919 -301.77521) (xy 293.38319 -301.788902) (xy 293.427652 -301.81)
			(xy 293.468155 -301.837956) (xy 293.503648 -301.872048) (xy 293.533213 -301.911392) (xy 293.556084 -301.954969)
			(xy 293.571668 -302.00165) (xy 293.579563 -302.050227) (xy 293.580058 -302.074834) (xy 293.918906 -302.074834)
			(xy 293.922866 -302.02578) (xy 293.934643 -301.977996) (xy 293.953934 -301.93272) (xy 293.980237 -301.891124)
			(xy 294.012872 -301.854287) (xy 294.050993 -301.823162) (xy 294.093614 -301.798555) (xy 294.13963 -301.781103)
			(xy 294.187849 -301.771259) (xy 294.237024 -301.769278) (xy 294.285879 -301.77521) (xy 294.33315 -301.788902)
			(xy 294.377612 -301.81) (xy 294.418115 -301.837956) (xy 294.453608 -301.872048) (xy 294.483173 -301.911392)
			(xy 294.506044 -301.954969) (xy 294.521628 -302.00165) (xy 294.529523 -302.050227) (xy 294.530018 -302.074834)
			(xy 294.86912 -302.074834) (xy 294.87308 -302.02578) (xy 294.884857 -301.977996) (xy 294.904148 -301.93272)
			(xy 294.930451 -301.891124) (xy 294.963086 -301.854287) (xy 295.001207 -301.823162) (xy 295.043828 -301.798555)
			(xy 295.089844 -301.781103) (xy 295.138063 -301.771259) (xy 295.187238 -301.769278) (xy 295.236093 -301.77521)
			(xy 295.283364 -301.788902) (xy 295.327826 -301.81) (xy 295.368329 -301.837956) (xy 295.403822 -301.872048)
			(xy 295.433387 -301.911392) (xy 295.456258 -301.954969) (xy 295.471842 -302.00165) (xy 295.479737 -302.050227)
			(xy 295.480232 -302.074834) (xy 295.81908 -302.074834) (xy 295.82304 -302.02578) (xy 295.834817 -301.977996)
			(xy 295.854108 -301.93272) (xy 295.880411 -301.891124) (xy 295.913046 -301.854287) (xy 295.951167 -301.823162)
			(xy 295.993788 -301.798555) (xy 296.039804 -301.781103) (xy 296.088023 -301.771259) (xy 296.137198 -301.769278)
			(xy 296.186053 -301.77521) (xy 296.233324 -301.788902) (xy 296.277786 -301.81) (xy 296.318289 -301.837956)
			(xy 296.353782 -301.872048) (xy 296.383347 -301.911392) (xy 296.406218 -301.954969) (xy 296.421802 -302.00165)
			(xy 296.429697 -302.050227) (xy 296.430192 -302.074834) (xy 296.76904 -302.074834) (xy 296.773 -302.02578)
			(xy 296.784777 -301.977996) (xy 296.804068 -301.93272) (xy 296.830371 -301.891124) (xy 296.863006 -301.854287)
			(xy 296.901127 -301.823162) (xy 296.943748 -301.798555) (xy 296.989764 -301.781103) (xy 297.037983 -301.771259)
			(xy 297.087158 -301.769278) (xy 297.136013 -301.77521) (xy 297.183284 -301.788902) (xy 297.227746 -301.81)
			(xy 297.268249 -301.837956) (xy 297.303742 -301.872048) (xy 297.333307 -301.911392) (xy 297.356178 -301.954969)
			(xy 297.371762 -302.00165) (xy 297.379657 -302.050227) (xy 297.380152 -302.074834) (xy 297.719 -302.074834)
			(xy 297.72296 -302.02578) (xy 297.734737 -301.977996) (xy 297.754028 -301.93272) (xy 297.780331 -301.891124)
			(xy 297.812966 -301.854287) (xy 297.851087 -301.823162) (xy 297.893708 -301.798555) (xy 297.939724 -301.781103)
			(xy 297.987943 -301.771259) (xy 298.037118 -301.769278) (xy 298.085973 -301.77521) (xy 298.133244 -301.788902)
			(xy 298.177706 -301.81) (xy 298.218209 -301.837956) (xy 298.253702 -301.872048) (xy 298.283267 -301.911392)
			(xy 298.306138 -301.954969) (xy 298.321722 -302.00165) (xy 298.329617 -302.050227) (xy 298.330112 -302.074834)
			(xy 298.66896 -302.074834) (xy 298.67292 -302.02578) (xy 298.684697 -301.977996) (xy 298.703988 -301.93272)
			(xy 298.730291 -301.891124) (xy 298.762926 -301.854287) (xy 298.801047 -301.823162) (xy 298.843668 -301.798555)
			(xy 298.889684 -301.781103) (xy 298.937903 -301.771259) (xy 298.987078 -301.769278) (xy 299.035933 -301.77521)
			(xy 299.083204 -301.788902) (xy 299.127666 -301.81) (xy 299.168169 -301.837956) (xy 299.203662 -301.872048)
			(xy 299.233227 -301.911392) (xy 299.256098 -301.954969) (xy 299.271682 -302.00165) (xy 299.279577 -302.050227)
			(xy 299.280072 -302.074834) (xy 299.61892 -302.074834) (xy 299.62288 -302.02578) (xy 299.634657 -301.977996)
			(xy 299.653948 -301.93272) (xy 299.680251 -301.891124) (xy 299.712886 -301.854287) (xy 299.751007 -301.823162)
			(xy 299.793628 -301.798555) (xy 299.839644 -301.781103) (xy 299.887863 -301.771259) (xy 299.937038 -301.769278)
			(xy 299.985893 -301.77521) (xy 300.033164 -301.788902) (xy 300.077626 -301.81) (xy 300.118129 -301.837956)
			(xy 300.153622 -301.872048) (xy 300.183187 -301.911392) (xy 300.206058 -301.954969) (xy 300.221642 -302.00165)
			(xy 300.229537 -302.050227) (xy 300.230032 -302.074834) (xy 300.56888 -302.074834) (xy 300.57284 -302.02578)
			(xy 300.584617 -301.977996) (xy 300.603908 -301.93272) (xy 300.630211 -301.891124) (xy 300.662846 -301.854287)
			(xy 300.700967 -301.823162) (xy 300.743588 -301.798555) (xy 300.789604 -301.781103) (xy 300.837823 -301.771259)
			(xy 300.886998 -301.769278) (xy 300.935853 -301.77521) (xy 300.983124 -301.788902) (xy 301.027586 -301.81)
			(xy 301.068089 -301.837956) (xy 301.103582 -301.872048) (xy 301.133147 -301.911392) (xy 301.156018 -301.954969)
			(xy 301.171602 -302.00165) (xy 301.179497 -302.050227) (xy 301.179992 -302.074834) (xy 301.519094 -302.074834)
			(xy 301.523054 -302.02578) (xy 301.534831 -301.977996) (xy 301.554122 -301.93272) (xy 301.580425 -301.891124)
			(xy 301.61306 -301.854287) (xy 301.651181 -301.823162) (xy 301.693802 -301.798555) (xy 301.739818 -301.781103)
			(xy 301.788037 -301.771259) (xy 301.837212 -301.769278) (xy 301.886067 -301.77521) (xy 301.933338 -301.788902)
			(xy 301.9778 -301.81) (xy 302.018303 -301.837956) (xy 302.053796 -301.872048) (xy 302.083361 -301.911392)
			(xy 302.106232 -301.954969) (xy 302.121816 -302.00165) (xy 302.129711 -302.050227) (xy 302.130206 -302.074834)
			(xy 302.469054 -302.074834) (xy 302.473014 -302.02578) (xy 302.484791 -301.977996) (xy 302.504082 -301.93272)
			(xy 302.530385 -301.891124) (xy 302.56302 -301.854287) (xy 302.601141 -301.823162) (xy 302.643762 -301.798555)
			(xy 302.689778 -301.781103) (xy 302.737997 -301.771259) (xy 302.787172 -301.769278) (xy 302.836027 -301.77521)
			(xy 302.883298 -301.788902) (xy 302.92776 -301.81) (xy 302.968263 -301.837956) (xy 303.003756 -301.872048)
			(xy 303.033321 -301.911392) (xy 303.056192 -301.954969) (xy 303.071776 -302.00165) (xy 303.079671 -302.050227)
			(xy 303.080166 -302.074834) (xy 303.419014 -302.074834) (xy 303.422974 -302.02578) (xy 303.434751 -301.977996)
			(xy 303.454042 -301.93272) (xy 303.480345 -301.891124) (xy 303.51298 -301.854287) (xy 303.551101 -301.823162)
			(xy 303.593722 -301.798555) (xy 303.639738 -301.781103) (xy 303.687957 -301.771259) (xy 303.737132 -301.769278)
			(xy 303.785987 -301.77521) (xy 303.833258 -301.788902) (xy 303.87772 -301.81) (xy 303.918223 -301.837956)
			(xy 303.953716 -301.872048) (xy 303.983281 -301.911392) (xy 304.006152 -301.954969) (xy 304.021736 -302.00165)
			(xy 304.029631 -302.050227) (xy 304.030126 -302.074834) (xy 304.368974 -302.074834) (xy 304.372934 -302.02578)
			(xy 304.384711 -301.977996) (xy 304.404002 -301.93272) (xy 304.430305 -301.891124) (xy 304.46294 -301.854287)
			(xy 304.501061 -301.823162) (xy 304.543682 -301.798555) (xy 304.589698 -301.781103) (xy 304.637917 -301.771259)
			(xy 304.687092 -301.769278) (xy 304.735947 -301.77521) (xy 304.783218 -301.788902) (xy 304.82768 -301.81)
			(xy 304.868183 -301.837956) (xy 304.903676 -301.872048) (xy 304.933241 -301.911392) (xy 304.956112 -301.954969)
			(xy 304.971696 -302.00165) (xy 304.979591 -302.050227) (xy 304.980086 -302.074834) (xy 305.318934 -302.074834)
			(xy 305.322894 -302.02578) (xy 305.334671 -301.977996) (xy 305.353962 -301.93272) (xy 305.380265 -301.891124)
			(xy 305.4129 -301.854287) (xy 305.451021 -301.823162) (xy 305.493642 -301.798555) (xy 305.539658 -301.781103)
			(xy 305.587877 -301.771259) (xy 305.637052 -301.769278) (xy 305.685907 -301.77521) (xy 305.733178 -301.788902)
			(xy 305.77764 -301.81) (xy 305.818143 -301.837956) (xy 305.853636 -301.872048) (xy 305.883201 -301.911392)
			(xy 305.906072 -301.954969) (xy 305.921656 -302.00165) (xy 305.929551 -302.050227) (xy 305.930046 -302.074834)
			(xy 306.268894 -302.074834) (xy 306.272854 -302.02578) (xy 306.284631 -301.977996) (xy 306.303922 -301.93272)
			(xy 306.330225 -301.891124) (xy 306.36286 -301.854287) (xy 306.400981 -301.823162) (xy 306.443602 -301.798555)
			(xy 306.489618 -301.781103) (xy 306.537837 -301.771259) (xy 306.587012 -301.769278) (xy 306.635867 -301.77521)
			(xy 306.683138 -301.788902) (xy 306.7276 -301.81) (xy 306.768103 -301.837956) (xy 306.803596 -301.872048)
			(xy 306.833161 -301.911392) (xy 306.856032 -301.954969) (xy 306.871616 -302.00165) (xy 306.879511 -302.050227)
			(xy 306.880006 -302.074834) (xy 307.219108 -302.074834) (xy 307.223068 -302.02578) (xy 307.234845 -301.977996)
			(xy 307.254136 -301.93272) (xy 307.280439 -301.891124) (xy 307.313074 -301.854287) (xy 307.351195 -301.823162)
			(xy 307.393816 -301.798555) (xy 307.439832 -301.781103) (xy 307.488051 -301.771259) (xy 307.537226 -301.769278)
			(xy 307.586081 -301.77521) (xy 307.633352 -301.788902) (xy 307.677814 -301.81) (xy 307.718317 -301.837956)
			(xy 307.75381 -301.872048) (xy 307.783375 -301.911392) (xy 307.806246 -301.954969) (xy 307.82183 -302.00165)
			(xy 307.829725 -302.050227) (xy 307.83022 -302.074834) (xy 308.169068 -302.074834) (xy 308.173028 -302.02578)
			(xy 308.184805 -301.977996) (xy 308.204096 -301.93272) (xy 308.230399 -301.891124) (xy 308.263034 -301.854287)
			(xy 308.301155 -301.823162) (xy 308.343776 -301.798555) (xy 308.389792 -301.781103) (xy 308.438011 -301.771259)
			(xy 308.487186 -301.769278) (xy 308.536041 -301.77521) (xy 308.583312 -301.788902) (xy 308.627774 -301.81)
			(xy 308.668277 -301.837956) (xy 308.70377 -301.872048) (xy 308.733335 -301.911392) (xy 308.756206 -301.954969)
			(xy 308.77179 -302.00165) (xy 308.779685 -302.050227) (xy 308.78018 -302.074834) (xy 309.119028 -302.074834)
			(xy 309.122988 -302.02578) (xy 309.134765 -301.977996) (xy 309.154056 -301.93272) (xy 309.180359 -301.891124)
			(xy 309.212994 -301.854287) (xy 309.251115 -301.823162) (xy 309.293736 -301.798555) (xy 309.339752 -301.781103)
			(xy 309.387971 -301.771259) (xy 309.437146 -301.769278) (xy 309.486001 -301.77521) (xy 309.533272 -301.788902)
			(xy 309.577734 -301.81) (xy 309.618237 -301.837956) (xy 309.65373 -301.872048) (xy 309.683295 -301.911392)
			(xy 309.706166 -301.954969) (xy 309.72175 -302.00165) (xy 309.729645 -302.050227) (xy 309.73014 -302.074834)
			(xy 310.068988 -302.074834) (xy 310.072948 -302.02578) (xy 310.084725 -301.977996) (xy 310.104016 -301.93272)
			(xy 310.130319 -301.891124) (xy 310.162954 -301.854287) (xy 310.201075 -301.823162) (xy 310.243696 -301.798555)
			(xy 310.289712 -301.781103) (xy 310.337931 -301.771259) (xy 310.387106 -301.769278) (xy 310.435961 -301.77521)
			(xy 310.483232 -301.788902) (xy 310.527694 -301.81) (xy 310.568197 -301.837956) (xy 310.60369 -301.872048)
			(xy 310.633255 -301.911392) (xy 310.656126 -301.954969) (xy 310.67171 -302.00165) (xy 310.679605 -302.050227)
			(xy 310.6801 -302.074834) (xy 311.018948 -302.074834) (xy 311.022908 -302.02578) (xy 311.034685 -301.977996)
			(xy 311.053976 -301.93272) (xy 311.080279 -301.891124) (xy 311.112914 -301.854287) (xy 311.151035 -301.823162)
			(xy 311.193656 -301.798555) (xy 311.239672 -301.781103) (xy 311.287891 -301.771259) (xy 311.337066 -301.769278)
			(xy 311.385921 -301.77521) (xy 311.433192 -301.788902) (xy 311.477654 -301.81) (xy 311.518157 -301.837956)
			(xy 311.55365 -301.872048) (xy 311.583215 -301.911392) (xy 311.606086 -301.954969) (xy 311.62167 -302.00165)
			(xy 311.629565 -302.050227) (xy 311.63006 -302.074834) (xy 311.968908 -302.074834) (xy 311.972868 -302.02578)
			(xy 311.984645 -301.977996) (xy 312.003936 -301.93272) (xy 312.030239 -301.891124) (xy 312.062874 -301.854287)
			(xy 312.100995 -301.823162) (xy 312.143616 -301.798555) (xy 312.189632 -301.781103) (xy 312.237851 -301.771259)
			(xy 312.287026 -301.769278) (xy 312.335881 -301.77521) (xy 312.383152 -301.788902) (xy 312.427614 -301.81)
			(xy 312.468117 -301.837956) (xy 312.50361 -301.872048) (xy 312.533175 -301.911392) (xy 312.556046 -301.954969)
			(xy 312.57163 -302.00165) (xy 312.579525 -302.050227) (xy 312.58002 -302.074834) (xy 312.919122 -302.074834)
			(xy 312.923082 -302.02578) (xy 312.934859 -301.977996) (xy 312.95415 -301.93272) (xy 312.980453 -301.891124)
			(xy 313.013088 -301.854287) (xy 313.051209 -301.823162) (xy 313.09383 -301.798555) (xy 313.139846 -301.781103)
			(xy 313.188065 -301.771259) (xy 313.23724 -301.769278) (xy 313.286095 -301.77521) (xy 313.333366 -301.788902)
			(xy 313.377828 -301.81) (xy 313.418331 -301.837956) (xy 313.453824 -301.872048) (xy 313.483389 -301.911392)
			(xy 313.50626 -301.954969) (xy 313.521844 -302.00165) (xy 313.529739 -302.050227) (xy 313.530234 -302.074834)
			(xy 313.869082 -302.074834) (xy 313.873042 -302.02578) (xy 313.884819 -301.977996) (xy 313.90411 -301.93272)
			(xy 313.930413 -301.891124) (xy 313.963048 -301.854287) (xy 314.001169 -301.823162) (xy 314.04379 -301.798555)
			(xy 314.089806 -301.781103) (xy 314.138025 -301.771259) (xy 314.1872 -301.769278) (xy 314.236055 -301.77521)
			(xy 314.283326 -301.788902) (xy 314.327788 -301.81) (xy 314.368291 -301.837956) (xy 314.403784 -301.872048)
			(xy 314.433349 -301.911392) (xy 314.45622 -301.954969) (xy 314.471804 -302.00165) (xy 314.479699 -302.050227)
			(xy 314.480194 -302.074834) (xy 314.819042 -302.074834) (xy 314.823002 -302.02578) (xy 314.834779 -301.977996)
			(xy 314.85407 -301.93272) (xy 314.880373 -301.891124) (xy 314.913008 -301.854287) (xy 314.951129 -301.823162)
			(xy 314.99375 -301.798555) (xy 315.039766 -301.781103) (xy 315.087985 -301.771259) (xy 315.13716 -301.769278)
			(xy 315.186015 -301.77521) (xy 315.233286 -301.788902) (xy 315.277748 -301.81) (xy 315.318251 -301.837956)
			(xy 315.348333 -301.866851) (xy 318.548485 -301.866851) (xy 318.548485 -301.812349) (xy 318.556242 -301.758401)
			(xy 318.571597 -301.706106) (xy 318.594239 -301.656529) (xy 318.623706 -301.610679) (xy 318.659398 -301.569489)
			(xy 318.700589 -301.533799) (xy 318.74644 -301.504333) (xy 318.796018 -301.481693) (xy 318.848313 -301.466339)
			(xy 318.902261 -301.458584) (xy 318.929512 -301.458122) (xy 318.958713 -301.458699) (xy 319.016433 -301.467594)
			(xy 319.07212 -301.485191) (xy 319.124471 -301.511077) (xy 319.17226 -301.544646) (xy 319.214369 -301.585112)
			(xy 319.232534 -301.607982) (xy 319.241381 -301.618749) (xy 319.263653 -301.63548) (xy 319.289615 -301.645572)
			(xy 319.317339 -301.648275) (xy 319.344762 -301.64339) (xy 319.369846 -301.631278) (xy 319.390726 -301.61284)
			(xy 319.39865 -301.601378) (xy 319.413795 -301.57882) (xy 319.449486 -301.537853) (xy 319.490628 -301.502365)
			(xy 319.53639 -301.473073) (xy 319.585845 -301.450571) (xy 319.637993 -301.435314) (xy 319.691777 -301.427611)
			(xy 319.718944 -301.427134) (xy 319.746196 -301.427539) (xy 319.800145 -301.435301) (xy 319.85244 -301.450662)
			(xy 319.902017 -301.473308) (xy 319.947867 -301.502779) (xy 319.989057 -301.538474) (xy 320.001305 -301.55261)
			(xy 320.319652 -301.55261) (xy 320.323723 -301.496988) (xy 320.335849 -301.442551) (xy 320.355772 -301.39046)
			(xy 320.383068 -301.341825) (xy 320.417154 -301.297682) (xy 320.457303 -301.258973) (xy 320.502661 -301.226522)
			(xy 320.552261 -301.201021) (xy 320.605045 -301.183014) (xy 320.659888 -301.172884) (xy 320.715622 -301.170847)
			(xy 320.771059 -301.176947) (xy 320.825016 -301.191053) (xy 320.876345 -301.212865) (xy 320.923951 -301.241919)
			(xy 320.966819 -301.277594) (xy 321.004036 -301.319131) (xy 321.034809 -301.365644) (xy 321.058481 -301.416141)
			(xy 321.074549 -301.469548) (xy 321.082669 -301.524724) (xy 321.083178 -301.55261) (xy 321.083099 -301.556928)
			(xy 323.713092 -301.556928) (xy 323.717163 -301.501306) (xy 323.729289 -301.446869) (xy 323.749212 -301.394778)
			(xy 323.776508 -301.346143) (xy 323.810594 -301.302) (xy 323.850743 -301.263291) (xy 323.896101 -301.23084)
			(xy 323.945701 -301.205339) (xy 323.998485 -301.187332) (xy 324.053328 -301.177202) (xy 324.109062 -301.175165)
			(xy 324.164499 -301.181265) (xy 324.218456 -301.195371) (xy 324.269785 -301.217183) (xy 324.317391 -301.246237)
			(xy 324.360259 -301.281912) (xy 324.397476 -301.323449) (xy 324.428249 -301.369962) (xy 324.451921 -301.420459)
			(xy 324.467989 -301.473866) (xy 324.476109 -301.529042) (xy 324.476618 -301.556928) (xy 324.476109 -301.584814)
			(xy 324.467989 -301.63999) (xy 324.451921 -301.693397) (xy 324.428249 -301.743894) (xy 324.397476 -301.790407)
			(xy 324.360259 -301.831944) (xy 324.317391 -301.867619) (xy 324.269785 -301.896673) (xy 324.218456 -301.918485)
			(xy 324.164499 -301.932591) (xy 324.109062 -301.938691) (xy 324.053328 -301.936654) (xy 323.998485 -301.926524)
			(xy 323.945701 -301.908517) (xy 323.896101 -301.883016) (xy 323.850743 -301.850565) (xy 323.810594 -301.811856)
			(xy 323.776508 -301.767713) (xy 323.749212 -301.719078) (xy 323.729289 -301.666987) (xy 323.717163 -301.61255)
			(xy 323.713092 -301.556928) (xy 321.083099 -301.556928) (xy 321.082669 -301.580496) (xy 321.074549 -301.635672)
			(xy 321.058481 -301.689079) (xy 321.034809 -301.739576) (xy 321.004036 -301.786089) (xy 320.966819 -301.827626)
			(xy 320.923951 -301.863301) (xy 320.876345 -301.892355) (xy 320.825016 -301.914167) (xy 320.771059 -301.928273)
			(xy 320.715622 -301.934373) (xy 320.659888 -301.932336) (xy 320.605045 -301.922206) (xy 320.552261 -301.904199)
			(xy 320.502661 -301.878698) (xy 320.457303 -301.846247) (xy 320.417154 -301.807538) (xy 320.383068 -301.763395)
			(xy 320.355772 -301.71476) (xy 320.335849 -301.662669) (xy 320.323723 -301.608232) (xy 320.319652 -301.55261)
			(xy 320.001305 -301.55261) (xy 320.024748 -301.579668) (xy 320.054213 -301.625521) (xy 320.076853 -301.675101)
			(xy 320.092208 -301.727398) (xy 320.099964 -301.781348) (xy 320.099964 -301.835852) (xy 320.092208 -301.889802)
			(xy 320.076853 -301.942099) (xy 320.054213 -301.991679) (xy 320.024748 -302.037532) (xy 319.989057 -302.078726)
			(xy 319.947867 -302.114421) (xy 319.902017 -302.143892) (xy 319.85244 -302.166538) (xy 319.800145 -302.181899)
			(xy 319.746196 -302.189661) (xy 319.718944 -302.19015) (xy 319.689742 -302.189616) (xy 319.632019 -302.180713)
			(xy 319.576331 -302.163108) (xy 319.52398 -302.137215) (xy 319.476192 -302.103638) (xy 319.434085 -302.063164)
			(xy 319.415922 -302.04029) (xy 319.407123 -302.029481) (xy 319.384839 -302.012756) (xy 319.358866 -302.00267)
			(xy 319.331134 -301.999973) (xy 319.303704 -302.004866) (xy 319.278615 -302.016984) (xy 319.257731 -302.035429)
			(xy 319.249806 -302.046894) (xy 319.234649 -302.069443) (xy 319.198957 -302.110407) (xy 319.157816 -302.145893)
			(xy 319.112056 -302.175184) (xy 319.062604 -302.197688) (xy 319.01046 -302.212948) (xy 318.956678 -302.220658)
			(xy 318.929512 -302.221138) (xy 318.902261 -302.220616) (xy 318.848313 -302.212861) (xy 318.796018 -302.197507)
			(xy 318.74644 -302.174867) (xy 318.700589 -302.145401) (xy 318.659398 -302.109711) (xy 318.623706 -302.068521)
			(xy 318.594239 -302.022671) (xy 318.571597 -301.973094) (xy 318.556242 -301.920799) (xy 318.548485 -301.866851)
			(xy 315.348333 -301.866851) (xy 315.353744 -301.872048) (xy 315.383309 -301.911392) (xy 315.40618 -301.954969)
			(xy 315.421764 -302.00165) (xy 315.429659 -302.050227) (xy 315.430154 -302.074834) (xy 315.429659 -302.099441)
			(xy 315.421764 -302.148018) (xy 315.40618 -302.194699) (xy 315.383309 -302.238276) (xy 315.353744 -302.27762)
			(xy 315.318251 -302.311712) (xy 315.277748 -302.339668) (xy 315.233286 -302.360766) (xy 315.186015 -302.374458)
			(xy 315.13716 -302.38039) (xy 315.087985 -302.378409) (xy 315.039766 -302.368565) (xy 314.99375 -302.351113)
			(xy 314.951129 -302.326506) (xy 314.913008 -302.295381) (xy 314.880373 -302.258544) (xy 314.85407 -302.216948)
			(xy 314.834779 -302.171672) (xy 314.823002 -302.123888) (xy 314.819042 -302.074834) (xy 314.480194 -302.074834)
			(xy 314.479699 -302.099441) (xy 314.471804 -302.148018) (xy 314.45622 -302.194699) (xy 314.433349 -302.238276)
			(xy 314.403784 -302.27762) (xy 314.368291 -302.311712) (xy 314.327788 -302.339668) (xy 314.283326 -302.360766)
			(xy 314.236055 -302.374458) (xy 314.1872 -302.38039) (xy 314.138025 -302.378409) (xy 314.089806 -302.368565)
			(xy 314.04379 -302.351113) (xy 314.001169 -302.326506) (xy 313.963048 -302.295381) (xy 313.930413 -302.258544)
			(xy 313.90411 -302.216948) (xy 313.884819 -302.171672) (xy 313.873042 -302.123888) (xy 313.869082 -302.074834)
			(xy 313.530234 -302.074834) (xy 313.529739 -302.099441) (xy 313.521844 -302.148018) (xy 313.50626 -302.194699)
			(xy 313.483389 -302.238276) (xy 313.453824 -302.27762) (xy 313.418331 -302.311712) (xy 313.377828 -302.339668)
			(xy 313.333366 -302.360766) (xy 313.286095 -302.374458) (xy 313.23724 -302.38039) (xy 313.188065 -302.378409)
			(xy 313.139846 -302.368565) (xy 313.09383 -302.351113) (xy 313.051209 -302.326506) (xy 313.013088 -302.295381)
			(xy 312.980453 -302.258544) (xy 312.95415 -302.216948) (xy 312.934859 -302.171672) (xy 312.923082 -302.123888)
			(xy 312.919122 -302.074834) (xy 312.58002 -302.074834) (xy 312.579525 -302.099441) (xy 312.57163 -302.148018)
			(xy 312.556046 -302.194699) (xy 312.533175 -302.238276) (xy 312.50361 -302.27762) (xy 312.468117 -302.311712)
			(xy 312.427614 -302.339668) (xy 312.383152 -302.360766) (xy 312.335881 -302.374458) (xy 312.287026 -302.38039)
			(xy 312.237851 -302.378409) (xy 312.189632 -302.368565) (xy 312.143616 -302.351113) (xy 312.100995 -302.326506)
			(xy 312.062874 -302.295381) (xy 312.030239 -302.258544) (xy 312.003936 -302.216948) (xy 311.984645 -302.171672)
			(xy 311.972868 -302.123888) (xy 311.968908 -302.074834) (xy 311.63006 -302.074834) (xy 311.629565 -302.099441)
			(xy 311.62167 -302.148018) (xy 311.606086 -302.194699) (xy 311.583215 -302.238276) (xy 311.55365 -302.27762)
			(xy 311.518157 -302.311712) (xy 311.477654 -302.339668) (xy 311.433192 -302.360766) (xy 311.385921 -302.374458)
			(xy 311.337066 -302.38039) (xy 311.287891 -302.378409) (xy 311.239672 -302.368565) (xy 311.193656 -302.351113)
			(xy 311.151035 -302.326506) (xy 311.112914 -302.295381) (xy 311.080279 -302.258544) (xy 311.053976 -302.216948)
			(xy 311.034685 -302.171672) (xy 311.022908 -302.123888) (xy 311.018948 -302.074834) (xy 310.6801 -302.074834)
			(xy 310.679605 -302.099441) (xy 310.67171 -302.148018) (xy 310.656126 -302.194699) (xy 310.633255 -302.238276)
			(xy 310.60369 -302.27762) (xy 310.568197 -302.311712) (xy 310.527694 -302.339668) (xy 310.483232 -302.360766)
			(xy 310.435961 -302.374458) (xy 310.387106 -302.38039) (xy 310.337931 -302.378409) (xy 310.289712 -302.368565)
			(xy 310.243696 -302.351113) (xy 310.201075 -302.326506) (xy 310.162954 -302.295381) (xy 310.130319 -302.258544)
			(xy 310.104016 -302.216948) (xy 310.084725 -302.171672) (xy 310.072948 -302.123888) (xy 310.068988 -302.074834)
			(xy 309.73014 -302.074834) (xy 309.729645 -302.099441) (xy 309.72175 -302.148018) (xy 309.706166 -302.194699)
			(xy 309.683295 -302.238276) (xy 309.65373 -302.27762) (xy 309.618237 -302.311712) (xy 309.577734 -302.339668)
			(xy 309.533272 -302.360766) (xy 309.486001 -302.374458) (xy 309.437146 -302.38039) (xy 309.387971 -302.378409)
			(xy 309.339752 -302.368565) (xy 309.293736 -302.351113) (xy 309.251115 -302.326506) (xy 309.212994 -302.295381)
			(xy 309.180359 -302.258544) (xy 309.154056 -302.216948) (xy 309.134765 -302.171672) (xy 309.122988 -302.123888)
			(xy 309.119028 -302.074834) (xy 308.78018 -302.074834) (xy 308.779685 -302.099441) (xy 308.77179 -302.148018)
			(xy 308.756206 -302.194699) (xy 308.733335 -302.238276) (xy 308.70377 -302.27762) (xy 308.668277 -302.311712)
			(xy 308.627774 -302.339668) (xy 308.583312 -302.360766) (xy 308.536041 -302.374458) (xy 308.487186 -302.38039)
			(xy 308.438011 -302.378409) (xy 308.389792 -302.368565) (xy 308.343776 -302.351113) (xy 308.301155 -302.326506)
			(xy 308.263034 -302.295381) (xy 308.230399 -302.258544) (xy 308.204096 -302.216948) (xy 308.184805 -302.171672)
			(xy 308.173028 -302.123888) (xy 308.169068 -302.074834) (xy 307.83022 -302.074834) (xy 307.829725 -302.099441)
			(xy 307.82183 -302.148018) (xy 307.806246 -302.194699) (xy 307.783375 -302.238276) (xy 307.75381 -302.27762)
			(xy 307.718317 -302.311712) (xy 307.677814 -302.339668) (xy 307.633352 -302.360766) (xy 307.586081 -302.374458)
			(xy 307.537226 -302.38039) (xy 307.488051 -302.378409) (xy 307.439832 -302.368565) (xy 307.393816 -302.351113)
			(xy 307.351195 -302.326506) (xy 307.313074 -302.295381) (xy 307.280439 -302.258544) (xy 307.254136 -302.216948)
			(xy 307.234845 -302.171672) (xy 307.223068 -302.123888) (xy 307.219108 -302.074834) (xy 306.880006 -302.074834)
			(xy 306.879511 -302.099441) (xy 306.871616 -302.148018) (xy 306.856032 -302.194699) (xy 306.833161 -302.238276)
			(xy 306.803596 -302.27762) (xy 306.768103 -302.311712) (xy 306.7276 -302.339668) (xy 306.683138 -302.360766)
			(xy 306.635867 -302.374458) (xy 306.587012 -302.38039) (xy 306.537837 -302.378409) (xy 306.489618 -302.368565)
			(xy 306.443602 -302.351113) (xy 306.400981 -302.326506) (xy 306.36286 -302.295381) (xy 306.330225 -302.258544)
			(xy 306.303922 -302.216948) (xy 306.284631 -302.171672) (xy 306.272854 -302.123888) (xy 306.268894 -302.074834)
			(xy 305.930046 -302.074834) (xy 305.929551 -302.099441) (xy 305.921656 -302.148018) (xy 305.906072 -302.194699)
			(xy 305.883201 -302.238276) (xy 305.853636 -302.27762) (xy 305.818143 -302.311712) (xy 305.77764 -302.339668)
			(xy 305.733178 -302.360766) (xy 305.685907 -302.374458) (xy 305.637052 -302.38039) (xy 305.587877 -302.378409)
			(xy 305.539658 -302.368565) (xy 305.493642 -302.351113) (xy 305.451021 -302.326506) (xy 305.4129 -302.295381)
			(xy 305.380265 -302.258544) (xy 305.353962 -302.216948) (xy 305.334671 -302.171672) (xy 305.322894 -302.123888)
			(xy 305.318934 -302.074834) (xy 304.980086 -302.074834) (xy 304.979591 -302.099441) (xy 304.971696 -302.148018)
			(xy 304.956112 -302.194699) (xy 304.933241 -302.238276) (xy 304.903676 -302.27762) (xy 304.868183 -302.311712)
			(xy 304.82768 -302.339668) (xy 304.783218 -302.360766) (xy 304.735947 -302.374458) (xy 304.687092 -302.38039)
			(xy 304.637917 -302.378409) (xy 304.589698 -302.368565) (xy 304.543682 -302.351113) (xy 304.501061 -302.326506)
			(xy 304.46294 -302.295381) (xy 304.430305 -302.258544) (xy 304.404002 -302.216948) (xy 304.384711 -302.171672)
			(xy 304.372934 -302.123888) (xy 304.368974 -302.074834) (xy 304.030126 -302.074834) (xy 304.029631 -302.099441)
			(xy 304.021736 -302.148018) (xy 304.006152 -302.194699) (xy 303.983281 -302.238276) (xy 303.953716 -302.27762)
			(xy 303.918223 -302.311712) (xy 303.87772 -302.339668) (xy 303.833258 -302.360766) (xy 303.785987 -302.374458)
			(xy 303.737132 -302.38039) (xy 303.687957 -302.378409) (xy 303.639738 -302.368565) (xy 303.593722 -302.351113)
			(xy 303.551101 -302.326506) (xy 303.51298 -302.295381) (xy 303.480345 -302.258544) (xy 303.454042 -302.216948)
			(xy 303.434751 -302.171672) (xy 303.422974 -302.123888) (xy 303.419014 -302.074834) (xy 303.080166 -302.074834)
			(xy 303.079671 -302.099441) (xy 303.071776 -302.148018) (xy 303.056192 -302.194699) (xy 303.033321 -302.238276)
			(xy 303.003756 -302.27762) (xy 302.968263 -302.311712) (xy 302.92776 -302.339668) (xy 302.883298 -302.360766)
			(xy 302.836027 -302.374458) (xy 302.787172 -302.38039) (xy 302.737997 -302.378409) (xy 302.689778 -302.368565)
			(xy 302.643762 -302.351113) (xy 302.601141 -302.326506) (xy 302.56302 -302.295381) (xy 302.530385 -302.258544)
			(xy 302.504082 -302.216948) (xy 302.484791 -302.171672) (xy 302.473014 -302.123888) (xy 302.469054 -302.074834)
			(xy 302.130206 -302.074834) (xy 302.129711 -302.099441) (xy 302.121816 -302.148018) (xy 302.106232 -302.194699)
			(xy 302.083361 -302.238276) (xy 302.053796 -302.27762) (xy 302.018303 -302.311712) (xy 301.9778 -302.339668)
			(xy 301.933338 -302.360766) (xy 301.886067 -302.374458) (xy 301.837212 -302.38039) (xy 301.788037 -302.378409)
			(xy 301.739818 -302.368565) (xy 301.693802 -302.351113) (xy 301.651181 -302.326506) (xy 301.61306 -302.295381)
			(xy 301.580425 -302.258544) (xy 301.554122 -302.216948) (xy 301.534831 -302.171672) (xy 301.523054 -302.123888)
			(xy 301.519094 -302.074834) (xy 301.179992 -302.074834) (xy 301.179497 -302.099441) (xy 301.171602 -302.148018)
			(xy 301.156018 -302.194699) (xy 301.133147 -302.238276) (xy 301.103582 -302.27762) (xy 301.068089 -302.311712)
			(xy 301.027586 -302.339668) (xy 300.983124 -302.360766) (xy 300.935853 -302.374458) (xy 300.886998 -302.38039)
			(xy 300.837823 -302.378409) (xy 300.789604 -302.368565) (xy 300.743588 -302.351113) (xy 300.700967 -302.326506)
			(xy 300.662846 -302.295381) (xy 300.630211 -302.258544) (xy 300.603908 -302.216948) (xy 300.584617 -302.171672)
			(xy 300.57284 -302.123888) (xy 300.56888 -302.074834) (xy 300.230032 -302.074834) (xy 300.229537 -302.099441)
			(xy 300.221642 -302.148018) (xy 300.206058 -302.194699) (xy 300.183187 -302.238276) (xy 300.153622 -302.27762)
			(xy 300.118129 -302.311712) (xy 300.077626 -302.339668) (xy 300.033164 -302.360766) (xy 299.985893 -302.374458)
			(xy 299.937038 -302.38039) (xy 299.887863 -302.378409) (xy 299.839644 -302.368565) (xy 299.793628 -302.351113)
			(xy 299.751007 -302.326506) (xy 299.712886 -302.295381) (xy 299.680251 -302.258544) (xy 299.653948 -302.216948)
			(xy 299.634657 -302.171672) (xy 299.62288 -302.123888) (xy 299.61892 -302.074834) (xy 299.280072 -302.074834)
			(xy 299.279577 -302.099441) (xy 299.271682 -302.148018) (xy 299.256098 -302.194699) (xy 299.233227 -302.238276)
			(xy 299.203662 -302.27762) (xy 299.168169 -302.311712) (xy 299.127666 -302.339668) (xy 299.083204 -302.360766)
			(xy 299.035933 -302.374458) (xy 298.987078 -302.38039) (xy 298.937903 -302.378409) (xy 298.889684 -302.368565)
			(xy 298.843668 -302.351113) (xy 298.801047 -302.326506) (xy 298.762926 -302.295381) (xy 298.730291 -302.258544)
			(xy 298.703988 -302.216948) (xy 298.684697 -302.171672) (xy 298.67292 -302.123888) (xy 298.66896 -302.074834)
			(xy 298.330112 -302.074834) (xy 298.329617 -302.099441) (xy 298.321722 -302.148018) (xy 298.306138 -302.194699)
			(xy 298.283267 -302.238276) (xy 298.253702 -302.27762) (xy 298.218209 -302.311712) (xy 298.177706 -302.339668)
			(xy 298.133244 -302.360766) (xy 298.085973 -302.374458) (xy 298.037118 -302.38039) (xy 297.987943 -302.378409)
			(xy 297.939724 -302.368565) (xy 297.893708 -302.351113) (xy 297.851087 -302.326506) (xy 297.812966 -302.295381)
			(xy 297.780331 -302.258544) (xy 297.754028 -302.216948) (xy 297.734737 -302.171672) (xy 297.72296 -302.123888)
			(xy 297.719 -302.074834) (xy 297.380152 -302.074834) (xy 297.379657 -302.099441) (xy 297.371762 -302.148018)
			(xy 297.356178 -302.194699) (xy 297.333307 -302.238276) (xy 297.303742 -302.27762) (xy 297.268249 -302.311712)
			(xy 297.227746 -302.339668) (xy 297.183284 -302.360766) (xy 297.136013 -302.374458) (xy 297.087158 -302.38039)
			(xy 297.037983 -302.378409) (xy 296.989764 -302.368565) (xy 296.943748 -302.351113) (xy 296.901127 -302.326506)
			(xy 296.863006 -302.295381) (xy 296.830371 -302.258544) (xy 296.804068 -302.216948) (xy 296.784777 -302.171672)
			(xy 296.773 -302.123888) (xy 296.76904 -302.074834) (xy 296.430192 -302.074834) (xy 296.429697 -302.099441)
			(xy 296.421802 -302.148018) (xy 296.406218 -302.194699) (xy 296.383347 -302.238276) (xy 296.353782 -302.27762)
			(xy 296.318289 -302.311712) (xy 296.277786 -302.339668) (xy 296.233324 -302.360766) (xy 296.186053 -302.374458)
			(xy 296.137198 -302.38039) (xy 296.088023 -302.378409) (xy 296.039804 -302.368565) (xy 295.993788 -302.351113)
			(xy 295.951167 -302.326506) (xy 295.913046 -302.295381) (xy 295.880411 -302.258544) (xy 295.854108 -302.216948)
			(xy 295.834817 -302.171672) (xy 295.82304 -302.123888) (xy 295.81908 -302.074834) (xy 295.480232 -302.074834)
			(xy 295.479737 -302.099441) (xy 295.471842 -302.148018) (xy 295.456258 -302.194699) (xy 295.433387 -302.238276)
			(xy 295.403822 -302.27762) (xy 295.368329 -302.311712) (xy 295.327826 -302.339668) (xy 295.283364 -302.360766)
			(xy 295.236093 -302.374458) (xy 295.187238 -302.38039) (xy 295.138063 -302.378409) (xy 295.089844 -302.368565)
			(xy 295.043828 -302.351113) (xy 295.001207 -302.326506) (xy 294.963086 -302.295381) (xy 294.930451 -302.258544)
			(xy 294.904148 -302.216948) (xy 294.884857 -302.171672) (xy 294.87308 -302.123888) (xy 294.86912 -302.074834)
			(xy 294.530018 -302.074834) (xy 294.529523 -302.099441) (xy 294.521628 -302.148018) (xy 294.506044 -302.194699)
			(xy 294.483173 -302.238276) (xy 294.453608 -302.27762) (xy 294.418115 -302.311712) (xy 294.377612 -302.339668)
			(xy 294.33315 -302.360766) (xy 294.285879 -302.374458) (xy 294.237024 -302.38039) (xy 294.187849 -302.378409)
			(xy 294.13963 -302.368565) (xy 294.093614 -302.351113) (xy 294.050993 -302.326506) (xy 294.012872 -302.295381)
			(xy 293.980237 -302.258544) (xy 293.953934 -302.216948) (xy 293.934643 -302.171672) (xy 293.922866 -302.123888)
			(xy 293.918906 -302.074834) (xy 293.580058 -302.074834) (xy 293.579563 -302.099441) (xy 293.571668 -302.148018)
			(xy 293.556084 -302.194699) (xy 293.533213 -302.238276) (xy 293.503648 -302.27762) (xy 293.468155 -302.311712)
			(xy 293.427652 -302.339668) (xy 293.38319 -302.360766) (xy 293.335919 -302.374458) (xy 293.287064 -302.38039)
			(xy 293.237889 -302.378409) (xy 293.18967 -302.368565) (xy 293.143654 -302.351113) (xy 293.101033 -302.326506)
			(xy 293.062912 -302.295381) (xy 293.030277 -302.258544) (xy 293.003974 -302.216948) (xy 292.984683 -302.171672)
			(xy 292.972906 -302.123888) (xy 292.968946 -302.074834) (xy 292.630098 -302.074834) (xy 292.629603 -302.099441)
			(xy 292.621708 -302.148018) (xy 292.606124 -302.194699) (xy 292.583253 -302.238276) (xy 292.553688 -302.27762)
			(xy 292.518195 -302.311712) (xy 292.477692 -302.339668) (xy 292.43323 -302.360766) (xy 292.385959 -302.374458)
			(xy 292.337104 -302.38039) (xy 292.287929 -302.378409) (xy 292.23971 -302.368565) (xy 292.193694 -302.351113)
			(xy 292.151073 -302.326506) (xy 292.112952 -302.295381) (xy 292.080317 -302.258544) (xy 292.054014 -302.216948)
			(xy 292.034723 -302.171672) (xy 292.022946 -302.123888) (xy 292.018986 -302.074834) (xy 290.730178 -302.074834)
			(xy 290.729683 -302.099441) (xy 290.721788 -302.148018) (xy 290.706204 -302.194699) (xy 290.683333 -302.238276)
			(xy 290.653768 -302.27762) (xy 290.618275 -302.311712) (xy 290.577772 -302.339668) (xy 290.53331 -302.360766)
			(xy 290.486039 -302.374458) (xy 290.437184 -302.38039) (xy 290.388009 -302.378409) (xy 290.33979 -302.368565)
			(xy 290.293774 -302.351113) (xy 290.251153 -302.326506) (xy 290.213032 -302.295381) (xy 290.180397 -302.258544)
			(xy 290.154094 -302.216948) (xy 290.134803 -302.171672) (xy 290.123026 -302.123888) (xy 290.119066 -302.074834)
			(xy 289.780218 -302.074834) (xy 289.779723 -302.099441) (xy 289.771828 -302.148018) (xy 289.756244 -302.194699)
			(xy 289.733373 -302.238276) (xy 289.703808 -302.27762) (xy 289.668315 -302.311712) (xy 289.627812 -302.339668)
			(xy 289.58335 -302.360766) (xy 289.536079 -302.374458) (xy 289.487224 -302.38039) (xy 289.438049 -302.378409)
			(xy 289.38983 -302.368565) (xy 289.343814 -302.351113) (xy 289.301193 -302.326506) (xy 289.263072 -302.295381)
			(xy 289.230437 -302.258544) (xy 289.204134 -302.216948) (xy 289.184843 -302.171672) (xy 289.173066 -302.123888)
			(xy 289.169106 -302.074834) (xy 288.830004 -302.074834) (xy 288.829509 -302.099441) (xy 288.821614 -302.148018)
			(xy 288.80603 -302.194699) (xy 288.783159 -302.238276) (xy 288.753594 -302.27762) (xy 288.718101 -302.311712)
			(xy 288.677598 -302.339668) (xy 288.633136 -302.360766) (xy 288.585865 -302.374458) (xy 288.53701 -302.38039)
			(xy 288.487835 -302.378409) (xy 288.439616 -302.368565) (xy 288.3936 -302.351113) (xy 288.350979 -302.326506)
			(xy 288.312858 -302.295381) (xy 288.280223 -302.258544) (xy 288.25392 -302.216948) (xy 288.234629 -302.171672)
			(xy 288.222852 -302.123888) (xy 288.218892 -302.074834) (xy 287.880044 -302.074834) (xy 287.879549 -302.099441)
			(xy 287.871654 -302.148018) (xy 287.85607 -302.194699) (xy 287.833199 -302.238276) (xy 287.803634 -302.27762)
			(xy 287.768141 -302.311712) (xy 287.727638 -302.339668) (xy 287.683176 -302.360766) (xy 287.635905 -302.374458)
			(xy 287.58705 -302.38039) (xy 287.537875 -302.378409) (xy 287.489656 -302.368565) (xy 287.44364 -302.351113)
			(xy 287.401019 -302.326506) (xy 287.362898 -302.295381) (xy 287.330263 -302.258544) (xy 287.30396 -302.216948)
			(xy 287.284669 -302.171672) (xy 287.272892 -302.123888) (xy 287.268932 -302.074834) (xy 286.930084 -302.074834)
			(xy 286.929589 -302.099441) (xy 286.921694 -302.148018) (xy 286.90611 -302.194699) (xy 286.883239 -302.238276)
			(xy 286.853674 -302.27762) (xy 286.818181 -302.311712) (xy 286.777678 -302.339668) (xy 286.733216 -302.360766)
			(xy 286.685945 -302.374458) (xy 286.63709 -302.38039) (xy 286.587915 -302.378409) (xy 286.539696 -302.368565)
			(xy 286.49368 -302.351113) (xy 286.451059 -302.326506) (xy 286.412938 -302.295381) (xy 286.380303 -302.258544)
			(xy 286.354 -302.216948) (xy 286.334709 -302.171672) (xy 286.322932 -302.123888) (xy 286.318972 -302.074834)
			(xy 285.980124 -302.074834) (xy 285.979629 -302.099441) (xy 285.971734 -302.148018) (xy 285.95615 -302.194699)
			(xy 285.933279 -302.238276) (xy 285.903714 -302.27762) (xy 285.868221 -302.311712) (xy 285.827718 -302.339668)
			(xy 285.783256 -302.360766) (xy 285.735985 -302.374458) (xy 285.68713 -302.38039) (xy 285.637955 -302.378409)
			(xy 285.589736 -302.368565) (xy 285.54372 -302.351113) (xy 285.501099 -302.326506) (xy 285.462978 -302.295381)
			(xy 285.430343 -302.258544) (xy 285.40404 -302.216948) (xy 285.384749 -302.171672) (xy 285.372972 -302.123888)
			(xy 285.369012 -302.074834) (xy 285.030164 -302.074834) (xy 285.029669 -302.099441) (xy 285.021774 -302.148018)
			(xy 285.00619 -302.194699) (xy 284.983319 -302.238276) (xy 284.953754 -302.27762) (xy 284.918261 -302.311712)
			(xy 284.877758 -302.339668) (xy 284.833296 -302.360766) (xy 284.786025 -302.374458) (xy 284.73717 -302.38039)
			(xy 284.687995 -302.378409) (xy 284.639776 -302.368565) (xy 284.59376 -302.351113) (xy 284.551139 -302.326506)
			(xy 284.513018 -302.295381) (xy 284.480383 -302.258544) (xy 284.45408 -302.216948) (xy 284.434789 -302.171672)
			(xy 284.423012 -302.123888) (xy 284.419052 -302.074834) (xy 284.080204 -302.074834) (xy 284.079709 -302.099441)
			(xy 284.071814 -302.148018) (xy 284.05623 -302.194699) (xy 284.033359 -302.238276) (xy 284.003794 -302.27762)
			(xy 283.968301 -302.311712) (xy 283.927798 -302.339668) (xy 283.883336 -302.360766) (xy 283.836065 -302.374458)
			(xy 283.78721 -302.38039) (xy 283.738035 -302.378409) (xy 283.689816 -302.368565) (xy 283.6438 -302.351113)
			(xy 283.601179 -302.326506) (xy 283.563058 -302.295381) (xy 283.530423 -302.258544) (xy 283.50412 -302.216948)
			(xy 283.484829 -302.171672) (xy 283.473052 -302.123888) (xy 283.469092 -302.074834) (xy 283.130244 -302.074834)
			(xy 283.129749 -302.099441) (xy 283.121854 -302.148018) (xy 283.10627 -302.194699) (xy 283.083399 -302.238276)
			(xy 283.053834 -302.27762) (xy 283.018341 -302.311712) (xy 282.977838 -302.339668) (xy 282.933376 -302.360766)
			(xy 282.886105 -302.374458) (xy 282.83725 -302.38039) (xy 282.788075 -302.378409) (xy 282.739856 -302.368565)
			(xy 282.69384 -302.351113) (xy 282.651219 -302.326506) (xy 282.613098 -302.295381) (xy 282.580463 -302.258544)
			(xy 282.55416 -302.216948) (xy 282.534869 -302.171672) (xy 282.523092 -302.123888) (xy 282.519132 -302.074834)
			(xy 282.180494 -302.074834) (xy 282.176327 -302.12513) (xy 282.16393 -302.174088) (xy 282.143644 -302.220337)
			(xy 282.116022 -302.262617) (xy 282.081819 -302.299774) (xy 282.041967 -302.330795) (xy 281.997552 -302.354834)
			(xy 281.949787 -302.371235) (xy 281.899973 -302.379551) (xy 281.874722 -302.380142) (xy 281.844648 -302.379448)
			(xy 281.785663 -302.367681) (xy 281.757628 -302.356774) (xy 281.745436 -302.351694) (xy 281.720544 -302.354234)
			(xy 281.639518 -302.408336) (xy 281.629468 -302.415858) (xy 281.617636 -302.437966) (xy 281.616912 -302.4505)
			(xy 281.616912 -302.538384) (xy 319.861182 -302.538384) (xy 319.865253 -302.482762) (xy 319.877379 -302.428325)
			(xy 319.897302 -302.376234) (xy 319.924598 -302.327599) (xy 319.958684 -302.283456) (xy 319.998833 -302.244747)
			(xy 320.044191 -302.212296) (xy 320.093791 -302.186795) (xy 320.146575 -302.168788) (xy 320.201418 -302.158658)
			(xy 320.257152 -302.156621) (xy 320.312589 -302.162721) (xy 320.366546 -302.176827) (xy 320.417875 -302.198639)
			(xy 320.465481 -302.227693) (xy 320.508349 -302.263368) (xy 320.545566 -302.304905) (xy 320.576339 -302.351418)
			(xy 320.600011 -302.401915) (xy 320.616079 -302.455322) (xy 320.624199 -302.510498) (xy 320.624708 -302.538384)
			(xy 320.624199 -302.56627) (xy 320.616079 -302.621446) (xy 320.600011 -302.674853) (xy 320.576339 -302.72535)
			(xy 320.545566 -302.771863) (xy 320.508349 -302.8134) (xy 320.465481 -302.849075) (xy 320.417875 -302.878129)
			(xy 320.366546 -302.899941) (xy 320.312589 -302.914047) (xy 320.257152 -302.920147) (xy 320.201418 -302.91811)
			(xy 320.146575 -302.90798) (xy 320.093791 -302.889973) (xy 320.044191 -302.864472) (xy 319.998833 -302.832021)
			(xy 319.958684 -302.793312) (xy 319.924598 -302.749169) (xy 319.897302 -302.700534) (xy 319.877379 -302.648443)
			(xy 319.865253 -302.594006) (xy 319.861182 -302.538384) (xy 281.616912 -302.538384) (xy 281.616912 -302.649128)
			(xy 281.61756 -302.661681) (xy 281.629422 -302.683804) (xy 281.639518 -302.691292) (xy 281.720544 -302.745394)
			(xy 281.745436 -302.747934) (xy 281.757628 -302.742854) (xy 281.785665 -302.731953) (xy 281.844649 -302.720185)
			(xy 281.874722 -302.719486) (xy 281.899977 -302.720009) (xy 281.949797 -302.728326) (xy 281.997568 -302.744729)
			(xy 282.041989 -302.768771) (xy 282.081846 -302.799796) (xy 282.116054 -302.836958) (xy 282.143679 -302.879244)
			(xy 282.163967 -302.925499) (xy 282.176366 -302.974463) (xy 282.180537 -303.024794) (xy 282.519132 -303.024794)
			(xy 282.523092 -302.97574) (xy 282.534869 -302.927956) (xy 282.55416 -302.88268) (xy 282.580463 -302.841084)
			(xy 282.613098 -302.804247) (xy 282.651219 -302.773122) (xy 282.69384 -302.748515) (xy 282.739856 -302.731063)
			(xy 282.788075 -302.721219) (xy 282.83725 -302.719238) (xy 282.886105 -302.72517) (xy 282.933376 -302.738862)
			(xy 282.977838 -302.75996) (xy 283.018341 -302.787916) (xy 283.053834 -302.822008) (xy 283.083399 -302.861352)
			(xy 283.10627 -302.904929) (xy 283.121854 -302.95161) (xy 283.129749 -303.000187) (xy 283.130244 -303.024794)
			(xy 283.469092 -303.024794) (xy 283.473052 -302.97574) (xy 283.484829 -302.927956) (xy 283.50412 -302.88268)
			(xy 283.530423 -302.841084) (xy 283.563058 -302.804247) (xy 283.601179 -302.773122) (xy 283.6438 -302.748515)
			(xy 283.689816 -302.731063) (xy 283.738035 -302.721219) (xy 283.78721 -302.719238) (xy 283.836065 -302.72517)
			(xy 283.883336 -302.738862) (xy 283.927798 -302.75996) (xy 283.968301 -302.787916) (xy 284.003794 -302.822008)
			(xy 284.033359 -302.861352) (xy 284.05623 -302.904929) (xy 284.071814 -302.95161) (xy 284.079709 -303.000187)
			(xy 284.080204 -303.024794) (xy 284.419052 -303.024794) (xy 284.423012 -302.97574) (xy 284.434789 -302.927956)
			(xy 284.45408 -302.88268) (xy 284.480383 -302.841084) (xy 284.513018 -302.804247) (xy 284.551139 -302.773122)
			(xy 284.59376 -302.748515) (xy 284.639776 -302.731063) (xy 284.687995 -302.721219) (xy 284.73717 -302.719238)
			(xy 284.786025 -302.72517) (xy 284.833296 -302.738862) (xy 284.877758 -302.75996) (xy 284.918261 -302.787916)
			(xy 284.953754 -302.822008) (xy 284.983319 -302.861352) (xy 285.00619 -302.904929) (xy 285.021774 -302.95161)
			(xy 285.029669 -303.000187) (xy 285.030164 -303.024794) (xy 285.369012 -303.024794) (xy 285.372972 -302.97574)
			(xy 285.384749 -302.927956) (xy 285.40404 -302.88268) (xy 285.430343 -302.841084) (xy 285.462978 -302.804247)
			(xy 285.501099 -302.773122) (xy 285.54372 -302.748515) (xy 285.589736 -302.731063) (xy 285.637955 -302.721219)
			(xy 285.68713 -302.719238) (xy 285.735985 -302.72517) (xy 285.783256 -302.738862) (xy 285.827718 -302.75996)
			(xy 285.868221 -302.787916) (xy 285.903714 -302.822008) (xy 285.933279 -302.861352) (xy 285.95615 -302.904929)
			(xy 285.971734 -302.95161) (xy 285.979629 -303.000187) (xy 285.980124 -303.024794) (xy 286.318972 -303.024794)
			(xy 286.322932 -302.97574) (xy 286.334709 -302.927956) (xy 286.354 -302.88268) (xy 286.380303 -302.841084)
			(xy 286.412938 -302.804247) (xy 286.451059 -302.773122) (xy 286.49368 -302.748515) (xy 286.539696 -302.731063)
			(xy 286.587915 -302.721219) (xy 286.63709 -302.719238) (xy 286.685945 -302.72517) (xy 286.733216 -302.738862)
			(xy 286.777678 -302.75996) (xy 286.818181 -302.787916) (xy 286.853674 -302.822008) (xy 286.883239 -302.861352)
			(xy 286.90611 -302.904929) (xy 286.921694 -302.95161) (xy 286.929589 -303.000187) (xy 286.930084 -303.024794)
			(xy 287.268932 -303.024794) (xy 287.272892 -302.97574) (xy 287.284669 -302.927956) (xy 287.30396 -302.88268)
			(xy 287.330263 -302.841084) (xy 287.362898 -302.804247) (xy 287.401019 -302.773122) (xy 287.44364 -302.748515)
			(xy 287.489656 -302.731063) (xy 287.537875 -302.721219) (xy 287.58705 -302.719238) (xy 287.635905 -302.72517)
			(xy 287.683176 -302.738862) (xy 287.727638 -302.75996) (xy 287.768141 -302.787916) (xy 287.803634 -302.822008)
			(xy 287.833199 -302.861352) (xy 287.85607 -302.904929) (xy 287.871654 -302.95161) (xy 287.879549 -303.000187)
			(xy 287.880044 -303.024794) (xy 288.218892 -303.024794) (xy 288.222852 -302.97574) (xy 288.234629 -302.927956)
			(xy 288.25392 -302.88268) (xy 288.280223 -302.841084) (xy 288.312858 -302.804247) (xy 288.350979 -302.773122)
			(xy 288.3936 -302.748515) (xy 288.439616 -302.731063) (xy 288.487835 -302.721219) (xy 288.53701 -302.719238)
			(xy 288.585865 -302.72517) (xy 288.633136 -302.738862) (xy 288.677598 -302.75996) (xy 288.718101 -302.787916)
			(xy 288.753594 -302.822008) (xy 288.783159 -302.861352) (xy 288.80603 -302.904929) (xy 288.821614 -302.95161)
			(xy 288.829509 -303.000187) (xy 288.830004 -303.024794) (xy 289.169106 -303.024794) (xy 289.173066 -302.97574)
			(xy 289.184843 -302.927956) (xy 289.204134 -302.88268) (xy 289.230437 -302.841084) (xy 289.263072 -302.804247)
			(xy 289.301193 -302.773122) (xy 289.343814 -302.748515) (xy 289.38983 -302.731063) (xy 289.438049 -302.721219)
			(xy 289.487224 -302.719238) (xy 289.536079 -302.72517) (xy 289.58335 -302.738862) (xy 289.627812 -302.75996)
			(xy 289.668315 -302.787916) (xy 289.703808 -302.822008) (xy 289.733373 -302.861352) (xy 289.756244 -302.904929)
			(xy 289.771828 -302.95161) (xy 289.779723 -303.000187) (xy 289.780218 -303.024794) (xy 290.119066 -303.024794)
			(xy 290.123026 -302.97574) (xy 290.134803 -302.927956) (xy 290.154094 -302.88268) (xy 290.180397 -302.841084)
			(xy 290.213032 -302.804247) (xy 290.251153 -302.773122) (xy 290.293774 -302.748515) (xy 290.33979 -302.731063)
			(xy 290.388009 -302.721219) (xy 290.437184 -302.719238) (xy 290.486039 -302.72517) (xy 290.53331 -302.738862)
			(xy 290.577772 -302.75996) (xy 290.618275 -302.787916) (xy 290.653768 -302.822008) (xy 290.683333 -302.861352)
			(xy 290.706204 -302.904929) (xy 290.721788 -302.95161) (xy 290.729683 -303.000187) (xy 290.730178 -303.024794)
			(xy 292.018986 -303.024794) (xy 292.022946 -302.97574) (xy 292.034723 -302.927956) (xy 292.054014 -302.88268)
			(xy 292.080317 -302.841084) (xy 292.112952 -302.804247) (xy 292.151073 -302.773122) (xy 292.193694 -302.748515)
			(xy 292.23971 -302.731063) (xy 292.287929 -302.721219) (xy 292.337104 -302.719238) (xy 292.385959 -302.72517)
			(xy 292.43323 -302.738862) (xy 292.477692 -302.75996) (xy 292.518195 -302.787916) (xy 292.553688 -302.822008)
			(xy 292.583253 -302.861352) (xy 292.606124 -302.904929) (xy 292.621708 -302.95161) (xy 292.629603 -303.000187)
			(xy 292.630098 -303.024794) (xy 292.968946 -303.024794) (xy 292.972906 -302.97574) (xy 292.984683 -302.927956)
			(xy 293.003974 -302.88268) (xy 293.030277 -302.841084) (xy 293.062912 -302.804247) (xy 293.101033 -302.773122)
			(xy 293.143654 -302.748515) (xy 293.18967 -302.731063) (xy 293.237889 -302.721219) (xy 293.287064 -302.719238)
			(xy 293.335919 -302.72517) (xy 293.38319 -302.738862) (xy 293.427652 -302.75996) (xy 293.468155 -302.787916)
			(xy 293.503648 -302.822008) (xy 293.533213 -302.861352) (xy 293.556084 -302.904929) (xy 293.571668 -302.95161)
			(xy 293.579563 -303.000187) (xy 293.580058 -303.024794) (xy 293.918906 -303.024794) (xy 293.922866 -302.97574)
			(xy 293.934643 -302.927956) (xy 293.953934 -302.88268) (xy 293.980237 -302.841084) (xy 294.012872 -302.804247)
			(xy 294.050993 -302.773122) (xy 294.093614 -302.748515) (xy 294.13963 -302.731063) (xy 294.187849 -302.721219)
			(xy 294.237024 -302.719238) (xy 294.285879 -302.72517) (xy 294.33315 -302.738862) (xy 294.377612 -302.75996)
			(xy 294.418115 -302.787916) (xy 294.453608 -302.822008) (xy 294.483173 -302.861352) (xy 294.506044 -302.904929)
			(xy 294.521628 -302.95161) (xy 294.529523 -303.000187) (xy 294.530018 -303.024794) (xy 294.86912 -303.024794)
			(xy 294.87308 -302.97574) (xy 294.884857 -302.927956) (xy 294.904148 -302.88268) (xy 294.930451 -302.841084)
			(xy 294.963086 -302.804247) (xy 295.001207 -302.773122) (xy 295.043828 -302.748515) (xy 295.089844 -302.731063)
			(xy 295.138063 -302.721219) (xy 295.187238 -302.719238) (xy 295.236093 -302.72517) (xy 295.283364 -302.738862)
			(xy 295.327826 -302.75996) (xy 295.368329 -302.787916) (xy 295.403822 -302.822008) (xy 295.433387 -302.861352)
			(xy 295.456258 -302.904929) (xy 295.471842 -302.95161) (xy 295.479737 -303.000187) (xy 295.480232 -303.024794)
			(xy 295.81908 -303.024794) (xy 295.82304 -302.97574) (xy 295.834817 -302.927956) (xy 295.854108 -302.88268)
			(xy 295.880411 -302.841084) (xy 295.913046 -302.804247) (xy 295.951167 -302.773122) (xy 295.993788 -302.748515)
			(xy 296.039804 -302.731063) (xy 296.088023 -302.721219) (xy 296.137198 -302.719238) (xy 296.186053 -302.72517)
			(xy 296.233324 -302.738862) (xy 296.277786 -302.75996) (xy 296.318289 -302.787916) (xy 296.353782 -302.822008)
			(xy 296.383347 -302.861352) (xy 296.406218 -302.904929) (xy 296.421802 -302.95161) (xy 296.429697 -303.000187)
			(xy 296.430192 -303.024794) (xy 296.76904 -303.024794) (xy 296.773 -302.97574) (xy 296.784777 -302.927956)
			(xy 296.804068 -302.88268) (xy 296.830371 -302.841084) (xy 296.863006 -302.804247) (xy 296.901127 -302.773122)
			(xy 296.943748 -302.748515) (xy 296.989764 -302.731063) (xy 297.037983 -302.721219) (xy 297.087158 -302.719238)
			(xy 297.136013 -302.72517) (xy 297.183284 -302.738862) (xy 297.227746 -302.75996) (xy 297.268249 -302.787916)
			(xy 297.303742 -302.822008) (xy 297.333307 -302.861352) (xy 297.356178 -302.904929) (xy 297.371762 -302.95161)
			(xy 297.379657 -303.000187) (xy 297.380152 -303.024794) (xy 297.719 -303.024794) (xy 297.72296 -302.97574)
			(xy 297.734737 -302.927956) (xy 297.754028 -302.88268) (xy 297.780331 -302.841084) (xy 297.812966 -302.804247)
			(xy 297.851087 -302.773122) (xy 297.893708 -302.748515) (xy 297.939724 -302.731063) (xy 297.987943 -302.721219)
			(xy 298.037118 -302.719238) (xy 298.085973 -302.72517) (xy 298.133244 -302.738862) (xy 298.177706 -302.75996)
			(xy 298.218209 -302.787916) (xy 298.253702 -302.822008) (xy 298.283267 -302.861352) (xy 298.306138 -302.904929)
			(xy 298.321722 -302.95161) (xy 298.329617 -303.000187) (xy 298.330112 -303.024794) (xy 298.66896 -303.024794)
			(xy 298.67292 -302.97574) (xy 298.684697 -302.927956) (xy 298.703988 -302.88268) (xy 298.730291 -302.841084)
			(xy 298.762926 -302.804247) (xy 298.801047 -302.773122) (xy 298.843668 -302.748515) (xy 298.889684 -302.731063)
			(xy 298.937903 -302.721219) (xy 298.987078 -302.719238) (xy 299.035933 -302.72517) (xy 299.083204 -302.738862)
			(xy 299.127666 -302.75996) (xy 299.168169 -302.787916) (xy 299.203662 -302.822008) (xy 299.233227 -302.861352)
			(xy 299.256098 -302.904929) (xy 299.271682 -302.95161) (xy 299.279577 -303.000187) (xy 299.280072 -303.024794)
			(xy 299.61892 -303.024794) (xy 299.62288 -302.97574) (xy 299.634657 -302.927956) (xy 299.653948 -302.88268)
			(xy 299.680251 -302.841084) (xy 299.712886 -302.804247) (xy 299.751007 -302.773122) (xy 299.793628 -302.748515)
			(xy 299.839644 -302.731063) (xy 299.887863 -302.721219) (xy 299.937038 -302.719238) (xy 299.985893 -302.72517)
			(xy 300.033164 -302.738862) (xy 300.077626 -302.75996) (xy 300.118129 -302.787916) (xy 300.153622 -302.822008)
			(xy 300.183187 -302.861352) (xy 300.206058 -302.904929) (xy 300.221642 -302.95161) (xy 300.229537 -303.000187)
			(xy 300.230032 -303.024794) (xy 300.56888 -303.024794) (xy 300.57284 -302.97574) (xy 300.584617 -302.927956)
			(xy 300.603908 -302.88268) (xy 300.630211 -302.841084) (xy 300.662846 -302.804247) (xy 300.700967 -302.773122)
			(xy 300.743588 -302.748515) (xy 300.789604 -302.731063) (xy 300.837823 -302.721219) (xy 300.886998 -302.719238)
			(xy 300.935853 -302.72517) (xy 300.983124 -302.738862) (xy 301.027586 -302.75996) (xy 301.068089 -302.787916)
			(xy 301.103582 -302.822008) (xy 301.133147 -302.861352) (xy 301.156018 -302.904929) (xy 301.171602 -302.95161)
			(xy 301.179497 -303.000187) (xy 301.179992 -303.024794) (xy 301.519094 -303.024794) (xy 301.523054 -302.97574)
			(xy 301.534831 -302.927956) (xy 301.554122 -302.88268) (xy 301.580425 -302.841084) (xy 301.61306 -302.804247)
			(xy 301.651181 -302.773122) (xy 301.693802 -302.748515) (xy 301.739818 -302.731063) (xy 301.788037 -302.721219)
			(xy 301.837212 -302.719238) (xy 301.886067 -302.72517) (xy 301.933338 -302.738862) (xy 301.9778 -302.75996)
			(xy 302.018303 -302.787916) (xy 302.053796 -302.822008) (xy 302.083361 -302.861352) (xy 302.106232 -302.904929)
			(xy 302.121816 -302.95161) (xy 302.129711 -303.000187) (xy 302.130206 -303.024794) (xy 302.469054 -303.024794)
			(xy 302.473014 -302.97574) (xy 302.484791 -302.927956) (xy 302.504082 -302.88268) (xy 302.530385 -302.841084)
			(xy 302.56302 -302.804247) (xy 302.601141 -302.773122) (xy 302.643762 -302.748515) (xy 302.689778 -302.731063)
			(xy 302.737997 -302.721219) (xy 302.787172 -302.719238) (xy 302.836027 -302.72517) (xy 302.883298 -302.738862)
			(xy 302.92776 -302.75996) (xy 302.968263 -302.787916) (xy 303.003756 -302.822008) (xy 303.033321 -302.861352)
			(xy 303.056192 -302.904929) (xy 303.071776 -302.95161) (xy 303.079671 -303.000187) (xy 303.080166 -303.024794)
			(xy 303.419014 -303.024794) (xy 303.422974 -302.97574) (xy 303.434751 -302.927956) (xy 303.454042 -302.88268)
			(xy 303.480345 -302.841084) (xy 303.51298 -302.804247) (xy 303.551101 -302.773122) (xy 303.593722 -302.748515)
			(xy 303.639738 -302.731063) (xy 303.687957 -302.721219) (xy 303.737132 -302.719238) (xy 303.785987 -302.72517)
			(xy 303.833258 -302.738862) (xy 303.87772 -302.75996) (xy 303.918223 -302.787916) (xy 303.953716 -302.822008)
			(xy 303.983281 -302.861352) (xy 304.006152 -302.904929) (xy 304.021736 -302.95161) (xy 304.029631 -303.000187)
			(xy 304.030126 -303.024794) (xy 304.368974 -303.024794) (xy 304.372934 -302.97574) (xy 304.384711 -302.927956)
			(xy 304.404002 -302.88268) (xy 304.430305 -302.841084) (xy 304.46294 -302.804247) (xy 304.501061 -302.773122)
			(xy 304.543682 -302.748515) (xy 304.589698 -302.731063) (xy 304.637917 -302.721219) (xy 304.687092 -302.719238)
			(xy 304.735947 -302.72517) (xy 304.783218 -302.738862) (xy 304.82768 -302.75996) (xy 304.868183 -302.787916)
			(xy 304.903676 -302.822008) (xy 304.933241 -302.861352) (xy 304.956112 -302.904929) (xy 304.971696 -302.95161)
			(xy 304.979591 -303.000187) (xy 304.980086 -303.024794) (xy 305.318934 -303.024794) (xy 305.322894 -302.97574)
			(xy 305.334671 -302.927956) (xy 305.353962 -302.88268) (xy 305.380265 -302.841084) (xy 305.4129 -302.804247)
			(xy 305.451021 -302.773122) (xy 305.493642 -302.748515) (xy 305.539658 -302.731063) (xy 305.587877 -302.721219)
			(xy 305.637052 -302.719238) (xy 305.685907 -302.72517) (xy 305.733178 -302.738862) (xy 305.77764 -302.75996)
			(xy 305.818143 -302.787916) (xy 305.853636 -302.822008) (xy 305.883201 -302.861352) (xy 305.906072 -302.904929)
			(xy 305.921656 -302.95161) (xy 305.929551 -303.000187) (xy 305.930046 -303.024794) (xy 305.929551 -303.049401)
			(xy 305.921656 -303.097978) (xy 305.906072 -303.144659) (xy 305.883201 -303.188236) (xy 305.853636 -303.22758)
			(xy 305.818143 -303.261672) (xy 305.77764 -303.289628) (xy 305.733178 -303.310726) (xy 305.685907 -303.324418)
			(xy 305.637052 -303.33035) (xy 305.587877 -303.328369) (xy 305.539658 -303.318525) (xy 305.493642 -303.301073)
			(xy 305.451021 -303.276466) (xy 305.4129 -303.245341) (xy 305.380265 -303.208504) (xy 305.353962 -303.166908)
			(xy 305.334671 -303.121632) (xy 305.322894 -303.073848) (xy 305.318934 -303.024794) (xy 304.980086 -303.024794)
			(xy 304.979591 -303.049401) (xy 304.971696 -303.097978) (xy 304.956112 -303.144659) (xy 304.933241 -303.188236)
			(xy 304.903676 -303.22758) (xy 304.868183 -303.261672) (xy 304.82768 -303.289628) (xy 304.783218 -303.310726)
			(xy 304.735947 -303.324418) (xy 304.687092 -303.33035) (xy 304.637917 -303.328369) (xy 304.589698 -303.318525)
			(xy 304.543682 -303.301073) (xy 304.501061 -303.276466) (xy 304.46294 -303.245341) (xy 304.430305 -303.208504)
			(xy 304.404002 -303.166908) (xy 304.384711 -303.121632) (xy 304.372934 -303.073848) (xy 304.368974 -303.024794)
			(xy 304.030126 -303.024794) (xy 304.029631 -303.049401) (xy 304.021736 -303.097978) (xy 304.006152 -303.144659)
			(xy 303.983281 -303.188236) (xy 303.953716 -303.22758) (xy 303.918223 -303.261672) (xy 303.87772 -303.289628)
			(xy 303.833258 -303.310726) (xy 303.785987 -303.324418) (xy 303.737132 -303.33035) (xy 303.687957 -303.328369)
			(xy 303.639738 -303.318525) (xy 303.593722 -303.301073) (xy 303.551101 -303.276466) (xy 303.51298 -303.245341)
			(xy 303.480345 -303.208504) (xy 303.454042 -303.166908) (xy 303.434751 -303.121632) (xy 303.422974 -303.073848)
			(xy 303.419014 -303.024794) (xy 303.080166 -303.024794) (xy 303.079671 -303.049401) (xy 303.071776 -303.097978)
			(xy 303.056192 -303.144659) (xy 303.033321 -303.188236) (xy 303.003756 -303.22758) (xy 302.968263 -303.261672)
			(xy 302.92776 -303.289628) (xy 302.883298 -303.310726) (xy 302.836027 -303.324418) (xy 302.787172 -303.33035)
			(xy 302.737997 -303.328369) (xy 302.689778 -303.318525) (xy 302.643762 -303.301073) (xy 302.601141 -303.276466)
			(xy 302.56302 -303.245341) (xy 302.530385 -303.208504) (xy 302.504082 -303.166908) (xy 302.484791 -303.121632)
			(xy 302.473014 -303.073848) (xy 302.469054 -303.024794) (xy 302.130206 -303.024794) (xy 302.129711 -303.049401)
			(xy 302.121816 -303.097978) (xy 302.106232 -303.144659) (xy 302.083361 -303.188236) (xy 302.053796 -303.22758)
			(xy 302.018303 -303.261672) (xy 301.9778 -303.289628) (xy 301.933338 -303.310726) (xy 301.886067 -303.324418)
			(xy 301.837212 -303.33035) (xy 301.788037 -303.328369) (xy 301.739818 -303.318525) (xy 301.693802 -303.301073)
			(xy 301.651181 -303.276466) (xy 301.61306 -303.245341) (xy 301.580425 -303.208504) (xy 301.554122 -303.166908)
			(xy 301.534831 -303.121632) (xy 301.523054 -303.073848) (xy 301.519094 -303.024794) (xy 301.179992 -303.024794)
			(xy 301.179497 -303.049401) (xy 301.171602 -303.097978) (xy 301.156018 -303.144659) (xy 301.133147 -303.188236)
			(xy 301.103582 -303.22758) (xy 301.068089 -303.261672) (xy 301.027586 -303.289628) (xy 300.983124 -303.310726)
			(xy 300.935853 -303.324418) (xy 300.886998 -303.33035) (xy 300.837823 -303.328369) (xy 300.789604 -303.318525)
			(xy 300.743588 -303.301073) (xy 300.700967 -303.276466) (xy 300.662846 -303.245341) (xy 300.630211 -303.208504)
			(xy 300.603908 -303.166908) (xy 300.584617 -303.121632) (xy 300.57284 -303.073848) (xy 300.56888 -303.024794)
			(xy 300.230032 -303.024794) (xy 300.229537 -303.049401) (xy 300.221642 -303.097978) (xy 300.206058 -303.144659)
			(xy 300.183187 -303.188236) (xy 300.153622 -303.22758) (xy 300.118129 -303.261672) (xy 300.077626 -303.289628)
			(xy 300.033164 -303.310726) (xy 299.985893 -303.324418) (xy 299.937038 -303.33035) (xy 299.887863 -303.328369)
			(xy 299.839644 -303.318525) (xy 299.793628 -303.301073) (xy 299.751007 -303.276466) (xy 299.712886 -303.245341)
			(xy 299.680251 -303.208504) (xy 299.653948 -303.166908) (xy 299.634657 -303.121632) (xy 299.62288 -303.073848)
			(xy 299.61892 -303.024794) (xy 299.280072 -303.024794) (xy 299.279577 -303.049401) (xy 299.271682 -303.097978)
			(xy 299.256098 -303.144659) (xy 299.233227 -303.188236) (xy 299.203662 -303.22758) (xy 299.168169 -303.261672)
			(xy 299.127666 -303.289628) (xy 299.083204 -303.310726) (xy 299.035933 -303.324418) (xy 298.987078 -303.33035)
			(xy 298.937903 -303.328369) (xy 298.889684 -303.318525) (xy 298.843668 -303.301073) (xy 298.801047 -303.276466)
			(xy 298.762926 -303.245341) (xy 298.730291 -303.208504) (xy 298.703988 -303.166908) (xy 298.684697 -303.121632)
			(xy 298.67292 -303.073848) (xy 298.66896 -303.024794) (xy 298.330112 -303.024794) (xy 298.329617 -303.049401)
			(xy 298.321722 -303.097978) (xy 298.306138 -303.144659) (xy 298.283267 -303.188236) (xy 298.253702 -303.22758)
			(xy 298.218209 -303.261672) (xy 298.177706 -303.289628) (xy 298.133244 -303.310726) (xy 298.085973 -303.324418)
			(xy 298.037118 -303.33035) (xy 297.987943 -303.328369) (xy 297.939724 -303.318525) (xy 297.893708 -303.301073)
			(xy 297.851087 -303.276466) (xy 297.812966 -303.245341) (xy 297.780331 -303.208504) (xy 297.754028 -303.166908)
			(xy 297.734737 -303.121632) (xy 297.72296 -303.073848) (xy 297.719 -303.024794) (xy 297.380152 -303.024794)
			(xy 297.379657 -303.049401) (xy 297.371762 -303.097978) (xy 297.356178 -303.144659) (xy 297.333307 -303.188236)
			(xy 297.303742 -303.22758) (xy 297.268249 -303.261672) (xy 297.227746 -303.289628) (xy 297.183284 -303.310726)
			(xy 297.136013 -303.324418) (xy 297.087158 -303.33035) (xy 297.037983 -303.328369) (xy 296.989764 -303.318525)
			(xy 296.943748 -303.301073) (xy 296.901127 -303.276466) (xy 296.863006 -303.245341) (xy 296.830371 -303.208504)
			(xy 296.804068 -303.166908) (xy 296.784777 -303.121632) (xy 296.773 -303.073848) (xy 296.76904 -303.024794)
			(xy 296.430192 -303.024794) (xy 296.429697 -303.049401) (xy 296.421802 -303.097978) (xy 296.406218 -303.144659)
			(xy 296.383347 -303.188236) (xy 296.353782 -303.22758) (xy 296.318289 -303.261672) (xy 296.277786 -303.289628)
			(xy 296.233324 -303.310726) (xy 296.186053 -303.324418) (xy 296.137198 -303.33035) (xy 296.088023 -303.328369)
			(xy 296.039804 -303.318525) (xy 295.993788 -303.301073) (xy 295.951167 -303.276466) (xy 295.913046 -303.245341)
			(xy 295.880411 -303.208504) (xy 295.854108 -303.166908) (xy 295.834817 -303.121632) (xy 295.82304 -303.073848)
			(xy 295.81908 -303.024794) (xy 295.480232 -303.024794) (xy 295.479737 -303.049401) (xy 295.471842 -303.097978)
			(xy 295.456258 -303.144659) (xy 295.433387 -303.188236) (xy 295.403822 -303.22758) (xy 295.368329 -303.261672)
			(xy 295.327826 -303.289628) (xy 295.283364 -303.310726) (xy 295.236093 -303.324418) (xy 295.187238 -303.33035)
			(xy 295.138063 -303.328369) (xy 295.089844 -303.318525) (xy 295.043828 -303.301073) (xy 295.001207 -303.276466)
			(xy 294.963086 -303.245341) (xy 294.930451 -303.208504) (xy 294.904148 -303.166908) (xy 294.884857 -303.121632)
			(xy 294.87308 -303.073848) (xy 294.86912 -303.024794) (xy 294.530018 -303.024794) (xy 294.529523 -303.049401)
			(xy 294.521628 -303.097978) (xy 294.506044 -303.144659) (xy 294.483173 -303.188236) (xy 294.453608 -303.22758)
			(xy 294.418115 -303.261672) (xy 294.377612 -303.289628) (xy 294.33315 -303.310726) (xy 294.285879 -303.324418)
			(xy 294.237024 -303.33035) (xy 294.187849 -303.328369) (xy 294.13963 -303.318525) (xy 294.093614 -303.301073)
			(xy 294.050993 -303.276466) (xy 294.012872 -303.245341) (xy 293.980237 -303.208504) (xy 293.953934 -303.166908)
			(xy 293.934643 -303.121632) (xy 293.922866 -303.073848) (xy 293.918906 -303.024794) (xy 293.580058 -303.024794)
			(xy 293.579563 -303.049401) (xy 293.571668 -303.097978) (xy 293.556084 -303.144659) (xy 293.533213 -303.188236)
			(xy 293.503648 -303.22758) (xy 293.468155 -303.261672) (xy 293.427652 -303.289628) (xy 293.38319 -303.310726)
			(xy 293.335919 -303.324418) (xy 293.287064 -303.33035) (xy 293.237889 -303.328369) (xy 293.18967 -303.318525)
			(xy 293.143654 -303.301073) (xy 293.101033 -303.276466) (xy 293.062912 -303.245341) (xy 293.030277 -303.208504)
			(xy 293.003974 -303.166908) (xy 292.984683 -303.121632) (xy 292.972906 -303.073848) (xy 292.968946 -303.024794)
			(xy 292.630098 -303.024794) (xy 292.629603 -303.049401) (xy 292.621708 -303.097978) (xy 292.606124 -303.144659)
			(xy 292.583253 -303.188236) (xy 292.553688 -303.22758) (xy 292.518195 -303.261672) (xy 292.477692 -303.289628)
			(xy 292.43323 -303.310726) (xy 292.385959 -303.324418) (xy 292.337104 -303.33035) (xy 292.287929 -303.328369)
			(xy 292.23971 -303.318525) (xy 292.193694 -303.301073) (xy 292.151073 -303.276466) (xy 292.112952 -303.245341)
			(xy 292.080317 -303.208504) (xy 292.054014 -303.166908) (xy 292.034723 -303.121632) (xy 292.022946 -303.073848)
			(xy 292.018986 -303.024794) (xy 290.730178 -303.024794) (xy 290.729683 -303.049401) (xy 290.721788 -303.097978)
			(xy 290.706204 -303.144659) (xy 290.683333 -303.188236) (xy 290.653768 -303.22758) (xy 290.618275 -303.261672)
			(xy 290.577772 -303.289628) (xy 290.53331 -303.310726) (xy 290.486039 -303.324418) (xy 290.437184 -303.33035)
			(xy 290.388009 -303.328369) (xy 290.33979 -303.318525) (xy 290.293774 -303.301073) (xy 290.251153 -303.276466)
			(xy 290.213032 -303.245341) (xy 290.180397 -303.208504) (xy 290.154094 -303.166908) (xy 290.134803 -303.121632)
			(xy 290.123026 -303.073848) (xy 290.119066 -303.024794) (xy 289.780218 -303.024794) (xy 289.779723 -303.049401)
			(xy 289.771828 -303.097978) (xy 289.756244 -303.144659) (xy 289.733373 -303.188236) (xy 289.703808 -303.22758)
			(xy 289.668315 -303.261672) (xy 289.627812 -303.289628) (xy 289.58335 -303.310726) (xy 289.536079 -303.324418)
			(xy 289.487224 -303.33035) (xy 289.438049 -303.328369) (xy 289.38983 -303.318525) (xy 289.343814 -303.301073)
			(xy 289.301193 -303.276466) (xy 289.263072 -303.245341) (xy 289.230437 -303.208504) (xy 289.204134 -303.166908)
			(xy 289.184843 -303.121632) (xy 289.173066 -303.073848) (xy 289.169106 -303.024794) (xy 288.830004 -303.024794)
			(xy 288.829509 -303.049401) (xy 288.821614 -303.097978) (xy 288.80603 -303.144659) (xy 288.783159 -303.188236)
			(xy 288.753594 -303.22758) (xy 288.718101 -303.261672) (xy 288.677598 -303.289628) (xy 288.633136 -303.310726)
			(xy 288.585865 -303.324418) (xy 288.53701 -303.33035) (xy 288.487835 -303.328369) (xy 288.439616 -303.318525)
			(xy 288.3936 -303.301073) (xy 288.350979 -303.276466) (xy 288.312858 -303.245341) (xy 288.280223 -303.208504)
			(xy 288.25392 -303.166908) (xy 288.234629 -303.121632) (xy 288.222852 -303.073848) (xy 288.218892 -303.024794)
			(xy 287.880044 -303.024794) (xy 287.879549 -303.049401) (xy 287.871654 -303.097978) (xy 287.85607 -303.144659)
			(xy 287.833199 -303.188236) (xy 287.803634 -303.22758) (xy 287.768141 -303.261672) (xy 287.727638 -303.289628)
			(xy 287.683176 -303.310726) (xy 287.635905 -303.324418) (xy 287.58705 -303.33035) (xy 287.537875 -303.328369)
			(xy 287.489656 -303.318525) (xy 287.44364 -303.301073) (xy 287.401019 -303.276466) (xy 287.362898 -303.245341)
			(xy 287.330263 -303.208504) (xy 287.30396 -303.166908) (xy 287.284669 -303.121632) (xy 287.272892 -303.073848)
			(xy 287.268932 -303.024794) (xy 286.930084 -303.024794) (xy 286.929589 -303.049401) (xy 286.921694 -303.097978)
			(xy 286.90611 -303.144659) (xy 286.883239 -303.188236) (xy 286.853674 -303.22758) (xy 286.818181 -303.261672)
			(xy 286.777678 -303.289628) (xy 286.733216 -303.310726) (xy 286.685945 -303.324418) (xy 286.63709 -303.33035)
			(xy 286.587915 -303.328369) (xy 286.539696 -303.318525) (xy 286.49368 -303.301073) (xy 286.451059 -303.276466)
			(xy 286.412938 -303.245341) (xy 286.380303 -303.208504) (xy 286.354 -303.166908) (xy 286.334709 -303.121632)
			(xy 286.322932 -303.073848) (xy 286.318972 -303.024794) (xy 285.980124 -303.024794) (xy 285.979629 -303.049401)
			(xy 285.971734 -303.097978) (xy 285.95615 -303.144659) (xy 285.933279 -303.188236) (xy 285.903714 -303.22758)
			(xy 285.868221 -303.261672) (xy 285.827718 -303.289628) (xy 285.783256 -303.310726) (xy 285.735985 -303.324418)
			(xy 285.68713 -303.33035) (xy 285.637955 -303.328369) (xy 285.589736 -303.318525) (xy 285.54372 -303.301073)
			(xy 285.501099 -303.276466) (xy 285.462978 -303.245341) (xy 285.430343 -303.208504) (xy 285.40404 -303.166908)
			(xy 285.384749 -303.121632) (xy 285.372972 -303.073848) (xy 285.369012 -303.024794) (xy 285.030164 -303.024794)
			(xy 285.029669 -303.049401) (xy 285.021774 -303.097978) (xy 285.00619 -303.144659) (xy 284.983319 -303.188236)
			(xy 284.953754 -303.22758) (xy 284.918261 -303.261672) (xy 284.877758 -303.289628) (xy 284.833296 -303.310726)
			(xy 284.786025 -303.324418) (xy 284.73717 -303.33035) (xy 284.687995 -303.328369) (xy 284.639776 -303.318525)
			(xy 284.59376 -303.301073) (xy 284.551139 -303.276466) (xy 284.513018 -303.245341) (xy 284.480383 -303.208504)
			(xy 284.45408 -303.166908) (xy 284.434789 -303.121632) (xy 284.423012 -303.073848) (xy 284.419052 -303.024794)
			(xy 284.080204 -303.024794) (xy 284.079709 -303.049401) (xy 284.071814 -303.097978) (xy 284.05623 -303.144659)
			(xy 284.033359 -303.188236) (xy 284.003794 -303.22758) (xy 283.968301 -303.261672) (xy 283.927798 -303.289628)
			(xy 283.883336 -303.310726) (xy 283.836065 -303.324418) (xy 283.78721 -303.33035) (xy 283.738035 -303.328369)
			(xy 283.689816 -303.318525) (xy 283.6438 -303.301073) (xy 283.601179 -303.276466) (xy 283.563058 -303.245341)
			(xy 283.530423 -303.208504) (xy 283.50412 -303.166908) (xy 283.484829 -303.121632) (xy 283.473052 -303.073848)
			(xy 283.469092 -303.024794) (xy 283.130244 -303.024794) (xy 283.129749 -303.049401) (xy 283.121854 -303.097978)
			(xy 283.10627 -303.144659) (xy 283.083399 -303.188236) (xy 283.053834 -303.22758) (xy 283.018341 -303.261672)
			(xy 282.977838 -303.289628) (xy 282.933376 -303.310726) (xy 282.886105 -303.324418) (xy 282.83725 -303.33035)
			(xy 282.788075 -303.328369) (xy 282.739856 -303.318525) (xy 282.69384 -303.301073) (xy 282.651219 -303.276466)
			(xy 282.613098 -303.245341) (xy 282.580463 -303.208504) (xy 282.55416 -303.166908) (xy 282.534869 -303.121632)
			(xy 282.523092 -303.073848) (xy 282.519132 -303.024794) (xy 282.180537 -303.024794) (xy 282.180537 -303.0248)
			(xy 282.176366 -303.075137) (xy 282.163967 -303.124101) (xy 282.143679 -303.170356) (xy 282.116054 -303.212642)
			(xy 282.081846 -303.249804) (xy 282.041989 -303.280829) (xy 281.997568 -303.304871) (xy 281.949797 -303.321274)
			(xy 281.899977 -303.329591) (xy 281.874722 -303.330102) (xy 281.844648 -303.329409) (xy 281.785662 -303.317643)
			(xy 281.757628 -303.306734) (xy 281.745436 -303.301654) (xy 281.720544 -303.304194) (xy 281.639518 -303.358296)
			(xy 281.629461 -303.365815) (xy 281.617612 -303.387922) (xy 281.616912 -303.40046) (xy 281.616912 -303.499774)
			(xy 306.744128 -303.499774) (xy 306.748088 -303.45072) (xy 306.759865 -303.402936) (xy 306.779156 -303.35766)
			(xy 306.805459 -303.316064) (xy 306.838094 -303.279227) (xy 306.876215 -303.248102) (xy 306.918836 -303.223495)
			(xy 306.964852 -303.206043) (xy 307.013071 -303.196199) (xy 307.062246 -303.194218) (xy 307.111101 -303.20015)
			(xy 307.158372 -303.213842) (xy 307.202834 -303.23494) (xy 307.243337 -303.262896) (xy 307.27883 -303.296988)
			(xy 307.308395 -303.336332) (xy 307.331266 -303.379909) (xy 307.34685 -303.42659) (xy 307.354745 -303.475167)
			(xy 307.355074 -303.491531) (xy 307.694155 -303.491531) (xy 307.69952 -303.442176) (xy 307.7128 -303.394338)
			(xy 307.733644 -303.349279) (xy 307.761504 -303.308186) (xy 307.795644 -303.272142) (xy 307.835167 -303.242096)
			(xy 307.879029 -303.21884) (xy 307.926076 -303.202986) (xy 307.975069 -303.194953) (xy 307.999892 -303.194466)
			(xy 308.014075 -303.194644) (xy 308.042315 -303.197315) (xy 308.05628 -303.1998) (xy 308.070247 -303.201963)
			(xy 308.09838 -303.199389) (xy 308.124731 -303.189201) (xy 308.14728 -303.172181) (xy 308.1643 -303.149632)
			(xy 308.174488 -303.123282) (xy 308.177063 -303.095148) (xy 308.174898 -303.081182) (xy 308.172423 -303.067216)
			(xy 308.16975 -303.038976) (xy 308.169564 -303.024794) (xy 308.170084 -302.999973) (xy 308.178117 -302.950986)
			(xy 308.193968 -302.903943) (xy 308.217222 -302.860085) (xy 308.247265 -302.820567) (xy 308.283306 -302.78643)
			(xy 308.324394 -302.758573) (xy 308.369448 -302.737731) (xy 308.417281 -302.724452) (xy 308.466632 -302.719087)
			(xy 308.5162 -302.721777) (xy 308.564681 -302.73245) (xy 308.610796 -302.750827) (xy 308.65333 -302.776422)
			(xy 308.691163 -302.808561) (xy 308.723298 -302.846398) (xy 308.748888 -302.888935) (xy 308.76726 -302.935052)
			(xy 308.777928 -302.983534) (xy 308.780162 -303.024794) (xy 309.119028 -303.024794) (xy 309.122988 -302.97574)
			(xy 309.134765 -302.927956) (xy 309.154056 -302.88268) (xy 309.180359 -302.841084) (xy 309.212994 -302.804247)
			(xy 309.251115 -302.773122) (xy 309.293736 -302.748515) (xy 309.339752 -302.731063) (xy 309.387971 -302.721219)
			(xy 309.437146 -302.719238) (xy 309.486001 -302.72517) (xy 309.533272 -302.738862) (xy 309.577734 -302.75996)
			(xy 309.618237 -302.787916) (xy 309.65373 -302.822008) (xy 309.683295 -302.861352) (xy 309.706166 -302.904929)
			(xy 309.72175 -302.95161) (xy 309.729645 -303.000187) (xy 309.73014 -303.024794) (xy 309.729973 -303.033078)
			(xy 310.069089 -303.033078) (xy 310.071777 -302.983511) (xy 310.082449 -302.935032) (xy 310.100823 -302.888917)
			(xy 310.126415 -302.846383) (xy 310.158551 -302.80855) (xy 310.196385 -302.776414) (xy 310.238919 -302.750822)
			(xy 310.285034 -302.732448) (xy 310.333513 -302.721777) (xy 310.38308 -302.719089) (xy 310.432429 -302.724456)
			(xy 310.48026 -302.737736) (xy 310.525312 -302.758578) (xy 310.566399 -302.786435) (xy 310.602437 -302.820572)
			(xy 310.632479 -302.86009) (xy 310.655731 -302.903947) (xy 310.671582 -302.950988) (xy 310.679614 -302.999974)
			(xy 310.6801 -303.024794) (xy 310.679923 -303.038977) (xy 310.677251 -303.067217) (xy 310.674766 -303.081182)
			(xy 310.67248 -303.093628) (xy 310.679846 -303.11725) (xy 310.757316 -303.19472) (xy 310.780938 -303.202086)
			(xy 310.793384 -303.1998) (xy 310.807349 -303.197316) (xy 310.835589 -303.194649) (xy 310.849772 -303.194466)
			(xy 310.863955 -303.194647) (xy 310.892195 -303.197316) (xy 310.90616 -303.1998) (xy 310.918606 -303.202086)
			(xy 310.942228 -303.19472) (xy 311.019698 -303.11725) (xy 311.027064 -303.093628) (xy 311.024778 -303.081182)
			(xy 311.022303 -303.067216) (xy 311.01963 -303.038976) (xy 311.019444 -303.024794) (xy 311.019984 -302.999973)
			(xy 311.028017 -302.950985) (xy 311.043869 -302.903942) (xy 311.067123 -302.860083) (xy 311.097167 -302.820564)
			(xy 311.133208 -302.786427) (xy 311.174298 -302.758571) (xy 311.219353 -302.737729) (xy 311.267187 -302.724451)
			(xy 311.316538 -302.719087) (xy 311.366107 -302.721778) (xy 311.414588 -302.732453) (xy 311.460703 -302.750831)
			(xy 311.503237 -302.776427) (xy 311.54107 -302.808568) (xy 311.573204 -302.846406) (xy 311.598793 -302.888945)
			(xy 311.617163 -302.935063) (xy 311.62783 -302.983546) (xy 311.630062 -303.024794) (xy 311.968908 -303.024794)
			(xy 311.972868 -302.97574) (xy 311.984645 -302.927956) (xy 312.003936 -302.88268) (xy 312.030239 -302.841084)
			(xy 312.062874 -302.804247) (xy 312.100995 -302.773122) (xy 312.143616 -302.748515) (xy 312.189632 -302.731063)
			(xy 312.237851 -302.721219) (xy 312.287026 -302.719238) (xy 312.335881 -302.72517) (xy 312.383152 -302.738862)
			(xy 312.427614 -302.75996) (xy 312.468117 -302.787916) (xy 312.50361 -302.822008) (xy 312.533175 -302.861352)
			(xy 312.556046 -302.904929) (xy 312.57163 -302.95161) (xy 312.579525 -303.000187) (xy 312.58002 -303.024794)
			(xy 312.919122 -303.024794) (xy 312.923082 -302.97574) (xy 312.934859 -302.927956) (xy 312.95415 -302.88268)
			(xy 312.980453 -302.841084) (xy 313.013088 -302.804247) (xy 313.051209 -302.773122) (xy 313.09383 -302.748515)
			(xy 313.139846 -302.731063) (xy 313.188065 -302.721219) (xy 313.23724 -302.719238) (xy 313.286095 -302.72517)
			(xy 313.333366 -302.738862) (xy 313.377828 -302.75996) (xy 313.418331 -302.787916) (xy 313.453824 -302.822008)
			(xy 313.483389 -302.861352) (xy 313.50626 -302.904929) (xy 313.521844 -302.95161) (xy 313.529739 -303.000187)
			(xy 313.530234 -303.024794) (xy 313.869082 -303.024794) (xy 313.873042 -302.97574) (xy 313.884819 -302.927956)
			(xy 313.90411 -302.88268) (xy 313.930413 -302.841084) (xy 313.963048 -302.804247) (xy 314.001169 -302.773122)
			(xy 314.04379 -302.748515) (xy 314.089806 -302.731063) (xy 314.138025 -302.721219) (xy 314.1872 -302.719238)
			(xy 314.236055 -302.72517) (xy 314.283326 -302.738862) (xy 314.327788 -302.75996) (xy 314.368291 -302.787916)
			(xy 314.403784 -302.822008) (xy 314.433349 -302.861352) (xy 314.45622 -302.904929) (xy 314.471804 -302.95161)
			(xy 314.479699 -303.000187) (xy 314.480194 -303.024794) (xy 314.803802 -303.024794) (xy 314.807762 -302.97574)
			(xy 314.819539 -302.927956) (xy 314.83883 -302.88268) (xy 314.865133 -302.841084) (xy 314.897768 -302.804247)
			(xy 314.935889 -302.773122) (xy 314.97851 -302.748515) (xy 315.024526 -302.731063) (xy 315.072745 -302.721219)
			(xy 315.12192 -302.719238) (xy 315.170775 -302.72517) (xy 315.218046 -302.738862) (xy 315.262508 -302.75996)
			(xy 315.303011 -302.787916) (xy 315.338504 -302.822008) (xy 315.368069 -302.861352) (xy 315.39094 -302.904929)
			(xy 315.406524 -302.95161) (xy 315.414419 -303.000187) (xy 315.414914 -303.024794) (xy 315.414873 -303.026826)
			(xy 320.819524 -303.026826) (xy 320.823595 -302.971204) (xy 320.835721 -302.916767) (xy 320.855644 -302.864676)
			(xy 320.88294 -302.816041) (xy 320.917026 -302.771898) (xy 320.957175 -302.733189) (xy 321.002533 -302.700738)
			(xy 321.052133 -302.675237) (xy 321.104917 -302.65723) (xy 321.15976 -302.6471) (xy 321.215494 -302.645063)
			(xy 321.270931 -302.651163) (xy 321.324888 -302.665269) (xy 321.376217 -302.687081) (xy 321.423823 -302.716135)
			(xy 321.466691 -302.75181) (xy 321.503908 -302.793347) (xy 321.534681 -302.83986) (xy 321.558353 -302.890357)
			(xy 321.574421 -302.943764) (xy 321.582541 -302.99894) (xy 321.58305 -303.026826) (xy 321.835524 -303.026826)
			(xy 321.839595 -302.971204) (xy 321.851721 -302.916767) (xy 321.871644 -302.864676) (xy 321.89894 -302.816041)
			(xy 321.933026 -302.771898) (xy 321.973175 -302.733189) (xy 322.018533 -302.700738) (xy 322.068133 -302.675237)
			(xy 322.120917 -302.65723) (xy 322.17576 -302.6471) (xy 322.231494 -302.645063) (xy 322.286931 -302.651163)
			(xy 322.340888 -302.665269) (xy 322.392217 -302.687081) (xy 322.439823 -302.716135) (xy 322.482691 -302.75181)
			(xy 322.519908 -302.793347) (xy 322.550681 -302.83986) (xy 322.574353 -302.890357) (xy 322.590421 -302.943764)
			(xy 322.598541 -302.99894) (xy 322.59905 -303.026826) (xy 322.851524 -303.026826) (xy 322.855595 -302.971204)
			(xy 322.867721 -302.916767) (xy 322.887644 -302.864676) (xy 322.91494 -302.816041) (xy 322.949026 -302.771898)
			(xy 322.989175 -302.733189) (xy 323.034533 -302.700738) (xy 323.084133 -302.675237) (xy 323.136917 -302.65723)
			(xy 323.19176 -302.6471) (xy 323.247494 -302.645063) (xy 323.302931 -302.651163) (xy 323.356888 -302.665269)
			(xy 323.408217 -302.687081) (xy 323.455823 -302.716135) (xy 323.498691 -302.75181) (xy 323.535908 -302.793347)
			(xy 323.566681 -302.83986) (xy 323.590353 -302.890357) (xy 323.606421 -302.943764) (xy 323.614541 -302.99894)
			(xy 323.61505 -303.026826) (xy 323.867524 -303.026826) (xy 323.871595 -302.971204) (xy 323.883721 -302.916767)
			(xy 323.903644 -302.864676) (xy 323.93094 -302.816041) (xy 323.965026 -302.771898) (xy 324.005175 -302.733189)
			(xy 324.050533 -302.700738) (xy 324.100133 -302.675237) (xy 324.152917 -302.65723) (xy 324.20776 -302.6471)
			(xy 324.263494 -302.645063) (xy 324.318931 -302.651163) (xy 324.372888 -302.665269) (xy 324.424217 -302.687081)
			(xy 324.471823 -302.716135) (xy 324.514691 -302.75181) (xy 324.551908 -302.793347) (xy 324.582681 -302.83986)
			(xy 324.606353 -302.890357) (xy 324.622421 -302.943764) (xy 324.630541 -302.99894) (xy 324.63105 -303.026826)
			(xy 324.883524 -303.026826) (xy 324.887595 -302.971204) (xy 324.899721 -302.916767) (xy 324.919644 -302.864676)
			(xy 324.94694 -302.816041) (xy 324.981026 -302.771898) (xy 325.021175 -302.733189) (xy 325.066533 -302.700738)
			(xy 325.116133 -302.675237) (xy 325.168917 -302.65723) (xy 325.22376 -302.6471) (xy 325.279494 -302.645063)
			(xy 325.334931 -302.651163) (xy 325.388888 -302.665269) (xy 325.440217 -302.687081) (xy 325.487823 -302.716135)
			(xy 325.530691 -302.75181) (xy 325.567908 -302.793347) (xy 325.598681 -302.83986) (xy 325.622353 -302.890357)
			(xy 325.638421 -302.943764) (xy 325.646541 -302.99894) (xy 325.64705 -303.026826) (xy 325.646541 -303.054712)
			(xy 325.638421 -303.109888) (xy 325.62887 -303.141634) (xy 348.984568 -303.141634) (xy 348.988639 -303.086012)
			(xy 349.000765 -303.031575) (xy 349.020688 -302.979484) (xy 349.047984 -302.930849) (xy 349.08207 -302.886706)
			(xy 349.122219 -302.847997) (xy 349.167577 -302.815546) (xy 349.217177 -302.790045) (xy 349.269961 -302.772038)
			(xy 349.324804 -302.761908) (xy 349.380538 -302.759871) (xy 349.435975 -302.765971) (xy 349.489932 -302.780077)
			(xy 349.541261 -302.801889) (xy 349.588867 -302.830943) (xy 349.631735 -302.866618) (xy 349.668952 -302.908155)
			(xy 349.699725 -302.954668) (xy 349.723397 -303.005165) (xy 349.739465 -303.058572) (xy 349.747585 -303.113748)
			(xy 349.748094 -303.141634) (xy 349.747585 -303.16952) (xy 349.739465 -303.224696) (xy 349.723397 -303.278103)
			(xy 349.699725 -303.3286) (xy 349.668952 -303.375113) (xy 349.631735 -303.41665) (xy 349.588867 -303.452325)
			(xy 349.541261 -303.481379) (xy 349.489932 -303.503191) (xy 349.435975 -303.517297) (xy 349.380538 -303.523397)
			(xy 349.324804 -303.52136) (xy 349.269961 -303.51123) (xy 349.217177 -303.493223) (xy 349.167577 -303.467722)
			(xy 349.122219 -303.435271) (xy 349.08207 -303.396562) (xy 349.047984 -303.352419) (xy 349.020688 -303.303784)
			(xy 349.000765 -303.251693) (xy 348.988639 -303.197256) (xy 348.984568 -303.141634) (xy 325.62887 -303.141634)
			(xy 325.622353 -303.163295) (xy 325.598681 -303.213792) (xy 325.567908 -303.260305) (xy 325.530691 -303.301842)
			(xy 325.487823 -303.337517) (xy 325.440217 -303.366571) (xy 325.388888 -303.388383) (xy 325.334931 -303.402489)
			(xy 325.279494 -303.408589) (xy 325.22376 -303.406552) (xy 325.168917 -303.396422) (xy 325.116133 -303.378415)
			(xy 325.066533 -303.352914) (xy 325.021175 -303.320463) (xy 324.981026 -303.281754) (xy 324.94694 -303.237611)
			(xy 324.919644 -303.188976) (xy 324.899721 -303.136885) (xy 324.887595 -303.082448) (xy 324.883524 -303.026826)
			(xy 324.63105 -303.026826) (xy 324.630541 -303.054712) (xy 324.622421 -303.109888) (xy 324.606353 -303.163295)
			(xy 324.582681 -303.213792) (xy 324.551908 -303.260305) (xy 324.514691 -303.301842) (xy 324.471823 -303.337517)
			(xy 324.424217 -303.366571) (xy 324.372888 -303.388383) (xy 324.318931 -303.402489) (xy 324.263494 -303.408589)
			(xy 324.20776 -303.406552) (xy 324.152917 -303.396422) (xy 324.100133 -303.378415) (xy 324.050533 -303.352914)
			(xy 324.005175 -303.320463) (xy 323.965026 -303.281754) (xy 323.93094 -303.237611) (xy 323.903644 -303.188976)
			(xy 323.883721 -303.136885) (xy 323.871595 -303.082448) (xy 323.867524 -303.026826) (xy 323.61505 -303.026826)
			(xy 323.614541 -303.054712) (xy 323.606421 -303.109888) (xy 323.590353 -303.163295) (xy 323.566681 -303.213792)
			(xy 323.535908 -303.260305) (xy 323.498691 -303.301842) (xy 323.455823 -303.337517) (xy 323.408217 -303.366571)
			(xy 323.356888 -303.388383) (xy 323.302931 -303.402489) (xy 323.247494 -303.408589) (xy 323.19176 -303.406552)
			(xy 323.136917 -303.396422) (xy 323.084133 -303.378415) (xy 323.034533 -303.352914) (xy 322.989175 -303.320463)
			(xy 322.949026 -303.281754) (xy 322.91494 -303.237611) (xy 322.887644 -303.188976) (xy 322.867721 -303.136885)
			(xy 322.855595 -303.082448) (xy 322.851524 -303.026826) (xy 322.59905 -303.026826) (xy 322.598541 -303.054712)
			(xy 322.590421 -303.109888) (xy 322.574353 -303.163295) (xy 322.550681 -303.213792) (xy 322.519908 -303.260305)
			(xy 322.482691 -303.301842) (xy 322.439823 -303.337517) (xy 322.392217 -303.366571) (xy 322.340888 -303.388383)
			(xy 322.286931 -303.402489) (xy 322.231494 -303.408589) (xy 322.17576 -303.406552) (xy 322.120917 -303.396422)
			(xy 322.068133 -303.378415) (xy 322.018533 -303.352914) (xy 321.973175 -303.320463) (xy 321.933026 -303.281754)
			(xy 321.89894 -303.237611) (xy 321.871644 -303.188976) (xy 321.851721 -303.136885) (xy 321.839595 -303.082448)
			(xy 321.835524 -303.026826) (xy 321.58305 -303.026826) (xy 321.582541 -303.054712) (xy 321.574421 -303.109888)
			(xy 321.558353 -303.163295) (xy 321.534681 -303.213792) (xy 321.503908 -303.260305) (xy 321.466691 -303.301842)
			(xy 321.423823 -303.337517) (xy 321.376217 -303.366571) (xy 321.324888 -303.388383) (xy 321.270931 -303.402489)
			(xy 321.215494 -303.408589) (xy 321.15976 -303.406552) (xy 321.104917 -303.396422) (xy 321.052133 -303.378415)
			(xy 321.002533 -303.352914) (xy 320.957175 -303.320463) (xy 320.917026 -303.281754) (xy 320.88294 -303.237611)
			(xy 320.855644 -303.188976) (xy 320.835721 -303.136885) (xy 320.823595 -303.082448) (xy 320.819524 -303.026826)
			(xy 315.414873 -303.026826) (xy 315.414419 -303.049401) (xy 315.406524 -303.097978) (xy 315.39094 -303.144659)
			(xy 315.368069 -303.188236) (xy 315.338504 -303.22758) (xy 315.303011 -303.261672) (xy 315.262508 -303.289628)
			(xy 315.218046 -303.310726) (xy 315.170775 -303.324418) (xy 315.12192 -303.33035) (xy 315.072745 -303.328369)
			(xy 315.024526 -303.318525) (xy 314.97851 -303.301073) (xy 314.935889 -303.276466) (xy 314.897768 -303.245341)
			(xy 314.865133 -303.208504) (xy 314.83883 -303.166908) (xy 314.819539 -303.121632) (xy 314.807762 -303.073848)
			(xy 314.803802 -303.024794) (xy 314.480194 -303.024794) (xy 314.479699 -303.049401) (xy 314.471804 -303.097978)
			(xy 314.45622 -303.144659) (xy 314.433349 -303.188236) (xy 314.403784 -303.22758) (xy 314.368291 -303.261672)
			(xy 314.327788 -303.289628) (xy 314.283326 -303.310726) (xy 314.236055 -303.324418) (xy 314.1872 -303.33035)
			(xy 314.138025 -303.328369) (xy 314.089806 -303.318525) (xy 314.04379 -303.301073) (xy 314.001169 -303.276466)
			(xy 313.963048 -303.245341) (xy 313.930413 -303.208504) (xy 313.90411 -303.166908) (xy 313.884819 -303.121632)
			(xy 313.873042 -303.073848) (xy 313.869082 -303.024794) (xy 313.530234 -303.024794) (xy 313.529739 -303.049401)
			(xy 313.521844 -303.097978) (xy 313.50626 -303.144659) (xy 313.483389 -303.188236) (xy 313.453824 -303.22758)
			(xy 313.418331 -303.261672) (xy 313.377828 -303.289628) (xy 313.333366 -303.310726) (xy 313.286095 -303.324418)
			(xy 313.23724 -303.33035) (xy 313.188065 -303.328369) (xy 313.139846 -303.318525) (xy 313.09383 -303.301073)
			(xy 313.051209 -303.276466) (xy 313.013088 -303.245341) (xy 312.980453 -303.208504) (xy 312.95415 -303.166908)
			(xy 312.934859 -303.121632) (xy 312.923082 -303.073848) (xy 312.919122 -303.024794) (xy 312.58002 -303.024794)
			(xy 312.579525 -303.049401) (xy 312.57163 -303.097978) (xy 312.556046 -303.144659) (xy 312.533175 -303.188236)
			(xy 312.50361 -303.22758) (xy 312.468117 -303.261672) (xy 312.427614 -303.289628) (xy 312.383152 -303.310726)
			(xy 312.335881 -303.324418) (xy 312.287026 -303.33035) (xy 312.237851 -303.328369) (xy 312.189632 -303.318525)
			(xy 312.143616 -303.301073) (xy 312.100995 -303.276466) (xy 312.062874 -303.245341) (xy 312.030239 -303.208504)
			(xy 312.003936 -303.166908) (xy 311.984645 -303.121632) (xy 311.972868 -303.073848) (xy 311.968908 -303.024794)
			(xy 311.630062 -303.024794) (xy 311.630512 -303.033116) (xy 311.625139 -303.082466) (xy 311.611853 -303.130298)
			(xy 311.591003 -303.175349) (xy 311.563139 -303.216434) (xy 311.528995 -303.252469) (xy 311.489471 -303.282506)
			(xy 311.445609 -303.305752) (xy 311.398563 -303.321596) (xy 311.349573 -303.32962) (xy 311.324752 -303.330102)
			(xy 311.310569 -303.329918) (xy 311.282329 -303.327251) (xy 311.268364 -303.324768) (xy 311.255918 -303.322482)
			(xy 311.232296 -303.329848) (xy 311.154826 -303.407318) (xy 311.14746 -303.43094) (xy 311.149746 -303.443386)
			(xy 311.152216 -303.457353) (xy 311.154892 -303.485592) (xy 311.15508 -303.499774) (xy 311.154558 -303.525029)
			(xy 311.152702 -303.536153) (xy 317.895173 -303.536153) (xy 317.895173 -303.481647) (xy 317.902931 -303.427697)
			(xy 317.918287 -303.3754) (xy 317.94093 -303.32582) (xy 317.970399 -303.279968) (xy 318.006094 -303.238777)
			(xy 318.047287 -303.203085) (xy 318.093141 -303.173619) (xy 318.142722 -303.150979) (xy 318.19502 -303.135625)
			(xy 318.248971 -303.127872) (xy 318.276224 -303.12741) (xy 318.304673 -303.127942) (xy 318.360943 -303.136369)
			(xy 318.415337 -303.153063) (xy 318.466646 -303.177652) (xy 318.513733 -303.209592) (xy 318.555552 -303.248173)
			(xy 318.591175 -303.292539) (xy 318.619812 -303.341705) (xy 318.630808 -303.367948) (xy 318.63411 -303.376584)
			(xy 318.646302 -303.390046) (xy 318.723264 -303.429162) (xy 318.741044 -303.43094) (xy 318.750442 -303.428654)
			(xy 318.773729 -303.423072) (xy 318.82124 -303.417089) (xy 318.845184 -303.416716) (xy 318.872439 -303.41713)
			(xy 318.926395 -303.424885) (xy 318.978699 -303.440241) (xy 319.028284 -303.462884) (xy 319.074142 -303.492354)
			(xy 319.115339 -303.528049) (xy 319.151037 -303.569245) (xy 319.180508 -303.615102) (xy 319.203153 -303.664686)
			(xy 319.218511 -303.716989) (xy 319.226269 -303.770945) (xy 319.226269 -303.825455) (xy 319.218511 -303.879411)
			(xy 319.203153 -303.931714) (xy 319.180508 -303.981298) (xy 319.151037 -304.027155) (xy 319.115339 -304.068351)
			(xy 319.074142 -304.104046) (xy 319.028284 -304.133516) (xy 318.978699 -304.156159) (xy 318.926395 -304.171515)
			(xy 318.872439 -304.17927) (xy 318.845184 -304.179732) (xy 318.816733 -304.17923) (xy 318.76046 -304.170802)
			(xy 318.706064 -304.154107) (xy 318.654753 -304.129514) (xy 318.607665 -304.097569) (xy 318.565847 -304.058983)
			(xy 318.530226 -304.014612) (xy 318.501594 -303.96544) (xy 318.4906 -303.939194) (xy 318.487298 -303.930558)
			(xy 318.475106 -303.917096) (xy 318.398144 -303.87798) (xy 318.380364 -303.876202) (xy 318.370966 -303.878488)
			(xy 318.347679 -303.884068) (xy 318.300167 -303.890053) (xy 318.276224 -303.890426) (xy 318.248971 -303.889928)
			(xy 318.19502 -303.882175) (xy 318.142722 -303.866821) (xy 318.093141 -303.844181) (xy 318.047287 -303.814715)
			(xy 318.006094 -303.779023) (xy 317.970399 -303.737832) (xy 317.94093 -303.69198) (xy 317.918287 -303.6424)
			(xy 317.902931 -303.590103) (xy 317.895173 -303.536153) (xy 311.152702 -303.536153) (xy 311.146245 -303.574851)
			(xy 311.129844 -303.622625) (xy 311.105803 -303.667048) (xy 311.074779 -303.706908) (xy 311.037617 -303.741118)
			(xy 310.995331 -303.768744) (xy 310.949075 -303.789034) (xy 310.90011 -303.801434) (xy 310.849772 -303.805605)
			(xy 310.799434 -303.801434) (xy 310.750469 -303.789034) (xy 310.704213 -303.768744) (xy 310.661927 -303.741118)
			(xy 310.624765 -303.706908) (xy 310.593741 -303.667048) (xy 310.5697 -303.622625) (xy 310.553299 -303.574851)
			(xy 310.544986 -303.525029) (xy 310.544464 -303.499774) (xy 310.544637 -303.485591) (xy 310.547312 -303.457351)
			(xy 310.549798 -303.443386) (xy 310.552084 -303.43094) (xy 310.544718 -303.407318) (xy 310.467248 -303.329848)
			(xy 310.443626 -303.322482) (xy 310.43118 -303.324768) (xy 310.417214 -303.327243) (xy 310.388974 -303.329916)
			(xy 310.374792 -303.330102) (xy 310.349972 -303.329614) (xy 310.300986 -303.321581) (xy 310.253945 -303.30573)
			(xy 310.210088 -303.282478) (xy 310.170571 -303.252436) (xy 310.136434 -303.216397) (xy 310.108578 -303.17531)
			(xy 310.087735 -303.130258) (xy 310.074455 -303.082427) (xy 310.069089 -303.033078) (xy 309.729973 -303.033078)
			(xy 309.729645 -303.049401) (xy 309.72175 -303.097978) (xy 309.706166 -303.144659) (xy 309.683295 -303.188236)
			(xy 309.65373 -303.22758) (xy 309.618237 -303.261672) (xy 309.577734 -303.289628) (xy 309.533272 -303.310726)
			(xy 309.486001 -303.324418) (xy 309.437146 -303.33035) (xy 309.387971 -303.328369) (xy 309.339752 -303.318525)
			(xy 309.293736 -303.301073) (xy 309.251115 -303.276466) (xy 309.212994 -303.245341) (xy 309.180359 -303.208504)
			(xy 309.154056 -303.166908) (xy 309.134765 -303.121632) (xy 309.122988 -303.073848) (xy 309.119028 -303.024794)
			(xy 308.780162 -303.024794) (xy 308.780612 -303.033102) (xy 308.775242 -303.082452) (xy 308.761958 -303.130284)
			(xy 308.74111 -303.175335) (xy 308.713249 -303.216421) (xy 308.679108 -303.252458) (xy 308.639586 -303.282496)
			(xy 308.595725 -303.305745) (xy 308.548681 -303.321592) (xy 308.499693 -303.329618) (xy 308.474872 -303.330102)
			(xy 308.460689 -303.329929) (xy 308.432449 -303.327255) (xy 308.418484 -303.324768) (xy 308.404519 -303.322605)
			(xy 308.376389 -303.325188) (xy 308.350043 -303.335379) (xy 308.327498 -303.352399) (xy 308.310478 -303.374945)
			(xy 308.300288 -303.401291) (xy 308.297705 -303.429421) (xy 308.299866 -303.443386) (xy 308.302336 -303.457353)
			(xy 308.305012 -303.485592) (xy 308.3052 -303.499774) (xy 308.30475 -303.524597) (xy 308.296722 -303.573591)
			(xy 308.280874 -303.62064) (xy 308.257622 -303.664505) (xy 308.227581 -303.70403) (xy 308.19154 -303.738175)
			(xy 308.15045 -303.766039) (xy 308.105394 -303.786888) (xy 308.057558 -303.800173) (xy 308.008203 -303.805544)
			(xy 307.958629 -303.80286) (xy 307.910142 -303.79219) (xy 307.864021 -303.773817) (xy 307.821479 -303.748224)
			(xy 307.783638 -303.716086) (xy 307.751496 -303.678249) (xy 307.725898 -303.63571) (xy 307.70752 -303.58959)
			(xy 307.696845 -303.541105) (xy 307.694155 -303.491531) (xy 307.355074 -303.491531) (xy 307.35524 -303.499774)
			(xy 307.354745 -303.524381) (xy 307.34685 -303.572958) (xy 307.331266 -303.619639) (xy 307.308395 -303.663216)
			(xy 307.27883 -303.70256) (xy 307.243337 -303.736652) (xy 307.202834 -303.764608) (xy 307.158372 -303.785706)
			(xy 307.111101 -303.799398) (xy 307.062246 -303.80533) (xy 307.013071 -303.803349) (xy 306.964852 -303.793505)
			(xy 306.918836 -303.776053) (xy 306.876215 -303.751446) (xy 306.838094 -303.720321) (xy 306.805459 -303.683484)
			(xy 306.779156 -303.641888) (xy 306.759865 -303.596612) (xy 306.748088 -303.548828) (xy 306.744128 -303.499774)
			(xy 281.616912 -303.499774) (xy 281.616912 -303.599088) (xy 281.617551 -303.611645) (xy 281.629404 -303.633784)
			(xy 281.639518 -303.641252) (xy 281.720544 -303.695354) (xy 281.745436 -303.697894) (xy 281.757628 -303.692814)
			(xy 281.785665 -303.681915) (xy 281.844649 -303.670148) (xy 281.874722 -303.669446) (xy 281.89998 -303.669969)
			(xy 281.949806 -303.678287) (xy 281.997584 -303.694692) (xy 282.042011 -303.718737) (xy 282.081874 -303.749766)
			(xy 282.116086 -303.786933) (xy 282.143715 -303.829225) (xy 282.164006 -303.875486) (xy 282.176406 -303.924457)
			(xy 282.180574 -303.974754) (xy 282.519132 -303.974754) (xy 282.523092 -303.9257) (xy 282.534869 -303.877916)
			(xy 282.55416 -303.83264) (xy 282.580463 -303.791044) (xy 282.613098 -303.754207) (xy 282.651219 -303.723082)
			(xy 282.69384 -303.698475) (xy 282.739856 -303.681023) (xy 282.788075 -303.671179) (xy 282.83725 -303.669198)
			(xy 282.886105 -303.67513) (xy 282.933376 -303.688822) (xy 282.977838 -303.70992) (xy 283.018341 -303.737876)
			(xy 283.053834 -303.771968) (xy 283.083399 -303.811312) (xy 283.10627 -303.854889) (xy 283.121854 -303.90157)
			(xy 283.129749 -303.950147) (xy 283.130244 -303.974754) (xy 283.469092 -303.974754) (xy 283.473052 -303.9257)
			(xy 283.484829 -303.877916) (xy 283.50412 -303.83264) (xy 283.530423 -303.791044) (xy 283.563058 -303.754207)
			(xy 283.601179 -303.723082) (xy 283.6438 -303.698475) (xy 283.689816 -303.681023) (xy 283.738035 -303.671179)
			(xy 283.78721 -303.669198) (xy 283.836065 -303.67513) (xy 283.883336 -303.688822) (xy 283.927798 -303.70992)
			(xy 283.968301 -303.737876) (xy 284.003794 -303.771968) (xy 284.033359 -303.811312) (xy 284.05623 -303.854889)
			(xy 284.071814 -303.90157) (xy 284.079709 -303.950147) (xy 284.080204 -303.974754) (xy 284.419052 -303.974754)
			(xy 284.423012 -303.9257) (xy 284.434789 -303.877916) (xy 284.45408 -303.83264) (xy 284.480383 -303.791044)
			(xy 284.513018 -303.754207) (xy 284.551139 -303.723082) (xy 284.59376 -303.698475) (xy 284.639776 -303.681023)
			(xy 284.687995 -303.671179) (xy 284.73717 -303.669198) (xy 284.786025 -303.67513) (xy 284.833296 -303.688822)
			(xy 284.877758 -303.70992) (xy 284.918261 -303.737876) (xy 284.953754 -303.771968) (xy 284.983319 -303.811312)
			(xy 285.00619 -303.854889) (xy 285.021774 -303.90157) (xy 285.029669 -303.950147) (xy 285.030164 -303.974754)
			(xy 285.369012 -303.974754) (xy 285.372972 -303.9257) (xy 285.384749 -303.877916) (xy 285.40404 -303.83264)
			(xy 285.430343 -303.791044) (xy 285.462978 -303.754207) (xy 285.501099 -303.723082) (xy 285.54372 -303.698475)
			(xy 285.589736 -303.681023) (xy 285.637955 -303.671179) (xy 285.68713 -303.669198) (xy 285.735985 -303.67513)
			(xy 285.783256 -303.688822) (xy 285.827718 -303.70992) (xy 285.868221 -303.737876) (xy 285.903714 -303.771968)
			(xy 285.933279 -303.811312) (xy 285.95615 -303.854889) (xy 285.971734 -303.90157) (xy 285.979629 -303.950147)
			(xy 285.980124 -303.974754) (xy 286.318972 -303.974754) (xy 286.322932 -303.9257) (xy 286.334709 -303.877916)
			(xy 286.354 -303.83264) (xy 286.380303 -303.791044) (xy 286.412938 -303.754207) (xy 286.451059 -303.723082)
			(xy 286.49368 -303.698475) (xy 286.539696 -303.681023) (xy 286.587915 -303.671179) (xy 286.63709 -303.669198)
			(xy 286.685945 -303.67513) (xy 286.733216 -303.688822) (xy 286.777678 -303.70992) (xy 286.818181 -303.737876)
			(xy 286.853674 -303.771968) (xy 286.883239 -303.811312) (xy 286.90611 -303.854889) (xy 286.921694 -303.90157)
			(xy 286.929589 -303.950147) (xy 286.930084 -303.974754) (xy 287.268932 -303.974754) (xy 287.272892 -303.9257)
			(xy 287.284669 -303.877916) (xy 287.30396 -303.83264) (xy 287.330263 -303.791044) (xy 287.362898 -303.754207)
			(xy 287.401019 -303.723082) (xy 287.44364 -303.698475) (xy 287.489656 -303.681023) (xy 287.537875 -303.671179)
			(xy 287.58705 -303.669198) (xy 287.635905 -303.67513) (xy 287.683176 -303.688822) (xy 287.727638 -303.70992)
			(xy 287.768141 -303.737876) (xy 287.803634 -303.771968) (xy 287.833199 -303.811312) (xy 287.85607 -303.854889)
			(xy 287.871654 -303.90157) (xy 287.879549 -303.950147) (xy 287.880044 -303.974754) (xy 288.218892 -303.974754)
			(xy 288.222852 -303.9257) (xy 288.234629 -303.877916) (xy 288.25392 -303.83264) (xy 288.280223 -303.791044)
			(xy 288.312858 -303.754207) (xy 288.350979 -303.723082) (xy 288.3936 -303.698475) (xy 288.439616 -303.681023)
			(xy 288.487835 -303.671179) (xy 288.53701 -303.669198) (xy 288.585865 -303.67513) (xy 288.633136 -303.688822)
			(xy 288.677598 -303.70992) (xy 288.718101 -303.737876) (xy 288.753594 -303.771968) (xy 288.783159 -303.811312)
			(xy 288.80603 -303.854889) (xy 288.821614 -303.90157) (xy 288.829509 -303.950147) (xy 288.830004 -303.974754)
			(xy 289.169106 -303.974754) (xy 289.173066 -303.9257) (xy 289.184843 -303.877916) (xy 289.204134 -303.83264)
			(xy 289.230437 -303.791044) (xy 289.263072 -303.754207) (xy 289.301193 -303.723082) (xy 289.343814 -303.698475)
			(xy 289.38983 -303.681023) (xy 289.438049 -303.671179) (xy 289.487224 -303.669198) (xy 289.536079 -303.67513)
			(xy 289.58335 -303.688822) (xy 289.627812 -303.70992) (xy 289.668315 -303.737876) (xy 289.703808 -303.771968)
			(xy 289.733373 -303.811312) (xy 289.756244 -303.854889) (xy 289.771828 -303.90157) (xy 289.779723 -303.950147)
			(xy 289.780218 -303.974754) (xy 290.119066 -303.974754) (xy 290.123026 -303.9257) (xy 290.134803 -303.877916)
			(xy 290.154094 -303.83264) (xy 290.180397 -303.791044) (xy 290.213032 -303.754207) (xy 290.251153 -303.723082)
			(xy 290.293774 -303.698475) (xy 290.33979 -303.681023) (xy 290.388009 -303.671179) (xy 290.437184 -303.669198)
			(xy 290.486039 -303.67513) (xy 290.53331 -303.688822) (xy 290.577772 -303.70992) (xy 290.618275 -303.737876)
			(xy 290.653768 -303.771968) (xy 290.683333 -303.811312) (xy 290.706204 -303.854889) (xy 290.721788 -303.90157)
			(xy 290.729683 -303.950147) (xy 290.730178 -303.974754) (xy 292.018986 -303.974754) (xy 292.022946 -303.9257)
			(xy 292.034723 -303.877916) (xy 292.054014 -303.83264) (xy 292.080317 -303.791044) (xy 292.112952 -303.754207)
			(xy 292.151073 -303.723082) (xy 292.193694 -303.698475) (xy 292.23971 -303.681023) (xy 292.287929 -303.671179)
			(xy 292.337104 -303.669198) (xy 292.385959 -303.67513) (xy 292.43323 -303.688822) (xy 292.477692 -303.70992)
			(xy 292.518195 -303.737876) (xy 292.553688 -303.771968) (xy 292.583253 -303.811312) (xy 292.606124 -303.854889)
			(xy 292.621708 -303.90157) (xy 292.629603 -303.950147) (xy 292.630098 -303.974754) (xy 292.968946 -303.974754)
			(xy 292.972906 -303.9257) (xy 292.984683 -303.877916) (xy 293.003974 -303.83264) (xy 293.030277 -303.791044)
			(xy 293.062912 -303.754207) (xy 293.101033 -303.723082) (xy 293.143654 -303.698475) (xy 293.18967 -303.681023)
			(xy 293.237889 -303.671179) (xy 293.287064 -303.669198) (xy 293.335919 -303.67513) (xy 293.38319 -303.688822)
			(xy 293.427652 -303.70992) (xy 293.468155 -303.737876) (xy 293.503648 -303.771968) (xy 293.533213 -303.811312)
			(xy 293.556084 -303.854889) (xy 293.571668 -303.90157) (xy 293.579563 -303.950147) (xy 293.580058 -303.974754)
			(xy 293.918906 -303.974754) (xy 293.922866 -303.9257) (xy 293.934643 -303.877916) (xy 293.953934 -303.83264)
			(xy 293.980237 -303.791044) (xy 294.012872 -303.754207) (xy 294.050993 -303.723082) (xy 294.093614 -303.698475)
			(xy 294.13963 -303.681023) (xy 294.187849 -303.671179) (xy 294.237024 -303.669198) (xy 294.285879 -303.67513)
			(xy 294.33315 -303.688822) (xy 294.377612 -303.70992) (xy 294.418115 -303.737876) (xy 294.453608 -303.771968)
			(xy 294.483173 -303.811312) (xy 294.506044 -303.854889) (xy 294.521628 -303.90157) (xy 294.529523 -303.950147)
			(xy 294.530018 -303.974754) (xy 294.86912 -303.974754) (xy 294.87308 -303.9257) (xy 294.884857 -303.877916)
			(xy 294.904148 -303.83264) (xy 294.930451 -303.791044) (xy 294.963086 -303.754207) (xy 295.001207 -303.723082)
			(xy 295.043828 -303.698475) (xy 295.089844 -303.681023) (xy 295.138063 -303.671179) (xy 295.187238 -303.669198)
			(xy 295.236093 -303.67513) (xy 295.283364 -303.688822) (xy 295.327826 -303.70992) (xy 295.368329 -303.737876)
			(xy 295.403822 -303.771968) (xy 295.433387 -303.811312) (xy 295.456258 -303.854889) (xy 295.471842 -303.90157)
			(xy 295.479737 -303.950147) (xy 295.480232 -303.974754) (xy 295.81908 -303.974754) (xy 295.82304 -303.9257)
			(xy 295.834817 -303.877916) (xy 295.854108 -303.83264) (xy 295.880411 -303.791044) (xy 295.913046 -303.754207)
			(xy 295.951167 -303.723082) (xy 295.993788 -303.698475) (xy 296.039804 -303.681023) (xy 296.088023 -303.671179)
			(xy 296.137198 -303.669198) (xy 296.186053 -303.67513) (xy 296.233324 -303.688822) (xy 296.277786 -303.70992)
			(xy 296.318289 -303.737876) (xy 296.353782 -303.771968) (xy 296.383347 -303.811312) (xy 296.406218 -303.854889)
			(xy 296.421802 -303.90157) (xy 296.429697 -303.950147) (xy 296.430192 -303.974754) (xy 296.76904 -303.974754)
			(xy 296.773 -303.9257) (xy 296.784777 -303.877916) (xy 296.804068 -303.83264) (xy 296.830371 -303.791044)
			(xy 296.863006 -303.754207) (xy 296.901127 -303.723082) (xy 296.943748 -303.698475) (xy 296.989764 -303.681023)
			(xy 297.037983 -303.671179) (xy 297.087158 -303.669198) (xy 297.136013 -303.67513) (xy 297.183284 -303.688822)
			(xy 297.227746 -303.70992) (xy 297.268249 -303.737876) (xy 297.303742 -303.771968) (xy 297.333307 -303.811312)
			(xy 297.356178 -303.854889) (xy 297.371762 -303.90157) (xy 297.379657 -303.950147) (xy 297.380152 -303.974754)
			(xy 297.719 -303.974754) (xy 297.72296 -303.9257) (xy 297.734737 -303.877916) (xy 297.754028 -303.83264)
			(xy 297.780331 -303.791044) (xy 297.812966 -303.754207) (xy 297.851087 -303.723082) (xy 297.893708 -303.698475)
			(xy 297.939724 -303.681023) (xy 297.987943 -303.671179) (xy 298.037118 -303.669198) (xy 298.085973 -303.67513)
			(xy 298.133244 -303.688822) (xy 298.177706 -303.70992) (xy 298.218209 -303.737876) (xy 298.253702 -303.771968)
			(xy 298.283267 -303.811312) (xy 298.306138 -303.854889) (xy 298.321722 -303.90157) (xy 298.329617 -303.950147)
			(xy 298.330112 -303.974754) (xy 298.66896 -303.974754) (xy 298.67292 -303.9257) (xy 298.684697 -303.877916)
			(xy 298.703988 -303.83264) (xy 298.730291 -303.791044) (xy 298.762926 -303.754207) (xy 298.801047 -303.723082)
			(xy 298.843668 -303.698475) (xy 298.889684 -303.681023) (xy 298.937903 -303.671179) (xy 298.987078 -303.669198)
			(xy 299.035933 -303.67513) (xy 299.083204 -303.688822) (xy 299.127666 -303.70992) (xy 299.168169 -303.737876)
			(xy 299.203662 -303.771968) (xy 299.233227 -303.811312) (xy 299.256098 -303.854889) (xy 299.271682 -303.90157)
			(xy 299.279577 -303.950147) (xy 299.280072 -303.974754) (xy 299.61892 -303.974754) (xy 299.62288 -303.9257)
			(xy 299.634657 -303.877916) (xy 299.653948 -303.83264) (xy 299.680251 -303.791044) (xy 299.712886 -303.754207)
			(xy 299.751007 -303.723082) (xy 299.793628 -303.698475) (xy 299.839644 -303.681023) (xy 299.887863 -303.671179)
			(xy 299.937038 -303.669198) (xy 299.985893 -303.67513) (xy 300.033164 -303.688822) (xy 300.077626 -303.70992)
			(xy 300.118129 -303.737876) (xy 300.153622 -303.771968) (xy 300.183187 -303.811312) (xy 300.206058 -303.854889)
			(xy 300.221642 -303.90157) (xy 300.229537 -303.950147) (xy 300.229935 -303.969928) (xy 300.57396 -303.969928)
			(xy 300.57792 -303.920874) (xy 300.589697 -303.87309) (xy 300.608988 -303.827814) (xy 300.635291 -303.786218)
			(xy 300.667926 -303.749381) (xy 300.706047 -303.718256) (xy 300.748668 -303.693649) (xy 300.794684 -303.676197)
			(xy 300.842903 -303.666353) (xy 300.892078 -303.664372) (xy 300.940933 -303.670304) (xy 300.988204 -303.683996)
			(xy 301.032666 -303.705094) (xy 301.073169 -303.73305) (xy 301.108662 -303.767142) (xy 301.138227 -303.806486)
			(xy 301.161098 -303.850063) (xy 301.176682 -303.896744) (xy 301.184577 -303.945321) (xy 301.185072 -303.969928)
			(xy 301.184975 -303.974754) (xy 301.519094 -303.974754) (xy 301.523054 -303.9257) (xy 301.534831 -303.877916)
			(xy 301.554122 -303.83264) (xy 301.580425 -303.791044) (xy 301.61306 -303.754207) (xy 301.651181 -303.723082)
			(xy 301.693802 -303.698475) (xy 301.739818 -303.681023) (xy 301.788037 -303.671179) (xy 301.837212 -303.669198)
			(xy 301.886067 -303.67513) (xy 301.933338 -303.688822) (xy 301.9778 -303.70992) (xy 302.018303 -303.737876)
			(xy 302.053796 -303.771968) (xy 302.083361 -303.811312) (xy 302.106232 -303.854889) (xy 302.121816 -303.90157)
			(xy 302.129711 -303.950147) (xy 302.130206 -303.974754) (xy 302.469054 -303.974754) (xy 302.473014 -303.9257)
			(xy 302.484791 -303.877916) (xy 302.504082 -303.83264) (xy 302.530385 -303.791044) (xy 302.56302 -303.754207)
			(xy 302.601141 -303.723082) (xy 302.643762 -303.698475) (xy 302.689778 -303.681023) (xy 302.737997 -303.671179)
			(xy 302.787172 -303.669198) (xy 302.836027 -303.67513) (xy 302.883298 -303.688822) (xy 302.92776 -303.70992)
			(xy 302.968263 -303.737876) (xy 303.003756 -303.771968) (xy 303.033321 -303.811312) (xy 303.056192 -303.854889)
			(xy 303.071776 -303.90157) (xy 303.079671 -303.950147) (xy 303.080166 -303.974754) (xy 303.419014 -303.974754)
			(xy 303.422974 -303.9257) (xy 303.434751 -303.877916) (xy 303.454042 -303.83264) (xy 303.480345 -303.791044)
			(xy 303.51298 -303.754207) (xy 303.551101 -303.723082) (xy 303.593722 -303.698475) (xy 303.639738 -303.681023)
			(xy 303.687957 -303.671179) (xy 303.737132 -303.669198) (xy 303.785987 -303.67513) (xy 303.833258 -303.688822)
			(xy 303.87772 -303.70992) (xy 303.918223 -303.737876) (xy 303.953716 -303.771968) (xy 303.983281 -303.811312)
			(xy 304.006152 -303.854889) (xy 304.021736 -303.90157) (xy 304.029631 -303.950147) (xy 304.030126 -303.974754)
			(xy 304.368974 -303.974754) (xy 304.372934 -303.9257) (xy 304.384711 -303.877916) (xy 304.404002 -303.83264)
			(xy 304.430305 -303.791044) (xy 304.46294 -303.754207) (xy 304.501061 -303.723082) (xy 304.543682 -303.698475)
			(xy 304.589698 -303.681023) (xy 304.637917 -303.671179) (xy 304.687092 -303.669198) (xy 304.735947 -303.67513)
			(xy 304.783218 -303.688822) (xy 304.82768 -303.70992) (xy 304.868183 -303.737876) (xy 304.903676 -303.771968)
			(xy 304.933241 -303.811312) (xy 304.956112 -303.854889) (xy 304.971696 -303.90157) (xy 304.979591 -303.950147)
			(xy 304.980086 -303.974754) (xy 304.979591 -303.999361) (xy 304.971696 -304.047938) (xy 304.956112 -304.094619)
			(xy 304.933241 -304.138196) (xy 304.903676 -304.17754) (xy 304.868183 -304.211632) (xy 304.82768 -304.239588)
			(xy 304.783218 -304.260686) (xy 304.735947 -304.274378) (xy 304.687092 -304.28031) (xy 304.637917 -304.278329)
			(xy 304.589698 -304.268485) (xy 304.543682 -304.251033) (xy 304.501061 -304.226426) (xy 304.46294 -304.195301)
			(xy 304.430305 -304.158464) (xy 304.404002 -304.116868) (xy 304.384711 -304.071592) (xy 304.372934 -304.023808)
			(xy 304.368974 -303.974754) (xy 304.030126 -303.974754) (xy 304.029631 -303.999361) (xy 304.021736 -304.047938)
			(xy 304.006152 -304.094619) (xy 303.983281 -304.138196) (xy 303.953716 -304.17754) (xy 303.918223 -304.211632)
			(xy 303.87772 -304.239588) (xy 303.833258 -304.260686) (xy 303.785987 -304.274378) (xy 303.737132 -304.28031)
			(xy 303.687957 -304.278329) (xy 303.639738 -304.268485) (xy 303.593722 -304.251033) (xy 303.551101 -304.226426)
			(xy 303.51298 -304.195301) (xy 303.480345 -304.158464) (xy 303.454042 -304.116868) (xy 303.434751 -304.071592)
			(xy 303.422974 -304.023808) (xy 303.419014 -303.974754) (xy 303.080166 -303.974754) (xy 303.079671 -303.999361)
			(xy 303.071776 -304.047938) (xy 303.056192 -304.094619) (xy 303.033321 -304.138196) (xy 303.003756 -304.17754)
			(xy 302.968263 -304.211632) (xy 302.92776 -304.239588) (xy 302.883298 -304.260686) (xy 302.836027 -304.274378)
			(xy 302.787172 -304.28031) (xy 302.737997 -304.278329) (xy 302.689778 -304.268485) (xy 302.643762 -304.251033)
			(xy 302.601141 -304.226426) (xy 302.56302 -304.195301) (xy 302.530385 -304.158464) (xy 302.504082 -304.116868)
			(xy 302.484791 -304.071592) (xy 302.473014 -304.023808) (xy 302.469054 -303.974754) (xy 302.130206 -303.974754)
			(xy 302.129711 -303.999361) (xy 302.121816 -304.047938) (xy 302.106232 -304.094619) (xy 302.083361 -304.138196)
			(xy 302.053796 -304.17754) (xy 302.018303 -304.211632) (xy 301.9778 -304.239588) (xy 301.933338 -304.260686)
			(xy 301.886067 -304.274378) (xy 301.837212 -304.28031) (xy 301.788037 -304.278329) (xy 301.739818 -304.268485)
			(xy 301.693802 -304.251033) (xy 301.651181 -304.226426) (xy 301.61306 -304.195301) (xy 301.580425 -304.158464)
			(xy 301.554122 -304.116868) (xy 301.534831 -304.071592) (xy 301.523054 -304.023808) (xy 301.519094 -303.974754)
			(xy 301.184975 -303.974754) (xy 301.184577 -303.994535) (xy 301.176682 -304.043112) (xy 301.161098 -304.089793)
			(xy 301.138227 -304.13337) (xy 301.108662 -304.172714) (xy 301.073169 -304.206806) (xy 301.032666 -304.234762)
			(xy 300.988204 -304.25586) (xy 300.940933 -304.269552) (xy 300.892078 -304.275484) (xy 300.842903 -304.273503)
			(xy 300.794684 -304.263659) (xy 300.748668 -304.246207) (xy 300.706047 -304.2216) (xy 300.667926 -304.190475)
			(xy 300.635291 -304.153638) (xy 300.608988 -304.112042) (xy 300.589697 -304.066766) (xy 300.57792 -304.018982)
			(xy 300.57396 -303.969928) (xy 300.229935 -303.969928) (xy 300.230032 -303.974754) (xy 300.229537 -303.999361)
			(xy 300.221642 -304.047938) (xy 300.206058 -304.094619) (xy 300.183187 -304.138196) (xy 300.153622 -304.17754)
			(xy 300.118129 -304.211632) (xy 300.077626 -304.239588) (xy 300.033164 -304.260686) (xy 299.985893 -304.274378)
			(xy 299.937038 -304.28031) (xy 299.887863 -304.278329) (xy 299.839644 -304.268485) (xy 299.793628 -304.251033)
			(xy 299.751007 -304.226426) (xy 299.712886 -304.195301) (xy 299.680251 -304.158464) (xy 299.653948 -304.116868)
			(xy 299.634657 -304.071592) (xy 299.62288 -304.023808) (xy 299.61892 -303.974754) (xy 299.280072 -303.974754)
			(xy 299.279577 -303.999361) (xy 299.271682 -304.047938) (xy 299.256098 -304.094619) (xy 299.233227 -304.138196)
			(xy 299.203662 -304.17754) (xy 299.168169 -304.211632) (xy 299.127666 -304.239588) (xy 299.083204 -304.260686)
			(xy 299.035933 -304.274378) (xy 298.987078 -304.28031) (xy 298.937903 -304.278329) (xy 298.889684 -304.268485)
			(xy 298.843668 -304.251033) (xy 298.801047 -304.226426) (xy 298.762926 -304.195301) (xy 298.730291 -304.158464)
			(xy 298.703988 -304.116868) (xy 298.684697 -304.071592) (xy 298.67292 -304.023808) (xy 298.66896 -303.974754)
			(xy 298.330112 -303.974754) (xy 298.329617 -303.999361) (xy 298.321722 -304.047938) (xy 298.306138 -304.094619)
			(xy 298.283267 -304.138196) (xy 298.253702 -304.17754) (xy 298.218209 -304.211632) (xy 298.177706 -304.239588)
			(xy 298.133244 -304.260686) (xy 298.085973 -304.274378) (xy 298.037118 -304.28031) (xy 297.987943 -304.278329)
			(xy 297.939724 -304.268485) (xy 297.893708 -304.251033) (xy 297.851087 -304.226426) (xy 297.812966 -304.195301)
			(xy 297.780331 -304.158464) (xy 297.754028 -304.116868) (xy 297.734737 -304.071592) (xy 297.72296 -304.023808)
			(xy 297.719 -303.974754) (xy 297.380152 -303.974754) (xy 297.379657 -303.999361) (xy 297.371762 -304.047938)
			(xy 297.356178 -304.094619) (xy 297.333307 -304.138196) (xy 297.303742 -304.17754) (xy 297.268249 -304.211632)
			(xy 297.227746 -304.239588) (xy 297.183284 -304.260686) (xy 297.136013 -304.274378) (xy 297.087158 -304.28031)
			(xy 297.037983 -304.278329) (xy 296.989764 -304.268485) (xy 296.943748 -304.251033) (xy 296.901127 -304.226426)
			(xy 296.863006 -304.195301) (xy 296.830371 -304.158464) (xy 296.804068 -304.116868) (xy 296.784777 -304.071592)
			(xy 296.773 -304.023808) (xy 296.76904 -303.974754) (xy 296.430192 -303.974754) (xy 296.429697 -303.999361)
			(xy 296.421802 -304.047938) (xy 296.406218 -304.094619) (xy 296.383347 -304.138196) (xy 296.353782 -304.17754)
			(xy 296.318289 -304.211632) (xy 296.277786 -304.239588) (xy 296.233324 -304.260686) (xy 296.186053 -304.274378)
			(xy 296.137198 -304.28031) (xy 296.088023 -304.278329) (xy 296.039804 -304.268485) (xy 295.993788 -304.251033)
			(xy 295.951167 -304.226426) (xy 295.913046 -304.195301) (xy 295.880411 -304.158464) (xy 295.854108 -304.116868)
			(xy 295.834817 -304.071592) (xy 295.82304 -304.023808) (xy 295.81908 -303.974754) (xy 295.480232 -303.974754)
			(xy 295.479737 -303.999361) (xy 295.471842 -304.047938) (xy 295.456258 -304.094619) (xy 295.433387 -304.138196)
			(xy 295.403822 -304.17754) (xy 295.368329 -304.211632) (xy 295.327826 -304.239588) (xy 295.283364 -304.260686)
			(xy 295.236093 -304.274378) (xy 295.187238 -304.28031) (xy 295.138063 -304.278329) (xy 295.089844 -304.268485)
			(xy 295.043828 -304.251033) (xy 295.001207 -304.226426) (xy 294.963086 -304.195301) (xy 294.930451 -304.158464)
			(xy 294.904148 -304.116868) (xy 294.884857 -304.071592) (xy 294.87308 -304.023808) (xy 294.86912 -303.974754)
			(xy 294.530018 -303.974754) (xy 294.529523 -303.999361) (xy 294.521628 -304.047938) (xy 294.506044 -304.094619)
			(xy 294.483173 -304.138196) (xy 294.453608 -304.17754) (xy 294.418115 -304.211632) (xy 294.377612 -304.239588)
			(xy 294.33315 -304.260686) (xy 294.285879 -304.274378) (xy 294.237024 -304.28031) (xy 294.187849 -304.278329)
			(xy 294.13963 -304.268485) (xy 294.093614 -304.251033) (xy 294.050993 -304.226426) (xy 294.012872 -304.195301)
			(xy 293.980237 -304.158464) (xy 293.953934 -304.116868) (xy 293.934643 -304.071592) (xy 293.922866 -304.023808)
			(xy 293.918906 -303.974754) (xy 293.580058 -303.974754) (xy 293.579563 -303.999361) (xy 293.571668 -304.047938)
			(xy 293.556084 -304.094619) (xy 293.533213 -304.138196) (xy 293.503648 -304.17754) (xy 293.468155 -304.211632)
			(xy 293.427652 -304.239588) (xy 293.38319 -304.260686) (xy 293.335919 -304.274378) (xy 293.287064 -304.28031)
			(xy 293.237889 -304.278329) (xy 293.18967 -304.268485) (xy 293.143654 -304.251033) (xy 293.101033 -304.226426)
			(xy 293.062912 -304.195301) (xy 293.030277 -304.158464) (xy 293.003974 -304.116868) (xy 292.984683 -304.071592)
			(xy 292.972906 -304.023808) (xy 292.968946 -303.974754) (xy 292.630098 -303.974754) (xy 292.629603 -303.999361)
			(xy 292.621708 -304.047938) (xy 292.606124 -304.094619) (xy 292.583253 -304.138196) (xy 292.553688 -304.17754)
			(xy 292.518195 -304.211632) (xy 292.477692 -304.239588) (xy 292.43323 -304.260686) (xy 292.385959 -304.274378)
			(xy 292.337104 -304.28031) (xy 292.287929 -304.278329) (xy 292.23971 -304.268485) (xy 292.193694 -304.251033)
			(xy 292.151073 -304.226426) (xy 292.112952 -304.195301) (xy 292.080317 -304.158464) (xy 292.054014 -304.116868)
			(xy 292.034723 -304.071592) (xy 292.022946 -304.023808) (xy 292.018986 -303.974754) (xy 290.730178 -303.974754)
			(xy 290.729683 -303.999361) (xy 290.721788 -304.047938) (xy 290.706204 -304.094619) (xy 290.683333 -304.138196)
			(xy 290.653768 -304.17754) (xy 290.618275 -304.211632) (xy 290.577772 -304.239588) (xy 290.53331 -304.260686)
			(xy 290.486039 -304.274378) (xy 290.437184 -304.28031) (xy 290.388009 -304.278329) (xy 290.33979 -304.268485)
			(xy 290.293774 -304.251033) (xy 290.251153 -304.226426) (xy 290.213032 -304.195301) (xy 290.180397 -304.158464)
			(xy 290.154094 -304.116868) (xy 290.134803 -304.071592) (xy 290.123026 -304.023808) (xy 290.119066 -303.974754)
			(xy 289.780218 -303.974754) (xy 289.779723 -303.999361) (xy 289.771828 -304.047938) (xy 289.756244 -304.094619)
			(xy 289.733373 -304.138196) (xy 289.703808 -304.17754) (xy 289.668315 -304.211632) (xy 289.627812 -304.239588)
			(xy 289.58335 -304.260686) (xy 289.536079 -304.274378) (xy 289.487224 -304.28031) (xy 289.438049 -304.278329)
			(xy 289.38983 -304.268485) (xy 289.343814 -304.251033) (xy 289.301193 -304.226426) (xy 289.263072 -304.195301)
			(xy 289.230437 -304.158464) (xy 289.204134 -304.116868) (xy 289.184843 -304.071592) (xy 289.173066 -304.023808)
			(xy 289.169106 -303.974754) (xy 288.830004 -303.974754) (xy 288.829509 -303.999361) (xy 288.821614 -304.047938)
			(xy 288.80603 -304.094619) (xy 288.783159 -304.138196) (xy 288.753594 -304.17754) (xy 288.718101 -304.211632)
			(xy 288.677598 -304.239588) (xy 288.633136 -304.260686) (xy 288.585865 -304.274378) (xy 288.53701 -304.28031)
			(xy 288.487835 -304.278329) (xy 288.439616 -304.268485) (xy 288.3936 -304.251033) (xy 288.350979 -304.226426)
			(xy 288.312858 -304.195301) (xy 288.280223 -304.158464) (xy 288.25392 -304.116868) (xy 288.234629 -304.071592)
			(xy 288.222852 -304.023808) (xy 288.218892 -303.974754) (xy 287.880044 -303.974754) (xy 287.879549 -303.999361)
			(xy 287.871654 -304.047938) (xy 287.85607 -304.094619) (xy 287.833199 -304.138196) (xy 287.803634 -304.17754)
			(xy 287.768141 -304.211632) (xy 287.727638 -304.239588) (xy 287.683176 -304.260686) (xy 287.635905 -304.274378)
			(xy 287.58705 -304.28031) (xy 287.537875 -304.278329) (xy 287.489656 -304.268485) (xy 287.44364 -304.251033)
			(xy 287.401019 -304.226426) (xy 287.362898 -304.195301) (xy 287.330263 -304.158464) (xy 287.30396 -304.116868)
			(xy 287.284669 -304.071592) (xy 287.272892 -304.023808) (xy 287.268932 -303.974754) (xy 286.930084 -303.974754)
			(xy 286.929589 -303.999361) (xy 286.921694 -304.047938) (xy 286.90611 -304.094619) (xy 286.883239 -304.138196)
			(xy 286.853674 -304.17754) (xy 286.818181 -304.211632) (xy 286.777678 -304.239588) (xy 286.733216 -304.260686)
			(xy 286.685945 -304.274378) (xy 286.63709 -304.28031) (xy 286.587915 -304.278329) (xy 286.539696 -304.268485)
			(xy 286.49368 -304.251033) (xy 286.451059 -304.226426) (xy 286.412938 -304.195301) (xy 286.380303 -304.158464)
			(xy 286.354 -304.116868) (xy 286.334709 -304.071592) (xy 286.322932 -304.023808) (xy 286.318972 -303.974754)
			(xy 285.980124 -303.974754) (xy 285.979629 -303.999361) (xy 285.971734 -304.047938) (xy 285.95615 -304.094619)
			(xy 285.933279 -304.138196) (xy 285.903714 -304.17754) (xy 285.868221 -304.211632) (xy 285.827718 -304.239588)
			(xy 285.783256 -304.260686) (xy 285.735985 -304.274378) (xy 285.68713 -304.28031) (xy 285.637955 -304.278329)
			(xy 285.589736 -304.268485) (xy 285.54372 -304.251033) (xy 285.501099 -304.226426) (xy 285.462978 -304.195301)
			(xy 285.430343 -304.158464) (xy 285.40404 -304.116868) (xy 285.384749 -304.071592) (xy 285.372972 -304.023808)
			(xy 285.369012 -303.974754) (xy 285.030164 -303.974754) (xy 285.029669 -303.999361) (xy 285.021774 -304.047938)
			(xy 285.00619 -304.094619) (xy 284.983319 -304.138196) (xy 284.953754 -304.17754) (xy 284.918261 -304.211632)
			(xy 284.877758 -304.239588) (xy 284.833296 -304.260686) (xy 284.786025 -304.274378) (xy 284.73717 -304.28031)
			(xy 284.687995 -304.278329) (xy 284.639776 -304.268485) (xy 284.59376 -304.251033) (xy 284.551139 -304.226426)
			(xy 284.513018 -304.195301) (xy 284.480383 -304.158464) (xy 284.45408 -304.116868) (xy 284.434789 -304.071592)
			(xy 284.423012 -304.023808) (xy 284.419052 -303.974754) (xy 284.080204 -303.974754) (xy 284.079709 -303.999361)
			(xy 284.071814 -304.047938) (xy 284.05623 -304.094619) (xy 284.033359 -304.138196) (xy 284.003794 -304.17754)
			(xy 283.968301 -304.211632) (xy 283.927798 -304.239588) (xy 283.883336 -304.260686) (xy 283.836065 -304.274378)
			(xy 283.78721 -304.28031) (xy 283.738035 -304.278329) (xy 283.689816 -304.268485) (xy 283.6438 -304.251033)
			(xy 283.601179 -304.226426) (xy 283.563058 -304.195301) (xy 283.530423 -304.158464) (xy 283.50412 -304.116868)
			(xy 283.484829 -304.071592) (xy 283.473052 -304.023808) (xy 283.469092 -303.974754) (xy 283.130244 -303.974754)
			(xy 283.129749 -303.999361) (xy 283.121854 -304.047938) (xy 283.10627 -304.094619) (xy 283.083399 -304.138196)
			(xy 283.053834 -304.17754) (xy 283.018341 -304.211632) (xy 282.977838 -304.239588) (xy 282.933376 -304.260686)
			(xy 282.886105 -304.274378) (xy 282.83725 -304.28031) (xy 282.788075 -304.278329) (xy 282.739856 -304.268485)
			(xy 282.69384 -304.251033) (xy 282.651219 -304.226426) (xy 282.613098 -304.195301) (xy 282.580463 -304.158464)
			(xy 282.55416 -304.116868) (xy 282.534869 -304.071592) (xy 282.523092 -304.023808) (xy 282.519132 -303.974754)
			(xy 282.180574 -303.974754) (xy 282.180578 -303.9748) (xy 282.176406 -304.025143) (xy 282.164006 -304.074114)
			(xy 282.143715 -304.120375) (xy 282.116086 -304.162667) (xy 282.081874 -304.199834) (xy 282.042011 -304.230863)
			(xy 281.997584 -304.254908) (xy 281.949806 -304.271313) (xy 281.89998 -304.279631) (xy 281.874722 -304.280062)
			(xy 281.844648 -304.279369) (xy 281.785663 -304.267602) (xy 281.757628 -304.256694) (xy 281.745436 -304.251614)
			(xy 281.720544 -304.254154) (xy 281.639518 -304.308256) (xy 281.629454 -304.315772) (xy 281.617589 -304.337879)
			(xy 281.616912 -304.35042) (xy 281.616912 -304.449734) (xy 305.793914 -304.449734) (xy 305.797874 -304.40068)
			(xy 305.809651 -304.352896) (xy 305.828942 -304.30762) (xy 305.855245 -304.266024) (xy 305.88788 -304.229187)
			(xy 305.926001 -304.198062) (xy 305.968622 -304.173455) (xy 306.014638 -304.156003) (xy 306.062857 -304.146159)
			(xy 306.112032 -304.144178) (xy 306.160887 -304.15011) (xy 306.208158 -304.163802) (xy 306.25262 -304.1849)
			(xy 306.293123 -304.212856) (xy 306.328616 -304.246948) (xy 306.358181 -304.286292) (xy 306.381052 -304.329869)
			(xy 306.396636 -304.37655) (xy 306.404531 -304.425127) (xy 306.405026 -304.449734) (xy 306.404531 -304.474341)
			(xy 306.404352 -304.475442) (xy 306.723284 -304.475442) (xy 306.723284 -304.424026) (xy 306.731327 -304.373244)
			(xy 306.747215 -304.324345) (xy 306.770558 -304.278533) (xy 306.800779 -304.236937) (xy 306.837135 -304.200581)
			(xy 306.878731 -304.17036) (xy 306.924543 -304.147017) (xy 306.973442 -304.131129) (xy 307.024224 -304.123086)
			(xy 307.07564 -304.123086) (xy 307.126422 -304.131129) (xy 307.175321 -304.147017) (xy 307.221133 -304.17036)
			(xy 307.262729 -304.200581) (xy 307.299085 -304.236937) (xy 307.329306 -304.278533) (xy 307.352649 -304.324345)
			(xy 307.368537 -304.373244) (xy 307.37658 -304.424026) (xy 307.377084 -304.449734) (xy 307.37658 -304.475442)
			(xy 307.673244 -304.475442) (xy 307.673244 -304.424026) (xy 307.681287 -304.373244) (xy 307.697175 -304.324345)
			(xy 307.720518 -304.278533) (xy 307.750739 -304.236937) (xy 307.787095 -304.200581) (xy 307.828691 -304.17036)
			(xy 307.874503 -304.147017) (xy 307.923402 -304.131129) (xy 307.974184 -304.123086) (xy 308.0256 -304.123086)
			(xy 308.076382 -304.131129) (xy 308.125281 -304.147017) (xy 308.171093 -304.17036) (xy 308.212689 -304.200581)
			(xy 308.249045 -304.236937) (xy 308.279266 -304.278533) (xy 308.302609 -304.324345) (xy 308.318497 -304.373244)
			(xy 308.32654 -304.424026) (xy 308.327044 -304.449734) (xy 308.644048 -304.449734) (xy 308.648008 -304.40068)
			(xy 308.659785 -304.352896) (xy 308.679076 -304.30762) (xy 308.705379 -304.266024) (xy 308.738014 -304.229187)
			(xy 308.776135 -304.198062) (xy 308.818756 -304.173455) (xy 308.864772 -304.156003) (xy 308.912991 -304.146159)
			(xy 308.962166 -304.144178) (xy 309.011021 -304.15011) (xy 309.058292 -304.163802) (xy 309.102754 -304.1849)
			(xy 309.143257 -304.212856) (xy 309.17875 -304.246948) (xy 309.208315 -304.286292) (xy 309.231186 -304.329869)
			(xy 309.24677 -304.37655) (xy 309.254665 -304.425127) (xy 309.25516 -304.449734) (xy 309.594008 -304.449734)
			(xy 309.597968 -304.40068) (xy 309.609745 -304.352896) (xy 309.629036 -304.30762) (xy 309.655339 -304.266024)
			(xy 309.687974 -304.229187) (xy 309.726095 -304.198062) (xy 309.768716 -304.173455) (xy 309.814732 -304.156003)
			(xy 309.862951 -304.146159) (xy 309.912126 -304.144178) (xy 309.960981 -304.15011) (xy 310.008252 -304.163802)
			(xy 310.052714 -304.1849) (xy 310.093217 -304.212856) (xy 310.12871 -304.246948) (xy 310.158275 -304.286292)
			(xy 310.181146 -304.329869) (xy 310.19673 -304.37655) (xy 310.204625 -304.425127) (xy 310.20512 -304.449734)
			(xy 310.543968 -304.449734) (xy 310.547928 -304.40068) (xy 310.559705 -304.352896) (xy 310.578996 -304.30762)
			(xy 310.605299 -304.266024) (xy 310.637934 -304.229187) (xy 310.676055 -304.198062) (xy 310.718676 -304.173455)
			(xy 310.764692 -304.156003) (xy 310.812911 -304.146159) (xy 310.862086 -304.144178) (xy 310.910941 -304.15011)
			(xy 310.958212 -304.163802) (xy 311.002674 -304.1849) (xy 311.043177 -304.212856) (xy 311.07867 -304.246948)
			(xy 311.108235 -304.286292) (xy 311.131106 -304.329869) (xy 311.14669 -304.37655) (xy 311.154585 -304.425127)
			(xy 311.154912 -304.441387) (xy 311.494016 -304.441387) (xy 311.499388 -304.392042) (xy 311.512672 -304.344216)
			(xy 311.533519 -304.29917) (xy 311.561378 -304.25809) (xy 311.595517 -304.222058) (xy 311.635035 -304.192024)
			(xy 311.678891 -304.168778) (xy 311.725931 -304.152934) (xy 311.774914 -304.144909) (xy 311.799732 -304.144426)
			(xy 311.813915 -304.144598) (xy 311.842155 -304.147273) (xy 311.85612 -304.14976) (xy 311.868566 -304.152046)
			(xy 311.892188 -304.14468) (xy 311.969658 -304.06721) (xy 311.977024 -304.043588) (xy 311.974738 -304.031142)
			(xy 311.972258 -304.017177) (xy 311.969588 -303.988937) (xy 311.969404 -303.974754) (xy 311.969926 -303.949499)
			(xy 311.978239 -303.899677) (xy 311.99464 -303.851903) (xy 312.018681 -303.80748) (xy 312.049705 -303.76762)
			(xy 312.086867 -303.73341) (xy 312.129153 -303.705784) (xy 312.175409 -303.685494) (xy 312.224374 -303.673094)
			(xy 312.274712 -303.668923) (xy 312.32505 -303.673094) (xy 312.374015 -303.685494) (xy 312.420271 -303.705784)
			(xy 312.462557 -303.73341) (xy 312.499719 -303.76762) (xy 312.530743 -303.80748) (xy 312.554784 -303.851903)
			(xy 312.571185 -303.899677) (xy 312.579498 -303.949499) (xy 312.58002 -303.974754) (xy 312.579837 -303.988937)
			(xy 312.577169 -304.017177) (xy 312.574686 -304.031142) (xy 312.5724 -304.043588) (xy 312.579766 -304.06721)
			(xy 312.657236 -304.14468) (xy 312.680858 -304.152046) (xy 312.693304 -304.14976) (xy 312.707271 -304.147287)
			(xy 312.73551 -304.144613) (xy 312.749692 -304.144426) (xy 312.763939 -304.144596) (xy 312.792307 -304.147263)
			(xy 312.806334 -304.14976) (xy 312.818526 -304.152046) (xy 312.842656 -304.14468) (xy 312.919872 -304.067464)
			(xy 312.927238 -304.043588) (xy 312.924952 -304.031142) (xy 312.922472 -304.017177) (xy 312.919802 -303.988937)
			(xy 312.919618 -303.974754) (xy 312.92014 -303.949499) (xy 312.928453 -303.899677) (xy 312.944854 -303.851903)
			(xy 312.968895 -303.80748) (xy 312.999919 -303.76762) (xy 313.037081 -303.73341) (xy 313.079367 -303.705784)
			(xy 313.125623 -303.685494) (xy 313.174588 -303.673094) (xy 313.224926 -303.668923) (xy 313.275264 -303.673094)
			(xy 313.324229 -303.685494) (xy 313.370485 -303.705784) (xy 313.412771 -303.73341) (xy 313.449933 -303.76762)
			(xy 313.480957 -303.80748) (xy 313.504998 -303.851903) (xy 313.521399 -303.899677) (xy 313.529712 -303.949499)
			(xy 313.530234 -303.974754) (xy 313.530051 -303.988937) (xy 313.527383 -304.017177) (xy 313.5249 -304.031142)
			(xy 313.522614 -304.043588) (xy 313.52998 -304.06721) (xy 313.60745 -304.14468) (xy 313.631072 -304.152046)
			(xy 313.643518 -304.14976) (xy 313.657484 -304.147286) (xy 313.685724 -304.144612) (xy 313.699906 -304.144426)
			(xy 313.724726 -304.144884) (xy 313.773711 -304.152916) (xy 313.820752 -304.168766) (xy 313.864609 -304.192018)
			(xy 313.904126 -304.222058) (xy 313.938263 -304.258096) (xy 313.96612 -304.299182) (xy 313.986964 -304.344233)
			(xy 314.000245 -304.392063) (xy 314.005613 -304.441411) (xy 314.005162 -304.449734) (xy 314.344062 -304.449734)
			(xy 314.348022 -304.40068) (xy 314.359799 -304.352896) (xy 314.37909 -304.30762) (xy 314.405393 -304.266024)
			(xy 314.438028 -304.229187) (xy 314.476149 -304.198062) (xy 314.51877 -304.173455) (xy 314.564786 -304.156003)
			(xy 314.613005 -304.146159) (xy 314.66218 -304.144178) (xy 314.711035 -304.15011) (xy 314.758306 -304.163802)
			(xy 314.802768 -304.1849) (xy 314.843271 -304.212856) (xy 314.878764 -304.246948) (xy 314.908329 -304.286292)
			(xy 314.9312 -304.329869) (xy 314.946784 -304.37655) (xy 314.954679 -304.425127) (xy 314.955174 -304.449734)
			(xy 315.294276 -304.449734) (xy 315.298236 -304.40068) (xy 315.310013 -304.352896) (xy 315.329304 -304.30762)
			(xy 315.355607 -304.266024) (xy 315.388242 -304.229187) (xy 315.426363 -304.198062) (xy 315.468984 -304.173455)
			(xy 315.515 -304.156003) (xy 315.563219 -304.146159) (xy 315.612394 -304.144178) (xy 315.661249 -304.15011)
			(xy 315.70852 -304.163802) (xy 315.752982 -304.1849) (xy 315.793485 -304.212856) (xy 315.828978 -304.246948)
			(xy 315.858543 -304.286292) (xy 315.881414 -304.329869) (xy 315.896998 -304.37655) (xy 315.904893 -304.425127)
			(xy 315.905388 -304.449734) (xy 315.904893 -304.474341) (xy 315.896998 -304.522918) (xy 315.881414 -304.569599)
			(xy 315.858543 -304.613176) (xy 315.828978 -304.65252) (xy 315.793485 -304.686612) (xy 315.752982 -304.714568)
			(xy 315.70852 -304.735666) (xy 315.661249 -304.749358) (xy 315.612394 -304.75529) (xy 315.563219 -304.753309)
			(xy 315.515 -304.743465) (xy 315.468984 -304.726013) (xy 315.426363 -304.701406) (xy 315.388242 -304.670281)
			(xy 315.355607 -304.633444) (xy 315.329304 -304.591848) (xy 315.310013 -304.546572) (xy 315.298236 -304.498788)
			(xy 315.294276 -304.449734) (xy 314.955174 -304.449734) (xy 314.954679 -304.474341) (xy 314.946784 -304.522918)
			(xy 314.9312 -304.569599) (xy 314.908329 -304.613176) (xy 314.878764 -304.65252) (xy 314.843271 -304.686612)
			(xy 314.802768 -304.714568) (xy 314.758306 -304.735666) (xy 314.711035 -304.749358) (xy 314.66218 -304.75529)
			(xy 314.613005 -304.753309) (xy 314.564786 -304.743465) (xy 314.51877 -304.726013) (xy 314.476149 -304.701406)
			(xy 314.438028 -304.670281) (xy 314.405393 -304.633444) (xy 314.37909 -304.591848) (xy 314.359799 -304.546572)
			(xy 314.348022 -304.498788) (xy 314.344062 -304.449734) (xy 314.005162 -304.449734) (xy 314.002927 -304.490978)
			(xy 313.992257 -304.539457) (xy 313.973885 -304.585572) (xy 313.948295 -304.628106) (xy 313.916161 -304.665941)
			(xy 313.878329 -304.698079) (xy 313.835797 -304.723673) (xy 313.789684 -304.742049) (xy 313.741206 -304.752723)
			(xy 313.691639 -304.755413) (xy 313.642291 -304.75005) (xy 313.59446 -304.736774) (xy 313.549406 -304.715934)
			(xy 313.508318 -304.688081) (xy 313.472277 -304.653947) (xy 313.442233 -304.614432) (xy 313.418977 -304.570577)
			(xy 313.403123 -304.523538) (xy 313.395087 -304.474554) (xy 313.394598 -304.449734) (xy 313.394779 -304.435551)
			(xy 313.397448 -304.407311) (xy 313.399932 -304.393346) (xy 313.402218 -304.3809) (xy 313.394852 -304.357278)
			(xy 313.317382 -304.279808) (xy 313.29376 -304.272442) (xy 313.281314 -304.274728) (xy 313.267347 -304.277199)
			(xy 313.239108 -304.279874) (xy 313.224926 -304.280062) (xy 313.210679 -304.279904) (xy 313.182311 -304.277229)
			(xy 313.168284 -304.274728) (xy 313.156092 -304.272442) (xy 313.131962 -304.279808) (xy 313.054746 -304.357024)
			(xy 313.04738 -304.3809) (xy 313.049666 -304.393346) (xy 313.052145 -304.407312) (xy 313.054815 -304.435551)
			(xy 313.055 -304.449734) (xy 313.054478 -304.474989) (xy 313.046165 -304.524811) (xy 313.029764 -304.572585)
			(xy 313.005723 -304.617008) (xy 312.974699 -304.656868) (xy 312.937537 -304.691078) (xy 312.895251 -304.718704)
			(xy 312.848995 -304.738994) (xy 312.80003 -304.751394) (xy 312.749692 -304.755565) (xy 312.699354 -304.751394)
			(xy 312.650389 -304.738994) (xy 312.604133 -304.718704) (xy 312.561847 -304.691078) (xy 312.524685 -304.656868)
			(xy 312.493661 -304.617008) (xy 312.46962 -304.572585) (xy 312.453219 -304.524811) (xy 312.444906 -304.474989)
			(xy 312.444384 -304.449734) (xy 312.444565 -304.435551) (xy 312.447234 -304.407311) (xy 312.449718 -304.393346)
			(xy 312.452004 -304.3809) (xy 312.444638 -304.357278) (xy 312.367168 -304.279808) (xy 312.343546 -304.272442)
			(xy 312.3311 -304.274728) (xy 312.317134 -304.277201) (xy 312.288894 -304.279875) (xy 312.274712 -304.280062)
			(xy 312.260529 -304.279884) (xy 312.232289 -304.277213) (xy 312.218324 -304.274728) (xy 312.205878 -304.272442)
			(xy 312.182256 -304.279808) (xy 312.104786 -304.357278) (xy 312.09742 -304.3809) (xy 312.099706 -304.393346)
			(xy 312.102185 -304.407311) (xy 312.104855 -304.435551) (xy 312.10504 -304.449734) (xy 312.104485 -304.474552)
			(xy 312.09645 -304.523533) (xy 312.080596 -304.570569) (xy 312.057341 -304.614421) (xy 312.027298 -304.653933)
			(xy 311.991259 -304.688063) (xy 311.950172 -304.715914) (xy 311.905121 -304.736751) (xy 311.857293 -304.750025)
			(xy 311.807947 -304.755386) (xy 311.758384 -304.752693) (xy 311.70991 -304.742018) (xy 311.663801 -304.72364)
			(xy 311.621273 -304.698046) (xy 311.583445 -304.665908) (xy 311.551316 -304.628074) (xy 311.52573 -304.58554)
			(xy 311.507363 -304.539427) (xy 311.496698 -304.49095) (xy 311.494016 -304.441387) (xy 311.154912 -304.441387)
			(xy 311.15508 -304.449734) (xy 311.154585 -304.474341) (xy 311.14669 -304.522918) (xy 311.131106 -304.569599)
			(xy 311.108235 -304.613176) (xy 311.07867 -304.65252) (xy 311.043177 -304.686612) (xy 311.002674 -304.714568)
			(xy 310.958212 -304.735666) (xy 310.910941 -304.749358) (xy 310.862086 -304.75529) (xy 310.812911 -304.753309)
			(xy 310.764692 -304.743465) (xy 310.718676 -304.726013) (xy 310.676055 -304.701406) (xy 310.637934 -304.670281)
			(xy 310.605299 -304.633444) (xy 310.578996 -304.591848) (xy 310.559705 -304.546572) (xy 310.547928 -304.498788)
			(xy 310.543968 -304.449734) (xy 310.20512 -304.449734) (xy 310.204625 -304.474341) (xy 310.19673 -304.522918)
			(xy 310.181146 -304.569599) (xy 310.158275 -304.613176) (xy 310.12871 -304.65252) (xy 310.093217 -304.686612)
			(xy 310.052714 -304.714568) (xy 310.008252 -304.735666) (xy 309.960981 -304.749358) (xy 309.912126 -304.75529)
			(xy 309.862951 -304.753309) (xy 309.814732 -304.743465) (xy 309.768716 -304.726013) (xy 309.726095 -304.701406)
			(xy 309.687974 -304.670281) (xy 309.655339 -304.633444) (xy 309.629036 -304.591848) (xy 309.609745 -304.546572)
			(xy 309.597968 -304.498788) (xy 309.594008 -304.449734) (xy 309.25516 -304.449734) (xy 309.254665 -304.474341)
			(xy 309.24677 -304.522918) (xy 309.231186 -304.569599) (xy 309.208315 -304.613176) (xy 309.17875 -304.65252)
			(xy 309.143257 -304.686612) (xy 309.102754 -304.714568) (xy 309.058292 -304.735666) (xy 309.011021 -304.749358)
			(xy 308.962166 -304.75529) (xy 308.912991 -304.753309) (xy 308.864772 -304.743465) (xy 308.818756 -304.726013)
			(xy 308.776135 -304.701406) (xy 308.738014 -304.670281) (xy 308.705379 -304.633444) (xy 308.679076 -304.591848)
			(xy 308.659785 -304.546572) (xy 308.648008 -304.498788) (xy 308.644048 -304.449734) (xy 308.327044 -304.449734)
			(xy 308.32654 -304.475442) (xy 308.318497 -304.526224) (xy 308.302609 -304.575123) (xy 308.279266 -304.620935)
			(xy 308.249045 -304.662531) (xy 308.212689 -304.698887) (xy 308.171093 -304.729108) (xy 308.125281 -304.752451)
			(xy 308.076382 -304.768339) (xy 308.0256 -304.776382) (xy 307.974184 -304.776382) (xy 307.923402 -304.768339)
			(xy 307.874503 -304.752451) (xy 307.828691 -304.729108) (xy 307.787095 -304.698887) (xy 307.750739 -304.662531)
			(xy 307.720518 -304.620935) (xy 307.697175 -304.575123) (xy 307.681287 -304.526224) (xy 307.673244 -304.475442)
			(xy 307.37658 -304.475442) (xy 307.368537 -304.526224) (xy 307.352649 -304.575123) (xy 307.329306 -304.620935)
			(xy 307.299085 -304.662531) (xy 307.262729 -304.698887) (xy 307.221133 -304.729108) (xy 307.175321 -304.752451)
			(xy 307.126422 -304.768339) (xy 307.07564 -304.776382) (xy 307.024224 -304.776382) (xy 306.973442 -304.768339)
			(xy 306.924543 -304.752451) (xy 306.878731 -304.729108) (xy 306.837135 -304.698887) (xy 306.800779 -304.662531)
			(xy 306.770558 -304.620935) (xy 306.747215 -304.575123) (xy 306.731327 -304.526224) (xy 306.723284 -304.475442)
			(xy 306.404352 -304.475442) (xy 306.396636 -304.522918) (xy 306.381052 -304.569599) (xy 306.358181 -304.613176)
			(xy 306.328616 -304.65252) (xy 306.293123 -304.686612) (xy 306.25262 -304.714568) (xy 306.208158 -304.735666)
			(xy 306.160887 -304.749358) (xy 306.112032 -304.75529) (xy 306.062857 -304.753309) (xy 306.014638 -304.743465)
			(xy 305.968622 -304.726013) (xy 305.926001 -304.701406) (xy 305.88788 -304.670281) (xy 305.855245 -304.633444)
			(xy 305.828942 -304.591848) (xy 305.809651 -304.546572) (xy 305.797874 -304.498788) (xy 305.793914 -304.449734)
			(xy 281.616912 -304.449734) (xy 281.616912 -304.549048) (xy 281.617565 -304.561598) (xy 281.629432 -304.583714)
			(xy 281.639518 -304.591212) (xy 281.720544 -304.645314) (xy 281.745436 -304.647854) (xy 281.757628 -304.642774)
			(xy 281.785665 -304.631876) (xy 281.844649 -304.620111) (xy 281.874722 -304.619406) (xy 281.899975 -304.619929)
			(xy 281.949792 -304.628245) (xy 281.99756 -304.644647) (xy 282.041978 -304.668688) (xy 282.081833 -304.699711)
			(xy 282.116038 -304.736871) (xy 282.143661 -304.779153) (xy 282.163948 -304.825406) (xy 282.176346 -304.874366)
			(xy 282.180517 -304.9247) (xy 282.180516 -304.924714) (xy 282.519132 -304.924714) (xy 282.523092 -304.87566)
			(xy 282.534869 -304.827876) (xy 282.55416 -304.7826) (xy 282.580463 -304.741004) (xy 282.613098 -304.704167)
			(xy 282.651219 -304.673042) (xy 282.69384 -304.648435) (xy 282.739856 -304.630983) (xy 282.788075 -304.621139)
			(xy 282.83725 -304.619158) (xy 282.886105 -304.62509) (xy 282.933376 -304.638782) (xy 282.977838 -304.65988)
			(xy 283.018341 -304.687836) (xy 283.053834 -304.721928) (xy 283.083399 -304.761272) (xy 283.10627 -304.804849)
			(xy 283.121854 -304.85153) (xy 283.129749 -304.900107) (xy 283.130244 -304.924714) (xy 283.469092 -304.924714)
			(xy 283.473052 -304.87566) (xy 283.484829 -304.827876) (xy 283.50412 -304.7826) (xy 283.530423 -304.741004)
			(xy 283.563058 -304.704167) (xy 283.601179 -304.673042) (xy 283.6438 -304.648435) (xy 283.689816 -304.630983)
			(xy 283.738035 -304.621139) (xy 283.78721 -304.619158) (xy 283.836065 -304.62509) (xy 283.883336 -304.638782)
			(xy 283.927798 -304.65988) (xy 283.968301 -304.687836) (xy 284.003794 -304.721928) (xy 284.033359 -304.761272)
			(xy 284.05623 -304.804849) (xy 284.071814 -304.85153) (xy 284.079709 -304.900107) (xy 284.080204 -304.924714)
			(xy 284.419052 -304.924714) (xy 284.423012 -304.87566) (xy 284.434789 -304.827876) (xy 284.45408 -304.7826)
			(xy 284.480383 -304.741004) (xy 284.513018 -304.704167) (xy 284.551139 -304.673042) (xy 284.59376 -304.648435)
			(xy 284.639776 -304.630983) (xy 284.687995 -304.621139) (xy 284.73717 -304.619158) (xy 284.786025 -304.62509)
			(xy 284.833296 -304.638782) (xy 284.877758 -304.65988) (xy 284.918261 -304.687836) (xy 284.953754 -304.721928)
			(xy 284.983319 -304.761272) (xy 285.00619 -304.804849) (xy 285.021774 -304.85153) (xy 285.029669 -304.900107)
			(xy 285.030164 -304.924714) (xy 285.369012 -304.924714) (xy 285.372972 -304.87566) (xy 285.384749 -304.827876)
			(xy 285.40404 -304.7826) (xy 285.430343 -304.741004) (xy 285.462978 -304.704167) (xy 285.501099 -304.673042)
			(xy 285.54372 -304.648435) (xy 285.589736 -304.630983) (xy 285.637955 -304.621139) (xy 285.68713 -304.619158)
			(xy 285.735985 -304.62509) (xy 285.783256 -304.638782) (xy 285.827718 -304.65988) (xy 285.868221 -304.687836)
			(xy 285.903714 -304.721928) (xy 285.933279 -304.761272) (xy 285.95615 -304.804849) (xy 285.971734 -304.85153)
			(xy 285.979629 -304.900107) (xy 285.980124 -304.924714) (xy 286.318972 -304.924714) (xy 286.322932 -304.87566)
			(xy 286.334709 -304.827876) (xy 286.354 -304.7826) (xy 286.380303 -304.741004) (xy 286.412938 -304.704167)
			(xy 286.451059 -304.673042) (xy 286.49368 -304.648435) (xy 286.539696 -304.630983) (xy 286.587915 -304.621139)
			(xy 286.63709 -304.619158) (xy 286.685945 -304.62509) (xy 286.733216 -304.638782) (xy 286.777678 -304.65988)
			(xy 286.818181 -304.687836) (xy 286.853674 -304.721928) (xy 286.883239 -304.761272) (xy 286.90611 -304.804849)
			(xy 286.921694 -304.85153) (xy 286.929589 -304.900107) (xy 286.930084 -304.924714) (xy 287.268932 -304.924714)
			(xy 287.272892 -304.87566) (xy 287.284669 -304.827876) (xy 287.30396 -304.7826) (xy 287.330263 -304.741004)
			(xy 287.362898 -304.704167) (xy 287.401019 -304.673042) (xy 287.44364 -304.648435) (xy 287.489656 -304.630983)
			(xy 287.537875 -304.621139) (xy 287.58705 -304.619158) (xy 287.635905 -304.62509) (xy 287.683176 -304.638782)
			(xy 287.727638 -304.65988) (xy 287.768141 -304.687836) (xy 287.803634 -304.721928) (xy 287.833199 -304.761272)
			(xy 287.85607 -304.804849) (xy 287.871654 -304.85153) (xy 287.879549 -304.900107) (xy 287.880044 -304.924714)
			(xy 288.218892 -304.924714) (xy 288.222852 -304.87566) (xy 288.234629 -304.827876) (xy 288.25392 -304.7826)
			(xy 288.280223 -304.741004) (xy 288.312858 -304.704167) (xy 288.350979 -304.673042) (xy 288.3936 -304.648435)
			(xy 288.439616 -304.630983) (xy 288.487835 -304.621139) (xy 288.53701 -304.619158) (xy 288.585865 -304.62509)
			(xy 288.633136 -304.638782) (xy 288.677598 -304.65988) (xy 288.718101 -304.687836) (xy 288.753594 -304.721928)
			(xy 288.783159 -304.761272) (xy 288.80603 -304.804849) (xy 288.821614 -304.85153) (xy 288.829509 -304.900107)
			(xy 288.830004 -304.924714) (xy 289.169106 -304.924714) (xy 289.173066 -304.87566) (xy 289.184843 -304.827876)
			(xy 289.204134 -304.7826) (xy 289.230437 -304.741004) (xy 289.263072 -304.704167) (xy 289.301193 -304.673042)
			(xy 289.343814 -304.648435) (xy 289.38983 -304.630983) (xy 289.438049 -304.621139) (xy 289.487224 -304.619158)
			(xy 289.536079 -304.62509) (xy 289.58335 -304.638782) (xy 289.627812 -304.65988) (xy 289.668315 -304.687836)
			(xy 289.703808 -304.721928) (xy 289.733373 -304.761272) (xy 289.756244 -304.804849) (xy 289.771828 -304.85153)
			(xy 289.779723 -304.900107) (xy 289.780218 -304.924714) (xy 290.119066 -304.924714) (xy 290.123026 -304.87566)
			(xy 290.134803 -304.827876) (xy 290.154094 -304.7826) (xy 290.180397 -304.741004) (xy 290.213032 -304.704167)
			(xy 290.251153 -304.673042) (xy 290.293774 -304.648435) (xy 290.33979 -304.630983) (xy 290.388009 -304.621139)
			(xy 290.437184 -304.619158) (xy 290.486039 -304.62509) (xy 290.53331 -304.638782) (xy 290.577772 -304.65988)
			(xy 290.618275 -304.687836) (xy 290.653768 -304.721928) (xy 290.683333 -304.761272) (xy 290.706204 -304.804849)
			(xy 290.721788 -304.85153) (xy 290.729683 -304.900107) (xy 290.730178 -304.924714) (xy 292.018986 -304.924714)
			(xy 292.022946 -304.87566) (xy 292.034723 -304.827876) (xy 292.054014 -304.7826) (xy 292.080317 -304.741004)
			(xy 292.112952 -304.704167) (xy 292.151073 -304.673042) (xy 292.193694 -304.648435) (xy 292.23971 -304.630983)
			(xy 292.287929 -304.621139) (xy 292.337104 -304.619158) (xy 292.385959 -304.62509) (xy 292.43323 -304.638782)
			(xy 292.477692 -304.65988) (xy 292.518195 -304.687836) (xy 292.553688 -304.721928) (xy 292.583253 -304.761272)
			(xy 292.606124 -304.804849) (xy 292.621708 -304.85153) (xy 292.629603 -304.900107) (xy 292.630098 -304.924714)
			(xy 292.968946 -304.924714) (xy 292.972906 -304.87566) (xy 292.984683 -304.827876) (xy 293.003974 -304.7826)
			(xy 293.030277 -304.741004) (xy 293.062912 -304.704167) (xy 293.101033 -304.673042) (xy 293.143654 -304.648435)
			(xy 293.18967 -304.630983) (xy 293.237889 -304.621139) (xy 293.287064 -304.619158) (xy 293.335919 -304.62509)
			(xy 293.38319 -304.638782) (xy 293.427652 -304.65988) (xy 293.468155 -304.687836) (xy 293.503648 -304.721928)
			(xy 293.533213 -304.761272) (xy 293.556084 -304.804849) (xy 293.571668 -304.85153) (xy 293.579563 -304.900107)
			(xy 293.580058 -304.924714) (xy 293.918906 -304.924714) (xy 293.922866 -304.87566) (xy 293.934643 -304.827876)
			(xy 293.953934 -304.7826) (xy 293.980237 -304.741004) (xy 294.012872 -304.704167) (xy 294.050993 -304.673042)
			(xy 294.093614 -304.648435) (xy 294.13963 -304.630983) (xy 294.187849 -304.621139) (xy 294.237024 -304.619158)
			(xy 294.285879 -304.62509) (xy 294.33315 -304.638782) (xy 294.377612 -304.65988) (xy 294.418115 -304.687836)
			(xy 294.453608 -304.721928) (xy 294.483173 -304.761272) (xy 294.506044 -304.804849) (xy 294.521628 -304.85153)
			(xy 294.529523 -304.900107) (xy 294.530018 -304.924714) (xy 294.86912 -304.924714) (xy 294.87308 -304.87566)
			(xy 294.884857 -304.827876) (xy 294.904148 -304.7826) (xy 294.930451 -304.741004) (xy 294.963086 -304.704167)
			(xy 295.001207 -304.673042) (xy 295.043828 -304.648435) (xy 295.089844 -304.630983) (xy 295.138063 -304.621139)
			(xy 295.187238 -304.619158) (xy 295.236093 -304.62509) (xy 295.283364 -304.638782) (xy 295.327826 -304.65988)
			(xy 295.368329 -304.687836) (xy 295.403822 -304.721928) (xy 295.433387 -304.761272) (xy 295.456258 -304.804849)
			(xy 295.471842 -304.85153) (xy 295.479737 -304.900107) (xy 295.480232 -304.924714) (xy 295.81908 -304.924714)
			(xy 295.82304 -304.87566) (xy 295.834817 -304.827876) (xy 295.854108 -304.7826) (xy 295.880411 -304.741004)
			(xy 295.913046 -304.704167) (xy 295.951167 -304.673042) (xy 295.993788 -304.648435) (xy 296.039804 -304.630983)
			(xy 296.088023 -304.621139) (xy 296.137198 -304.619158) (xy 296.186053 -304.62509) (xy 296.233324 -304.638782)
			(xy 296.277786 -304.65988) (xy 296.318289 -304.687836) (xy 296.353782 -304.721928) (xy 296.383347 -304.761272)
			(xy 296.406218 -304.804849) (xy 296.421802 -304.85153) (xy 296.429697 -304.900107) (xy 296.430192 -304.924714)
			(xy 296.76904 -304.924714) (xy 296.773 -304.87566) (xy 296.784777 -304.827876) (xy 296.804068 -304.7826)
			(xy 296.830371 -304.741004) (xy 296.863006 -304.704167) (xy 296.901127 -304.673042) (xy 296.943748 -304.648435)
			(xy 296.989764 -304.630983) (xy 297.037983 -304.621139) (xy 297.087158 -304.619158) (xy 297.136013 -304.62509)
			(xy 297.183284 -304.638782) (xy 297.227746 -304.65988) (xy 297.268249 -304.687836) (xy 297.303742 -304.721928)
			(xy 297.333307 -304.761272) (xy 297.356178 -304.804849) (xy 297.371762 -304.85153) (xy 297.379657 -304.900107)
			(xy 297.380152 -304.924714) (xy 297.719 -304.924714) (xy 297.72296 -304.87566) (xy 297.734737 -304.827876)
			(xy 297.754028 -304.7826) (xy 297.780331 -304.741004) (xy 297.812966 -304.704167) (xy 297.851087 -304.673042)
			(xy 297.893708 -304.648435) (xy 297.939724 -304.630983) (xy 297.987943 -304.621139) (xy 298.037118 -304.619158)
			(xy 298.085973 -304.62509) (xy 298.133244 -304.638782) (xy 298.177706 -304.65988) (xy 298.218209 -304.687836)
			(xy 298.253702 -304.721928) (xy 298.283267 -304.761272) (xy 298.306138 -304.804849) (xy 298.321722 -304.85153)
			(xy 298.329617 -304.900107) (xy 298.330112 -304.924714) (xy 298.66896 -304.924714) (xy 298.67292 -304.87566)
			(xy 298.684697 -304.827876) (xy 298.703988 -304.7826) (xy 298.730291 -304.741004) (xy 298.762926 -304.704167)
			(xy 298.801047 -304.673042) (xy 298.843668 -304.648435) (xy 298.889684 -304.630983) (xy 298.937903 -304.621139)
			(xy 298.987078 -304.619158) (xy 299.035933 -304.62509) (xy 299.083204 -304.638782) (xy 299.127666 -304.65988)
			(xy 299.168169 -304.687836) (xy 299.203662 -304.721928) (xy 299.233227 -304.761272) (xy 299.256098 -304.804849)
			(xy 299.271682 -304.85153) (xy 299.279577 -304.900107) (xy 299.280072 -304.924714) (xy 299.61892 -304.924714)
			(xy 299.62288 -304.87566) (xy 299.634657 -304.827876) (xy 299.653948 -304.7826) (xy 299.680251 -304.741004)
			(xy 299.712886 -304.704167) (xy 299.751007 -304.673042) (xy 299.793628 -304.648435) (xy 299.839644 -304.630983)
			(xy 299.887863 -304.621139) (xy 299.937038 -304.619158) (xy 299.985893 -304.62509) (xy 300.033164 -304.638782)
			(xy 300.077626 -304.65988) (xy 300.118129 -304.687836) (xy 300.153622 -304.721928) (xy 300.183187 -304.761272)
			(xy 300.206058 -304.804849) (xy 300.221642 -304.85153) (xy 300.229537 -304.900107) (xy 300.230032 -304.924714)
			(xy 300.56888 -304.924714) (xy 300.57284 -304.87566) (xy 300.584617 -304.827876) (xy 300.603908 -304.7826)
			(xy 300.630211 -304.741004) (xy 300.662846 -304.704167) (xy 300.700967 -304.673042) (xy 300.743588 -304.648435)
			(xy 300.789604 -304.630983) (xy 300.837823 -304.621139) (xy 300.886998 -304.619158) (xy 300.935853 -304.62509)
			(xy 300.983124 -304.638782) (xy 301.027586 -304.65988) (xy 301.068089 -304.687836) (xy 301.103582 -304.721928)
			(xy 301.133147 -304.761272) (xy 301.156018 -304.804849) (xy 301.171602 -304.85153) (xy 301.179497 -304.900107)
			(xy 301.179992 -304.924714) (xy 301.519094 -304.924714) (xy 301.523054 -304.87566) (xy 301.534831 -304.827876)
			(xy 301.554122 -304.7826) (xy 301.580425 -304.741004) (xy 301.61306 -304.704167) (xy 301.651181 -304.673042)
			(xy 301.693802 -304.648435) (xy 301.739818 -304.630983) (xy 301.788037 -304.621139) (xy 301.837212 -304.619158)
			(xy 301.886067 -304.62509) (xy 301.933338 -304.638782) (xy 301.9778 -304.65988) (xy 302.018303 -304.687836)
			(xy 302.053796 -304.721928) (xy 302.083361 -304.761272) (xy 302.106232 -304.804849) (xy 302.121816 -304.85153)
			(xy 302.129711 -304.900107) (xy 302.130206 -304.924714) (xy 302.469054 -304.924714) (xy 302.473014 -304.87566)
			(xy 302.484791 -304.827876) (xy 302.504082 -304.7826) (xy 302.530385 -304.741004) (xy 302.56302 -304.704167)
			(xy 302.601141 -304.673042) (xy 302.643762 -304.648435) (xy 302.689778 -304.630983) (xy 302.737997 -304.621139)
			(xy 302.787172 -304.619158) (xy 302.836027 -304.62509) (xy 302.883298 -304.638782) (xy 302.92776 -304.65988)
			(xy 302.968263 -304.687836) (xy 303.003756 -304.721928) (xy 303.033321 -304.761272) (xy 303.056192 -304.804849)
			(xy 303.071776 -304.85153) (xy 303.079671 -304.900107) (xy 303.080166 -304.924714) (xy 303.419014 -304.924714)
			(xy 303.422974 -304.87566) (xy 303.434751 -304.827876) (xy 303.454042 -304.7826) (xy 303.480345 -304.741004)
			(xy 303.51298 -304.704167) (xy 303.551101 -304.673042) (xy 303.593722 -304.648435) (xy 303.639738 -304.630983)
			(xy 303.687957 -304.621139) (xy 303.737132 -304.619158) (xy 303.785987 -304.62509) (xy 303.833258 -304.638782)
			(xy 303.87772 -304.65988) (xy 303.918223 -304.687836) (xy 303.953716 -304.721928) (xy 303.983281 -304.761272)
			(xy 304.006152 -304.804849) (xy 304.021736 -304.85153) (xy 304.029631 -304.900107) (xy 304.030126 -304.924714)
			(xy 304.368974 -304.924714) (xy 304.372934 -304.87566) (xy 304.384711 -304.827876) (xy 304.404002 -304.7826)
			(xy 304.430305 -304.741004) (xy 304.46294 -304.704167) (xy 304.501061 -304.673042) (xy 304.543682 -304.648435)
			(xy 304.589698 -304.630983) (xy 304.637917 -304.621139) (xy 304.687092 -304.619158) (xy 304.735947 -304.62509)
			(xy 304.783218 -304.638782) (xy 304.82768 -304.65988) (xy 304.868183 -304.687836) (xy 304.903676 -304.721928)
			(xy 304.933241 -304.761272) (xy 304.943098 -304.780052) (xy 320.049634 -304.780052) (xy 320.049634 -304.725548)
			(xy 320.05739 -304.671598) (xy 320.072744 -304.619301) (xy 320.095385 -304.569721) (xy 320.12485 -304.523868)
			(xy 320.16054 -304.482674) (xy 320.20173 -304.446979) (xy 320.247579 -304.417508) (xy 320.297156 -304.394861)
			(xy 320.349451 -304.3795) (xy 320.4034 -304.371737) (xy 320.430652 -304.371248) (xy 320.457798 -304.371686)
			(xy 320.511542 -304.379369) (xy 320.563653 -304.394598) (xy 320.613075 -304.417068) (xy 320.65881 -304.446323)
			(xy 320.699931 -304.481771) (xy 320.735606 -304.522694) (xy 320.765115 -304.568266) (xy 320.787858 -304.617563)
			(xy 320.803377 -304.669588) (xy 320.807842 -304.696368) (xy 320.810662 -304.711198) (xy 320.823697 -304.738407)
			(xy 320.844104 -304.760628) (xy 320.870107 -304.775928) (xy 320.899443 -304.782974) (xy 320.929558 -304.781155)
			(xy 320.957832 -304.770627) (xy 320.970148 -304.7619) (xy 320.990212 -304.747097) (xy 321.033428 -304.722226)
			(xy 321.079513 -304.703192) (xy 321.127683 -304.690317) (xy 321.177119 -304.683822) (xy 321.20205 -304.683414)
			(xy 321.229307 -304.683829) (xy 321.283266 -304.691581) (xy 321.335573 -304.706934) (xy 321.385163 -304.729575)
			(xy 321.431025 -304.759043) (xy 321.472226 -304.794739) (xy 321.507927 -304.835935) (xy 321.537401 -304.881793)
			(xy 321.560049 -304.93138) (xy 321.575408 -304.983685) (xy 321.583167 -305.037643) (xy 321.583167 -305.064922)
			(xy 321.835016 -305.064922) (xy 321.839087 -305.0093) (xy 321.851213 -304.954863) (xy 321.871136 -304.902772)
			(xy 321.898432 -304.854137) (xy 321.932518 -304.809994) (xy 321.972667 -304.771285) (xy 322.018025 -304.738834)
			(xy 322.067625 -304.713333) (xy 322.120409 -304.695326) (xy 322.175252 -304.685196) (xy 322.230986 -304.683159)
			(xy 322.286423 -304.689259) (xy 322.34038 -304.703365) (xy 322.391709 -304.725177) (xy 322.439315 -304.754231)
			(xy 322.482183 -304.789906) (xy 322.5194 -304.831443) (xy 322.550173 -304.877956) (xy 322.573845 -304.928453)
			(xy 322.589913 -304.98186) (xy 322.598033 -305.037036) (xy 322.598542 -305.064922) (xy 322.843396 -305.064922)
			(xy 322.847467 -305.0093) (xy 322.859593 -304.954863) (xy 322.879516 -304.902772) (xy 322.906812 -304.854137)
			(xy 322.940898 -304.809994) (xy 322.981047 -304.771285) (xy 323.026405 -304.738834) (xy 323.076005 -304.713333)
			(xy 323.128789 -304.695326) (xy 323.183632 -304.685196) (xy 323.239366 -304.683159) (xy 323.294803 -304.689259)
			(xy 323.34876 -304.703365) (xy 323.400089 -304.725177) (xy 323.447695 -304.754231) (xy 323.490563 -304.789906)
			(xy 323.52778 -304.831443) (xy 323.558553 -304.877956) (xy 323.582225 -304.928453) (xy 323.598293 -304.98186)
			(xy 323.606413 -305.037036) (xy 323.606903 -305.063906) (xy 323.868032 -305.063906) (xy 323.872103 -305.008284)
			(xy 323.884229 -304.953847) (xy 323.904152 -304.901756) (xy 323.931448 -304.853121) (xy 323.965534 -304.808978)
			(xy 324.005683 -304.770269) (xy 324.051041 -304.737818) (xy 324.100641 -304.712317) (xy 324.153425 -304.69431)
			(xy 324.208268 -304.68418) (xy 324.264002 -304.682143) (xy 324.319439 -304.688243) (xy 324.373396 -304.702349)
			(xy 324.424725 -304.724161) (xy 324.472331 -304.753215) (xy 324.515199 -304.78889) (xy 324.552416 -304.830427)
			(xy 324.583189 -304.87694) (xy 324.606861 -304.927437) (xy 324.622929 -304.980844) (xy 324.631049 -305.03602)
			(xy 324.631233 -305.046126) (xy 324.884032 -305.046126) (xy 324.888103 -304.990504) (xy 324.900229 -304.936067)
			(xy 324.920152 -304.883976) (xy 324.947448 -304.835341) (xy 324.981534 -304.791198) (xy 325.021683 -304.752489)
			(xy 325.067041 -304.720038) (xy 325.116641 -304.694537) (xy 325.169425 -304.67653) (xy 325.224268 -304.6664)
			(xy 325.280002 -304.664363) (xy 325.335439 -304.670463) (xy 325.389396 -304.684569) (xy 325.440725 -304.706381)
			(xy 325.488331 -304.735435) (xy 325.531199 -304.77111) (xy 325.568416 -304.812647) (xy 325.599189 -304.85916)
			(xy 325.622861 -304.909657) (xy 325.638929 -304.963064) (xy 325.645621 -305.008534) (xy 334.435704 -305.008534)
			(xy 334.436189 -304.981164) (xy 334.444002 -304.926986) (xy 334.459487 -304.874483) (xy 334.482324 -304.824736)
			(xy 334.512045 -304.778768) (xy 334.529684 -304.757836) (xy 334.53578 -304.750724) (xy 334.54213 -304.733706)
			(xy 334.54213 -304.648362) (xy 334.53578 -304.631344) (xy 334.529684 -304.624232) (xy 334.512044 -304.603301)
			(xy 334.482333 -304.557327) (xy 334.459497 -304.50758) (xy 334.444006 -304.455079) (xy 334.436178 -304.400903)
			(xy 334.435704 -304.373534) (xy 334.43619 -304.346283) (xy 334.443946 -304.292335) (xy 334.459301 -304.24004)
			(xy 334.481943 -304.190463) (xy 334.511409 -304.144613) (xy 334.5471 -304.103422) (xy 334.588291 -304.067731)
			(xy 334.634141 -304.038265) (xy 334.683718 -304.015623) (xy 334.736013 -304.000268) (xy 334.789961 -303.992512)
			(xy 334.844463 -303.992512) (xy 334.898411 -304.000268) (xy 334.950706 -304.015623) (xy 335.000283 -304.038265)
			(xy 335.046133 -304.067731) (xy 335.087324 -304.103422) (xy 335.123015 -304.144613) (xy 335.152481 -304.190463)
			(xy 335.175123 -304.24004) (xy 335.190478 -304.292335) (xy 335.198234 -304.346283) (xy 335.19872 -304.373534)
			(xy 335.198293 -304.400906) (xy 335.190469 -304.455087) (xy 335.174972 -304.507592) (xy 335.152121 -304.557338)
			(xy 335.122386 -304.603302) (xy 335.10474 -304.624232) (xy 335.098644 -304.631344) (xy 335.092294 -304.648362)
			(xy 335.092294 -304.733706) (xy 335.098644 -304.750724) (xy 335.10474 -304.757836) (xy 335.122369 -304.778776)
			(xy 335.152081 -304.824747) (xy 335.174919 -304.874493) (xy 335.190412 -304.926991) (xy 335.198244 -304.981165)
			(xy 335.19872 -305.008534) (xy 337.855814 -305.008534) (xy 337.856297 -304.981164) (xy 337.86411 -304.926986)
			(xy 337.879595 -304.874483) (xy 337.902433 -304.824736) (xy 337.932154 -304.778768) (xy 337.949794 -304.757836)
			(xy 337.95589 -304.750724) (xy 337.96224 -304.733706) (xy 337.96224 -304.648362) (xy 337.95589 -304.631344)
			(xy 337.949794 -304.624232) (xy 337.932156 -304.603299) (xy 337.902444 -304.557327) (xy 337.879608 -304.507579)
			(xy 337.864117 -304.455079) (xy 337.856288 -304.400903) (xy 337.855814 -304.373534) (xy 337.8563 -304.346283)
			(xy 337.864056 -304.292335) (xy 337.879411 -304.24004) (xy 337.902053 -304.190463) (xy 337.931519 -304.144613)
			(xy 337.96721 -304.103422) (xy 338.008401 -304.067731) (xy 338.054251 -304.038265) (xy 338.103828 -304.015623)
			(xy 338.156123 -304.000268) (xy 338.210071 -303.992512) (xy 338.264573 -303.992512) (xy 338.318521 -304.000268)
			(xy 338.370816 -304.015623) (xy 338.420393 -304.038265) (xy 338.466243 -304.067731) (xy 338.507434 -304.103422)
			(xy 338.543125 -304.144613) (xy 338.572591 -304.190463) (xy 338.595233 -304.24004) (xy 338.610588 -304.292335)
			(xy 338.618344 -304.346283) (xy 338.61883 -304.373534) (xy 338.618401 -304.400906) (xy 338.610577 -304.455087)
			(xy 338.59508 -304.507591) (xy 338.57223 -304.557338) (xy 338.542496 -304.603302) (xy 338.52485 -304.624232)
			(xy 338.518754 -304.631344) (xy 338.512404 -304.648362) (xy 338.512404 -304.733706) (xy 338.518754 -304.750724)
			(xy 338.52485 -304.757836) (xy 338.542465 -304.778788) (xy 338.572182 -304.824754) (xy 338.595023 -304.874497)
			(xy 338.61052 -304.926993) (xy 338.618353 -304.981166) (xy 338.61883 -305.008534) (xy 339.243924 -305.008534)
			(xy 339.244404 -304.981164) (xy 339.252218 -304.926985) (xy 339.267703 -304.874482) (xy 339.290542 -304.824735)
			(xy 339.320264 -304.778768) (xy 339.337904 -304.757836) (xy 339.344 -304.750724) (xy 339.35035 -304.733706)
			(xy 339.35035 -304.648362) (xy 339.344 -304.631344) (xy 339.337904 -304.624232) (xy 339.320267 -304.603298)
			(xy 339.290555 -304.557326) (xy 339.267718 -304.507579) (xy 339.252227 -304.455079) (xy 339.244398 -304.400903)
			(xy 339.243924 -304.373534) (xy 339.24441 -304.346283) (xy 339.252166 -304.292335) (xy 339.267521 -304.24004)
			(xy 339.290163 -304.190463) (xy 339.319629 -304.144613) (xy 339.35532 -304.103422) (xy 339.396511 -304.067731)
			(xy 339.442361 -304.038265) (xy 339.491938 -304.015623) (xy 339.544233 -304.000268) (xy 339.598181 -303.992512)
			(xy 339.652683 -303.992512) (xy 339.706631 -304.000268) (xy 339.758926 -304.015623) (xy 339.808503 -304.038265)
			(xy 339.854353 -304.067731) (xy 339.895544 -304.103422) (xy 339.931235 -304.144613) (xy 339.960701 -304.190463)
			(xy 339.983343 -304.24004) (xy 339.998698 -304.292335) (xy 340.006454 -304.346283) (xy 340.00694 -304.373534)
			(xy 340.006508 -304.400906) (xy 339.998685 -304.455087) (xy 339.983188 -304.507591) (xy 339.960338 -304.557337)
			(xy 339.930605 -304.603302) (xy 339.91296 -304.624232) (xy 339.906864 -304.631344) (xy 339.900514 -304.648362)
			(xy 339.900514 -304.733706) (xy 339.906864 -304.750724) (xy 339.91296 -304.757836) (xy 339.930576 -304.778787)
			(xy 339.960293 -304.824754) (xy 339.983134 -304.874496) (xy 339.99863 -304.926993) (xy 340.006463 -304.981166)
			(xy 340.00694 -305.008534) (xy 341.275924 -305.008534) (xy 341.276404 -304.981164) (xy 341.284218 -304.926985)
			(xy 341.299703 -304.874482) (xy 341.322542 -304.824735) (xy 341.352264 -304.778768) (xy 341.369904 -304.757836)
			(xy 341.376 -304.750724) (xy 341.38235 -304.733706) (xy 341.38235 -304.648362) (xy 341.376 -304.631344)
			(xy 341.369904 -304.624232) (xy 341.352267 -304.603298) (xy 341.322555 -304.557326) (xy 341.299718 -304.507579)
			(xy 341.284227 -304.455079) (xy 341.276398 -304.400903) (xy 341.275924 -304.373534) (xy 341.27641 -304.346283)
			(xy 341.284166 -304.292335) (xy 341.299521 -304.24004) (xy 341.322163 -304.190463) (xy 341.351629 -304.144613)
			(xy 341.38732 -304.103422) (xy 341.428511 -304.067731) (xy 341.474361 -304.038265) (xy 341.523938 -304.015623)
			(xy 341.576233 -304.000268) (xy 341.630181 -303.992512) (xy 341.684683 -303.992512) (xy 341.738631 -304.000268)
			(xy 341.790926 -304.015623) (xy 341.840503 -304.038265) (xy 341.886353 -304.067731) (xy 341.927544 -304.103422)
			(xy 341.963235 -304.144613) (xy 341.992701 -304.190463) (xy 342.015343 -304.24004) (xy 342.030698 -304.292335)
			(xy 342.038454 -304.346283) (xy 342.03894 -304.373534) (xy 342.038508 -304.400906) (xy 342.030685 -304.455087)
			(xy 342.015188 -304.507591) (xy 341.992338 -304.557337) (xy 341.962605 -304.603302) (xy 341.94496 -304.624232)
			(xy 341.938864 -304.631344) (xy 341.932514 -304.648362) (xy 341.932514 -304.733706) (xy 341.938864 -304.750724)
			(xy 341.94496 -304.757836) (xy 341.962576 -304.778787) (xy 341.992293 -304.824754) (xy 342.015134 -304.874496)
			(xy 342.03063 -304.926993) (xy 342.038463 -304.981166) (xy 342.03894 -305.008534) (xy 346.084144 -305.008534)
			(xy 346.084619 -304.981164) (xy 346.092433 -304.926985) (xy 346.10792 -304.874481) (xy 346.13076 -304.824734)
			(xy 346.160483 -304.778768) (xy 346.178124 -304.757836) (xy 346.18422 -304.750724) (xy 346.19057 -304.733706)
			(xy 346.19057 -304.648362) (xy 346.18422 -304.631344) (xy 346.178124 -304.624232) (xy 346.16049 -304.603296)
			(xy 346.130777 -304.557324) (xy 346.107939 -304.507578) (xy 346.092447 -304.455078) (xy 346.084618 -304.400903)
			(xy 346.084144 -304.373534) (xy 346.08463 -304.346283) (xy 346.092386 -304.292335) (xy 346.107741 -304.24004)
			(xy 346.130383 -304.190463) (xy 346.159849 -304.144613) (xy 346.19554 -304.103422) (xy 346.236731 -304.067731)
			(xy 346.282581 -304.038265) (xy 346.332158 -304.015623) (xy 346.384453 -304.000268) (xy 346.438401 -303.992512)
			(xy 346.492903 -303.992512) (xy 346.546851 -304.000268) (xy 346.599146 -304.015623) (xy 346.648723 -304.038265)
			(xy 346.694573 -304.067731) (xy 346.735764 -304.103422) (xy 346.771455 -304.144613) (xy 346.779823 -304.157634)
			(xy 348.984568 -304.157634) (xy 348.988639 -304.102012) (xy 349.000765 -304.047575) (xy 349.020688 -303.995484)
			(xy 349.047984 -303.946849) (xy 349.08207 -303.902706) (xy 349.122219 -303.863997) (xy 349.167577 -303.831546)
			(xy 349.217177 -303.806045) (xy 349.269961 -303.788038) (xy 349.324804 -303.777908) (xy 349.380538 -303.775871)
			(xy 349.435975 -303.781971) (xy 349.489932 -303.796077) (xy 349.541261 -303.817889) (xy 349.588867 -303.846943)
			(xy 349.631735 -303.882618) (xy 349.668952 -303.924155) (xy 349.699725 -303.970668) (xy 349.723397 -304.021165)
			(xy 349.739465 -304.074572) (xy 349.747585 -304.129748) (xy 349.748094 -304.157634) (xy 349.747585 -304.18552)
			(xy 349.739465 -304.240696) (xy 349.723397 -304.294103) (xy 349.699725 -304.3446) (xy 349.668952 -304.391113)
			(xy 349.631735 -304.43265) (xy 349.588867 -304.468325) (xy 349.541261 -304.497379) (xy 349.489932 -304.519191)
			(xy 349.435975 -304.533297) (xy 349.380538 -304.539397) (xy 349.324804 -304.53736) (xy 349.269961 -304.52723)
			(xy 349.217177 -304.509223) (xy 349.167577 -304.483722) (xy 349.122219 -304.451271) (xy 349.08207 -304.412562)
			(xy 349.047984 -304.368419) (xy 349.020688 -304.319784) (xy 349.000765 -304.267693) (xy 348.988639 -304.213256)
			(xy 348.984568 -304.157634) (xy 346.779823 -304.157634) (xy 346.800921 -304.190463) (xy 346.823563 -304.24004)
			(xy 346.838918 -304.292335) (xy 346.846674 -304.346283) (xy 346.84716 -304.373534) (xy 346.846724 -304.400905)
			(xy 346.8389 -304.455086) (xy 346.823405 -304.50759) (xy 346.800556 -304.557336) (xy 346.770825 -304.603302)
			(xy 346.75318 -304.624232) (xy 346.747084 -304.631344) (xy 346.740734 -304.648362) (xy 346.740734 -304.733706)
			(xy 346.747084 -304.750724) (xy 346.75318 -304.757836) (xy 346.770799 -304.778784) (xy 346.800515 -304.824752)
			(xy 346.823355 -304.874496) (xy 346.838851 -304.926993) (xy 346.846684 -304.981166) (xy 346.84716 -305.008534)
			(xy 346.846674 -305.035785) (xy 346.838918 -305.089733) (xy 346.823563 -305.142028) (xy 346.800921 -305.191605)
			(xy 346.771455 -305.237455) (xy 346.735764 -305.278646) (xy 346.694573 -305.314337) (xy 346.648723 -305.343803)
			(xy 346.599146 -305.366445) (xy 346.546851 -305.3818) (xy 346.492903 -305.389556) (xy 346.438401 -305.389556)
			(xy 346.384453 -305.3818) (xy 346.332158 -305.366445) (xy 346.282581 -305.343803) (xy 346.236731 -305.314337)
			(xy 346.19554 -305.278646) (xy 346.159849 -305.237455) (xy 346.130383 -305.191605) (xy 346.107741 -305.142028)
			(xy 346.092386 -305.089733) (xy 346.08463 -305.035785) (xy 346.084144 -305.008534) (xy 342.03894 -305.008534)
			(xy 342.038454 -305.035785) (xy 342.030698 -305.089733) (xy 342.015343 -305.142028) (xy 341.992701 -305.191605)
			(xy 341.963235 -305.237455) (xy 341.927544 -305.278646) (xy 341.886353 -305.314337) (xy 341.840503 -305.343803)
			(xy 341.790926 -305.366445) (xy 341.738631 -305.3818) (xy 341.684683 -305.389556) (xy 341.630181 -305.389556)
			(xy 341.576233 -305.3818) (xy 341.523938 -305.366445) (xy 341.474361 -305.343803) (xy 341.428511 -305.314337)
			(xy 341.38732 -305.278646) (xy 341.351629 -305.237455) (xy 341.322163 -305.191605) (xy 341.299521 -305.142028)
			(xy 341.284166 -305.089733) (xy 341.27641 -305.035785) (xy 341.275924 -305.008534) (xy 340.00694 -305.008534)
			(xy 340.006454 -305.035785) (xy 339.998698 -305.089733) (xy 339.983343 -305.142028) (xy 339.960701 -305.191605)
			(xy 339.931235 -305.237455) (xy 339.895544 -305.278646) (xy 339.854353 -305.314337) (xy 339.808503 -305.343803)
			(xy 339.758926 -305.366445) (xy 339.706631 -305.3818) (xy 339.652683 -305.389556) (xy 339.598181 -305.389556)
			(xy 339.544233 -305.3818) (xy 339.491938 -305.366445) (xy 339.442361 -305.343803) (xy 339.396511 -305.314337)
			(xy 339.35532 -305.278646) (xy 339.319629 -305.237455) (xy 339.290163 -305.191605) (xy 339.267521 -305.142028)
			(xy 339.252166 -305.089733) (xy 339.24441 -305.035785) (xy 339.243924 -305.008534) (xy 338.61883 -305.008534)
			(xy 338.618344 -305.035785) (xy 338.610588 -305.089733) (xy 338.595233 -305.142028) (xy 338.572591 -305.191605)
			(xy 338.543125 -305.237455) (xy 338.507434 -305.278646) (xy 338.466243 -305.314337) (xy 338.420393 -305.343803)
			(xy 338.370816 -305.366445) (xy 338.318521 -305.3818) (xy 338.264573 -305.389556) (xy 338.210071 -305.389556)
			(xy 338.156123 -305.3818) (xy 338.103828 -305.366445) (xy 338.054251 -305.343803) (xy 338.008401 -305.314337)
			(xy 337.96721 -305.278646) (xy 337.931519 -305.237455) (xy 337.902053 -305.191605) (xy 337.879411 -305.142028)
			(xy 337.864056 -305.089733) (xy 337.8563 -305.035785) (xy 337.855814 -305.008534) (xy 335.19872 -305.008534)
			(xy 335.198234 -305.035785) (xy 335.190478 -305.089733) (xy 335.175123 -305.142028) (xy 335.152481 -305.191605)
			(xy 335.123015 -305.237455) (xy 335.087324 -305.278646) (xy 335.046133 -305.314337) (xy 335.000283 -305.343803)
			(xy 334.950706 -305.366445) (xy 334.898411 -305.3818) (xy 334.844463 -305.389556) (xy 334.789961 -305.389556)
			(xy 334.736013 -305.3818) (xy 334.683718 -305.366445) (xy 334.634141 -305.343803) (xy 334.588291 -305.314337)
			(xy 334.5471 -305.278646) (xy 334.511409 -305.237455) (xy 334.481943 -305.191605) (xy 334.459301 -305.142028)
			(xy 334.443946 -305.089733) (xy 334.43619 -305.035785) (xy 334.435704 -305.008534) (xy 325.645621 -305.008534)
			(xy 325.647049 -305.01824) (xy 325.647558 -305.046126) (xy 325.647049 -305.074012) (xy 325.638929 -305.129188)
			(xy 325.622861 -305.182595) (xy 325.599189 -305.233092) (xy 325.568416 -305.279605) (xy 325.531199 -305.321142)
			(xy 325.488331 -305.356817) (xy 325.440725 -305.385871) (xy 325.389396 -305.407683) (xy 325.335439 -305.421789)
			(xy 325.280002 -305.427889) (xy 325.224268 -305.425852) (xy 325.169425 -305.415722) (xy 325.116641 -305.397715)
			(xy 325.067041 -305.372214) (xy 325.021683 -305.339763) (xy 324.981534 -305.301054) (xy 324.947448 -305.256911)
			(xy 324.920152 -305.208276) (xy 324.900229 -305.156185) (xy 324.888103 -305.101748) (xy 324.884032 -305.046126)
			(xy 324.631233 -305.046126) (xy 324.631558 -305.063906) (xy 324.631049 -305.091792) (xy 324.622929 -305.146968)
			(xy 324.606861 -305.200375) (xy 324.583189 -305.250872) (xy 324.552416 -305.297385) (xy 324.515199 -305.338922)
			(xy 324.472331 -305.374597) (xy 324.424725 -305.403651) (xy 324.373396 -305.425463) (xy 324.319439 -305.439569)
			(xy 324.264002 -305.445669) (xy 324.208268 -305.443632) (xy 324.153425 -305.433502) (xy 324.100641 -305.415495)
			(xy 324.051041 -305.389994) (xy 324.005683 -305.357543) (xy 323.965534 -305.318834) (xy 323.931448 -305.274691)
			(xy 323.904152 -305.226056) (xy 323.884229 -305.173965) (xy 323.872103 -305.119528) (xy 323.868032 -305.063906)
			(xy 323.606903 -305.063906) (xy 323.606922 -305.064922) (xy 323.606413 -305.092808) (xy 323.598293 -305.147984)
			(xy 323.582225 -305.201391) (xy 323.558553 -305.251888) (xy 323.52778 -305.298401) (xy 323.490563 -305.339938)
			(xy 323.447695 -305.375613) (xy 323.400089 -305.404667) (xy 323.34876 -305.426479) (xy 323.294803 -305.440585)
			(xy 323.239366 -305.446685) (xy 323.183632 -305.444648) (xy 323.128789 -305.434518) (xy 323.076005 -305.416511)
			(xy 323.026405 -305.39101) (xy 322.981047 -305.358559) (xy 322.940898 -305.31985) (xy 322.906812 -305.275707)
			(xy 322.879516 -305.227072) (xy 322.859593 -305.174981) (xy 322.847467 -305.120544) (xy 322.843396 -305.064922)
			(xy 322.598542 -305.064922) (xy 322.598033 -305.092808) (xy 322.589913 -305.147984) (xy 322.573845 -305.201391)
			(xy 322.550173 -305.251888) (xy 322.5194 -305.298401) (xy 322.482183 -305.339938) (xy 322.439315 -305.375613)
			(xy 322.391709 -305.404667) (xy 322.34038 -305.426479) (xy 322.286423 -305.440585) (xy 322.230986 -305.446685)
			(xy 322.175252 -305.444648) (xy 322.120409 -305.434518) (xy 322.067625 -305.416511) (xy 322.018025 -305.39101)
			(xy 321.972667 -305.358559) (xy 321.932518 -305.31985) (xy 321.898432 -305.275707) (xy 321.871136 -305.227072)
			(xy 321.851213 -305.174981) (xy 321.839087 -305.120544) (xy 321.835016 -305.064922) (xy 321.583167 -305.064922)
			(xy 321.583167 -305.092157) (xy 321.575408 -305.146115) (xy 321.560049 -305.19842) (xy 321.537401 -305.248007)
			(xy 321.507927 -305.293865) (xy 321.472226 -305.335061) (xy 321.431025 -305.370757) (xy 321.385163 -305.400225)
			(xy 321.335573 -305.422866) (xy 321.283266 -305.438219) (xy 321.229307 -305.445971) (xy 321.20205 -305.44643)
			(xy 321.174904 -305.446009) (xy 321.121158 -305.438326) (xy 321.069045 -305.423095) (xy 321.019622 -305.400624)
			(xy 320.973886 -305.371368) (xy 320.932765 -305.335918) (xy 320.89709 -305.294992) (xy 320.867582 -305.249418)
			(xy 320.84484 -305.200119) (xy 320.829323 -305.148091) (xy 320.82486 -305.12131) (xy 320.822048 -305.106479)
			(xy 320.809009 -305.079273) (xy 320.788599 -305.057054) (xy 320.762596 -305.041756) (xy 320.733261 -305.03471)
			(xy 320.703146 -305.036528) (xy 320.674871 -305.047052) (xy 320.662554 -305.055778) (xy 320.642497 -305.070592)
			(xy 320.599278 -305.095458) (xy 320.553191 -305.114489) (xy 320.50502 -305.127362) (xy 320.455583 -305.133857)
			(xy 320.430652 -305.134264) (xy 320.4034 -305.133863) (xy 320.349451 -305.1261) (xy 320.297156 -305.110739)
			(xy 320.247579 -305.088092) (xy 320.20173 -305.058621) (xy 320.16054 -305.022926) (xy 320.12485 -304.981732)
			(xy 320.095385 -304.935879) (xy 320.072744 -304.886299) (xy 320.05739 -304.834002) (xy 320.049634 -304.780052)
			(xy 304.943098 -304.780052) (xy 304.956112 -304.804849) (xy 304.971696 -304.85153) (xy 304.979591 -304.900107)
			(xy 304.980086 -304.924714) (xy 304.979591 -304.949321) (xy 304.971696 -304.997898) (xy 304.956112 -305.044579)
			(xy 304.933241 -305.088156) (xy 304.903676 -305.1275) (xy 304.868183 -305.161592) (xy 304.82768 -305.189548)
			(xy 304.783218 -305.210646) (xy 304.735947 -305.224338) (xy 304.687092 -305.23027) (xy 304.637917 -305.228289)
			(xy 304.589698 -305.218445) (xy 304.543682 -305.200993) (xy 304.501061 -305.176386) (xy 304.46294 -305.145261)
			(xy 304.430305 -305.108424) (xy 304.404002 -305.066828) (xy 304.384711 -305.021552) (xy 304.372934 -304.973768)
			(xy 304.368974 -304.924714) (xy 304.030126 -304.924714) (xy 304.029631 -304.949321) (xy 304.021736 -304.997898)
			(xy 304.006152 -305.044579) (xy 303.983281 -305.088156) (xy 303.953716 -305.1275) (xy 303.918223 -305.161592)
			(xy 303.87772 -305.189548) (xy 303.833258 -305.210646) (xy 303.785987 -305.224338) (xy 303.737132 -305.23027)
			(xy 303.687957 -305.228289) (xy 303.639738 -305.218445) (xy 303.593722 -305.200993) (xy 303.551101 -305.176386)
			(xy 303.51298 -305.145261) (xy 303.480345 -305.108424) (xy 303.454042 -305.066828) (xy 303.434751 -305.021552)
			(xy 303.422974 -304.973768) (xy 303.419014 -304.924714) (xy 303.080166 -304.924714) (xy 303.079671 -304.949321)
			(xy 303.071776 -304.997898) (xy 303.056192 -305.044579) (xy 303.033321 -305.088156) (xy 303.003756 -305.1275)
			(xy 302.968263 -305.161592) (xy 302.92776 -305.189548) (xy 302.883298 -305.210646) (xy 302.836027 -305.224338)
			(xy 302.787172 -305.23027) (xy 302.737997 -305.228289) (xy 302.689778 -305.218445) (xy 302.643762 -305.200993)
			(xy 302.601141 -305.176386) (xy 302.56302 -305.145261) (xy 302.530385 -305.108424) (xy 302.504082 -305.066828)
			(xy 302.484791 -305.021552) (xy 302.473014 -304.973768) (xy 302.469054 -304.924714) (xy 302.130206 -304.924714)
			(xy 302.129711 -304.949321) (xy 302.121816 -304.997898) (xy 302.106232 -305.044579) (xy 302.083361 -305.088156)
			(xy 302.053796 -305.1275) (xy 302.018303 -305.161592) (xy 301.9778 -305.189548) (xy 301.933338 -305.210646)
			(xy 301.886067 -305.224338) (xy 301.837212 -305.23027) (xy 301.788037 -305.228289) (xy 301.739818 -305.218445)
			(xy 301.693802 -305.200993) (xy 301.651181 -305.176386) (xy 301.61306 -305.145261) (xy 301.580425 -305.108424)
			(xy 301.554122 -305.066828) (xy 301.534831 -305.021552) (xy 301.523054 -304.973768) (xy 301.519094 -304.924714)
			(xy 301.179992 -304.924714) (xy 301.179497 -304.949321) (xy 301.171602 -304.997898) (xy 301.156018 -305.044579)
			(xy 301.133147 -305.088156) (xy 301.103582 -305.1275) (xy 301.068089 -305.161592) (xy 301.027586 -305.189548)
			(xy 300.983124 -305.210646) (xy 300.935853 -305.224338) (xy 300.886998 -305.23027) (xy 300.837823 -305.228289)
			(xy 300.789604 -305.218445) (xy 300.743588 -305.200993) (xy 300.700967 -305.176386) (xy 300.662846 -305.145261)
			(xy 300.630211 -305.108424) (xy 300.603908 -305.066828) (xy 300.584617 -305.021552) (xy 300.57284 -304.973768)
			(xy 300.56888 -304.924714) (xy 300.230032 -304.924714) (xy 300.229537 -304.949321) (xy 300.221642 -304.997898)
			(xy 300.206058 -305.044579) (xy 300.183187 -305.088156) (xy 300.153622 -305.1275) (xy 300.118129 -305.161592)
			(xy 300.077626 -305.189548) (xy 300.033164 -305.210646) (xy 299.985893 -305.224338) (xy 299.937038 -305.23027)
			(xy 299.887863 -305.228289) (xy 299.839644 -305.218445) (xy 299.793628 -305.200993) (xy 299.751007 -305.176386)
			(xy 299.712886 -305.145261) (xy 299.680251 -305.108424) (xy 299.653948 -305.066828) (xy 299.634657 -305.021552)
			(xy 299.62288 -304.973768) (xy 299.61892 -304.924714) (xy 299.280072 -304.924714) (xy 299.279577 -304.949321)
			(xy 299.271682 -304.997898) (xy 299.256098 -305.044579) (xy 299.233227 -305.088156) (xy 299.203662 -305.1275)
			(xy 299.168169 -305.161592) (xy 299.127666 -305.189548) (xy 299.083204 -305.210646) (xy 299.035933 -305.224338)
			(xy 298.987078 -305.23027) (xy 298.937903 -305.228289) (xy 298.889684 -305.218445) (xy 298.843668 -305.200993)
			(xy 298.801047 -305.176386) (xy 298.762926 -305.145261) (xy 298.730291 -305.108424) (xy 298.703988 -305.066828)
			(xy 298.684697 -305.021552) (xy 298.67292 -304.973768) (xy 298.66896 -304.924714) (xy 298.330112 -304.924714)
			(xy 298.329617 -304.949321) (xy 298.321722 -304.997898) (xy 298.306138 -305.044579) (xy 298.283267 -305.088156)
			(xy 298.253702 -305.1275) (xy 298.218209 -305.161592) (xy 298.177706 -305.189548) (xy 298.133244 -305.210646)
			(xy 298.085973 -305.224338) (xy 298.037118 -305.23027) (xy 297.987943 -305.228289) (xy 297.939724 -305.218445)
			(xy 297.893708 -305.200993) (xy 297.851087 -305.176386) (xy 297.812966 -305.145261) (xy 297.780331 -305.108424)
			(xy 297.754028 -305.066828) (xy 297.734737 -305.021552) (xy 297.72296 -304.973768) (xy 297.719 -304.924714)
			(xy 297.380152 -304.924714) (xy 297.379657 -304.949321) (xy 297.371762 -304.997898) (xy 297.356178 -305.044579)
			(xy 297.333307 -305.088156) (xy 297.303742 -305.1275) (xy 297.268249 -305.161592) (xy 297.227746 -305.189548)
			(xy 297.183284 -305.210646) (xy 297.136013 -305.224338) (xy 297.087158 -305.23027) (xy 297.037983 -305.228289)
			(xy 296.989764 -305.218445) (xy 296.943748 -305.200993) (xy 296.901127 -305.176386) (xy 296.863006 -305.145261)
			(xy 296.830371 -305.108424) (xy 296.804068 -305.066828) (xy 296.784777 -305.021552) (xy 296.773 -304.973768)
			(xy 296.76904 -304.924714) (xy 296.430192 -304.924714) (xy 296.429697 -304.949321) (xy 296.421802 -304.997898)
			(xy 296.406218 -305.044579) (xy 296.383347 -305.088156) (xy 296.353782 -305.1275) (xy 296.318289 -305.161592)
			(xy 296.277786 -305.189548) (xy 296.233324 -305.210646) (xy 296.186053 -305.224338) (xy 296.137198 -305.23027)
			(xy 296.088023 -305.228289) (xy 296.039804 -305.218445) (xy 295.993788 -305.200993) (xy 295.951167 -305.176386)
			(xy 295.913046 -305.145261) (xy 295.880411 -305.108424) (xy 295.854108 -305.066828) (xy 295.834817 -305.021552)
			(xy 295.82304 -304.973768) (xy 295.81908 -304.924714) (xy 295.480232 -304.924714) (xy 295.479737 -304.949321)
			(xy 295.471842 -304.997898) (xy 295.456258 -305.044579) (xy 295.433387 -305.088156) (xy 295.403822 -305.1275)
			(xy 295.368329 -305.161592) (xy 295.327826 -305.189548) (xy 295.283364 -305.210646) (xy 295.236093 -305.224338)
			(xy 295.187238 -305.23027) (xy 295.138063 -305.228289) (xy 295.089844 -305.218445) (xy 295.043828 -305.200993)
			(xy 295.001207 -305.176386) (xy 294.963086 -305.145261) (xy 294.930451 -305.108424) (xy 294.904148 -305.066828)
			(xy 294.884857 -305.021552) (xy 294.87308 -304.973768) (xy 294.86912 -304.924714) (xy 294.530018 -304.924714)
			(xy 294.529523 -304.949321) (xy 294.521628 -304.997898) (xy 294.506044 -305.044579) (xy 294.483173 -305.088156)
			(xy 294.453608 -305.1275) (xy 294.418115 -305.161592) (xy 294.377612 -305.189548) (xy 294.33315 -305.210646)
			(xy 294.285879 -305.224338) (xy 294.237024 -305.23027) (xy 294.187849 -305.228289) (xy 294.13963 -305.218445)
			(xy 294.093614 -305.200993) (xy 294.050993 -305.176386) (xy 294.012872 -305.145261) (xy 293.980237 -305.108424)
			(xy 293.953934 -305.066828) (xy 293.934643 -305.021552) (xy 293.922866 -304.973768) (xy 293.918906 -304.924714)
			(xy 293.580058 -304.924714) (xy 293.579563 -304.949321) (xy 293.571668 -304.997898) (xy 293.556084 -305.044579)
			(xy 293.533213 -305.088156) (xy 293.503648 -305.1275) (xy 293.468155 -305.161592) (xy 293.427652 -305.189548)
			(xy 293.38319 -305.210646) (xy 293.335919 -305.224338) (xy 293.287064 -305.23027) (xy 293.237889 -305.228289)
			(xy 293.18967 -305.218445) (xy 293.143654 -305.200993) (xy 293.101033 -305.176386) (xy 293.062912 -305.145261)
			(xy 293.030277 -305.108424) (xy 293.003974 -305.066828) (xy 292.984683 -305.021552) (xy 292.972906 -304.973768)
			(xy 292.968946 -304.924714) (xy 292.630098 -304.924714) (xy 292.629603 -304.949321) (xy 292.621708 -304.997898)
			(xy 292.606124 -305.044579) (xy 292.583253 -305.088156) (xy 292.553688 -305.1275) (xy 292.518195 -305.161592)
			(xy 292.477692 -305.189548) (xy 292.43323 -305.210646) (xy 292.385959 -305.224338) (xy 292.337104 -305.23027)
			(xy 292.287929 -305.228289) (xy 292.23971 -305.218445) (xy 292.193694 -305.200993) (xy 292.151073 -305.176386)
			(xy 292.112952 -305.145261) (xy 292.080317 -305.108424) (xy 292.054014 -305.066828) (xy 292.034723 -305.021552)
			(xy 292.022946 -304.973768) (xy 292.018986 -304.924714) (xy 290.730178 -304.924714) (xy 290.729683 -304.949321)
			(xy 290.721788 -304.997898) (xy 290.706204 -305.044579) (xy 290.683333 -305.088156) (xy 290.653768 -305.1275)
			(xy 290.618275 -305.161592) (xy 290.577772 -305.189548) (xy 290.53331 -305.210646) (xy 290.486039 -305.224338)
			(xy 290.437184 -305.23027) (xy 290.388009 -305.228289) (xy 290.33979 -305.218445) (xy 290.293774 -305.200993)
			(xy 290.251153 -305.176386) (xy 290.213032 -305.145261) (xy 290.180397 -305.108424) (xy 290.154094 -305.066828)
			(xy 290.134803 -305.021552) (xy 290.123026 -304.973768) (xy 290.119066 -304.924714) (xy 289.780218 -304.924714)
			(xy 289.779723 -304.949321) (xy 289.771828 -304.997898) (xy 289.756244 -305.044579) (xy 289.733373 -305.088156)
			(xy 289.703808 -305.1275) (xy 289.668315 -305.161592) (xy 289.627812 -305.189548) (xy 289.58335 -305.210646)
			(xy 289.536079 -305.224338) (xy 289.487224 -305.23027) (xy 289.438049 -305.228289) (xy 289.38983 -305.218445)
			(xy 289.343814 -305.200993) (xy 289.301193 -305.176386) (xy 289.263072 -305.145261) (xy 289.230437 -305.108424)
			(xy 289.204134 -305.066828) (xy 289.184843 -305.021552) (xy 289.173066 -304.973768) (xy 289.169106 -304.924714)
			(xy 288.830004 -304.924714) (xy 288.829509 -304.949321) (xy 288.821614 -304.997898) (xy 288.80603 -305.044579)
			(xy 288.783159 -305.088156) (xy 288.753594 -305.1275) (xy 288.718101 -305.161592) (xy 288.677598 -305.189548)
			(xy 288.633136 -305.210646) (xy 288.585865 -305.224338) (xy 288.53701 -305.23027) (xy 288.487835 -305.228289)
			(xy 288.439616 -305.218445) (xy 288.3936 -305.200993) (xy 288.350979 -305.176386) (xy 288.312858 -305.145261)
			(xy 288.280223 -305.108424) (xy 288.25392 -305.066828) (xy 288.234629 -305.021552) (xy 288.222852 -304.973768)
			(xy 288.218892 -304.924714) (xy 287.880044 -304.924714) (xy 287.879549 -304.949321) (xy 287.871654 -304.997898)
			(xy 287.85607 -305.044579) (xy 287.833199 -305.088156) (xy 287.803634 -305.1275) (xy 287.768141 -305.161592)
			(xy 287.727638 -305.189548) (xy 287.683176 -305.210646) (xy 287.635905 -305.224338) (xy 287.58705 -305.23027)
			(xy 287.537875 -305.228289) (xy 287.489656 -305.218445) (xy 287.44364 -305.200993) (xy 287.401019 -305.176386)
			(xy 287.362898 -305.145261) (xy 287.330263 -305.108424) (xy 287.30396 -305.066828) (xy 287.284669 -305.021552)
			(xy 287.272892 -304.973768) (xy 287.268932 -304.924714) (xy 286.930084 -304.924714) (xy 286.929589 -304.949321)
			(xy 286.921694 -304.997898) (xy 286.90611 -305.044579) (xy 286.883239 -305.088156) (xy 286.853674 -305.1275)
			(xy 286.818181 -305.161592) (xy 286.777678 -305.189548) (xy 286.733216 -305.210646) (xy 286.685945 -305.224338)
			(xy 286.63709 -305.23027) (xy 286.587915 -305.228289) (xy 286.539696 -305.218445) (xy 286.49368 -305.200993)
			(xy 286.451059 -305.176386) (xy 286.412938 -305.145261) (xy 286.380303 -305.108424) (xy 286.354 -305.066828)
			(xy 286.334709 -305.021552) (xy 286.322932 -304.973768) (xy 286.318972 -304.924714) (xy 285.980124 -304.924714)
			(xy 285.979629 -304.949321) (xy 285.971734 -304.997898) (xy 285.95615 -305.044579) (xy 285.933279 -305.088156)
			(xy 285.903714 -305.1275) (xy 285.868221 -305.161592) (xy 285.827718 -305.189548) (xy 285.783256 -305.210646)
			(xy 285.735985 -305.224338) (xy 285.68713 -305.23027) (xy 285.637955 -305.228289) (xy 285.589736 -305.218445)
			(xy 285.54372 -305.200993) (xy 285.501099 -305.176386) (xy 285.462978 -305.145261) (xy 285.430343 -305.108424)
			(xy 285.40404 -305.066828) (xy 285.384749 -305.021552) (xy 285.372972 -304.973768) (xy 285.369012 -304.924714)
			(xy 285.030164 -304.924714) (xy 285.029669 -304.949321) (xy 285.021774 -304.997898) (xy 285.00619 -305.044579)
			(xy 284.983319 -305.088156) (xy 284.953754 -305.1275) (xy 284.918261 -305.161592) (xy 284.877758 -305.189548)
			(xy 284.833296 -305.210646) (xy 284.786025 -305.224338) (xy 284.73717 -305.23027) (xy 284.687995 -305.228289)
			(xy 284.639776 -305.218445) (xy 284.59376 -305.200993) (xy 284.551139 -305.176386) (xy 284.513018 -305.145261)
			(xy 284.480383 -305.108424) (xy 284.45408 -305.066828) (xy 284.434789 -305.021552) (xy 284.423012 -304.973768)
			(xy 284.419052 -304.924714) (xy 284.080204 -304.924714) (xy 284.079709 -304.949321) (xy 284.071814 -304.997898)
			(xy 284.05623 -305.044579) (xy 284.033359 -305.088156) (xy 284.003794 -305.1275) (xy 283.968301 -305.161592)
			(xy 283.927798 -305.189548) (xy 283.883336 -305.210646) (xy 283.836065 -305.224338) (xy 283.78721 -305.23027)
			(xy 283.738035 -305.228289) (xy 283.689816 -305.218445) (xy 283.6438 -305.200993) (xy 283.601179 -305.176386)
			(xy 283.563058 -305.145261) (xy 283.530423 -305.108424) (xy 283.50412 -305.066828) (xy 283.484829 -305.021552)
			(xy 283.473052 -304.973768) (xy 283.469092 -304.924714) (xy 283.130244 -304.924714) (xy 283.129749 -304.949321)
			(xy 283.121854 -304.997898) (xy 283.10627 -305.044579) (xy 283.083399 -305.088156) (xy 283.053834 -305.1275)
			(xy 283.018341 -305.161592) (xy 282.977838 -305.189548) (xy 282.933376 -305.210646) (xy 282.886105 -305.224338)
			(xy 282.83725 -305.23027) (xy 282.788075 -305.228289) (xy 282.739856 -305.218445) (xy 282.69384 -305.200993)
			(xy 282.651219 -305.176386) (xy 282.613098 -305.145261) (xy 282.580463 -305.108424) (xy 282.55416 -305.066828)
			(xy 282.534869 -305.021552) (xy 282.523092 -304.973768) (xy 282.519132 -304.924714) (xy 282.180516 -304.924714)
			(xy 282.176346 -304.975034) (xy 282.163948 -305.023994) (xy 282.143661 -305.070247) (xy 282.116038 -305.112529)
			(xy 282.081833 -305.149689) (xy 282.041978 -305.180712) (xy 281.99756 -305.204753) (xy 281.949792 -305.221155)
			(xy 281.899975 -305.229471) (xy 281.874722 -305.230022) (xy 281.844648 -305.229328) (xy 281.785663 -305.21756)
			(xy 281.757628 -305.206654) (xy 281.745436 -305.201574) (xy 281.720544 -305.204114) (xy 281.639518 -305.258216)
			(xy 281.629465 -305.265737) (xy 281.617625 -305.287844) (xy 281.616912 -305.30038) (xy 281.616912 -305.399948)
			(xy 305.793914 -305.399948) (xy 305.797874 -305.350894) (xy 305.809651 -305.30311) (xy 305.828942 -305.257834)
			(xy 305.855245 -305.216238) (xy 305.88788 -305.179401) (xy 305.926001 -305.148276) (xy 305.968622 -305.123669)
			(xy 306.014638 -305.106217) (xy 306.062857 -305.096373) (xy 306.112032 -305.094392) (xy 306.160887 -305.100324)
			(xy 306.208158 -305.114016) (xy 306.25262 -305.135114) (xy 306.293123 -305.16307) (xy 306.328616 -305.197162)
			(xy 306.358181 -305.236506) (xy 306.381052 -305.280083) (xy 306.396636 -305.326764) (xy 306.404531 -305.375341)
			(xy 306.405026 -305.399948) (xy 306.744128 -305.399948) (xy 306.748088 -305.350894) (xy 306.759865 -305.30311)
			(xy 306.779156 -305.257834) (xy 306.805459 -305.216238) (xy 306.838094 -305.179401) (xy 306.876215 -305.148276)
			(xy 306.918836 -305.123669) (xy 306.964852 -305.106217) (xy 307.013071 -305.096373) (xy 307.062246 -305.094392)
			(xy 307.111101 -305.100324) (xy 307.158372 -305.114016) (xy 307.202834 -305.135114) (xy 307.243337 -305.16307)
			(xy 307.27883 -305.197162) (xy 307.308395 -305.236506) (xy 307.331266 -305.280083) (xy 307.34685 -305.326764)
			(xy 307.354745 -305.375341) (xy 307.35524 -305.399948) (xy 307.694088 -305.399948) (xy 307.698048 -305.350894)
			(xy 307.709825 -305.30311) (xy 307.729116 -305.257834) (xy 307.755419 -305.216238) (xy 307.788054 -305.179401)
			(xy 307.826175 -305.148276) (xy 307.868796 -305.123669) (xy 307.914812 -305.106217) (xy 307.963031 -305.096373)
			(xy 308.012206 -305.094392) (xy 308.061061 -305.100324) (xy 308.108332 -305.114016) (xy 308.152794 -305.135114)
			(xy 308.193297 -305.16307) (xy 308.22879 -305.197162) (xy 308.258355 -305.236506) (xy 308.281226 -305.280083)
			(xy 308.29681 -305.326764) (xy 308.304705 -305.375341) (xy 308.3052 -305.399948) (xy 308.304705 -305.424555)
			(xy 308.304526 -305.425656) (xy 308.623204 -305.425656) (xy 308.623204 -305.37424) (xy 308.631247 -305.323458)
			(xy 308.647135 -305.274559) (xy 308.670478 -305.228747) (xy 308.700699 -305.187151) (xy 308.737055 -305.150795)
			(xy 308.778651 -305.120574) (xy 308.824463 -305.097231) (xy 308.873362 -305.081343) (xy 308.924144 -305.0733)
			(xy 308.97556 -305.0733) (xy 309.026342 -305.081343) (xy 309.075241 -305.097231) (xy 309.121053 -305.120574)
			(xy 309.162649 -305.150795) (xy 309.199005 -305.187151) (xy 309.229226 -305.228747) (xy 309.252569 -305.274559)
			(xy 309.268457 -305.323458) (xy 309.2765 -305.37424) (xy 309.277004 -305.399948) (xy 309.2765 -305.425656)
			(xy 309.573164 -305.425656) (xy 309.573164 -305.37424) (xy 309.581207 -305.323458) (xy 309.597095 -305.274559)
			(xy 309.620438 -305.228747) (xy 309.650659 -305.187151) (xy 309.687015 -305.150795) (xy 309.728611 -305.120574)
			(xy 309.774423 -305.097231) (xy 309.823322 -305.081343) (xy 309.874104 -305.0733) (xy 309.92552 -305.0733)
			(xy 309.976302 -305.081343) (xy 310.025201 -305.097231) (xy 310.071013 -305.120574) (xy 310.112609 -305.150795)
			(xy 310.148965 -305.187151) (xy 310.179186 -305.228747) (xy 310.202529 -305.274559) (xy 310.218417 -305.323458)
			(xy 310.22646 -305.37424) (xy 310.226964 -305.399948) (xy 310.543968 -305.399948) (xy 310.547928 -305.350894)
			(xy 310.559705 -305.30311) (xy 310.578996 -305.257834) (xy 310.605299 -305.216238) (xy 310.637934 -305.179401)
			(xy 310.676055 -305.148276) (xy 310.718676 -305.123669) (xy 310.764692 -305.106217) (xy 310.812911 -305.096373)
			(xy 310.862086 -305.094392) (xy 310.910941 -305.100324) (xy 310.958212 -305.114016) (xy 311.002674 -305.135114)
			(xy 311.043177 -305.16307) (xy 311.07867 -305.197162) (xy 311.108235 -305.236506) (xy 311.131106 -305.280083)
			(xy 311.14669 -305.326764) (xy 311.154585 -305.375341) (xy 311.15508 -305.399948) (xy 311.493928 -305.399948)
			(xy 311.497888 -305.350894) (xy 311.509665 -305.30311) (xy 311.528956 -305.257834) (xy 311.555259 -305.216238)
			(xy 311.587894 -305.179401) (xy 311.626015 -305.148276) (xy 311.668636 -305.123669) (xy 311.714652 -305.106217)
			(xy 311.762871 -305.096373) (xy 311.812046 -305.094392) (xy 311.860901 -305.100324) (xy 311.908172 -305.114016)
			(xy 311.952634 -305.135114) (xy 311.993137 -305.16307) (xy 312.02863 -305.197162) (xy 312.058195 -305.236506)
			(xy 312.081066 -305.280083) (xy 312.09665 -305.326764) (xy 312.104545 -305.375341) (xy 312.10504 -305.399948)
			(xy 312.443888 -305.399948) (xy 312.447848 -305.350894) (xy 312.459625 -305.30311) (xy 312.478916 -305.257834)
			(xy 312.505219 -305.216238) (xy 312.537854 -305.179401) (xy 312.575975 -305.148276) (xy 312.618596 -305.123669)
			(xy 312.664612 -305.106217) (xy 312.712831 -305.096373) (xy 312.762006 -305.094392) (xy 312.810861 -305.100324)
			(xy 312.858132 -305.114016) (xy 312.902594 -305.135114) (xy 312.943097 -305.16307) (xy 312.97859 -305.197162)
			(xy 313.008155 -305.236506) (xy 313.031026 -305.280083) (xy 313.04661 -305.326764) (xy 313.054505 -305.375341)
			(xy 313.055 -305.399948) (xy 313.394102 -305.399948) (xy 313.398062 -305.350894) (xy 313.409839 -305.30311)
			(xy 313.42913 -305.257834) (xy 313.455433 -305.216238) (xy 313.488068 -305.179401) (xy 313.526189 -305.148276)
			(xy 313.56881 -305.123669) (xy 313.614826 -305.106217) (xy 313.663045 -305.096373) (xy 313.71222 -305.094392)
			(xy 313.761075 -305.100324) (xy 313.808346 -305.114016) (xy 313.852808 -305.135114) (xy 313.893311 -305.16307)
			(xy 313.928804 -305.197162) (xy 313.958369 -305.236506) (xy 313.98124 -305.280083) (xy 313.996824 -305.326764)
			(xy 314.004719 -305.375341) (xy 314.005214 -305.399948) (xy 314.344062 -305.399948) (xy 314.348022 -305.350894)
			(xy 314.359799 -305.30311) (xy 314.37909 -305.257834) (xy 314.405393 -305.216238) (xy 314.438028 -305.179401)
			(xy 314.476149 -305.148276) (xy 314.51877 -305.123669) (xy 314.564786 -305.106217) (xy 314.613005 -305.096373)
			(xy 314.66218 -305.094392) (xy 314.711035 -305.100324) (xy 314.758306 -305.114016) (xy 314.802768 -305.135114)
			(xy 314.843271 -305.16307) (xy 314.878764 -305.197162) (xy 314.908329 -305.236506) (xy 314.9312 -305.280083)
			(xy 314.946784 -305.326764) (xy 314.954679 -305.375341) (xy 314.955174 -305.399948) (xy 314.954679 -305.424555)
			(xy 314.946784 -305.473132) (xy 314.9312 -305.519813) (xy 314.908329 -305.56339) (xy 314.878764 -305.602734)
			(xy 314.843271 -305.636826) (xy 314.802768 -305.664782) (xy 314.758306 -305.68588) (xy 314.711035 -305.699572)
			(xy 314.66218 -305.705504) (xy 314.613005 -305.703523) (xy 314.564786 -305.693679) (xy 314.51877 -305.676227)
			(xy 314.476149 -305.65162) (xy 314.438028 -305.620495) (xy 314.405393 -305.583658) (xy 314.37909 -305.542062)
			(xy 314.359799 -305.496786) (xy 314.348022 -305.449002) (xy 314.344062 -305.399948) (xy 314.005214 -305.399948)
			(xy 314.004719 -305.424555) (xy 313.996824 -305.473132) (xy 313.98124 -305.519813) (xy 313.958369 -305.56339)
			(xy 313.928804 -305.602734) (xy 313.893311 -305.636826) (xy 313.852808 -305.664782) (xy 313.808346 -305.68588)
			(xy 313.761075 -305.699572) (xy 313.71222 -305.705504) (xy 313.663045 -305.703523) (xy 313.614826 -305.693679)
			(xy 313.56881 -305.676227) (xy 313.526189 -305.65162) (xy 313.488068 -305.620495) (xy 313.455433 -305.583658)
			(xy 313.42913 -305.542062) (xy 313.409839 -305.496786) (xy 313.398062 -305.449002) (xy 313.394102 -305.399948)
			(xy 313.055 -305.399948) (xy 313.054505 -305.424555) (xy 313.04661 -305.473132) (xy 313.031026 -305.519813)
			(xy 313.008155 -305.56339) (xy 312.97859 -305.602734) (xy 312.943097 -305.636826) (xy 312.902594 -305.664782)
			(xy 312.858132 -305.68588) (xy 312.810861 -305.699572) (xy 312.762006 -305.705504) (xy 312.712831 -305.703523)
			(xy 312.664612 -305.693679) (xy 312.618596 -305.676227) (xy 312.575975 -305.65162) (xy 312.537854 -305.620495)
			(xy 312.505219 -305.583658) (xy 312.478916 -305.542062) (xy 312.459625 -305.496786) (xy 312.447848 -305.449002)
			(xy 312.443888 -305.399948) (xy 312.10504 -305.399948) (xy 312.104545 -305.424555) (xy 312.09665 -305.473132)
			(xy 312.081066 -305.519813) (xy 312.058195 -305.56339) (xy 312.02863 -305.602734) (xy 311.993137 -305.636826)
			(xy 311.952634 -305.664782) (xy 311.908172 -305.68588) (xy 311.860901 -305.699572) (xy 311.812046 -305.705504)
			(xy 311.762871 -305.703523) (xy 311.714652 -305.693679) (xy 311.668636 -305.676227) (xy 311.626015 -305.65162)
			(xy 311.587894 -305.620495) (xy 311.555259 -305.583658) (xy 311.528956 -305.542062) (xy 311.509665 -305.496786)
			(xy 311.497888 -305.449002) (xy 311.493928 -305.399948) (xy 311.15508 -305.399948) (xy 311.154585 -305.424555)
			(xy 311.14669 -305.473132) (xy 311.131106 -305.519813) (xy 311.108235 -305.56339) (xy 311.07867 -305.602734)
			(xy 311.043177 -305.636826) (xy 311.002674 -305.664782) (xy 310.958212 -305.68588) (xy 310.910941 -305.699572)
			(xy 310.862086 -305.705504) (xy 310.812911 -305.703523) (xy 310.764692 -305.693679) (xy 310.718676 -305.676227)
			(xy 310.676055 -305.65162) (xy 310.637934 -305.620495) (xy 310.605299 -305.583658) (xy 310.578996 -305.542062)
			(xy 310.559705 -305.496786) (xy 310.547928 -305.449002) (xy 310.543968 -305.399948) (xy 310.226964 -305.399948)
			(xy 310.22646 -305.425656) (xy 310.218417 -305.476438) (xy 310.202529 -305.525337) (xy 310.179186 -305.571149)
			(xy 310.148965 -305.612745) (xy 310.112609 -305.649101) (xy 310.071013 -305.679322) (xy 310.025201 -305.702665)
			(xy 309.976302 -305.718553) (xy 309.92552 -305.726596) (xy 309.874104 -305.726596) (xy 309.823322 -305.718553)
			(xy 309.774423 -305.702665) (xy 309.728611 -305.679322) (xy 309.687015 -305.649101) (xy 309.650659 -305.612745)
			(xy 309.620438 -305.571149) (xy 309.597095 -305.525337) (xy 309.581207 -305.476438) (xy 309.573164 -305.425656)
			(xy 309.2765 -305.425656) (xy 309.268457 -305.476438) (xy 309.252569 -305.525337) (xy 309.229226 -305.571149)
			(xy 309.199005 -305.612745) (xy 309.162649 -305.649101) (xy 309.121053 -305.679322) (xy 309.075241 -305.702665)
			(xy 309.026342 -305.718553) (xy 308.97556 -305.726596) (xy 308.924144 -305.726596) (xy 308.873362 -305.718553)
			(xy 308.824463 -305.702665) (xy 308.778651 -305.679322) (xy 308.737055 -305.649101) (xy 308.700699 -305.612745)
			(xy 308.670478 -305.571149) (xy 308.647135 -305.525337) (xy 308.631247 -305.476438) (xy 308.623204 -305.425656)
			(xy 308.304526 -305.425656) (xy 308.29681 -305.473132) (xy 308.281226 -305.519813) (xy 308.258355 -305.56339)
			(xy 308.22879 -305.602734) (xy 308.193297 -305.636826) (xy 308.152794 -305.664782) (xy 308.108332 -305.68588)
			(xy 308.061061 -305.699572) (xy 308.012206 -305.705504) (xy 307.963031 -305.703523) (xy 307.914812 -305.693679)
			(xy 307.868796 -305.676227) (xy 307.826175 -305.65162) (xy 307.788054 -305.620495) (xy 307.755419 -305.583658)
			(xy 307.729116 -305.542062) (xy 307.709825 -305.496786) (xy 307.698048 -305.449002) (xy 307.694088 -305.399948)
			(xy 307.35524 -305.399948) (xy 307.354745 -305.424555) (xy 307.34685 -305.473132) (xy 307.331266 -305.519813)
			(xy 307.308395 -305.56339) (xy 307.27883 -305.602734) (xy 307.243337 -305.636826) (xy 307.202834 -305.664782)
			(xy 307.158372 -305.68588) (xy 307.111101 -305.699572) (xy 307.062246 -305.705504) (xy 307.013071 -305.703523)
			(xy 306.964852 -305.693679) (xy 306.918836 -305.676227) (xy 306.876215 -305.65162) (xy 306.838094 -305.620495)
			(xy 306.805459 -305.583658) (xy 306.779156 -305.542062) (xy 306.759865 -305.496786) (xy 306.748088 -305.449002)
			(xy 306.744128 -305.399948) (xy 306.405026 -305.399948) (xy 306.404531 -305.424555) (xy 306.396636 -305.473132)
			(xy 306.381052 -305.519813) (xy 306.358181 -305.56339) (xy 306.328616 -305.602734) (xy 306.293123 -305.636826)
			(xy 306.25262 -305.664782) (xy 306.208158 -305.68588) (xy 306.160887 -305.699572) (xy 306.112032 -305.705504)
			(xy 306.062857 -305.703523) (xy 306.014638 -305.693679) (xy 305.968622 -305.676227) (xy 305.926001 -305.65162)
			(xy 305.88788 -305.620495) (xy 305.855245 -305.583658) (xy 305.828942 -305.542062) (xy 305.809651 -305.496786)
			(xy 305.797874 -305.449002) (xy 305.793914 -305.399948) (xy 281.616912 -305.399948) (xy 281.616912 -305.499262)
			(xy 281.617568 -305.51181) (xy 281.629438 -305.533921) (xy 281.639518 -305.541426) (xy 281.720544 -305.595528)
			(xy 281.745436 -305.598068) (xy 281.757628 -305.592988) (xy 281.785665 -305.58209) (xy 281.844649 -305.570324)
			(xy 281.874722 -305.56962) (xy 281.899974 -305.570143) (xy 281.949788 -305.578459) (xy 281.997555 -305.59486)
			(xy 282.04197 -305.6189) (xy 282.081823 -305.649921) (xy 282.116027 -305.687079) (xy 282.143649 -305.72936)
			(xy 282.163935 -305.77561) (xy 282.176333 -305.824569) (xy 282.180503 -305.8749) (xy 282.180501 -305.874928)
			(xy 282.519132 -305.874928) (xy 282.523092 -305.825874) (xy 282.534869 -305.77809) (xy 282.55416 -305.732814)
			(xy 282.580463 -305.691218) (xy 282.613098 -305.654381) (xy 282.651219 -305.623256) (xy 282.69384 -305.598649)
			(xy 282.739856 -305.581197) (xy 282.788075 -305.571353) (xy 282.83725 -305.569372) (xy 282.886105 -305.575304)
			(xy 282.933376 -305.588996) (xy 282.977838 -305.610094) (xy 283.018341 -305.63805) (xy 283.053834 -305.672142)
			(xy 283.083399 -305.711486) (xy 283.10627 -305.755063) (xy 283.121854 -305.801744) (xy 283.129749 -305.850321)
			(xy 283.130244 -305.874928) (xy 283.469092 -305.874928) (xy 283.473052 -305.825874) (xy 283.484829 -305.77809)
			(xy 283.50412 -305.732814) (xy 283.530423 -305.691218) (xy 283.563058 -305.654381) (xy 283.601179 -305.623256)
			(xy 283.6438 -305.598649) (xy 283.689816 -305.581197) (xy 283.738035 -305.571353) (xy 283.78721 -305.569372)
			(xy 283.836065 -305.575304) (xy 283.883336 -305.588996) (xy 283.927798 -305.610094) (xy 283.968301 -305.63805)
			(xy 284.003794 -305.672142) (xy 284.033359 -305.711486) (xy 284.05623 -305.755063) (xy 284.071814 -305.801744)
			(xy 284.079709 -305.850321) (xy 284.080204 -305.874928) (xy 284.419052 -305.874928) (xy 284.423012 -305.825874)
			(xy 284.434789 -305.77809) (xy 284.45408 -305.732814) (xy 284.480383 -305.691218) (xy 284.513018 -305.654381)
			(xy 284.551139 -305.623256) (xy 284.59376 -305.598649) (xy 284.639776 -305.581197) (xy 284.687995 -305.571353)
			(xy 284.73717 -305.569372) (xy 284.786025 -305.575304) (xy 284.833296 -305.588996) (xy 284.877758 -305.610094)
			(xy 284.918261 -305.63805) (xy 284.953754 -305.672142) (xy 284.983319 -305.711486) (xy 285.00619 -305.755063)
			(xy 285.021774 -305.801744) (xy 285.029669 -305.850321) (xy 285.030164 -305.874928) (xy 285.369012 -305.874928)
			(xy 285.372972 -305.825874) (xy 285.384749 -305.77809) (xy 285.40404 -305.732814) (xy 285.430343 -305.691218)
			(xy 285.462978 -305.654381) (xy 285.501099 -305.623256) (xy 285.54372 -305.598649) (xy 285.589736 -305.581197)
			(xy 285.637955 -305.571353) (xy 285.68713 -305.569372) (xy 285.735985 -305.575304) (xy 285.783256 -305.588996)
			(xy 285.827718 -305.610094) (xy 285.868221 -305.63805) (xy 285.903714 -305.672142) (xy 285.933279 -305.711486)
			(xy 285.95615 -305.755063) (xy 285.971734 -305.801744) (xy 285.979629 -305.850321) (xy 285.980124 -305.874928)
			(xy 286.318972 -305.874928) (xy 286.322932 -305.825874) (xy 286.334709 -305.77809) (xy 286.354 -305.732814)
			(xy 286.380303 -305.691218) (xy 286.412938 -305.654381) (xy 286.451059 -305.623256) (xy 286.49368 -305.598649)
			(xy 286.539696 -305.581197) (xy 286.587915 -305.571353) (xy 286.63709 -305.569372) (xy 286.685945 -305.575304)
			(xy 286.733216 -305.588996) (xy 286.777678 -305.610094) (xy 286.818181 -305.63805) (xy 286.853674 -305.672142)
			(xy 286.883239 -305.711486) (xy 286.90611 -305.755063) (xy 286.921694 -305.801744) (xy 286.929589 -305.850321)
			(xy 286.930084 -305.874928) (xy 287.268932 -305.874928) (xy 287.272892 -305.825874) (xy 287.284669 -305.77809)
			(xy 287.30396 -305.732814) (xy 287.330263 -305.691218) (xy 287.362898 -305.654381) (xy 287.401019 -305.623256)
			(xy 287.44364 -305.598649) (xy 287.489656 -305.581197) (xy 287.537875 -305.571353) (xy 287.58705 -305.569372)
			(xy 287.635905 -305.575304) (xy 287.683176 -305.588996) (xy 287.727638 -305.610094) (xy 287.768141 -305.63805)
			(xy 287.803634 -305.672142) (xy 287.833199 -305.711486) (xy 287.85607 -305.755063) (xy 287.871654 -305.801744)
			(xy 287.879549 -305.850321) (xy 287.880044 -305.874928) (xy 288.218892 -305.874928) (xy 288.222852 -305.825874)
			(xy 288.234629 -305.77809) (xy 288.25392 -305.732814) (xy 288.280223 -305.691218) (xy 288.312858 -305.654381)
			(xy 288.350979 -305.623256) (xy 288.3936 -305.598649) (xy 288.439616 -305.581197) (xy 288.487835 -305.571353)
			(xy 288.53701 -305.569372) (xy 288.585865 -305.575304) (xy 288.633136 -305.588996) (xy 288.677598 -305.610094)
			(xy 288.718101 -305.63805) (xy 288.753594 -305.672142) (xy 288.783159 -305.711486) (xy 288.80603 -305.755063)
			(xy 288.821614 -305.801744) (xy 288.829509 -305.850321) (xy 288.830004 -305.874928) (xy 289.169106 -305.874928)
			(xy 289.173066 -305.825874) (xy 289.184843 -305.77809) (xy 289.204134 -305.732814) (xy 289.230437 -305.691218)
			(xy 289.263072 -305.654381) (xy 289.301193 -305.623256) (xy 289.343814 -305.598649) (xy 289.38983 -305.581197)
			(xy 289.438049 -305.571353) (xy 289.487224 -305.569372) (xy 289.536079 -305.575304) (xy 289.58335 -305.588996)
			(xy 289.627812 -305.610094) (xy 289.668315 -305.63805) (xy 289.703808 -305.672142) (xy 289.733373 -305.711486)
			(xy 289.756244 -305.755063) (xy 289.771828 -305.801744) (xy 289.779723 -305.850321) (xy 289.780218 -305.874928)
			(xy 290.119066 -305.874928) (xy 290.123026 -305.825874) (xy 290.134803 -305.77809) (xy 290.154094 -305.732814)
			(xy 290.180397 -305.691218) (xy 290.213032 -305.654381) (xy 290.251153 -305.623256) (xy 290.293774 -305.598649)
			(xy 290.33979 -305.581197) (xy 290.388009 -305.571353) (xy 290.437184 -305.569372) (xy 290.486039 -305.575304)
			(xy 290.53331 -305.588996) (xy 290.577772 -305.610094) (xy 290.618275 -305.63805) (xy 290.653768 -305.672142)
			(xy 290.683333 -305.711486) (xy 290.706204 -305.755063) (xy 290.721788 -305.801744) (xy 290.729683 -305.850321)
			(xy 290.730178 -305.874928) (xy 292.018986 -305.874928) (xy 292.022946 -305.825874) (xy 292.034723 -305.77809)
			(xy 292.054014 -305.732814) (xy 292.080317 -305.691218) (xy 292.112952 -305.654381) (xy 292.151073 -305.623256)
			(xy 292.193694 -305.598649) (xy 292.23971 -305.581197) (xy 292.287929 -305.571353) (xy 292.337104 -305.569372)
			(xy 292.385959 -305.575304) (xy 292.43323 -305.588996) (xy 292.477692 -305.610094) (xy 292.518195 -305.63805)
			(xy 292.553688 -305.672142) (xy 292.583253 -305.711486) (xy 292.606124 -305.755063) (xy 292.621708 -305.801744)
			(xy 292.629603 -305.850321) (xy 292.630098 -305.874928) (xy 292.968946 -305.874928) (xy 292.972906 -305.825874)
			(xy 292.984683 -305.77809) (xy 293.003974 -305.732814) (xy 293.030277 -305.691218) (xy 293.062912 -305.654381)
			(xy 293.101033 -305.623256) (xy 293.143654 -305.598649) (xy 293.18967 -305.581197) (xy 293.237889 -305.571353)
			(xy 293.287064 -305.569372) (xy 293.335919 -305.575304) (xy 293.38319 -305.588996) (xy 293.427652 -305.610094)
			(xy 293.468155 -305.63805) (xy 293.503648 -305.672142) (xy 293.533213 -305.711486) (xy 293.556084 -305.755063)
			(xy 293.571668 -305.801744) (xy 293.579563 -305.850321) (xy 293.580058 -305.874928) (xy 293.918906 -305.874928)
			(xy 293.922866 -305.825874) (xy 293.934643 -305.77809) (xy 293.953934 -305.732814) (xy 293.980237 -305.691218)
			(xy 294.012872 -305.654381) (xy 294.050993 -305.623256) (xy 294.093614 -305.598649) (xy 294.13963 -305.581197)
			(xy 294.187849 -305.571353) (xy 294.237024 -305.569372) (xy 294.285879 -305.575304) (xy 294.33315 -305.588996)
			(xy 294.377612 -305.610094) (xy 294.418115 -305.63805) (xy 294.453608 -305.672142) (xy 294.483173 -305.711486)
			(xy 294.506044 -305.755063) (xy 294.521628 -305.801744) (xy 294.529523 -305.850321) (xy 294.530018 -305.874928)
			(xy 294.86912 -305.874928) (xy 294.87308 -305.825874) (xy 294.884857 -305.77809) (xy 294.904148 -305.732814)
			(xy 294.930451 -305.691218) (xy 294.963086 -305.654381) (xy 295.001207 -305.623256) (xy 295.043828 -305.598649)
			(xy 295.089844 -305.581197) (xy 295.138063 -305.571353) (xy 295.187238 -305.569372) (xy 295.236093 -305.575304)
			(xy 295.283364 -305.588996) (xy 295.327826 -305.610094) (xy 295.368329 -305.63805) (xy 295.403822 -305.672142)
			(xy 295.433387 -305.711486) (xy 295.456258 -305.755063) (xy 295.471842 -305.801744) (xy 295.479737 -305.850321)
			(xy 295.480232 -305.874928) (xy 295.81908 -305.874928) (xy 295.82304 -305.825874) (xy 295.834817 -305.77809)
			(xy 295.854108 -305.732814) (xy 295.880411 -305.691218) (xy 295.913046 -305.654381) (xy 295.951167 -305.623256)
			(xy 295.993788 -305.598649) (xy 296.039804 -305.581197) (xy 296.088023 -305.571353) (xy 296.137198 -305.569372)
			(xy 296.186053 -305.575304) (xy 296.233324 -305.588996) (xy 296.277786 -305.610094) (xy 296.318289 -305.63805)
			(xy 296.353782 -305.672142) (xy 296.383347 -305.711486) (xy 296.406218 -305.755063) (xy 296.421802 -305.801744)
			(xy 296.429697 -305.850321) (xy 296.430192 -305.874928) (xy 296.76904 -305.874928) (xy 296.773 -305.825874)
			(xy 296.784777 -305.77809) (xy 296.804068 -305.732814) (xy 296.830371 -305.691218) (xy 296.863006 -305.654381)
			(xy 296.901127 -305.623256) (xy 296.943748 -305.598649) (xy 296.989764 -305.581197) (xy 297.037983 -305.571353)
			(xy 297.087158 -305.569372) (xy 297.136013 -305.575304) (xy 297.183284 -305.588996) (xy 297.227746 -305.610094)
			(xy 297.268249 -305.63805) (xy 297.303742 -305.672142) (xy 297.333307 -305.711486) (xy 297.356178 -305.755063)
			(xy 297.371762 -305.801744) (xy 297.379657 -305.850321) (xy 297.380152 -305.874928) (xy 297.719 -305.874928)
			(xy 297.72296 -305.825874) (xy 297.734737 -305.77809) (xy 297.754028 -305.732814) (xy 297.780331 -305.691218)
			(xy 297.812966 -305.654381) (xy 297.851087 -305.623256) (xy 297.893708 -305.598649) (xy 297.939724 -305.581197)
			(xy 297.987943 -305.571353) (xy 298.037118 -305.569372) (xy 298.085973 -305.575304) (xy 298.133244 -305.588996)
			(xy 298.177706 -305.610094) (xy 298.218209 -305.63805) (xy 298.253702 -305.672142) (xy 298.283267 -305.711486)
			(xy 298.306138 -305.755063) (xy 298.321722 -305.801744) (xy 298.329617 -305.850321) (xy 298.330112 -305.874928)
			(xy 298.66896 -305.874928) (xy 298.67292 -305.825874) (xy 298.684697 -305.77809) (xy 298.703988 -305.732814)
			(xy 298.730291 -305.691218) (xy 298.762926 -305.654381) (xy 298.801047 -305.623256) (xy 298.843668 -305.598649)
			(xy 298.889684 -305.581197) (xy 298.937903 -305.571353) (xy 298.987078 -305.569372) (xy 299.035933 -305.575304)
			(xy 299.083204 -305.588996) (xy 299.127666 -305.610094) (xy 299.168169 -305.63805) (xy 299.203662 -305.672142)
			(xy 299.233227 -305.711486) (xy 299.256098 -305.755063) (xy 299.271682 -305.801744) (xy 299.279577 -305.850321)
			(xy 299.280072 -305.874928) (xy 299.61892 -305.874928) (xy 299.62288 -305.825874) (xy 299.634657 -305.77809)
			(xy 299.653948 -305.732814) (xy 299.680251 -305.691218) (xy 299.712886 -305.654381) (xy 299.751007 -305.623256)
			(xy 299.793628 -305.598649) (xy 299.839644 -305.581197) (xy 299.887863 -305.571353) (xy 299.937038 -305.569372)
			(xy 299.985893 -305.575304) (xy 300.033164 -305.588996) (xy 300.077626 -305.610094) (xy 300.118129 -305.63805)
			(xy 300.153622 -305.672142) (xy 300.183187 -305.711486) (xy 300.206058 -305.755063) (xy 300.221642 -305.801744)
			(xy 300.229537 -305.850321) (xy 300.230032 -305.874928) (xy 300.56888 -305.874928) (xy 300.57284 -305.825874)
			(xy 300.584617 -305.77809) (xy 300.603908 -305.732814) (xy 300.630211 -305.691218) (xy 300.662846 -305.654381)
			(xy 300.700967 -305.623256) (xy 300.743588 -305.598649) (xy 300.789604 -305.581197) (xy 300.837823 -305.571353)
			(xy 300.886998 -305.569372) (xy 300.935853 -305.575304) (xy 300.983124 -305.588996) (xy 301.027586 -305.610094)
			(xy 301.068089 -305.63805) (xy 301.103582 -305.672142) (xy 301.133147 -305.711486) (xy 301.156018 -305.755063)
			(xy 301.171602 -305.801744) (xy 301.179497 -305.850321) (xy 301.179992 -305.874928) (xy 301.519094 -305.874928)
			(xy 301.523054 -305.825874) (xy 301.534831 -305.77809) (xy 301.554122 -305.732814) (xy 301.580425 -305.691218)
			(xy 301.61306 -305.654381) (xy 301.651181 -305.623256) (xy 301.693802 -305.598649) (xy 301.739818 -305.581197)
			(xy 301.788037 -305.571353) (xy 301.837212 -305.569372) (xy 301.886067 -305.575304) (xy 301.933338 -305.588996)
			(xy 301.9778 -305.610094) (xy 302.018303 -305.63805) (xy 302.053796 -305.672142) (xy 302.083361 -305.711486)
			(xy 302.106232 -305.755063) (xy 302.121816 -305.801744) (xy 302.129711 -305.850321) (xy 302.130206 -305.874928)
			(xy 302.469054 -305.874928) (xy 302.473014 -305.825874) (xy 302.484791 -305.77809) (xy 302.504082 -305.732814)
			(xy 302.530385 -305.691218) (xy 302.56302 -305.654381) (xy 302.601141 -305.623256) (xy 302.643762 -305.598649)
			(xy 302.689778 -305.581197) (xy 302.737997 -305.571353) (xy 302.787172 -305.569372) (xy 302.836027 -305.575304)
			(xy 302.883298 -305.588996) (xy 302.92776 -305.610094) (xy 302.968263 -305.63805) (xy 303.003756 -305.672142)
			(xy 303.033321 -305.711486) (xy 303.056192 -305.755063) (xy 303.071776 -305.801744) (xy 303.079671 -305.850321)
			(xy 303.080166 -305.874928) (xy 303.419014 -305.874928) (xy 303.422974 -305.825874) (xy 303.434751 -305.77809)
			(xy 303.454042 -305.732814) (xy 303.480345 -305.691218) (xy 303.51298 -305.654381) (xy 303.551101 -305.623256)
			(xy 303.593722 -305.598649) (xy 303.639738 -305.581197) (xy 303.687957 -305.571353) (xy 303.737132 -305.569372)
			(xy 303.785987 -305.575304) (xy 303.833258 -305.588996) (xy 303.87772 -305.610094) (xy 303.918223 -305.63805)
			(xy 303.953716 -305.672142) (xy 303.983281 -305.711486) (xy 304.006152 -305.755063) (xy 304.021736 -305.801744)
			(xy 304.029631 -305.850321) (xy 304.030126 -305.874928) (xy 304.368974 -305.874928) (xy 304.372934 -305.825874)
			(xy 304.384711 -305.77809) (xy 304.404002 -305.732814) (xy 304.430305 -305.691218) (xy 304.46294 -305.654381)
			(xy 304.501061 -305.623256) (xy 304.543682 -305.598649) (xy 304.589698 -305.581197) (xy 304.637917 -305.571353)
			(xy 304.687092 -305.569372) (xy 304.735947 -305.575304) (xy 304.783218 -305.588996) (xy 304.82768 -305.610094)
			(xy 304.868183 -305.63805) (xy 304.903676 -305.672142) (xy 304.933241 -305.711486) (xy 304.956112 -305.755063)
			(xy 304.971696 -305.801744) (xy 304.979591 -305.850321) (xy 304.980086 -305.874928) (xy 304.979591 -305.899535)
			(xy 304.971696 -305.948112) (xy 304.956112 -305.994793) (xy 304.933241 -306.03837) (xy 304.903676 -306.077714)
			(xy 304.868183 -306.111806) (xy 304.82768 -306.139762) (xy 304.783218 -306.16086) (xy 304.735947 -306.174552)
			(xy 304.687092 -306.180484) (xy 304.637917 -306.178503) (xy 304.589698 -306.168659) (xy 304.543682 -306.151207)
			(xy 304.501061 -306.1266) (xy 304.46294 -306.095475) (xy 304.430305 -306.058638) (xy 304.404002 -306.017042)
			(xy 304.384711 -305.971766) (xy 304.372934 -305.923982) (xy 304.368974 -305.874928) (xy 304.030126 -305.874928)
			(xy 304.029631 -305.899535) (xy 304.021736 -305.948112) (xy 304.006152 -305.994793) (xy 303.983281 -306.03837)
			(xy 303.953716 -306.077714) (xy 303.918223 -306.111806) (xy 303.87772 -306.139762) (xy 303.833258 -306.16086)
			(xy 303.785987 -306.174552) (xy 303.737132 -306.180484) (xy 303.687957 -306.178503) (xy 303.639738 -306.168659)
			(xy 303.593722 -306.151207) (xy 303.551101 -306.1266) (xy 303.51298 -306.095475) (xy 303.480345 -306.058638)
			(xy 303.454042 -306.017042) (xy 303.434751 -305.971766) (xy 303.422974 -305.923982) (xy 303.419014 -305.874928)
			(xy 303.080166 -305.874928) (xy 303.079671 -305.899535) (xy 303.071776 -305.948112) (xy 303.056192 -305.994793)
			(xy 303.033321 -306.03837) (xy 303.003756 -306.077714) (xy 302.968263 -306.111806) (xy 302.92776 -306.139762)
			(xy 302.883298 -306.16086) (xy 302.836027 -306.174552) (xy 302.787172 -306.180484) (xy 302.737997 -306.178503)
			(xy 302.689778 -306.168659) (xy 302.643762 -306.151207) (xy 302.601141 -306.1266) (xy 302.56302 -306.095475)
			(xy 302.530385 -306.058638) (xy 302.504082 -306.017042) (xy 302.484791 -305.971766) (xy 302.473014 -305.923982)
			(xy 302.469054 -305.874928) (xy 302.130206 -305.874928) (xy 302.129711 -305.899535) (xy 302.121816 -305.948112)
			(xy 302.106232 -305.994793) (xy 302.083361 -306.03837) (xy 302.053796 -306.077714) (xy 302.018303 -306.111806)
			(xy 301.9778 -306.139762) (xy 301.933338 -306.16086) (xy 301.886067 -306.174552) (xy 301.837212 -306.180484)
			(xy 301.788037 -306.178503) (xy 301.739818 -306.168659) (xy 301.693802 -306.151207) (xy 301.651181 -306.1266)
			(xy 301.61306 -306.095475) (xy 301.580425 -306.058638) (xy 301.554122 -306.017042) (xy 301.534831 -305.971766)
			(xy 301.523054 -305.923982) (xy 301.519094 -305.874928) (xy 301.179992 -305.874928) (xy 301.179497 -305.899535)
			(xy 301.171602 -305.948112) (xy 301.156018 -305.994793) (xy 301.133147 -306.03837) (xy 301.103582 -306.077714)
			(xy 301.068089 -306.111806) (xy 301.027586 -306.139762) (xy 300.983124 -306.16086) (xy 300.935853 -306.174552)
			(xy 300.886998 -306.180484) (xy 300.837823 -306.178503) (xy 300.789604 -306.168659) (xy 300.743588 -306.151207)
			(xy 300.700967 -306.1266) (xy 300.662846 -306.095475) (xy 300.630211 -306.058638) (xy 300.603908 -306.017042)
			(xy 300.584617 -305.971766) (xy 300.57284 -305.923982) (xy 300.56888 -305.874928) (xy 300.230032 -305.874928)
			(xy 300.229537 -305.899535) (xy 300.221642 -305.948112) (xy 300.206058 -305.994793) (xy 300.183187 -306.03837)
			(xy 300.153622 -306.077714) (xy 300.118129 -306.111806) (xy 300.077626 -306.139762) (xy 300.033164 -306.16086)
			(xy 299.985893 -306.174552) (xy 299.937038 -306.180484) (xy 299.887863 -306.178503) (xy 299.839644 -306.168659)
			(xy 299.793628 -306.151207) (xy 299.751007 -306.1266) (xy 299.712886 -306.095475) (xy 299.680251 -306.058638)
			(xy 299.653948 -306.017042) (xy 299.634657 -305.971766) (xy 299.62288 -305.923982) (xy 299.61892 -305.874928)
			(xy 299.280072 -305.874928) (xy 299.279577 -305.899535) (xy 299.271682 -305.948112) (xy 299.256098 -305.994793)
			(xy 299.233227 -306.03837) (xy 299.203662 -306.077714) (xy 299.168169 -306.111806) (xy 299.127666 -306.139762)
			(xy 299.083204 -306.16086) (xy 299.035933 -306.174552) (xy 298.987078 -306.180484) (xy 298.937903 -306.178503)
			(xy 298.889684 -306.168659) (xy 298.843668 -306.151207) (xy 298.801047 -306.1266) (xy 298.762926 -306.095475)
			(xy 298.730291 -306.058638) (xy 298.703988 -306.017042) (xy 298.684697 -305.971766) (xy 298.67292 -305.923982)
			(xy 298.66896 -305.874928) (xy 298.330112 -305.874928) (xy 298.329617 -305.899535) (xy 298.321722 -305.948112)
			(xy 298.306138 -305.994793) (xy 298.283267 -306.03837) (xy 298.253702 -306.077714) (xy 298.218209 -306.111806)
			(xy 298.177706 -306.139762) (xy 298.133244 -306.16086) (xy 298.085973 -306.174552) (xy 298.037118 -306.180484)
			(xy 297.987943 -306.178503) (xy 297.939724 -306.168659) (xy 297.893708 -306.151207) (xy 297.851087 -306.1266)
			(xy 297.812966 -306.095475) (xy 297.780331 -306.058638) (xy 297.754028 -306.017042) (xy 297.734737 -305.971766)
			(xy 297.72296 -305.923982) (xy 297.719 -305.874928) (xy 297.380152 -305.874928) (xy 297.379657 -305.899535)
			(xy 297.371762 -305.948112) (xy 297.356178 -305.994793) (xy 297.333307 -306.03837) (xy 297.303742 -306.077714)
			(xy 297.268249 -306.111806) (xy 297.227746 -306.139762) (xy 297.183284 -306.16086) (xy 297.136013 -306.174552)
			(xy 297.087158 -306.180484) (xy 297.037983 -306.178503) (xy 296.989764 -306.168659) (xy 296.943748 -306.151207)
			(xy 296.901127 -306.1266) (xy 296.863006 -306.095475) (xy 296.830371 -306.058638) (xy 296.804068 -306.017042)
			(xy 296.784777 -305.971766) (xy 296.773 -305.923982) (xy 296.76904 -305.874928) (xy 296.430192 -305.874928)
			(xy 296.429697 -305.899535) (xy 296.421802 -305.948112) (xy 296.406218 -305.994793) (xy 296.383347 -306.03837)
			(xy 296.353782 -306.077714) (xy 296.318289 -306.111806) (xy 296.277786 -306.139762) (xy 296.233324 -306.16086)
			(xy 296.186053 -306.174552) (xy 296.137198 -306.180484) (xy 296.088023 -306.178503) (xy 296.039804 -306.168659)
			(xy 295.993788 -306.151207) (xy 295.951167 -306.1266) (xy 295.913046 -306.095475) (xy 295.880411 -306.058638)
			(xy 295.854108 -306.017042) (xy 295.834817 -305.971766) (xy 295.82304 -305.923982) (xy 295.81908 -305.874928)
			(xy 295.480232 -305.874928) (xy 295.479737 -305.899535) (xy 295.471842 -305.948112) (xy 295.456258 -305.994793)
			(xy 295.433387 -306.03837) (xy 295.403822 -306.077714) (xy 295.368329 -306.111806) (xy 295.327826 -306.139762)
			(xy 295.283364 -306.16086) (xy 295.236093 -306.174552) (xy 295.187238 -306.180484) (xy 295.138063 -306.178503)
			(xy 295.089844 -306.168659) (xy 295.043828 -306.151207) (xy 295.001207 -306.1266) (xy 294.963086 -306.095475)
			(xy 294.930451 -306.058638) (xy 294.904148 -306.017042) (xy 294.884857 -305.971766) (xy 294.87308 -305.923982)
			(xy 294.86912 -305.874928) (xy 294.530018 -305.874928) (xy 294.529523 -305.899535) (xy 294.521628 -305.948112)
			(xy 294.506044 -305.994793) (xy 294.483173 -306.03837) (xy 294.453608 -306.077714) (xy 294.418115 -306.111806)
			(xy 294.377612 -306.139762) (xy 294.33315 -306.16086) (xy 294.285879 -306.174552) (xy 294.237024 -306.180484)
			(xy 294.187849 -306.178503) (xy 294.13963 -306.168659) (xy 294.093614 -306.151207) (xy 294.050993 -306.1266)
			(xy 294.012872 -306.095475) (xy 293.980237 -306.058638) (xy 293.953934 -306.017042) (xy 293.934643 -305.971766)
			(xy 293.922866 -305.923982) (xy 293.918906 -305.874928) (xy 293.580058 -305.874928) (xy 293.579563 -305.899535)
			(xy 293.571668 -305.948112) (xy 293.556084 -305.994793) (xy 293.533213 -306.03837) (xy 293.503648 -306.077714)
			(xy 293.468155 -306.111806) (xy 293.427652 -306.139762) (xy 293.38319 -306.16086) (xy 293.335919 -306.174552)
			(xy 293.287064 -306.180484) (xy 293.237889 -306.178503) (xy 293.18967 -306.168659) (xy 293.143654 -306.151207)
			(xy 293.101033 -306.1266) (xy 293.062912 -306.095475) (xy 293.030277 -306.058638) (xy 293.003974 -306.017042)
			(xy 292.984683 -305.971766) (xy 292.972906 -305.923982) (xy 292.968946 -305.874928) (xy 292.630098 -305.874928)
			(xy 292.629603 -305.899535) (xy 292.621708 -305.948112) (xy 292.606124 -305.994793) (xy 292.583253 -306.03837)
			(xy 292.553688 -306.077714) (xy 292.518195 -306.111806) (xy 292.477692 -306.139762) (xy 292.43323 -306.16086)
			(xy 292.385959 -306.174552) (xy 292.337104 -306.180484) (xy 292.287929 -306.178503) (xy 292.23971 -306.168659)
			(xy 292.193694 -306.151207) (xy 292.151073 -306.1266) (xy 292.112952 -306.095475) (xy 292.080317 -306.058638)
			(xy 292.054014 -306.017042) (xy 292.034723 -305.971766) (xy 292.022946 -305.923982) (xy 292.018986 -305.874928)
			(xy 290.730178 -305.874928) (xy 290.729683 -305.899535) (xy 290.721788 -305.948112) (xy 290.706204 -305.994793)
			(xy 290.683333 -306.03837) (xy 290.653768 -306.077714) (xy 290.618275 -306.111806) (xy 290.577772 -306.139762)
			(xy 290.53331 -306.16086) (xy 290.486039 -306.174552) (xy 290.437184 -306.180484) (xy 290.388009 -306.178503)
			(xy 290.33979 -306.168659) (xy 290.293774 -306.151207) (xy 290.251153 -306.1266) (xy 290.213032 -306.095475)
			(xy 290.180397 -306.058638) (xy 290.154094 -306.017042) (xy 290.134803 -305.971766) (xy 290.123026 -305.923982)
			(xy 290.119066 -305.874928) (xy 289.780218 -305.874928) (xy 289.779723 -305.899535) (xy 289.771828 -305.948112)
			(xy 289.756244 -305.994793) (xy 289.733373 -306.03837) (xy 289.703808 -306.077714) (xy 289.668315 -306.111806)
			(xy 289.627812 -306.139762) (xy 289.58335 -306.16086) (xy 289.536079 -306.174552) (xy 289.487224 -306.180484)
			(xy 289.438049 -306.178503) (xy 289.38983 -306.168659) (xy 289.343814 -306.151207) (xy 289.301193 -306.1266)
			(xy 289.263072 -306.095475) (xy 289.230437 -306.058638) (xy 289.204134 -306.017042) (xy 289.184843 -305.971766)
			(xy 289.173066 -305.923982) (xy 289.169106 -305.874928) (xy 288.830004 -305.874928) (xy 288.829509 -305.899535)
			(xy 288.821614 -305.948112) (xy 288.80603 -305.994793) (xy 288.783159 -306.03837) (xy 288.753594 -306.077714)
			(xy 288.718101 -306.111806) (xy 288.677598 -306.139762) (xy 288.633136 -306.16086) (xy 288.585865 -306.174552)
			(xy 288.53701 -306.180484) (xy 288.487835 -306.178503) (xy 288.439616 -306.168659) (xy 288.3936 -306.151207)
			(xy 288.350979 -306.1266) (xy 288.312858 -306.095475) (xy 288.280223 -306.058638) (xy 288.25392 -306.017042)
			(xy 288.234629 -305.971766) (xy 288.222852 -305.923982) (xy 288.218892 -305.874928) (xy 287.880044 -305.874928)
			(xy 287.879549 -305.899535) (xy 287.871654 -305.948112) (xy 287.85607 -305.994793) (xy 287.833199 -306.03837)
			(xy 287.803634 -306.077714) (xy 287.768141 -306.111806) (xy 287.727638 -306.139762) (xy 287.683176 -306.16086)
			(xy 287.635905 -306.174552) (xy 287.58705 -306.180484) (xy 287.537875 -306.178503) (xy 287.489656 -306.168659)
			(xy 287.44364 -306.151207) (xy 287.401019 -306.1266) (xy 287.362898 -306.095475) (xy 287.330263 -306.058638)
			(xy 287.30396 -306.017042) (xy 287.284669 -305.971766) (xy 287.272892 -305.923982) (xy 287.268932 -305.874928)
			(xy 286.930084 -305.874928) (xy 286.929589 -305.899535) (xy 286.921694 -305.948112) (xy 286.90611 -305.994793)
			(xy 286.883239 -306.03837) (xy 286.853674 -306.077714) (xy 286.818181 -306.111806) (xy 286.777678 -306.139762)
			(xy 286.733216 -306.16086) (xy 286.685945 -306.174552) (xy 286.63709 -306.180484) (xy 286.587915 -306.178503)
			(xy 286.539696 -306.168659) (xy 286.49368 -306.151207) (xy 286.451059 -306.1266) (xy 286.412938 -306.095475)
			(xy 286.380303 -306.058638) (xy 286.354 -306.017042) (xy 286.334709 -305.971766) (xy 286.322932 -305.923982)
			(xy 286.318972 -305.874928) (xy 285.980124 -305.874928) (xy 285.979629 -305.899535) (xy 285.971734 -305.948112)
			(xy 285.95615 -305.994793) (xy 285.933279 -306.03837) (xy 285.903714 -306.077714) (xy 285.868221 -306.111806)
			(xy 285.827718 -306.139762) (xy 285.783256 -306.16086) (xy 285.735985 -306.174552) (xy 285.68713 -306.180484)
			(xy 285.637955 -306.178503) (xy 285.589736 -306.168659) (xy 285.54372 -306.151207) (xy 285.501099 -306.1266)
			(xy 285.462978 -306.095475) (xy 285.430343 -306.058638) (xy 285.40404 -306.017042) (xy 285.384749 -305.971766)
			(xy 285.372972 -305.923982) (xy 285.369012 -305.874928) (xy 285.030164 -305.874928) (xy 285.029669 -305.899535)
			(xy 285.021774 -305.948112) (xy 285.00619 -305.994793) (xy 284.983319 -306.03837) (xy 284.953754 -306.077714)
			(xy 284.918261 -306.111806) (xy 284.877758 -306.139762) (xy 284.833296 -306.16086) (xy 284.786025 -306.174552)
			(xy 284.73717 -306.180484) (xy 284.687995 -306.178503) (xy 284.639776 -306.168659) (xy 284.59376 -306.151207)
			(xy 284.551139 -306.1266) (xy 284.513018 -306.095475) (xy 284.480383 -306.058638) (xy 284.45408 -306.017042)
			(xy 284.434789 -305.971766) (xy 284.423012 -305.923982) (xy 284.419052 -305.874928) (xy 284.080204 -305.874928)
			(xy 284.079709 -305.899535) (xy 284.071814 -305.948112) (xy 284.05623 -305.994793) (xy 284.033359 -306.03837)
			(xy 284.003794 -306.077714) (xy 283.968301 -306.111806) (xy 283.927798 -306.139762) (xy 283.883336 -306.16086)
			(xy 283.836065 -306.174552) (xy 283.78721 -306.180484) (xy 283.738035 -306.178503) (xy 283.689816 -306.168659)
			(xy 283.6438 -306.151207) (xy 283.601179 -306.1266) (xy 283.563058 -306.095475) (xy 283.530423 -306.058638)
			(xy 283.50412 -306.017042) (xy 283.484829 -305.971766) (xy 283.473052 -305.923982) (xy 283.469092 -305.874928)
			(xy 283.130244 -305.874928) (xy 283.129749 -305.899535) (xy 283.121854 -305.948112) (xy 283.10627 -305.994793)
			(xy 283.083399 -306.03837) (xy 283.053834 -306.077714) (xy 283.018341 -306.111806) (xy 282.977838 -306.139762)
			(xy 282.933376 -306.16086) (xy 282.886105 -306.174552) (xy 282.83725 -306.180484) (xy 282.788075 -306.178503)
			(xy 282.739856 -306.168659) (xy 282.69384 -306.151207) (xy 282.651219 -306.1266) (xy 282.613098 -306.095475)
			(xy 282.580463 -306.058638) (xy 282.55416 -306.017042) (xy 282.534869 -305.971766) (xy 282.523092 -305.923982)
			(xy 282.519132 -305.874928) (xy 282.180501 -305.874928) (xy 282.176333 -305.925231) (xy 282.163935 -305.97419)
			(xy 282.143649 -306.02044) (xy 282.116027 -306.062721) (xy 282.081823 -306.099879) (xy 282.04197 -306.1309)
			(xy 281.997555 -306.15494) (xy 281.949788 -306.171341) (xy 281.899974 -306.179657) (xy 281.874722 -306.180236)
			(xy 281.844648 -306.179542) (xy 281.785663 -306.167774) (xy 281.757628 -306.156868) (xy 281.745436 -306.151788)
			(xy 281.720544 -306.154328) (xy 281.639518 -306.20843) (xy 281.629467 -306.215952) (xy 281.617633 -306.238059)
			(xy 281.616912 -306.250594) (xy 281.616912 -306.349908) (xy 305.793914 -306.349908) (xy 305.797874 -306.300854)
			(xy 305.809651 -306.25307) (xy 305.828942 -306.207794) (xy 305.855245 -306.166198) (xy 305.88788 -306.129361)
			(xy 305.926001 -306.098236) (xy 305.968622 -306.073629) (xy 306.014638 -306.056177) (xy 306.062857 -306.046333)
			(xy 306.112032 -306.044352) (xy 306.160887 -306.050284) (xy 306.208158 -306.063976) (xy 306.25262 -306.085074)
			(xy 306.293123 -306.11303) (xy 306.328616 -306.147122) (xy 306.358181 -306.186466) (xy 306.381052 -306.230043)
			(xy 306.396636 -306.276724) (xy 306.404531 -306.325301) (xy 306.405026 -306.349908) (xy 306.404531 -306.374515)
			(xy 306.404352 -306.375616) (xy 306.723284 -306.375616) (xy 306.723284 -306.3242) (xy 306.731327 -306.273418)
			(xy 306.747215 -306.224519) (xy 306.770558 -306.178707) (xy 306.800779 -306.137111) (xy 306.837135 -306.100755)
			(xy 306.878731 -306.070534) (xy 306.924543 -306.047191) (xy 306.973442 -306.031303) (xy 307.024224 -306.02326)
			(xy 307.07564 -306.02326) (xy 307.126422 -306.031303) (xy 307.175321 -306.047191) (xy 307.221133 -306.070534)
			(xy 307.262729 -306.100755) (xy 307.299085 -306.137111) (xy 307.329306 -306.178707) (xy 307.352649 -306.224519)
			(xy 307.368537 -306.273418) (xy 307.37658 -306.3242) (xy 307.377084 -306.349908) (xy 307.37658 -306.375616)
			(xy 307.673244 -306.375616) (xy 307.673244 -306.3242) (xy 307.681287 -306.273418) (xy 307.697175 -306.224519)
			(xy 307.720518 -306.178707) (xy 307.750739 -306.137111) (xy 307.787095 -306.100755) (xy 307.828691 -306.070534)
			(xy 307.874503 -306.047191) (xy 307.923402 -306.031303) (xy 307.974184 -306.02326) (xy 308.0256 -306.02326)
			(xy 308.076382 -306.031303) (xy 308.125281 -306.047191) (xy 308.171093 -306.070534) (xy 308.212689 -306.100755)
			(xy 308.249045 -306.137111) (xy 308.279266 -306.178707) (xy 308.302609 -306.224519) (xy 308.318497 -306.273418)
			(xy 308.32654 -306.3242) (xy 308.327044 -306.349908) (xy 308.644048 -306.349908) (xy 308.648008 -306.300854)
			(xy 308.659785 -306.25307) (xy 308.679076 -306.207794) (xy 308.705379 -306.166198) (xy 308.738014 -306.129361)
			(xy 308.776135 -306.098236) (xy 308.818756 -306.073629) (xy 308.864772 -306.056177) (xy 308.912991 -306.046333)
			(xy 308.962166 -306.044352) (xy 309.011021 -306.050284) (xy 309.058292 -306.063976) (xy 309.102754 -306.085074)
			(xy 309.143257 -306.11303) (xy 309.17875 -306.147122) (xy 309.208315 -306.186466) (xy 309.231186 -306.230043)
			(xy 309.24677 -306.276724) (xy 309.254665 -306.325301) (xy 309.25516 -306.349908) (xy 309.594008 -306.349908)
			(xy 309.597968 -306.300854) (xy 309.609745 -306.25307) (xy 309.629036 -306.207794) (xy 309.655339 -306.166198)
			(xy 309.687974 -306.129361) (xy 309.726095 -306.098236) (xy 309.768716 -306.073629) (xy 309.814732 -306.056177)
			(xy 309.862951 -306.046333) (xy 309.912126 -306.044352) (xy 309.960981 -306.050284) (xy 310.008252 -306.063976)
			(xy 310.052714 -306.085074) (xy 310.093217 -306.11303) (xy 310.12871 -306.147122) (xy 310.158275 -306.186466)
			(xy 310.181146 -306.230043) (xy 310.19673 -306.276724) (xy 310.204625 -306.325301) (xy 310.20512 -306.349908)
			(xy 310.543968 -306.349908) (xy 310.547928 -306.300854) (xy 310.559705 -306.25307) (xy 310.578996 -306.207794)
			(xy 310.605299 -306.166198) (xy 310.637934 -306.129361) (xy 310.676055 -306.098236) (xy 310.718676 -306.073629)
			(xy 310.764692 -306.056177) (xy 310.812911 -306.046333) (xy 310.862086 -306.044352) (xy 310.910941 -306.050284)
			(xy 310.958212 -306.063976) (xy 311.002674 -306.085074) (xy 311.043177 -306.11303) (xy 311.07867 -306.147122)
			(xy 311.108235 -306.186466) (xy 311.131106 -306.230043) (xy 311.14669 -306.276724) (xy 311.154585 -306.325301)
			(xy 311.15508 -306.349908) (xy 311.493928 -306.349908) (xy 311.497888 -306.300854) (xy 311.509665 -306.25307)
			(xy 311.528956 -306.207794) (xy 311.555259 -306.166198) (xy 311.587894 -306.129361) (xy 311.626015 -306.098236)
			(xy 311.668636 -306.073629) (xy 311.714652 -306.056177) (xy 311.762871 -306.046333) (xy 311.812046 -306.044352)
			(xy 311.860901 -306.050284) (xy 311.908172 -306.063976) (xy 311.952634 -306.085074) (xy 311.993137 -306.11303)
			(xy 312.02863 -306.147122) (xy 312.058195 -306.186466) (xy 312.081066 -306.230043) (xy 312.09665 -306.276724)
			(xy 312.104545 -306.325301) (xy 312.10504 -306.349908) (xy 312.443888 -306.349908) (xy 312.447848 -306.300854)
			(xy 312.459625 -306.25307) (xy 312.478916 -306.207794) (xy 312.505219 -306.166198) (xy 312.537854 -306.129361)
			(xy 312.575975 -306.098236) (xy 312.618596 -306.073629) (xy 312.664612 -306.056177) (xy 312.712831 -306.046333)
			(xy 312.762006 -306.044352) (xy 312.810861 -306.050284) (xy 312.858132 -306.063976) (xy 312.902594 -306.085074)
			(xy 312.943097 -306.11303) (xy 312.97859 -306.147122) (xy 313.008155 -306.186466) (xy 313.031026 -306.230043)
			(xy 313.04661 -306.276724) (xy 313.054505 -306.325301) (xy 313.055 -306.349908) (xy 313.394102 -306.349908)
			(xy 313.398062 -306.300854) (xy 313.409839 -306.25307) (xy 313.42913 -306.207794) (xy 313.455433 -306.166198)
			(xy 313.488068 -306.129361) (xy 313.526189 -306.098236) (xy 313.56881 -306.073629) (xy 313.614826 -306.056177)
			(xy 313.663045 -306.046333) (xy 313.71222 -306.044352) (xy 313.761075 -306.050284) (xy 313.808346 -306.063976)
			(xy 313.852808 -306.085074) (xy 313.893311 -306.11303) (xy 313.928804 -306.147122) (xy 313.958369 -306.186466)
			(xy 313.98124 -306.230043) (xy 313.996824 -306.276724) (xy 314.004719 -306.325301) (xy 314.005214 -306.349908)
			(xy 314.344062 -306.349908) (xy 314.348022 -306.300854) (xy 314.359799 -306.25307) (xy 314.37909 -306.207794)
			(xy 314.405393 -306.166198) (xy 314.438028 -306.129361) (xy 314.476149 -306.098236) (xy 314.51877 -306.073629)
			(xy 314.564786 -306.056177) (xy 314.613005 -306.046333) (xy 314.66218 -306.044352) (xy 314.711035 -306.050284)
			(xy 314.758306 -306.063976) (xy 314.802768 -306.085074) (xy 314.843271 -306.11303) (xy 314.878764 -306.147122)
			(xy 314.908329 -306.186466) (xy 314.9312 -306.230043) (xy 314.946784 -306.276724) (xy 314.954679 -306.325301)
			(xy 314.955174 -306.349908) (xy 315.294276 -306.349908) (xy 315.298236 -306.300854) (xy 315.310013 -306.25307)
			(xy 315.329304 -306.207794) (xy 315.355607 -306.166198) (xy 315.388242 -306.129361) (xy 315.426363 -306.098236)
			(xy 315.468984 -306.073629) (xy 315.515 -306.056177) (xy 315.563219 -306.046333) (xy 315.612394 -306.044352)
			(xy 315.661249 -306.050284) (xy 315.70852 -306.063976) (xy 315.752982 -306.085074) (xy 315.793485 -306.11303)
			(xy 315.828978 -306.147122) (xy 315.858543 -306.186466) (xy 315.881414 -306.230043) (xy 315.896998 -306.276724)
			(xy 315.904893 -306.325301) (xy 315.905388 -306.349908) (xy 315.904893 -306.374515) (xy 315.896998 -306.423092)
			(xy 315.881414 -306.469773) (xy 315.858543 -306.51335) (xy 315.828978 -306.552694) (xy 315.793485 -306.586786)
			(xy 315.752982 -306.614742) (xy 315.70852 -306.63584) (xy 315.661249 -306.649532) (xy 315.612394 -306.655464)
			(xy 315.563219 -306.653483) (xy 315.515 -306.643639) (xy 315.468984 -306.626187) (xy 315.426363 -306.60158)
			(xy 315.388242 -306.570455) (xy 315.355607 -306.533618) (xy 315.329304 -306.492022) (xy 315.310013 -306.446746)
			(xy 315.298236 -306.398962) (xy 315.294276 -306.349908) (xy 314.955174 -306.349908) (xy 314.954679 -306.374515)
			(xy 314.946784 -306.423092) (xy 314.9312 -306.469773) (xy 314.908329 -306.51335) (xy 314.878764 -306.552694)
			(xy 314.843271 -306.586786) (xy 314.802768 -306.614742) (xy 314.758306 -306.63584) (xy 314.711035 -306.649532)
			(xy 314.66218 -306.655464) (xy 314.613005 -306.653483) (xy 314.564786 -306.643639) (xy 314.51877 -306.626187)
			(xy 314.476149 -306.60158) (xy 314.438028 -306.570455) (xy 314.405393 -306.533618) (xy 314.37909 -306.492022)
			(xy 314.359799 -306.446746) (xy 314.348022 -306.398962) (xy 314.344062 -306.349908) (xy 314.005214 -306.349908)
			(xy 314.004719 -306.374515) (xy 313.996824 -306.423092) (xy 313.98124 -306.469773) (xy 313.958369 -306.51335)
			(xy 313.928804 -306.552694) (xy 313.893311 -306.586786) (xy 313.852808 -306.614742) (xy 313.808346 -306.63584)
			(xy 313.761075 -306.649532) (xy 313.71222 -306.655464) (xy 313.663045 -306.653483) (xy 313.614826 -306.643639)
			(xy 313.56881 -306.626187) (xy 313.526189 -306.60158) (xy 313.488068 -306.570455) (xy 313.455433 -306.533618)
			(xy 313.42913 -306.492022) (xy 313.409839 -306.446746) (xy 313.398062 -306.398962) (xy 313.394102 -306.349908)
			(xy 313.055 -306.349908) (xy 313.054505 -306.374515) (xy 313.04661 -306.423092) (xy 313.031026 -306.469773)
			(xy 313.008155 -306.51335) (xy 312.97859 -306.552694) (xy 312.943097 -306.586786) (xy 312.902594 -306.614742)
			(xy 312.858132 -306.63584) (xy 312.810861 -306.649532) (xy 312.762006 -306.655464) (xy 312.712831 -306.653483)
			(xy 312.664612 -306.643639) (xy 312.618596 -306.626187) (xy 312.575975 -306.60158) (xy 312.537854 -306.570455)
			(xy 312.505219 -306.533618) (xy 312.478916 -306.492022) (xy 312.459625 -306.446746) (xy 312.447848 -306.398962)
			(xy 312.443888 -306.349908) (xy 312.10504 -306.349908) (xy 312.104545 -306.374515) (xy 312.09665 -306.423092)
			(xy 312.081066 -306.469773) (xy 312.058195 -306.51335) (xy 312.02863 -306.552694) (xy 311.993137 -306.586786)
			(xy 311.952634 -306.614742) (xy 311.908172 -306.63584) (xy 311.860901 -306.649532) (xy 311.812046 -306.655464)
			(xy 311.762871 -306.653483) (xy 311.714652 -306.643639) (xy 311.668636 -306.626187) (xy 311.626015 -306.60158)
			(xy 311.587894 -306.570455) (xy 311.555259 -306.533618) (xy 311.528956 -306.492022) (xy 311.509665 -306.446746)
			(xy 311.497888 -306.398962) (xy 311.493928 -306.349908) (xy 311.15508 -306.349908) (xy 311.154585 -306.374515)
			(xy 311.14669 -306.423092) (xy 311.131106 -306.469773) (xy 311.108235 -306.51335) (xy 311.07867 -306.552694)
			(xy 311.043177 -306.586786) (xy 311.002674 -306.614742) (xy 310.958212 -306.63584) (xy 310.910941 -306.649532)
			(xy 310.862086 -306.655464) (xy 310.812911 -306.653483) (xy 310.764692 -306.643639) (xy 310.718676 -306.626187)
			(xy 310.676055 -306.60158) (xy 310.637934 -306.570455) (xy 310.605299 -306.533618) (xy 310.578996 -306.492022)
			(xy 310.559705 -306.446746) (xy 310.547928 -306.398962) (xy 310.543968 -306.349908) (xy 310.20512 -306.349908)
			(xy 310.204625 -306.374515) (xy 310.19673 -306.423092) (xy 310.181146 -306.469773) (xy 310.158275 -306.51335)
			(xy 310.12871 -306.552694) (xy 310.093217 -306.586786) (xy 310.052714 -306.614742) (xy 310.008252 -306.63584)
			(xy 309.960981 -306.649532) (xy 309.912126 -306.655464) (xy 309.862951 -306.653483) (xy 309.814732 -306.643639)
			(xy 309.768716 -306.626187) (xy 309.726095 -306.60158) (xy 309.687974 -306.570455) (xy 309.655339 -306.533618)
			(xy 309.629036 -306.492022) (xy 309.609745 -306.446746) (xy 309.597968 -306.398962) (xy 309.594008 -306.349908)
			(xy 309.25516 -306.349908) (xy 309.254665 -306.374515) (xy 309.24677 -306.423092) (xy 309.231186 -306.469773)
			(xy 309.208315 -306.51335) (xy 309.17875 -306.552694) (xy 309.143257 -306.586786) (xy 309.102754 -306.614742)
			(xy 309.058292 -306.63584) (xy 309.011021 -306.649532) (xy 308.962166 -306.655464) (xy 308.912991 -306.653483)
			(xy 308.864772 -306.643639) (xy 308.818756 -306.626187) (xy 308.776135 -306.60158) (xy 308.738014 -306.570455)
			(xy 308.705379 -306.533618) (xy 308.679076 -306.492022) (xy 308.659785 -306.446746) (xy 308.648008 -306.398962)
			(xy 308.644048 -306.349908) (xy 308.327044 -306.349908) (xy 308.32654 -306.375616) (xy 308.318497 -306.426398)
			(xy 308.302609 -306.475297) (xy 308.279266 -306.521109) (xy 308.249045 -306.562705) (xy 308.212689 -306.599061)
			(xy 308.171093 -306.629282) (xy 308.125281 -306.652625) (xy 308.076382 -306.668513) (xy 308.0256 -306.676556)
			(xy 307.974184 -306.676556) (xy 307.923402 -306.668513) (xy 307.874503 -306.652625) (xy 307.828691 -306.629282)
			(xy 307.787095 -306.599061) (xy 307.750739 -306.562705) (xy 307.720518 -306.521109) (xy 307.697175 -306.475297)
			(xy 307.681287 -306.426398) (xy 307.673244 -306.375616) (xy 307.37658 -306.375616) (xy 307.368537 -306.426398)
			(xy 307.352649 -306.475297) (xy 307.329306 -306.521109) (xy 307.299085 -306.562705) (xy 307.262729 -306.599061)
			(xy 307.221133 -306.629282) (xy 307.175321 -306.652625) (xy 307.126422 -306.668513) (xy 307.07564 -306.676556)
			(xy 307.024224 -306.676556) (xy 306.973442 -306.668513) (xy 306.924543 -306.652625) (xy 306.878731 -306.629282)
			(xy 306.837135 -306.599061) (xy 306.800779 -306.562705) (xy 306.770558 -306.521109) (xy 306.747215 -306.475297)
			(xy 306.731327 -306.426398) (xy 306.723284 -306.375616) (xy 306.404352 -306.375616) (xy 306.396636 -306.423092)
			(xy 306.381052 -306.469773) (xy 306.358181 -306.51335) (xy 306.328616 -306.552694) (xy 306.293123 -306.586786)
			(xy 306.25262 -306.614742) (xy 306.208158 -306.63584) (xy 306.160887 -306.649532) (xy 306.112032 -306.655464)
			(xy 306.062857 -306.653483) (xy 306.014638 -306.643639) (xy 305.968622 -306.626187) (xy 305.926001 -306.60158)
			(xy 305.88788 -306.570455) (xy 305.855245 -306.533618) (xy 305.828942 -306.492022) (xy 305.809651 -306.446746)
			(xy 305.797874 -306.398962) (xy 305.793914 -306.349908) (xy 281.616912 -306.349908) (xy 281.616912 -306.449222)
			(xy 281.617559 -306.461775) (xy 281.62942 -306.483901) (xy 281.639518 -306.491386) (xy 281.720544 -306.545488)
			(xy 281.745436 -306.548028) (xy 281.757628 -306.542948) (xy 281.785665 -306.532048) (xy 281.844649 -306.520279)
			(xy 281.874722 -306.51958) (xy 281.899977 -306.520103) (xy 281.949798 -306.52842) (xy 281.997571 -306.544824)
			(xy 282.041992 -306.568866) (xy 282.08185 -306.599892) (xy 282.116059 -306.637055) (xy 282.143684 -306.679341)
			(xy 282.163973 -306.725597) (xy 282.176372 -306.774562) (xy 282.180542 -306.824888) (xy 282.519132 -306.824888)
			(xy 282.523092 -306.775834) (xy 282.534869 -306.72805) (xy 282.55416 -306.682774) (xy 282.580463 -306.641178)
			(xy 282.613098 -306.604341) (xy 282.651219 -306.573216) (xy 282.69384 -306.548609) (xy 282.739856 -306.531157)
			(xy 282.788075 -306.521313) (xy 282.83725 -306.519332) (xy 282.886105 -306.525264) (xy 282.933376 -306.538956)
			(xy 282.977838 -306.560054) (xy 283.018341 -306.58801) (xy 283.053834 -306.622102) (xy 283.083399 -306.661446)
			(xy 283.10627 -306.705023) (xy 283.121854 -306.751704) (xy 283.129749 -306.800281) (xy 283.130244 -306.824888)
			(xy 283.469092 -306.824888) (xy 283.473052 -306.775834) (xy 283.484829 -306.72805) (xy 283.50412 -306.682774)
			(xy 283.530423 -306.641178) (xy 283.563058 -306.604341) (xy 283.601179 -306.573216) (xy 283.6438 -306.548609)
			(xy 283.689816 -306.531157) (xy 283.738035 -306.521313) (xy 283.78721 -306.519332) (xy 283.836065 -306.525264)
			(xy 283.883336 -306.538956) (xy 283.927798 -306.560054) (xy 283.968301 -306.58801) (xy 284.003794 -306.622102)
			(xy 284.033359 -306.661446) (xy 284.05623 -306.705023) (xy 284.071814 -306.751704) (xy 284.079709 -306.800281)
			(xy 284.080204 -306.824888) (xy 284.419052 -306.824888) (xy 284.423012 -306.775834) (xy 284.434789 -306.72805)
			(xy 284.45408 -306.682774) (xy 284.480383 -306.641178) (xy 284.513018 -306.604341) (xy 284.551139 -306.573216)
			(xy 284.59376 -306.548609) (xy 284.639776 -306.531157) (xy 284.687995 -306.521313) (xy 284.73717 -306.519332)
			(xy 284.786025 -306.525264) (xy 284.833296 -306.538956) (xy 284.877758 -306.560054) (xy 284.918261 -306.58801)
			(xy 284.953754 -306.622102) (xy 284.983319 -306.661446) (xy 285.00619 -306.705023) (xy 285.021774 -306.751704)
			(xy 285.029669 -306.800281) (xy 285.030164 -306.824888) (xy 285.369012 -306.824888) (xy 285.372972 -306.775834)
			(xy 285.384749 -306.72805) (xy 285.40404 -306.682774) (xy 285.430343 -306.641178) (xy 285.462978 -306.604341)
			(xy 285.501099 -306.573216) (xy 285.54372 -306.548609) (xy 285.589736 -306.531157) (xy 285.637955 -306.521313)
			(xy 285.68713 -306.519332) (xy 285.735985 -306.525264) (xy 285.783256 -306.538956) (xy 285.827718 -306.560054)
			(xy 285.868221 -306.58801) (xy 285.903714 -306.622102) (xy 285.933279 -306.661446) (xy 285.95615 -306.705023)
			(xy 285.971734 -306.751704) (xy 285.979629 -306.800281) (xy 285.980124 -306.824888) (xy 286.318972 -306.824888)
			(xy 286.322932 -306.775834) (xy 286.334709 -306.72805) (xy 286.354 -306.682774) (xy 286.380303 -306.641178)
			(xy 286.412938 -306.604341) (xy 286.451059 -306.573216) (xy 286.49368 -306.548609) (xy 286.539696 -306.531157)
			(xy 286.587915 -306.521313) (xy 286.63709 -306.519332) (xy 286.685945 -306.525264) (xy 286.733216 -306.538956)
			(xy 286.777678 -306.560054) (xy 286.818181 -306.58801) (xy 286.853674 -306.622102) (xy 286.883239 -306.661446)
			(xy 286.90611 -306.705023) (xy 286.921694 -306.751704) (xy 286.929589 -306.800281) (xy 286.930084 -306.824888)
			(xy 287.268932 -306.824888) (xy 287.272892 -306.775834) (xy 287.284669 -306.72805) (xy 287.30396 -306.682774)
			(xy 287.330263 -306.641178) (xy 287.362898 -306.604341) (xy 287.401019 -306.573216) (xy 287.44364 -306.548609)
			(xy 287.489656 -306.531157) (xy 287.537875 -306.521313) (xy 287.58705 -306.519332) (xy 287.635905 -306.525264)
			(xy 287.683176 -306.538956) (xy 287.727638 -306.560054) (xy 287.768141 -306.58801) (xy 287.803634 -306.622102)
			(xy 287.833199 -306.661446) (xy 287.85607 -306.705023) (xy 287.871654 -306.751704) (xy 287.879549 -306.800281)
			(xy 287.880044 -306.824888) (xy 288.218892 -306.824888) (xy 288.222852 -306.775834) (xy 288.234629 -306.72805)
			(xy 288.25392 -306.682774) (xy 288.280223 -306.641178) (xy 288.312858 -306.604341) (xy 288.350979 -306.573216)
			(xy 288.3936 -306.548609) (xy 288.439616 -306.531157) (xy 288.487835 -306.521313) (xy 288.53701 -306.519332)
			(xy 288.585865 -306.525264) (xy 288.633136 -306.538956) (xy 288.677598 -306.560054) (xy 288.718101 -306.58801)
			(xy 288.753594 -306.622102) (xy 288.783159 -306.661446) (xy 288.80603 -306.705023) (xy 288.821614 -306.751704)
			(xy 288.829509 -306.800281) (xy 288.830004 -306.824888) (xy 289.169106 -306.824888) (xy 289.173066 -306.775834)
			(xy 289.184843 -306.72805) (xy 289.204134 -306.682774) (xy 289.230437 -306.641178) (xy 289.263072 -306.604341)
			(xy 289.301193 -306.573216) (xy 289.343814 -306.548609) (xy 289.38983 -306.531157) (xy 289.438049 -306.521313)
			(xy 289.487224 -306.519332) (xy 289.536079 -306.525264) (xy 289.58335 -306.538956) (xy 289.627812 -306.560054)
			(xy 289.668315 -306.58801) (xy 289.703808 -306.622102) (xy 289.733373 -306.661446) (xy 289.756244 -306.705023)
			(xy 289.771828 -306.751704) (xy 289.779723 -306.800281) (xy 289.780218 -306.824888) (xy 290.119066 -306.824888)
			(xy 290.123026 -306.775834) (xy 290.134803 -306.72805) (xy 290.154094 -306.682774) (xy 290.180397 -306.641178)
			(xy 290.213032 -306.604341) (xy 290.251153 -306.573216) (xy 290.293774 -306.548609) (xy 290.33979 -306.531157)
			(xy 290.388009 -306.521313) (xy 290.437184 -306.519332) (xy 290.486039 -306.525264) (xy 290.53331 -306.538956)
			(xy 290.577772 -306.560054) (xy 290.618275 -306.58801) (xy 290.653768 -306.622102) (xy 290.683333 -306.661446)
			(xy 290.706204 -306.705023) (xy 290.721788 -306.751704) (xy 290.729683 -306.800281) (xy 290.730178 -306.824888)
			(xy 292.018986 -306.824888) (xy 292.022946 -306.775834) (xy 292.034723 -306.72805) (xy 292.054014 -306.682774)
			(xy 292.080317 -306.641178) (xy 292.112952 -306.604341) (xy 292.151073 -306.573216) (xy 292.193694 -306.548609)
			(xy 292.23971 -306.531157) (xy 292.287929 -306.521313) (xy 292.337104 -306.519332) (xy 292.385959 -306.525264)
			(xy 292.43323 -306.538956) (xy 292.477692 -306.560054) (xy 292.518195 -306.58801) (xy 292.553688 -306.622102)
			(xy 292.583253 -306.661446) (xy 292.606124 -306.705023) (xy 292.621708 -306.751704) (xy 292.629603 -306.800281)
			(xy 292.630098 -306.824888) (xy 292.968946 -306.824888) (xy 292.972906 -306.775834) (xy 292.984683 -306.72805)
			(xy 293.003974 -306.682774) (xy 293.030277 -306.641178) (xy 293.062912 -306.604341) (xy 293.101033 -306.573216)
			(xy 293.143654 -306.548609) (xy 293.18967 -306.531157) (xy 293.237889 -306.521313) (xy 293.287064 -306.519332)
			(xy 293.335919 -306.525264) (xy 293.38319 -306.538956) (xy 293.427652 -306.560054) (xy 293.468155 -306.58801)
			(xy 293.503648 -306.622102) (xy 293.533213 -306.661446) (xy 293.556084 -306.705023) (xy 293.571668 -306.751704)
			(xy 293.579563 -306.800281) (xy 293.580058 -306.824888) (xy 293.918906 -306.824888) (xy 293.922866 -306.775834)
			(xy 293.934643 -306.72805) (xy 293.953934 -306.682774) (xy 293.980237 -306.641178) (xy 294.012872 -306.604341)
			(xy 294.050993 -306.573216) (xy 294.093614 -306.548609) (xy 294.13963 -306.531157) (xy 294.187849 -306.521313)
			(xy 294.237024 -306.519332) (xy 294.285879 -306.525264) (xy 294.33315 -306.538956) (xy 294.377612 -306.560054)
			(xy 294.418115 -306.58801) (xy 294.453608 -306.622102) (xy 294.483173 -306.661446) (xy 294.506044 -306.705023)
			(xy 294.521628 -306.751704) (xy 294.529523 -306.800281) (xy 294.530018 -306.824888) (xy 294.86912 -306.824888)
			(xy 294.87308 -306.775834) (xy 294.884857 -306.72805) (xy 294.904148 -306.682774) (xy 294.930451 -306.641178)
			(xy 294.963086 -306.604341) (xy 295.001207 -306.573216) (xy 295.043828 -306.548609) (xy 295.089844 -306.531157)
			(xy 295.138063 -306.521313) (xy 295.187238 -306.519332) (xy 295.236093 -306.525264) (xy 295.283364 -306.538956)
			(xy 295.327826 -306.560054) (xy 295.368329 -306.58801) (xy 295.403822 -306.622102) (xy 295.433387 -306.661446)
			(xy 295.456258 -306.705023) (xy 295.471842 -306.751704) (xy 295.479737 -306.800281) (xy 295.480232 -306.824888)
			(xy 295.81908 -306.824888) (xy 295.82304 -306.775834) (xy 295.834817 -306.72805) (xy 295.854108 -306.682774)
			(xy 295.880411 -306.641178) (xy 295.913046 -306.604341) (xy 295.951167 -306.573216) (xy 295.993788 -306.548609)
			(xy 296.039804 -306.531157) (xy 296.088023 -306.521313) (xy 296.137198 -306.519332) (xy 296.186053 -306.525264)
			(xy 296.233324 -306.538956) (xy 296.277786 -306.560054) (xy 296.318289 -306.58801) (xy 296.353782 -306.622102)
			(xy 296.383347 -306.661446) (xy 296.406218 -306.705023) (xy 296.421802 -306.751704) (xy 296.429697 -306.800281)
			(xy 296.430192 -306.824888) (xy 296.76904 -306.824888) (xy 296.773 -306.775834) (xy 296.784777 -306.72805)
			(xy 296.804068 -306.682774) (xy 296.830371 -306.641178) (xy 296.863006 -306.604341) (xy 296.901127 -306.573216)
			(xy 296.943748 -306.548609) (xy 296.989764 -306.531157) (xy 297.037983 -306.521313) (xy 297.087158 -306.519332)
			(xy 297.136013 -306.525264) (xy 297.183284 -306.538956) (xy 297.227746 -306.560054) (xy 297.268249 -306.58801)
			(xy 297.303742 -306.622102) (xy 297.333307 -306.661446) (xy 297.356178 -306.705023) (xy 297.371762 -306.751704)
			(xy 297.379657 -306.800281) (xy 297.380152 -306.824888) (xy 297.719 -306.824888) (xy 297.72296 -306.775834)
			(xy 297.734737 -306.72805) (xy 297.754028 -306.682774) (xy 297.780331 -306.641178) (xy 297.812966 -306.604341)
			(xy 297.851087 -306.573216) (xy 297.893708 -306.548609) (xy 297.939724 -306.531157) (xy 297.987943 -306.521313)
			(xy 298.037118 -306.519332) (xy 298.085973 -306.525264) (xy 298.133244 -306.538956) (xy 298.177706 -306.560054)
			(xy 298.218209 -306.58801) (xy 298.253702 -306.622102) (xy 298.283267 -306.661446) (xy 298.306138 -306.705023)
			(xy 298.321722 -306.751704) (xy 298.329617 -306.800281) (xy 298.330112 -306.824888) (xy 298.66896 -306.824888)
			(xy 298.67292 -306.775834) (xy 298.684697 -306.72805) (xy 298.703988 -306.682774) (xy 298.730291 -306.641178)
			(xy 298.762926 -306.604341) (xy 298.801047 -306.573216) (xy 298.843668 -306.548609) (xy 298.889684 -306.531157)
			(xy 298.937903 -306.521313) (xy 298.987078 -306.519332) (xy 299.035933 -306.525264) (xy 299.083204 -306.538956)
			(xy 299.127666 -306.560054) (xy 299.168169 -306.58801) (xy 299.203662 -306.622102) (xy 299.233227 -306.661446)
			(xy 299.256098 -306.705023) (xy 299.271682 -306.751704) (xy 299.279577 -306.800281) (xy 299.280072 -306.824888)
			(xy 299.61892 -306.824888) (xy 299.62288 -306.775834) (xy 299.634657 -306.72805) (xy 299.653948 -306.682774)
			(xy 299.680251 -306.641178) (xy 299.712886 -306.604341) (xy 299.751007 -306.573216) (xy 299.793628 -306.548609)
			(xy 299.839644 -306.531157) (xy 299.887863 -306.521313) (xy 299.937038 -306.519332) (xy 299.985893 -306.525264)
			(xy 300.033164 -306.538956) (xy 300.077626 -306.560054) (xy 300.118129 -306.58801) (xy 300.153622 -306.622102)
			(xy 300.183187 -306.661446) (xy 300.206058 -306.705023) (xy 300.221642 -306.751704) (xy 300.229537 -306.800281)
			(xy 300.230032 -306.824888) (xy 300.56888 -306.824888) (xy 300.57284 -306.775834) (xy 300.584617 -306.72805)
			(xy 300.603908 -306.682774) (xy 300.630211 -306.641178) (xy 300.662846 -306.604341) (xy 300.700967 -306.573216)
			(xy 300.743588 -306.548609) (xy 300.789604 -306.531157) (xy 300.837823 -306.521313) (xy 300.886998 -306.519332)
			(xy 300.935853 -306.525264) (xy 300.983124 -306.538956) (xy 301.027586 -306.560054) (xy 301.068089 -306.58801)
			(xy 301.103582 -306.622102) (xy 301.133147 -306.661446) (xy 301.156018 -306.705023) (xy 301.171602 -306.751704)
			(xy 301.179497 -306.800281) (xy 301.179992 -306.824888) (xy 301.519094 -306.824888) (xy 301.523054 -306.775834)
			(xy 301.534831 -306.72805) (xy 301.554122 -306.682774) (xy 301.580425 -306.641178) (xy 301.61306 -306.604341)
			(xy 301.651181 -306.573216) (xy 301.693802 -306.548609) (xy 301.739818 -306.531157) (xy 301.788037 -306.521313)
			(xy 301.837212 -306.519332) (xy 301.886067 -306.525264) (xy 301.933338 -306.538956) (xy 301.9778 -306.560054)
			(xy 302.018303 -306.58801) (xy 302.053796 -306.622102) (xy 302.083361 -306.661446) (xy 302.106232 -306.705023)
			(xy 302.121816 -306.751704) (xy 302.129711 -306.800281) (xy 302.130206 -306.824888) (xy 302.469054 -306.824888)
			(xy 302.473014 -306.775834) (xy 302.484791 -306.72805) (xy 302.504082 -306.682774) (xy 302.530385 -306.641178)
			(xy 302.56302 -306.604341) (xy 302.601141 -306.573216) (xy 302.643762 -306.548609) (xy 302.689778 -306.531157)
			(xy 302.737997 -306.521313) (xy 302.787172 -306.519332) (xy 302.836027 -306.525264) (xy 302.883298 -306.538956)
			(xy 302.92776 -306.560054) (xy 302.968263 -306.58801) (xy 303.003756 -306.622102) (xy 303.033321 -306.661446)
			(xy 303.056192 -306.705023) (xy 303.071776 -306.751704) (xy 303.079671 -306.800281) (xy 303.080166 -306.824888)
			(xy 303.419014 -306.824888) (xy 303.422974 -306.775834) (xy 303.434751 -306.72805) (xy 303.454042 -306.682774)
			(xy 303.480345 -306.641178) (xy 303.51298 -306.604341) (xy 303.551101 -306.573216) (xy 303.593722 -306.548609)
			(xy 303.639738 -306.531157) (xy 303.687957 -306.521313) (xy 303.737132 -306.519332) (xy 303.785987 -306.525264)
			(xy 303.833258 -306.538956) (xy 303.87772 -306.560054) (xy 303.918223 -306.58801) (xy 303.953716 -306.622102)
			(xy 303.983281 -306.661446) (xy 304.006152 -306.705023) (xy 304.021736 -306.751704) (xy 304.029631 -306.800281)
			(xy 304.030126 -306.824888) (xy 304.368974 -306.824888) (xy 304.372934 -306.775834) (xy 304.384711 -306.72805)
			(xy 304.404002 -306.682774) (xy 304.430305 -306.641178) (xy 304.46294 -306.604341) (xy 304.501061 -306.573216)
			(xy 304.543682 -306.548609) (xy 304.589698 -306.531157) (xy 304.637917 -306.521313) (xy 304.687092 -306.519332)
			(xy 304.735947 -306.525264) (xy 304.783218 -306.538956) (xy 304.82768 -306.560054) (xy 304.868183 -306.58801)
			(xy 304.903676 -306.622102) (xy 304.933241 -306.661446) (xy 304.956112 -306.705023) (xy 304.971696 -306.751704)
			(xy 304.979591 -306.800281) (xy 304.980086 -306.824888) (xy 304.979591 -306.849495) (xy 304.971696 -306.898072)
			(xy 304.956112 -306.944753) (xy 304.933241 -306.98833) (xy 304.903676 -307.027674) (xy 304.868183 -307.061766)
			(xy 304.82768 -307.089722) (xy 304.783218 -307.11082) (xy 304.735947 -307.124512) (xy 304.687092 -307.130444)
			(xy 304.637917 -307.128463) (xy 304.589698 -307.118619) (xy 304.543682 -307.101167) (xy 304.501061 -307.07656)
			(xy 304.46294 -307.045435) (xy 304.430305 -307.008598) (xy 304.404002 -306.967002) (xy 304.384711 -306.921726)
			(xy 304.372934 -306.873942) (xy 304.368974 -306.824888) (xy 304.030126 -306.824888) (xy 304.029631 -306.849495)
			(xy 304.021736 -306.898072) (xy 304.006152 -306.944753) (xy 303.983281 -306.98833) (xy 303.953716 -307.027674)
			(xy 303.918223 -307.061766) (xy 303.87772 -307.089722) (xy 303.833258 -307.11082) (xy 303.785987 -307.124512)
			(xy 303.737132 -307.130444) (xy 303.687957 -307.128463) (xy 303.639738 -307.118619) (xy 303.593722 -307.101167)
			(xy 303.551101 -307.07656) (xy 303.51298 -307.045435) (xy 303.480345 -307.008598) (xy 303.454042 -306.967002)
			(xy 303.434751 -306.921726) (xy 303.422974 -306.873942) (xy 303.419014 -306.824888) (xy 303.080166 -306.824888)
			(xy 303.079671 -306.849495) (xy 303.071776 -306.898072) (xy 303.056192 -306.944753) (xy 303.033321 -306.98833)
			(xy 303.003756 -307.027674) (xy 302.968263 -307.061766) (xy 302.92776 -307.089722) (xy 302.883298 -307.11082)
			(xy 302.836027 -307.124512) (xy 302.787172 -307.130444) (xy 302.737997 -307.128463) (xy 302.689778 -307.118619)
			(xy 302.643762 -307.101167) (xy 302.601141 -307.07656) (xy 302.56302 -307.045435) (xy 302.530385 -307.008598)
			(xy 302.504082 -306.967002) (xy 302.484791 -306.921726) (xy 302.473014 -306.873942) (xy 302.469054 -306.824888)
			(xy 302.130206 -306.824888) (xy 302.129711 -306.849495) (xy 302.121816 -306.898072) (xy 302.106232 -306.944753)
			(xy 302.083361 -306.98833) (xy 302.053796 -307.027674) (xy 302.018303 -307.061766) (xy 301.9778 -307.089722)
			(xy 301.933338 -307.11082) (xy 301.886067 -307.124512) (xy 301.837212 -307.130444) (xy 301.788037 -307.128463)
			(xy 301.739818 -307.118619) (xy 301.693802 -307.101167) (xy 301.651181 -307.07656) (xy 301.61306 -307.045435)
			(xy 301.580425 -307.008598) (xy 301.554122 -306.967002) (xy 301.534831 -306.921726) (xy 301.523054 -306.873942)
			(xy 301.519094 -306.824888) (xy 301.179992 -306.824888) (xy 301.179497 -306.849495) (xy 301.171602 -306.898072)
			(xy 301.156018 -306.944753) (xy 301.133147 -306.98833) (xy 301.103582 -307.027674) (xy 301.068089 -307.061766)
			(xy 301.027586 -307.089722) (xy 300.983124 -307.11082) (xy 300.935853 -307.124512) (xy 300.886998 -307.130444)
			(xy 300.837823 -307.128463) (xy 300.789604 -307.118619) (xy 300.743588 -307.101167) (xy 300.700967 -307.07656)
			(xy 300.662846 -307.045435) (xy 300.630211 -307.008598) (xy 300.603908 -306.967002) (xy 300.584617 -306.921726)
			(xy 300.57284 -306.873942) (xy 300.56888 -306.824888) (xy 300.230032 -306.824888) (xy 300.229537 -306.849495)
			(xy 300.221642 -306.898072) (xy 300.206058 -306.944753) (xy 300.183187 -306.98833) (xy 300.153622 -307.027674)
			(xy 300.118129 -307.061766) (xy 300.077626 -307.089722) (xy 300.033164 -307.11082) (xy 299.985893 -307.124512)
			(xy 299.937038 -307.130444) (xy 299.887863 -307.128463) (xy 299.839644 -307.118619) (xy 299.793628 -307.101167)
			(xy 299.751007 -307.07656) (xy 299.712886 -307.045435) (xy 299.680251 -307.008598) (xy 299.653948 -306.967002)
			(xy 299.634657 -306.921726) (xy 299.62288 -306.873942) (xy 299.61892 -306.824888) (xy 299.280072 -306.824888)
			(xy 299.279577 -306.849495) (xy 299.271682 -306.898072) (xy 299.256098 -306.944753) (xy 299.233227 -306.98833)
			(xy 299.203662 -307.027674) (xy 299.168169 -307.061766) (xy 299.127666 -307.089722) (xy 299.083204 -307.11082)
			(xy 299.035933 -307.124512) (xy 298.987078 -307.130444) (xy 298.937903 -307.128463) (xy 298.889684 -307.118619)
			(xy 298.843668 -307.101167) (xy 298.801047 -307.07656) (xy 298.762926 -307.045435) (xy 298.730291 -307.008598)
			(xy 298.703988 -306.967002) (xy 298.684697 -306.921726) (xy 298.67292 -306.873942) (xy 298.66896 -306.824888)
			(xy 298.330112 -306.824888) (xy 298.329617 -306.849495) (xy 298.321722 -306.898072) (xy 298.306138 -306.944753)
			(xy 298.283267 -306.98833) (xy 298.253702 -307.027674) (xy 298.218209 -307.061766) (xy 298.177706 -307.089722)
			(xy 298.133244 -307.11082) (xy 298.085973 -307.124512) (xy 298.037118 -307.130444) (xy 297.987943 -307.128463)
			(xy 297.939724 -307.118619) (xy 297.893708 -307.101167) (xy 297.851087 -307.07656) (xy 297.812966 -307.045435)
			(xy 297.780331 -307.008598) (xy 297.754028 -306.967002) (xy 297.734737 -306.921726) (xy 297.72296 -306.873942)
			(xy 297.719 -306.824888) (xy 297.380152 -306.824888) (xy 297.379657 -306.849495) (xy 297.371762 -306.898072)
			(xy 297.356178 -306.944753) (xy 297.333307 -306.98833) (xy 297.303742 -307.027674) (xy 297.268249 -307.061766)
			(xy 297.227746 -307.089722) (xy 297.183284 -307.11082) (xy 297.136013 -307.124512) (xy 297.087158 -307.130444)
			(xy 297.037983 -307.128463) (xy 296.989764 -307.118619) (xy 296.943748 -307.101167) (xy 296.901127 -307.07656)
			(xy 296.863006 -307.045435) (xy 296.830371 -307.008598) (xy 296.804068 -306.967002) (xy 296.784777 -306.921726)
			(xy 296.773 -306.873942) (xy 296.76904 -306.824888) (xy 296.430192 -306.824888) (xy 296.429697 -306.849495)
			(xy 296.421802 -306.898072) (xy 296.406218 -306.944753) (xy 296.383347 -306.98833) (xy 296.353782 -307.027674)
			(xy 296.318289 -307.061766) (xy 296.277786 -307.089722) (xy 296.233324 -307.11082) (xy 296.186053 -307.124512)
			(xy 296.137198 -307.130444) (xy 296.088023 -307.128463) (xy 296.039804 -307.118619) (xy 295.993788 -307.101167)
			(xy 295.951167 -307.07656) (xy 295.913046 -307.045435) (xy 295.880411 -307.008598) (xy 295.854108 -306.967002)
			(xy 295.834817 -306.921726) (xy 295.82304 -306.873942) (xy 295.81908 -306.824888) (xy 295.480232 -306.824888)
			(xy 295.479737 -306.849495) (xy 295.471842 -306.898072) (xy 295.456258 -306.944753) (xy 295.433387 -306.98833)
			(xy 295.403822 -307.027674) (xy 295.368329 -307.061766) (xy 295.327826 -307.089722) (xy 295.283364 -307.11082)
			(xy 295.236093 -307.124512) (xy 295.187238 -307.130444) (xy 295.138063 -307.128463) (xy 295.089844 -307.118619)
			(xy 295.043828 -307.101167) (xy 295.001207 -307.07656) (xy 294.963086 -307.045435) (xy 294.930451 -307.008598)
			(xy 294.904148 -306.967002) (xy 294.884857 -306.921726) (xy 294.87308 -306.873942) (xy 294.86912 -306.824888)
			(xy 294.530018 -306.824888) (xy 294.529523 -306.849495) (xy 294.521628 -306.898072) (xy 294.506044 -306.944753)
			(xy 294.483173 -306.98833) (xy 294.453608 -307.027674) (xy 294.418115 -307.061766) (xy 294.377612 -307.089722)
			(xy 294.33315 -307.11082) (xy 294.285879 -307.124512) (xy 294.237024 -307.130444) (xy 294.187849 -307.128463)
			(xy 294.13963 -307.118619) (xy 294.093614 -307.101167) (xy 294.050993 -307.07656) (xy 294.012872 -307.045435)
			(xy 293.980237 -307.008598) (xy 293.953934 -306.967002) (xy 293.934643 -306.921726) (xy 293.922866 -306.873942)
			(xy 293.918906 -306.824888) (xy 293.580058 -306.824888) (xy 293.579563 -306.849495) (xy 293.571668 -306.898072)
			(xy 293.556084 -306.944753) (xy 293.533213 -306.98833) (xy 293.503648 -307.027674) (xy 293.468155 -307.061766)
			(xy 293.427652 -307.089722) (xy 293.38319 -307.11082) (xy 293.335919 -307.124512) (xy 293.287064 -307.130444)
			(xy 293.237889 -307.128463) (xy 293.18967 -307.118619) (xy 293.143654 -307.101167) (xy 293.101033 -307.07656)
			(xy 293.062912 -307.045435) (xy 293.030277 -307.008598) (xy 293.003974 -306.967002) (xy 292.984683 -306.921726)
			(xy 292.972906 -306.873942) (xy 292.968946 -306.824888) (xy 292.630098 -306.824888) (xy 292.629603 -306.849495)
			(xy 292.621708 -306.898072) (xy 292.606124 -306.944753) (xy 292.583253 -306.98833) (xy 292.553688 -307.027674)
			(xy 292.518195 -307.061766) (xy 292.477692 -307.089722) (xy 292.43323 -307.11082) (xy 292.385959 -307.124512)
			(xy 292.337104 -307.130444) (xy 292.287929 -307.128463) (xy 292.23971 -307.118619) (xy 292.193694 -307.101167)
			(xy 292.151073 -307.07656) (xy 292.112952 -307.045435) (xy 292.080317 -307.008598) (xy 292.054014 -306.967002)
			(xy 292.034723 -306.921726) (xy 292.022946 -306.873942) (xy 292.018986 -306.824888) (xy 290.730178 -306.824888)
			(xy 290.729683 -306.849495) (xy 290.721788 -306.898072) (xy 290.706204 -306.944753) (xy 290.683333 -306.98833)
			(xy 290.653768 -307.027674) (xy 290.618275 -307.061766) (xy 290.577772 -307.089722) (xy 290.53331 -307.11082)
			(xy 290.486039 -307.124512) (xy 290.437184 -307.130444) (xy 290.388009 -307.128463) (xy 290.33979 -307.118619)
			(xy 290.293774 -307.101167) (xy 290.251153 -307.07656) (xy 290.213032 -307.045435) (xy 290.180397 -307.008598)
			(xy 290.154094 -306.967002) (xy 290.134803 -306.921726) (xy 290.123026 -306.873942) (xy 290.119066 -306.824888)
			(xy 289.780218 -306.824888) (xy 289.779723 -306.849495) (xy 289.771828 -306.898072) (xy 289.756244 -306.944753)
			(xy 289.733373 -306.98833) (xy 289.703808 -307.027674) (xy 289.668315 -307.061766) (xy 289.627812 -307.089722)
			(xy 289.58335 -307.11082) (xy 289.536079 -307.124512) (xy 289.487224 -307.130444) (xy 289.438049 -307.128463)
			(xy 289.38983 -307.118619) (xy 289.343814 -307.101167) (xy 289.301193 -307.07656) (xy 289.263072 -307.045435)
			(xy 289.230437 -307.008598) (xy 289.204134 -306.967002) (xy 289.184843 -306.921726) (xy 289.173066 -306.873942)
			(xy 289.169106 -306.824888) (xy 288.830004 -306.824888) (xy 288.829509 -306.849495) (xy 288.821614 -306.898072)
			(xy 288.80603 -306.944753) (xy 288.783159 -306.98833) (xy 288.753594 -307.027674) (xy 288.718101 -307.061766)
			(xy 288.677598 -307.089722) (xy 288.633136 -307.11082) (xy 288.585865 -307.124512) (xy 288.53701 -307.130444)
			(xy 288.487835 -307.128463) (xy 288.439616 -307.118619) (xy 288.3936 -307.101167) (xy 288.350979 -307.07656)
			(xy 288.312858 -307.045435) (xy 288.280223 -307.008598) (xy 288.25392 -306.967002) (xy 288.234629 -306.921726)
			(xy 288.222852 -306.873942) (xy 288.218892 -306.824888) (xy 287.880044 -306.824888) (xy 287.879549 -306.849495)
			(xy 287.871654 -306.898072) (xy 287.85607 -306.944753) (xy 287.833199 -306.98833) (xy 287.803634 -307.027674)
			(xy 287.768141 -307.061766) (xy 287.727638 -307.089722) (xy 287.683176 -307.11082) (xy 287.635905 -307.124512)
			(xy 287.58705 -307.130444) (xy 287.537875 -307.128463) (xy 287.489656 -307.118619) (xy 287.44364 -307.101167)
			(xy 287.401019 -307.07656) (xy 287.362898 -307.045435) (xy 287.330263 -307.008598) (xy 287.30396 -306.967002)
			(xy 287.284669 -306.921726) (xy 287.272892 -306.873942) (xy 287.268932 -306.824888) (xy 286.930084 -306.824888)
			(xy 286.929589 -306.849495) (xy 286.921694 -306.898072) (xy 286.90611 -306.944753) (xy 286.883239 -306.98833)
			(xy 286.853674 -307.027674) (xy 286.818181 -307.061766) (xy 286.777678 -307.089722) (xy 286.733216 -307.11082)
			(xy 286.685945 -307.124512) (xy 286.63709 -307.130444) (xy 286.587915 -307.128463) (xy 286.539696 -307.118619)
			(xy 286.49368 -307.101167) (xy 286.451059 -307.07656) (xy 286.412938 -307.045435) (xy 286.380303 -307.008598)
			(xy 286.354 -306.967002) (xy 286.334709 -306.921726) (xy 286.322932 -306.873942) (xy 286.318972 -306.824888)
			(xy 285.980124 -306.824888) (xy 285.979629 -306.849495) (xy 285.971734 -306.898072) (xy 285.95615 -306.944753)
			(xy 285.933279 -306.98833) (xy 285.903714 -307.027674) (xy 285.868221 -307.061766) (xy 285.827718 -307.089722)
			(xy 285.783256 -307.11082) (xy 285.735985 -307.124512) (xy 285.68713 -307.130444) (xy 285.637955 -307.128463)
			(xy 285.589736 -307.118619) (xy 285.54372 -307.101167) (xy 285.501099 -307.07656) (xy 285.462978 -307.045435)
			(xy 285.430343 -307.008598) (xy 285.40404 -306.967002) (xy 285.384749 -306.921726) (xy 285.372972 -306.873942)
			(xy 285.369012 -306.824888) (xy 285.030164 -306.824888) (xy 285.029669 -306.849495) (xy 285.021774 -306.898072)
			(xy 285.00619 -306.944753) (xy 284.983319 -306.98833) (xy 284.953754 -307.027674) (xy 284.918261 -307.061766)
			(xy 284.877758 -307.089722) (xy 284.833296 -307.11082) (xy 284.786025 -307.124512) (xy 284.73717 -307.130444)
			(xy 284.687995 -307.128463) (xy 284.639776 -307.118619) (xy 284.59376 -307.101167) (xy 284.551139 -307.07656)
			(xy 284.513018 -307.045435) (xy 284.480383 -307.008598) (xy 284.45408 -306.967002) (xy 284.434789 -306.921726)
			(xy 284.423012 -306.873942) (xy 284.419052 -306.824888) (xy 284.080204 -306.824888) (xy 284.079709 -306.849495)
			(xy 284.071814 -306.898072) (xy 284.05623 -306.944753) (xy 284.033359 -306.98833) (xy 284.003794 -307.027674)
			(xy 283.968301 -307.061766) (xy 283.927798 -307.089722) (xy 283.883336 -307.11082) (xy 283.836065 -307.124512)
			(xy 283.78721 -307.130444) (xy 283.738035 -307.128463) (xy 283.689816 -307.118619) (xy 283.6438 -307.101167)
			(xy 283.601179 -307.07656) (xy 283.563058 -307.045435) (xy 283.530423 -307.008598) (xy 283.50412 -306.967002)
			(xy 283.484829 -306.921726) (xy 283.473052 -306.873942) (xy 283.469092 -306.824888) (xy 283.130244 -306.824888)
			(xy 283.129749 -306.849495) (xy 283.121854 -306.898072) (xy 283.10627 -306.944753) (xy 283.083399 -306.98833)
			(xy 283.053834 -307.027674) (xy 283.018341 -307.061766) (xy 282.977838 -307.089722) (xy 282.933376 -307.11082)
			(xy 282.886105 -307.124512) (xy 282.83725 -307.130444) (xy 282.788075 -307.128463) (xy 282.739856 -307.118619)
			(xy 282.69384 -307.101167) (xy 282.651219 -307.07656) (xy 282.613098 -307.045435) (xy 282.580463 -307.008598)
			(xy 282.55416 -306.967002) (xy 282.534869 -306.921726) (xy 282.523092 -306.873942) (xy 282.519132 -306.824888)
			(xy 282.180542 -306.824888) (xy 282.180543 -306.8249) (xy 282.176372 -306.875238) (xy 282.163973 -306.924203)
			(xy 282.143684 -306.970459) (xy 282.116059 -307.012745) (xy 282.08185 -307.049908) (xy 282.041992 -307.080934)
			(xy 281.997571 -307.104976) (xy 281.949798 -307.12138) (xy 281.899977 -307.129697) (xy 281.874722 -307.130196)
			(xy 281.844648 -307.129503) (xy 281.785662 -307.117737) (xy 281.757628 -307.106828) (xy 281.745436 -307.101748)
			(xy 281.720544 -307.104288) (xy 281.639518 -307.15839) (xy 281.62946 -307.165909) (xy 281.617609 -307.188016)
			(xy 281.616912 -307.200554) (xy 281.616912 -307.299868) (xy 305.793914 -307.299868) (xy 305.797874 -307.250814)
			(xy 305.809651 -307.20303) (xy 305.828942 -307.157754) (xy 305.855245 -307.116158) (xy 305.88788 -307.079321)
			(xy 305.926001 -307.048196) (xy 305.968622 -307.023589) (xy 306.014638 -307.006137) (xy 306.062857 -306.996293)
			(xy 306.112032 -306.994312) (xy 306.160887 -307.000244) (xy 306.208158 -307.013936) (xy 306.25262 -307.035034)
			(xy 306.293123 -307.06299) (xy 306.328616 -307.097082) (xy 306.358181 -307.136426) (xy 306.381052 -307.180003)
			(xy 306.396636 -307.226684) (xy 306.404531 -307.275261) (xy 306.405026 -307.299868) (xy 306.744128 -307.299868)
			(xy 306.748088 -307.250814) (xy 306.759865 -307.20303) (xy 306.779156 -307.157754) (xy 306.805459 -307.116158)
			(xy 306.838094 -307.079321) (xy 306.876215 -307.048196) (xy 306.918836 -307.023589) (xy 306.964852 -307.006137)
			(xy 307.013071 -306.996293) (xy 307.062246 -306.994312) (xy 307.111101 -307.000244) (xy 307.158372 -307.013936)
			(xy 307.202834 -307.035034) (xy 307.243337 -307.06299) (xy 307.27883 -307.097082) (xy 307.308395 -307.136426)
			(xy 307.331266 -307.180003) (xy 307.34685 -307.226684) (xy 307.354745 -307.275261) (xy 307.35524 -307.299868)
			(xy 307.694088 -307.299868) (xy 307.698048 -307.250814) (xy 307.709825 -307.20303) (xy 307.729116 -307.157754)
			(xy 307.755419 -307.116158) (xy 307.788054 -307.079321) (xy 307.826175 -307.048196) (xy 307.868796 -307.023589)
			(xy 307.914812 -307.006137) (xy 307.963031 -306.996293) (xy 308.012206 -306.994312) (xy 308.061061 -307.000244)
			(xy 308.108332 -307.013936) (xy 308.152794 -307.035034) (xy 308.193297 -307.06299) (xy 308.22879 -307.097082)
			(xy 308.258355 -307.136426) (xy 308.281226 -307.180003) (xy 308.29681 -307.226684) (xy 308.304705 -307.275261)
			(xy 308.3052 -307.299868) (xy 308.304705 -307.324475) (xy 308.304526 -307.325576) (xy 308.623204 -307.325576)
			(xy 308.623204 -307.27416) (xy 308.631247 -307.223378) (xy 308.647135 -307.174479) (xy 308.670478 -307.128667)
			(xy 308.700699 -307.087071) (xy 308.737055 -307.050715) (xy 308.778651 -307.020494) (xy 308.824463 -306.997151)
			(xy 308.873362 -306.981263) (xy 308.924144 -306.97322) (xy 308.97556 -306.97322) (xy 309.026342 -306.981263)
			(xy 309.075241 -306.997151) (xy 309.121053 -307.020494) (xy 309.162649 -307.050715) (xy 309.199005 -307.087071)
			(xy 309.229226 -307.128667) (xy 309.252569 -307.174479) (xy 309.268457 -307.223378) (xy 309.2765 -307.27416)
			(xy 309.277004 -307.299868) (xy 309.2765 -307.325576) (xy 309.573164 -307.325576) (xy 309.573164 -307.27416)
			(xy 309.581207 -307.223378) (xy 309.597095 -307.174479) (xy 309.620438 -307.128667) (xy 309.650659 -307.087071)
			(xy 309.687015 -307.050715) (xy 309.728611 -307.020494) (xy 309.774423 -306.997151) (xy 309.823322 -306.981263)
			(xy 309.874104 -306.97322) (xy 309.92552 -306.97322) (xy 309.976302 -306.981263) (xy 310.025201 -306.997151)
			(xy 310.071013 -307.020494) (xy 310.112609 -307.050715) (xy 310.148965 -307.087071) (xy 310.179186 -307.128667)
			(xy 310.202529 -307.174479) (xy 310.218417 -307.223378) (xy 310.22646 -307.27416) (xy 310.226964 -307.299868)
			(xy 310.543968 -307.299868) (xy 310.547928 -307.250814) (xy 310.559705 -307.20303) (xy 310.578996 -307.157754)
			(xy 310.605299 -307.116158) (xy 310.637934 -307.079321) (xy 310.676055 -307.048196) (xy 310.718676 -307.023589)
			(xy 310.764692 -307.006137) (xy 310.812911 -306.996293) (xy 310.862086 -306.994312) (xy 310.910941 -307.000244)
			(xy 310.958212 -307.013936) (xy 311.002674 -307.035034) (xy 311.043177 -307.06299) (xy 311.07867 -307.097082)
			(xy 311.108235 -307.136426) (xy 311.131106 -307.180003) (xy 311.14669 -307.226684) (xy 311.154585 -307.275261)
			(xy 311.15508 -307.299868) (xy 311.493928 -307.299868) (xy 311.497888 -307.250814) (xy 311.509665 -307.20303)
			(xy 311.528956 -307.157754) (xy 311.555259 -307.116158) (xy 311.587894 -307.079321) (xy 311.626015 -307.048196)
			(xy 311.668636 -307.023589) (xy 311.714652 -307.006137) (xy 311.762871 -306.996293) (xy 311.812046 -306.994312)
			(xy 311.860901 -307.000244) (xy 311.908172 -307.013936) (xy 311.952634 -307.035034) (xy 311.993137 -307.06299)
			(xy 312.02863 -307.097082) (xy 312.058195 -307.136426) (xy 312.081066 -307.180003) (xy 312.09665 -307.226684)
			(xy 312.104545 -307.275261) (xy 312.10504 -307.299868) (xy 312.443888 -307.299868) (xy 312.447848 -307.250814)
			(xy 312.459625 -307.20303) (xy 312.478916 -307.157754) (xy 312.505219 -307.116158) (xy 312.537854 -307.079321)
			(xy 312.575975 -307.048196) (xy 312.618596 -307.023589) (xy 312.664612 -307.006137) (xy 312.712831 -306.996293)
			(xy 312.762006 -306.994312) (xy 312.810861 -307.000244) (xy 312.858132 -307.013936) (xy 312.902594 -307.035034)
			(xy 312.943097 -307.06299) (xy 312.97859 -307.097082) (xy 313.008155 -307.136426) (xy 313.031026 -307.180003)
			(xy 313.04661 -307.226684) (xy 313.054505 -307.275261) (xy 313.055 -307.299868) (xy 313.394102 -307.299868)
			(xy 313.398062 -307.250814) (xy 313.409839 -307.20303) (xy 313.42913 -307.157754) (xy 313.455433 -307.116158)
			(xy 313.488068 -307.079321) (xy 313.526189 -307.048196) (xy 313.56881 -307.023589) (xy 313.614826 -307.006137)
			(xy 313.663045 -306.996293) (xy 313.71222 -306.994312) (xy 313.761075 -307.000244) (xy 313.808346 -307.013936)
			(xy 313.852808 -307.035034) (xy 313.893311 -307.06299) (xy 313.928804 -307.097082) (xy 313.958369 -307.136426)
			(xy 313.98124 -307.180003) (xy 313.996824 -307.226684) (xy 314.004719 -307.275261) (xy 314.005214 -307.299868)
			(xy 314.344062 -307.299868) (xy 314.348022 -307.250814) (xy 314.359799 -307.20303) (xy 314.37909 -307.157754)
			(xy 314.405393 -307.116158) (xy 314.438028 -307.079321) (xy 314.476149 -307.048196) (xy 314.51877 -307.023589)
			(xy 314.564786 -307.006137) (xy 314.613005 -306.996293) (xy 314.66218 -306.994312) (xy 314.711035 -307.000244)
			(xy 314.758306 -307.013936) (xy 314.802768 -307.035034) (xy 314.843271 -307.06299) (xy 314.878764 -307.097082)
			(xy 314.908329 -307.136426) (xy 314.9312 -307.180003) (xy 314.940667 -307.208361) (xy 323.477026 -307.208361)
			(xy 323.484781 -307.154405) (xy 323.500137 -307.102102) (xy 323.52278 -307.052516) (xy 323.552249 -307.006658)
			(xy 323.587945 -306.96546) (xy 323.62914 -306.929762) (xy 323.674997 -306.90029) (xy 323.724581 -306.877644)
			(xy 323.776883 -306.862286) (xy 323.830839 -306.854527) (xy 323.88535 -306.854527) (xy 323.939306 -306.862284)
			(xy 323.991609 -306.877641) (xy 324.041194 -306.900285) (xy 324.087051 -306.929756) (xy 324.128248 -306.965453)
			(xy 324.163945 -307.006649) (xy 324.193415 -307.052507) (xy 324.207899 -307.084222) (xy 324.914258 -307.084222)
			(xy 324.918329 -307.0286) (xy 324.930455 -306.974163) (xy 324.950378 -306.922072) (xy 324.977674 -306.873437)
			(xy 325.01176 -306.829294) (xy 325.051909 -306.790585) (xy 325.097267 -306.758134) (xy 325.146867 -306.732633)
			(xy 325.199651 -306.714626) (xy 325.254494 -306.704496) (xy 325.310228 -306.702459) (xy 325.365665 -306.708559)
			(xy 325.419622 -306.722665) (xy 325.470951 -306.744477) (xy 325.518557 -306.773531) (xy 325.561425 -306.809206)
			(xy 325.598642 -306.850743) (xy 325.629415 -306.897256) (xy 325.653087 -306.947753) (xy 325.669155 -307.00116)
			(xy 325.677275 -307.056336) (xy 325.677784 -307.084222) (xy 325.677275 -307.112108) (xy 325.669155 -307.167284)
			(xy 325.653087 -307.220691) (xy 325.629415 -307.271188) (xy 325.598642 -307.317701) (xy 325.561425 -307.359238)
			(xy 325.518557 -307.394913) (xy 325.470951 -307.423967) (xy 325.419622 -307.445779) (xy 325.365665 -307.459885)
			(xy 325.310228 -307.465985) (xy 325.254494 -307.463948) (xy 325.199651 -307.453818) (xy 325.146867 -307.435811)
			(xy 325.097267 -307.41031) (xy 325.051909 -307.377859) (xy 325.01176 -307.33915) (xy 324.977674 -307.295007)
			(xy 324.950378 -307.246372) (xy 324.930455 -307.194281) (xy 324.918329 -307.139844) (xy 324.914258 -307.084222)
			(xy 324.207899 -307.084222) (xy 324.21606 -307.102092) (xy 324.231416 -307.154395) (xy 324.239173 -307.208351)
			(xy 324.239636 -307.235606) (xy 324.237858 -307.272182) (xy 324.236842 -307.283612) (xy 324.244462 -307.304694)
			(xy 324.31609 -307.376322) (xy 324.337426 -307.383942) (xy 324.348856 -307.382926) (xy 324.385432 -307.381148)
			(xy 324.412682 -307.381648) (xy 324.466627 -307.389408) (xy 324.518919 -307.404765) (xy 324.568493 -307.427406)
			(xy 324.614341 -307.456872) (xy 324.65553 -307.492562) (xy 324.691221 -307.533749) (xy 324.720688 -307.579596)
			(xy 324.743331 -307.62917) (xy 324.75869 -307.681461) (xy 324.766451 -307.735406) (xy 324.76694 -307.762656)
			(xy 324.766584 -307.785162) (xy 324.761957 -307.82387) (xy 335.023714 -307.82387) (xy 335.024159 -307.796499)
			(xy 335.031981 -307.742319) (xy 335.047475 -307.689815) (xy 335.070322 -307.640069) (xy 335.100051 -307.594103)
			(xy 335.117694 -307.573172) (xy 335.12379 -307.56606) (xy 335.13014 -307.549042) (xy 335.13014 -307.463698)
			(xy 335.12379 -307.44668) (xy 335.117694 -307.439568) (xy 335.100025 -307.418658) (xy 335.070304 -307.372686)
			(xy 335.047463 -307.322936) (xy 335.03197 -307.27043) (xy 335.024145 -307.216249) (xy 335.024148 -307.161506)
			(xy 335.03198 -307.107326) (xy 335.047479 -307.054822) (xy 335.070326 -307.005075) (xy 335.100053 -306.959105)
			(xy 335.117694 -306.938172) (xy 335.12379 -306.93106) (xy 335.13014 -306.914042) (xy 335.13014 -306.828698)
			(xy 335.12379 -306.81168) (xy 335.117694 -306.804568) (xy 335.100025 -306.783658) (xy 335.070304 -306.737686)
			(xy 335.047463 -306.687936) (xy 335.03197 -306.63543) (xy 335.024145 -306.581249) (xy 335.024148 -306.526506)
			(xy 335.03198 -306.472326) (xy 335.047479 -306.419822) (xy 335.070326 -306.370075) (xy 335.100053 -306.324105)
			(xy 335.117694 -306.303172) (xy 335.12379 -306.29606) (xy 335.13014 -306.279042) (xy 335.13014 -306.193698)
			(xy 335.12379 -306.17668) (xy 335.117694 -306.169568) (xy 335.100072 -306.148622) (xy 335.070358 -306.102653)
			(xy 335.047519 -306.052909) (xy 335.032024 -306.000411) (xy 335.024191 -305.946238) (xy 335.023714 -305.91887)
			(xy 335.0242 -305.891619) (xy 335.031956 -305.837671) (xy 335.047311 -305.785376) (xy 335.069953 -305.735799)
			(xy 335.099419 -305.689949) (xy 335.13511 -305.648758) (xy 335.176301 -305.613067) (xy 335.222151 -305.583601)
			(xy 335.271728 -305.560959) (xy 335.324023 -305.545604) (xy 335.377971 -305.537848) (xy 335.432473 -305.537848)
			(xy 335.486421 -305.545604) (xy 335.538716 -305.560959) (xy 335.588293 -305.583601) (xy 335.634143 -305.613067)
			(xy 335.675334 -305.648758) (xy 335.711025 -305.689949) (xy 335.740491 -305.735799) (xy 335.763133 -305.785376)
			(xy 335.778488 -305.837671) (xy 335.786244 -305.891619) (xy 335.78673 -305.91887) (xy 335.786263 -305.94624)
			(xy 335.778448 -306.00042) (xy 335.76296 -306.052924) (xy 335.740118 -306.102671) (xy 335.710392 -306.148637)
			(xy 335.69275 -306.169568) (xy 335.686654 -306.17668) (xy 335.680304 -306.193698) (xy 335.680304 -306.279042)
			(xy 335.686654 -306.29606) (xy 335.69275 -306.303172) (xy 335.710362 -306.324128) (xy 335.74009 -306.370091)
			(xy 335.762939 -306.419834) (xy 335.778438 -306.472332) (xy 335.78627 -306.526508) (xy 335.786273 -306.581247)
			(xy 335.778448 -306.635424) (xy 335.762954 -306.687924) (xy 335.740112 -306.737669) (xy 335.71039 -306.783636)
			(xy 335.69275 -306.804568) (xy 335.686654 -306.81168) (xy 335.680304 -306.828698) (xy 335.680304 -306.914042)
			(xy 335.686654 -306.93106) (xy 335.69275 -306.938172) (xy 335.710362 -306.959128) (xy 335.74009 -307.005091)
			(xy 335.762939 -307.054834) (xy 335.778438 -307.107332) (xy 335.78627 -307.161508) (xy 335.786273 -307.216247)
			(xy 335.778448 -307.270424) (xy 335.762954 -307.322924) (xy 335.740112 -307.372669) (xy 335.71039 -307.418636)
			(xy 335.69275 -307.439568) (xy 335.686654 -307.44668) (xy 335.680304 -307.463698) (xy 335.680304 -307.549042)
			(xy 335.686654 -307.56606) (xy 335.69275 -307.573172) (xy 335.710382 -307.59411) (xy 335.740096 -307.640081)
			(xy 335.762934 -307.689826) (xy 335.778427 -307.742326) (xy 335.786256 -307.796501) (xy 335.78673 -307.82387)
			(xy 335.786244 -307.851121) (xy 335.78242 -307.877718) (xy 338.655914 -307.877718) (xy 338.656387 -307.850348)
			(xy 338.664203 -307.796169) (xy 338.67969 -307.743666) (xy 338.70253 -307.693919) (xy 338.732253 -307.647952)
			(xy 338.749894 -307.62702) (xy 338.75599 -307.619908) (xy 338.76234 -307.60289) (xy 338.76234 -307.517546)
			(xy 338.75599 -307.500528) (xy 338.749894 -307.493416) (xy 338.732272 -307.472468) (xy 338.702549 -307.426502)
			(xy 338.679705 -307.376758) (xy 338.664209 -307.324259) (xy 338.656379 -307.270083) (xy 338.656377 -307.215344)
			(xy 338.664203 -307.161168) (xy 338.679695 -307.108667) (xy 338.702536 -307.058921) (xy 338.732256 -307.012953)
			(xy 338.749894 -306.99202) (xy 338.75599 -306.984908) (xy 338.76234 -306.96789) (xy 338.76234 -306.882546)
			(xy 338.75599 -306.865528) (xy 338.749894 -306.858416) (xy 338.732272 -306.837468) (xy 338.702549 -306.791502)
			(xy 338.679705 -306.741758) (xy 338.664209 -306.689259) (xy 338.656379 -306.635083) (xy 338.656377 -306.580344)
			(xy 338.664203 -306.526168) (xy 338.679695 -306.473667) (xy 338.702536 -306.423921) (xy 338.732256 -306.377953)
			(xy 338.749894 -306.35702) (xy 338.75599 -306.349908) (xy 338.76234 -306.33289) (xy 338.76234 -306.247546)
			(xy 338.75599 -306.230528) (xy 338.749894 -306.223416) (xy 338.732248 -306.20249) (xy 338.702537 -306.156515)
			(xy 338.679703 -306.106766) (xy 338.664213 -306.054264) (xy 338.656387 -306.000088) (xy 338.655914 -305.972718)
			(xy 338.6564 -305.945467) (xy 338.664156 -305.891519) (xy 338.679511 -305.839224) (xy 338.702153 -305.789647)
			(xy 338.731619 -305.743797) (xy 338.76731 -305.702606) (xy 338.808501 -305.666915) (xy 338.854351 -305.637449)
			(xy 338.903928 -305.614807) (xy 338.956223 -305.599452) (xy 339.010171 -305.591696) (xy 339.064673 -305.591696)
			(xy 339.118621 -305.599452) (xy 339.170916 -305.614807) (xy 339.220493 -305.637449) (xy 339.266343 -305.666915)
			(xy 339.307534 -305.702606) (xy 339.343225 -305.743797) (xy 339.372691 -305.789647) (xy 339.395333 -305.839224)
			(xy 339.410688 -305.891519) (xy 339.418444 -305.945467) (xy 339.41893 -305.972718) (xy 339.418492 -306.000089)
			(xy 339.41067 -306.05427) (xy 339.395175 -306.106774) (xy 339.372327 -306.156521) (xy 339.342595 -306.202486)
			(xy 339.32495 -306.223416) (xy 339.318854 -306.230528) (xy 339.312504 -306.247546) (xy 339.312504 -306.33289)
			(xy 339.318854 -306.349908) (xy 339.32495 -306.35702) (xy 339.342609 -306.377938) (xy 339.372335 -306.423908)
			(xy 339.395181 -306.473656) (xy 339.410677 -306.526161) (xy 339.418504 -306.580342) (xy 339.418502 -306.635085)
			(xy 339.410671 -306.689266) (xy 339.395171 -306.741769) (xy 339.372322 -306.791516) (xy 339.342593 -306.837484)
			(xy 339.32495 -306.858416) (xy 339.318854 -306.865528) (xy 339.312504 -306.882546) (xy 339.312504 -306.96789)
			(xy 339.318854 -306.984908) (xy 339.32495 -306.99202) (xy 339.342609 -307.012938) (xy 339.372335 -307.058908)
			(xy 339.395181 -307.108656) (xy 339.410677 -307.161161) (xy 339.418504 -307.215342) (xy 339.418502 -307.270085)
			(xy 339.410671 -307.324266) (xy 339.395171 -307.376769) (xy 339.372322 -307.426516) (xy 339.342593 -307.472484)
			(xy 339.32495 -307.493416) (xy 339.318854 -307.500528) (xy 339.312504 -307.517546) (xy 339.312504 -307.60289)
			(xy 339.318854 -307.619908) (xy 339.32495 -307.62702) (xy 339.342557 -307.647978) (xy 339.372276 -307.693943)
			(xy 339.395118 -307.743684) (xy 339.410617 -307.796179) (xy 339.414622 -307.82387) (xy 341.863934 -307.82387)
			(xy 341.864374 -307.796499) (xy 341.872197 -307.742318) (xy 341.887692 -307.689814) (xy 341.910539 -307.640068)
			(xy 341.94027 -307.594103) (xy 341.957914 -307.573172) (xy 341.96401 -307.56606) (xy 341.97036 -307.549042)
			(xy 341.97036 -307.463698) (xy 341.96401 -307.44668) (xy 341.957914 -307.439568) (xy 341.940244 -307.418659)
			(xy 341.910522 -307.372687) (xy 341.887679 -307.322936) (xy 341.872186 -307.270431) (xy 341.86436 -307.216249)
			(xy 341.864363 -307.161506) (xy 341.872195 -307.107325) (xy 341.887695 -307.054821) (xy 341.910544 -307.005074)
			(xy 341.940272 -306.959105) (xy 341.957914 -306.938172) (xy 341.96401 -306.93106) (xy 341.97036 -306.914042)
			(xy 341.97036 -306.828698) (xy 341.96401 -306.81168) (xy 341.957914 -306.804568) (xy 341.940244 -306.783659)
			(xy 341.910522 -306.737687) (xy 341.887679 -306.687936) (xy 341.872186 -306.635431) (xy 341.86436 -306.581249)
			(xy 341.864363 -306.526506) (xy 341.872195 -306.472325) (xy 341.887695 -306.419821) (xy 341.910544 -306.370074)
			(xy 341.940272 -306.324105) (xy 341.957914 -306.303172) (xy 341.96401 -306.29606) (xy 341.97036 -306.279042)
			(xy 341.97036 -306.193698) (xy 341.96401 -306.17668) (xy 341.957914 -306.169568) (xy 341.940296 -306.148619)
			(xy 341.91058 -306.102651) (xy 341.88774 -306.052908) (xy 341.872244 -306.000411) (xy 341.864411 -305.946238)
			(xy 341.863934 -305.91887) (xy 341.86442 -305.891619) (xy 341.872176 -305.837671) (xy 341.887531 -305.785376)
			(xy 341.910173 -305.735799) (xy 341.939639 -305.689949) (xy 341.97533 -305.648758) (xy 342.016521 -305.613067)
			(xy 342.062371 -305.583601) (xy 342.111948 -305.560959) (xy 342.164243 -305.545604) (xy 342.218191 -305.537848)
			(xy 342.272693 -305.537848) (xy 342.326641 -305.545604) (xy 342.378936 -305.560959) (xy 342.428513 -305.583601)
			(xy 342.474363 -305.613067) (xy 342.515554 -305.648758) (xy 342.551245 -305.689949) (xy 342.580711 -305.735799)
			(xy 342.603353 -305.785376) (xy 342.618708 -305.837671) (xy 342.626464 -305.891619) (xy 342.62695 -305.91887)
			(xy 342.626479 -305.94624) (xy 342.618664 -306.00042) (xy 342.603177 -306.052923) (xy 342.580336 -306.10267)
			(xy 342.550611 -306.148637) (xy 342.53297 -306.169568) (xy 342.526874 -306.17668) (xy 342.520524 -306.193698)
			(xy 342.520524 -306.279042) (xy 342.526874 -306.29606) (xy 342.53297 -306.303172) (xy 342.550581 -306.324128)
			(xy 342.580308 -306.370092) (xy 342.603155 -306.419834) (xy 342.618654 -306.472333) (xy 342.626485 -306.526508)
			(xy 342.626488 -306.581247) (xy 342.618663 -306.635423) (xy 342.603171 -306.687923) (xy 342.580329 -306.737668)
			(xy 342.550609 -306.783635) (xy 342.53297 -306.804568) (xy 342.526874 -306.81168) (xy 342.520524 -306.828698)
			(xy 342.520524 -306.914042) (xy 342.526874 -306.93106) (xy 342.53297 -306.938172) (xy 342.550581 -306.959128)
			(xy 342.580308 -307.005092) (xy 342.603155 -307.054834) (xy 342.618654 -307.107333) (xy 342.626485 -307.161508)
			(xy 342.626488 -307.216247) (xy 342.618663 -307.270423) (xy 342.603171 -307.322923) (xy 342.580329 -307.372668)
			(xy 342.550609 -307.418635) (xy 342.53297 -307.439568) (xy 342.526874 -307.44668) (xy 342.520524 -307.463698)
			(xy 342.520524 -307.549042) (xy 342.526874 -307.56606) (xy 342.53297 -307.573172) (xy 342.550605 -307.594108)
			(xy 342.580318 -307.640079) (xy 342.603156 -307.689826) (xy 342.618648 -307.742326) (xy 342.626476 -307.796501)
			(xy 342.62695 -307.82387) (xy 342.626464 -307.851121) (xy 342.62264 -307.877718) (xy 345.496134 -307.877718)
			(xy 345.496602 -307.850348) (xy 345.504418 -307.796168) (xy 345.519906 -307.743665) (xy 345.542748 -307.693918)
			(xy 345.572473 -307.647951) (xy 345.590114 -307.62702) (xy 345.59621 -307.619908) (xy 345.60256 -307.60289)
			(xy 345.60256 -307.517546) (xy 345.59621 -307.500528) (xy 345.590114 -307.493416) (xy 345.572491 -307.472469)
			(xy 345.542767 -307.426503) (xy 345.519921 -307.376759) (xy 345.504424 -307.324259) (xy 345.496594 -307.270083)
			(xy 345.496592 -307.215344) (xy 345.504418 -307.161167) (xy 345.519912 -307.108666) (xy 345.542754 -307.058921)
			(xy 345.572475 -307.012953) (xy 345.590114 -306.99202) (xy 345.59621 -306.984908) (xy 345.60256 -306.96789)
			(xy 345.60256 -306.882546) (xy 345.59621 -306.865528) (xy 345.590114 -306.858416) (xy 345.572491 -306.837469)
			(xy 345.542767 -306.791503) (xy 345.519921 -306.741759) (xy 345.504424 -306.689259) (xy 345.496594 -306.635083)
			(xy 345.496592 -306.580344) (xy 345.504418 -306.526167) (xy 345.519912 -306.473666) (xy 345.542754 -306.423921)
			(xy 345.572475 -306.377953) (xy 345.590114 -306.35702) (xy 345.59621 -306.349908) (xy 345.60256 -306.33289)
			(xy 345.60256 -306.247546) (xy 345.59621 -306.230528) (xy 345.590114 -306.223416) (xy 345.572471 -306.202487)
			(xy 345.542759 -306.156514) (xy 345.519924 -306.106765) (xy 345.504434 -306.054264) (xy 345.496607 -306.000087)
			(xy 345.496134 -305.972718) (xy 345.49662 -305.945467) (xy 345.504376 -305.891519) (xy 345.519731 -305.839224)
			(xy 345.542373 -305.789647) (xy 345.571839 -305.743797) (xy 345.60753 -305.702606) (xy 345.648721 -305.666915)
			(xy 345.694571 -305.637449) (xy 345.744148 -305.614807) (xy 345.796443 -305.599452) (xy 345.850391 -305.591696)
			(xy 345.904893 -305.591696) (xy 345.958841 -305.599452) (xy 346.011136 -305.614807) (xy 346.060713 -305.637449)
			(xy 346.106563 -305.666915) (xy 346.147754 -305.702606) (xy 346.183445 -305.743797) (xy 346.212911 -305.789647)
			(xy 346.235553 -305.839224) (xy 346.250908 -305.891519) (xy 346.258664 -305.945467) (xy 346.25915 -305.972718)
			(xy 346.258707 -306.000089) (xy 346.250885 -306.05427) (xy 346.235392 -306.106774) (xy 346.212544 -306.15652)
			(xy 346.182814 -306.202486) (xy 346.16517 -306.223416) (xy 346.159074 -306.230528) (xy 346.152724 -306.247546)
			(xy 346.152724 -306.33289) (xy 346.159074 -306.349908) (xy 346.16517 -306.35702) (xy 346.182828 -306.377938)
			(xy 346.212553 -306.423909) (xy 346.235397 -306.473657) (xy 346.250892 -306.526161) (xy 346.258719 -306.580342)
			(xy 346.258717 -306.635085) (xy 346.250886 -306.689265) (xy 346.235388 -306.741768) (xy 346.21254 -306.791515)
			(xy 346.182812 -306.837483) (xy 346.16517 -306.858416) (xy 346.159074 -306.865528) (xy 346.152724 -306.882546)
			(xy 346.152724 -306.96789) (xy 346.159074 -306.984908) (xy 346.16517 -306.99202) (xy 346.182828 -307.012938)
			(xy 346.212553 -307.058909) (xy 346.235397 -307.108657) (xy 346.250892 -307.161161) (xy 346.258719 -307.215342)
			(xy 346.258717 -307.270085) (xy 346.250886 -307.324265) (xy 346.235388 -307.376768) (xy 346.21254 -307.426515)
			(xy 346.182812 -307.472483) (xy 346.16517 -307.493416) (xy 346.159074 -307.500528) (xy 346.152724 -307.517546)
			(xy 346.152724 -307.60289) (xy 346.159074 -307.619908) (xy 346.16517 -307.62702) (xy 346.18278 -307.647975)
			(xy 346.212498 -307.693941) (xy 346.23534 -307.743683) (xy 346.250837 -307.796178) (xy 346.258672 -307.85035)
			(xy 346.25915 -307.877718) (xy 346.258664 -307.904969) (xy 346.250908 -307.958917) (xy 346.235553 -308.011212)
			(xy 346.212911 -308.060789) (xy 346.183445 -308.106639) (xy 346.147754 -308.14783) (xy 346.106563 -308.183521)
			(xy 346.060713 -308.212987) (xy 346.011136 -308.235629) (xy 345.958841 -308.250984) (xy 345.904893 -308.25874)
			(xy 345.850391 -308.25874) (xy 345.796443 -308.250984) (xy 345.744148 -308.235629) (xy 345.694571 -308.212987)
			(xy 345.648721 -308.183521) (xy 345.60753 -308.14783) (xy 345.571839 -308.106639) (xy 345.542373 -308.060789)
			(xy 345.519731 -308.011212) (xy 345.504376 -307.958917) (xy 345.49662 -307.904969) (xy 345.496134 -307.877718)
			(xy 342.62264 -307.877718) (xy 342.618708 -307.905069) (xy 342.603353 -307.957364) (xy 342.580711 -308.006941)
			(xy 342.551245 -308.052791) (xy 342.515554 -308.093982) (xy 342.474363 -308.129673) (xy 342.428513 -308.159139)
			(xy 342.378936 -308.181781) (xy 342.326641 -308.197136) (xy 342.272693 -308.204892) (xy 342.218191 -308.204892)
			(xy 342.164243 -308.197136) (xy 342.111948 -308.181781) (xy 342.062371 -308.159139) (xy 342.016521 -308.129673)
			(xy 341.97533 -308.093982) (xy 341.939639 -308.052791) (xy 341.910173 -308.006941) (xy 341.887531 -307.957364)
			(xy 341.872176 -307.905069) (xy 341.86442 -307.851121) (xy 341.863934 -307.82387) (xy 339.414622 -307.82387)
			(xy 339.418452 -307.85035) (xy 339.41893 -307.877718) (xy 339.418444 -307.904969) (xy 339.410688 -307.958917)
			(xy 339.395333 -308.011212) (xy 339.372691 -308.060789) (xy 339.343225 -308.106639) (xy 339.307534 -308.14783)
			(xy 339.266343 -308.183521) (xy 339.220493 -308.212987) (xy 339.170916 -308.235629) (xy 339.118621 -308.250984)
			(xy 339.064673 -308.25874) (xy 339.010171 -308.25874) (xy 338.956223 -308.250984) (xy 338.903928 -308.235629)
			(xy 338.854351 -308.212987) (xy 338.808501 -308.183521) (xy 338.76731 -308.14783) (xy 338.731619 -308.106639)
			(xy 338.702153 -308.060789) (xy 338.679511 -308.011212) (xy 338.664156 -307.958917) (xy 338.6564 -307.904969)
			(xy 338.655914 -307.877718) (xy 335.78242 -307.877718) (xy 335.778488 -307.905069) (xy 335.763133 -307.957364)
			(xy 335.740491 -308.006941) (xy 335.711025 -308.052791) (xy 335.675334 -308.093982) (xy 335.634143 -308.129673)
			(xy 335.588293 -308.159139) (xy 335.538716 -308.181781) (xy 335.486421 -308.197136) (xy 335.432473 -308.204892)
			(xy 335.377971 -308.204892) (xy 335.324023 -308.197136) (xy 335.271728 -308.181781) (xy 335.222151 -308.159139)
			(xy 335.176301 -308.129673) (xy 335.13511 -308.093982) (xy 335.099419 -308.052791) (xy 335.069953 -308.006941)
			(xy 335.047311 -307.957364) (xy 335.031956 -307.905069) (xy 335.0242 -307.851121) (xy 335.023714 -307.82387)
			(xy 324.761957 -307.82387) (xy 324.761241 -307.829856) (xy 324.756272 -307.85181) (xy 324.753224 -307.865018)
			(xy 324.760336 -307.890164) (xy 324.8406 -307.970428) (xy 324.865746 -307.97754) (xy 324.878954 -307.974492)
			(xy 324.90091 -307.969534) (xy 324.945603 -307.964184) (xy 324.968108 -307.963824) (xy 324.995358 -307.964286)
			(xy 325.049303 -307.972043) (xy 325.101596 -307.987399) (xy 325.15117 -308.010039) (xy 325.197019 -308.039505)
			(xy 325.238207 -308.075195) (xy 325.273897 -308.116384) (xy 325.303362 -308.162232) (xy 325.326002 -308.211807)
			(xy 325.341357 -308.264099) (xy 325.349114 -308.318045) (xy 325.349115 -308.372545) (xy 325.341359 -308.42649)
			(xy 325.326006 -308.478783) (xy 325.303367 -308.528359) (xy 325.273903 -308.574208) (xy 325.238214 -308.615397)
			(xy 325.197027 -308.651089) (xy 325.15118 -308.680555) (xy 325.101606 -308.703198) (xy 325.049314 -308.718554)
			(xy 324.995369 -308.726313) (xy 324.940869 -308.726316) (xy 324.886923 -308.718562) (xy 324.834629 -308.703211)
			(xy 324.785053 -308.680573) (xy 324.739203 -308.651111) (xy 324.698012 -308.615424) (xy 324.662319 -308.574238)
			(xy 324.632851 -308.528392) (xy 324.610207 -308.478818) (xy 324.594849 -308.426527) (xy 324.587088 -308.372582)
			(xy 324.5866 -308.345332) (xy 324.586955 -308.322826) (xy 324.592299 -308.278132) (xy 324.597268 -308.256178)
			(xy 324.600316 -308.24297) (xy 324.593204 -308.217824) (xy 324.51294 -308.13756) (xy 324.487794 -308.130448)
			(xy 324.474586 -308.133496) (xy 324.452633 -308.138464) (xy 324.407938 -308.143807) (xy 324.385432 -308.144164)
			(xy 324.358178 -308.143715) (xy 324.304224 -308.135961) (xy 324.251923 -308.120607) (xy 324.20234 -308.097965)
			(xy 324.156485 -308.068496) (xy 324.115291 -308.032801) (xy 324.079597 -307.991605) (xy 324.050129 -307.945749)
			(xy 324.027489 -307.896165) (xy 324.012136 -307.843864) (xy 324.004384 -307.78991) (xy 324.003924 -307.762656)
			(xy 324.005702 -307.72608) (xy 324.006718 -307.71465) (xy 323.999098 -307.693568) (xy 323.92747 -307.62194)
			(xy 323.906134 -307.61432) (xy 323.894704 -307.615336) (xy 323.858128 -307.617114) (xy 323.830873 -307.616675)
			(xy 323.776916 -307.608921) (xy 323.724612 -307.593567) (xy 323.675026 -307.570926) (xy 323.629167 -307.541458)
			(xy 323.587968 -307.505763) (xy 323.552269 -307.464569) (xy 323.522796 -307.418713) (xy 323.500148 -307.36913)
			(xy 323.484788 -307.316828) (xy 323.477028 -307.262872) (xy 323.477026 -307.208361) (xy 314.940667 -307.208361)
			(xy 314.946784 -307.226684) (xy 314.954679 -307.275261) (xy 314.955174 -307.299868) (xy 314.954679 -307.324475)
			(xy 314.946784 -307.373052) (xy 314.9312 -307.419733) (xy 314.908329 -307.46331) (xy 314.878764 -307.502654)
			(xy 314.843271 -307.536746) (xy 314.802768 -307.564702) (xy 314.758306 -307.5858) (xy 314.711035 -307.599492)
			(xy 314.66218 -307.605424) (xy 314.613005 -307.603443) (xy 314.564786 -307.593599) (xy 314.51877 -307.576147)
			(xy 314.476149 -307.55154) (xy 314.438028 -307.520415) (xy 314.405393 -307.483578) (xy 314.37909 -307.441982)
			(xy 314.359799 -307.396706) (xy 314.348022 -307.348922) (xy 314.344062 -307.299868) (xy 314.005214 -307.299868)
			(xy 314.004719 -307.324475) (xy 313.996824 -307.373052) (xy 313.98124 -307.419733) (xy 313.958369 -307.46331)
			(xy 313.928804 -307.502654) (xy 313.893311 -307.536746) (xy 313.852808 -307.564702) (xy 313.808346 -307.5858)
			(xy 313.761075 -307.599492) (xy 313.71222 -307.605424) (xy 313.663045 -307.603443) (xy 313.614826 -307.593599)
			(xy 313.56881 -307.576147) (xy 313.526189 -307.55154) (xy 313.488068 -307.520415) (xy 313.455433 -307.483578)
			(xy 313.42913 -307.441982) (xy 313.409839 -307.396706) (xy 313.398062 -307.348922) (xy 313.394102 -307.299868)
			(xy 313.055 -307.299868) (xy 313.054505 -307.324475) (xy 313.04661 -307.373052) (xy 313.031026 -307.419733)
			(xy 313.008155 -307.46331) (xy 312.97859 -307.502654) (xy 312.943097 -307.536746) (xy 312.902594 -307.564702)
			(xy 312.858132 -307.5858) (xy 312.810861 -307.599492) (xy 312.762006 -307.605424) (xy 312.712831 -307.603443)
			(xy 312.664612 -307.593599) (xy 312.618596 -307.576147) (xy 312.575975 -307.55154) (xy 312.537854 -307.520415)
			(xy 312.505219 -307.483578) (xy 312.478916 -307.441982) (xy 312.459625 -307.396706) (xy 312.447848 -307.348922)
			(xy 312.443888 -307.299868) (xy 312.10504 -307.299868) (xy 312.104545 -307.324475) (xy 312.09665 -307.373052)
			(xy 312.081066 -307.419733) (xy 312.058195 -307.46331) (xy 312.02863 -307.502654) (xy 311.993137 -307.536746)
			(xy 311.952634 -307.564702) (xy 311.908172 -307.5858) (xy 311.860901 -307.599492) (xy 311.812046 -307.605424)
			(xy 311.762871 -307.603443) (xy 311.714652 -307.593599) (xy 311.668636 -307.576147) (xy 311.626015 -307.55154)
			(xy 311.587894 -307.520415) (xy 311.555259 -307.483578) (xy 311.528956 -307.441982) (xy 311.509665 -307.396706)
			(xy 311.497888 -307.348922) (xy 311.493928 -307.299868) (xy 311.15508 -307.299868) (xy 311.154585 -307.324475)
			(xy 311.14669 -307.373052) (xy 311.131106 -307.419733) (xy 311.108235 -307.46331) (xy 311.07867 -307.502654)
			(xy 311.043177 -307.536746) (xy 311.002674 -307.564702) (xy 310.958212 -307.5858) (xy 310.910941 -307.599492)
			(xy 310.862086 -307.605424) (xy 310.812911 -307.603443) (xy 310.764692 -307.593599) (xy 310.718676 -307.576147)
			(xy 310.676055 -307.55154) (xy 310.637934 -307.520415) (xy 310.605299 -307.483578) (xy 310.578996 -307.441982)
			(xy 310.559705 -307.396706) (xy 310.547928 -307.348922) (xy 310.543968 -307.299868) (xy 310.226964 -307.299868)
			(xy 310.22646 -307.325576) (xy 310.218417 -307.376358) (xy 310.202529 -307.425257) (xy 310.179186 -307.471069)
			(xy 310.148965 -307.512665) (xy 310.112609 -307.549021) (xy 310.071013 -307.579242) (xy 310.025201 -307.602585)
			(xy 309.976302 -307.618473) (xy 309.92552 -307.626516) (xy 309.874104 -307.626516) (xy 309.823322 -307.618473)
			(xy 309.774423 -307.602585) (xy 309.728611 -307.579242) (xy 309.687015 -307.549021) (xy 309.650659 -307.512665)
			(xy 309.620438 -307.471069) (xy 309.597095 -307.425257) (xy 309.581207 -307.376358) (xy 309.573164 -307.325576)
			(xy 309.2765 -307.325576) (xy 309.268457 -307.376358) (xy 309.252569 -307.425257) (xy 309.229226 -307.471069)
			(xy 309.199005 -307.512665) (xy 309.162649 -307.549021) (xy 309.121053 -307.579242) (xy 309.075241 -307.602585)
			(xy 309.026342 -307.618473) (xy 308.97556 -307.626516) (xy 308.924144 -307.626516) (xy 308.873362 -307.618473)
			(xy 308.824463 -307.602585) (xy 308.778651 -307.579242) (xy 308.737055 -307.549021) (xy 308.700699 -307.512665)
			(xy 308.670478 -307.471069) (xy 308.647135 -307.425257) (xy 308.631247 -307.376358) (xy 308.623204 -307.325576)
			(xy 308.304526 -307.325576) (xy 308.29681 -307.373052) (xy 308.281226 -307.419733) (xy 308.258355 -307.46331)
			(xy 308.22879 -307.502654) (xy 308.193297 -307.536746) (xy 308.152794 -307.564702) (xy 308.108332 -307.5858)
			(xy 308.061061 -307.599492) (xy 308.012206 -307.605424) (xy 307.963031 -307.603443) (xy 307.914812 -307.593599)
			(xy 307.868796 -307.576147) (xy 307.826175 -307.55154) (xy 307.788054 -307.520415) (xy 307.755419 -307.483578)
			(xy 307.729116 -307.441982) (xy 307.709825 -307.396706) (xy 307.698048 -307.348922) (xy 307.694088 -307.299868)
			(xy 307.35524 -307.299868) (xy 307.354745 -307.324475) (xy 307.34685 -307.373052) (xy 307.331266 -307.419733)
			(xy 307.308395 -307.46331) (xy 307.27883 -307.502654) (xy 307.243337 -307.536746) (xy 307.202834 -307.564702)
			(xy 307.158372 -307.5858) (xy 307.111101 -307.599492) (xy 307.062246 -307.605424) (xy 307.013071 -307.603443)
			(xy 306.964852 -307.593599) (xy 306.918836 -307.576147) (xy 306.876215 -307.55154) (xy 306.838094 -307.520415)
			(xy 306.805459 -307.483578) (xy 306.779156 -307.441982) (xy 306.759865 -307.396706) (xy 306.748088 -307.348922)
			(xy 306.744128 -307.299868) (xy 306.405026 -307.299868) (xy 306.404531 -307.324475) (xy 306.396636 -307.373052)
			(xy 306.381052 -307.419733) (xy 306.358181 -307.46331) (xy 306.328616 -307.502654) (xy 306.293123 -307.536746)
			(xy 306.25262 -307.564702) (xy 306.208158 -307.5858) (xy 306.160887 -307.599492) (xy 306.112032 -307.605424)
			(xy 306.062857 -307.603443) (xy 306.014638 -307.593599) (xy 305.968622 -307.576147) (xy 305.926001 -307.55154)
			(xy 305.88788 -307.520415) (xy 305.855245 -307.483578) (xy 305.828942 -307.441982) (xy 305.809651 -307.396706)
			(xy 305.797874 -307.348922) (xy 305.793914 -307.299868) (xy 281.616912 -307.299868) (xy 281.616912 -307.399182)
			(xy 281.61755 -307.41174) (xy 281.629401 -307.433881) (xy 281.639518 -307.441346) (xy 281.720544 -307.495448)
			(xy 281.745436 -307.497988) (xy 281.757628 -307.492908) (xy 281.785665 -307.482009) (xy 281.844649 -307.470242)
			(xy 281.874722 -307.46954) (xy 281.899972 -307.470063) (xy 281.949783 -307.478378) (xy 281.997547 -307.494779)
			(xy 282.041959 -307.518816) (xy 282.08181 -307.549836) (xy 282.116011 -307.586992) (xy 282.143631 -307.62927)
			(xy 282.163916 -307.675517) (xy 282.176313 -307.724472) (xy 282.180483 -307.7748) (xy 282.180479 -307.774848)
			(xy 282.519132 -307.774848) (xy 282.523092 -307.725794) (xy 282.534869 -307.67801) (xy 282.55416 -307.632734)
			(xy 282.580463 -307.591138) (xy 282.613098 -307.554301) (xy 282.651219 -307.523176) (xy 282.69384 -307.498569)
			(xy 282.739856 -307.481117) (xy 282.788075 -307.471273) (xy 282.83725 -307.469292) (xy 282.886105 -307.475224)
			(xy 282.933376 -307.488916) (xy 282.977838 -307.510014) (xy 283.018341 -307.53797) (xy 283.053834 -307.572062)
			(xy 283.083399 -307.611406) (xy 283.10627 -307.654983) (xy 283.121854 -307.701664) (xy 283.129749 -307.750241)
			(xy 283.130244 -307.774848) (xy 283.469092 -307.774848) (xy 283.473052 -307.725794) (xy 283.484829 -307.67801)
			(xy 283.50412 -307.632734) (xy 283.530423 -307.591138) (xy 283.563058 -307.554301) (xy 283.601179 -307.523176)
			(xy 283.6438 -307.498569) (xy 283.689816 -307.481117) (xy 283.738035 -307.471273) (xy 283.78721 -307.469292)
			(xy 283.836065 -307.475224) (xy 283.883336 -307.488916) (xy 283.927798 -307.510014) (xy 283.968301 -307.53797)
			(xy 284.003794 -307.572062) (xy 284.033359 -307.611406) (xy 284.05623 -307.654983) (xy 284.071814 -307.701664)
			(xy 284.079709 -307.750241) (xy 284.080204 -307.774848) (xy 284.419052 -307.774848) (xy 284.423012 -307.725794)
			(xy 284.434789 -307.67801) (xy 284.45408 -307.632734) (xy 284.480383 -307.591138) (xy 284.513018 -307.554301)
			(xy 284.551139 -307.523176) (xy 284.59376 -307.498569) (xy 284.639776 -307.481117) (xy 284.687995 -307.471273)
			(xy 284.73717 -307.469292) (xy 284.786025 -307.475224) (xy 284.833296 -307.488916) (xy 284.877758 -307.510014)
			(xy 284.918261 -307.53797) (xy 284.953754 -307.572062) (xy 284.983319 -307.611406) (xy 285.00619 -307.654983)
			(xy 285.021774 -307.701664) (xy 285.029669 -307.750241) (xy 285.030164 -307.774848) (xy 285.369012 -307.774848)
			(xy 285.372972 -307.725794) (xy 285.384749 -307.67801) (xy 285.40404 -307.632734) (xy 285.430343 -307.591138)
			(xy 285.462978 -307.554301) (xy 285.501099 -307.523176) (xy 285.54372 -307.498569) (xy 285.589736 -307.481117)
			(xy 285.637955 -307.471273) (xy 285.68713 -307.469292) (xy 285.735985 -307.475224) (xy 285.783256 -307.488916)
			(xy 285.827718 -307.510014) (xy 285.868221 -307.53797) (xy 285.903714 -307.572062) (xy 285.933279 -307.611406)
			(xy 285.95615 -307.654983) (xy 285.971734 -307.701664) (xy 285.979629 -307.750241) (xy 285.980124 -307.774848)
			(xy 286.318972 -307.774848) (xy 286.322932 -307.725794) (xy 286.334709 -307.67801) (xy 286.354 -307.632734)
			(xy 286.380303 -307.591138) (xy 286.412938 -307.554301) (xy 286.451059 -307.523176) (xy 286.49368 -307.498569)
			(xy 286.539696 -307.481117) (xy 286.587915 -307.471273) (xy 286.63709 -307.469292) (xy 286.685945 -307.475224)
			(xy 286.733216 -307.488916) (xy 286.777678 -307.510014) (xy 286.818181 -307.53797) (xy 286.853674 -307.572062)
			(xy 286.883239 -307.611406) (xy 286.90611 -307.654983) (xy 286.921694 -307.701664) (xy 286.929589 -307.750241)
			(xy 286.930084 -307.774848) (xy 287.268932 -307.774848) (xy 287.272892 -307.725794) (xy 287.284669 -307.67801)
			(xy 287.30396 -307.632734) (xy 287.330263 -307.591138) (xy 287.362898 -307.554301) (xy 287.401019 -307.523176)
			(xy 287.44364 -307.498569) (xy 287.489656 -307.481117) (xy 287.537875 -307.471273) (xy 287.58705 -307.469292)
			(xy 287.635905 -307.475224) (xy 287.683176 -307.488916) (xy 287.727638 -307.510014) (xy 287.768141 -307.53797)
			(xy 287.803634 -307.572062) (xy 287.833199 -307.611406) (xy 287.85607 -307.654983) (xy 287.871654 -307.701664)
			(xy 287.879549 -307.750241) (xy 287.880044 -307.774848) (xy 288.219146 -307.774848) (xy 288.223106 -307.725794)
			(xy 288.234883 -307.67801) (xy 288.254174 -307.632734) (xy 288.280477 -307.591138) (xy 288.313112 -307.554301)
			(xy 288.351233 -307.523176) (xy 288.393854 -307.498569) (xy 288.43987 -307.481117) (xy 288.488089 -307.471273)
			(xy 288.537264 -307.469292) (xy 288.586119 -307.475224) (xy 288.63339 -307.488916) (xy 288.677852 -307.510014)
			(xy 288.718355 -307.53797) (xy 288.753848 -307.572062) (xy 288.783413 -307.611406) (xy 288.806284 -307.654983)
			(xy 288.821868 -307.701664) (xy 288.829763 -307.750241) (xy 288.830258 -307.774848) (xy 289.169106 -307.774848)
			(xy 289.173066 -307.725794) (xy 289.184843 -307.67801) (xy 289.204134 -307.632734) (xy 289.230437 -307.591138)
			(xy 289.263072 -307.554301) (xy 289.301193 -307.523176) (xy 289.343814 -307.498569) (xy 289.38983 -307.481117)
			(xy 289.438049 -307.471273) (xy 289.487224 -307.469292) (xy 289.536079 -307.475224) (xy 289.58335 -307.488916)
			(xy 289.627812 -307.510014) (xy 289.668315 -307.53797) (xy 289.703808 -307.572062) (xy 289.733373 -307.611406)
			(xy 289.756244 -307.654983) (xy 289.771828 -307.701664) (xy 289.779723 -307.750241) (xy 289.780218 -307.774848)
			(xy 290.119066 -307.774848) (xy 290.123026 -307.725794) (xy 290.134803 -307.67801) (xy 290.154094 -307.632734)
			(xy 290.180397 -307.591138) (xy 290.213032 -307.554301) (xy 290.251153 -307.523176) (xy 290.293774 -307.498569)
			(xy 290.33979 -307.481117) (xy 290.388009 -307.471273) (xy 290.437184 -307.469292) (xy 290.486039 -307.475224)
			(xy 290.53331 -307.488916) (xy 290.577772 -307.510014) (xy 290.618275 -307.53797) (xy 290.653768 -307.572062)
			(xy 290.683333 -307.611406) (xy 290.706204 -307.654983) (xy 290.721788 -307.701664) (xy 290.729683 -307.750241)
			(xy 290.730178 -307.774848) (xy 292.018986 -307.774848) (xy 292.022946 -307.725794) (xy 292.034723 -307.67801)
			(xy 292.054014 -307.632734) (xy 292.080317 -307.591138) (xy 292.112952 -307.554301) (xy 292.151073 -307.523176)
			(xy 292.193694 -307.498569) (xy 292.23971 -307.481117) (xy 292.287929 -307.471273) (xy 292.337104 -307.469292)
			(xy 292.385959 -307.475224) (xy 292.43323 -307.488916) (xy 292.477692 -307.510014) (xy 292.518195 -307.53797)
			(xy 292.553688 -307.572062) (xy 292.583253 -307.611406) (xy 292.606124 -307.654983) (xy 292.621708 -307.701664)
			(xy 292.629603 -307.750241) (xy 292.630098 -307.774848) (xy 292.968946 -307.774848) (xy 292.972906 -307.725794)
			(xy 292.984683 -307.67801) (xy 293.003974 -307.632734) (xy 293.030277 -307.591138) (xy 293.062912 -307.554301)
			(xy 293.101033 -307.523176) (xy 293.143654 -307.498569) (xy 293.18967 -307.481117) (xy 293.237889 -307.471273)
			(xy 293.287064 -307.469292) (xy 293.335919 -307.475224) (xy 293.38319 -307.488916) (xy 293.427652 -307.510014)
			(xy 293.468155 -307.53797) (xy 293.503648 -307.572062) (xy 293.533213 -307.611406) (xy 293.556084 -307.654983)
			(xy 293.571668 -307.701664) (xy 293.579563 -307.750241) (xy 293.580058 -307.774848) (xy 293.918906 -307.774848)
			(xy 293.922866 -307.725794) (xy 293.934643 -307.67801) (xy 293.953934 -307.632734) (xy 293.980237 -307.591138)
			(xy 294.012872 -307.554301) (xy 294.050993 -307.523176) (xy 294.093614 -307.498569) (xy 294.13963 -307.481117)
			(xy 294.187849 -307.471273) (xy 294.237024 -307.469292) (xy 294.285879 -307.475224) (xy 294.33315 -307.488916)
			(xy 294.377612 -307.510014) (xy 294.418115 -307.53797) (xy 294.453608 -307.572062) (xy 294.483173 -307.611406)
			(xy 294.506044 -307.654983) (xy 294.521628 -307.701664) (xy 294.529523 -307.750241) (xy 294.530013 -307.774594)
			(xy 294.868866 -307.774594) (xy 294.872826 -307.72554) (xy 294.884603 -307.677756) (xy 294.903894 -307.63248)
			(xy 294.930197 -307.590884) (xy 294.962832 -307.554047) (xy 295.000953 -307.522922) (xy 295.043574 -307.498315)
			(xy 295.08959 -307.480863) (xy 295.137809 -307.471019) (xy 295.186984 -307.469038) (xy 295.235839 -307.47497)
			(xy 295.28311 -307.488662) (xy 295.327572 -307.50976) (xy 295.368075 -307.537716) (xy 295.403568 -307.571808)
			(xy 295.433133 -307.611152) (xy 295.456004 -307.654729) (xy 295.471588 -307.70141) (xy 295.479483 -307.749987)
			(xy 295.479978 -307.774594) (xy 295.81908 -307.774594) (xy 295.82304 -307.72554) (xy 295.834817 -307.677756)
			(xy 295.854108 -307.63248) (xy 295.880411 -307.590884) (xy 295.913046 -307.554047) (xy 295.951167 -307.522922)
			(xy 295.993788 -307.498315) (xy 296.039804 -307.480863) (xy 296.088023 -307.471019) (xy 296.137198 -307.469038)
			(xy 296.186053 -307.47497) (xy 296.233324 -307.488662) (xy 296.277786 -307.50976) (xy 296.318289 -307.537716)
			(xy 296.353782 -307.571808) (xy 296.383347 -307.611152) (xy 296.406218 -307.654729) (xy 296.421802 -307.70141)
			(xy 296.429697 -307.749987) (xy 296.430192 -307.774594) (xy 296.430187 -307.774848) (xy 296.76904 -307.774848)
			(xy 296.773 -307.725794) (xy 296.784777 -307.67801) (xy 296.804068 -307.632734) (xy 296.830371 -307.591138)
			(xy 296.863006 -307.554301) (xy 296.901127 -307.523176) (xy 296.943748 -307.498569) (xy 296.989764 -307.481117)
			(xy 297.037983 -307.471273) (xy 297.087158 -307.469292) (xy 297.136013 -307.475224) (xy 297.183284 -307.488916)
			(xy 297.227746 -307.510014) (xy 297.268249 -307.53797) (xy 297.303742 -307.572062) (xy 297.333307 -307.611406)
			(xy 297.356178 -307.654983) (xy 297.371762 -307.701664) (xy 297.379657 -307.750241) (xy 297.380152 -307.774848)
			(xy 297.719 -307.774848) (xy 297.72296 -307.725794) (xy 297.734737 -307.67801) (xy 297.754028 -307.632734)
			(xy 297.780331 -307.591138) (xy 297.812966 -307.554301) (xy 297.851087 -307.523176) (xy 297.893708 -307.498569)
			(xy 297.939724 -307.481117) (xy 297.987943 -307.471273) (xy 298.037118 -307.469292) (xy 298.085973 -307.475224)
			(xy 298.133244 -307.488916) (xy 298.177706 -307.510014) (xy 298.218209 -307.53797) (xy 298.253702 -307.572062)
			(xy 298.283267 -307.611406) (xy 298.306138 -307.654983) (xy 298.321722 -307.701664) (xy 298.329617 -307.750241)
			(xy 298.330112 -307.774848) (xy 298.66896 -307.774848) (xy 298.67292 -307.725794) (xy 298.684697 -307.67801)
			(xy 298.703988 -307.632734) (xy 298.730291 -307.591138) (xy 298.762926 -307.554301) (xy 298.801047 -307.523176)
			(xy 298.843668 -307.498569) (xy 298.889684 -307.481117) (xy 298.937903 -307.471273) (xy 298.987078 -307.469292)
			(xy 299.035933 -307.475224) (xy 299.083204 -307.488916) (xy 299.127666 -307.510014) (xy 299.168169 -307.53797)
			(xy 299.203662 -307.572062) (xy 299.233227 -307.611406) (xy 299.256098 -307.654983) (xy 299.271682 -307.701664)
			(xy 299.279577 -307.750241) (xy 299.280072 -307.774848) (xy 299.61892 -307.774848) (xy 299.62288 -307.725794)
			(xy 299.634657 -307.67801) (xy 299.653948 -307.632734) (xy 299.680251 -307.591138) (xy 299.712886 -307.554301)
			(xy 299.751007 -307.523176) (xy 299.793628 -307.498569) (xy 299.839644 -307.481117) (xy 299.887863 -307.471273)
			(xy 299.937038 -307.469292) (xy 299.985893 -307.475224) (xy 300.033164 -307.488916) (xy 300.077626 -307.510014)
			(xy 300.118129 -307.53797) (xy 300.153622 -307.572062) (xy 300.183187 -307.611406) (xy 300.206058 -307.654983)
			(xy 300.221642 -307.701664) (xy 300.229537 -307.750241) (xy 300.230032 -307.774848) (xy 300.56888 -307.774848)
			(xy 300.57284 -307.725794) (xy 300.584617 -307.67801) (xy 300.603908 -307.632734) (xy 300.630211 -307.591138)
			(xy 300.662846 -307.554301) (xy 300.700967 -307.523176) (xy 300.743588 -307.498569) (xy 300.789604 -307.481117)
			(xy 300.837823 -307.471273) (xy 300.886998 -307.469292) (xy 300.935853 -307.475224) (xy 300.983124 -307.488916)
			(xy 301.027586 -307.510014) (xy 301.068089 -307.53797) (xy 301.103582 -307.572062) (xy 301.133147 -307.611406)
			(xy 301.156018 -307.654983) (xy 301.171602 -307.701664) (xy 301.179497 -307.750241) (xy 301.179992 -307.774848)
			(xy 301.519094 -307.774848) (xy 301.523054 -307.725794) (xy 301.534831 -307.67801) (xy 301.554122 -307.632734)
			(xy 301.580425 -307.591138) (xy 301.61306 -307.554301) (xy 301.651181 -307.523176) (xy 301.693802 -307.498569)
			(xy 301.739818 -307.481117) (xy 301.788037 -307.471273) (xy 301.837212 -307.469292) (xy 301.886067 -307.475224)
			(xy 301.933338 -307.488916) (xy 301.9778 -307.510014) (xy 302.018303 -307.53797) (xy 302.053796 -307.572062)
			(xy 302.083361 -307.611406) (xy 302.106232 -307.654983) (xy 302.121816 -307.701664) (xy 302.129711 -307.750241)
			(xy 302.130206 -307.774848) (xy 302.469054 -307.774848) (xy 302.473014 -307.725794) (xy 302.484791 -307.67801)
			(xy 302.504082 -307.632734) (xy 302.530385 -307.591138) (xy 302.56302 -307.554301) (xy 302.601141 -307.523176)
			(xy 302.643762 -307.498569) (xy 302.689778 -307.481117) (xy 302.737997 -307.471273) (xy 302.787172 -307.469292)
			(xy 302.836027 -307.475224) (xy 302.883298 -307.488916) (xy 302.92776 -307.510014) (xy 302.968263 -307.53797)
			(xy 303.003756 -307.572062) (xy 303.033321 -307.611406) (xy 303.056192 -307.654983) (xy 303.071776 -307.701664)
			(xy 303.079671 -307.750241) (xy 303.080166 -307.774848) (xy 303.419014 -307.774848) (xy 303.422974 -307.725794)
			(xy 303.434751 -307.67801) (xy 303.454042 -307.632734) (xy 303.480345 -307.591138) (xy 303.51298 -307.554301)
			(xy 303.551101 -307.523176) (xy 303.593722 -307.498569) (xy 303.639738 -307.481117) (xy 303.687957 -307.471273)
			(xy 303.737132 -307.469292) (xy 303.785987 -307.475224) (xy 303.833258 -307.488916) (xy 303.87772 -307.510014)
			(xy 303.918223 -307.53797) (xy 303.953716 -307.572062) (xy 303.983281 -307.611406) (xy 304.006152 -307.654983)
			(xy 304.021736 -307.701664) (xy 304.029631 -307.750241) (xy 304.030126 -307.774848) (xy 304.368974 -307.774848)
			(xy 304.372934 -307.725794) (xy 304.384711 -307.67801) (xy 304.404002 -307.632734) (xy 304.430305 -307.591138)
			(xy 304.46294 -307.554301) (xy 304.501061 -307.523176) (xy 304.543682 -307.498569) (xy 304.589698 -307.481117)
			(xy 304.637917 -307.471273) (xy 304.687092 -307.469292) (xy 304.735947 -307.475224) (xy 304.783218 -307.488916)
			(xy 304.82768 -307.510014) (xy 304.868183 -307.53797) (xy 304.903676 -307.572062) (xy 304.933241 -307.611406)
			(xy 304.956112 -307.654983) (xy 304.971696 -307.701664) (xy 304.979591 -307.750241) (xy 304.980086 -307.774848)
			(xy 304.979591 -307.799455) (xy 304.971696 -307.848032) (xy 304.956112 -307.894713) (xy 304.933241 -307.93829)
			(xy 304.903676 -307.977634) (xy 304.868183 -308.011726) (xy 304.82768 -308.039682) (xy 304.783218 -308.06078)
			(xy 304.735947 -308.074472) (xy 304.687092 -308.080404) (xy 304.637917 -308.078423) (xy 304.589698 -308.068579)
			(xy 304.543682 -308.051127) (xy 304.501061 -308.02652) (xy 304.46294 -307.995395) (xy 304.430305 -307.958558)
			(xy 304.404002 -307.916962) (xy 304.384711 -307.871686) (xy 304.372934 -307.823902) (xy 304.368974 -307.774848)
			(xy 304.030126 -307.774848) (xy 304.029631 -307.799455) (xy 304.021736 -307.848032) (xy 304.006152 -307.894713)
			(xy 303.983281 -307.93829) (xy 303.953716 -307.977634) (xy 303.918223 -308.011726) (xy 303.87772 -308.039682)
			(xy 303.833258 -308.06078) (xy 303.785987 -308.074472) (xy 303.737132 -308.080404) (xy 303.687957 -308.078423)
			(xy 303.639738 -308.068579) (xy 303.593722 -308.051127) (xy 303.551101 -308.02652) (xy 303.51298 -307.995395)
			(xy 303.480345 -307.958558) (xy 303.454042 -307.916962) (xy 303.434751 -307.871686) (xy 303.422974 -307.823902)
			(xy 303.419014 -307.774848) (xy 303.080166 -307.774848) (xy 303.079671 -307.799455) (xy 303.071776 -307.848032)
			(xy 303.056192 -307.894713) (xy 303.033321 -307.93829) (xy 303.003756 -307.977634) (xy 302.968263 -308.011726)
			(xy 302.92776 -308.039682) (xy 302.883298 -308.06078) (xy 302.836027 -308.074472) (xy 302.787172 -308.080404)
			(xy 302.737997 -308.078423) (xy 302.689778 -308.068579) (xy 302.643762 -308.051127) (xy 302.601141 -308.02652)
			(xy 302.56302 -307.995395) (xy 302.530385 -307.958558) (xy 302.504082 -307.916962) (xy 302.484791 -307.871686)
			(xy 302.473014 -307.823902) (xy 302.469054 -307.774848) (xy 302.130206 -307.774848) (xy 302.129711 -307.799455)
			(xy 302.121816 -307.848032) (xy 302.106232 -307.894713) (xy 302.083361 -307.93829) (xy 302.053796 -307.977634)
			(xy 302.018303 -308.011726) (xy 301.9778 -308.039682) (xy 301.933338 -308.06078) (xy 301.886067 -308.074472)
			(xy 301.837212 -308.080404) (xy 301.788037 -308.078423) (xy 301.739818 -308.068579) (xy 301.693802 -308.051127)
			(xy 301.651181 -308.02652) (xy 301.61306 -307.995395) (xy 301.580425 -307.958558) (xy 301.554122 -307.916962)
			(xy 301.534831 -307.871686) (xy 301.523054 -307.823902) (xy 301.519094 -307.774848) (xy 301.179992 -307.774848)
			(xy 301.179497 -307.799455) (xy 301.171602 -307.848032) (xy 301.156018 -307.894713) (xy 301.133147 -307.93829)
			(xy 301.103582 -307.977634) (xy 301.068089 -308.011726) (xy 301.027586 -308.039682) (xy 300.983124 -308.06078)
			(xy 300.935853 -308.074472) (xy 300.886998 -308.080404) (xy 300.837823 -308.078423) (xy 300.789604 -308.068579)
			(xy 300.743588 -308.051127) (xy 300.700967 -308.02652) (xy 300.662846 -307.995395) (xy 300.630211 -307.958558)
			(xy 300.603908 -307.916962) (xy 300.584617 -307.871686) (xy 300.57284 -307.823902) (xy 300.56888 -307.774848)
			(xy 300.230032 -307.774848) (xy 300.229537 -307.799455) (xy 300.221642 -307.848032) (xy 300.206058 -307.894713)
			(xy 300.183187 -307.93829) (xy 300.153622 -307.977634) (xy 300.118129 -308.011726) (xy 300.077626 -308.039682)
			(xy 300.033164 -308.06078) (xy 299.985893 -308.074472) (xy 299.937038 -308.080404) (xy 299.887863 -308.078423)
			(xy 299.839644 -308.068579) (xy 299.793628 -308.051127) (xy 299.751007 -308.02652) (xy 299.712886 -307.995395)
			(xy 299.680251 -307.958558) (xy 299.653948 -307.916962) (xy 299.634657 -307.871686) (xy 299.62288 -307.823902)
			(xy 299.61892 -307.774848) (xy 299.280072 -307.774848) (xy 299.279577 -307.799455) (xy 299.271682 -307.848032)
			(xy 299.256098 -307.894713) (xy 299.233227 -307.93829) (xy 299.203662 -307.977634) (xy 299.168169 -308.011726)
			(xy 299.127666 -308.039682) (xy 299.083204 -308.06078) (xy 299.035933 -308.074472) (xy 298.987078 -308.080404)
			(xy 298.937903 -308.078423) (xy 298.889684 -308.068579) (xy 298.843668 -308.051127) (xy 298.801047 -308.02652)
			(xy 298.762926 -307.995395) (xy 298.730291 -307.958558) (xy 298.703988 -307.916962) (xy 298.684697 -307.871686)
			(xy 298.67292 -307.823902) (xy 298.66896 -307.774848) (xy 298.330112 -307.774848) (xy 298.329617 -307.799455)
			(xy 298.321722 -307.848032) (xy 298.306138 -307.894713) (xy 298.283267 -307.93829) (xy 298.253702 -307.977634)
			(xy 298.218209 -308.011726) (xy 298.177706 -308.039682) (xy 298.133244 -308.06078) (xy 298.085973 -308.074472)
			(xy 298.037118 -308.080404) (xy 297.987943 -308.078423) (xy 297.939724 -308.068579) (xy 297.893708 -308.051127)
			(xy 297.851087 -308.02652) (xy 297.812966 -307.995395) (xy 297.780331 -307.958558) (xy 297.754028 -307.916962)
			(xy 297.734737 -307.871686) (xy 297.72296 -307.823902) (xy 297.719 -307.774848) (xy 297.380152 -307.774848)
			(xy 297.379657 -307.799455) (xy 297.371762 -307.848032) (xy 297.356178 -307.894713) (xy 297.333307 -307.93829)
			(xy 297.303742 -307.977634) (xy 297.268249 -308.011726) (xy 297.227746 -308.039682) (xy 297.183284 -308.06078)
			(xy 297.136013 -308.074472) (xy 297.087158 -308.080404) (xy 297.037983 -308.078423) (xy 296.989764 -308.068579)
			(xy 296.943748 -308.051127) (xy 296.901127 -308.02652) (xy 296.863006 -307.995395) (xy 296.830371 -307.958558)
			(xy 296.804068 -307.916962) (xy 296.784777 -307.871686) (xy 296.773 -307.823902) (xy 296.76904 -307.774848)
			(xy 296.430187 -307.774848) (xy 296.429697 -307.799201) (xy 296.421802 -307.847778) (xy 296.406218 -307.894459)
			(xy 296.383347 -307.938036) (xy 296.353782 -307.97738) (xy 296.318289 -308.011472) (xy 296.277786 -308.039428)
			(xy 296.233324 -308.060526) (xy 296.186053 -308.074218) (xy 296.137198 -308.08015) (xy 296.088023 -308.078169)
			(xy 296.039804 -308.068325) (xy 295.993788 -308.050873) (xy 295.951167 -308.026266) (xy 295.913046 -307.995141)
			(xy 295.880411 -307.958304) (xy 295.854108 -307.916708) (xy 295.834817 -307.871432) (xy 295.82304 -307.823648)
			(xy 295.81908 -307.774594) (xy 295.479978 -307.774594) (xy 295.479483 -307.799201) (xy 295.471588 -307.847778)
			(xy 295.456004 -307.894459) (xy 295.433133 -307.938036) (xy 295.403568 -307.97738) (xy 295.368075 -308.011472)
			(xy 295.327572 -308.039428) (xy 295.28311 -308.060526) (xy 295.235839 -308.074218) (xy 295.186984 -308.08015)
			(xy 295.137809 -308.078169) (xy 295.08959 -308.068325) (xy 295.043574 -308.050873) (xy 295.000953 -308.026266)
			(xy 294.962832 -307.995141) (xy 294.930197 -307.958304) (xy 294.903894 -307.916708) (xy 294.884603 -307.871432)
			(xy 294.872826 -307.823648) (xy 294.868866 -307.774594) (xy 294.530013 -307.774594) (xy 294.530018 -307.774848)
			(xy 294.529523 -307.799455) (xy 294.521628 -307.848032) (xy 294.506044 -307.894713) (xy 294.483173 -307.93829)
			(xy 294.453608 -307.977634) (xy 294.418115 -308.011726) (xy 294.377612 -308.039682) (xy 294.33315 -308.06078)
			(xy 294.285879 -308.074472) (xy 294.237024 -308.080404) (xy 294.187849 -308.078423) (xy 294.13963 -308.068579)
			(xy 294.093614 -308.051127) (xy 294.050993 -308.02652) (xy 294.012872 -307.995395) (xy 293.980237 -307.958558)
			(xy 293.953934 -307.916962) (xy 293.934643 -307.871686) (xy 293.922866 -307.823902) (xy 293.918906 -307.774848)
			(xy 293.580058 -307.774848) (xy 293.579563 -307.799455) (xy 293.571668 -307.848032) (xy 293.556084 -307.894713)
			(xy 293.533213 -307.93829) (xy 293.503648 -307.977634) (xy 293.468155 -308.011726) (xy 293.427652 -308.039682)
			(xy 293.38319 -308.06078) (xy 293.335919 -308.074472) (xy 293.287064 -308.080404) (xy 293.237889 -308.078423)
			(xy 293.18967 -308.068579) (xy 293.143654 -308.051127) (xy 293.101033 -308.02652) (xy 293.062912 -307.995395)
			(xy 293.030277 -307.958558) (xy 293.003974 -307.916962) (xy 292.984683 -307.871686) (xy 292.972906 -307.823902)
			(xy 292.968946 -307.774848) (xy 292.630098 -307.774848) (xy 292.629603 -307.799455) (xy 292.621708 -307.848032)
			(xy 292.606124 -307.894713) (xy 292.583253 -307.93829) (xy 292.553688 -307.977634) (xy 292.518195 -308.011726)
			(xy 292.477692 -308.039682) (xy 292.43323 -308.06078) (xy 292.385959 -308.074472) (xy 292.337104 -308.080404)
			(xy 292.287929 -308.078423) (xy 292.23971 -308.068579) (xy 292.193694 -308.051127) (xy 292.151073 -308.02652)
			(xy 292.112952 -307.995395) (xy 292.080317 -307.958558) (xy 292.054014 -307.916962) (xy 292.034723 -307.871686)
			(xy 292.022946 -307.823902) (xy 292.018986 -307.774848) (xy 290.730178 -307.774848) (xy 290.729683 -307.799455)
			(xy 290.721788 -307.848032) (xy 290.706204 -307.894713) (xy 290.683333 -307.93829) (xy 290.653768 -307.977634)
			(xy 290.618275 -308.011726) (xy 290.577772 -308.039682) (xy 290.53331 -308.06078) (xy 290.486039 -308.074472)
			(xy 290.437184 -308.080404) (xy 290.388009 -308.078423) (xy 290.33979 -308.068579) (xy 290.293774 -308.051127)
			(xy 290.251153 -308.02652) (xy 290.213032 -307.995395) (xy 290.180397 -307.958558) (xy 290.154094 -307.916962)
			(xy 290.134803 -307.871686) (xy 290.123026 -307.823902) (xy 290.119066 -307.774848) (xy 289.780218 -307.774848)
			(xy 289.779723 -307.799455) (xy 289.771828 -307.848032) (xy 289.756244 -307.894713) (xy 289.733373 -307.93829)
			(xy 289.703808 -307.977634) (xy 289.668315 -308.011726) (xy 289.627812 -308.039682) (xy 289.58335 -308.06078)
			(xy 289.536079 -308.074472) (xy 289.487224 -308.080404) (xy 289.438049 -308.078423) (xy 289.38983 -308.068579)
			(xy 289.343814 -308.051127) (xy 289.301193 -308.02652) (xy 289.263072 -307.995395) (xy 289.230437 -307.958558)
			(xy 289.204134 -307.916962) (xy 289.184843 -307.871686) (xy 289.173066 -307.823902) (xy 289.169106 -307.774848)
			(xy 288.830258 -307.774848) (xy 288.829763 -307.799455) (xy 288.821868 -307.848032) (xy 288.806284 -307.894713)
			(xy 288.783413 -307.93829) (xy 288.753848 -307.977634) (xy 288.718355 -308.011726) (xy 288.677852 -308.039682)
			(xy 288.63339 -308.06078) (xy 288.586119 -308.074472) (xy 288.537264 -308.080404) (xy 288.488089 -308.078423)
			(xy 288.43987 -308.068579) (xy 288.393854 -308.051127) (xy 288.351233 -308.02652) (xy 288.313112 -307.995395)
			(xy 288.280477 -307.958558) (xy 288.254174 -307.916962) (xy 288.234883 -307.871686) (xy 288.223106 -307.823902)
			(xy 288.219146 -307.774848) (xy 287.880044 -307.774848) (xy 287.879549 -307.799455) (xy 287.871654 -307.848032)
			(xy 287.85607 -307.894713) (xy 287.833199 -307.93829) (xy 287.803634 -307.977634) (xy 287.768141 -308.011726)
			(xy 287.727638 -308.039682) (xy 287.683176 -308.06078) (xy 287.635905 -308.074472) (xy 287.58705 -308.080404)
			(xy 287.537875 -308.078423) (xy 287.489656 -308.068579) (xy 287.44364 -308.051127) (xy 287.401019 -308.02652)
			(xy 287.362898 -307.995395) (xy 287.330263 -307.958558) (xy 287.30396 -307.916962) (xy 287.284669 -307.871686)
			(xy 287.272892 -307.823902) (xy 287.268932 -307.774848) (xy 286.930084 -307.774848) (xy 286.929589 -307.799455)
			(xy 286.921694 -307.848032) (xy 286.90611 -307.894713) (xy 286.883239 -307.93829) (xy 286.853674 -307.977634)
			(xy 286.818181 -308.011726) (xy 286.777678 -308.039682) (xy 286.733216 -308.06078) (xy 286.685945 -308.074472)
			(xy 286.63709 -308.080404) (xy 286.587915 -308.078423) (xy 286.539696 -308.068579) (xy 286.49368 -308.051127)
			(xy 286.451059 -308.02652) (xy 286.412938 -307.995395) (xy 286.380303 -307.958558) (xy 286.354 -307.916962)
			(xy 286.334709 -307.871686) (xy 286.322932 -307.823902) (xy 286.318972 -307.774848) (xy 285.980124 -307.774848)
			(xy 285.979629 -307.799455) (xy 285.971734 -307.848032) (xy 285.95615 -307.894713) (xy 285.933279 -307.93829)
			(xy 285.903714 -307.977634) (xy 285.868221 -308.011726) (xy 285.827718 -308.039682) (xy 285.783256 -308.06078)
			(xy 285.735985 -308.074472) (xy 285.68713 -308.080404) (xy 285.637955 -308.078423) (xy 285.589736 -308.068579)
			(xy 285.54372 -308.051127) (xy 285.501099 -308.02652) (xy 285.462978 -307.995395) (xy 285.430343 -307.958558)
			(xy 285.40404 -307.916962) (xy 285.384749 -307.871686) (xy 285.372972 -307.823902) (xy 285.369012 -307.774848)
			(xy 285.030164 -307.774848) (xy 285.029669 -307.799455) (xy 285.021774 -307.848032) (xy 285.00619 -307.894713)
			(xy 284.983319 -307.93829) (xy 284.953754 -307.977634) (xy 284.918261 -308.011726) (xy 284.877758 -308.039682)
			(xy 284.833296 -308.06078) (xy 284.786025 -308.074472) (xy 284.73717 -308.080404) (xy 284.687995 -308.078423)
			(xy 284.639776 -308.068579) (xy 284.59376 -308.051127) (xy 284.551139 -308.02652) (xy 284.513018 -307.995395)
			(xy 284.480383 -307.958558) (xy 284.45408 -307.916962) (xy 284.434789 -307.871686) (xy 284.423012 -307.823902)
			(xy 284.419052 -307.774848) (xy 284.080204 -307.774848) (xy 284.079709 -307.799455) (xy 284.071814 -307.848032)
			(xy 284.05623 -307.894713) (xy 284.033359 -307.93829) (xy 284.003794 -307.977634) (xy 283.968301 -308.011726)
			(xy 283.927798 -308.039682) (xy 283.883336 -308.06078) (xy 283.836065 -308.074472) (xy 283.78721 -308.080404)
			(xy 283.738035 -308.078423) (xy 283.689816 -308.068579) (xy 283.6438 -308.051127) (xy 283.601179 -308.02652)
			(xy 283.563058 -307.995395) (xy 283.530423 -307.958558) (xy 283.50412 -307.916962) (xy 283.484829 -307.871686)
			(xy 283.473052 -307.823902) (xy 283.469092 -307.774848) (xy 283.130244 -307.774848) (xy 283.129749 -307.799455)
			(xy 283.121854 -307.848032) (xy 283.10627 -307.894713) (xy 283.083399 -307.93829) (xy 283.053834 -307.977634)
			(xy 283.018341 -308.011726) (xy 282.977838 -308.039682) (xy 282.933376 -308.06078) (xy 282.886105 -308.074472)
			(xy 282.83725 -308.080404) (xy 282.788075 -308.078423) (xy 282.739856 -308.068579) (xy 282.69384 -308.051127)
			(xy 282.651219 -308.02652) (xy 282.613098 -307.995395) (xy 282.580463 -307.958558) (xy 282.55416 -307.916962)
			(xy 282.534869 -307.871686) (xy 282.523092 -307.823902) (xy 282.519132 -307.774848) (xy 282.180479 -307.774848)
			(xy 282.176313 -307.825128) (xy 282.163916 -307.874083) (xy 282.143631 -307.920331) (xy 282.116011 -307.962608)
			(xy 282.08181 -307.999764) (xy 282.041959 -308.030784) (xy 281.997546 -308.054821) (xy 281.949783 -308.071222)
			(xy 281.899972 -308.079537) (xy 281.874722 -308.080156) (xy 281.844648 -308.079462) (xy 281.785663 -308.067695)
			(xy 281.757628 -308.056788) (xy 281.745436 -308.051708) (xy 281.720544 -308.054248) (xy 281.639518 -308.10835)
			(xy 281.629471 -308.115873) (xy 281.617645 -308.137981) (xy 281.616912 -308.150514) (xy 281.616912 -308.249828)
			(xy 305.793914 -308.249828) (xy 305.797874 -308.200774) (xy 305.809651 -308.15299) (xy 305.828942 -308.107714)
			(xy 305.855245 -308.066118) (xy 305.88788 -308.029281) (xy 305.926001 -307.998156) (xy 305.968622 -307.973549)
			(xy 306.014638 -307.956097) (xy 306.062857 -307.946253) (xy 306.112032 -307.944272) (xy 306.160887 -307.950204)
			(xy 306.208158 -307.963896) (xy 306.25262 -307.984994) (xy 306.293123 -308.01295) (xy 306.328616 -308.047042)
			(xy 306.358181 -308.086386) (xy 306.381052 -308.129963) (xy 306.396636 -308.176644) (xy 306.404531 -308.225221)
			(xy 306.405026 -308.249828) (xy 306.404531 -308.274435) (xy 306.404352 -308.275536) (xy 306.723284 -308.275536)
			(xy 306.723284 -308.22412) (xy 306.731327 -308.173338) (xy 306.747215 -308.124439) (xy 306.770558 -308.078627)
			(xy 306.800779 -308.037031) (xy 306.837135 -308.000675) (xy 306.878731 -307.970454) (xy 306.924543 -307.947111)
			(xy 306.973442 -307.931223) (xy 307.024224 -307.92318) (xy 307.07564 -307.92318) (xy 307.126422 -307.931223)
			(xy 307.175321 -307.947111) (xy 307.221133 -307.970454) (xy 307.262729 -308.000675) (xy 307.299085 -308.037031)
			(xy 307.329306 -308.078627) (xy 307.352649 -308.124439) (xy 307.368537 -308.173338) (xy 307.37658 -308.22412)
			(xy 307.377084 -308.249828) (xy 307.37658 -308.275536) (xy 307.673244 -308.275536) (xy 307.673244 -308.22412)
			(xy 307.681287 -308.173338) (xy 307.697175 -308.124439) (xy 307.720518 -308.078627) (xy 307.750739 -308.037031)
			(xy 307.787095 -308.000675) (xy 307.828691 -307.970454) (xy 307.874503 -307.947111) (xy 307.923402 -307.931223)
			(xy 307.974184 -307.92318) (xy 308.0256 -307.92318) (xy 308.076382 -307.931223) (xy 308.125281 -307.947111)
			(xy 308.171093 -307.970454) (xy 308.212689 -308.000675) (xy 308.249045 -308.037031) (xy 308.279266 -308.078627)
			(xy 308.302609 -308.124439) (xy 308.318497 -308.173338) (xy 308.32654 -308.22412) (xy 308.327044 -308.249828)
			(xy 308.644048 -308.249828) (xy 308.648008 -308.200774) (xy 308.659785 -308.15299) (xy 308.679076 -308.107714)
			(xy 308.705379 -308.066118) (xy 308.738014 -308.029281) (xy 308.776135 -307.998156) (xy 308.818756 -307.973549)
			(xy 308.864772 -307.956097) (xy 308.912991 -307.946253) (xy 308.962166 -307.944272) (xy 309.011021 -307.950204)
			(xy 309.058292 -307.963896) (xy 309.102754 -307.984994) (xy 309.143257 -308.01295) (xy 309.17875 -308.047042)
			(xy 309.208315 -308.086386) (xy 309.231186 -308.129963) (xy 309.24677 -308.176644) (xy 309.254665 -308.225221)
			(xy 309.25516 -308.249828) (xy 309.594008 -308.249828) (xy 309.597968 -308.200774) (xy 309.609745 -308.15299)
			(xy 309.629036 -308.107714) (xy 309.655339 -308.066118) (xy 309.687974 -308.029281) (xy 309.726095 -307.998156)
			(xy 309.768716 -307.973549) (xy 309.814732 -307.956097) (xy 309.862951 -307.946253) (xy 309.912126 -307.944272)
			(xy 309.960981 -307.950204) (xy 310.008252 -307.963896) (xy 310.052714 -307.984994) (xy 310.093217 -308.01295)
			(xy 310.12871 -308.047042) (xy 310.158275 -308.086386) (xy 310.181146 -308.129963) (xy 310.19673 -308.176644)
			(xy 310.204625 -308.225221) (xy 310.20512 -308.249828) (xy 310.543968 -308.249828) (xy 310.547928 -308.200774)
			(xy 310.559705 -308.15299) (xy 310.578996 -308.107714) (xy 310.605299 -308.066118) (xy 310.637934 -308.029281)
			(xy 310.676055 -307.998156) (xy 310.718676 -307.973549) (xy 310.764692 -307.956097) (xy 310.812911 -307.946253)
			(xy 310.862086 -307.944272) (xy 310.910941 -307.950204) (xy 310.958212 -307.963896) (xy 311.002674 -307.984994)
			(xy 311.043177 -308.01295) (xy 311.07867 -308.047042) (xy 311.108235 -308.086386) (xy 311.131106 -308.129963)
			(xy 311.14669 -308.176644) (xy 311.154585 -308.225221) (xy 311.15508 -308.249828) (xy 311.493928 -308.249828)
			(xy 311.497888 -308.200774) (xy 311.509665 -308.15299) (xy 311.528956 -308.107714) (xy 311.555259 -308.066118)
			(xy 311.587894 -308.029281) (xy 311.626015 -307.998156) (xy 311.668636 -307.973549) (xy 311.714652 -307.956097)
			(xy 311.762871 -307.946253) (xy 311.812046 -307.944272) (xy 311.860901 -307.950204) (xy 311.908172 -307.963896)
			(xy 311.952634 -307.984994) (xy 311.993137 -308.01295) (xy 312.02863 -308.047042) (xy 312.058195 -308.086386)
			(xy 312.081066 -308.129963) (xy 312.09665 -308.176644) (xy 312.104545 -308.225221) (xy 312.10504 -308.249828)
			(xy 312.443888 -308.249828) (xy 312.447848 -308.200774) (xy 312.459625 -308.15299) (xy 312.478916 -308.107714)
			(xy 312.505219 -308.066118) (xy 312.537854 -308.029281) (xy 312.575975 -307.998156) (xy 312.618596 -307.973549)
			(xy 312.664612 -307.956097) (xy 312.712831 -307.946253) (xy 312.762006 -307.944272) (xy 312.810861 -307.950204)
			(xy 312.858132 -307.963896) (xy 312.902594 -307.984994) (xy 312.943097 -308.01295) (xy 312.97859 -308.047042)
			(xy 313.008155 -308.086386) (xy 313.031026 -308.129963) (xy 313.04661 -308.176644) (xy 313.054505 -308.225221)
			(xy 313.055 -308.249828) (xy 313.394102 -308.249828) (xy 313.398062 -308.200774) (xy 313.409839 -308.15299)
			(xy 313.42913 -308.107714) (xy 313.455433 -308.066118) (xy 313.488068 -308.029281) (xy 313.526189 -307.998156)
			(xy 313.56881 -307.973549) (xy 313.614826 -307.956097) (xy 313.663045 -307.946253) (xy 313.71222 -307.944272)
			(xy 313.761075 -307.950204) (xy 313.808346 -307.963896) (xy 313.852808 -307.984994) (xy 313.893311 -308.01295)
			(xy 313.928804 -308.047042) (xy 313.958369 -308.086386) (xy 313.98124 -308.129963) (xy 313.996824 -308.176644)
			(xy 314.004719 -308.225221) (xy 314.005214 -308.249828) (xy 314.344062 -308.249828) (xy 314.348022 -308.200774)
			(xy 314.359799 -308.15299) (xy 314.37909 -308.107714) (xy 314.405393 -308.066118) (xy 314.438028 -308.029281)
			(xy 314.476149 -307.998156) (xy 314.51877 -307.973549) (xy 314.564786 -307.956097) (xy 314.613005 -307.946253)
			(xy 314.66218 -307.944272) (xy 314.711035 -307.950204) (xy 314.758306 -307.963896) (xy 314.802768 -307.984994)
			(xy 314.843271 -308.01295) (xy 314.878764 -308.047042) (xy 314.908329 -308.086386) (xy 314.9312 -308.129963)
			(xy 314.946784 -308.176644) (xy 314.954679 -308.225221) (xy 314.955174 -308.249828) (xy 315.294276 -308.249828)
			(xy 315.298236 -308.200774) (xy 315.310013 -308.15299) (xy 315.329304 -308.107714) (xy 315.355607 -308.066118)
			(xy 315.388242 -308.029281) (xy 315.426363 -307.998156) (xy 315.468984 -307.973549) (xy 315.515 -307.956097)
			(xy 315.563219 -307.946253) (xy 315.612394 -307.944272) (xy 315.661249 -307.950204) (xy 315.70852 -307.963896)
			(xy 315.752982 -307.984994) (xy 315.793485 -308.01295) (xy 315.828978 -308.047042) (xy 315.858543 -308.086386)
			(xy 315.881414 -308.129963) (xy 315.896998 -308.176644) (xy 315.904893 -308.225221) (xy 315.905388 -308.249828)
			(xy 315.904893 -308.274435) (xy 315.896998 -308.323012) (xy 315.881414 -308.369693) (xy 315.858543 -308.41327)
			(xy 315.828978 -308.452614) (xy 315.793485 -308.486706) (xy 315.752982 -308.514662) (xy 315.70852 -308.53576)
			(xy 315.661249 -308.549452) (xy 315.612394 -308.555384) (xy 315.563219 -308.553403) (xy 315.515 -308.543559)
			(xy 315.468984 -308.526107) (xy 315.426363 -308.5015) (xy 315.388242 -308.470375) (xy 315.355607 -308.433538)
			(xy 315.329304 -308.391942) (xy 315.310013 -308.346666) (xy 315.298236 -308.298882) (xy 315.294276 -308.249828)
			(xy 314.955174 -308.249828) (xy 314.954679 -308.274435) (xy 314.946784 -308.323012) (xy 314.9312 -308.369693)
			(xy 314.908329 -308.41327) (xy 314.878764 -308.452614) (xy 314.843271 -308.486706) (xy 314.802768 -308.514662)
			(xy 314.758306 -308.53576) (xy 314.711035 -308.549452) (xy 314.66218 -308.555384) (xy 314.613005 -308.553403)
			(xy 314.564786 -308.543559) (xy 314.51877 -308.526107) (xy 314.476149 -308.5015) (xy 314.438028 -308.470375)
			(xy 314.405393 -308.433538) (xy 314.37909 -308.391942) (xy 314.359799 -308.346666) (xy 314.348022 -308.298882)
			(xy 314.344062 -308.249828) (xy 314.005214 -308.249828) (xy 314.004719 -308.274435) (xy 313.996824 -308.323012)
			(xy 313.98124 -308.369693) (xy 313.958369 -308.41327) (xy 313.928804 -308.452614) (xy 313.893311 -308.486706)
			(xy 313.852808 -308.514662) (xy 313.808346 -308.53576) (xy 313.761075 -308.549452) (xy 313.71222 -308.555384)
			(xy 313.663045 -308.553403) (xy 313.614826 -308.543559) (xy 313.56881 -308.526107) (xy 313.526189 -308.5015)
			(xy 313.488068 -308.470375) (xy 313.455433 -308.433538) (xy 313.42913 -308.391942) (xy 313.409839 -308.346666)
			(xy 313.398062 -308.298882) (xy 313.394102 -308.249828) (xy 313.055 -308.249828) (xy 313.054505 -308.274435)
			(xy 313.04661 -308.323012) (xy 313.031026 -308.369693) (xy 313.008155 -308.41327) (xy 312.97859 -308.452614)
			(xy 312.943097 -308.486706) (xy 312.902594 -308.514662) (xy 312.858132 -308.53576) (xy 312.810861 -308.549452)
			(xy 312.762006 -308.555384) (xy 312.712831 -308.553403) (xy 312.664612 -308.543559) (xy 312.618596 -308.526107)
			(xy 312.575975 -308.5015) (xy 312.537854 -308.470375) (xy 312.505219 -308.433538) (xy 312.478916 -308.391942)
			(xy 312.459625 -308.346666) (xy 312.447848 -308.298882) (xy 312.443888 -308.249828) (xy 312.10504 -308.249828)
			(xy 312.104545 -308.274435) (xy 312.09665 -308.323012) (xy 312.081066 -308.369693) (xy 312.058195 -308.41327)
			(xy 312.02863 -308.452614) (xy 311.993137 -308.486706) (xy 311.952634 -308.514662) (xy 311.908172 -308.53576)
			(xy 311.860901 -308.549452) (xy 311.812046 -308.555384) (xy 311.762871 -308.553403) (xy 311.714652 -308.543559)
			(xy 311.668636 -308.526107) (xy 311.626015 -308.5015) (xy 311.587894 -308.470375) (xy 311.555259 -308.433538)
			(xy 311.528956 -308.391942) (xy 311.509665 -308.346666) (xy 311.497888 -308.298882) (xy 311.493928 -308.249828)
			(xy 311.15508 -308.249828) (xy 311.154585 -308.274435) (xy 311.14669 -308.323012) (xy 311.131106 -308.369693)
			(xy 311.108235 -308.41327) (xy 311.07867 -308.452614) (xy 311.043177 -308.486706) (xy 311.002674 -308.514662)
			(xy 310.958212 -308.53576) (xy 310.910941 -308.549452) (xy 310.862086 -308.555384) (xy 310.812911 -308.553403)
			(xy 310.764692 -308.543559) (xy 310.718676 -308.526107) (xy 310.676055 -308.5015) (xy 310.637934 -308.470375)
			(xy 310.605299 -308.433538) (xy 310.578996 -308.391942) (xy 310.559705 -308.346666) (xy 310.547928 -308.298882)
			(xy 310.543968 -308.249828) (xy 310.20512 -308.249828) (xy 310.204625 -308.274435) (xy 310.19673 -308.323012)
			(xy 310.181146 -308.369693) (xy 310.158275 -308.41327) (xy 310.12871 -308.452614) (xy 310.093217 -308.486706)
			(xy 310.052714 -308.514662) (xy 310.008252 -308.53576) (xy 309.960981 -308.549452) (xy 309.912126 -308.555384)
			(xy 309.862951 -308.553403) (xy 309.814732 -308.543559) (xy 309.768716 -308.526107) (xy 309.726095 -308.5015)
			(xy 309.687974 -308.470375) (xy 309.655339 -308.433538) (xy 309.629036 -308.391942) (xy 309.609745 -308.346666)
			(xy 309.597968 -308.298882) (xy 309.594008 -308.249828) (xy 309.25516 -308.249828) (xy 309.254665 -308.274435)
			(xy 309.24677 -308.323012) (xy 309.231186 -308.369693) (xy 309.208315 -308.41327) (xy 309.17875 -308.452614)
			(xy 309.143257 -308.486706) (xy 309.102754 -308.514662) (xy 309.058292 -308.53576) (xy 309.011021 -308.549452)
			(xy 308.962166 -308.555384) (xy 308.912991 -308.553403) (xy 308.864772 -308.543559) (xy 308.818756 -308.526107)
			(xy 308.776135 -308.5015) (xy 308.738014 -308.470375) (xy 308.705379 -308.433538) (xy 308.679076 -308.391942)
			(xy 308.659785 -308.346666) (xy 308.648008 -308.298882) (xy 308.644048 -308.249828) (xy 308.327044 -308.249828)
			(xy 308.32654 -308.275536) (xy 308.318497 -308.326318) (xy 308.302609 -308.375217) (xy 308.279266 -308.421029)
			(xy 308.249045 -308.462625) (xy 308.212689 -308.498981) (xy 308.171093 -308.529202) (xy 308.125281 -308.552545)
			(xy 308.076382 -308.568433) (xy 308.0256 -308.576476) (xy 307.974184 -308.576476) (xy 307.923402 -308.568433)
			(xy 307.874503 -308.552545) (xy 307.828691 -308.529202) (xy 307.787095 -308.498981) (xy 307.750739 -308.462625)
			(xy 307.720518 -308.421029) (xy 307.697175 -308.375217) (xy 307.681287 -308.326318) (xy 307.673244 -308.275536)
			(xy 307.37658 -308.275536) (xy 307.368537 -308.326318) (xy 307.352649 -308.375217) (xy 307.329306 -308.421029)
			(xy 307.299085 -308.462625) (xy 307.262729 -308.498981) (xy 307.221133 -308.529202) (xy 307.175321 -308.552545)
			(xy 307.126422 -308.568433) (xy 307.07564 -308.576476) (xy 307.024224 -308.576476) (xy 306.973442 -308.568433)
			(xy 306.924543 -308.552545) (xy 306.878731 -308.529202) (xy 306.837135 -308.498981) (xy 306.800779 -308.462625)
			(xy 306.770558 -308.421029) (xy 306.747215 -308.375217) (xy 306.731327 -308.326318) (xy 306.723284 -308.275536)
			(xy 306.404352 -308.275536) (xy 306.396636 -308.323012) (xy 306.381052 -308.369693) (xy 306.358181 -308.41327)
			(xy 306.328616 -308.452614) (xy 306.293123 -308.486706) (xy 306.25262 -308.514662) (xy 306.208158 -308.53576)
			(xy 306.160887 -308.549452) (xy 306.112032 -308.555384) (xy 306.062857 -308.553403) (xy 306.014638 -308.543559)
			(xy 305.968622 -308.526107) (xy 305.926001 -308.5015) (xy 305.88788 -308.470375) (xy 305.855245 -308.433538)
			(xy 305.828942 -308.391942) (xy 305.809651 -308.346666) (xy 305.797874 -308.298882) (xy 305.793914 -308.249828)
			(xy 281.616912 -308.249828) (xy 281.616912 -308.349142) (xy 281.617563 -308.361693) (xy 281.629429 -308.383811)
			(xy 281.639518 -308.391306) (xy 281.720544 -308.445408) (xy 281.745436 -308.447948) (xy 281.757628 -308.442868)
			(xy 281.785665 -308.43197) (xy 281.844649 -308.420205) (xy 281.874722 -308.4195) (xy 281.898712 -308.419972)
			(xy 281.9461 -308.427481) (xy 281.991731 -308.442311) (xy 282.03448 -308.464095) (xy 282.073295 -308.492299)
			(xy 282.10722 -308.526228) (xy 282.13542 -308.565046) (xy 282.157201 -308.607797) (xy 282.172026 -308.653429)
			(xy 282.17953 -308.700818) (xy 282.18003 -308.724808) (xy 282.179843 -308.73899) (xy 282.177169 -308.76723)
			(xy 282.174696 -308.781196) (xy 282.17241 -308.793642) (xy 282.179776 -308.817264) (xy 282.257246 -308.894734)
			(xy 282.280868 -308.9021) (xy 282.293314 -308.899814) (xy 282.307279 -308.897329) (xy 282.335519 -308.894657)
			(xy 282.349702 -308.89448) (xy 282.373693 -308.894951) (xy 282.421086 -308.902457) (xy 282.46672 -308.917284)
			(xy 282.509473 -308.939068) (xy 282.548293 -308.967271) (xy 282.582222 -309.0012) (xy 282.610427 -309.040018)
			(xy 282.632212 -309.082771) (xy 282.647041 -309.128405) (xy 282.654548 -309.175797) (xy 282.65501 -309.199788)
			(xy 282.654918 -309.208956) (xy 282.653775 -309.227256) (xy 282.652724 -309.236364) (xy 282.651454 -309.248302)
			(xy 282.659328 -309.270654) (xy 282.735782 -309.343552) (xy 282.758388 -309.350664) (xy 282.770326 -309.348632)
			(xy 282.783877 -309.346494) (xy 282.811218 -309.344206) (xy 282.824936 -309.34406) (xy 282.83859 -309.344221)
			(xy 282.865803 -309.346508) (xy 282.879292 -309.348632) (xy 282.89123 -309.350664) (xy 282.913836 -309.343552)
			(xy 282.99029 -309.270654) (xy 282.998164 -309.248302) (xy 282.996894 -309.23611) (xy 282.995846 -309.227066)
			(xy 282.994703 -309.208892) (xy 282.994608 -309.199788) (xy 282.995055 -309.175796) (xy 283.002563 -309.128403)
			(xy 283.017393 -309.082768) (xy 283.039179 -309.040015) (xy 283.067386 -309.001196) (xy 283.101317 -308.967267)
			(xy 283.140138 -308.939065) (xy 283.182894 -308.917283) (xy 283.22853 -308.902457) (xy 283.275924 -308.894953)
			(xy 283.299916 -308.89448) (xy 283.314098 -308.894667) (xy 283.342337 -308.897342) (xy 283.356304 -308.899814)
			(xy 283.36875 -308.9021) (xy 283.392372 -308.894734) (xy 283.469842 -308.817264) (xy 283.477208 -308.793642)
			(xy 283.474922 -308.781196) (xy 283.472436 -308.767231) (xy 283.469764 -308.738991) (xy 283.469588 -308.724808)
			(xy 283.470073 -308.699987) (xy 283.478103 -308.650998) (xy 283.493953 -308.603953) (xy 283.517205 -308.560093)
			(xy 283.547247 -308.520572) (xy 283.583287 -308.486432) (xy 283.624375 -308.458572) (xy 283.669429 -308.437727)
			(xy 283.717262 -308.424445) (xy 283.766614 -308.419077) (xy 283.816184 -308.421764) (xy 283.864666 -308.432435)
			(xy 283.910784 -308.45081) (xy 283.953321 -308.476403) (xy 283.991157 -308.508541) (xy 284.023295 -308.546376)
			(xy 284.048889 -308.588913) (xy 284.067263 -308.63503) (xy 284.077935 -308.683512) (xy 284.080174 -308.724808)
			(xy 284.419052 -308.724808) (xy 284.423012 -308.675754) (xy 284.434789 -308.62797) (xy 284.45408 -308.582694)
			(xy 284.480383 -308.541098) (xy 284.513018 -308.504261) (xy 284.551139 -308.473136) (xy 284.59376 -308.448529)
			(xy 284.639776 -308.431077) (xy 284.687995 -308.421233) (xy 284.73717 -308.419252) (xy 284.786025 -308.425184)
			(xy 284.833296 -308.438876) (xy 284.877758 -308.459974) (xy 284.918261 -308.48793) (xy 284.953754 -308.522022)
			(xy 284.983319 -308.561366) (xy 285.00619 -308.604943) (xy 285.021774 -308.651624) (xy 285.029669 -308.700201)
			(xy 285.030164 -308.724808) (xy 285.369012 -308.724808) (xy 285.372972 -308.675754) (xy 285.384749 -308.62797)
			(xy 285.40404 -308.582694) (xy 285.430343 -308.541098) (xy 285.462978 -308.504261) (xy 285.501099 -308.473136)
			(xy 285.54372 -308.448529) (xy 285.589736 -308.431077) (xy 285.637955 -308.421233) (xy 285.68713 -308.419252)
			(xy 285.735985 -308.425184) (xy 285.783256 -308.438876) (xy 285.827718 -308.459974) (xy 285.868221 -308.48793)
			(xy 285.903714 -308.522022) (xy 285.933279 -308.561366) (xy 285.95615 -308.604943) (xy 285.971734 -308.651624)
			(xy 285.979629 -308.700201) (xy 285.980124 -308.724808) (xy 286.318972 -308.724808) (xy 286.322932 -308.675754)
			(xy 286.334709 -308.62797) (xy 286.354 -308.582694) (xy 286.380303 -308.541098) (xy 286.412938 -308.504261)
			(xy 286.451059 -308.473136) (xy 286.49368 -308.448529) (xy 286.539696 -308.431077) (xy 286.587915 -308.421233)
			(xy 286.63709 -308.419252) (xy 286.685945 -308.425184) (xy 286.733216 -308.438876) (xy 286.777678 -308.459974)
			(xy 286.818181 -308.48793) (xy 286.853674 -308.522022) (xy 286.883239 -308.561366) (xy 286.90611 -308.604943)
			(xy 286.921694 -308.651624) (xy 286.929589 -308.700201) (xy 286.930084 -308.724808) (xy 286.929589 -308.749415)
			(xy 286.921694 -308.797992) (xy 286.90611 -308.844673) (xy 286.883239 -308.88825) (xy 286.853674 -308.927594)
			(xy 286.818181 -308.961686) (xy 286.777678 -308.989642) (xy 286.733216 -309.01074) (xy 286.685945 -309.024432)
			(xy 286.63709 -309.030364) (xy 286.587915 -309.028383) (xy 286.539696 -309.018539) (xy 286.49368 -309.001087)
			(xy 286.451059 -308.97648) (xy 286.412938 -308.945355) (xy 286.380303 -308.908518) (xy 286.354 -308.866922)
			(xy 286.334709 -308.821646) (xy 286.322932 -308.773862) (xy 286.318972 -308.724808) (xy 285.980124 -308.724808)
			(xy 285.979629 -308.749415) (xy 285.971734 -308.797992) (xy 285.95615 -308.844673) (xy 285.933279 -308.88825)
			(xy 285.903714 -308.927594) (xy 285.868221 -308.961686) (xy 285.827718 -308.989642) (xy 285.783256 -309.01074)
			(xy 285.735985 -309.024432) (xy 285.68713 -309.030364) (xy 285.637955 -309.028383) (xy 285.589736 -309.018539)
			(xy 285.54372 -309.001087) (xy 285.501099 -308.97648) (xy 285.462978 -308.945355) (xy 285.430343 -308.908518)
			(xy 285.40404 -308.866922) (xy 285.384749 -308.821646) (xy 285.372972 -308.773862) (xy 285.369012 -308.724808)
			(xy 285.030164 -308.724808) (xy 285.029669 -308.749415) (xy 285.021774 -308.797992) (xy 285.00619 -308.844673)
			(xy 284.983319 -308.88825) (xy 284.953754 -308.927594) (xy 284.918261 -308.961686) (xy 284.877758 -308.989642)
			(xy 284.833296 -309.01074) (xy 284.786025 -309.024432) (xy 284.73717 -309.030364) (xy 284.687995 -309.028383)
			(xy 284.639776 -309.018539) (xy 284.59376 -309.001087) (xy 284.551139 -308.97648) (xy 284.513018 -308.945355)
			(xy 284.480383 -308.908518) (xy 284.45408 -308.866922) (xy 284.434789 -308.821646) (xy 284.423012 -308.773862)
			(xy 284.419052 -308.724808) (xy 284.080174 -308.724808) (xy 284.080623 -308.733082) (xy 284.075255 -308.782434)
			(xy 284.061975 -308.830267) (xy 284.04113 -308.875321) (xy 284.013271 -308.91641) (xy 283.979131 -308.95245)
			(xy 283.939611 -308.982492) (xy 283.895751 -309.005745) (xy 283.848706 -309.021596) (xy 283.799717 -309.029626)
			(xy 283.774896 -309.030116) (xy 283.760714 -309.029929) (xy 283.732474 -309.027256) (xy 283.718508 -309.024782)
			(xy 283.706062 -309.022496) (xy 283.68244 -309.029862) (xy 283.60497 -309.107332) (xy 283.597604 -309.130954)
			(xy 283.59989 -309.1434) (xy 283.602376 -309.157365) (xy 283.605049 -309.185605) (xy 283.605224 -309.199788)
			(xy 283.605125 -309.208892) (xy 283.603978 -309.227065) (xy 283.602938 -309.23611) (xy 283.601668 -309.248302)
			(xy 283.609542 -309.270654) (xy 283.685996 -309.343552) (xy 283.708602 -309.350664) (xy 283.72054 -309.348632)
			(xy 283.734028 -309.346501) (xy 283.761241 -309.344213) (xy 283.774896 -309.34406) (xy 283.800884 -309.344569)
			(xy 283.852221 -309.352699) (xy 283.901654 -309.368759) (xy 283.947967 -309.392354) (xy 283.990018 -309.422904)
			(xy 284.026773 -309.459655) (xy 284.057327 -309.501703) (xy 284.080927 -309.548012) (xy 284.096992 -309.597444)
			(xy 284.105128 -309.64878) (xy 284.105604 -309.674768) (xy 284.10535 -309.688992) (xy 284.105336 -309.697987)
			(xy 284.110872 -309.715089) (xy 284.122003 -309.729203) (xy 284.12948 -309.734204) (xy 284.216856 -309.788052)
			(xy 284.244034 -309.788814) (xy 284.256226 -309.781956) (xy 284.282068 -309.767839) (xy 284.335192 -309.742422)
			(xy 284.362398 -309.731156) (xy 284.371573 -309.726971) (xy 284.385911 -309.712812) (xy 284.39373 -309.694239)
			(xy 284.394148 -309.684166) (xy 284.394148 -309.674768) (xy 284.394658 -309.648781) (xy 284.402788 -309.597446)
			(xy 284.418849 -309.548016) (xy 284.442445 -309.501706) (xy 284.472995 -309.459658) (xy 284.509746 -309.422907)
			(xy 284.551794 -309.392357) (xy 284.598104 -309.368761) (xy 284.647534 -309.3527) (xy 284.698869 -309.34457)
			(xy 284.750843 -309.34457) (xy 284.802178 -309.3527) (xy 284.851608 -309.368761) (xy 284.897918 -309.392357)
			(xy 284.939966 -309.422907) (xy 284.976717 -309.459658) (xy 285.007267 -309.501706) (xy 285.030863 -309.548016)
			(xy 285.046924 -309.597446) (xy 285.055054 -309.648781) (xy 285.055564 -309.674768) (xy 285.055564 -309.682642)
			(xy 285.055056 -309.69839) (xy 285.072328 -309.72506) (xy 285.087314 -309.731156) (xy 285.114514 -309.742435)
			(xy 285.167636 -309.767855) (xy 285.193486 -309.781956) (xy 285.205678 -309.788814) (xy 285.232856 -309.788052)
			(xy 285.320232 -309.734204) (xy 285.327678 -309.729177) (xy 285.33876 -309.715049) (xy 285.344321 -309.697977)
			(xy 285.344362 -309.688992) (xy 285.344108 -309.674768) (xy 285.344618 -309.648781) (xy 285.352748 -309.597446)
			(xy 285.368809 -309.548016) (xy 285.392405 -309.501706) (xy 285.422955 -309.459658) (xy 285.459706 -309.422907)
			(xy 285.501754 -309.392357) (xy 285.548064 -309.368761) (xy 285.597494 -309.3527) (xy 285.648829 -309.34457)
			(xy 285.700803 -309.34457) (xy 285.752138 -309.3527) (xy 285.801568 -309.368761) (xy 285.847878 -309.392357)
			(xy 285.889926 -309.422907) (xy 285.926677 -309.459658) (xy 285.957227 -309.501706) (xy 285.980823 -309.548016)
			(xy 285.996884 -309.597446) (xy 286.005014 -309.648781) (xy 286.005524 -309.674768) (xy 286.00527 -309.688992)
			(xy 286.005257 -309.697986) (xy 286.010794 -309.715086) (xy 286.021927 -309.729197) (xy 286.0294 -309.734204)
			(xy 286.116776 -309.788052) (xy 286.143954 -309.788814) (xy 286.156146 -309.781956) (xy 286.181987 -309.767837)
			(xy 286.235109 -309.742416) (xy 286.262318 -309.731156) (xy 286.27149 -309.726969) (xy 286.285823 -309.712808)
			(xy 286.293638 -309.694238) (xy 286.294068 -309.684166) (xy 286.294068 -309.674768) (xy 286.294578 -309.648781)
			(xy 286.302708 -309.597446) (xy 286.318769 -309.548016) (xy 286.342365 -309.501706) (xy 286.372915 -309.459658)
			(xy 286.409666 -309.422907) (xy 286.451714 -309.392357) (xy 286.498024 -309.368761) (xy 286.547454 -309.3527)
			(xy 286.598789 -309.34457) (xy 286.650763 -309.34457) (xy 286.702098 -309.3527) (xy 286.751528 -309.368761)
			(xy 286.797838 -309.392357) (xy 286.839886 -309.422907) (xy 286.876637 -309.459658) (xy 286.907187 -309.501706)
			(xy 286.930783 -309.548016) (xy 286.946844 -309.597446) (xy 286.954974 -309.648781) (xy 286.955484 -309.674768)
			(xy 286.955484 -309.682642) (xy 286.954976 -309.69839) (xy 286.972248 -309.72506) (xy 286.987234 -309.731156)
			(xy 287.014435 -309.742433) (xy 287.067559 -309.76785) (xy 287.093406 -309.781956) (xy 287.105598 -309.788814)
			(xy 287.132776 -309.788052) (xy 287.220152 -309.734204) (xy 287.227596 -309.729175) (xy 287.238673 -309.715047)
			(xy 287.244232 -309.697976) (xy 287.244282 -309.688992) (xy 287.244028 -309.674768) (xy 287.244514 -309.648781)
			(xy 287.252649 -309.597449) (xy 287.268715 -309.548021) (xy 287.292315 -309.501715) (xy 287.322868 -309.459671)
			(xy 287.359622 -309.422924) (xy 287.401673 -309.392379) (xy 287.447984 -309.368788) (xy 287.497415 -309.352733)
			(xy 287.548749 -309.344608) (xy 287.574736 -309.34406) (xy 287.58839 -309.344221) (xy 287.615603 -309.346508)
			(xy 287.629092 -309.348632) (xy 287.64103 -309.350664) (xy 287.663636 -309.343552) (xy 287.74009 -309.270654)
			(xy 287.747964 -309.248302) (xy 287.746694 -309.23611) (xy 287.745646 -309.227066) (xy 287.744503 -309.208892)
			(xy 287.744408 -309.199788) (xy 287.744595 -309.185606) (xy 287.74727 -309.157367) (xy 287.749742 -309.1434)
			(xy 287.752028 -309.130954) (xy 287.744662 -309.107332) (xy 287.667192 -309.029862) (xy 287.64357 -309.022496)
			(xy 287.631124 -309.024782) (xy 287.617159 -309.027269) (xy 287.588919 -309.029944) (xy 287.574736 -309.030116)
			(xy 287.549914 -309.029633) (xy 287.500922 -309.021607) (xy 287.453875 -309.00576) (xy 287.410011 -308.982511)
			(xy 287.370486 -308.952471) (xy 287.336342 -308.916433) (xy 287.308479 -308.875345) (xy 287.28763 -308.830291)
			(xy 287.274345 -308.782457) (xy 287.268974 -308.733104) (xy 287.271658 -308.683532) (xy 287.282327 -308.635047)
			(xy 287.3007 -308.588927) (xy 287.326292 -308.546388) (xy 287.358429 -308.508549) (xy 287.396265 -308.476408)
			(xy 287.438802 -308.450812) (xy 287.48492 -308.432435) (xy 287.533404 -308.421762) (xy 287.582976 -308.419073)
			(xy 287.632329 -308.42444) (xy 287.680164 -308.43772) (xy 287.725221 -308.458565) (xy 287.766311 -308.486425)
			(xy 287.802353 -308.520565) (xy 287.832396 -308.560087) (xy 287.855649 -308.603949) (xy 287.8715 -308.650995)
			(xy 287.879531 -308.699986) (xy 287.880044 -308.724808) (xy 287.879857 -308.73899) (xy 287.877183 -308.76723)
			(xy 287.87471 -308.781196) (xy 287.872424 -308.793642) (xy 287.87979 -308.817264) (xy 287.95726 -308.894734)
			(xy 287.980882 -308.9021) (xy 287.993328 -308.899814) (xy 288.007293 -308.89733) (xy 288.035533 -308.894659)
			(xy 288.049716 -308.89448) (xy 288.063962 -308.894656) (xy 288.09233 -308.897325) (xy 288.106358 -308.899814)
			(xy 288.11855 -308.9021) (xy 288.14268 -308.894734) (xy 288.219896 -308.817518) (xy 288.227262 -308.793642)
			(xy 288.224976 -308.781196) (xy 288.22249 -308.767231) (xy 288.219817 -308.738991) (xy 288.219642 -308.724808)
			(xy 288.220127 -308.699992) (xy 288.228155 -308.651013) (xy 288.244001 -308.603979) (xy 288.267247 -308.560127)
			(xy 288.297282 -308.520614) (xy 288.333313 -308.48648) (xy 288.374391 -308.458625) (xy 288.419435 -308.437782)
			(xy 288.467257 -308.424501) (xy 288.516598 -308.419132) (xy 288.566157 -308.421815) (xy 288.61463 -308.432481)
			(xy 288.660739 -308.450848) (xy 288.703269 -308.476432) (xy 288.741099 -308.50856) (xy 288.773234 -308.546384)
			(xy 288.798827 -308.588909) (xy 288.817202 -308.635014) (xy 288.827877 -308.683485) (xy 288.830122 -308.724808)
			(xy 290.119066 -308.724808) (xy 290.123026 -308.675754) (xy 290.134803 -308.62797) (xy 290.154094 -308.582694)
			(xy 290.180397 -308.541098) (xy 290.213032 -308.504261) (xy 290.251153 -308.473136) (xy 290.293774 -308.448529)
			(xy 290.33979 -308.431077) (xy 290.388009 -308.421233) (xy 290.437184 -308.419252) (xy 290.486039 -308.425184)
			(xy 290.53331 -308.438876) (xy 290.577772 -308.459974) (xy 290.618275 -308.48793) (xy 290.653768 -308.522022)
			(xy 290.683333 -308.561366) (xy 290.706204 -308.604943) (xy 290.721788 -308.651624) (xy 290.729683 -308.700201)
			(xy 290.730178 -308.724808) (xy 290.730012 -308.733072) (xy 292.019091 -308.733072) (xy 292.02178 -308.683505)
			(xy 292.032452 -308.635026) (xy 292.050828 -308.588912) (xy 292.076421 -308.546378) (xy 292.108558 -308.508546)
			(xy 292.146393 -308.47641) (xy 292.188928 -308.45082) (xy 292.235043 -308.432447) (xy 292.283523 -308.421777)
			(xy 292.33309 -308.419091) (xy 292.382439 -308.42446) (xy 292.430269 -308.437741) (xy 292.475321 -308.458586)
			(xy 292.516406 -308.486444) (xy 292.552444 -308.520583) (xy 292.582484 -308.560102) (xy 292.605734 -308.60396)
			(xy 292.621583 -308.651002) (xy 292.629613 -308.699988) (xy 292.630098 -308.724808) (xy 292.629923 -308.738991)
			(xy 292.62725 -308.767231) (xy 292.624764 -308.781196) (xy 292.622478 -308.793642) (xy 292.629844 -308.817264)
			(xy 292.707314 -308.894734) (xy 292.730936 -308.9021) (xy 292.743382 -308.899814) (xy 292.757347 -308.89733)
			(xy 292.785587 -308.894663) (xy 292.79977 -308.89448) (xy 292.813953 -308.894661) (xy 292.842193 -308.89733)
			(xy 292.856158 -308.899814) (xy 292.868604 -308.9021) (xy 292.892226 -308.894734) (xy 292.969696 -308.817264)
			(xy 292.977062 -308.793642) (xy 292.974776 -308.781196) (xy 292.972303 -308.76723) (xy 292.969629 -308.73899)
			(xy 292.969442 -308.724808) (xy 292.969964 -308.699553) (xy 292.978277 -308.649731) (xy 292.994678 -308.601957)
			(xy 293.018719 -308.557534) (xy 293.049743 -308.517674) (xy 293.086905 -308.483464) (xy 293.129191 -308.455838)
			(xy 293.175447 -308.435548) (xy 293.224412 -308.423148) (xy 293.27475 -308.418977) (xy 293.325088 -308.423148)
			(xy 293.374053 -308.435548) (xy 293.420309 -308.455838) (xy 293.462595 -308.483464) (xy 293.499757 -308.517674)
			(xy 293.530781 -308.557534) (xy 293.554822 -308.601957) (xy 293.571223 -308.649731) (xy 293.579536 -308.699553)
			(xy 293.580058 -308.724808) (xy 293.579883 -308.738991) (xy 293.57721 -308.767231) (xy 293.574724 -308.781196)
			(xy 293.572438 -308.793642) (xy 293.579804 -308.817264) (xy 293.657274 -308.894734) (xy 293.680896 -308.9021)
			(xy 293.693342 -308.899814) (xy 293.707308 -308.897336) (xy 293.735547 -308.894665) (xy 293.74973 -308.89448)
			(xy 293.763913 -308.894653) (xy 293.792153 -308.897327) (xy 293.806118 -308.899814) (xy 293.818564 -308.9021)
			(xy 293.842186 -308.894734) (xy 293.919656 -308.817264) (xy 293.927022 -308.793642) (xy 293.924736 -308.781196)
			(xy 293.922263 -308.76723) (xy 293.919589 -308.73899) (xy 293.919402 -308.724808) (xy 293.919869 -308.699987)
			(xy 293.927899 -308.650997) (xy 293.943749 -308.603953) (xy 293.967001 -308.560092) (xy 293.997043 -308.520571)
			(xy 294.033082 -308.48643) (xy 294.07417 -308.45857) (xy 294.119225 -308.437724) (xy 294.167058 -308.424442)
			(xy 294.216409 -308.419073) (xy 294.26598 -308.42176) (xy 294.314462 -308.43243) (xy 294.36058 -308.450803)
			(xy 294.403118 -308.476396) (xy 294.440954 -308.508533) (xy 294.473094 -308.546368) (xy 294.498689 -308.588904)
			(xy 294.517065 -308.635021) (xy 294.527738 -308.683503) (xy 294.529965 -308.724554) (xy 294.868866 -308.724554)
			(xy 294.872826 -308.6755) (xy 294.884603 -308.627716) (xy 294.903894 -308.58244) (xy 294.930197 -308.540844)
			(xy 294.962832 -308.504007) (xy 295.000953 -308.472882) (xy 295.043574 -308.448275) (xy 295.08959 -308.430823)
			(xy 295.137809 -308.420979) (xy 295.186984 -308.418998) (xy 295.235839 -308.42493) (xy 295.28311 -308.438622)
			(xy 295.327572 -308.45972) (xy 295.368075 -308.487676) (xy 295.403568 -308.521768) (xy 295.433133 -308.561112)
			(xy 295.456004 -308.604689) (xy 295.471588 -308.65137) (xy 295.479483 -308.699947) (xy 295.479978 -308.724554)
			(xy 295.479973 -308.724808) (xy 295.81908 -308.724808) (xy 295.82304 -308.675754) (xy 295.834817 -308.62797)
			(xy 295.854108 -308.582694) (xy 295.880411 -308.541098) (xy 295.913046 -308.504261) (xy 295.951167 -308.473136)
			(xy 295.993788 -308.448529) (xy 296.039804 -308.431077) (xy 296.088023 -308.421233) (xy 296.137198 -308.419252)
			(xy 296.186053 -308.425184) (xy 296.233324 -308.438876) (xy 296.277786 -308.459974) (xy 296.318289 -308.48793)
			(xy 296.353782 -308.522022) (xy 296.383347 -308.561366) (xy 296.406218 -308.604943) (xy 296.421802 -308.651624)
			(xy 296.429697 -308.700201) (xy 296.430192 -308.724808) (xy 296.76904 -308.724808) (xy 296.773 -308.675754)
			(xy 296.784777 -308.62797) (xy 296.804068 -308.582694) (xy 296.830371 -308.541098) (xy 296.863006 -308.504261)
			(xy 296.901127 -308.473136) (xy 296.943748 -308.448529) (xy 296.989764 -308.431077) (xy 297.037983 -308.421233)
			(xy 297.087158 -308.419252) (xy 297.136013 -308.425184) (xy 297.183284 -308.438876) (xy 297.227746 -308.459974)
			(xy 297.268249 -308.48793) (xy 297.303742 -308.522022) (xy 297.333307 -308.561366) (xy 297.356178 -308.604943)
			(xy 297.371762 -308.651624) (xy 297.379657 -308.700201) (xy 297.380152 -308.724808) (xy 297.719 -308.724808)
			(xy 297.72296 -308.675754) (xy 297.734737 -308.62797) (xy 297.754028 -308.582694) (xy 297.780331 -308.541098)
			(xy 297.812966 -308.504261) (xy 297.851087 -308.473136) (xy 297.893708 -308.448529) (xy 297.939724 -308.431077)
			(xy 297.987943 -308.421233) (xy 298.037118 -308.419252) (xy 298.085973 -308.425184) (xy 298.133244 -308.438876)
			(xy 298.177706 -308.459974) (xy 298.218209 -308.48793) (xy 298.253702 -308.522022) (xy 298.283267 -308.561366)
			(xy 298.306138 -308.604943) (xy 298.321722 -308.651624) (xy 298.329617 -308.700201) (xy 298.330112 -308.724808)
			(xy 298.66896 -308.724808) (xy 298.67292 -308.675754) (xy 298.684697 -308.62797) (xy 298.703988 -308.582694)
			(xy 298.730291 -308.541098) (xy 298.762926 -308.504261) (xy 298.801047 -308.473136) (xy 298.843668 -308.448529)
			(xy 298.889684 -308.431077) (xy 298.937903 -308.421233) (xy 298.987078 -308.419252) (xy 299.035933 -308.425184)
			(xy 299.083204 -308.438876) (xy 299.127666 -308.459974) (xy 299.168169 -308.48793) (xy 299.203662 -308.522022)
			(xy 299.233227 -308.561366) (xy 299.256098 -308.604943) (xy 299.271682 -308.651624) (xy 299.279577 -308.700201)
			(xy 299.280072 -308.724808) (xy 299.61892 -308.724808) (xy 299.62288 -308.675754) (xy 299.634657 -308.62797)
			(xy 299.653948 -308.582694) (xy 299.680251 -308.541098) (xy 299.712886 -308.504261) (xy 299.751007 -308.473136)
			(xy 299.793628 -308.448529) (xy 299.839644 -308.431077) (xy 299.887863 -308.421233) (xy 299.937038 -308.419252)
			(xy 299.985893 -308.425184) (xy 300.033164 -308.438876) (xy 300.077626 -308.459974) (xy 300.118129 -308.48793)
			(xy 300.153622 -308.522022) (xy 300.183187 -308.561366) (xy 300.206058 -308.604943) (xy 300.221642 -308.651624)
			(xy 300.229537 -308.700201) (xy 300.230032 -308.724808) (xy 300.569134 -308.724808) (xy 300.573094 -308.675754)
			(xy 300.584871 -308.62797) (xy 300.604162 -308.582694) (xy 300.630465 -308.541098) (xy 300.6631 -308.504261)
			(xy 300.701221 -308.473136) (xy 300.743842 -308.448529) (xy 300.789858 -308.431077) (xy 300.838077 -308.421233)
			(xy 300.887252 -308.419252) (xy 300.936107 -308.425184) (xy 300.983378 -308.438876) (xy 301.02784 -308.459974)
			(xy 301.068343 -308.48793) (xy 301.103836 -308.522022) (xy 301.133401 -308.561366) (xy 301.156272 -308.604943)
			(xy 301.171856 -308.651624) (xy 301.179751 -308.700201) (xy 301.180246 -308.724808) (xy 301.519094 -308.724808)
			(xy 301.523054 -308.675754) (xy 301.534831 -308.62797) (xy 301.554122 -308.582694) (xy 301.580425 -308.541098)
			(xy 301.61306 -308.504261) (xy 301.651181 -308.473136) (xy 301.693802 -308.448529) (xy 301.739818 -308.431077)
			(xy 301.788037 -308.421233) (xy 301.837212 -308.419252) (xy 301.886067 -308.425184) (xy 301.933338 -308.438876)
			(xy 301.9778 -308.459974) (xy 302.018303 -308.48793) (xy 302.053796 -308.522022) (xy 302.083361 -308.561366)
			(xy 302.106232 -308.604943) (xy 302.121816 -308.651624) (xy 302.129711 -308.700201) (xy 302.130206 -308.724808)
			(xy 302.469054 -308.724808) (xy 302.473014 -308.675754) (xy 302.484791 -308.62797) (xy 302.504082 -308.582694)
			(xy 302.530385 -308.541098) (xy 302.56302 -308.504261) (xy 302.601141 -308.473136) (xy 302.643762 -308.448529)
			(xy 302.689778 -308.431077) (xy 302.737997 -308.421233) (xy 302.787172 -308.419252) (xy 302.836027 -308.425184)
			(xy 302.883298 -308.438876) (xy 302.92776 -308.459974) (xy 302.968263 -308.48793) (xy 303.003756 -308.522022)
			(xy 303.033321 -308.561366) (xy 303.056192 -308.604943) (xy 303.071776 -308.651624) (xy 303.079671 -308.700201)
			(xy 303.080166 -308.724808) (xy 303.419014 -308.724808) (xy 303.422974 -308.675754) (xy 303.434751 -308.62797)
			(xy 303.454042 -308.582694) (xy 303.480345 -308.541098) (xy 303.51298 -308.504261) (xy 303.551101 -308.473136)
			(xy 303.593722 -308.448529) (xy 303.639738 -308.431077) (xy 303.687957 -308.421233) (xy 303.737132 -308.419252)
			(xy 303.785987 -308.425184) (xy 303.833258 -308.438876) (xy 303.87772 -308.459974) (xy 303.918223 -308.48793)
			(xy 303.953716 -308.522022) (xy 303.983281 -308.561366) (xy 304.006152 -308.604943) (xy 304.021736 -308.651624)
			(xy 304.029631 -308.700201) (xy 304.030126 -308.724808) (xy 304.368974 -308.724808) (xy 304.372934 -308.675754)
			(xy 304.384711 -308.62797) (xy 304.404002 -308.582694) (xy 304.430305 -308.541098) (xy 304.46294 -308.504261)
			(xy 304.501061 -308.473136) (xy 304.543682 -308.448529) (xy 304.589698 -308.431077) (xy 304.637917 -308.421233)
			(xy 304.687092 -308.419252) (xy 304.735947 -308.425184) (xy 304.783218 -308.438876) (xy 304.82768 -308.459974)
			(xy 304.868183 -308.48793) (xy 304.903676 -308.522022) (xy 304.933241 -308.561366) (xy 304.956112 -308.604943)
			(xy 304.971696 -308.651624) (xy 304.979591 -308.700201) (xy 304.980086 -308.724808) (xy 304.979591 -308.749415)
			(xy 304.971696 -308.797992) (xy 304.956112 -308.844673) (xy 304.933241 -308.88825) (xy 304.903676 -308.927594)
			(xy 304.868183 -308.961686) (xy 304.82768 -308.989642) (xy 304.783218 -309.01074) (xy 304.735947 -309.024432)
			(xy 304.687092 -309.030364) (xy 304.637917 -309.028383) (xy 304.589698 -309.018539) (xy 304.543682 -309.001087)
			(xy 304.501061 -308.97648) (xy 304.46294 -308.945355) (xy 304.430305 -308.908518) (xy 304.404002 -308.866922)
			(xy 304.384711 -308.821646) (xy 304.372934 -308.773862) (xy 304.368974 -308.724808) (xy 304.030126 -308.724808)
			(xy 304.029631 -308.749415) (xy 304.021736 -308.797992) (xy 304.006152 -308.844673) (xy 303.983281 -308.88825)
			(xy 303.953716 -308.927594) (xy 303.918223 -308.961686) (xy 303.87772 -308.989642) (xy 303.833258 -309.01074)
			(xy 303.785987 -309.024432) (xy 303.737132 -309.030364) (xy 303.687957 -309.028383) (xy 303.639738 -309.018539)
			(xy 303.593722 -309.001087) (xy 303.551101 -308.97648) (xy 303.51298 -308.945355) (xy 303.480345 -308.908518)
			(xy 303.454042 -308.866922) (xy 303.434751 -308.821646) (xy 303.422974 -308.773862) (xy 303.419014 -308.724808)
			(xy 303.080166 -308.724808) (xy 303.079671 -308.749415) (xy 303.071776 -308.797992) (xy 303.056192 -308.844673)
			(xy 303.033321 -308.88825) (xy 303.003756 -308.927594) (xy 302.968263 -308.961686) (xy 302.92776 -308.989642)
			(xy 302.883298 -309.01074) (xy 302.836027 -309.024432) (xy 302.787172 -309.030364) (xy 302.737997 -309.028383)
			(xy 302.689778 -309.018539) (xy 302.643762 -309.001087) (xy 302.601141 -308.97648) (xy 302.56302 -308.945355)
			(xy 302.530385 -308.908518) (xy 302.504082 -308.866922) (xy 302.484791 -308.821646) (xy 302.473014 -308.773862)
			(xy 302.469054 -308.724808) (xy 302.130206 -308.724808) (xy 302.129711 -308.749415) (xy 302.121816 -308.797992)
			(xy 302.106232 -308.844673) (xy 302.083361 -308.88825) (xy 302.053796 -308.927594) (xy 302.018303 -308.961686)
			(xy 301.9778 -308.989642) (xy 301.933338 -309.01074) (xy 301.886067 -309.024432) (xy 301.837212 -309.030364)
			(xy 301.788037 -309.028383) (xy 301.739818 -309.018539) (xy 301.693802 -309.001087) (xy 301.651181 -308.97648)
			(xy 301.61306 -308.945355) (xy 301.580425 -308.908518) (xy 301.554122 -308.866922) (xy 301.534831 -308.821646)
			(xy 301.523054 -308.773862) (xy 301.519094 -308.724808) (xy 301.180246 -308.724808) (xy 301.179751 -308.749415)
			(xy 301.171856 -308.797992) (xy 301.156272 -308.844673) (xy 301.133401 -308.88825) (xy 301.103836 -308.927594)
			(xy 301.068343 -308.961686) (xy 301.02784 -308.989642) (xy 300.983378 -309.01074) (xy 300.936107 -309.024432)
			(xy 300.887252 -309.030364) (xy 300.838077 -309.028383) (xy 300.789858 -309.018539) (xy 300.743842 -309.001087)
			(xy 300.701221 -308.97648) (xy 300.6631 -308.945355) (xy 300.630465 -308.908518) (xy 300.604162 -308.866922)
			(xy 300.584871 -308.821646) (xy 300.573094 -308.773862) (xy 300.569134 -308.724808) (xy 300.230032 -308.724808)
			(xy 300.229537 -308.749415) (xy 300.221642 -308.797992) (xy 300.206058 -308.844673) (xy 300.183187 -308.88825)
			(xy 300.153622 -308.927594) (xy 300.118129 -308.961686) (xy 300.077626 -308.989642) (xy 300.033164 -309.01074)
			(xy 299.985893 -309.024432) (xy 299.937038 -309.030364) (xy 299.887863 -309.028383) (xy 299.839644 -309.018539)
			(xy 299.793628 -309.001087) (xy 299.751007 -308.97648) (xy 299.712886 -308.945355) (xy 299.680251 -308.908518)
			(xy 299.653948 -308.866922) (xy 299.634657 -308.821646) (xy 299.62288 -308.773862) (xy 299.61892 -308.724808)
			(xy 299.280072 -308.724808) (xy 299.279577 -308.749415) (xy 299.271682 -308.797992) (xy 299.256098 -308.844673)
			(xy 299.233227 -308.88825) (xy 299.203662 -308.927594) (xy 299.168169 -308.961686) (xy 299.127666 -308.989642)
			(xy 299.083204 -309.01074) (xy 299.035933 -309.024432) (xy 298.987078 -309.030364) (xy 298.937903 -309.028383)
			(xy 298.889684 -309.018539) (xy 298.843668 -309.001087) (xy 298.801047 -308.97648) (xy 298.762926 -308.945355)
			(xy 298.730291 -308.908518) (xy 298.703988 -308.866922) (xy 298.684697 -308.821646) (xy 298.67292 -308.773862)
			(xy 298.66896 -308.724808) (xy 298.330112 -308.724808) (xy 298.329617 -308.749415) (xy 298.321722 -308.797992)
			(xy 298.306138 -308.844673) (xy 298.283267 -308.88825) (xy 298.253702 -308.927594) (xy 298.218209 -308.961686)
			(xy 298.177706 -308.989642) (xy 298.133244 -309.01074) (xy 298.085973 -309.024432) (xy 298.037118 -309.030364)
			(xy 297.987943 -309.028383) (xy 297.939724 -309.018539) (xy 297.893708 -309.001087) (xy 297.851087 -308.97648)
			(xy 297.812966 -308.945355) (xy 297.780331 -308.908518) (xy 297.754028 -308.866922) (xy 297.734737 -308.821646)
			(xy 297.72296 -308.773862) (xy 297.719 -308.724808) (xy 297.380152 -308.724808) (xy 297.379657 -308.749415)
			(xy 297.371762 -308.797992) (xy 297.356178 -308.844673) (xy 297.333307 -308.88825) (xy 297.303742 -308.927594)
			(xy 297.268249 -308.961686) (xy 297.227746 -308.989642) (xy 297.183284 -309.01074) (xy 297.136013 -309.024432)
			(xy 297.087158 -309.030364) (xy 297.037983 -309.028383) (xy 296.989764 -309.018539) (xy 296.943748 -309.001087)
			(xy 296.901127 -308.97648) (xy 296.863006 -308.945355) (xy 296.830371 -308.908518) (xy 296.804068 -308.866922)
			(xy 296.784777 -308.821646) (xy 296.773 -308.773862) (xy 296.76904 -308.724808) (xy 296.430192 -308.724808)
			(xy 296.429697 -308.749415) (xy 296.421802 -308.797992) (xy 296.406218 -308.844673) (xy 296.383347 -308.88825)
			(xy 296.353782 -308.927594) (xy 296.318289 -308.961686) (xy 296.277786 -308.989642) (xy 296.233324 -309.01074)
			(xy 296.186053 -309.024432) (xy 296.137198 -309.030364) (xy 296.088023 -309.028383) (xy 296.039804 -309.018539)
			(xy 295.993788 -309.001087) (xy 295.951167 -308.97648) (xy 295.913046 -308.945355) (xy 295.880411 -308.908518)
			(xy 295.854108 -308.866922) (xy 295.834817 -308.821646) (xy 295.82304 -308.773862) (xy 295.81908 -308.724808)
			(xy 295.479973 -308.724808) (xy 295.479483 -308.749161) (xy 295.471588 -308.797738) (xy 295.456004 -308.844419)
			(xy 295.433133 -308.887996) (xy 295.403568 -308.92734) (xy 295.368075 -308.961432) (xy 295.327572 -308.989388)
			(xy 295.28311 -309.010486) (xy 295.235839 -309.024178) (xy 295.186984 -309.03011) (xy 295.137809 -309.028129)
			(xy 295.08959 -309.018285) (xy 295.043574 -309.000833) (xy 295.000953 -308.976226) (xy 294.962832 -308.945101)
			(xy 294.930197 -308.908264) (xy 294.903894 -308.866668) (xy 294.884603 -308.821392) (xy 294.872826 -308.773608)
			(xy 294.868866 -308.724554) (xy 294.529965 -308.724554) (xy 294.530427 -308.733073) (xy 294.525061 -308.782425)
			(xy 294.511782 -308.830259) (xy 294.490939 -308.875314) (xy 294.463081 -308.916404) (xy 294.428943 -308.952445)
			(xy 294.389423 -308.982489) (xy 294.345564 -309.005744) (xy 294.29852 -309.021596) (xy 294.249531 -309.029629)
			(xy 294.22471 -309.030116) (xy 294.210527 -309.029938) (xy 294.182287 -309.027267) (xy 294.168322 -309.024782)
			(xy 294.155876 -309.022496) (xy 294.132254 -309.029862) (xy 294.054784 -309.107332) (xy 294.047418 -309.130954)
			(xy 294.049704 -309.1434) (xy 294.052177 -309.157367) (xy 294.054851 -309.185606) (xy 294.055038 -309.199788)
			(xy 305.793914 -309.199788) (xy 305.797874 -309.150734) (xy 305.809651 -309.10295) (xy 305.828942 -309.057674)
			(xy 305.855245 -309.016078) (xy 305.88788 -308.979241) (xy 305.926001 -308.948116) (xy 305.968622 -308.923509)
			(xy 306.014638 -308.906057) (xy 306.062857 -308.896213) (xy 306.112032 -308.894232) (xy 306.160887 -308.900164)
			(xy 306.208158 -308.913856) (xy 306.25262 -308.934954) (xy 306.293123 -308.96291) (xy 306.328616 -308.997002)
			(xy 306.358181 -309.036346) (xy 306.381052 -309.079923) (xy 306.396636 -309.126604) (xy 306.404531 -309.175181)
			(xy 306.405026 -309.199788) (xy 306.744128 -309.199788) (xy 306.748088 -309.150734) (xy 306.759865 -309.10295)
			(xy 306.779156 -309.057674) (xy 306.805459 -309.016078) (xy 306.838094 -308.979241) (xy 306.876215 -308.948116)
			(xy 306.918836 -308.923509) (xy 306.964852 -308.906057) (xy 307.013071 -308.896213) (xy 307.062246 -308.894232)
			(xy 307.111101 -308.900164) (xy 307.158372 -308.913856) (xy 307.202834 -308.934954) (xy 307.243337 -308.96291)
			(xy 307.27883 -308.997002) (xy 307.308395 -309.036346) (xy 307.331266 -309.079923) (xy 307.34685 -309.126604)
			(xy 307.354745 -309.175181) (xy 307.35524 -309.199788) (xy 307.694088 -309.199788) (xy 307.698048 -309.150734)
			(xy 307.709825 -309.10295) (xy 307.729116 -309.057674) (xy 307.755419 -309.016078) (xy 307.788054 -308.979241)
			(xy 307.826175 -308.948116) (xy 307.868796 -308.923509) (xy 307.914812 -308.906057) (xy 307.963031 -308.896213)
			(xy 308.012206 -308.894232) (xy 308.061061 -308.900164) (xy 308.108332 -308.913856) (xy 308.152794 -308.934954)
			(xy 308.193297 -308.96291) (xy 308.22879 -308.997002) (xy 308.258355 -309.036346) (xy 308.281226 -309.079923)
			(xy 308.29681 -309.126604) (xy 308.304705 -309.175181) (xy 308.3052 -309.199788) (xy 308.304705 -309.224395)
			(xy 308.304526 -309.225496) (xy 308.623204 -309.225496) (xy 308.623204 -309.17408) (xy 308.631247 -309.123298)
			(xy 308.647135 -309.074399) (xy 308.670478 -309.028587) (xy 308.700699 -308.986991) (xy 308.737055 -308.950635)
			(xy 308.778651 -308.920414) (xy 308.824463 -308.897071) (xy 308.873362 -308.881183) (xy 308.924144 -308.87314)
			(xy 308.97556 -308.87314) (xy 309.026342 -308.881183) (xy 309.075241 -308.897071) (xy 309.121053 -308.920414)
			(xy 309.162649 -308.950635) (xy 309.199005 -308.986991) (xy 309.229226 -309.028587) (xy 309.252569 -309.074399)
			(xy 309.268457 -309.123298) (xy 309.2765 -309.17408) (xy 309.277004 -309.199788) (xy 309.2765 -309.225496)
			(xy 309.573164 -309.225496) (xy 309.573164 -309.17408) (xy 309.581207 -309.123298) (xy 309.597095 -309.074399)
			(xy 309.620438 -309.028587) (xy 309.650659 -308.986991) (xy 309.687015 -308.950635) (xy 309.728611 -308.920414)
			(xy 309.774423 -308.897071) (xy 309.823322 -308.881183) (xy 309.874104 -308.87314) (xy 309.92552 -308.87314)
			(xy 309.976302 -308.881183) (xy 310.025201 -308.897071) (xy 310.071013 -308.920414) (xy 310.112609 -308.950635)
			(xy 310.148965 -308.986991) (xy 310.179186 -309.028587) (xy 310.202529 -309.074399) (xy 310.218417 -309.123298)
			(xy 310.22646 -309.17408) (xy 310.226964 -309.199788) (xy 310.543968 -309.199788) (xy 310.547928 -309.150734)
			(xy 310.559705 -309.10295) (xy 310.578996 -309.057674) (xy 310.605299 -309.016078) (xy 310.637934 -308.979241)
			(xy 310.676055 -308.948116) (xy 310.718676 -308.923509) (xy 310.764692 -308.906057) (xy 310.812911 -308.896213)
			(xy 310.862086 -308.894232) (xy 310.910941 -308.900164) (xy 310.958212 -308.913856) (xy 311.002674 -308.934954)
			(xy 311.043177 -308.96291) (xy 311.07867 -308.997002) (xy 311.108235 -309.036346) (xy 311.131106 -309.079923)
			(xy 311.14669 -309.126604) (xy 311.154585 -309.175181) (xy 311.15508 -309.199788) (xy 311.493928 -309.199788)
			(xy 311.497888 -309.150734) (xy 311.509665 -309.10295) (xy 311.528956 -309.057674) (xy 311.555259 -309.016078)
			(xy 311.587894 -308.979241) (xy 311.626015 -308.948116) (xy 311.668636 -308.923509) (xy 311.714652 -308.906057)
			(xy 311.762871 -308.896213) (xy 311.812046 -308.894232) (xy 311.860901 -308.900164) (xy 311.908172 -308.913856)
			(xy 311.952634 -308.934954) (xy 311.993137 -308.96291) (xy 312.02863 -308.997002) (xy 312.058195 -309.036346)
			(xy 312.081066 -309.079923) (xy 312.09665 -309.126604) (xy 312.104545 -309.175181) (xy 312.10504 -309.199788)
			(xy 312.443888 -309.199788) (xy 312.447848 -309.150734) (xy 312.459625 -309.10295) (xy 312.478916 -309.057674)
			(xy 312.505219 -309.016078) (xy 312.537854 -308.979241) (xy 312.575975 -308.948116) (xy 312.618596 -308.923509)
			(xy 312.664612 -308.906057) (xy 312.712831 -308.896213) (xy 312.762006 -308.894232) (xy 312.810861 -308.900164)
			(xy 312.858132 -308.913856) (xy 312.902594 -308.934954) (xy 312.943097 -308.96291) (xy 312.97859 -308.997002)
			(xy 313.008155 -309.036346) (xy 313.031026 -309.079923) (xy 313.04661 -309.126604) (xy 313.054505 -309.175181)
			(xy 313.055 -309.199788) (xy 313.394102 -309.199788) (xy 313.398062 -309.150734) (xy 313.409839 -309.10295)
			(xy 313.42913 -309.057674) (xy 313.455433 -309.016078) (xy 313.488068 -308.979241) (xy 313.526189 -308.948116)
			(xy 313.56881 -308.923509) (xy 313.614826 -308.906057) (xy 313.663045 -308.896213) (xy 313.71222 -308.894232)
			(xy 313.761075 -308.900164) (xy 313.808346 -308.913856) (xy 313.852808 -308.934954) (xy 313.893311 -308.96291)
			(xy 313.928804 -308.997002) (xy 313.958369 -309.036346) (xy 313.98124 -309.079923) (xy 313.996824 -309.126604)
			(xy 314.004719 -309.175181) (xy 314.005214 -309.199788) (xy 314.344062 -309.199788) (xy 314.348022 -309.150734)
			(xy 314.359799 -309.10295) (xy 314.37909 -309.057674) (xy 314.405393 -309.016078) (xy 314.438028 -308.979241)
			(xy 314.476149 -308.948116) (xy 314.51877 -308.923509) (xy 314.564786 -308.906057) (xy 314.613005 -308.896213)
			(xy 314.66218 -308.894232) (xy 314.711035 -308.900164) (xy 314.758306 -308.913856) (xy 314.802768 -308.934954)
			(xy 314.843271 -308.96291) (xy 314.878764 -308.997002) (xy 314.908329 -309.036346) (xy 314.9312 -309.079923)
			(xy 314.946784 -309.126604) (xy 314.954679 -309.175181) (xy 314.954694 -309.175912) (xy 320.534028 -309.175912)
			(xy 320.538099 -309.12029) (xy 320.550225 -309.065853) (xy 320.570148 -309.013762) (xy 320.597444 -308.965127)
			(xy 320.63153 -308.920984) (xy 320.671679 -308.882275) (xy 320.717037 -308.849824) (xy 320.766637 -308.824323)
			(xy 320.819421 -308.806316) (xy 320.874264 -308.796186) (xy 320.929998 -308.794149) (xy 320.985435 -308.800249)
			(xy 321.039392 -308.814355) (xy 321.090721 -308.836167) (xy 321.138327 -308.865221) (xy 321.181195 -308.900896)
			(xy 321.218412 -308.942433) (xy 321.249185 -308.988946) (xy 321.272857 -309.039443) (xy 321.288925 -309.09285)
			(xy 321.297045 -309.148026) (xy 321.297554 -309.175912) (xy 321.297045 -309.203798) (xy 321.288925 -309.258974)
			(xy 321.272857 -309.312381) (xy 321.249185 -309.362878) (xy 321.218412 -309.409391) (xy 321.181195 -309.450928)
			(xy 321.138327 -309.486603) (xy 321.090721 -309.515657) (xy 321.039392 -309.537469) (xy 320.985435 -309.551575)
			(xy 320.929998 -309.557675) (xy 320.874264 -309.555638) (xy 320.819421 -309.545508) (xy 320.766637 -309.527501)
			(xy 320.717037 -309.502) (xy 320.671679 -309.469549) (xy 320.63153 -309.43084) (xy 320.597444 -309.386697)
			(xy 320.570148 -309.338062) (xy 320.550225 -309.285971) (xy 320.538099 -309.231534) (xy 320.534028 -309.175912)
			(xy 314.954694 -309.175912) (xy 314.955174 -309.199788) (xy 314.954679 -309.224395) (xy 314.946784 -309.272972)
			(xy 314.9312 -309.319653) (xy 314.908329 -309.36323) (xy 314.878764 -309.402574) (xy 314.843271 -309.436666)
			(xy 314.802768 -309.464622) (xy 314.758306 -309.48572) (xy 314.711035 -309.499412) (xy 314.66218 -309.505344)
			(xy 314.613005 -309.503363) (xy 314.564786 -309.493519) (xy 314.51877 -309.476067) (xy 314.476149 -309.45146)
			(xy 314.438028 -309.420335) (xy 314.405393 -309.383498) (xy 314.37909 -309.341902) (xy 314.359799 -309.296626)
			(xy 314.348022 -309.248842) (xy 314.344062 -309.199788) (xy 314.005214 -309.199788) (xy 314.004719 -309.224395)
			(xy 313.996824 -309.272972) (xy 313.98124 -309.319653) (xy 313.958369 -309.36323) (xy 313.928804 -309.402574)
			(xy 313.893311 -309.436666) (xy 313.852808 -309.464622) (xy 313.808346 -309.48572) (xy 313.761075 -309.499412)
			(xy 313.71222 -309.505344) (xy 313.663045 -309.503363) (xy 313.614826 -309.493519) (xy 313.56881 -309.476067)
			(xy 313.526189 -309.45146) (xy 313.488068 -309.420335) (xy 313.455433 -309.383498) (xy 313.42913 -309.341902)
			(xy 313.409839 -309.296626) (xy 313.398062 -309.248842) (xy 313.394102 -309.199788) (xy 313.055 -309.199788)
			(xy 313.054505 -309.224395) (xy 313.04661 -309.272972) (xy 313.031026 -309.319653) (xy 313.008155 -309.36323)
			(xy 312.97859 -309.402574) (xy 312.943097 -309.436666) (xy 312.902594 -309.464622) (xy 312.858132 -309.48572)
			(xy 312.810861 -309.499412) (xy 312.762006 -309.505344) (xy 312.712831 -309.503363) (xy 312.664612 -309.493519)
			(xy 312.618596 -309.476067) (xy 312.575975 -309.45146) (xy 312.537854 -309.420335) (xy 312.505219 -309.383498)
			(xy 312.478916 -309.341902) (xy 312.459625 -309.296626) (xy 312.447848 -309.248842) (xy 312.443888 -309.199788)
			(xy 312.10504 -309.199788) (xy 312.104545 -309.224395) (xy 312.09665 -309.272972) (xy 312.081066 -309.319653)
			(xy 312.058195 -309.36323) (xy 312.02863 -309.402574) (xy 311.993137 -309.436666) (xy 311.952634 -309.464622)
			(xy 311.908172 -309.48572) (xy 311.860901 -309.499412) (xy 311.812046 -309.505344) (xy 311.762871 -309.503363)
			(xy 311.714652 -309.493519) (xy 311.668636 -309.476067) (xy 311.626015 -309.45146) (xy 311.587894 -309.420335)
			(xy 311.555259 -309.383498) (xy 311.528956 -309.341902) (xy 311.509665 -309.296626) (xy 311.497888 -309.248842)
			(xy 311.493928 -309.199788) (xy 311.15508 -309.199788) (xy 311.154585 -309.224395) (xy 311.14669 -309.272972)
			(xy 311.131106 -309.319653) (xy 311.108235 -309.36323) (xy 311.07867 -309.402574) (xy 311.043177 -309.436666)
			(xy 311.002674 -309.464622) (xy 310.958212 -309.48572) (xy 310.910941 -309.499412) (xy 310.862086 -309.505344)
			(xy 310.812911 -309.503363) (xy 310.764692 -309.493519) (xy 310.718676 -309.476067) (xy 310.676055 -309.45146)
			(xy 310.637934 -309.420335) (xy 310.605299 -309.383498) (xy 310.578996 -309.341902) (xy 310.559705 -309.296626)
			(xy 310.547928 -309.248842) (xy 310.543968 -309.199788) (xy 310.226964 -309.199788) (xy 310.22646 -309.225496)
			(xy 310.218417 -309.276278) (xy 310.202529 -309.325177) (xy 310.179186 -309.370989) (xy 310.148965 -309.412585)
			(xy 310.112609 -309.448941) (xy 310.071013 -309.479162) (xy 310.025201 -309.502505) (xy 309.976302 -309.518393)
			(xy 309.92552 -309.526436) (xy 309.874104 -309.526436) (xy 309.823322 -309.518393) (xy 309.774423 -309.502505)
			(xy 309.728611 -309.479162) (xy 309.687015 -309.448941) (xy 309.650659 -309.412585) (xy 309.620438 -309.370989)
			(xy 309.597095 -309.325177) (xy 309.581207 -309.276278) (xy 309.573164 -309.225496) (xy 309.2765 -309.225496)
			(xy 309.268457 -309.276278) (xy 309.252569 -309.325177) (xy 309.229226 -309.370989) (xy 309.199005 -309.412585)
			(xy 309.162649 -309.448941) (xy 309.121053 -309.479162) (xy 309.075241 -309.502505) (xy 309.026342 -309.518393)
			(xy 308.97556 -309.526436) (xy 308.924144 -309.526436) (xy 308.873362 -309.518393) (xy 308.824463 -309.502505)
			(xy 308.778651 -309.479162) (xy 308.737055 -309.448941) (xy 308.700699 -309.412585) (xy 308.670478 -309.370989)
			(xy 308.647135 -309.325177) (xy 308.631247 -309.276278) (xy 308.623204 -309.225496) (xy 308.304526 -309.225496)
			(xy 308.29681 -309.272972) (xy 308.281226 -309.319653) (xy 308.258355 -309.36323) (xy 308.22879 -309.402574)
			(xy 308.193297 -309.436666) (xy 308.152794 -309.464622) (xy 308.108332 -309.48572) (xy 308.061061 -309.499412)
			(xy 308.012206 -309.505344) (xy 307.963031 -309.503363) (xy 307.914812 -309.493519) (xy 307.868796 -309.476067)
			(xy 307.826175 -309.45146) (xy 307.788054 -309.420335) (xy 307.755419 -309.383498) (xy 307.729116 -309.341902)
			(xy 307.709825 -309.296626) (xy 307.698048 -309.248842) (xy 307.694088 -309.199788) (xy 307.35524 -309.199788)
			(xy 307.354745 -309.224395) (xy 307.34685 -309.272972) (xy 307.331266 -309.319653) (xy 307.308395 -309.36323)
			(xy 307.27883 -309.402574) (xy 307.243337 -309.436666) (xy 307.202834 -309.464622) (xy 307.158372 -309.48572)
			(xy 307.111101 -309.499412) (xy 307.062246 -309.505344) (xy 307.013071 -309.503363) (xy 306.964852 -309.493519)
			(xy 306.918836 -309.476067) (xy 306.876215 -309.45146) (xy 306.838094 -309.420335) (xy 306.805459 -309.383498)
			(xy 306.779156 -309.341902) (xy 306.759865 -309.296626) (xy 306.748088 -309.248842) (xy 306.744128 -309.199788)
			(xy 306.405026 -309.199788) (xy 306.404531 -309.224395) (xy 306.396636 -309.272972) (xy 306.381052 -309.319653)
			(xy 306.358181 -309.36323) (xy 306.328616 -309.402574) (xy 306.293123 -309.436666) (xy 306.25262 -309.464622)
			(xy 306.208158 -309.48572) (xy 306.160887 -309.499412) (xy 306.112032 -309.505344) (xy 306.062857 -309.503363)
			(xy 306.014638 -309.493519) (xy 305.968622 -309.476067) (xy 305.926001 -309.45146) (xy 305.88788 -309.420335)
			(xy 305.855245 -309.383498) (xy 305.828942 -309.341902) (xy 305.809651 -309.296626) (xy 305.797874 -309.248842)
			(xy 305.793914 -309.199788) (xy 294.055038 -309.199788) (xy 294.054516 -309.225043) (xy 294.046203 -309.274865)
			(xy 294.029802 -309.322639) (xy 294.005761 -309.367062) (xy 293.974737 -309.406922) (xy 293.937575 -309.441132)
			(xy 293.895289 -309.468758) (xy 293.849033 -309.489048) (xy 293.800068 -309.501448) (xy 293.74973 -309.505619)
			(xy 293.699392 -309.501448) (xy 293.650427 -309.489048) (xy 293.604171 -309.468758) (xy 293.561885 -309.441132)
			(xy 293.524723 -309.406922) (xy 293.493699 -309.367062) (xy 293.469658 -309.322639) (xy 293.453257 -309.274865)
			(xy 293.444944 -309.225043) (xy 293.444422 -309.199788) (xy 293.444596 -309.185605) (xy 293.44727 -309.157365)
			(xy 293.449756 -309.1434) (xy 293.452042 -309.130954) (xy 293.444676 -309.107332) (xy 293.367206 -309.029862)
			(xy 293.343584 -309.022496) (xy 293.331138 -309.024782) (xy 293.317173 -309.027263) (xy 293.288933 -309.029932)
			(xy 293.27475 -309.030116) (xy 293.260567 -309.029932) (xy 293.232327 -309.027265) (xy 293.218362 -309.024782)
			(xy 293.205916 -309.022496) (xy 293.182294 -309.029862) (xy 293.104824 -309.107332) (xy 293.097458 -309.130954)
			(xy 293.099744 -309.1434) (xy 293.102216 -309.157367) (xy 293.104891 -309.185606) (xy 293.105078 -309.199788)
			(xy 293.104556 -309.225043) (xy 293.096243 -309.274865) (xy 293.079842 -309.322639) (xy 293.055801 -309.367062)
			(xy 293.024777 -309.406922) (xy 292.987615 -309.441132) (xy 292.945329 -309.468758) (xy 292.899073 -309.489048)
			(xy 292.850108 -309.501448) (xy 292.79977 -309.505619) (xy 292.749432 -309.501448) (xy 292.700467 -309.489048)
			(xy 292.654211 -309.468758) (xy 292.611925 -309.441132) (xy 292.574763 -309.406922) (xy 292.543739 -309.367062)
			(xy 292.519698 -309.322639) (xy 292.503297 -309.274865) (xy 292.494984 -309.225043) (xy 292.494462 -309.199788)
			(xy 292.494637 -309.185605) (xy 292.49731 -309.157365) (xy 292.499796 -309.1434) (xy 292.502082 -309.130954)
			(xy 292.494716 -309.107332) (xy 292.417246 -309.029862) (xy 292.393624 -309.022496) (xy 292.381178 -309.024782)
			(xy 292.367212 -309.027257) (xy 292.338972 -309.02993) (xy 292.32479 -309.030116) (xy 292.29997 -309.029611)
			(xy 292.250984 -309.021579) (xy 292.203943 -309.005727) (xy 292.160086 -308.982474) (xy 292.120569 -308.952432)
			(xy 292.086433 -308.916392) (xy 292.058577 -308.875305) (xy 292.037735 -308.830252) (xy 292.024456 -308.782421)
			(xy 292.019091 -308.733072) (xy 290.730012 -308.733072) (xy 290.729683 -308.749415) (xy 290.721788 -308.797992)
			(xy 290.706204 -308.844673) (xy 290.683333 -308.88825) (xy 290.653768 -308.927594) (xy 290.618275 -308.961686)
			(xy 290.577772 -308.989642) (xy 290.53331 -309.01074) (xy 290.486039 -309.024432) (xy 290.437184 -309.030364)
			(xy 290.388009 -309.028383) (xy 290.33979 -309.018539) (xy 290.293774 -309.001087) (xy 290.251153 -308.97648)
			(xy 290.213032 -308.945355) (xy 290.180397 -308.908518) (xy 290.154094 -308.866922) (xy 290.134803 -308.821646)
			(xy 290.123026 -308.773862) (xy 290.119066 -308.724808) (xy 288.830122 -308.724808) (xy 288.83057 -308.733044)
			(xy 288.82521 -308.782386) (xy 288.811938 -308.830211) (xy 288.791104 -308.875258) (xy 288.763256 -308.916342)
			(xy 288.729129 -308.95238) (xy 288.689622 -308.982421) (xy 288.645775 -309.005676) (xy 288.598743 -309.021531)
			(xy 288.549766 -309.029568) (xy 288.52495 -309.030116) (xy 288.510704 -309.029938) (xy 288.482337 -309.027266)
			(xy 288.468308 -309.024782) (xy 288.456116 -309.022496) (xy 288.431986 -309.029862) (xy 288.35477 -309.107078)
			(xy 288.347404 -309.130954) (xy 288.34969 -309.1434) (xy 288.352176 -309.157365) (xy 288.354849 -309.185605)
			(xy 288.355024 -309.199788) (xy 288.354925 -309.208892) (xy 288.353778 -309.227065) (xy 288.352738 -309.23611)
			(xy 288.351468 -309.248302) (xy 288.359342 -309.270654) (xy 288.435796 -309.343552) (xy 288.458402 -309.350664)
			(xy 288.47034 -309.348632) (xy 288.483828 -309.346501) (xy 288.511041 -309.344213) (xy 288.524696 -309.34406)
			(xy 288.550684 -309.344569) (xy 288.602021 -309.352699) (xy 288.651454 -309.368759) (xy 288.697767 -309.392354)
			(xy 288.739818 -309.422904) (xy 288.776573 -309.459655) (xy 288.807127 -309.501703) (xy 288.830727 -309.548012)
			(xy 288.846792 -309.597444) (xy 288.854928 -309.64878) (xy 288.855404 -309.674768) (xy 288.855404 -309.682642)
			(xy 288.854896 -309.698644) (xy 288.872422 -309.725314) (xy 288.897568 -309.735474) (xy 288.904172 -309.738268)
			(xy 288.918396 -309.74411) (xy 288.951924 -309.760112) (xy 288.982912 -309.776114) (xy 288.9885 -309.779162)
			(xy 289.000438 -309.78221) (xy 289.028632 -309.78221) (xy 289.031426 -309.78221) (xy 289.045142 -309.779416)
			(xy 289.055302 -309.77459) (xy 289.1155 -309.73776) (xy 289.118294 -309.735982) (xy 289.135058 -309.72252)
			(xy 289.144964 -309.700676) (xy 289.144456 -309.688738) (xy 289.144202 -309.674768) (xy 289.144712 -309.648781)
			(xy 289.152842 -309.597446) (xy 289.168903 -309.548016) (xy 289.192499 -309.501706) (xy 289.223049 -309.459658)
			(xy 289.2598 -309.422907) (xy 289.301848 -309.392357) (xy 289.348158 -309.368761) (xy 289.397588 -309.3527)
			(xy 289.448923 -309.34457) (xy 289.500897 -309.34457) (xy 289.552232 -309.3527) (xy 289.601662 -309.368761)
			(xy 289.647972 -309.392357) (xy 289.69002 -309.422907) (xy 289.726771 -309.459658) (xy 289.757321 -309.501706)
			(xy 289.780917 -309.548016) (xy 289.796978 -309.597446) (xy 289.805108 -309.648781) (xy 289.805618 -309.674768)
			(xy 289.805456 -309.688422) (xy 289.803167 -309.715635) (xy 289.801046 -309.729124) (xy 289.799014 -309.741062)
			(xy 289.806126 -309.763668) (xy 289.879024 -309.840122) (xy 289.901376 -309.847996) (xy 289.913568 -309.846726)
			(xy 289.922612 -309.845677) (xy 289.940786 -309.844533) (xy 289.94989 -309.84444) (xy 289.975144 -309.844932)
			(xy 290.024964 -309.853244) (xy 290.072737 -309.869643) (xy 290.117158 -309.893681) (xy 290.157017 -309.924703)
			(xy 290.191226 -309.961863) (xy 290.218852 -310.004147) (xy 290.239142 -310.050401) (xy 290.251541 -310.099364)
			(xy 290.255712 -310.1497) (xy 290.255708 -310.149748) (xy 290.594046 -310.149748) (xy 290.598006 -310.100694)
			(xy 290.609783 -310.05291) (xy 290.629074 -310.007634) (xy 290.655377 -309.966038) (xy 290.688012 -309.929201)
			(xy 290.726133 -309.898076) (xy 290.768754 -309.873469) (xy 290.81477 -309.856017) (xy 290.862989 -309.846173)
			(xy 290.912164 -309.844192) (xy 290.961019 -309.850124) (xy 291.00829 -309.863816) (xy 291.052752 -309.884914)
			(xy 291.093255 -309.91287) (xy 291.128748 -309.946962) (xy 291.158313 -309.986306) (xy 291.181184 -310.029883)
			(xy 291.196768 -310.076564) (xy 291.204663 -310.125141) (xy 291.205158 -310.149748) (xy 291.544006 -310.149748)
			(xy 291.547966 -310.100694) (xy 291.559743 -310.05291) (xy 291.579034 -310.007634) (xy 291.605337 -309.966038)
			(xy 291.637972 -309.929201) (xy 291.676093 -309.898076) (xy 291.718714 -309.873469) (xy 291.76473 -309.856017)
			(xy 291.812949 -309.846173) (xy 291.862124 -309.844192) (xy 291.910979 -309.850124) (xy 291.95825 -309.863816)
			(xy 292.002712 -309.884914) (xy 292.043215 -309.91287) (xy 292.078708 -309.946962) (xy 292.108273 -309.986306)
			(xy 292.131144 -310.029883) (xy 292.146728 -310.076564) (xy 292.154623 -310.125141) (xy 292.155118 -310.149748)
			(xy 292.493966 -310.149748) (xy 292.497926 -310.100694) (xy 292.509703 -310.05291) (xy 292.528994 -310.007634)
			(xy 292.555297 -309.966038) (xy 292.587932 -309.929201) (xy 292.626053 -309.898076) (xy 292.668674 -309.873469)
			(xy 292.71469 -309.856017) (xy 292.762909 -309.846173) (xy 292.812084 -309.844192) (xy 292.860939 -309.850124)
			(xy 292.90821 -309.863816) (xy 292.952672 -309.884914) (xy 292.993175 -309.91287) (xy 293.028668 -309.946962)
			(xy 293.058233 -309.986306) (xy 293.081104 -310.029883) (xy 293.096688 -310.076564) (xy 293.104583 -310.125141)
			(xy 293.105078 -310.149748) (xy 293.443926 -310.149748) (xy 293.447886 -310.100694) (xy 293.459663 -310.05291)
			(xy 293.478954 -310.007634) (xy 293.505257 -309.966038) (xy 293.537892 -309.929201) (xy 293.576013 -309.898076)
			(xy 293.618634 -309.873469) (xy 293.66465 -309.856017) (xy 293.712869 -309.846173) (xy 293.762044 -309.844192)
			(xy 293.810899 -309.850124) (xy 293.85817 -309.863816) (xy 293.902632 -309.884914) (xy 293.943135 -309.91287)
			(xy 293.978628 -309.946962) (xy 294.008193 -309.986306) (xy 294.031064 -310.029883) (xy 294.046648 -310.076564)
			(xy 294.054543 -310.125141) (xy 294.055038 -310.149748) (xy 294.393886 -310.149748) (xy 294.397846 -310.100694)
			(xy 294.409623 -310.05291) (xy 294.428914 -310.007634) (xy 294.455217 -309.966038) (xy 294.487852 -309.929201)
			(xy 294.525973 -309.898076) (xy 294.568594 -309.873469) (xy 294.61461 -309.856017) (xy 294.662829 -309.846173)
			(xy 294.712004 -309.844192) (xy 294.760859 -309.850124) (xy 294.80813 -309.863816) (xy 294.852592 -309.884914)
			(xy 294.893095 -309.91287) (xy 294.928588 -309.946962) (xy 294.958153 -309.986306) (xy 294.981024 -310.029883)
			(xy 294.996608 -310.076564) (xy 295.004503 -310.125141) (xy 295.004998 -310.149748) (xy 295.3441 -310.149748)
			(xy 295.34806 -310.100694) (xy 295.359837 -310.05291) (xy 295.379128 -310.007634) (xy 295.405431 -309.966038)
			(xy 295.438066 -309.929201) (xy 295.476187 -309.898076) (xy 295.518808 -309.873469) (xy 295.564824 -309.856017)
			(xy 295.613043 -309.846173) (xy 295.662218 -309.844192) (xy 295.711073 -309.850124) (xy 295.758344 -309.863816)
			(xy 295.802806 -309.884914) (xy 295.843309 -309.91287) (xy 295.878802 -309.946962) (xy 295.908367 -309.986306)
			(xy 295.931238 -310.029883) (xy 295.946822 -310.076564) (xy 295.954717 -310.125141) (xy 295.955212 -310.149748)
			(xy 296.29406 -310.149748) (xy 296.29802 -310.100694) (xy 296.309797 -310.05291) (xy 296.329088 -310.007634)
			(xy 296.355391 -309.966038) (xy 296.388026 -309.929201) (xy 296.426147 -309.898076) (xy 296.468768 -309.873469)
			(xy 296.514784 -309.856017) (xy 296.563003 -309.846173) (xy 296.612178 -309.844192) (xy 296.661033 -309.850124)
			(xy 296.708304 -309.863816) (xy 296.752766 -309.884914) (xy 296.793269 -309.91287) (xy 296.828762 -309.946962)
			(xy 296.858327 -309.986306) (xy 296.881198 -310.029883) (xy 296.896782 -310.076564) (xy 296.904677 -310.125141)
			(xy 296.905172 -310.149748) (xy 297.24402 -310.149748) (xy 297.24798 -310.100694) (xy 297.259757 -310.05291)
			(xy 297.279048 -310.007634) (xy 297.305351 -309.966038) (xy 297.337986 -309.929201) (xy 297.376107 -309.898076)
			(xy 297.418728 -309.873469) (xy 297.464744 -309.856017) (xy 297.512963 -309.846173) (xy 297.562138 -309.844192)
			(xy 297.610993 -309.850124) (xy 297.658264 -309.863816) (xy 297.702726 -309.884914) (xy 297.743229 -309.91287)
			(xy 297.778722 -309.946962) (xy 297.808287 -309.986306) (xy 297.831158 -310.029883) (xy 297.846742 -310.076564)
			(xy 297.854637 -310.125141) (xy 297.855132 -310.149748) (xy 298.19398 -310.149748) (xy 298.19794 -310.100694)
			(xy 298.209717 -310.05291) (xy 298.229008 -310.007634) (xy 298.255311 -309.966038) (xy 298.287946 -309.929201)
			(xy 298.326067 -309.898076) (xy 298.368688 -309.873469) (xy 298.414704 -309.856017) (xy 298.462923 -309.846173)
			(xy 298.512098 -309.844192) (xy 298.560953 -309.850124) (xy 298.608224 -309.863816) (xy 298.652686 -309.884914)
			(xy 298.693189 -309.91287) (xy 298.728682 -309.946962) (xy 298.758247 -309.986306) (xy 298.781118 -310.029883)
			(xy 298.796702 -310.076564) (xy 298.804597 -310.125141) (xy 298.805092 -310.149748) (xy 299.14394 -310.149748)
			(xy 299.1479 -310.100694) (xy 299.159677 -310.05291) (xy 299.178968 -310.007634) (xy 299.205271 -309.966038)
			(xy 299.237906 -309.929201) (xy 299.276027 -309.898076) (xy 299.318648 -309.873469) (xy 299.364664 -309.856017)
			(xy 299.412883 -309.846173) (xy 299.462058 -309.844192) (xy 299.510913 -309.850124) (xy 299.558184 -309.863816)
			(xy 299.602646 -309.884914) (xy 299.643149 -309.91287) (xy 299.678642 -309.946962) (xy 299.708207 -309.986306)
			(xy 299.731078 -310.029883) (xy 299.746662 -310.076564) (xy 299.754557 -310.125141) (xy 299.755052 -310.149748)
			(xy 300.0939 -310.149748) (xy 300.09786 -310.100694) (xy 300.109637 -310.05291) (xy 300.128928 -310.007634)
			(xy 300.155231 -309.966038) (xy 300.187866 -309.929201) (xy 300.225987 -309.898076) (xy 300.268608 -309.873469)
			(xy 300.314624 -309.856017) (xy 300.362843 -309.846173) (xy 300.412018 -309.844192) (xy 300.460873 -309.850124)
			(xy 300.508144 -309.863816) (xy 300.552606 -309.884914) (xy 300.593109 -309.91287) (xy 300.628602 -309.946962)
			(xy 300.658167 -309.986306) (xy 300.681038 -310.029883) (xy 300.696622 -310.076564) (xy 300.704517 -310.125141)
			(xy 300.705012 -310.149748) (xy 301.044114 -310.149748) (xy 301.048074 -310.100694) (xy 301.059851 -310.05291)
			(xy 301.079142 -310.007634) (xy 301.105445 -309.966038) (xy 301.13808 -309.929201) (xy 301.176201 -309.898076)
			(xy 301.218822 -309.873469) (xy 301.264838 -309.856017) (xy 301.313057 -309.846173) (xy 301.362232 -309.844192)
			(xy 301.411087 -309.850124) (xy 301.458358 -309.863816) (xy 301.50282 -309.884914) (xy 301.543323 -309.91287)
			(xy 301.578816 -309.946962) (xy 301.608381 -309.986306) (xy 301.631252 -310.029883) (xy 301.646836 -310.076564)
			(xy 301.654731 -310.125141) (xy 301.655226 -310.149748) (xy 301.994074 -310.149748) (xy 301.998034 -310.100694)
			(xy 302.009811 -310.05291) (xy 302.029102 -310.007634) (xy 302.055405 -309.966038) (xy 302.08804 -309.929201)
			(xy 302.126161 -309.898076) (xy 302.168782 -309.873469) (xy 302.214798 -309.856017) (xy 302.263017 -309.846173)
			(xy 302.312192 -309.844192) (xy 302.361047 -309.850124) (xy 302.408318 -309.863816) (xy 302.45278 -309.884914)
			(xy 302.493283 -309.91287) (xy 302.528776 -309.946962) (xy 302.558341 -309.986306) (xy 302.581212 -310.029883)
			(xy 302.596796 -310.076564) (xy 302.604691 -310.125141) (xy 302.605186 -310.149748) (xy 302.944034 -310.149748)
			(xy 302.947994 -310.100694) (xy 302.959771 -310.05291) (xy 302.979062 -310.007634) (xy 303.005365 -309.966038)
			(xy 303.038 -309.929201) (xy 303.076121 -309.898076) (xy 303.118742 -309.873469) (xy 303.164758 -309.856017)
			(xy 303.212977 -309.846173) (xy 303.262152 -309.844192) (xy 303.311007 -309.850124) (xy 303.358278 -309.863816)
			(xy 303.40274 -309.884914) (xy 303.443243 -309.91287) (xy 303.478736 -309.946962) (xy 303.508301 -309.986306)
			(xy 303.531172 -310.029883) (xy 303.546756 -310.076564) (xy 303.554651 -310.125141) (xy 303.555146 -310.149748)
			(xy 303.893994 -310.149748) (xy 303.897954 -310.100694) (xy 303.909731 -310.05291) (xy 303.929022 -310.007634)
			(xy 303.955325 -309.966038) (xy 303.98796 -309.929201) (xy 304.026081 -309.898076) (xy 304.068702 -309.873469)
			(xy 304.114718 -309.856017) (xy 304.162937 -309.846173) (xy 304.212112 -309.844192) (xy 304.260967 -309.850124)
			(xy 304.308238 -309.863816) (xy 304.3527 -309.884914) (xy 304.393203 -309.91287) (xy 304.428696 -309.946962)
			(xy 304.458261 -309.986306) (xy 304.481132 -310.029883) (xy 304.496716 -310.076564) (xy 304.504611 -310.125141)
			(xy 304.505106 -310.149748) (xy 304.843954 -310.149748) (xy 304.847914 -310.100694) (xy 304.859691 -310.05291)
			(xy 304.878982 -310.007634) (xy 304.905285 -309.966038) (xy 304.93792 -309.929201) (xy 304.976041 -309.898076)
			(xy 305.018662 -309.873469) (xy 305.064678 -309.856017) (xy 305.112897 -309.846173) (xy 305.162072 -309.844192)
			(xy 305.210927 -309.850124) (xy 305.258198 -309.863816) (xy 305.30266 -309.884914) (xy 305.343163 -309.91287)
			(xy 305.378656 -309.946962) (xy 305.408221 -309.986306) (xy 305.431092 -310.029883) (xy 305.446676 -310.076564)
			(xy 305.454571 -310.125141) (xy 305.455066 -310.149748) (xy 305.793914 -310.149748) (xy 305.797874 -310.100694)
			(xy 305.809651 -310.05291) (xy 305.828942 -310.007634) (xy 305.855245 -309.966038) (xy 305.88788 -309.929201)
			(xy 305.926001 -309.898076) (xy 305.968622 -309.873469) (xy 306.014638 -309.856017) (xy 306.062857 -309.846173)
			(xy 306.112032 -309.844192) (xy 306.160887 -309.850124) (xy 306.208158 -309.863816) (xy 306.25262 -309.884914)
			(xy 306.293123 -309.91287) (xy 306.328616 -309.946962) (xy 306.358181 -309.986306) (xy 306.381052 -310.029883)
			(xy 306.396636 -310.076564) (xy 306.404531 -310.125141) (xy 306.405026 -310.149748) (xy 306.744128 -310.149748)
			(xy 306.748088 -310.100694) (xy 306.759865 -310.05291) (xy 306.779156 -310.007634) (xy 306.805459 -309.966038)
			(xy 306.838094 -309.929201) (xy 306.876215 -309.898076) (xy 306.918836 -309.873469) (xy 306.964852 -309.856017)
			(xy 307.013071 -309.846173) (xy 307.062246 -309.844192) (xy 307.111101 -309.850124) (xy 307.158372 -309.863816)
			(xy 307.202834 -309.884914) (xy 307.243337 -309.91287) (xy 307.27883 -309.946962) (xy 307.308395 -309.986306)
			(xy 307.331266 -310.029883) (xy 307.34685 -310.076564) (xy 307.354745 -310.125141) (xy 307.35524 -310.149748)
			(xy 307.694088 -310.149748) (xy 307.698048 -310.100694) (xy 307.709825 -310.05291) (xy 307.729116 -310.007634)
			(xy 307.755419 -309.966038) (xy 307.788054 -309.929201) (xy 307.826175 -309.898076) (xy 307.868796 -309.873469)
			(xy 307.914812 -309.856017) (xy 307.963031 -309.846173) (xy 308.012206 -309.844192) (xy 308.061061 -309.850124)
			(xy 308.108332 -309.863816) (xy 308.152794 -309.884914) (xy 308.193297 -309.91287) (xy 308.22879 -309.946962)
			(xy 308.258355 -309.986306) (xy 308.281226 -310.029883) (xy 308.29681 -310.076564) (xy 308.304705 -310.125141)
			(xy 308.3052 -310.149748) (xy 308.644048 -310.149748) (xy 308.648008 -310.100694) (xy 308.659785 -310.05291)
			(xy 308.679076 -310.007634) (xy 308.705379 -309.966038) (xy 308.738014 -309.929201) (xy 308.776135 -309.898076)
			(xy 308.818756 -309.873469) (xy 308.864772 -309.856017) (xy 308.912991 -309.846173) (xy 308.962166 -309.844192)
			(xy 309.011021 -309.850124) (xy 309.058292 -309.863816) (xy 309.102754 -309.884914) (xy 309.143257 -309.91287)
			(xy 309.17875 -309.946962) (xy 309.208315 -309.986306) (xy 309.231186 -310.029883) (xy 309.24677 -310.076564)
			(xy 309.254665 -310.125141) (xy 309.25516 -310.149748) (xy 309.594008 -310.149748) (xy 309.597968 -310.100694)
			(xy 309.609745 -310.05291) (xy 309.629036 -310.007634) (xy 309.655339 -309.966038) (xy 309.687974 -309.929201)
			(xy 309.726095 -309.898076) (xy 309.768716 -309.873469) (xy 309.814732 -309.856017) (xy 309.862951 -309.846173)
			(xy 309.912126 -309.844192) (xy 309.960981 -309.850124) (xy 310.008252 -309.863816) (xy 310.052714 -309.884914)
			(xy 310.093217 -309.91287) (xy 310.12871 -309.946962) (xy 310.158275 -309.986306) (xy 310.181146 -310.029883)
			(xy 310.19673 -310.076564) (xy 310.204625 -310.125141) (xy 310.20512 -310.149748) (xy 310.204625 -310.174355)
			(xy 310.19673 -310.222932) (xy 310.181146 -310.269613) (xy 310.158275 -310.31319) (xy 310.12871 -310.352534)
			(xy 310.093217 -310.386626) (xy 310.052714 -310.414582) (xy 310.008252 -310.43568) (xy 309.960981 -310.449372)
			(xy 309.912126 -310.455304) (xy 309.862951 -310.453323) (xy 309.814732 -310.443479) (xy 309.768716 -310.426027)
			(xy 309.726095 -310.40142) (xy 309.687974 -310.370295) (xy 309.655339 -310.333458) (xy 309.629036 -310.291862)
			(xy 309.609745 -310.246586) (xy 309.597968 -310.198802) (xy 309.594008 -310.149748) (xy 309.25516 -310.149748)
			(xy 309.254665 -310.174355) (xy 309.24677 -310.222932) (xy 309.231186 -310.269613) (xy 309.208315 -310.31319)
			(xy 309.17875 -310.352534) (xy 309.143257 -310.386626) (xy 309.102754 -310.414582) (xy 309.058292 -310.43568)
			(xy 309.011021 -310.449372) (xy 308.962166 -310.455304) (xy 308.912991 -310.453323) (xy 308.864772 -310.443479)
			(xy 308.818756 -310.426027) (xy 308.776135 -310.40142) (xy 308.738014 -310.370295) (xy 308.705379 -310.333458)
			(xy 308.679076 -310.291862) (xy 308.659785 -310.246586) (xy 308.648008 -310.198802) (xy 308.644048 -310.149748)
			(xy 308.3052 -310.149748) (xy 308.304705 -310.174355) (xy 308.29681 -310.222932) (xy 308.281226 -310.269613)
			(xy 308.258355 -310.31319) (xy 308.22879 -310.352534) (xy 308.193297 -310.386626) (xy 308.152794 -310.414582)
			(xy 308.108332 -310.43568) (xy 308.061061 -310.449372) (xy 308.012206 -310.455304) (xy 307.963031 -310.453323)
			(xy 307.914812 -310.443479) (xy 307.868796 -310.426027) (xy 307.826175 -310.40142) (xy 307.788054 -310.370295)
			(xy 307.755419 -310.333458) (xy 307.729116 -310.291862) (xy 307.709825 -310.246586) (xy 307.698048 -310.198802)
			(xy 307.694088 -310.149748) (xy 307.35524 -310.149748) (xy 307.354745 -310.174355) (xy 307.34685 -310.222932)
			(xy 307.331266 -310.269613) (xy 307.308395 -310.31319) (xy 307.27883 -310.352534) (xy 307.243337 -310.386626)
			(xy 307.202834 -310.414582) (xy 307.158372 -310.43568) (xy 307.111101 -310.449372) (xy 307.062246 -310.455304)
			(xy 307.013071 -310.453323) (xy 306.964852 -310.443479) (xy 306.918836 -310.426027) (xy 306.876215 -310.40142)
			(xy 306.838094 -310.370295) (xy 306.805459 -310.333458) (xy 306.779156 -310.291862) (xy 306.759865 -310.246586)
			(xy 306.748088 -310.198802) (xy 306.744128 -310.149748) (xy 306.405026 -310.149748) (xy 306.404531 -310.174355)
			(xy 306.396636 -310.222932) (xy 306.381052 -310.269613) (xy 306.358181 -310.31319) (xy 306.328616 -310.352534)
			(xy 306.293123 -310.386626) (xy 306.25262 -310.414582) (xy 306.208158 -310.43568) (xy 306.160887 -310.449372)
			(xy 306.112032 -310.455304) (xy 306.062857 -310.453323) (xy 306.014638 -310.443479) (xy 305.968622 -310.426027)
			(xy 305.926001 -310.40142) (xy 305.88788 -310.370295) (xy 305.855245 -310.333458) (xy 305.828942 -310.291862)
			(xy 305.809651 -310.246586) (xy 305.797874 -310.198802) (xy 305.793914 -310.149748) (xy 305.455066 -310.149748)
			(xy 305.454571 -310.174355) (xy 305.446676 -310.222932) (xy 305.431092 -310.269613) (xy 305.408221 -310.31319)
			(xy 305.378656 -310.352534) (xy 305.343163 -310.386626) (xy 305.30266 -310.414582) (xy 305.258198 -310.43568)
			(xy 305.210927 -310.449372) (xy 305.162072 -310.455304) (xy 305.112897 -310.453323) (xy 305.064678 -310.443479)
			(xy 305.018662 -310.426027) (xy 304.976041 -310.40142) (xy 304.93792 -310.370295) (xy 304.905285 -310.333458)
			(xy 304.878982 -310.291862) (xy 304.859691 -310.246586) (xy 304.847914 -310.198802) (xy 304.843954 -310.149748)
			(xy 304.505106 -310.149748) (xy 304.504611 -310.174355) (xy 304.496716 -310.222932) (xy 304.481132 -310.269613)
			(xy 304.458261 -310.31319) (xy 304.428696 -310.352534) (xy 304.393203 -310.386626) (xy 304.3527 -310.414582)
			(xy 304.308238 -310.43568) (xy 304.260967 -310.449372) (xy 304.212112 -310.455304) (xy 304.162937 -310.453323)
			(xy 304.114718 -310.443479) (xy 304.068702 -310.426027) (xy 304.026081 -310.40142) (xy 303.98796 -310.370295)
			(xy 303.955325 -310.333458) (xy 303.929022 -310.291862) (xy 303.909731 -310.246586) (xy 303.897954 -310.198802)
			(xy 303.893994 -310.149748) (xy 303.555146 -310.149748) (xy 303.554651 -310.174355) (xy 303.546756 -310.222932)
			(xy 303.531172 -310.269613) (xy 303.508301 -310.31319) (xy 303.478736 -310.352534) (xy 303.443243 -310.386626)
			(xy 303.40274 -310.414582) (xy 303.358278 -310.43568) (xy 303.311007 -310.449372) (xy 303.262152 -310.455304)
			(xy 303.212977 -310.453323) (xy 303.164758 -310.443479) (xy 303.118742 -310.426027) (xy 303.076121 -310.40142)
			(xy 303.038 -310.370295) (xy 303.005365 -310.333458) (xy 302.979062 -310.291862) (xy 302.959771 -310.246586)
			(xy 302.947994 -310.198802) (xy 302.944034 -310.149748) (xy 302.605186 -310.149748) (xy 302.604691 -310.174355)
			(xy 302.596796 -310.222932) (xy 302.581212 -310.269613) (xy 302.558341 -310.31319) (xy 302.528776 -310.352534)
			(xy 302.493283 -310.386626) (xy 302.45278 -310.414582) (xy 302.408318 -310.43568) (xy 302.361047 -310.449372)
			(xy 302.312192 -310.455304) (xy 302.263017 -310.453323) (xy 302.214798 -310.443479) (xy 302.168782 -310.426027)
			(xy 302.126161 -310.40142) (xy 302.08804 -310.370295) (xy 302.055405 -310.333458) (xy 302.029102 -310.291862)
			(xy 302.009811 -310.246586) (xy 301.998034 -310.198802) (xy 301.994074 -310.149748) (xy 301.655226 -310.149748)
			(xy 301.654731 -310.174355) (xy 301.646836 -310.222932) (xy 301.631252 -310.269613) (xy 301.608381 -310.31319)
			(xy 301.578816 -310.352534) (xy 301.543323 -310.386626) (xy 301.50282 -310.414582) (xy 301.458358 -310.43568)
			(xy 301.411087 -310.449372) (xy 301.362232 -310.455304) (xy 301.313057 -310.453323) (xy 301.264838 -310.443479)
			(xy 301.218822 -310.426027) (xy 301.176201 -310.40142) (xy 301.13808 -310.370295) (xy 301.105445 -310.333458)
			(xy 301.079142 -310.291862) (xy 301.059851 -310.246586) (xy 301.048074 -310.198802) (xy 301.044114 -310.149748)
			(xy 300.705012 -310.149748) (xy 300.704517 -310.174355) (xy 300.696622 -310.222932) (xy 300.681038 -310.269613)
			(xy 300.658167 -310.31319) (xy 300.628602 -310.352534) (xy 300.593109 -310.386626) (xy 300.552606 -310.414582)
			(xy 300.508144 -310.43568) (xy 300.460873 -310.449372) (xy 300.412018 -310.455304) (xy 300.362843 -310.453323)
			(xy 300.314624 -310.443479) (xy 300.268608 -310.426027) (xy 300.225987 -310.40142) (xy 300.187866 -310.370295)
			(xy 300.155231 -310.333458) (xy 300.128928 -310.291862) (xy 300.109637 -310.246586) (xy 300.09786 -310.198802)
			(xy 300.0939 -310.149748) (xy 299.755052 -310.149748) (xy 299.754557 -310.174355) (xy 299.746662 -310.222932)
			(xy 299.731078 -310.269613) (xy 299.708207 -310.31319) (xy 299.678642 -310.352534) (xy 299.643149 -310.386626)
			(xy 299.602646 -310.414582) (xy 299.558184 -310.43568) (xy 299.510913 -310.449372) (xy 299.462058 -310.455304)
			(xy 299.412883 -310.453323) (xy 299.364664 -310.443479) (xy 299.318648 -310.426027) (xy 299.276027 -310.40142)
			(xy 299.237906 -310.370295) (xy 299.205271 -310.333458) (xy 299.178968 -310.291862) (xy 299.159677 -310.246586)
			(xy 299.1479 -310.198802) (xy 299.14394 -310.149748) (xy 298.805092 -310.149748) (xy 298.804597 -310.174355)
			(xy 298.796702 -310.222932) (xy 298.781118 -310.269613) (xy 298.758247 -310.31319) (xy 298.728682 -310.352534)
			(xy 298.693189 -310.386626) (xy 298.652686 -310.414582) (xy 298.608224 -310.43568) (xy 298.560953 -310.449372)
			(xy 298.512098 -310.455304) (xy 298.462923 -310.453323) (xy 298.414704 -310.443479) (xy 298.368688 -310.426027)
			(xy 298.326067 -310.40142) (xy 298.287946 -310.370295) (xy 298.255311 -310.333458) (xy 298.229008 -310.291862)
			(xy 298.209717 -310.246586) (xy 298.19794 -310.198802) (xy 298.19398 -310.149748) (xy 297.855132 -310.149748)
			(xy 297.854637 -310.174355) (xy 297.846742 -310.222932) (xy 297.831158 -310.269613) (xy 297.808287 -310.31319)
			(xy 297.778722 -310.352534) (xy 297.743229 -310.386626) (xy 297.702726 -310.414582) (xy 297.658264 -310.43568)
			(xy 297.610993 -310.449372) (xy 297.562138 -310.455304) (xy 297.512963 -310.453323) (xy 297.464744 -310.443479)
			(xy 297.418728 -310.426027) (xy 297.376107 -310.40142) (xy 297.337986 -310.370295) (xy 297.305351 -310.333458)
			(xy 297.279048 -310.291862) (xy 297.259757 -310.246586) (xy 297.24798 -310.198802) (xy 297.24402 -310.149748)
			(xy 296.905172 -310.149748) (xy 296.904677 -310.174355) (xy 296.896782 -310.222932) (xy 296.881198 -310.269613)
			(xy 296.858327 -310.31319) (xy 296.828762 -310.352534) (xy 296.793269 -310.386626) (xy 296.752766 -310.414582)
			(xy 296.708304 -310.43568) (xy 296.661033 -310.449372) (xy 296.612178 -310.455304) (xy 296.563003 -310.453323)
			(xy 296.514784 -310.443479) (xy 296.468768 -310.426027) (xy 296.426147 -310.40142) (xy 296.388026 -310.370295)
			(xy 296.355391 -310.333458) (xy 296.329088 -310.291862) (xy 296.309797 -310.246586) (xy 296.29802 -310.198802)
			(xy 296.29406 -310.149748) (xy 295.955212 -310.149748) (xy 295.954717 -310.174355) (xy 295.946822 -310.222932)
			(xy 295.931238 -310.269613) (xy 295.908367 -310.31319) (xy 295.878802 -310.352534) (xy 295.843309 -310.386626)
			(xy 295.802806 -310.414582) (xy 295.758344 -310.43568) (xy 295.711073 -310.449372) (xy 295.662218 -310.455304)
			(xy 295.613043 -310.453323) (xy 295.564824 -310.443479) (xy 295.518808 -310.426027) (xy 295.476187 -310.40142)
			(xy 295.438066 -310.370295) (xy 295.405431 -310.333458) (xy 295.379128 -310.291862) (xy 295.359837 -310.246586)
			(xy 295.34806 -310.198802) (xy 295.3441 -310.149748) (xy 295.004998 -310.149748) (xy 295.004503 -310.174355)
			(xy 294.996608 -310.222932) (xy 294.981024 -310.269613) (xy 294.958153 -310.31319) (xy 294.928588 -310.352534)
			(xy 294.893095 -310.386626) (xy 294.852592 -310.414582) (xy 294.80813 -310.43568) (xy 294.760859 -310.449372)
			(xy 294.712004 -310.455304) (xy 294.662829 -310.453323) (xy 294.61461 -310.443479) (xy 294.568594 -310.426027)
			(xy 294.525973 -310.40142) (xy 294.487852 -310.370295) (xy 294.455217 -310.333458) (xy 294.428914 -310.291862)
			(xy 294.409623 -310.246586) (xy 294.397846 -310.198802) (xy 294.393886 -310.149748) (xy 294.055038 -310.149748)
			(xy 294.054543 -310.174355) (xy 294.046648 -310.222932) (xy 294.031064 -310.269613) (xy 294.008193 -310.31319)
			(xy 293.978628 -310.352534) (xy 293.943135 -310.386626) (xy 293.902632 -310.414582) (xy 293.85817 -310.43568)
			(xy 293.810899 -310.449372) (xy 293.762044 -310.455304) (xy 293.712869 -310.453323) (xy 293.66465 -310.443479)
			(xy 293.618634 -310.426027) (xy 293.576013 -310.40142) (xy 293.537892 -310.370295) (xy 293.505257 -310.333458)
			(xy 293.478954 -310.291862) (xy 293.459663 -310.246586) (xy 293.447886 -310.198802) (xy 293.443926 -310.149748)
			(xy 293.105078 -310.149748) (xy 293.104583 -310.174355) (xy 293.096688 -310.222932) (xy 293.081104 -310.269613)
			(xy 293.058233 -310.31319) (xy 293.028668 -310.352534) (xy 292.993175 -310.386626) (xy 292.952672 -310.414582)
			(xy 292.90821 -310.43568) (xy 292.860939 -310.449372) (xy 292.812084 -310.455304) (xy 292.762909 -310.453323)
			(xy 292.71469 -310.443479) (xy 292.668674 -310.426027) (xy 292.626053 -310.40142) (xy 292.587932 -310.370295)
			(xy 292.555297 -310.333458) (xy 292.528994 -310.291862) (xy 292.509703 -310.246586) (xy 292.497926 -310.198802)
			(xy 292.493966 -310.149748) (xy 292.155118 -310.149748) (xy 292.154623 -310.174355) (xy 292.146728 -310.222932)
			(xy 292.131144 -310.269613) (xy 292.108273 -310.31319) (xy 292.078708 -310.352534) (xy 292.043215 -310.386626)
			(xy 292.002712 -310.414582) (xy 291.95825 -310.43568) (xy 291.910979 -310.449372) (xy 291.862124 -310.455304)
			(xy 291.812949 -310.453323) (xy 291.76473 -310.443479) (xy 291.718714 -310.426027) (xy 291.676093 -310.40142)
			(xy 291.637972 -310.370295) (xy 291.605337 -310.333458) (xy 291.579034 -310.291862) (xy 291.559743 -310.246586)
			(xy 291.547966 -310.198802) (xy 291.544006 -310.149748) (xy 291.205158 -310.149748) (xy 291.204663 -310.174355)
			(xy 291.196768 -310.222932) (xy 291.181184 -310.269613) (xy 291.158313 -310.31319) (xy 291.128748 -310.352534)
			(xy 291.093255 -310.386626) (xy 291.052752 -310.414582) (xy 291.00829 -310.43568) (xy 290.961019 -310.449372)
			(xy 290.912164 -310.455304) (xy 290.862989 -310.453323) (xy 290.81477 -310.443479) (xy 290.768754 -310.426027)
			(xy 290.726133 -310.40142) (xy 290.688012 -310.370295) (xy 290.655377 -310.333458) (xy 290.629074 -310.291862)
			(xy 290.609783 -310.246586) (xy 290.598006 -310.198802) (xy 290.594046 -310.149748) (xy 290.255708 -310.149748)
			(xy 290.251541 -310.200036) (xy 290.239142 -310.248999) (xy 290.218852 -310.295253) (xy 290.191226 -310.337537)
			(xy 290.157017 -310.374697) (xy 290.117158 -310.405719) (xy 290.072737 -310.429757) (xy 290.024964 -310.446156)
			(xy 289.975144 -310.454468) (xy 289.94989 -310.455056) (xy 289.923644 -310.454533) (xy 289.87192 -310.445592)
			(xy 289.84702 -310.437276) (xy 289.837734 -310.434427) (xy 289.818342 -310.435184) (xy 289.800621 -310.443095)
			(xy 289.787111 -310.457028) (xy 289.779749 -310.474984) (xy 289.77959 -310.49439) (xy 289.782758 -310.50357)
			(xy 289.792664 -310.53278) (xy 289.793843 -310.53669) (xy 289.797288 -310.544093) (xy 289.799522 -310.547512)
			(xy 289.822118 -310.58094) (xy 289.862326 -310.650901) (xy 289.896598 -310.723954) (xy 289.911028 -310.761634)
			(xy 289.914998 -310.77097) (xy 289.928884 -310.785739) (xy 289.947387 -310.794019) (xy 289.95751 -310.794654)
			(xy 289.981111 -310.795677) (xy 290.027592 -310.8041) (xy 290.07222 -310.819584) (xy 290.11393 -310.841757)
			(xy 290.151726 -310.870092) (xy 290.184705 -310.903912) (xy 290.212081 -310.942408) (xy 290.2332 -310.984662)
			(xy 290.247557 -311.029665) (xy 290.254809 -311.076343) (xy 290.255198 -311.099962) (xy 290.254666 -311.12567)
			(xy 290.573202 -311.12567) (xy 290.573202 -311.074254) (xy 290.581245 -311.023472) (xy 290.597133 -310.974573)
			(xy 290.620476 -310.928761) (xy 290.650697 -310.887165) (xy 290.687053 -310.850809) (xy 290.728649 -310.820588)
			(xy 290.774461 -310.797245) (xy 290.82336 -310.781357) (xy 290.874142 -310.773314) (xy 290.925558 -310.773314)
			(xy 290.97634 -310.781357) (xy 291.025239 -310.797245) (xy 291.071051 -310.820588) (xy 291.112647 -310.850809)
			(xy 291.149003 -310.887165) (xy 291.179224 -310.928761) (xy 291.202567 -310.974573) (xy 291.218455 -311.023472)
			(xy 291.226498 -311.074254) (xy 291.227002 -311.099962) (xy 291.544006 -311.099962) (xy 291.547966 -311.050908)
			(xy 291.559743 -311.003124) (xy 291.579034 -310.957848) (xy 291.605337 -310.916252) (xy 291.637972 -310.879415)
			(xy 291.676093 -310.84829) (xy 291.718714 -310.823683) (xy 291.76473 -310.806231) (xy 291.812949 -310.796387)
			(xy 291.862124 -310.794406) (xy 291.910979 -310.800338) (xy 291.95825 -310.81403) (xy 292.002712 -310.835128)
			(xy 292.043215 -310.863084) (xy 292.078708 -310.897176) (xy 292.108273 -310.93652) (xy 292.131144 -310.980097)
			(xy 292.146728 -311.026778) (xy 292.154623 -311.075355) (xy 292.155118 -311.099962) (xy 292.154623 -311.124569)
			(xy 292.154444 -311.12567) (xy 292.473122 -311.12567) (xy 292.473122 -311.074254) (xy 292.481165 -311.023472)
			(xy 292.497053 -310.974573) (xy 292.520396 -310.928761) (xy 292.550617 -310.887165) (xy 292.586973 -310.850809)
			(xy 292.628569 -310.820588) (xy 292.674381 -310.797245) (xy 292.72328 -310.781357) (xy 292.774062 -310.773314)
			(xy 292.825478 -310.773314) (xy 292.87626 -310.781357) (xy 292.925159 -310.797245) (xy 292.970971 -310.820588)
			(xy 293.012567 -310.850809) (xy 293.048923 -310.887165) (xy 293.079144 -310.928761) (xy 293.102487 -310.974573)
			(xy 293.118375 -311.023472) (xy 293.126418 -311.074254) (xy 293.126922 -311.099962) (xy 293.443926 -311.099962)
			(xy 293.447886 -311.050908) (xy 293.459663 -311.003124) (xy 293.478954 -310.957848) (xy 293.505257 -310.916252)
			(xy 293.537892 -310.879415) (xy 293.576013 -310.84829) (xy 293.618634 -310.823683) (xy 293.66465 -310.806231)
			(xy 293.712869 -310.796387) (xy 293.762044 -310.794406) (xy 293.810899 -310.800338) (xy 293.85817 -310.81403)
			(xy 293.902632 -310.835128) (xy 293.943135 -310.863084) (xy 293.978628 -310.897176) (xy 294.008193 -310.93652)
			(xy 294.031064 -310.980097) (xy 294.046648 -311.026778) (xy 294.054543 -311.075355) (xy 294.055038 -311.099962)
			(xy 294.054543 -311.124569) (xy 294.054364 -311.12567) (xy 294.373042 -311.12567) (xy 294.373042 -311.074254)
			(xy 294.381085 -311.023472) (xy 294.396973 -310.974573) (xy 294.420316 -310.928761) (xy 294.450537 -310.887165)
			(xy 294.486893 -310.850809) (xy 294.528489 -310.820588) (xy 294.574301 -310.797245) (xy 294.6232 -310.781357)
			(xy 294.673982 -310.773314) (xy 294.725398 -310.773314) (xy 294.77618 -310.781357) (xy 294.825079 -310.797245)
			(xy 294.870891 -310.820588) (xy 294.912487 -310.850809) (xy 294.948843 -310.887165) (xy 294.979064 -310.928761)
			(xy 295.002407 -310.974573) (xy 295.018295 -311.023472) (xy 295.026338 -311.074254) (xy 295.026842 -311.099962)
			(xy 295.3441 -311.099962) (xy 295.34806 -311.050908) (xy 295.359837 -311.003124) (xy 295.379128 -310.957848)
			(xy 295.405431 -310.916252) (xy 295.438066 -310.879415) (xy 295.476187 -310.84829) (xy 295.518808 -310.823683)
			(xy 295.564824 -310.806231) (xy 295.613043 -310.796387) (xy 295.662218 -310.794406) (xy 295.711073 -310.800338)
			(xy 295.758344 -310.81403) (xy 295.802806 -310.835128) (xy 295.843309 -310.863084) (xy 295.878802 -310.897176)
			(xy 295.908367 -310.93652) (xy 295.931238 -310.980097) (xy 295.946822 -311.026778) (xy 295.954717 -311.075355)
			(xy 295.955212 -311.099962) (xy 295.954717 -311.124569) (xy 295.954538 -311.12567) (xy 296.273216 -311.12567)
			(xy 296.273216 -311.074254) (xy 296.281259 -311.023472) (xy 296.297147 -310.974573) (xy 296.32049 -310.928761)
			(xy 296.350711 -310.887165) (xy 296.387067 -310.850809) (xy 296.428663 -310.820588) (xy 296.474475 -310.797245)
			(xy 296.523374 -310.781357) (xy 296.574156 -310.773314) (xy 296.625572 -310.773314) (xy 296.676354 -310.781357)
			(xy 296.725253 -310.797245) (xy 296.771065 -310.820588) (xy 296.812661 -310.850809) (xy 296.849017 -310.887165)
			(xy 296.879238 -310.928761) (xy 296.902581 -310.974573) (xy 296.918469 -311.023472) (xy 296.926512 -311.074254)
			(xy 296.927016 -311.099962) (xy 297.24402 -311.099962) (xy 297.24798 -311.050908) (xy 297.259757 -311.003124)
			(xy 297.279048 -310.957848) (xy 297.305351 -310.916252) (xy 297.337986 -310.879415) (xy 297.376107 -310.84829)
			(xy 297.418728 -310.823683) (xy 297.464744 -310.806231) (xy 297.512963 -310.796387) (xy 297.562138 -310.794406)
			(xy 297.610993 -310.800338) (xy 297.658264 -310.81403) (xy 297.702726 -310.835128) (xy 297.743229 -310.863084)
			(xy 297.778722 -310.897176) (xy 297.808287 -310.93652) (xy 297.831158 -310.980097) (xy 297.846742 -311.026778)
			(xy 297.854637 -311.075355) (xy 297.855132 -311.099962) (xy 297.854637 -311.124569) (xy 297.854458 -311.12567)
			(xy 298.173136 -311.12567) (xy 298.173136 -311.074254) (xy 298.181179 -311.023472) (xy 298.197067 -310.974573)
			(xy 298.22041 -310.928761) (xy 298.250631 -310.887165) (xy 298.286987 -310.850809) (xy 298.328583 -310.820588)
			(xy 298.374395 -310.797245) (xy 298.423294 -310.781357) (xy 298.474076 -310.773314) (xy 298.525492 -310.773314)
			(xy 298.576274 -310.781357) (xy 298.625173 -310.797245) (xy 298.670985 -310.820588) (xy 298.712581 -310.850809)
			(xy 298.748937 -310.887165) (xy 298.779158 -310.928761) (xy 298.802501 -310.974573) (xy 298.818389 -311.023472)
			(xy 298.826432 -311.074254) (xy 298.826936 -311.099962) (xy 299.14394 -311.099962) (xy 299.1479 -311.050908)
			(xy 299.159677 -311.003124) (xy 299.178968 -310.957848) (xy 299.205271 -310.916252) (xy 299.237906 -310.879415)
			(xy 299.276027 -310.84829) (xy 299.318648 -310.823683) (xy 299.364664 -310.806231) (xy 299.412883 -310.796387)
			(xy 299.462058 -310.794406) (xy 299.510913 -310.800338) (xy 299.558184 -310.81403) (xy 299.602646 -310.835128)
			(xy 299.643149 -310.863084) (xy 299.678642 -310.897176) (xy 299.708207 -310.93652) (xy 299.731078 -310.980097)
			(xy 299.746662 -311.026778) (xy 299.754557 -311.075355) (xy 299.755052 -311.099962) (xy 299.754557 -311.124569)
			(xy 299.754378 -311.12567) (xy 300.073056 -311.12567) (xy 300.073056 -311.074254) (xy 300.081099 -311.023472)
			(xy 300.096987 -310.974573) (xy 300.12033 -310.928761) (xy 300.150551 -310.887165) (xy 300.186907 -310.850809)
			(xy 300.228503 -310.820588) (xy 300.274315 -310.797245) (xy 300.323214 -310.781357) (xy 300.373996 -310.773314)
			(xy 300.425412 -310.773314) (xy 300.476194 -310.781357) (xy 300.525093 -310.797245) (xy 300.570905 -310.820588)
			(xy 300.612501 -310.850809) (xy 300.648857 -310.887165) (xy 300.679078 -310.928761) (xy 300.702421 -310.974573)
			(xy 300.718309 -311.023472) (xy 300.726352 -311.074254) (xy 300.726856 -311.099962) (xy 301.044114 -311.099962)
			(xy 301.048074 -311.050908) (xy 301.059851 -311.003124) (xy 301.079142 -310.957848) (xy 301.105445 -310.916252)
			(xy 301.13808 -310.879415) (xy 301.176201 -310.84829) (xy 301.218822 -310.823683) (xy 301.264838 -310.806231)
			(xy 301.313057 -310.796387) (xy 301.362232 -310.794406) (xy 301.411087 -310.800338) (xy 301.458358 -310.81403)
			(xy 301.50282 -310.835128) (xy 301.543323 -310.863084) (xy 301.578816 -310.897176) (xy 301.608381 -310.93652)
			(xy 301.631252 -310.980097) (xy 301.646836 -311.026778) (xy 301.654731 -311.075355) (xy 301.655226 -311.099962)
			(xy 301.654731 -311.124569) (xy 301.654552 -311.12567) (xy 301.97323 -311.12567) (xy 301.97323 -311.074254)
			(xy 301.981273 -311.023472) (xy 301.997161 -310.974573) (xy 302.020504 -310.928761) (xy 302.050725 -310.887165)
			(xy 302.087081 -310.850809) (xy 302.128677 -310.820588) (xy 302.174489 -310.797245) (xy 302.223388 -310.781357)
			(xy 302.27417 -310.773314) (xy 302.325586 -310.773314) (xy 302.376368 -310.781357) (xy 302.425267 -310.797245)
			(xy 302.471079 -310.820588) (xy 302.512675 -310.850809) (xy 302.549031 -310.887165) (xy 302.579252 -310.928761)
			(xy 302.602595 -310.974573) (xy 302.618483 -311.023472) (xy 302.626526 -311.074254) (xy 302.62703 -311.099962)
			(xy 302.944034 -311.099962) (xy 302.947994 -311.050908) (xy 302.959771 -311.003124) (xy 302.979062 -310.957848)
			(xy 303.005365 -310.916252) (xy 303.038 -310.879415) (xy 303.076121 -310.84829) (xy 303.118742 -310.823683)
			(xy 303.164758 -310.806231) (xy 303.212977 -310.796387) (xy 303.262152 -310.794406) (xy 303.311007 -310.800338)
			(xy 303.358278 -310.81403) (xy 303.40274 -310.835128) (xy 303.443243 -310.863084) (xy 303.478736 -310.897176)
			(xy 303.508301 -310.93652) (xy 303.531172 -310.980097) (xy 303.546756 -311.026778) (xy 303.554651 -311.075355)
			(xy 303.555146 -311.099962) (xy 303.554651 -311.124569) (xy 303.554472 -311.12567) (xy 303.87315 -311.12567)
			(xy 303.87315 -311.074254) (xy 303.881193 -311.023472) (xy 303.897081 -310.974573) (xy 303.920424 -310.928761)
			(xy 303.950645 -310.887165) (xy 303.987001 -310.850809) (xy 304.028597 -310.820588) (xy 304.074409 -310.797245)
			(xy 304.123308 -310.781357) (xy 304.17409 -310.773314) (xy 304.225506 -310.773314) (xy 304.276288 -310.781357)
			(xy 304.325187 -310.797245) (xy 304.370999 -310.820588) (xy 304.412595 -310.850809) (xy 304.448951 -310.887165)
			(xy 304.479172 -310.928761) (xy 304.502515 -310.974573) (xy 304.518403 -311.023472) (xy 304.526446 -311.074254)
			(xy 304.52695 -311.099962) (xy 304.843954 -311.099962) (xy 304.847914 -311.050908) (xy 304.859691 -311.003124)
			(xy 304.878982 -310.957848) (xy 304.905285 -310.916252) (xy 304.93792 -310.879415) (xy 304.976041 -310.84829)
			(xy 305.018662 -310.823683) (xy 305.064678 -310.806231) (xy 305.112897 -310.796387) (xy 305.162072 -310.794406)
			(xy 305.210927 -310.800338) (xy 305.258198 -310.81403) (xy 305.30266 -310.835128) (xy 305.343163 -310.863084)
			(xy 305.378656 -310.897176) (xy 305.408221 -310.93652) (xy 305.431092 -310.980097) (xy 305.446676 -311.026778)
			(xy 305.454571 -311.075355) (xy 305.455066 -311.099962) (xy 305.454571 -311.124569) (xy 305.454392 -311.12567)
			(xy 305.77307 -311.12567) (xy 305.77307 -311.074254) (xy 305.781113 -311.023472) (xy 305.797001 -310.974573)
			(xy 305.820344 -310.928761) (xy 305.850565 -310.887165) (xy 305.886921 -310.850809) (xy 305.928517 -310.820588)
			(xy 305.974329 -310.797245) (xy 306.023228 -310.781357) (xy 306.07401 -310.773314) (xy 306.125426 -310.773314)
			(xy 306.176208 -310.781357) (xy 306.225107 -310.797245) (xy 306.270919 -310.820588) (xy 306.312515 -310.850809)
			(xy 306.348871 -310.887165) (xy 306.379092 -310.928761) (xy 306.402435 -310.974573) (xy 306.418323 -311.023472)
			(xy 306.426366 -311.074254) (xy 306.42687 -311.099962) (xy 306.744128 -311.099962) (xy 306.748088 -311.050908)
			(xy 306.759865 -311.003124) (xy 306.779156 -310.957848) (xy 306.805459 -310.916252) (xy 306.838094 -310.879415)
			(xy 306.876215 -310.84829) (xy 306.918836 -310.823683) (xy 306.964852 -310.806231) (xy 307.013071 -310.796387)
			(xy 307.062246 -310.794406) (xy 307.111101 -310.800338) (xy 307.158372 -310.81403) (xy 307.202834 -310.835128)
			(xy 307.243337 -310.863084) (xy 307.27883 -310.897176) (xy 307.308395 -310.93652) (xy 307.331266 -310.980097)
			(xy 307.34685 -311.026778) (xy 307.354745 -311.075355) (xy 307.35524 -311.099962) (xy 307.354745 -311.124569)
			(xy 307.354566 -311.12567) (xy 307.673244 -311.12567) (xy 307.673244 -311.074254) (xy 307.681287 -311.023472)
			(xy 307.697175 -310.974573) (xy 307.720518 -310.928761) (xy 307.750739 -310.887165) (xy 307.787095 -310.850809)
			(xy 307.828691 -310.820588) (xy 307.874503 -310.797245) (xy 307.923402 -310.781357) (xy 307.974184 -310.773314)
			(xy 308.0256 -310.773314) (xy 308.076382 -310.781357) (xy 308.125281 -310.797245) (xy 308.171093 -310.820588)
			(xy 308.212689 -310.850809) (xy 308.249045 -310.887165) (xy 308.279266 -310.928761) (xy 308.302609 -310.974573)
			(xy 308.318497 -311.023472) (xy 308.32654 -311.074254) (xy 308.327044 -311.099962) (xy 308.644048 -311.099962)
			(xy 308.648008 -311.050908) (xy 308.659785 -311.003124) (xy 308.679076 -310.957848) (xy 308.705379 -310.916252)
			(xy 308.738014 -310.879415) (xy 308.776135 -310.84829) (xy 308.818756 -310.823683) (xy 308.864772 -310.806231)
			(xy 308.912991 -310.796387) (xy 308.962166 -310.794406) (xy 309.011021 -310.800338) (xy 309.058292 -310.81403)
			(xy 309.102754 -310.835128) (xy 309.143257 -310.863084) (xy 309.17875 -310.897176) (xy 309.208315 -310.93652)
			(xy 309.231186 -310.980097) (xy 309.24677 -311.026778) (xy 309.254665 -311.075355) (xy 309.25516 -311.099962)
			(xy 309.254665 -311.124569) (xy 309.254486 -311.12567) (xy 309.573164 -311.12567) (xy 309.573164 -311.074254)
			(xy 309.581207 -311.023472) (xy 309.597095 -310.974573) (xy 309.620438 -310.928761) (xy 309.650659 -310.887165)
			(xy 309.687015 -310.850809) (xy 309.728611 -310.820588) (xy 309.774423 -310.797245) (xy 309.823322 -310.781357)
			(xy 309.874104 -310.773314) (xy 309.92552 -310.773314) (xy 309.976302 -310.781357) (xy 310.025201 -310.797245)
			(xy 310.071013 -310.820588) (xy 310.112609 -310.850809) (xy 310.148965 -310.887165) (xy 310.179186 -310.928761)
			(xy 310.202529 -310.974573) (xy 310.218417 -311.023472) (xy 310.22646 -311.074254) (xy 310.226803 -311.091749)
			(xy 310.544042 -311.091749) (xy 310.549405 -311.042391) (xy 310.562683 -310.994551) (xy 310.583525 -310.949489)
			(xy 310.611383 -310.908393) (xy 310.645522 -310.872346) (xy 310.685044 -310.842296) (xy 310.728907 -310.819036)
			(xy 310.775954 -310.803179) (xy 310.824948 -310.795142) (xy 310.849772 -310.794654) (xy 310.863955 -310.794835)
			(xy 310.892195 -310.797504) (xy 310.90616 -310.799988) (xy 310.918606 -310.802274) (xy 310.942482 -310.794908)
			(xy 311.019698 -310.717692) (xy 311.027064 -310.693562) (xy 311.024778 -310.68137) (xy 311.022292 -310.667341)
			(xy 311.019621 -310.638974) (xy 311.019444 -310.624728) (xy 311.019624 -310.610545) (xy 311.022294 -310.582305)
			(xy 311.024778 -310.56834) (xy 311.027064 -310.555894) (xy 311.019698 -310.532272) (xy 310.942228 -310.454802)
			(xy 310.918606 -310.447436) (xy 310.90616 -310.449722) (xy 310.892194 -310.4522) (xy 310.863955 -310.454871)
			(xy 310.849772 -310.455056) (xy 310.824953 -310.454492) (xy 310.77597 -310.446457) (xy 310.728932 -310.430603)
			(xy 310.685079 -310.407348) (xy 310.645565 -310.377304) (xy 310.611433 -310.341264) (xy 310.583581 -310.300176)
			(xy 310.562744 -310.255124) (xy 310.549469 -310.207294) (xy 310.544108 -310.157946) (xy 310.546801 -310.108382)
			(xy 310.557478 -310.059906) (xy 310.575856 -310.013795) (xy 310.601452 -309.971266) (xy 310.633592 -309.933438)
			(xy 310.671428 -309.901308) (xy 310.713963 -309.875722) (xy 310.760078 -309.857355) (xy 310.808557 -309.846691)
			(xy 310.858122 -309.84401) (xy 310.907469 -309.849384) (xy 310.955295 -309.86267) (xy 311.000342 -309.883519)
			(xy 311.041423 -309.911381) (xy 311.077455 -309.945522) (xy 311.107489 -309.985043) (xy 311.130733 -310.028902)
			(xy 311.146575 -310.075944) (xy 311.154598 -310.124929) (xy 311.15508 -310.149748) (xy 311.154897 -310.163931)
			(xy 311.152229 -310.192171) (xy 311.149746 -310.206136) (xy 311.14746 -310.218582) (xy 311.154826 -310.242204)
			(xy 311.232296 -310.319674) (xy 311.255918 -310.32704) (xy 311.268364 -310.324754) (xy 311.282329 -310.322273)
			(xy 311.310569 -310.319604) (xy 311.324752 -310.31942) (xy 311.338935 -310.319603) (xy 311.367175 -310.322271)
			(xy 311.38114 -310.324754) (xy 311.393586 -310.32704) (xy 311.417208 -310.319674) (xy 311.494678 -310.242204)
			(xy 311.502044 -310.218582) (xy 311.499758 -310.206136) (xy 311.497277 -310.192171) (xy 311.494608 -310.163931)
			(xy 311.494424 -310.149748) (xy 311.494826 -310.124923) (xy 311.502851 -310.075926) (xy 311.518697 -310.028872)
			(xy 311.541947 -309.985002) (xy 311.571988 -309.945471) (xy 311.608028 -309.911322) (xy 311.649119 -309.883453)
			(xy 311.694177 -309.862599) (xy 311.742016 -309.849309) (xy 311.791374 -309.843934) (xy 311.840952 -309.846615)
			(xy 311.889443 -309.857282) (xy 311.935569 -309.875653) (xy 311.978115 -309.901244) (xy 312.015961 -309.933382)
			(xy 312.048109 -309.971219) (xy 312.073712 -310.013759) (xy 312.092095 -310.059881) (xy 312.102774 -310.108369)
			(xy 312.105023 -310.149748) (xy 312.443888 -310.149748) (xy 312.447848 -310.100694) (xy 312.459625 -310.05291)
			(xy 312.478916 -310.007634) (xy 312.505219 -309.966038) (xy 312.537854 -309.929201) (xy 312.575975 -309.898076)
			(xy 312.618596 -309.873469) (xy 312.664612 -309.856017) (xy 312.712831 -309.846173) (xy 312.762006 -309.844192)
			(xy 312.810861 -309.850124) (xy 312.858132 -309.863816) (xy 312.902594 -309.884914) (xy 312.943097 -309.91287)
			(xy 312.97859 -309.946962) (xy 313.008155 -309.986306) (xy 313.031026 -310.029883) (xy 313.04661 -310.076564)
			(xy 313.054505 -310.125141) (xy 313.055 -310.149748) (xy 313.394102 -310.149748) (xy 313.398062 -310.100694)
			(xy 313.409839 -310.05291) (xy 313.42913 -310.007634) (xy 313.455433 -309.966038) (xy 313.488068 -309.929201)
			(xy 313.526189 -309.898076) (xy 313.56881 -309.873469) (xy 313.614826 -309.856017) (xy 313.663045 -309.846173)
			(xy 313.71222 -309.844192) (xy 313.761075 -309.850124) (xy 313.808346 -309.863816) (xy 313.852808 -309.884914)
			(xy 313.893311 -309.91287) (xy 313.928804 -309.946962) (xy 313.958369 -309.986306) (xy 313.98124 -310.029883)
			(xy 313.996824 -310.076564) (xy 314.004719 -310.125141) (xy 314.005214 -310.149748) (xy 314.344062 -310.149748)
			(xy 314.348022 -310.100694) (xy 314.359799 -310.05291) (xy 314.37909 -310.007634) (xy 314.405393 -309.966038)
			(xy 314.438028 -309.929201) (xy 314.476149 -309.898076) (xy 314.51877 -309.873469) (xy 314.564786 -309.856017)
			(xy 314.613005 -309.846173) (xy 314.66218 -309.844192) (xy 314.711035 -309.850124) (xy 314.758306 -309.863816)
			(xy 314.802768 -309.884914) (xy 314.843271 -309.91287) (xy 314.878764 -309.946962) (xy 314.908329 -309.986306)
			(xy 314.9312 -310.029883) (xy 314.946784 -310.076564) (xy 314.954679 -310.125141) (xy 314.955174 -310.149748)
			(xy 315.294276 -310.149748) (xy 315.298236 -310.100694) (xy 315.310013 -310.05291) (xy 315.329304 -310.007634)
			(xy 315.355607 -309.966038) (xy 315.388242 -309.929201) (xy 315.426363 -309.898076) (xy 315.468984 -309.873469)
			(xy 315.515 -309.856017) (xy 315.563219 -309.846173) (xy 315.612394 -309.844192) (xy 315.661249 -309.850124)
			(xy 315.672318 -309.85333) (xy 321.210684 -309.85333) (xy 321.214755 -309.797708) (xy 321.226881 -309.743271)
			(xy 321.246804 -309.69118) (xy 321.2741 -309.642545) (xy 321.308186 -309.598402) (xy 321.348335 -309.559693)
			(xy 321.393693 -309.527242) (xy 321.443293 -309.501741) (xy 321.496077 -309.483734) (xy 321.55092 -309.473604)
			(xy 321.606654 -309.471567) (xy 321.662091 -309.477667) (xy 321.716048 -309.491773) (xy 321.767377 -309.513585)
			(xy 321.814983 -309.542639) (xy 321.840069 -309.563516) (xy 325.804274 -309.563516) (xy 325.808345 -309.507894)
			(xy 325.820471 -309.453457) (xy 325.840394 -309.401366) (xy 325.86769 -309.352731) (xy 325.901776 -309.308588)
			(xy 325.941925 -309.269879) (xy 325.987283 -309.237428) (xy 326.036883 -309.211927) (xy 326.089667 -309.19392)
			(xy 326.14451 -309.18379) (xy 326.200244 -309.181753) (xy 326.255681 -309.187853) (xy 326.309638 -309.201959)
			(xy 326.360967 -309.223771) (xy 326.408573 -309.252825) (xy 326.451441 -309.2885) (xy 326.488658 -309.330037)
			(xy 326.519431 -309.37655) (xy 326.543103 -309.427047) (xy 326.559171 -309.480454) (xy 326.567291 -309.53563)
			(xy 326.5678 -309.563516) (xy 326.567291 -309.591402) (xy 326.559171 -309.646578) (xy 326.543103 -309.699985)
			(xy 326.519431 -309.750482) (xy 326.488658 -309.796995) (xy 326.451441 -309.838532) (xy 326.408573 -309.874207)
			(xy 326.360967 -309.903261) (xy 326.309638 -309.925073) (xy 326.255681 -309.939179) (xy 326.200244 -309.945279)
			(xy 326.14451 -309.943242) (xy 326.089667 -309.933112) (xy 326.036883 -309.915105) (xy 325.987283 -309.889604)
			(xy 325.941925 -309.857153) (xy 325.901776 -309.818444) (xy 325.86769 -309.774301) (xy 325.840394 -309.725666)
			(xy 325.820471 -309.673575) (xy 325.808345 -309.619138) (xy 325.804274 -309.563516) (xy 321.840069 -309.563516)
			(xy 321.857851 -309.578314) (xy 321.895068 -309.619851) (xy 321.925841 -309.666364) (xy 321.949513 -309.716861)
			(xy 321.965581 -309.770268) (xy 321.973701 -309.825444) (xy 321.97421 -309.85333) (xy 321.973701 -309.881216)
			(xy 321.965581 -309.936392) (xy 321.949513 -309.989799) (xy 321.925841 -310.040296) (xy 321.895068 -310.086809)
			(xy 321.857851 -310.128346) (xy 321.814983 -310.164021) (xy 321.767377 -310.193075) (xy 321.716048 -310.214887)
			(xy 321.662091 -310.228993) (xy 321.606654 -310.235093) (xy 321.55092 -310.233056) (xy 321.496077 -310.222926)
			(xy 321.443293 -310.204919) (xy 321.393693 -310.179418) (xy 321.348335 -310.146967) (xy 321.308186 -310.108258)
			(xy 321.2741 -310.064115) (xy 321.246804 -310.01548) (xy 321.226881 -309.963389) (xy 321.214755 -309.908952)
			(xy 321.210684 -309.85333) (xy 315.672318 -309.85333) (xy 315.70852 -309.863816) (xy 315.752982 -309.884914)
			(xy 315.793485 -309.91287) (xy 315.828978 -309.946962) (xy 315.858543 -309.986306) (xy 315.881414 -310.029883)
			(xy 315.896998 -310.076564) (xy 315.904893 -310.125141) (xy 315.905388 -310.149748) (xy 315.904893 -310.174355)
			(xy 315.896998 -310.222932) (xy 315.881414 -310.269613) (xy 315.858543 -310.31319) (xy 315.828978 -310.352534)
			(xy 315.793485 -310.386626) (xy 315.752982 -310.414582) (xy 315.70852 -310.43568) (xy 315.661249 -310.449372)
			(xy 315.612394 -310.455304) (xy 315.563219 -310.453323) (xy 315.515 -310.443479) (xy 315.468984 -310.426027)
			(xy 315.426363 -310.40142) (xy 315.388242 -310.370295) (xy 315.355607 -310.333458) (xy 315.329304 -310.291862)
			(xy 315.310013 -310.246586) (xy 315.298236 -310.198802) (xy 315.294276 -310.149748) (xy 314.955174 -310.149748)
			(xy 314.954679 -310.174355) (xy 314.946784 -310.222932) (xy 314.9312 -310.269613) (xy 314.908329 -310.31319)
			(xy 314.878764 -310.352534) (xy 314.843271 -310.386626) (xy 314.802768 -310.414582) (xy 314.758306 -310.43568)
			(xy 314.711035 -310.449372) (xy 314.66218 -310.455304) (xy 314.613005 -310.453323) (xy 314.564786 -310.443479)
			(xy 314.51877 -310.426027) (xy 314.476149 -310.40142) (xy 314.438028 -310.370295) (xy 314.405393 -310.333458)
			(xy 314.37909 -310.291862) (xy 314.359799 -310.246586) (xy 314.348022 -310.198802) (xy 314.344062 -310.149748)
			(xy 314.005214 -310.149748) (xy 314.004719 -310.174355) (xy 313.996824 -310.222932) (xy 313.98124 -310.269613)
			(xy 313.958369 -310.31319) (xy 313.928804 -310.352534) (xy 313.893311 -310.386626) (xy 313.852808 -310.414582)
			(xy 313.808346 -310.43568) (xy 313.761075 -310.449372) (xy 313.71222 -310.455304) (xy 313.663045 -310.453323)
			(xy 313.614826 -310.443479) (xy 313.56881 -310.426027) (xy 313.526189 -310.40142) (xy 313.488068 -310.370295)
			(xy 313.455433 -310.333458) (xy 313.42913 -310.291862) (xy 313.409839 -310.246586) (xy 313.398062 -310.198802)
			(xy 313.394102 -310.149748) (xy 313.055 -310.149748) (xy 313.054505 -310.174355) (xy 313.04661 -310.222932)
			(xy 313.031026 -310.269613) (xy 313.008155 -310.31319) (xy 312.97859 -310.352534) (xy 312.943097 -310.386626)
			(xy 312.902594 -310.414582) (xy 312.858132 -310.43568) (xy 312.810861 -310.449372) (xy 312.762006 -310.455304)
			(xy 312.712831 -310.453323) (xy 312.664612 -310.443479) (xy 312.618596 -310.426027) (xy 312.575975 -310.40142)
			(xy 312.537854 -310.370295) (xy 312.505219 -310.333458) (xy 312.478916 -310.291862) (xy 312.459625 -310.246586)
			(xy 312.447848 -310.198802) (xy 312.443888 -310.149748) (xy 312.105023 -310.149748) (xy 312.105468 -310.157946)
			(xy 312.100106 -310.207305) (xy 312.086829 -310.255147) (xy 312.065987 -310.300211) (xy 312.038129 -310.341309)
			(xy 312.003988 -310.377359) (xy 311.964466 -310.40741) (xy 311.920602 -310.430672) (xy 311.873552 -310.44653)
			(xy 311.824557 -310.454568) (xy 311.799732 -310.455056) (xy 311.785549 -310.454876) (xy 311.757309 -310.452206)
			(xy 311.743344 -310.449722) (xy 311.730898 -310.447436) (xy 311.707276 -310.454802) (xy 311.629806 -310.532272)
			(xy 311.62244 -310.555894) (xy 311.624726 -310.56834) (xy 311.627204 -310.582306) (xy 311.629875 -310.610545)
			(xy 311.63006 -310.624728) (xy 311.62999 -310.634599) (xy 311.628717 -310.6543) (xy 311.62752 -310.664098)
			(xy 311.625996 -310.67629) (xy 311.629093 -310.68518) (xy 322.042534 -310.68518) (xy 322.046605 -310.629558)
			(xy 322.058731 -310.575121) (xy 322.078654 -310.52303) (xy 322.10595 -310.474395) (xy 322.140036 -310.430252)
			(xy 322.180185 -310.391543) (xy 322.225543 -310.359092) (xy 322.275143 -310.333591) (xy 322.327927 -310.315584)
			(xy 322.38277 -310.305454) (xy 322.438504 -310.303417) (xy 322.493941 -310.309517) (xy 322.547898 -310.323623)
			(xy 322.599227 -310.345435) (xy 322.646833 -310.374489) (xy 322.689701 -310.410164) (xy 322.726918 -310.451701)
			(xy 322.757691 -310.498214) (xy 322.781363 -310.548711) (xy 322.797431 -310.602118) (xy 322.805551 -310.657294)
			(xy 322.80606 -310.68518) (xy 322.805551 -310.713066) (xy 322.797431 -310.768242) (xy 322.781363 -310.821649)
			(xy 322.757691 -310.872146) (xy 322.726918 -310.918659) (xy 322.689701 -310.960196) (xy 322.646833 -310.995871)
			(xy 322.599227 -311.024925) (xy 322.547898 -311.046737) (xy 322.493941 -311.060843) (xy 322.438504 -311.066943)
			(xy 322.38277 -311.064906) (xy 322.327927 -311.054776) (xy 322.275143 -311.036769) (xy 322.225543 -311.011268)
			(xy 322.180185 -310.978817) (xy 322.140036 -310.940108) (xy 322.10595 -310.895965) (xy 322.078654 -310.84733)
			(xy 322.058731 -310.795239) (xy 322.046605 -310.740802) (xy 322.042534 -310.68518) (xy 311.629093 -310.68518)
			(xy 311.63387 -310.698896) (xy 311.710324 -310.772556) (xy 311.733184 -310.779668) (xy 311.745122 -310.777636)
			(xy 311.758672 -310.775487) (xy 311.786013 -310.773194) (xy 311.799732 -310.773064) (xy 311.825443 -310.773561)
			(xy 311.87623 -310.781611) (xy 311.925133 -310.797508) (xy 311.970946 -310.82086) (xy 312.012541 -310.851092)
			(xy 312.048894 -310.88746) (xy 312.079109 -310.929068) (xy 312.102443 -310.97489) (xy 312.11832 -311.023799)
			(xy 312.12635 -311.07459) (xy 312.126342 -311.099962) (xy 312.443888 -311.099962) (xy 312.447848 -311.050908)
			(xy 312.459625 -311.003124) (xy 312.478916 -310.957848) (xy 312.505219 -310.916252) (xy 312.537854 -310.879415)
			(xy 312.575975 -310.84829) (xy 312.618596 -310.823683) (xy 312.664612 -310.806231) (xy 312.712831 -310.796387)
			(xy 312.762006 -310.794406) (xy 312.810861 -310.800338) (xy 312.858132 -310.81403) (xy 312.902594 -310.835128)
			(xy 312.943097 -310.863084) (xy 312.97859 -310.897176) (xy 313.008155 -310.93652) (xy 313.031026 -310.980097)
			(xy 313.04661 -311.026778) (xy 313.054505 -311.075355) (xy 313.055 -311.099962) (xy 313.394102 -311.099962)
			(xy 313.398062 -311.050908) (xy 313.409839 -311.003124) (xy 313.42913 -310.957848) (xy 313.455433 -310.916252)
			(xy 313.488068 -310.879415) (xy 313.526189 -310.84829) (xy 313.56881 -310.823683) (xy 313.614826 -310.806231)
			(xy 313.663045 -310.796387) (xy 313.71222 -310.794406) (xy 313.761075 -310.800338) (xy 313.808346 -310.81403)
			(xy 313.852808 -310.835128) (xy 313.893311 -310.863084) (xy 313.928804 -310.897176) (xy 313.958369 -310.93652)
			(xy 313.98124 -310.980097) (xy 313.996824 -311.026778) (xy 314.004719 -311.075355) (xy 314.005214 -311.099962)
			(xy 314.344062 -311.099962) (xy 314.348022 -311.050908) (xy 314.359799 -311.003124) (xy 314.37909 -310.957848)
			(xy 314.405393 -310.916252) (xy 314.438028 -310.879415) (xy 314.476149 -310.84829) (xy 314.51877 -310.823683)
			(xy 314.564786 -310.806231) (xy 314.613005 -310.796387) (xy 314.66218 -310.794406) (xy 314.711035 -310.800338)
			(xy 314.758306 -310.81403) (xy 314.802768 -310.835128) (xy 314.843271 -310.863084) (xy 314.878764 -310.897176)
			(xy 314.908329 -310.93652) (xy 314.9312 -310.980097) (xy 314.946784 -311.026778) (xy 314.954679 -311.075355)
			(xy 314.955174 -311.099962) (xy 314.954679 -311.124569) (xy 314.946784 -311.173146) (xy 314.9312 -311.219827)
			(xy 314.908329 -311.263404) (xy 314.878764 -311.302748) (xy 314.843271 -311.33684) (xy 314.802768 -311.364796)
			(xy 314.768923 -311.380856) (xy 322.766688 -311.380856) (xy 322.774443 -311.326911) (xy 322.789796 -311.274618)
			(xy 322.812435 -311.225043) (xy 322.841898 -311.179194) (xy 322.877587 -311.138005) (xy 322.918773 -311.102314)
			(xy 322.96462 -311.072847) (xy 323.014194 -311.050205) (xy 323.066485 -311.034849) (xy 323.12043 -311.02709)
			(xy 323.174929 -311.027087) (xy 323.228874 -311.03484) (xy 323.281167 -311.050191) (xy 323.330743 -311.072828)
			(xy 323.376593 -311.102289) (xy 323.417784 -311.137976) (xy 323.453477 -311.179161) (xy 323.482945 -311.225007)
			(xy 323.505589 -311.274579) (xy 323.520948 -311.32687) (xy 323.528709 -311.380814) (xy 323.529198 -311.408064)
			(xy 323.529002 -311.425112) (xy 323.525947 -311.459072) (xy 323.523102 -311.475882) (xy 323.521061 -311.489765)
			(xy 323.523783 -311.517684) (xy 323.53399 -311.543811) (xy 323.550916 -311.566181) (xy 323.573284 -311.583107)
			(xy 323.599411 -311.593316) (xy 323.62733 -311.596039) (xy 323.641212 -311.593992) (xy 323.658083 -311.591119)
			(xy 323.692171 -311.588068) (xy 323.709284 -311.587896) (xy 323.736538 -311.588338) (xy 323.790492 -311.596093)
			(xy 323.842793 -311.611448) (xy 323.892377 -311.634089) (xy 323.938233 -311.663557) (xy 323.979429 -311.699251)
			(xy 324.015126 -311.740444) (xy 324.044597 -311.786299) (xy 324.067243 -311.835881) (xy 324.082601 -311.88818)
			(xy 324.09036 -311.942134) (xy 324.090362 -311.996642) (xy 324.082606 -312.050596) (xy 324.067251 -312.102897)
			(xy 324.044609 -312.15248) (xy 324.015141 -312.198336) (xy 323.979446 -312.239532) (xy 323.938252 -312.275229)
			(xy 323.892398 -312.304699) (xy 323.842816 -312.327344) (xy 323.790516 -312.342702) (xy 323.736562 -312.350461)
			(xy 323.682054 -312.350462) (xy 323.6281 -312.342705) (xy 323.575799 -312.32735) (xy 323.526216 -312.304707)
			(xy 323.48036 -312.275238) (xy 323.439165 -312.239543) (xy 323.403469 -312.198349) (xy 323.373999 -312.152494)
			(xy 323.351355 -312.102912) (xy 323.335997 -312.050612) (xy 323.328239 -311.996658) (xy 323.327776 -311.969404)
			(xy 323.327981 -311.952356) (xy 323.33103 -311.918397) (xy 323.333872 -311.901586) (xy 323.335976 -311.88771)
			(xy 323.333247 -311.859783) (xy 323.323029 -311.833649) (xy 323.306093 -311.811277) (xy 323.283714 -311.79435)
			(xy 323.257576 -311.784144) (xy 323.229648 -311.781425) (xy 323.215762 -311.783476) (xy 323.19889 -311.78634)
			(xy 323.164802 -311.789396) (xy 323.14769 -311.789572) (xy 323.12044 -311.789111) (xy 323.066496 -311.781354)
			(xy 323.014204 -311.765998) (xy 322.96463 -311.743358) (xy 322.918782 -311.713893) (xy 322.877594 -311.678203)
			(xy 322.841905 -311.637014) (xy 322.81244 -311.591166) (xy 322.7898 -311.541592) (xy 322.774445 -311.4893)
			(xy 322.766689 -311.435355) (xy 322.766688 -311.380856) (xy 314.768923 -311.380856) (xy 314.758306 -311.385894)
			(xy 314.711035 -311.399586) (xy 314.66218 -311.405518) (xy 314.613005 -311.403537) (xy 314.564786 -311.393693)
			(xy 314.51877 -311.376241) (xy 314.476149 -311.351634) (xy 314.438028 -311.320509) (xy 314.405393 -311.283672)
			(xy 314.37909 -311.242076) (xy 314.359799 -311.1968) (xy 314.348022 -311.149016) (xy 314.344062 -311.099962)
			(xy 314.005214 -311.099962) (xy 314.004719 -311.124569) (xy 313.996824 -311.173146) (xy 313.98124 -311.219827)
			(xy 313.958369 -311.263404) (xy 313.928804 -311.302748) (xy 313.893311 -311.33684) (xy 313.852808 -311.364796)
			(xy 313.808346 -311.385894) (xy 313.761075 -311.399586) (xy 313.71222 -311.405518) (xy 313.663045 -311.403537)
			(xy 313.614826 -311.393693) (xy 313.56881 -311.376241) (xy 313.526189 -311.351634) (xy 313.488068 -311.320509)
			(xy 313.455433 -311.283672) (xy 313.42913 -311.242076) (xy 313.409839 -311.1968) (xy 313.398062 -311.149016)
			(xy 313.394102 -311.099962) (xy 313.055 -311.099962) (xy 313.054505 -311.124569) (xy 313.04661 -311.173146)
			(xy 313.031026 -311.219827) (xy 313.008155 -311.263404) (xy 312.97859 -311.302748) (xy 312.943097 -311.33684)
			(xy 312.902594 -311.364796) (xy 312.858132 -311.385894) (xy 312.810861 -311.399586) (xy 312.762006 -311.405518)
			(xy 312.712831 -311.403537) (xy 312.664612 -311.393693) (xy 312.618596 -311.376241) (xy 312.575975 -311.351634)
			(xy 312.537854 -311.320509) (xy 312.505219 -311.283672) (xy 312.478916 -311.242076) (xy 312.459625 -311.1968)
			(xy 312.447848 -311.149016) (xy 312.443888 -311.099962) (xy 312.126342 -311.099962) (xy 312.126334 -311.126011)
			(xy 312.118273 -311.176797) (xy 312.102366 -311.225696) (xy 312.079004 -311.271504) (xy 312.048763 -311.313093)
			(xy 312.012388 -311.349439) (xy 311.970774 -311.379645) (xy 311.924946 -311.402969) (xy 311.876034 -311.418836)
			(xy 311.825242 -311.426855) (xy 311.77382 -311.426828) (xy 311.723036 -311.418757) (xy 311.67414 -311.40284)
			(xy 311.628337 -311.379468) (xy 311.586755 -311.349218) (xy 311.550417 -311.312835) (xy 311.520219 -311.271215)
			(xy 311.496904 -311.225383) (xy 311.481048 -311.176467) (xy 311.47304 -311.125673) (xy 311.47258 -311.099962)
			(xy 311.47279 -311.086239) (xy 311.475205 -311.058899) (xy 311.477406 -311.045352) (xy 311.479438 -311.03316)
			(xy 311.472326 -311.0103) (xy 311.39892 -310.933846) (xy 311.37606 -310.925972) (xy 311.364122 -310.927496)
			(xy 311.354323 -310.928687) (xy 311.334623 -310.929956) (xy 311.324752 -310.930036) (xy 311.310569 -310.929852)
			(xy 311.282329 -310.927185) (xy 311.268364 -310.924702) (xy 311.255918 -310.922416) (xy 311.232042 -310.929782)
			(xy 311.154826 -311.006998) (xy 311.14746 -311.031128) (xy 311.149746 -311.04332) (xy 311.152231 -311.057349)
			(xy 311.154903 -311.085716) (xy 311.15508 -311.099962) (xy 311.154663 -311.124786) (xy 311.146637 -311.173781)
			(xy 311.13079 -311.220833) (xy 311.10754 -311.2647) (xy 311.077499 -311.304228) (xy 311.041458 -311.338376)
			(xy 311.000368 -311.366243) (xy 310.955311 -311.387095) (xy 310.907474 -311.400382) (xy 310.858118 -311.405756)
			(xy 310.808542 -311.403074) (xy 310.760053 -311.392406) (xy 310.713929 -311.374035) (xy 310.671385 -311.348443)
			(xy 310.633541 -311.316305) (xy 310.601396 -311.278469) (xy 310.575795 -311.23593) (xy 310.557413 -311.18981)
			(xy 310.546735 -311.141324) (xy 310.544042 -311.091749) (xy 310.226803 -311.091749) (xy 310.226964 -311.099962)
			(xy 310.22646 -311.12567) (xy 310.218417 -311.176452) (xy 310.202529 -311.225351) (xy 310.179186 -311.271163)
			(xy 310.148965 -311.312759) (xy 310.112609 -311.349115) (xy 310.071013 -311.379336) (xy 310.025201 -311.402679)
			(xy 309.976302 -311.418567) (xy 309.92552 -311.42661) (xy 309.874104 -311.42661) (xy 309.823322 -311.418567)
			(xy 309.774423 -311.402679) (xy 309.728611 -311.379336) (xy 309.687015 -311.349115) (xy 309.650659 -311.312759)
			(xy 309.620438 -311.271163) (xy 309.597095 -311.225351) (xy 309.581207 -311.176452) (xy 309.573164 -311.12567)
			(xy 309.254486 -311.12567) (xy 309.24677 -311.173146) (xy 309.231186 -311.219827) (xy 309.208315 -311.263404)
			(xy 309.17875 -311.302748) (xy 309.143257 -311.33684) (xy 309.102754 -311.364796) (xy 309.058292 -311.385894)
			(xy 309.011021 -311.399586) (xy 308.962166 -311.405518) (xy 308.912991 -311.403537) (xy 308.864772 -311.393693)
			(xy 308.818756 -311.376241) (xy 308.776135 -311.351634) (xy 308.738014 -311.320509) (xy 308.705379 -311.283672)
			(xy 308.679076 -311.242076) (xy 308.659785 -311.1968) (xy 308.648008 -311.149016) (xy 308.644048 -311.099962)
			(xy 308.327044 -311.099962) (xy 308.32654 -311.12567) (xy 308.318497 -311.176452) (xy 308.302609 -311.225351)
			(xy 308.279266 -311.271163) (xy 308.249045 -311.312759) (xy 308.212689 -311.349115) (xy 308.171093 -311.379336)
			(xy 308.125281 -311.402679) (xy 308.076382 -311.418567) (xy 308.0256 -311.42661) (xy 307.974184 -311.42661)
			(xy 307.923402 -311.418567) (xy 307.874503 -311.402679) (xy 307.828691 -311.379336) (xy 307.787095 -311.349115)
			(xy 307.750739 -311.312759) (xy 307.720518 -311.271163) (xy 307.697175 -311.225351) (xy 307.681287 -311.176452)
			(xy 307.673244 -311.12567) (xy 307.354566 -311.12567) (xy 307.34685 -311.173146) (xy 307.331266 -311.219827)
			(xy 307.308395 -311.263404) (xy 307.27883 -311.302748) (xy 307.243337 -311.33684) (xy 307.202834 -311.364796)
			(xy 307.158372 -311.385894) (xy 307.111101 -311.399586) (xy 307.062246 -311.405518) (xy 307.013071 -311.403537)
			(xy 306.964852 -311.393693) (xy 306.918836 -311.376241) (xy 306.876215 -311.351634) (xy 306.838094 -311.320509)
			(xy 306.805459 -311.283672) (xy 306.779156 -311.242076) (xy 306.759865 -311.1968) (xy 306.748088 -311.149016)
			(xy 306.744128 -311.099962) (xy 306.42687 -311.099962) (xy 306.426366 -311.12567) (xy 306.418323 -311.176452)
			(xy 306.402435 -311.225351) (xy 306.379092 -311.271163) (xy 306.348871 -311.312759) (xy 306.312515 -311.349115)
			(xy 306.270919 -311.379336) (xy 306.225107 -311.402679) (xy 306.176208 -311.418567) (xy 306.125426 -311.42661)
			(xy 306.07401 -311.42661) (xy 306.023228 -311.418567) (xy 305.974329 -311.402679) (xy 305.928517 -311.379336)
			(xy 305.886921 -311.349115) (xy 305.850565 -311.312759) (xy 305.820344 -311.271163) (xy 305.797001 -311.225351)
			(xy 305.781113 -311.176452) (xy 305.77307 -311.12567) (xy 305.454392 -311.12567) (xy 305.446676 -311.173146)
			(xy 305.431092 -311.219827) (xy 305.408221 -311.263404) (xy 305.378656 -311.302748) (xy 305.343163 -311.33684)
			(xy 305.30266 -311.364796) (xy 305.258198 -311.385894) (xy 305.210927 -311.399586) (xy 305.162072 -311.405518)
			(xy 305.112897 -311.403537) (xy 305.064678 -311.393693) (xy 305.018662 -311.376241) (xy 304.976041 -311.351634)
			(xy 304.93792 -311.320509) (xy 304.905285 -311.283672) (xy 304.878982 -311.242076) (xy 304.859691 -311.1968)
			(xy 304.847914 -311.149016) (xy 304.843954 -311.099962) (xy 304.52695 -311.099962) (xy 304.526446 -311.12567)
			(xy 304.518403 -311.176452) (xy 304.502515 -311.225351) (xy 304.479172 -311.271163) (xy 304.448951 -311.312759)
			(xy 304.412595 -311.349115) (xy 304.370999 -311.379336) (xy 304.325187 -311.402679) (xy 304.276288 -311.418567)
			(xy 304.225506 -311.42661) (xy 304.17409 -311.42661) (xy 304.123308 -311.418567) (xy 304.074409 -311.402679)
			(xy 304.028597 -311.379336) (xy 303.987001 -311.349115) (xy 303.950645 -311.312759) (xy 303.920424 -311.271163)
			(xy 303.897081 -311.225351) (xy 303.881193 -311.176452) (xy 303.87315 -311.12567) (xy 303.554472 -311.12567)
			(xy 303.546756 -311.173146) (xy 303.531172 -311.219827) (xy 303.508301 -311.263404) (xy 303.478736 -311.302748)
			(xy 303.443243 -311.33684) (xy 303.40274 -311.364796) (xy 303.358278 -311.385894) (xy 303.311007 -311.399586)
			(xy 303.262152 -311.405518) (xy 303.212977 -311.403537) (xy 303.164758 -311.393693) (xy 303.118742 -311.376241)
			(xy 303.076121 -311.351634) (xy 303.038 -311.320509) (xy 303.005365 -311.283672) (xy 302.979062 -311.242076)
			(xy 302.959771 -311.1968) (xy 302.947994 -311.149016) (xy 302.944034 -311.099962) (xy 302.62703 -311.099962)
			(xy 302.626526 -311.12567) (xy 302.618483 -311.176452) (xy 302.602595 -311.225351) (xy 302.579252 -311.271163)
			(xy 302.549031 -311.312759) (xy 302.512675 -311.349115) (xy 302.471079 -311.379336) (xy 302.425267 -311.402679)
			(xy 302.376368 -311.418567) (xy 302.325586 -311.42661) (xy 302.27417 -311.42661) (xy 302.223388 -311.418567)
			(xy 302.174489 -311.402679) (xy 302.128677 -311.379336) (xy 302.087081 -311.349115) (xy 302.050725 -311.312759)
			(xy 302.020504 -311.271163) (xy 301.997161 -311.225351) (xy 301.981273 -311.176452) (xy 301.97323 -311.12567)
			(xy 301.654552 -311.12567) (xy 301.646836 -311.173146) (xy 301.631252 -311.219827) (xy 301.608381 -311.263404)
			(xy 301.578816 -311.302748) (xy 301.543323 -311.33684) (xy 301.50282 -311.364796) (xy 301.458358 -311.385894)
			(xy 301.411087 -311.399586) (xy 301.362232 -311.405518) (xy 301.313057 -311.403537) (xy 301.264838 -311.393693)
			(xy 301.218822 -311.376241) (xy 301.176201 -311.351634) (xy 301.13808 -311.320509) (xy 301.105445 -311.283672)
			(xy 301.079142 -311.242076) (xy 301.059851 -311.1968) (xy 301.048074 -311.149016) (xy 301.044114 -311.099962)
			(xy 300.726856 -311.099962) (xy 300.726352 -311.12567) (xy 300.718309 -311.176452) (xy 300.702421 -311.225351)
			(xy 300.679078 -311.271163) (xy 300.648857 -311.312759) (xy 300.612501 -311.349115) (xy 300.570905 -311.379336)
			(xy 300.525093 -311.402679) (xy 300.476194 -311.418567) (xy 300.425412 -311.42661) (xy 300.373996 -311.42661)
			(xy 300.323214 -311.418567) (xy 300.274315 -311.402679) (xy 300.228503 -311.379336) (xy 300.186907 -311.349115)
			(xy 300.150551 -311.312759) (xy 300.12033 -311.271163) (xy 300.096987 -311.225351) (xy 300.081099 -311.176452)
			(xy 300.073056 -311.12567) (xy 299.754378 -311.12567) (xy 299.746662 -311.173146) (xy 299.731078 -311.219827)
			(xy 299.708207 -311.263404) (xy 299.678642 -311.302748) (xy 299.643149 -311.33684) (xy 299.602646 -311.364796)
			(xy 299.558184 -311.385894) (xy 299.510913 -311.399586) (xy 299.462058 -311.405518) (xy 299.412883 -311.403537)
			(xy 299.364664 -311.393693) (xy 299.318648 -311.376241) (xy 299.276027 -311.351634) (xy 299.237906 -311.320509)
			(xy 299.205271 -311.283672) (xy 299.178968 -311.242076) (xy 299.159677 -311.1968) (xy 299.1479 -311.149016)
			(xy 299.14394 -311.099962) (xy 298.826936 -311.099962) (xy 298.826432 -311.12567) (xy 298.818389 -311.176452)
			(xy 298.802501 -311.225351) (xy 298.779158 -311.271163) (xy 298.748937 -311.312759) (xy 298.712581 -311.349115)
			(xy 298.670985 -311.379336) (xy 298.625173 -311.402679) (xy 298.576274 -311.418567) (xy 298.525492 -311.42661)
			(xy 298.474076 -311.42661) (xy 298.423294 -311.418567) (xy 298.374395 -311.402679) (xy 298.328583 -311.379336)
			(xy 298.286987 -311.349115) (xy 298.250631 -311.312759) (xy 298.22041 -311.271163) (xy 298.197067 -311.225351)
			(xy 298.181179 -311.176452) (xy 298.173136 -311.12567) (xy 297.854458 -311.12567) (xy 297.846742 -311.173146)
			(xy 297.831158 -311.219827) (xy 297.808287 -311.263404) (xy 297.778722 -311.302748) (xy 297.743229 -311.33684)
			(xy 297.702726 -311.364796) (xy 297.658264 -311.385894) (xy 297.610993 -311.399586) (xy 297.562138 -311.405518)
			(xy 297.512963 -311.403537) (xy 297.464744 -311.393693) (xy 297.418728 -311.376241) (xy 297.376107 -311.351634)
			(xy 297.337986 -311.320509) (xy 297.305351 -311.283672) (xy 297.279048 -311.242076) (xy 297.259757 -311.1968)
			(xy 297.24798 -311.149016) (xy 297.24402 -311.099962) (xy 296.927016 -311.099962) (xy 296.926512 -311.12567)
			(xy 296.918469 -311.176452) (xy 296.902581 -311.225351) (xy 296.879238 -311.271163) (xy 296.849017 -311.312759)
			(xy 296.812661 -311.349115) (xy 296.771065 -311.379336) (xy 296.725253 -311.402679) (xy 296.676354 -311.418567)
			(xy 296.625572 -311.42661) (xy 296.574156 -311.42661) (xy 296.523374 -311.418567) (xy 296.474475 -311.402679)
			(xy 296.428663 -311.379336) (xy 296.387067 -311.349115) (xy 296.350711 -311.312759) (xy 296.32049 -311.271163)
			(xy 296.297147 -311.225351) (xy 296.281259 -311.176452) (xy 296.273216 -311.12567) (xy 295.954538 -311.12567)
			(xy 295.946822 -311.173146) (xy 295.931238 -311.219827) (xy 295.908367 -311.263404) (xy 295.878802 -311.302748)
			(xy 295.843309 -311.33684) (xy 295.802806 -311.364796) (xy 295.758344 -311.385894) (xy 295.711073 -311.399586)
			(xy 295.662218 -311.405518) (xy 295.613043 -311.403537) (xy 295.564824 -311.393693) (xy 295.518808 -311.376241)
			(xy 295.476187 -311.351634) (xy 295.438066 -311.320509) (xy 295.405431 -311.283672) (xy 295.379128 -311.242076)
			(xy 295.359837 -311.1968) (xy 295.34806 -311.149016) (xy 295.3441 -311.099962) (xy 295.026842 -311.099962)
			(xy 295.026338 -311.12567) (xy 295.018295 -311.176452) (xy 295.002407 -311.225351) (xy 294.979064 -311.271163)
			(xy 294.948843 -311.312759) (xy 294.912487 -311.349115) (xy 294.870891 -311.379336) (xy 294.825079 -311.402679)
			(xy 294.77618 -311.418567) (xy 294.725398 -311.42661) (xy 294.673982 -311.42661) (xy 294.6232 -311.418567)
			(xy 294.574301 -311.402679) (xy 294.528489 -311.379336) (xy 294.486893 -311.349115) (xy 294.450537 -311.312759)
			(xy 294.420316 -311.271163) (xy 294.396973 -311.225351) (xy 294.381085 -311.176452) (xy 294.373042 -311.12567)
			(xy 294.054364 -311.12567) (xy 294.046648 -311.173146) (xy 294.031064 -311.219827) (xy 294.008193 -311.263404)
			(xy 293.978628 -311.302748) (xy 293.943135 -311.33684) (xy 293.902632 -311.364796) (xy 293.85817 -311.385894)
			(xy 293.810899 -311.399586) (xy 293.762044 -311.405518) (xy 293.712869 -311.403537) (xy 293.66465 -311.393693)
			(xy 293.618634 -311.376241) (xy 293.576013 -311.351634) (xy 293.537892 -311.320509) (xy 293.505257 -311.283672)
			(xy 293.478954 -311.242076) (xy 293.459663 -311.1968) (xy 293.447886 -311.149016) (xy 293.443926 -311.099962)
			(xy 293.126922 -311.099962) (xy 293.126418 -311.12567) (xy 293.118375 -311.176452) (xy 293.102487 -311.225351)
			(xy 293.079144 -311.271163) (xy 293.048923 -311.312759) (xy 293.012567 -311.349115) (xy 292.970971 -311.379336)
			(xy 292.925159 -311.402679) (xy 292.87626 -311.418567) (xy 292.825478 -311.42661) (xy 292.774062 -311.42661)
			(xy 292.72328 -311.418567) (xy 292.674381 -311.402679) (xy 292.628569 -311.379336) (xy 292.586973 -311.349115)
			(xy 292.550617 -311.312759) (xy 292.520396 -311.271163) (xy 292.497053 -311.225351) (xy 292.481165 -311.176452)
			(xy 292.473122 -311.12567) (xy 292.154444 -311.12567) (xy 292.146728 -311.173146) (xy 292.131144 -311.219827)
			(xy 292.108273 -311.263404) (xy 292.078708 -311.302748) (xy 292.043215 -311.33684) (xy 292.002712 -311.364796)
			(xy 291.95825 -311.385894) (xy 291.910979 -311.399586) (xy 291.862124 -311.405518) (xy 291.812949 -311.403537)
			(xy 291.76473 -311.393693) (xy 291.718714 -311.376241) (xy 291.676093 -311.351634) (xy 291.637972 -311.320509)
			(xy 291.605337 -311.283672) (xy 291.579034 -311.242076) (xy 291.559743 -311.1968) (xy 291.547966 -311.149016)
			(xy 291.544006 -311.099962) (xy 291.227002 -311.099962) (xy 291.226498 -311.12567) (xy 291.218455 -311.176452)
			(xy 291.202567 -311.225351) (xy 291.179224 -311.271163) (xy 291.149003 -311.312759) (xy 291.112647 -311.349115)
			(xy 291.071051 -311.379336) (xy 291.025239 -311.402679) (xy 290.97634 -311.418567) (xy 290.925558 -311.42661)
			(xy 290.874142 -311.42661) (xy 290.82336 -311.418567) (xy 290.774461 -311.402679) (xy 290.728649 -311.379336)
			(xy 290.687053 -311.349115) (xy 290.650697 -311.312759) (xy 290.620476 -311.271163) (xy 290.597133 -311.225351)
			(xy 290.581245 -311.176452) (xy 290.573202 -311.12567) (xy 290.254666 -311.12567) (xy 290.254655 -311.126216)
			(xy 290.245681 -311.177953) (xy 290.227991 -311.227391) (xy 290.202106 -311.273076) (xy 290.168788 -311.313661)
			(xy 290.129021 -311.347949) (xy 290.083975 -311.374931) (xy 290.034978 -311.393811) (xy 290.009326 -311.399428)
			(xy 289.998645 -311.402104) (xy 289.980851 -311.415034) (xy 289.970108 -311.434228) (xy 289.968686 -311.445148)
			(xy 289.965928 -311.475209) (xy 289.957158 -311.534942) (xy 289.95116 -311.564528) (xy 289.950217 -311.569693)
			(xy 289.950225 -311.580189) (xy 289.95116 -311.585356) (xy 289.95717 -311.61494) (xy 289.96594 -311.674673)
			(xy 289.968686 -311.704736) (xy 289.97011 -311.715652) (xy 289.980872 -311.73483) (xy 289.99865 -311.747775)
			(xy 290.009326 -311.750456) (xy 290.034504 -311.756003) (xy 290.082666 -311.774393) (xy 290.127058 -311.800606)
			(xy 290.16642 -311.833897) (xy 290.199636 -311.873324) (xy 290.225763 -311.917766) (xy 290.24406 -311.965963)
			(xy 290.254007 -312.016547) (xy 290.255198 -312.042302) (xy 290.255832 -312.052435) (xy 290.264061 -312.070976)
			(xy 290.278858 -312.084852) (xy 290.288218 -312.088784) (xy 290.325941 -312.103207) (xy 290.399083 -312.137468)
			(xy 290.469128 -312.177683) (xy 290.502594 -312.20029) (xy 290.506005 -312.202585) (xy 290.513408 -312.206158)
			(xy 290.517326 -312.207402) (xy 290.523422 -312.20918) (xy 290.53416 -312.211987) (xy 290.556146 -312.209135)
			(xy 290.574885 -312.197287) (xy 290.586889 -312.178648) (xy 290.589923 -312.156686) (xy 290.587176 -312.145934)
			(xy 290.580465 -312.122503) (xy 290.573326 -312.074292) (xy 290.572952 -312.049922) (xy 290.573428 -312.024227)
			(xy 290.581464 -311.973469) (xy 290.597342 -311.924594) (xy 290.62067 -311.878804) (xy 290.650875 -311.837227)
			(xy 290.687212 -311.800888) (xy 290.728787 -311.770681) (xy 290.774575 -311.747349) (xy 290.82345 -311.731469)
			(xy 290.874207 -311.723429) (xy 290.925597 -311.72343) (xy 290.976354 -311.73147) (xy 291.025229 -311.747351)
			(xy 291.071017 -311.770683) (xy 291.112591 -311.800891) (xy 291.148928 -311.83723) (xy 291.179132 -311.878807)
			(xy 291.20246 -311.924597) (xy 291.218337 -311.973473) (xy 291.226372 -312.024231) (xy 291.22637 -312.049922)
			(xy 291.544006 -312.049922) (xy 291.547966 -312.000868) (xy 291.559743 -311.953084) (xy 291.579034 -311.907808)
			(xy 291.605337 -311.866212) (xy 291.637972 -311.829375) (xy 291.676093 -311.79825) (xy 291.718714 -311.773643)
			(xy 291.76473 -311.756191) (xy 291.812949 -311.746347) (xy 291.862124 -311.744366) (xy 291.910979 -311.750298)
			(xy 291.95825 -311.76399) (xy 292.002712 -311.785088) (xy 292.043215 -311.813044) (xy 292.078708 -311.847136)
			(xy 292.108273 -311.88648) (xy 292.131144 -311.930057) (xy 292.146728 -311.976738) (xy 292.154623 -312.025315)
			(xy 292.155118 -312.049922) (xy 292.154623 -312.074529) (xy 292.154444 -312.07563) (xy 292.473122 -312.07563)
			(xy 292.473122 -312.024214) (xy 292.481165 -311.973432) (xy 292.497053 -311.924533) (xy 292.520396 -311.878721)
			(xy 292.550617 -311.837125) (xy 292.586973 -311.800769) (xy 292.628569 -311.770548) (xy 292.674381 -311.747205)
			(xy 292.72328 -311.731317) (xy 292.774062 -311.723274) (xy 292.825478 -311.723274) (xy 292.87626 -311.731317)
			(xy 292.925159 -311.747205) (xy 292.970971 -311.770548) (xy 293.012567 -311.800769) (xy 293.048923 -311.837125)
			(xy 293.079144 -311.878721) (xy 293.102487 -311.924533) (xy 293.118375 -311.973432) (xy 293.126418 -312.024214)
			(xy 293.126922 -312.049922) (xy 293.443926 -312.049922) (xy 293.447886 -312.000868) (xy 293.459663 -311.953084)
			(xy 293.478954 -311.907808) (xy 293.505257 -311.866212) (xy 293.537892 -311.829375) (xy 293.576013 -311.79825)
			(xy 293.618634 -311.773643) (xy 293.66465 -311.756191) (xy 293.712869 -311.746347) (xy 293.762044 -311.744366)
			(xy 293.810899 -311.750298) (xy 293.85817 -311.76399) (xy 293.902632 -311.785088) (xy 293.943135 -311.813044)
			(xy 293.978628 -311.847136) (xy 294.008193 -311.88648) (xy 294.031064 -311.930057) (xy 294.046648 -311.976738)
			(xy 294.054543 -312.025315) (xy 294.055038 -312.049922) (xy 294.054543 -312.074529) (xy 294.054364 -312.07563)
			(xy 294.373042 -312.07563) (xy 294.373042 -312.024214) (xy 294.381085 -311.973432) (xy 294.396973 -311.924533)
			(xy 294.420316 -311.878721) (xy 294.450537 -311.837125) (xy 294.486893 -311.800769) (xy 294.528489 -311.770548)
			(xy 294.574301 -311.747205) (xy 294.6232 -311.731317) (xy 294.673982 -311.723274) (xy 294.725398 -311.723274)
			(xy 294.77618 -311.731317) (xy 294.825079 -311.747205) (xy 294.870891 -311.770548) (xy 294.912487 -311.800769)
			(xy 294.948843 -311.837125) (xy 294.979064 -311.878721) (xy 295.002407 -311.924533) (xy 295.018295 -311.973432)
			(xy 295.026338 -312.024214) (xy 295.026842 -312.049922) (xy 295.3441 -312.049922) (xy 295.34806 -312.000868)
			(xy 295.359837 -311.953084) (xy 295.379128 -311.907808) (xy 295.405431 -311.866212) (xy 295.438066 -311.829375)
			(xy 295.476187 -311.79825) (xy 295.518808 -311.773643) (xy 295.564824 -311.756191) (xy 295.613043 -311.746347)
			(xy 295.662218 -311.744366) (xy 295.711073 -311.750298) (xy 295.758344 -311.76399) (xy 295.802806 -311.785088)
			(xy 295.843309 -311.813044) (xy 295.878802 -311.847136) (xy 295.908367 -311.88648) (xy 295.931238 -311.930057)
			(xy 295.946822 -311.976738) (xy 295.954717 -312.025315) (xy 295.955212 -312.049922) (xy 295.954717 -312.074529)
			(xy 295.954538 -312.07563) (xy 296.273216 -312.07563) (xy 296.273216 -312.024214) (xy 296.281259 -311.973432)
			(xy 296.297147 -311.924533) (xy 296.32049 -311.878721) (xy 296.350711 -311.837125) (xy 296.387067 -311.800769)
			(xy 296.428663 -311.770548) (xy 296.474475 -311.747205) (xy 296.523374 -311.731317) (xy 296.574156 -311.723274)
			(xy 296.625572 -311.723274) (xy 296.676354 -311.731317) (xy 296.725253 -311.747205) (xy 296.771065 -311.770548)
			(xy 296.812661 -311.800769) (xy 296.849017 -311.837125) (xy 296.879238 -311.878721) (xy 296.902581 -311.924533)
			(xy 296.918469 -311.973432) (xy 296.926512 -312.024214) (xy 296.927016 -312.049922) (xy 297.24402 -312.049922)
			(xy 297.24798 -312.000868) (xy 297.259757 -311.953084) (xy 297.279048 -311.907808) (xy 297.305351 -311.866212)
			(xy 297.337986 -311.829375) (xy 297.376107 -311.79825) (xy 297.418728 -311.773643) (xy 297.464744 -311.756191)
			(xy 297.512963 -311.746347) (xy 297.562138 -311.744366) (xy 297.610993 -311.750298) (xy 297.658264 -311.76399)
			(xy 297.702726 -311.785088) (xy 297.743229 -311.813044) (xy 297.778722 -311.847136) (xy 297.808287 -311.88648)
			(xy 297.831158 -311.930057) (xy 297.846742 -311.976738) (xy 297.854637 -312.025315) (xy 297.855132 -312.049922)
			(xy 297.854637 -312.074529) (xy 297.854458 -312.07563) (xy 298.173136 -312.07563) (xy 298.173136 -312.024214)
			(xy 298.181179 -311.973432) (xy 298.197067 -311.924533) (xy 298.22041 -311.878721) (xy 298.250631 -311.837125)
			(xy 298.286987 -311.800769) (xy 298.328583 -311.770548) (xy 298.374395 -311.747205) (xy 298.423294 -311.731317)
			(xy 298.474076 -311.723274) (xy 298.525492 -311.723274) (xy 298.576274 -311.731317) (xy 298.625173 -311.747205)
			(xy 298.670985 -311.770548) (xy 298.712581 -311.800769) (xy 298.748937 -311.837125) (xy 298.779158 -311.878721)
			(xy 298.802501 -311.924533) (xy 298.818389 -311.973432) (xy 298.826432 -312.024214) (xy 298.826936 -312.049922)
			(xy 299.14394 -312.049922) (xy 299.1479 -312.000868) (xy 299.159677 -311.953084) (xy 299.178968 -311.907808)
			(xy 299.205271 -311.866212) (xy 299.237906 -311.829375) (xy 299.276027 -311.79825) (xy 299.318648 -311.773643)
			(xy 299.364664 -311.756191) (xy 299.412883 -311.746347) (xy 299.462058 -311.744366) (xy 299.510913 -311.750298)
			(xy 299.558184 -311.76399) (xy 299.602646 -311.785088) (xy 299.643149 -311.813044) (xy 299.678642 -311.847136)
			(xy 299.708207 -311.88648) (xy 299.731078 -311.930057) (xy 299.746662 -311.976738) (xy 299.754557 -312.025315)
			(xy 299.755052 -312.049922) (xy 299.754557 -312.074529) (xy 299.754378 -312.07563) (xy 300.073056 -312.07563)
			(xy 300.073056 -312.024214) (xy 300.081099 -311.973432) (xy 300.096987 -311.924533) (xy 300.12033 -311.878721)
			(xy 300.150551 -311.837125) (xy 300.186907 -311.800769) (xy 300.228503 -311.770548) (xy 300.274315 -311.747205)
			(xy 300.323214 -311.731317) (xy 300.373996 -311.723274) (xy 300.425412 -311.723274) (xy 300.476194 -311.731317)
			(xy 300.525093 -311.747205) (xy 300.570905 -311.770548) (xy 300.612501 -311.800769) (xy 300.648857 -311.837125)
			(xy 300.679078 -311.878721) (xy 300.702421 -311.924533) (xy 300.718309 -311.973432) (xy 300.726352 -312.024214)
			(xy 300.726856 -312.049922) (xy 301.044114 -312.049922) (xy 301.048074 -312.000868) (xy 301.059851 -311.953084)
			(xy 301.079142 -311.907808) (xy 301.105445 -311.866212) (xy 301.13808 -311.829375) (xy 301.176201 -311.79825)
			(xy 301.218822 -311.773643) (xy 301.264838 -311.756191) (xy 301.313057 -311.746347) (xy 301.362232 -311.744366)
			(xy 301.411087 -311.750298) (xy 301.458358 -311.76399) (xy 301.50282 -311.785088) (xy 301.543323 -311.813044)
			(xy 301.578816 -311.847136) (xy 301.608381 -311.88648) (xy 301.631252 -311.930057) (xy 301.646836 -311.976738)
			(xy 301.654731 -312.025315) (xy 301.655226 -312.049922) (xy 301.654731 -312.074529) (xy 301.654552 -312.07563)
			(xy 301.97323 -312.07563) (xy 301.97323 -312.024214) (xy 301.981273 -311.973432) (xy 301.997161 -311.924533)
			(xy 302.020504 -311.878721) (xy 302.050725 -311.837125) (xy 302.087081 -311.800769) (xy 302.128677 -311.770548)
			(xy 302.174489 -311.747205) (xy 302.223388 -311.731317) (xy 302.27417 -311.723274) (xy 302.325586 -311.723274)
			(xy 302.376368 -311.731317) (xy 302.425267 -311.747205) (xy 302.471079 -311.770548) (xy 302.512675 -311.800769)
			(xy 302.549031 -311.837125) (xy 302.579252 -311.878721) (xy 302.602595 -311.924533) (xy 302.618483 -311.973432)
			(xy 302.626526 -312.024214) (xy 302.62703 -312.049922) (xy 302.944034 -312.049922) (xy 302.947994 -312.000868)
			(xy 302.959771 -311.953084) (xy 302.979062 -311.907808) (xy 303.005365 -311.866212) (xy 303.038 -311.829375)
			(xy 303.076121 -311.79825) (xy 303.118742 -311.773643) (xy 303.164758 -311.756191) (xy 303.212977 -311.746347)
			(xy 303.262152 -311.744366) (xy 303.311007 -311.750298) (xy 303.358278 -311.76399) (xy 303.40274 -311.785088)
			(xy 303.443243 -311.813044) (xy 303.478736 -311.847136) (xy 303.508301 -311.88648) (xy 303.531172 -311.930057)
			(xy 303.546756 -311.976738) (xy 303.554651 -312.025315) (xy 303.555146 -312.049922) (xy 303.554651 -312.074529)
			(xy 303.554472 -312.07563) (xy 303.87315 -312.07563) (xy 303.87315 -312.024214) (xy 303.881193 -311.973432)
			(xy 303.897081 -311.924533) (xy 303.920424 -311.878721) (xy 303.950645 -311.837125) (xy 303.987001 -311.800769)
			(xy 304.028597 -311.770548) (xy 304.074409 -311.747205) (xy 304.123308 -311.731317) (xy 304.17409 -311.723274)
			(xy 304.225506 -311.723274) (xy 304.276288 -311.731317) (xy 304.325187 -311.747205) (xy 304.370999 -311.770548)
			(xy 304.412595 -311.800769) (xy 304.448951 -311.837125) (xy 304.479172 -311.878721) (xy 304.502515 -311.924533)
			(xy 304.518403 -311.973432) (xy 304.526446 -312.024214) (xy 304.52695 -312.049922) (xy 304.843954 -312.049922)
			(xy 304.847914 -312.000868) (xy 304.859691 -311.953084) (xy 304.878982 -311.907808) (xy 304.905285 -311.866212)
			(xy 304.93792 -311.829375) (xy 304.976041 -311.79825) (xy 305.018662 -311.773643) (xy 305.064678 -311.756191)
			(xy 305.112897 -311.746347) (xy 305.162072 -311.744366) (xy 305.210927 -311.750298) (xy 305.258198 -311.76399)
			(xy 305.30266 -311.785088) (xy 305.343163 -311.813044) (xy 305.378656 -311.847136) (xy 305.408221 -311.88648)
			(xy 305.431092 -311.930057) (xy 305.446676 -311.976738) (xy 305.454571 -312.025315) (xy 305.455066 -312.049922)
			(xy 305.454571 -312.074529) (xy 305.454392 -312.07563) (xy 305.77307 -312.07563) (xy 305.77307 -312.024214)
			(xy 305.781113 -311.973432) (xy 305.797001 -311.924533) (xy 305.820344 -311.878721) (xy 305.850565 -311.837125)
			(xy 305.886921 -311.800769) (xy 305.928517 -311.770548) (xy 305.974329 -311.747205) (xy 306.023228 -311.731317)
			(xy 306.07401 -311.723274) (xy 306.125426 -311.723274) (xy 306.176208 -311.731317) (xy 306.225107 -311.747205)
			(xy 306.270919 -311.770548) (xy 306.312515 -311.800769) (xy 306.348871 -311.837125) (xy 306.379092 -311.878721)
			(xy 306.402435 -311.924533) (xy 306.418323 -311.973432) (xy 306.426366 -312.024214) (xy 306.42687 -312.049922)
			(xy 306.744128 -312.049922) (xy 306.748088 -312.000868) (xy 306.759865 -311.953084) (xy 306.779156 -311.907808)
			(xy 306.805459 -311.866212) (xy 306.838094 -311.829375) (xy 306.876215 -311.79825) (xy 306.918836 -311.773643)
			(xy 306.964852 -311.756191) (xy 307.013071 -311.746347) (xy 307.062246 -311.744366) (xy 307.111101 -311.750298)
			(xy 307.158372 -311.76399) (xy 307.202834 -311.785088) (xy 307.243337 -311.813044) (xy 307.27883 -311.847136)
			(xy 307.308395 -311.88648) (xy 307.331266 -311.930057) (xy 307.34685 -311.976738) (xy 307.354745 -312.025315)
			(xy 307.35524 -312.049922) (xy 307.354745 -312.074529) (xy 307.354566 -312.07563) (xy 307.673244 -312.07563)
			(xy 307.673244 -312.024214) (xy 307.681287 -311.973432) (xy 307.697175 -311.924533) (xy 307.720518 -311.878721)
			(xy 307.750739 -311.837125) (xy 307.787095 -311.800769) (xy 307.828691 -311.770548) (xy 307.874503 -311.747205)
			(xy 307.923402 -311.731317) (xy 307.974184 -311.723274) (xy 308.0256 -311.723274) (xy 308.076382 -311.731317)
			(xy 308.125281 -311.747205) (xy 308.171093 -311.770548) (xy 308.212689 -311.800769) (xy 308.249045 -311.837125)
			(xy 308.279266 -311.878721) (xy 308.302609 -311.924533) (xy 308.318497 -311.973432) (xy 308.32654 -312.024214)
			(xy 308.327044 -312.049922) (xy 308.644048 -312.049922) (xy 308.648008 -312.000868) (xy 308.659785 -311.953084)
			(xy 308.679076 -311.907808) (xy 308.705379 -311.866212) (xy 308.738014 -311.829375) (xy 308.776135 -311.79825)
			(xy 308.818756 -311.773643) (xy 308.864772 -311.756191) (xy 308.912991 -311.746347) (xy 308.962166 -311.744366)
			(xy 309.011021 -311.750298) (xy 309.058292 -311.76399) (xy 309.102754 -311.785088) (xy 309.143257 -311.813044)
			(xy 309.17875 -311.847136) (xy 309.208315 -311.88648) (xy 309.231186 -311.930057) (xy 309.24677 -311.976738)
			(xy 309.254665 -312.025315) (xy 309.25516 -312.049922) (xy 309.254665 -312.074529) (xy 309.254486 -312.07563)
			(xy 309.573164 -312.07563) (xy 309.573164 -312.024214) (xy 309.581207 -311.973432) (xy 309.597095 -311.924533)
			(xy 309.620438 -311.878721) (xy 309.650659 -311.837125) (xy 309.687015 -311.800769) (xy 309.728611 -311.770548)
			(xy 309.774423 -311.747205) (xy 309.823322 -311.731317) (xy 309.874104 -311.723274) (xy 309.92552 -311.723274)
			(xy 309.976302 -311.731317) (xy 310.025201 -311.747205) (xy 310.071013 -311.770548) (xy 310.112609 -311.800769)
			(xy 310.148965 -311.837125) (xy 310.179186 -311.878721) (xy 310.202529 -311.924533) (xy 310.218417 -311.973432)
			(xy 310.22646 -312.024214) (xy 310.226964 -312.049922) (xy 310.543968 -312.049922) (xy 310.547928 -312.000868)
			(xy 310.559705 -311.953084) (xy 310.578996 -311.907808) (xy 310.605299 -311.866212) (xy 310.637934 -311.829375)
			(xy 310.676055 -311.79825) (xy 310.718676 -311.773643) (xy 310.764692 -311.756191) (xy 310.812911 -311.746347)
			(xy 310.862086 -311.744366) (xy 310.910941 -311.750298) (xy 310.958212 -311.76399) (xy 311.002674 -311.785088)
			(xy 311.043177 -311.813044) (xy 311.07867 -311.847136) (xy 311.108235 -311.88648) (xy 311.131106 -311.930057)
			(xy 311.14669 -311.976738) (xy 311.154585 -312.025315) (xy 311.15508 -312.049922) (xy 311.154585 -312.074529)
			(xy 311.154406 -312.07563) (xy 311.473084 -312.07563) (xy 311.473084 -312.024214) (xy 311.481127 -311.973432)
			(xy 311.497015 -311.924533) (xy 311.520358 -311.878721) (xy 311.550579 -311.837125) (xy 311.586935 -311.800769)
			(xy 311.628531 -311.770548) (xy 311.674343 -311.747205) (xy 311.723242 -311.731317) (xy 311.774024 -311.723274)
			(xy 311.82544 -311.723274) (xy 311.876222 -311.731317) (xy 311.925121 -311.747205) (xy 311.970933 -311.770548)
			(xy 312.012529 -311.800769) (xy 312.048885 -311.837125) (xy 312.079106 -311.878721) (xy 312.102449 -311.924533)
			(xy 312.118337 -311.973432) (xy 312.12638 -312.024214) (xy 312.126884 -312.049922) (xy 312.443888 -312.049922)
			(xy 312.447848 -312.000868) (xy 312.459625 -311.953084) (xy 312.478916 -311.907808) (xy 312.505219 -311.866212)
			(xy 312.537854 -311.829375) (xy 312.575975 -311.79825) (xy 312.618596 -311.773643) (xy 312.664612 -311.756191)
			(xy 312.712831 -311.746347) (xy 312.762006 -311.744366) (xy 312.810861 -311.750298) (xy 312.858132 -311.76399)
			(xy 312.902594 -311.785088) (xy 312.943097 -311.813044) (xy 312.97859 -311.847136) (xy 313.008155 -311.88648)
			(xy 313.031026 -311.930057) (xy 313.04661 -311.976738) (xy 313.054505 -312.025315) (xy 313.055 -312.049922)
			(xy 313.054505 -312.074529) (xy 313.054326 -312.07563) (xy 313.373258 -312.07563) (xy 313.373258 -312.024214)
			(xy 313.381301 -311.973432) (xy 313.397189 -311.924533) (xy 313.420532 -311.878721) (xy 313.450753 -311.837125)
			(xy 313.487109 -311.800769) (xy 313.528705 -311.770548) (xy 313.574517 -311.747205) (xy 313.623416 -311.731317)
			(xy 313.674198 -311.723274) (xy 313.725614 -311.723274) (xy 313.776396 -311.731317) (xy 313.825295 -311.747205)
			(xy 313.871107 -311.770548) (xy 313.912703 -311.800769) (xy 313.949059 -311.837125) (xy 313.97928 -311.878721)
			(xy 314.002623 -311.924533) (xy 314.018511 -311.973432) (xy 314.026554 -312.024214) (xy 314.027058 -312.049922)
			(xy 314.026554 -312.07563) (xy 314.323218 -312.07563) (xy 314.323218 -312.024214) (xy 314.331261 -311.973432)
			(xy 314.347149 -311.924533) (xy 314.370492 -311.878721) (xy 314.400713 -311.837125) (xy 314.437069 -311.800769)
			(xy 314.478665 -311.770548) (xy 314.524477 -311.747205) (xy 314.573376 -311.731317) (xy 314.624158 -311.723274)
			(xy 314.675574 -311.723274) (xy 314.726356 -311.731317) (xy 314.775255 -311.747205) (xy 314.821067 -311.770548)
			(xy 314.862663 -311.800769) (xy 314.899019 -311.837125) (xy 314.92924 -311.878721) (xy 314.952583 -311.924533)
			(xy 314.968471 -311.973432) (xy 314.976514 -312.024214) (xy 314.977018 -312.049922) (xy 315.294276 -312.049922)
			(xy 315.298236 -312.000868) (xy 315.310013 -311.953084) (xy 315.329304 -311.907808) (xy 315.355607 -311.866212)
			(xy 315.388242 -311.829375) (xy 315.426363 -311.79825) (xy 315.468984 -311.773643) (xy 315.515 -311.756191)
			(xy 315.563219 -311.746347) (xy 315.612394 -311.744366) (xy 315.661249 -311.750298) (xy 315.70852 -311.76399)
			(xy 315.752982 -311.785088) (xy 315.793485 -311.813044) (xy 315.828978 -311.847136) (xy 315.858543 -311.88648)
			(xy 315.881414 -311.930057) (xy 315.896998 -311.976738) (xy 315.904893 -312.025315) (xy 315.905388 -312.049922)
			(xy 315.904893 -312.074529) (xy 315.896998 -312.123106) (xy 315.881414 -312.169787) (xy 315.858543 -312.213364)
			(xy 315.828978 -312.252708) (xy 315.793485 -312.2868) (xy 315.752982 -312.314756) (xy 315.70852 -312.335854)
			(xy 315.661249 -312.349546) (xy 315.612394 -312.355478) (xy 315.563219 -312.353497) (xy 315.515 -312.343653)
			(xy 315.468984 -312.326201) (xy 315.426363 -312.301594) (xy 315.388242 -312.270469) (xy 315.355607 -312.233632)
			(xy 315.329304 -312.192036) (xy 315.310013 -312.14676) (xy 315.298236 -312.098976) (xy 315.294276 -312.049922)
			(xy 314.977018 -312.049922) (xy 314.976514 -312.07563) (xy 314.968471 -312.126412) (xy 314.952583 -312.175311)
			(xy 314.92924 -312.221123) (xy 314.899019 -312.262719) (xy 314.862663 -312.299075) (xy 314.821067 -312.329296)
			(xy 314.775255 -312.352639) (xy 314.726356 -312.368527) (xy 314.675574 -312.37657) (xy 314.624158 -312.37657)
			(xy 314.573376 -312.368527) (xy 314.524477 -312.352639) (xy 314.478665 -312.329296) (xy 314.437069 -312.299075)
			(xy 314.400713 -312.262719) (xy 314.370492 -312.221123) (xy 314.347149 -312.175311) (xy 314.331261 -312.126412)
			(xy 314.323218 -312.07563) (xy 314.026554 -312.07563) (xy 314.018511 -312.126412) (xy 314.002623 -312.175311)
			(xy 313.97928 -312.221123) (xy 313.949059 -312.262719) (xy 313.912703 -312.299075) (xy 313.871107 -312.329296)
			(xy 313.825295 -312.352639) (xy 313.776396 -312.368527) (xy 313.725614 -312.37657) (xy 313.674198 -312.37657)
			(xy 313.623416 -312.368527) (xy 313.574517 -312.352639) (xy 313.528705 -312.329296) (xy 313.487109 -312.299075)
			(xy 313.450753 -312.262719) (xy 313.420532 -312.221123) (xy 313.397189 -312.175311) (xy 313.381301 -312.126412)
			(xy 313.373258 -312.07563) (xy 313.054326 -312.07563) (xy 313.04661 -312.123106) (xy 313.031026 -312.169787)
			(xy 313.008155 -312.213364) (xy 312.97859 -312.252708) (xy 312.943097 -312.2868) (xy 312.902594 -312.314756)
			(xy 312.858132 -312.335854) (xy 312.810861 -312.349546) (xy 312.762006 -312.355478) (xy 312.712831 -312.353497)
			(xy 312.664612 -312.343653) (xy 312.618596 -312.326201) (xy 312.575975 -312.301594) (xy 312.537854 -312.270469)
			(xy 312.505219 -312.233632) (xy 312.478916 -312.192036) (xy 312.459625 -312.14676) (xy 312.447848 -312.098976)
			(xy 312.443888 -312.049922) (xy 312.126884 -312.049922) (xy 312.12638 -312.07563) (xy 312.118337 -312.126412)
			(xy 312.102449 -312.175311) (xy 312.079106 -312.221123) (xy 312.048885 -312.262719) (xy 312.012529 -312.299075)
			(xy 311.970933 -312.329296) (xy 311.925121 -312.352639) (xy 311.876222 -312.368527) (xy 311.82544 -312.37657)
			(xy 311.774024 -312.37657) (xy 311.723242 -312.368527) (xy 311.674343 -312.352639) (xy 311.628531 -312.329296)
			(xy 311.586935 -312.299075) (xy 311.550579 -312.262719) (xy 311.520358 -312.221123) (xy 311.497015 -312.175311)
			(xy 311.481127 -312.126412) (xy 311.473084 -312.07563) (xy 311.154406 -312.07563) (xy 311.14669 -312.123106)
			(xy 311.131106 -312.169787) (xy 311.108235 -312.213364) (xy 311.07867 -312.252708) (xy 311.043177 -312.2868)
			(xy 311.002674 -312.314756) (xy 310.958212 -312.335854) (xy 310.910941 -312.349546) (xy 310.862086 -312.355478)
			(xy 310.812911 -312.353497) (xy 310.764692 -312.343653) (xy 310.718676 -312.326201) (xy 310.676055 -312.301594)
			(xy 310.637934 -312.270469) (xy 310.605299 -312.233632) (xy 310.578996 -312.192036) (xy 310.559705 -312.14676)
			(xy 310.547928 -312.098976) (xy 310.543968 -312.049922) (xy 310.226964 -312.049922) (xy 310.22646 -312.07563)
			(xy 310.218417 -312.126412) (xy 310.202529 -312.175311) (xy 310.179186 -312.221123) (xy 310.148965 -312.262719)
			(xy 310.112609 -312.299075) (xy 310.071013 -312.329296) (xy 310.025201 -312.352639) (xy 309.976302 -312.368527)
			(xy 309.92552 -312.37657) (xy 309.874104 -312.37657) (xy 309.823322 -312.368527) (xy 309.774423 -312.352639)
			(xy 309.728611 -312.329296) (xy 309.687015 -312.299075) (xy 309.650659 -312.262719) (xy 309.620438 -312.221123)
			(xy 309.597095 -312.175311) (xy 309.581207 -312.126412) (xy 309.573164 -312.07563) (xy 309.254486 -312.07563)
			(xy 309.24677 -312.123106) (xy 309.231186 -312.169787) (xy 309.208315 -312.213364) (xy 309.17875 -312.252708)
			(xy 309.143257 -312.2868) (xy 309.102754 -312.314756) (xy 309.058292 -312.335854) (xy 309.011021 -312.349546)
			(xy 308.962166 -312.355478) (xy 308.912991 -312.353497) (xy 308.864772 -312.343653) (xy 308.818756 -312.326201)
			(xy 308.776135 -312.301594) (xy 308.738014 -312.270469) (xy 308.705379 -312.233632) (xy 308.679076 -312.192036)
			(xy 308.659785 -312.14676) (xy 308.648008 -312.098976) (xy 308.644048 -312.049922) (xy 308.327044 -312.049922)
			(xy 308.32654 -312.07563) (xy 308.318497 -312.126412) (xy 308.302609 -312.175311) (xy 308.279266 -312.221123)
			(xy 308.249045 -312.262719) (xy 308.212689 -312.299075) (xy 308.171093 -312.329296) (xy 308.125281 -312.352639)
			(xy 308.076382 -312.368527) (xy 308.0256 -312.37657) (xy 307.974184 -312.37657) (xy 307.923402 -312.368527)
			(xy 307.874503 -312.352639) (xy 307.828691 -312.329296) (xy 307.787095 -312.299075) (xy 307.750739 -312.262719)
			(xy 307.720518 -312.221123) (xy 307.697175 -312.175311) (xy 307.681287 -312.126412) (xy 307.673244 -312.07563)
			(xy 307.354566 -312.07563) (xy 307.34685 -312.123106) (xy 307.331266 -312.169787) (xy 307.308395 -312.213364)
			(xy 307.27883 -312.252708) (xy 307.243337 -312.2868) (xy 307.202834 -312.314756) (xy 307.158372 -312.335854)
			(xy 307.111101 -312.349546) (xy 307.062246 -312.355478) (xy 307.013071 -312.353497) (xy 306.964852 -312.343653)
			(xy 306.918836 -312.326201) (xy 306.876215 -312.301594) (xy 306.838094 -312.270469) (xy 306.805459 -312.233632)
			(xy 306.779156 -312.192036) (xy 306.759865 -312.14676) (xy 306.748088 -312.098976) (xy 306.744128 -312.049922)
			(xy 306.42687 -312.049922) (xy 306.426366 -312.07563) (xy 306.418323 -312.126412) (xy 306.402435 -312.175311)
			(xy 306.379092 -312.221123) (xy 306.348871 -312.262719) (xy 306.312515 -312.299075) (xy 306.270919 -312.329296)
			(xy 306.225107 -312.352639) (xy 306.176208 -312.368527) (xy 306.125426 -312.37657) (xy 306.07401 -312.37657)
			(xy 306.023228 -312.368527) (xy 305.974329 -312.352639) (xy 305.928517 -312.329296) (xy 305.886921 -312.299075)
			(xy 305.850565 -312.262719) (xy 305.820344 -312.221123) (xy 305.797001 -312.175311) (xy 305.781113 -312.126412)
			(xy 305.77307 -312.07563) (xy 305.454392 -312.07563) (xy 305.446676 -312.123106) (xy 305.431092 -312.169787)
			(xy 305.408221 -312.213364) (xy 305.378656 -312.252708) (xy 305.343163 -312.2868) (xy 305.30266 -312.314756)
			(xy 305.258198 -312.335854) (xy 305.210927 -312.349546) (xy 305.162072 -312.355478) (xy 305.112897 -312.353497)
			(xy 305.064678 -312.343653) (xy 305.018662 -312.326201) (xy 304.976041 -312.301594) (xy 304.93792 -312.270469)
			(xy 304.905285 -312.233632) (xy 304.878982 -312.192036) (xy 304.859691 -312.14676) (xy 304.847914 -312.098976)
			(xy 304.843954 -312.049922) (xy 304.52695 -312.049922) (xy 304.526446 -312.07563) (xy 304.518403 -312.126412)
			(xy 304.502515 -312.175311) (xy 304.479172 -312.221123) (xy 304.448951 -312.262719) (xy 304.412595 -312.299075)
			(xy 304.370999 -312.329296) (xy 304.325187 -312.352639) (xy 304.276288 -312.368527) (xy 304.225506 -312.37657)
			(xy 304.17409 -312.37657) (xy 304.123308 -312.368527) (xy 304.074409 -312.352639) (xy 304.028597 -312.329296)
			(xy 303.987001 -312.299075) (xy 303.950645 -312.262719) (xy 303.920424 -312.221123) (xy 303.897081 -312.175311)
			(xy 303.881193 -312.126412) (xy 303.87315 -312.07563) (xy 303.554472 -312.07563) (xy 303.546756 -312.123106)
			(xy 303.531172 -312.169787) (xy 303.508301 -312.213364) (xy 303.478736 -312.252708) (xy 303.443243 -312.2868)
			(xy 303.40274 -312.314756) (xy 303.358278 -312.335854) (xy 303.311007 -312.349546) (xy 303.262152 -312.355478)
			(xy 303.212977 -312.353497) (xy 303.164758 -312.343653) (xy 303.118742 -312.326201) (xy 303.076121 -312.301594)
			(xy 303.038 -312.270469) (xy 303.005365 -312.233632) (xy 302.979062 -312.192036) (xy 302.959771 -312.14676)
			(xy 302.947994 -312.098976) (xy 302.944034 -312.049922) (xy 302.62703 -312.049922) (xy 302.626526 -312.07563)
			(xy 302.618483 -312.126412) (xy 302.602595 -312.175311) (xy 302.579252 -312.221123) (xy 302.549031 -312.262719)
			(xy 302.512675 -312.299075) (xy 302.471079 -312.329296) (xy 302.425267 -312.352639) (xy 302.376368 -312.368527)
			(xy 302.325586 -312.37657) (xy 302.27417 -312.37657) (xy 302.223388 -312.368527) (xy 302.174489 -312.352639)
			(xy 302.128677 -312.329296) (xy 302.087081 -312.299075) (xy 302.050725 -312.262719) (xy 302.020504 -312.221123)
			(xy 301.997161 -312.175311) (xy 301.981273 -312.126412) (xy 301.97323 -312.07563) (xy 301.654552 -312.07563)
			(xy 301.646836 -312.123106) (xy 301.631252 -312.169787) (xy 301.608381 -312.213364) (xy 301.578816 -312.252708)
			(xy 301.543323 -312.2868) (xy 301.50282 -312.314756) (xy 301.458358 -312.335854) (xy 301.411087 -312.349546)
			(xy 301.362232 -312.355478) (xy 301.313057 -312.353497) (xy 301.264838 -312.343653) (xy 301.218822 -312.326201)
			(xy 301.176201 -312.301594) (xy 301.13808 -312.270469) (xy 301.105445 -312.233632) (xy 301.079142 -312.192036)
			(xy 301.059851 -312.14676) (xy 301.048074 -312.098976) (xy 301.044114 -312.049922) (xy 300.726856 -312.049922)
			(xy 300.726352 -312.07563) (xy 300.718309 -312.126412) (xy 300.702421 -312.175311) (xy 300.679078 -312.221123)
			(xy 300.648857 -312.262719) (xy 300.612501 -312.299075) (xy 300.570905 -312.329296) (xy 300.525093 -312.352639)
			(xy 300.476194 -312.368527) (xy 300.425412 -312.37657) (xy 300.373996 -312.37657) (xy 300.323214 -312.368527)
			(xy 300.274315 -312.352639) (xy 300.228503 -312.329296) (xy 300.186907 -312.299075) (xy 300.150551 -312.262719)
			(xy 300.12033 -312.221123) (xy 300.096987 -312.175311) (xy 300.081099 -312.126412) (xy 300.073056 -312.07563)
			(xy 299.754378 -312.07563) (xy 299.746662 -312.123106) (xy 299.731078 -312.169787) (xy 299.708207 -312.213364)
			(xy 299.678642 -312.252708) (xy 299.643149 -312.2868) (xy 299.602646 -312.314756) (xy 299.558184 -312.335854)
			(xy 299.510913 -312.349546) (xy 299.462058 -312.355478) (xy 299.412883 -312.353497) (xy 299.364664 -312.343653)
			(xy 299.318648 -312.326201) (xy 299.276027 -312.301594) (xy 299.237906 -312.270469) (xy 299.205271 -312.233632)
			(xy 299.178968 -312.192036) (xy 299.159677 -312.14676) (xy 299.1479 -312.098976) (xy 299.14394 -312.049922)
			(xy 298.826936 -312.049922) (xy 298.826432 -312.07563) (xy 298.818389 -312.126412) (xy 298.802501 -312.175311)
			(xy 298.779158 -312.221123) (xy 298.748937 -312.262719) (xy 298.712581 -312.299075) (xy 298.670985 -312.329296)
			(xy 298.625173 -312.352639) (xy 298.576274 -312.368527) (xy 298.525492 -312.37657) (xy 298.474076 -312.37657)
			(xy 298.423294 -312.368527) (xy 298.374395 -312.352639) (xy 298.328583 -312.329296) (xy 298.286987 -312.299075)
			(xy 298.250631 -312.262719) (xy 298.22041 -312.221123) (xy 298.197067 -312.175311) (xy 298.181179 -312.126412)
			(xy 298.173136 -312.07563) (xy 297.854458 -312.07563) (xy 297.846742 -312.123106) (xy 297.831158 -312.169787)
			(xy 297.808287 -312.213364) (xy 297.778722 -312.252708) (xy 297.743229 -312.2868) (xy 297.702726 -312.314756)
			(xy 297.658264 -312.335854) (xy 297.610993 -312.349546) (xy 297.562138 -312.355478) (xy 297.512963 -312.353497)
			(xy 297.464744 -312.343653) (xy 297.418728 -312.326201) (xy 297.376107 -312.301594) (xy 297.337986 -312.270469)
			(xy 297.305351 -312.233632) (xy 297.279048 -312.192036) (xy 297.259757 -312.14676) (xy 297.24798 -312.098976)
			(xy 297.24402 -312.049922) (xy 296.927016 -312.049922) (xy 296.926512 -312.07563) (xy 296.918469 -312.126412)
			(xy 296.902581 -312.175311) (xy 296.879238 -312.221123) (xy 296.849017 -312.262719) (xy 296.812661 -312.299075)
			(xy 296.771065 -312.329296) (xy 296.725253 -312.352639) (xy 296.676354 -312.368527) (xy 296.625572 -312.37657)
			(xy 296.574156 -312.37657) (xy 296.523374 -312.368527) (xy 296.474475 -312.352639) (xy 296.428663 -312.329296)
			(xy 296.387067 -312.299075) (xy 296.350711 -312.262719) (xy 296.32049 -312.221123) (xy 296.297147 -312.175311)
			(xy 296.281259 -312.126412) (xy 296.273216 -312.07563) (xy 295.954538 -312.07563) (xy 295.946822 -312.123106)
			(xy 295.931238 -312.169787) (xy 295.908367 -312.213364) (xy 295.878802 -312.252708) (xy 295.843309 -312.2868)
			(xy 295.802806 -312.314756) (xy 295.758344 -312.335854) (xy 295.711073 -312.349546) (xy 295.662218 -312.355478)
			(xy 295.613043 -312.353497) (xy 295.564824 -312.343653) (xy 295.518808 -312.326201) (xy 295.476187 -312.301594)
			(xy 295.438066 -312.270469) (xy 295.405431 -312.233632) (xy 295.379128 -312.192036) (xy 295.359837 -312.14676)
			(xy 295.34806 -312.098976) (xy 295.3441 -312.049922) (xy 295.026842 -312.049922) (xy 295.026338 -312.07563)
			(xy 295.018295 -312.126412) (xy 295.002407 -312.175311) (xy 294.979064 -312.221123) (xy 294.948843 -312.262719)
			(xy 294.912487 -312.299075) (xy 294.870891 -312.329296) (xy 294.825079 -312.352639) (xy 294.77618 -312.368527)
			(xy 294.725398 -312.37657) (xy 294.673982 -312.37657) (xy 294.6232 -312.368527) (xy 294.574301 -312.352639)
			(xy 294.528489 -312.329296) (xy 294.486893 -312.299075) (xy 294.450537 -312.262719) (xy 294.420316 -312.221123)
			(xy 294.396973 -312.175311) (xy 294.381085 -312.126412) (xy 294.373042 -312.07563) (xy 294.054364 -312.07563)
			(xy 294.046648 -312.123106) (xy 294.031064 -312.169787) (xy 294.008193 -312.213364) (xy 293.978628 -312.252708)
			(xy 293.943135 -312.2868) (xy 293.902632 -312.314756) (xy 293.85817 -312.335854) (xy 293.810899 -312.349546)
			(xy 293.762044 -312.355478) (xy 293.712869 -312.353497) (xy 293.66465 -312.343653) (xy 293.618634 -312.326201)
			(xy 293.576013 -312.301594) (xy 293.537892 -312.270469) (xy 293.505257 -312.233632) (xy 293.478954 -312.192036)
			(xy 293.459663 -312.14676) (xy 293.447886 -312.098976) (xy 293.443926 -312.049922) (xy 293.126922 -312.049922)
			(xy 293.126418 -312.07563) (xy 293.118375 -312.126412) (xy 293.102487 -312.175311) (xy 293.079144 -312.221123)
			(xy 293.048923 -312.262719) (xy 293.012567 -312.299075) (xy 292.970971 -312.329296) (xy 292.925159 -312.352639)
			(xy 292.87626 -312.368527) (xy 292.825478 -312.37657) (xy 292.774062 -312.37657) (xy 292.72328 -312.368527)
			(xy 292.674381 -312.352639) (xy 292.628569 -312.329296) (xy 292.586973 -312.299075) (xy 292.550617 -312.262719)
			(xy 292.520396 -312.221123) (xy 292.497053 -312.175311) (xy 292.481165 -312.126412) (xy 292.473122 -312.07563)
			(xy 292.154444 -312.07563) (xy 292.146728 -312.123106) (xy 292.131144 -312.169787) (xy 292.108273 -312.213364)
			(xy 292.078708 -312.252708) (xy 292.043215 -312.2868) (xy 292.002712 -312.314756) (xy 291.95825 -312.335854)
			(xy 291.910979 -312.349546) (xy 291.862124 -312.355478) (xy 291.812949 -312.353497) (xy 291.76473 -312.343653)
			(xy 291.718714 -312.326201) (xy 291.676093 -312.301594) (xy 291.637972 -312.270469) (xy 291.605337 -312.233632)
			(xy 291.579034 -312.192036) (xy 291.559743 -312.14676) (xy 291.547966 -312.098976) (xy 291.544006 -312.049922)
			(xy 291.22637 -312.049922) (xy 291.226368 -312.075621) (xy 291.218325 -312.126378) (xy 291.20244 -312.175251)
			(xy 291.179105 -312.221037) (xy 291.148894 -312.262609) (xy 291.112551 -312.298943) (xy 291.070972 -312.329144)
			(xy 291.02518 -312.352469) (xy 290.976303 -312.368343) (xy 290.925545 -312.376374) (xy 290.89985 -312.37682)
			(xy 290.875484 -312.376403) (xy 290.82728 -312.369256) (xy 290.803838 -312.362596) (xy 290.79308 -312.359914)
			(xy 290.771147 -312.362988) (xy 290.752529 -312.374984) (xy 290.740664 -312.393685) (xy 290.737743 -312.415639)
			(xy 290.740592 -312.42635) (xy 290.74237 -312.432446) (xy 290.74362 -312.436362) (xy 290.747194 -312.443763)
			(xy 290.749482 -312.447178) (xy 290.772086 -312.480646) (xy 290.812298 -312.550692) (xy 290.84656 -312.623833)
			(xy 290.860988 -312.661554) (xy 290.864963 -312.670881) (xy 290.878854 -312.685628) (xy 290.897354 -312.693884)
			(xy 290.90747 -312.694574) (xy 290.931067 -312.695601) (xy 290.97754 -312.704032) (xy 291.022158 -312.719521)
			(xy 291.063859 -312.741698) (xy 291.101645 -312.770034) (xy 291.134616 -312.803853) (xy 291.161983 -312.842347)
			(xy 291.183094 -312.884597) (xy 291.197445 -312.929595) (xy 291.204692 -312.976266) (xy 291.205158 -312.999882)
			(xy 291.204625 -313.02559) (xy 291.523162 -313.02559) (xy 291.523162 -312.974174) (xy 291.531205 -312.923392)
			(xy 291.547093 -312.874493) (xy 291.570436 -312.828681) (xy 291.600657 -312.787085) (xy 291.637013 -312.750729)
			(xy 291.678609 -312.720508) (xy 291.724421 -312.697165) (xy 291.77332 -312.681277) (xy 291.824102 -312.673234)
			(xy 291.875518 -312.673234) (xy 291.9263 -312.681277) (xy 291.975199 -312.697165) (xy 292.021011 -312.720508)
			(xy 292.062607 -312.750729) (xy 292.098963 -312.787085) (xy 292.129184 -312.828681) (xy 292.152527 -312.874493)
			(xy 292.168415 -312.923392) (xy 292.176458 -312.974174) (xy 292.176962 -312.999882) (xy 292.493966 -312.999882)
			(xy 292.497926 -312.950828) (xy 292.509703 -312.903044) (xy 292.528994 -312.857768) (xy 292.555297 -312.816172)
			(xy 292.587932 -312.779335) (xy 292.626053 -312.74821) (xy 292.668674 -312.723603) (xy 292.71469 -312.706151)
			(xy 292.762909 -312.696307) (xy 292.812084 -312.694326) (xy 292.860939 -312.700258) (xy 292.90821 -312.71395)
			(xy 292.952672 -312.735048) (xy 292.993175 -312.763004) (xy 293.028668 -312.797096) (xy 293.058233 -312.83644)
			(xy 293.081104 -312.880017) (xy 293.096688 -312.926698) (xy 293.104583 -312.975275) (xy 293.105078 -312.999882)
			(xy 293.104583 -313.024489) (xy 293.104404 -313.02559) (xy 293.423082 -313.02559) (xy 293.423082 -312.974174)
			(xy 293.431125 -312.923392) (xy 293.447013 -312.874493) (xy 293.470356 -312.828681) (xy 293.500577 -312.787085)
			(xy 293.536933 -312.750729) (xy 293.578529 -312.720508) (xy 293.624341 -312.697165) (xy 293.67324 -312.681277)
			(xy 293.724022 -312.673234) (xy 293.775438 -312.673234) (xy 293.82622 -312.681277) (xy 293.875119 -312.697165)
			(xy 293.920931 -312.720508) (xy 293.962527 -312.750729) (xy 293.998883 -312.787085) (xy 294.029104 -312.828681)
			(xy 294.052447 -312.874493) (xy 294.068335 -312.923392) (xy 294.076378 -312.974174) (xy 294.076882 -312.999882)
			(xy 294.393886 -312.999882) (xy 294.397846 -312.950828) (xy 294.409623 -312.903044) (xy 294.428914 -312.857768)
			(xy 294.455217 -312.816172) (xy 294.487852 -312.779335) (xy 294.525973 -312.74821) (xy 294.568594 -312.723603)
			(xy 294.61461 -312.706151) (xy 294.662829 -312.696307) (xy 294.712004 -312.694326) (xy 294.760859 -312.700258)
			(xy 294.80813 -312.71395) (xy 294.852592 -312.735048) (xy 294.893095 -312.763004) (xy 294.928588 -312.797096)
			(xy 294.958153 -312.83644) (xy 294.981024 -312.880017) (xy 294.996608 -312.926698) (xy 295.004503 -312.975275)
			(xy 295.004998 -312.999882) (xy 295.004503 -313.024489) (xy 295.004324 -313.02559) (xy 295.323256 -313.02559)
			(xy 295.323256 -312.974174) (xy 295.331299 -312.923392) (xy 295.347187 -312.874493) (xy 295.37053 -312.828681)
			(xy 295.400751 -312.787085) (xy 295.437107 -312.750729) (xy 295.478703 -312.720508) (xy 295.524515 -312.697165)
			(xy 295.573414 -312.681277) (xy 295.624196 -312.673234) (xy 295.675612 -312.673234) (xy 295.726394 -312.681277)
			(xy 295.775293 -312.697165) (xy 295.821105 -312.720508) (xy 295.862701 -312.750729) (xy 295.899057 -312.787085)
			(xy 295.929278 -312.828681) (xy 295.952621 -312.874493) (xy 295.968509 -312.923392) (xy 295.976552 -312.974174)
			(xy 295.977056 -312.999882) (xy 296.29406 -312.999882) (xy 296.29802 -312.950828) (xy 296.309797 -312.903044)
			(xy 296.329088 -312.857768) (xy 296.355391 -312.816172) (xy 296.388026 -312.779335) (xy 296.426147 -312.74821)
			(xy 296.468768 -312.723603) (xy 296.514784 -312.706151) (xy 296.563003 -312.696307) (xy 296.612178 -312.694326)
			(xy 296.661033 -312.700258) (xy 296.708304 -312.71395) (xy 296.752766 -312.735048) (xy 296.793269 -312.763004)
			(xy 296.828762 -312.797096) (xy 296.858327 -312.83644) (xy 296.881198 -312.880017) (xy 296.896782 -312.926698)
			(xy 296.904677 -312.975275) (xy 296.905172 -312.999882) (xy 296.904677 -313.024489) (xy 296.904498 -313.02559)
			(xy 297.223176 -313.02559) (xy 297.223176 -312.974174) (xy 297.231219 -312.923392) (xy 297.247107 -312.874493)
			(xy 297.27045 -312.828681) (xy 297.300671 -312.787085) (xy 297.337027 -312.750729) (xy 297.378623 -312.720508)
			(xy 297.424435 -312.697165) (xy 297.473334 -312.681277) (xy 297.524116 -312.673234) (xy 297.575532 -312.673234)
			(xy 297.626314 -312.681277) (xy 297.675213 -312.697165) (xy 297.721025 -312.720508) (xy 297.762621 -312.750729)
			(xy 297.798977 -312.787085) (xy 297.829198 -312.828681) (xy 297.852541 -312.874493) (xy 297.868429 -312.923392)
			(xy 297.876472 -312.974174) (xy 297.876976 -312.999882) (xy 298.19398 -312.999882) (xy 298.19794 -312.950828)
			(xy 298.209717 -312.903044) (xy 298.229008 -312.857768) (xy 298.255311 -312.816172) (xy 298.287946 -312.779335)
			(xy 298.326067 -312.74821) (xy 298.368688 -312.723603) (xy 298.414704 -312.706151) (xy 298.462923 -312.696307)
			(xy 298.512098 -312.694326) (xy 298.560953 -312.700258) (xy 298.608224 -312.71395) (xy 298.652686 -312.735048)
			(xy 298.693189 -312.763004) (xy 298.728682 -312.797096) (xy 298.758247 -312.83644) (xy 298.781118 -312.880017)
			(xy 298.796702 -312.926698) (xy 298.804597 -312.975275) (xy 298.805092 -312.999882) (xy 298.804597 -313.024489)
			(xy 298.804418 -313.02559) (xy 299.123096 -313.02559) (xy 299.123096 -312.974174) (xy 299.131139 -312.923392)
			(xy 299.147027 -312.874493) (xy 299.17037 -312.828681) (xy 299.200591 -312.787085) (xy 299.236947 -312.750729)
			(xy 299.278543 -312.720508) (xy 299.324355 -312.697165) (xy 299.373254 -312.681277) (xy 299.424036 -312.673234)
			(xy 299.475452 -312.673234) (xy 299.526234 -312.681277) (xy 299.575133 -312.697165) (xy 299.620945 -312.720508)
			(xy 299.662541 -312.750729) (xy 299.698897 -312.787085) (xy 299.729118 -312.828681) (xy 299.752461 -312.874493)
			(xy 299.768349 -312.923392) (xy 299.776392 -312.974174) (xy 299.776896 -312.999882) (xy 300.0939 -312.999882)
			(xy 300.09786 -312.950828) (xy 300.109637 -312.903044) (xy 300.128928 -312.857768) (xy 300.155231 -312.816172)
			(xy 300.187866 -312.779335) (xy 300.225987 -312.74821) (xy 300.268608 -312.723603) (xy 300.314624 -312.706151)
			(xy 300.362843 -312.696307) (xy 300.412018 -312.694326) (xy 300.460873 -312.700258) (xy 300.508144 -312.71395)
			(xy 300.552606 -312.735048) (xy 300.593109 -312.763004) (xy 300.628602 -312.797096) (xy 300.658167 -312.83644)
			(xy 300.681038 -312.880017) (xy 300.696622 -312.926698) (xy 300.704517 -312.975275) (xy 300.705012 -312.999882)
			(xy 300.704517 -313.024489) (xy 300.704338 -313.02559) (xy 301.02327 -313.02559) (xy 301.02327 -312.974174)
			(xy 301.031313 -312.923392) (xy 301.047201 -312.874493) (xy 301.070544 -312.828681) (xy 301.100765 -312.787085)
			(xy 301.137121 -312.750729) (xy 301.178717 -312.720508) (xy 301.224529 -312.697165) (xy 301.273428 -312.681277)
			(xy 301.32421 -312.673234) (xy 301.375626 -312.673234) (xy 301.426408 -312.681277) (xy 301.475307 -312.697165)
			(xy 301.521119 -312.720508) (xy 301.562715 -312.750729) (xy 301.599071 -312.787085) (xy 301.629292 -312.828681)
			(xy 301.652635 -312.874493) (xy 301.668523 -312.923392) (xy 301.676566 -312.974174) (xy 301.67707 -312.999882)
			(xy 301.994074 -312.999882) (xy 301.998034 -312.950828) (xy 302.009811 -312.903044) (xy 302.029102 -312.857768)
			(xy 302.055405 -312.816172) (xy 302.08804 -312.779335) (xy 302.126161 -312.74821) (xy 302.168782 -312.723603)
			(xy 302.214798 -312.706151) (xy 302.263017 -312.696307) (xy 302.312192 -312.694326) (xy 302.361047 -312.700258)
			(xy 302.408318 -312.71395) (xy 302.45278 -312.735048) (xy 302.493283 -312.763004) (xy 302.528776 -312.797096)
			(xy 302.558341 -312.83644) (xy 302.581212 -312.880017) (xy 302.596796 -312.926698) (xy 302.604691 -312.975275)
			(xy 302.605186 -312.999882) (xy 302.604691 -313.024489) (xy 302.604512 -313.02559) (xy 302.92319 -313.02559)
			(xy 302.92319 -312.974174) (xy 302.931233 -312.923392) (xy 302.947121 -312.874493) (xy 302.970464 -312.828681)
			(xy 303.000685 -312.787085) (xy 303.037041 -312.750729) (xy 303.078637 -312.720508) (xy 303.124449 -312.697165)
			(xy 303.173348 -312.681277) (xy 303.22413 -312.673234) (xy 303.275546 -312.673234) (xy 303.326328 -312.681277)
			(xy 303.375227 -312.697165) (xy 303.421039 -312.720508) (xy 303.462635 -312.750729) (xy 303.498991 -312.787085)
			(xy 303.529212 -312.828681) (xy 303.552555 -312.874493) (xy 303.568443 -312.923392) (xy 303.576486 -312.974174)
			(xy 303.57699 -312.999882) (xy 303.893994 -312.999882) (xy 303.897954 -312.950828) (xy 303.909731 -312.903044)
			(xy 303.929022 -312.857768) (xy 303.955325 -312.816172) (xy 303.98796 -312.779335) (xy 304.026081 -312.74821)
			(xy 304.068702 -312.723603) (xy 304.114718 -312.706151) (xy 304.162937 -312.696307) (xy 304.212112 -312.694326)
			(xy 304.260967 -312.700258) (xy 304.308238 -312.71395) (xy 304.3527 -312.735048) (xy 304.393203 -312.763004)
			(xy 304.428696 -312.797096) (xy 304.458261 -312.83644) (xy 304.481132 -312.880017) (xy 304.496716 -312.926698)
			(xy 304.504611 -312.975275) (xy 304.505106 -312.999882) (xy 304.504611 -313.024489) (xy 304.504432 -313.02559)
			(xy 304.82311 -313.02559) (xy 304.82311 -312.974174) (xy 304.831153 -312.923392) (xy 304.847041 -312.874493)
			(xy 304.870384 -312.828681) (xy 304.900605 -312.787085) (xy 304.936961 -312.750729) (xy 304.978557 -312.720508)
			(xy 305.024369 -312.697165) (xy 305.073268 -312.681277) (xy 305.12405 -312.673234) (xy 305.175466 -312.673234)
			(xy 305.226248 -312.681277) (xy 305.275147 -312.697165) (xy 305.320959 -312.720508) (xy 305.362555 -312.750729)
			(xy 305.398911 -312.787085) (xy 305.429132 -312.828681) (xy 305.452475 -312.874493) (xy 305.468363 -312.923392)
			(xy 305.476406 -312.974174) (xy 305.47691 -312.999882) (xy 305.793914 -312.999882) (xy 305.797874 -312.950828)
			(xy 305.809651 -312.903044) (xy 305.828942 -312.857768) (xy 305.855245 -312.816172) (xy 305.88788 -312.779335)
			(xy 305.926001 -312.74821) (xy 305.968622 -312.723603) (xy 306.014638 -312.706151) (xy 306.062857 -312.696307)
			(xy 306.112032 -312.694326) (xy 306.160887 -312.700258) (xy 306.208158 -312.71395) (xy 306.25262 -312.735048)
			(xy 306.293123 -312.763004) (xy 306.328616 -312.797096) (xy 306.358181 -312.83644) (xy 306.381052 -312.880017)
			(xy 306.396636 -312.926698) (xy 306.404531 -312.975275) (xy 306.405026 -312.999882) (xy 306.404531 -313.024489)
			(xy 306.404352 -313.02559) (xy 306.723284 -313.02559) (xy 306.723284 -312.974174) (xy 306.731327 -312.923392)
			(xy 306.747215 -312.874493) (xy 306.770558 -312.828681) (xy 306.800779 -312.787085) (xy 306.837135 -312.750729)
			(xy 306.878731 -312.720508) (xy 306.924543 -312.697165) (xy 306.973442 -312.681277) (xy 307.024224 -312.673234)
			(xy 307.07564 -312.673234) (xy 307.126422 -312.681277) (xy 307.175321 -312.697165) (xy 307.221133 -312.720508)
			(xy 307.262729 -312.750729) (xy 307.299085 -312.787085) (xy 307.329306 -312.828681) (xy 307.352649 -312.874493)
			(xy 307.368537 -312.923392) (xy 307.37658 -312.974174) (xy 307.377084 -312.999882) (xy 307.694088 -312.999882)
			(xy 307.698048 -312.950828) (xy 307.709825 -312.903044) (xy 307.729116 -312.857768) (xy 307.755419 -312.816172)
			(xy 307.788054 -312.779335) (xy 307.826175 -312.74821) (xy 307.868796 -312.723603) (xy 307.914812 -312.706151)
			(xy 307.963031 -312.696307) (xy 308.012206 -312.694326) (xy 308.061061 -312.700258) (xy 308.108332 -312.71395)
			(xy 308.152794 -312.735048) (xy 308.193297 -312.763004) (xy 308.22879 -312.797096) (xy 308.258355 -312.83644)
			(xy 308.281226 -312.880017) (xy 308.29681 -312.926698) (xy 308.304705 -312.975275) (xy 308.3052 -312.999882)
			(xy 308.304705 -313.024489) (xy 308.304526 -313.02559) (xy 308.623204 -313.02559) (xy 308.623204 -312.974174)
			(xy 308.631247 -312.923392) (xy 308.647135 -312.874493) (xy 308.670478 -312.828681) (xy 308.700699 -312.787085)
			(xy 308.737055 -312.750729) (xy 308.778651 -312.720508) (xy 308.824463 -312.697165) (xy 308.873362 -312.681277)
			(xy 308.924144 -312.673234) (xy 308.97556 -312.673234) (xy 309.026342 -312.681277) (xy 309.075241 -312.697165)
			(xy 309.121053 -312.720508) (xy 309.162649 -312.750729) (xy 309.199005 -312.787085) (xy 309.229226 -312.828681)
			(xy 309.252569 -312.874493) (xy 309.268457 -312.923392) (xy 309.2765 -312.974174) (xy 309.277004 -312.999882)
			(xy 309.594008 -312.999882) (xy 309.597968 -312.950828) (xy 309.609745 -312.903044) (xy 309.629036 -312.857768)
			(xy 309.655339 -312.816172) (xy 309.687974 -312.779335) (xy 309.726095 -312.74821) (xy 309.768716 -312.723603)
			(xy 309.814732 -312.706151) (xy 309.862951 -312.696307) (xy 309.912126 -312.694326) (xy 309.960981 -312.700258)
			(xy 310.008252 -312.71395) (xy 310.052714 -312.735048) (xy 310.093217 -312.763004) (xy 310.12871 -312.797096)
			(xy 310.158275 -312.83644) (xy 310.181146 -312.880017) (xy 310.19673 -312.926698) (xy 310.204625 -312.975275)
			(xy 310.20512 -312.999882) (xy 310.204625 -313.024489) (xy 310.204446 -313.02559) (xy 310.523124 -313.02559)
			(xy 310.523124 -312.974174) (xy 310.531167 -312.923392) (xy 310.547055 -312.874493) (xy 310.570398 -312.828681)
			(xy 310.600619 -312.787085) (xy 310.636975 -312.750729) (xy 310.678571 -312.720508) (xy 310.724383 -312.697165)
			(xy 310.773282 -312.681277) (xy 310.824064 -312.673234) (xy 310.87548 -312.673234) (xy 310.926262 -312.681277)
			(xy 310.975161 -312.697165) (xy 311.020973 -312.720508) (xy 311.062569 -312.750729) (xy 311.098925 -312.787085)
			(xy 311.129146 -312.828681) (xy 311.152489 -312.874493) (xy 311.168377 -312.923392) (xy 311.17642 -312.974174)
			(xy 311.176924 -312.999882) (xy 311.493928 -312.999882) (xy 311.497888 -312.950828) (xy 311.509665 -312.903044)
			(xy 311.528956 -312.857768) (xy 311.555259 -312.816172) (xy 311.587894 -312.779335) (xy 311.626015 -312.74821)
			(xy 311.668636 -312.723603) (xy 311.714652 -312.706151) (xy 311.762871 -312.696307) (xy 311.812046 -312.694326)
			(xy 311.860901 -312.700258) (xy 311.908172 -312.71395) (xy 311.952634 -312.735048) (xy 311.993137 -312.763004)
			(xy 312.02863 -312.797096) (xy 312.058195 -312.83644) (xy 312.081066 -312.880017) (xy 312.09665 -312.926698)
			(xy 312.104545 -312.975275) (xy 312.10504 -312.999882) (xy 312.104545 -313.024489) (xy 312.104366 -313.02559)
			(xy 312.423044 -313.02559) (xy 312.423044 -312.974174) (xy 312.431087 -312.923392) (xy 312.446975 -312.874493)
			(xy 312.470318 -312.828681) (xy 312.500539 -312.787085) (xy 312.536895 -312.750729) (xy 312.578491 -312.720508)
			(xy 312.624303 -312.697165) (xy 312.673202 -312.681277) (xy 312.723984 -312.673234) (xy 312.7754 -312.673234)
			(xy 312.826182 -312.681277) (xy 312.875081 -312.697165) (xy 312.920893 -312.720508) (xy 312.962489 -312.750729)
			(xy 312.998845 -312.787085) (xy 313.029066 -312.828681) (xy 313.052409 -312.874493) (xy 313.068297 -312.923392)
			(xy 313.07634 -312.974174) (xy 313.076844 -312.999882) (xy 313.394102 -312.999882) (xy 313.398062 -312.950828)
			(xy 313.409839 -312.903044) (xy 313.42913 -312.857768) (xy 313.455433 -312.816172) (xy 313.488068 -312.779335)
			(xy 313.526189 -312.74821) (xy 313.56881 -312.723603) (xy 313.614826 -312.706151) (xy 313.663045 -312.696307)
			(xy 313.71222 -312.694326) (xy 313.761075 -312.700258) (xy 313.808346 -312.71395) (xy 313.852808 -312.735048)
			(xy 313.893311 -312.763004) (xy 313.928804 -312.797096) (xy 313.958369 -312.83644) (xy 313.98124 -312.880017)
			(xy 313.996824 -312.926698) (xy 314.004719 -312.975275) (xy 314.005214 -312.999882) (xy 314.344062 -312.999882)
			(xy 314.348022 -312.950828) (xy 314.359799 -312.903044) (xy 314.37909 -312.857768) (xy 314.405393 -312.816172)
			(xy 314.438028 -312.779335) (xy 314.476149 -312.74821) (xy 314.51877 -312.723603) (xy 314.564786 -312.706151)
			(xy 314.613005 -312.696307) (xy 314.66218 -312.694326) (xy 314.711035 -312.700258) (xy 314.758306 -312.71395)
			(xy 314.802768 -312.735048) (xy 314.843271 -312.763004) (xy 314.878764 -312.797096) (xy 314.908329 -312.83644)
			(xy 314.9312 -312.880017) (xy 314.946784 -312.926698) (xy 314.954679 -312.975275) (xy 314.955174 -312.999882)
			(xy 314.954679 -313.024489) (xy 314.946784 -313.073066) (xy 314.9312 -313.119747) (xy 314.908329 -313.163324)
			(xy 314.878764 -313.202668) (xy 314.843271 -313.23676) (xy 314.802768 -313.264716) (xy 314.758306 -313.285814)
			(xy 314.711035 -313.299506) (xy 314.66218 -313.305438) (xy 314.613005 -313.303457) (xy 314.564786 -313.293613)
			(xy 314.51877 -313.276161) (xy 314.476149 -313.251554) (xy 314.438028 -313.220429) (xy 314.405393 -313.183592)
			(xy 314.37909 -313.141996) (xy 314.359799 -313.09672) (xy 314.348022 -313.048936) (xy 314.344062 -312.999882)
			(xy 314.005214 -312.999882) (xy 314.004719 -313.024489) (xy 313.996824 -313.073066) (xy 313.98124 -313.119747)
			(xy 313.958369 -313.163324) (xy 313.928804 -313.202668) (xy 313.893311 -313.23676) (xy 313.852808 -313.264716)
			(xy 313.808346 -313.285814) (xy 313.761075 -313.299506) (xy 313.71222 -313.305438) (xy 313.663045 -313.303457)
			(xy 313.614826 -313.293613) (xy 313.56881 -313.276161) (xy 313.526189 -313.251554) (xy 313.488068 -313.220429)
			(xy 313.455433 -313.183592) (xy 313.42913 -313.141996) (xy 313.409839 -313.09672) (xy 313.398062 -313.048936)
			(xy 313.394102 -312.999882) (xy 313.076844 -312.999882) (xy 313.07634 -313.02559) (xy 313.068297 -313.076372)
			(xy 313.052409 -313.125271) (xy 313.029066 -313.171083) (xy 312.998845 -313.212679) (xy 312.962489 -313.249035)
			(xy 312.920893 -313.279256) (xy 312.875081 -313.302599) (xy 312.826182 -313.318487) (xy 312.7754 -313.32653)
			(xy 312.723984 -313.32653) (xy 312.673202 -313.318487) (xy 312.624303 -313.302599) (xy 312.578491 -313.279256)
			(xy 312.536895 -313.249035) (xy 312.500539 -313.212679) (xy 312.470318 -313.171083) (xy 312.446975 -313.125271)
			(xy 312.431087 -313.076372) (xy 312.423044 -313.02559) (xy 312.104366 -313.02559) (xy 312.09665 -313.073066)
			(xy 312.081066 -313.119747) (xy 312.058195 -313.163324) (xy 312.02863 -313.202668) (xy 311.993137 -313.23676)
			(xy 311.952634 -313.264716) (xy 311.908172 -313.285814) (xy 311.860901 -313.299506) (xy 311.812046 -313.305438)
			(xy 311.762871 -313.303457) (xy 311.714652 -313.293613) (xy 311.668636 -313.276161) (xy 311.626015 -313.251554)
			(xy 311.587894 -313.220429) (xy 311.555259 -313.183592) (xy 311.528956 -313.141996) (xy 311.509665 -313.09672)
			(xy 311.497888 -313.048936) (xy 311.493928 -312.999882) (xy 311.176924 -312.999882) (xy 311.17642 -313.02559)
			(xy 311.168377 -313.076372) (xy 311.152489 -313.125271) (xy 311.129146 -313.171083) (xy 311.098925 -313.212679)
			(xy 311.062569 -313.249035) (xy 311.020973 -313.279256) (xy 310.975161 -313.302599) (xy 310.926262 -313.318487)
			(xy 310.87548 -313.32653) (xy 310.824064 -313.32653) (xy 310.773282 -313.318487) (xy 310.724383 -313.302599)
			(xy 310.678571 -313.279256) (xy 310.636975 -313.249035) (xy 310.600619 -313.212679) (xy 310.570398 -313.171083)
			(xy 310.547055 -313.125271) (xy 310.531167 -313.076372) (xy 310.523124 -313.02559) (xy 310.204446 -313.02559)
			(xy 310.19673 -313.073066) (xy 310.181146 -313.119747) (xy 310.158275 -313.163324) (xy 310.12871 -313.202668)
			(xy 310.093217 -313.23676) (xy 310.052714 -313.264716) (xy 310.008252 -313.285814) (xy 309.960981 -313.299506)
			(xy 309.912126 -313.305438) (xy 309.862951 -313.303457) (xy 309.814732 -313.293613) (xy 309.768716 -313.276161)
			(xy 309.726095 -313.251554) (xy 309.687974 -313.220429) (xy 309.655339 -313.183592) (xy 309.629036 -313.141996)
			(xy 309.609745 -313.09672) (xy 309.597968 -313.048936) (xy 309.594008 -312.999882) (xy 309.277004 -312.999882)
			(xy 309.2765 -313.02559) (xy 309.268457 -313.076372) (xy 309.252569 -313.125271) (xy 309.229226 -313.171083)
			(xy 309.199005 -313.212679) (xy 309.162649 -313.249035) (xy 309.121053 -313.279256) (xy 309.075241 -313.302599)
			(xy 309.026342 -313.318487) (xy 308.97556 -313.32653) (xy 308.924144 -313.32653) (xy 308.873362 -313.318487)
			(xy 308.824463 -313.302599) (xy 308.778651 -313.279256) (xy 308.737055 -313.249035) (xy 308.700699 -313.212679)
			(xy 308.670478 -313.171083) (xy 308.647135 -313.125271) (xy 308.631247 -313.076372) (xy 308.623204 -313.02559)
			(xy 308.304526 -313.02559) (xy 308.29681 -313.073066) (xy 308.281226 -313.119747) (xy 308.258355 -313.163324)
			(xy 308.22879 -313.202668) (xy 308.193297 -313.23676) (xy 308.152794 -313.264716) (xy 308.108332 -313.285814)
			(xy 308.061061 -313.299506) (xy 308.012206 -313.305438) (xy 307.963031 -313.303457) (xy 307.914812 -313.293613)
			(xy 307.868796 -313.276161) (xy 307.826175 -313.251554) (xy 307.788054 -313.220429) (xy 307.755419 -313.183592)
			(xy 307.729116 -313.141996) (xy 307.709825 -313.09672) (xy 307.698048 -313.048936) (xy 307.694088 -312.999882)
			(xy 307.377084 -312.999882) (xy 307.37658 -313.02559) (xy 307.368537 -313.076372) (xy 307.352649 -313.125271)
			(xy 307.329306 -313.171083) (xy 307.299085 -313.212679) (xy 307.262729 -313.249035) (xy 307.221133 -313.279256)
			(xy 307.175321 -313.302599) (xy 307.126422 -313.318487) (xy 307.07564 -313.32653) (xy 307.024224 -313.32653)
			(xy 306.973442 -313.318487) (xy 306.924543 -313.302599) (xy 306.878731 -313.279256) (xy 306.837135 -313.249035)
			(xy 306.800779 -313.212679) (xy 306.770558 -313.171083) (xy 306.747215 -313.125271) (xy 306.731327 -313.076372)
			(xy 306.723284 -313.02559) (xy 306.404352 -313.02559) (xy 306.396636 -313.073066) (xy 306.381052 -313.119747)
			(xy 306.358181 -313.163324) (xy 306.328616 -313.202668) (xy 306.293123 -313.23676) (xy 306.25262 -313.264716)
			(xy 306.208158 -313.285814) (xy 306.160887 -313.299506) (xy 306.112032 -313.305438) (xy 306.062857 -313.303457)
			(xy 306.014638 -313.293613) (xy 305.968622 -313.276161) (xy 305.926001 -313.251554) (xy 305.88788 -313.220429)
			(xy 305.855245 -313.183592) (xy 305.828942 -313.141996) (xy 305.809651 -313.09672) (xy 305.797874 -313.048936)
			(xy 305.793914 -312.999882) (xy 305.47691 -312.999882) (xy 305.476406 -313.02559) (xy 305.468363 -313.076372)
			(xy 305.452475 -313.125271) (xy 305.429132 -313.171083) (xy 305.398911 -313.212679) (xy 305.362555 -313.249035)
			(xy 305.320959 -313.279256) (xy 305.275147 -313.302599) (xy 305.226248 -313.318487) (xy 305.175466 -313.32653)
			(xy 305.12405 -313.32653) (xy 305.073268 -313.318487) (xy 305.024369 -313.302599) (xy 304.978557 -313.279256)
			(xy 304.936961 -313.249035) (xy 304.900605 -313.212679) (xy 304.870384 -313.171083) (xy 304.847041 -313.125271)
			(xy 304.831153 -313.076372) (xy 304.82311 -313.02559) (xy 304.504432 -313.02559) (xy 304.496716 -313.073066)
			(xy 304.481132 -313.119747) (xy 304.458261 -313.163324) (xy 304.428696 -313.202668) (xy 304.393203 -313.23676)
			(xy 304.3527 -313.264716) (xy 304.308238 -313.285814) (xy 304.260967 -313.299506) (xy 304.212112 -313.305438)
			(xy 304.162937 -313.303457) (xy 304.114718 -313.293613) (xy 304.068702 -313.276161) (xy 304.026081 -313.251554)
			(xy 303.98796 -313.220429) (xy 303.955325 -313.183592) (xy 303.929022 -313.141996) (xy 303.909731 -313.09672)
			(xy 303.897954 -313.048936) (xy 303.893994 -312.999882) (xy 303.57699 -312.999882) (xy 303.576486 -313.02559)
			(xy 303.568443 -313.076372) (xy 303.552555 -313.125271) (xy 303.529212 -313.171083) (xy 303.498991 -313.212679)
			(xy 303.462635 -313.249035) (xy 303.421039 -313.279256) (xy 303.375227 -313.302599) (xy 303.326328 -313.318487)
			(xy 303.275546 -313.32653) (xy 303.22413 -313.32653) (xy 303.173348 -313.318487) (xy 303.124449 -313.302599)
			(xy 303.078637 -313.279256) (xy 303.037041 -313.249035) (xy 303.000685 -313.212679) (xy 302.970464 -313.171083)
			(xy 302.947121 -313.125271) (xy 302.931233 -313.076372) (xy 302.92319 -313.02559) (xy 302.604512 -313.02559)
			(xy 302.596796 -313.073066) (xy 302.581212 -313.119747) (xy 302.558341 -313.163324) (xy 302.528776 -313.202668)
			(xy 302.493283 -313.23676) (xy 302.45278 -313.264716) (xy 302.408318 -313.285814) (xy 302.361047 -313.299506)
			(xy 302.312192 -313.305438) (xy 302.263017 -313.303457) (xy 302.214798 -313.293613) (xy 302.168782 -313.276161)
			(xy 302.126161 -313.251554) (xy 302.08804 -313.220429) (xy 302.055405 -313.183592) (xy 302.029102 -313.141996)
			(xy 302.009811 -313.09672) (xy 301.998034 -313.048936) (xy 301.994074 -312.999882) (xy 301.67707 -312.999882)
			(xy 301.676566 -313.02559) (xy 301.668523 -313.076372) (xy 301.652635 -313.125271) (xy 301.629292 -313.171083)
			(xy 301.599071 -313.212679) (xy 301.562715 -313.249035) (xy 301.521119 -313.279256) (xy 301.475307 -313.302599)
			(xy 301.426408 -313.318487) (xy 301.375626 -313.32653) (xy 301.32421 -313.32653) (xy 301.273428 -313.318487)
			(xy 301.224529 -313.302599) (xy 301.178717 -313.279256) (xy 301.137121 -313.249035) (xy 301.100765 -313.212679)
			(xy 301.070544 -313.171083) (xy 301.047201 -313.125271) (xy 301.031313 -313.076372) (xy 301.02327 -313.02559)
			(xy 300.704338 -313.02559) (xy 300.696622 -313.073066) (xy 300.681038 -313.119747) (xy 300.658167 -313.163324)
			(xy 300.628602 -313.202668) (xy 300.593109 -313.23676) (xy 300.552606 -313.264716) (xy 300.508144 -313.285814)
			(xy 300.460873 -313.299506) (xy 300.412018 -313.305438) (xy 300.362843 -313.303457) (xy 300.314624 -313.293613)
			(xy 300.268608 -313.276161) (xy 300.225987 -313.251554) (xy 300.187866 -313.220429) (xy 300.155231 -313.183592)
			(xy 300.128928 -313.141996) (xy 300.109637 -313.09672) (xy 300.09786 -313.048936) (xy 300.0939 -312.999882)
			(xy 299.776896 -312.999882) (xy 299.776392 -313.02559) (xy 299.768349 -313.076372) (xy 299.752461 -313.125271)
			(xy 299.729118 -313.171083) (xy 299.698897 -313.212679) (xy 299.662541 -313.249035) (xy 299.620945 -313.279256)
			(xy 299.575133 -313.302599) (xy 299.526234 -313.318487) (xy 299.475452 -313.32653) (xy 299.424036 -313.32653)
			(xy 299.373254 -313.318487) (xy 299.324355 -313.302599) (xy 299.278543 -313.279256) (xy 299.236947 -313.249035)
			(xy 299.200591 -313.212679) (xy 299.17037 -313.171083) (xy 299.147027 -313.125271) (xy 299.131139 -313.076372)
			(xy 299.123096 -313.02559) (xy 298.804418 -313.02559) (xy 298.796702 -313.073066) (xy 298.781118 -313.119747)
			(xy 298.758247 -313.163324) (xy 298.728682 -313.202668) (xy 298.693189 -313.23676) (xy 298.652686 -313.264716)
			(xy 298.608224 -313.285814) (xy 298.560953 -313.299506) (xy 298.512098 -313.305438) (xy 298.462923 -313.303457)
			(xy 298.414704 -313.293613) (xy 298.368688 -313.276161) (xy 298.326067 -313.251554) (xy 298.287946 -313.220429)
			(xy 298.255311 -313.183592) (xy 298.229008 -313.141996) (xy 298.209717 -313.09672) (xy 298.19794 -313.048936)
			(xy 298.19398 -312.999882) (xy 297.876976 -312.999882) (xy 297.876472 -313.02559) (xy 297.868429 -313.076372)
			(xy 297.852541 -313.125271) (xy 297.829198 -313.171083) (xy 297.798977 -313.212679) (xy 297.762621 -313.249035)
			(xy 297.721025 -313.279256) (xy 297.675213 -313.302599) (xy 297.626314 -313.318487) (xy 297.575532 -313.32653)
			(xy 297.524116 -313.32653) (xy 297.473334 -313.318487) (xy 297.424435 -313.302599) (xy 297.378623 -313.279256)
			(xy 297.337027 -313.249035) (xy 297.300671 -313.212679) (xy 297.27045 -313.171083) (xy 297.247107 -313.125271)
			(xy 297.231219 -313.076372) (xy 297.223176 -313.02559) (xy 296.904498 -313.02559) (xy 296.896782 -313.073066)
			(xy 296.881198 -313.119747) (xy 296.858327 -313.163324) (xy 296.828762 -313.202668) (xy 296.793269 -313.23676)
			(xy 296.752766 -313.264716) (xy 296.708304 -313.285814) (xy 296.661033 -313.299506) (xy 296.612178 -313.305438)
			(xy 296.563003 -313.303457) (xy 296.514784 -313.293613) (xy 296.468768 -313.276161) (xy 296.426147 -313.251554)
			(xy 296.388026 -313.220429) (xy 296.355391 -313.183592) (xy 296.329088 -313.141996) (xy 296.309797 -313.09672)
			(xy 296.29802 -313.048936) (xy 296.29406 -312.999882) (xy 295.977056 -312.999882) (xy 295.976552 -313.02559)
			(xy 295.968509 -313.076372) (xy 295.952621 -313.125271) (xy 295.929278 -313.171083) (xy 295.899057 -313.212679)
			(xy 295.862701 -313.249035) (xy 295.821105 -313.279256) (xy 295.775293 -313.302599) (xy 295.726394 -313.318487)
			(xy 295.675612 -313.32653) (xy 295.624196 -313.32653) (xy 295.573414 -313.318487) (xy 295.524515 -313.302599)
			(xy 295.478703 -313.279256) (xy 295.437107 -313.249035) (xy 295.400751 -313.212679) (xy 295.37053 -313.171083)
			(xy 295.347187 -313.125271) (xy 295.331299 -313.076372) (xy 295.323256 -313.02559) (xy 295.004324 -313.02559)
			(xy 294.996608 -313.073066) (xy 294.981024 -313.119747) (xy 294.958153 -313.163324) (xy 294.928588 -313.202668)
			(xy 294.893095 -313.23676) (xy 294.852592 -313.264716) (xy 294.80813 -313.285814) (xy 294.760859 -313.299506)
			(xy 294.712004 -313.305438) (xy 294.662829 -313.303457) (xy 294.61461 -313.293613) (xy 294.568594 -313.276161)
			(xy 294.525973 -313.251554) (xy 294.487852 -313.220429) (xy 294.455217 -313.183592) (xy 294.428914 -313.141996)
			(xy 294.409623 -313.09672) (xy 294.397846 -313.048936) (xy 294.393886 -312.999882) (xy 294.076882 -312.999882)
			(xy 294.076378 -313.02559) (xy 294.068335 -313.076372) (xy 294.052447 -313.125271) (xy 294.029104 -313.171083)
			(xy 293.998883 -313.212679) (xy 293.962527 -313.249035) (xy 293.920931 -313.279256) (xy 293.875119 -313.302599)
			(xy 293.82622 -313.318487) (xy 293.775438 -313.32653) (xy 293.724022 -313.32653) (xy 293.67324 -313.318487)
			(xy 293.624341 -313.302599) (xy 293.578529 -313.279256) (xy 293.536933 -313.249035) (xy 293.500577 -313.212679)
			(xy 293.470356 -313.171083) (xy 293.447013 -313.125271) (xy 293.431125 -313.076372) (xy 293.423082 -313.02559)
			(xy 293.104404 -313.02559) (xy 293.096688 -313.073066) (xy 293.081104 -313.119747) (xy 293.058233 -313.163324)
			(xy 293.028668 -313.202668) (xy 292.993175 -313.23676) (xy 292.952672 -313.264716) (xy 292.90821 -313.285814)
			(xy 292.860939 -313.299506) (xy 292.812084 -313.305438) (xy 292.762909 -313.303457) (xy 292.71469 -313.293613)
			(xy 292.668674 -313.276161) (xy 292.626053 -313.251554) (xy 292.587932 -313.220429) (xy 292.555297 -313.183592)
			(xy 292.528994 -313.141996) (xy 292.509703 -313.09672) (xy 292.497926 -313.048936) (xy 292.493966 -312.999882)
			(xy 292.176962 -312.999882) (xy 292.176458 -313.02559) (xy 292.168415 -313.076372) (xy 292.152527 -313.125271)
			(xy 292.129184 -313.171083) (xy 292.098963 -313.212679) (xy 292.062607 -313.249035) (xy 292.021011 -313.279256)
			(xy 291.975199 -313.302599) (xy 291.9263 -313.318487) (xy 291.875518 -313.32653) (xy 291.824102 -313.32653)
			(xy 291.77332 -313.318487) (xy 291.724421 -313.302599) (xy 291.678609 -313.279256) (xy 291.637013 -313.249035)
			(xy 291.600657 -313.212679) (xy 291.570436 -313.171083) (xy 291.547093 -313.125271) (xy 291.531205 -313.076372)
			(xy 291.523162 -313.02559) (xy 291.204625 -313.02559) (xy 291.204614 -313.026134) (xy 291.195636 -313.077866)
			(xy 291.177943 -313.1273) (xy 291.152056 -313.172979) (xy 291.118737 -313.213557) (xy 291.078968 -313.247838)
			(xy 291.033922 -313.274812) (xy 290.984926 -313.293684) (xy 290.959286 -313.299348) (xy 290.948598 -313.302015)
			(xy 290.930788 -313.31494) (xy 290.920037 -313.33414) (xy 290.918646 -313.345068) (xy 290.915887 -313.375129)
			(xy 290.907117 -313.434862) (xy 290.90112 -313.464448) (xy 290.900169 -313.469613) (xy 290.900162 -313.480113)
			(xy 290.90112 -313.485276) (xy 290.907129 -313.51486) (xy 290.915897 -313.574594) (xy 290.918646 -313.604656)
			(xy 290.920076 -313.615565) (xy 290.930846 -313.634724) (xy 290.948626 -313.647644) (xy 290.959286 -313.650376)
			(xy 290.984932 -313.656019) (xy 291.033929 -313.674893) (xy 291.078976 -313.70187) (xy 291.118745 -313.736154)
			(xy 291.152063 -313.776735) (xy 291.177949 -313.822417) (xy 291.19564 -313.871854) (xy 291.204614 -313.923589)
			(xy 291.205158 -313.949842) (xy 291.204715 -313.973455) (xy 291.204388 -313.97555) (xy 291.523162 -313.97555)
			(xy 291.523162 -313.924134) (xy 291.531205 -313.873352) (xy 291.547093 -313.824453) (xy 291.570436 -313.778641)
			(xy 291.600657 -313.737045) (xy 291.637013 -313.700689) (xy 291.678609 -313.670468) (xy 291.724421 -313.647125)
			(xy 291.77332 -313.631237) (xy 291.824102 -313.623194) (xy 291.875518 -313.623194) (xy 291.9263 -313.631237)
			(xy 291.975199 -313.647125) (xy 292.021011 -313.670468) (xy 292.062607 -313.700689) (xy 292.098963 -313.737045)
			(xy 292.129184 -313.778641) (xy 292.152527 -313.824453) (xy 292.168415 -313.873352) (xy 292.176458 -313.924134)
			(xy 292.176962 -313.949842) (xy 292.493966 -313.949842) (xy 292.497926 -313.900788) (xy 292.509703 -313.853004)
			(xy 292.528994 -313.807728) (xy 292.555297 -313.766132) (xy 292.587932 -313.729295) (xy 292.626053 -313.69817)
			(xy 292.668674 -313.673563) (xy 292.71469 -313.656111) (xy 292.762909 -313.646267) (xy 292.812084 -313.644286)
			(xy 292.860939 -313.650218) (xy 292.90821 -313.66391) (xy 292.952672 -313.685008) (xy 292.993175 -313.712964)
			(xy 293.028668 -313.747056) (xy 293.058233 -313.7864) (xy 293.081104 -313.829977) (xy 293.096688 -313.876658)
			(xy 293.104583 -313.925235) (xy 293.105078 -313.949842) (xy 293.104583 -313.974449) (xy 293.104404 -313.97555)
			(xy 293.423082 -313.97555) (xy 293.423082 -313.924134) (xy 293.431125 -313.873352) (xy 293.447013 -313.824453)
			(xy 293.470356 -313.778641) (xy 293.500577 -313.737045) (xy 293.536933 -313.700689) (xy 293.578529 -313.670468)
			(xy 293.624341 -313.647125) (xy 293.67324 -313.631237) (xy 293.724022 -313.623194) (xy 293.775438 -313.623194)
			(xy 293.82622 -313.631237) (xy 293.875119 -313.647125) (xy 293.920931 -313.670468) (xy 293.962527 -313.700689)
			(xy 293.998883 -313.737045) (xy 294.029104 -313.778641) (xy 294.052447 -313.824453) (xy 294.068335 -313.873352)
			(xy 294.076378 -313.924134) (xy 294.076882 -313.949842) (xy 294.393886 -313.949842) (xy 294.397846 -313.900788)
			(xy 294.409623 -313.853004) (xy 294.428914 -313.807728) (xy 294.455217 -313.766132) (xy 294.487852 -313.729295)
			(xy 294.525973 -313.69817) (xy 294.568594 -313.673563) (xy 294.61461 -313.656111) (xy 294.662829 -313.646267)
			(xy 294.712004 -313.644286) (xy 294.760859 -313.650218) (xy 294.80813 -313.66391) (xy 294.852592 -313.685008)
			(xy 294.893095 -313.712964) (xy 294.928588 -313.747056) (xy 294.958153 -313.7864) (xy 294.981024 -313.829977)
			(xy 294.996608 -313.876658) (xy 295.004503 -313.925235) (xy 295.004998 -313.949842) (xy 295.004503 -313.974449)
			(xy 295.004324 -313.97555) (xy 295.323256 -313.97555) (xy 295.323256 -313.924134) (xy 295.331299 -313.873352)
			(xy 295.347187 -313.824453) (xy 295.37053 -313.778641) (xy 295.400751 -313.737045) (xy 295.437107 -313.700689)
			(xy 295.478703 -313.670468) (xy 295.524515 -313.647125) (xy 295.573414 -313.631237) (xy 295.624196 -313.623194)
			(xy 295.675612 -313.623194) (xy 295.726394 -313.631237) (xy 295.775293 -313.647125) (xy 295.821105 -313.670468)
			(xy 295.862701 -313.700689) (xy 295.899057 -313.737045) (xy 295.929278 -313.778641) (xy 295.952621 -313.824453)
			(xy 295.968509 -313.873352) (xy 295.976552 -313.924134) (xy 295.977056 -313.949842) (xy 296.29406 -313.949842)
			(xy 296.29802 -313.900788) (xy 296.309797 -313.853004) (xy 296.329088 -313.807728) (xy 296.355391 -313.766132)
			(xy 296.388026 -313.729295) (xy 296.426147 -313.69817) (xy 296.468768 -313.673563) (xy 296.514784 -313.656111)
			(xy 296.563003 -313.646267) (xy 296.612178 -313.644286) (xy 296.661033 -313.650218) (xy 296.708304 -313.66391)
			(xy 296.752766 -313.685008) (xy 296.793269 -313.712964) (xy 296.828762 -313.747056) (xy 296.858327 -313.7864)
			(xy 296.881198 -313.829977) (xy 296.896782 -313.876658) (xy 296.904677 -313.925235) (xy 296.905172 -313.949842)
			(xy 296.904677 -313.974449) (xy 296.904498 -313.97555) (xy 297.223176 -313.97555) (xy 297.223176 -313.924134)
			(xy 297.231219 -313.873352) (xy 297.247107 -313.824453) (xy 297.27045 -313.778641) (xy 297.300671 -313.737045)
			(xy 297.337027 -313.700689) (xy 297.378623 -313.670468) (xy 297.424435 -313.647125) (xy 297.473334 -313.631237)
			(xy 297.524116 -313.623194) (xy 297.575532 -313.623194) (xy 297.626314 -313.631237) (xy 297.675213 -313.647125)
			(xy 297.721025 -313.670468) (xy 297.762621 -313.700689) (xy 297.798977 -313.737045) (xy 297.829198 -313.778641)
			(xy 297.852541 -313.824453) (xy 297.868429 -313.873352) (xy 297.876472 -313.924134) (xy 297.876976 -313.949842)
			(xy 298.19398 -313.949842) (xy 298.19794 -313.900788) (xy 298.209717 -313.853004) (xy 298.229008 -313.807728)
			(xy 298.255311 -313.766132) (xy 298.287946 -313.729295) (xy 298.326067 -313.69817) (xy 298.368688 -313.673563)
			(xy 298.414704 -313.656111) (xy 298.462923 -313.646267) (xy 298.512098 -313.644286) (xy 298.560953 -313.650218)
			(xy 298.608224 -313.66391) (xy 298.652686 -313.685008) (xy 298.693189 -313.712964) (xy 298.728682 -313.747056)
			(xy 298.758247 -313.7864) (xy 298.781118 -313.829977) (xy 298.796702 -313.876658) (xy 298.804597 -313.925235)
			(xy 298.805092 -313.949842) (xy 298.804597 -313.974449) (xy 298.804418 -313.97555) (xy 299.123096 -313.97555)
			(xy 299.123096 -313.924134) (xy 299.131139 -313.873352) (xy 299.147027 -313.824453) (xy 299.17037 -313.778641)
			(xy 299.200591 -313.737045) (xy 299.236947 -313.700689) (xy 299.278543 -313.670468) (xy 299.324355 -313.647125)
			(xy 299.373254 -313.631237) (xy 299.424036 -313.623194) (xy 299.475452 -313.623194) (xy 299.526234 -313.631237)
			(xy 299.575133 -313.647125) (xy 299.620945 -313.670468) (xy 299.662541 -313.700689) (xy 299.698897 -313.737045)
			(xy 299.729118 -313.778641) (xy 299.752461 -313.824453) (xy 299.768349 -313.873352) (xy 299.776392 -313.924134)
			(xy 299.776896 -313.949842) (xy 300.0939 -313.949842) (xy 300.09786 -313.900788) (xy 300.109637 -313.853004)
			(xy 300.128928 -313.807728) (xy 300.155231 -313.766132) (xy 300.187866 -313.729295) (xy 300.225987 -313.69817)
			(xy 300.268608 -313.673563) (xy 300.314624 -313.656111) (xy 300.362843 -313.646267) (xy 300.412018 -313.644286)
			(xy 300.460873 -313.650218) (xy 300.508144 -313.66391) (xy 300.552606 -313.685008) (xy 300.593109 -313.712964)
			(xy 300.628602 -313.747056) (xy 300.658167 -313.7864) (xy 300.681038 -313.829977) (xy 300.696622 -313.876658)
			(xy 300.704517 -313.925235) (xy 300.705012 -313.949842) (xy 300.704517 -313.974449) (xy 300.704338 -313.97555)
			(xy 301.02327 -313.97555) (xy 301.02327 -313.924134) (xy 301.031313 -313.873352) (xy 301.047201 -313.824453)
			(xy 301.070544 -313.778641) (xy 301.100765 -313.737045) (xy 301.137121 -313.700689) (xy 301.178717 -313.670468)
			(xy 301.224529 -313.647125) (xy 301.273428 -313.631237) (xy 301.32421 -313.623194) (xy 301.375626 -313.623194)
			(xy 301.426408 -313.631237) (xy 301.475307 -313.647125) (xy 301.521119 -313.670468) (xy 301.562715 -313.700689)
			(xy 301.599071 -313.737045) (xy 301.629292 -313.778641) (xy 301.652635 -313.824453) (xy 301.668523 -313.873352)
			(xy 301.676566 -313.924134) (xy 301.67707 -313.949842) (xy 301.994074 -313.949842) (xy 301.998034 -313.900788)
			(xy 302.009811 -313.853004) (xy 302.029102 -313.807728) (xy 302.055405 -313.766132) (xy 302.08804 -313.729295)
			(xy 302.126161 -313.69817) (xy 302.168782 -313.673563) (xy 302.214798 -313.656111) (xy 302.263017 -313.646267)
			(xy 302.312192 -313.644286) (xy 302.361047 -313.650218) (xy 302.408318 -313.66391) (xy 302.45278 -313.685008)
			(xy 302.493283 -313.712964) (xy 302.528776 -313.747056) (xy 302.558341 -313.7864) (xy 302.581212 -313.829977)
			(xy 302.596796 -313.876658) (xy 302.604691 -313.925235) (xy 302.605186 -313.949842) (xy 302.604691 -313.974449)
			(xy 302.604512 -313.97555) (xy 302.92319 -313.97555) (xy 302.92319 -313.924134) (xy 302.931233 -313.873352)
			(xy 302.947121 -313.824453) (xy 302.970464 -313.778641) (xy 303.000685 -313.737045) (xy 303.037041 -313.700689)
			(xy 303.078637 -313.670468) (xy 303.124449 -313.647125) (xy 303.173348 -313.631237) (xy 303.22413 -313.623194)
			(xy 303.275546 -313.623194) (xy 303.326328 -313.631237) (xy 303.375227 -313.647125) (xy 303.421039 -313.670468)
			(xy 303.462635 -313.700689) (xy 303.498991 -313.737045) (xy 303.529212 -313.778641) (xy 303.552555 -313.824453)
			(xy 303.568443 -313.873352) (xy 303.576486 -313.924134) (xy 303.57699 -313.949842) (xy 303.893994 -313.949842)
			(xy 303.897954 -313.900788) (xy 303.909731 -313.853004) (xy 303.929022 -313.807728) (xy 303.955325 -313.766132)
			(xy 303.98796 -313.729295) (xy 304.026081 -313.69817) (xy 304.068702 -313.673563) (xy 304.114718 -313.656111)
			(xy 304.162937 -313.646267) (xy 304.212112 -313.644286) (xy 304.260967 -313.650218) (xy 304.308238 -313.66391)
			(xy 304.3527 -313.685008) (xy 304.393203 -313.712964) (xy 304.428696 -313.747056) (xy 304.458261 -313.7864)
			(xy 304.481132 -313.829977) (xy 304.496716 -313.876658) (xy 304.504611 -313.925235) (xy 304.505106 -313.949842)
			(xy 304.504611 -313.974449) (xy 304.504432 -313.97555) (xy 304.82311 -313.97555) (xy 304.82311 -313.924134)
			(xy 304.831153 -313.873352) (xy 304.847041 -313.824453) (xy 304.870384 -313.778641) (xy 304.900605 -313.737045)
			(xy 304.936961 -313.700689) (xy 304.978557 -313.670468) (xy 305.024369 -313.647125) (xy 305.073268 -313.631237)
			(xy 305.12405 -313.623194) (xy 305.175466 -313.623194) (xy 305.226248 -313.631237) (xy 305.275147 -313.647125)
			(xy 305.320959 -313.670468) (xy 305.362555 -313.700689) (xy 305.398911 -313.737045) (xy 305.429132 -313.778641)
			(xy 305.452475 -313.824453) (xy 305.468363 -313.873352) (xy 305.476406 -313.924134) (xy 305.47691 -313.949842)
			(xy 305.793914 -313.949842) (xy 305.797874 -313.900788) (xy 305.809651 -313.853004) (xy 305.828942 -313.807728)
			(xy 305.855245 -313.766132) (xy 305.88788 -313.729295) (xy 305.926001 -313.69817) (xy 305.968622 -313.673563)
			(xy 306.014638 -313.656111) (xy 306.062857 -313.646267) (xy 306.112032 -313.644286) (xy 306.160887 -313.650218)
			(xy 306.208158 -313.66391) (xy 306.25262 -313.685008) (xy 306.293123 -313.712964) (xy 306.328616 -313.747056)
			(xy 306.358181 -313.7864) (xy 306.381052 -313.829977) (xy 306.396636 -313.876658) (xy 306.404531 -313.925235)
			(xy 306.405026 -313.949842) (xy 306.404531 -313.974449) (xy 306.404352 -313.97555) (xy 306.723284 -313.97555)
			(xy 306.723284 -313.924134) (xy 306.731327 -313.873352) (xy 306.747215 -313.824453) (xy 306.770558 -313.778641)
			(xy 306.800779 -313.737045) (xy 306.837135 -313.700689) (xy 306.878731 -313.670468) (xy 306.924543 -313.647125)
			(xy 306.973442 -313.631237) (xy 307.024224 -313.623194) (xy 307.07564 -313.623194) (xy 307.126422 -313.631237)
			(xy 307.175321 -313.647125) (xy 307.221133 -313.670468) (xy 307.262729 -313.700689) (xy 307.299085 -313.737045)
			(xy 307.329306 -313.778641) (xy 307.352649 -313.824453) (xy 307.368537 -313.873352) (xy 307.37658 -313.924134)
			(xy 307.377084 -313.949842) (xy 307.694088 -313.949842) (xy 307.698048 -313.900788) (xy 307.709825 -313.853004)
			(xy 307.729116 -313.807728) (xy 307.755419 -313.766132) (xy 307.788054 -313.729295) (xy 307.826175 -313.69817)
			(xy 307.868796 -313.673563) (xy 307.914812 -313.656111) (xy 307.963031 -313.646267) (xy 308.012206 -313.644286)
			(xy 308.061061 -313.650218) (xy 308.108332 -313.66391) (xy 308.152794 -313.685008) (xy 308.193297 -313.712964)
			(xy 308.22879 -313.747056) (xy 308.258355 -313.7864) (xy 308.281226 -313.829977) (xy 308.29681 -313.876658)
			(xy 308.304705 -313.925235) (xy 308.3052 -313.949842) (xy 308.304705 -313.974449) (xy 308.304526 -313.97555)
			(xy 308.623204 -313.97555) (xy 308.623204 -313.924134) (xy 308.631247 -313.873352) (xy 308.647135 -313.824453)
			(xy 308.670478 -313.778641) (xy 308.700699 -313.737045) (xy 308.737055 -313.700689) (xy 308.778651 -313.670468)
			(xy 308.824463 -313.647125) (xy 308.873362 -313.631237) (xy 308.924144 -313.623194) (xy 308.97556 -313.623194)
			(xy 309.026342 -313.631237) (xy 309.075241 -313.647125) (xy 309.121053 -313.670468) (xy 309.162649 -313.700689)
			(xy 309.199005 -313.737045) (xy 309.229226 -313.778641) (xy 309.252569 -313.824453) (xy 309.268457 -313.873352)
			(xy 309.2765 -313.924134) (xy 309.277004 -313.949842) (xy 309.594008 -313.949842) (xy 309.597968 -313.900788)
			(xy 309.609745 -313.853004) (xy 309.629036 -313.807728) (xy 309.655339 -313.766132) (xy 309.687974 -313.729295)
			(xy 309.726095 -313.69817) (xy 309.768716 -313.673563) (xy 309.814732 -313.656111) (xy 309.862951 -313.646267)
			(xy 309.912126 -313.644286) (xy 309.960981 -313.650218) (xy 310.008252 -313.66391) (xy 310.052714 -313.685008)
			(xy 310.093217 -313.712964) (xy 310.12871 -313.747056) (xy 310.158275 -313.7864) (xy 310.181146 -313.829977)
			(xy 310.19673 -313.876658) (xy 310.204625 -313.925235) (xy 310.20512 -313.949842) (xy 310.204625 -313.974449)
			(xy 310.204446 -313.97555) (xy 310.523124 -313.97555) (xy 310.523124 -313.924134) (xy 310.531167 -313.873352)
			(xy 310.547055 -313.824453) (xy 310.570398 -313.778641) (xy 310.600619 -313.737045) (xy 310.636975 -313.700689)
			(xy 310.678571 -313.670468) (xy 310.724383 -313.647125) (xy 310.773282 -313.631237) (xy 310.824064 -313.623194)
			(xy 310.87548 -313.623194) (xy 310.926262 -313.631237) (xy 310.975161 -313.647125) (xy 311.020973 -313.670468)
			(xy 311.062569 -313.700689) (xy 311.098925 -313.737045) (xy 311.129146 -313.778641) (xy 311.152489 -313.824453)
			(xy 311.168377 -313.873352) (xy 311.17642 -313.924134) (xy 311.176924 -313.949842) (xy 311.493928 -313.949842)
			(xy 311.497888 -313.900788) (xy 311.509665 -313.853004) (xy 311.528956 -313.807728) (xy 311.555259 -313.766132)
			(xy 311.587894 -313.729295) (xy 311.626015 -313.69817) (xy 311.668636 -313.673563) (xy 311.714652 -313.656111)
			(xy 311.762871 -313.646267) (xy 311.812046 -313.644286) (xy 311.860901 -313.650218) (xy 311.908172 -313.66391)
			(xy 311.952634 -313.685008) (xy 311.993137 -313.712964) (xy 312.02863 -313.747056) (xy 312.058195 -313.7864)
			(xy 312.081066 -313.829977) (xy 312.09665 -313.876658) (xy 312.104545 -313.925235) (xy 312.10504 -313.949842)
			(xy 312.104545 -313.974449) (xy 312.104366 -313.97555) (xy 312.423044 -313.97555) (xy 312.423044 -313.924134)
			(xy 312.431087 -313.873352) (xy 312.446975 -313.824453) (xy 312.470318 -313.778641) (xy 312.500539 -313.737045)
			(xy 312.536895 -313.700689) (xy 312.578491 -313.670468) (xy 312.624303 -313.647125) (xy 312.673202 -313.631237)
			(xy 312.723984 -313.623194) (xy 312.7754 -313.623194) (xy 312.826182 -313.631237) (xy 312.875081 -313.647125)
			(xy 312.920893 -313.670468) (xy 312.962489 -313.700689) (xy 312.998845 -313.737045) (xy 313.029066 -313.778641)
			(xy 313.052409 -313.824453) (xy 313.068297 -313.873352) (xy 313.07634 -313.924134) (xy 313.076844 -313.949842)
			(xy 313.394102 -313.949842) (xy 313.398062 -313.900788) (xy 313.409839 -313.853004) (xy 313.42913 -313.807728)
			(xy 313.455433 -313.766132) (xy 313.488068 -313.729295) (xy 313.526189 -313.69817) (xy 313.56881 -313.673563)
			(xy 313.614826 -313.656111) (xy 313.663045 -313.646267) (xy 313.71222 -313.644286) (xy 313.761075 -313.650218)
			(xy 313.808346 -313.66391) (xy 313.852808 -313.685008) (xy 313.893311 -313.712964) (xy 313.928804 -313.747056)
			(xy 313.958369 -313.7864) (xy 313.98124 -313.829977) (xy 313.996824 -313.876658) (xy 314.004719 -313.925235)
			(xy 314.005214 -313.949842) (xy 314.344062 -313.949842) (xy 314.348022 -313.900788) (xy 314.359799 -313.853004)
			(xy 314.37909 -313.807728) (xy 314.405393 -313.766132) (xy 314.438028 -313.729295) (xy 314.476149 -313.69817)
			(xy 314.51877 -313.673563) (xy 314.564786 -313.656111) (xy 314.613005 -313.646267) (xy 314.66218 -313.644286)
			(xy 314.711035 -313.650218) (xy 314.758306 -313.66391) (xy 314.802768 -313.685008) (xy 314.843271 -313.712964)
			(xy 314.878764 -313.747056) (xy 314.908329 -313.7864) (xy 314.9312 -313.829977) (xy 314.946784 -313.876658)
			(xy 314.954679 -313.925235) (xy 314.955174 -313.949842) (xy 314.954679 -313.974449) (xy 314.946784 -314.023026)
			(xy 314.9312 -314.069707) (xy 314.908329 -314.113284) (xy 314.878764 -314.152628) (xy 314.843271 -314.18672)
			(xy 314.802768 -314.214676) (xy 314.758306 -314.235774) (xy 314.711035 -314.249466) (xy 314.66218 -314.255398)
			(xy 314.613005 -314.253417) (xy 314.564786 -314.243573) (xy 314.51877 -314.226121) (xy 314.476149 -314.201514)
			(xy 314.438028 -314.170389) (xy 314.405393 -314.133552) (xy 314.37909 -314.091956) (xy 314.359799 -314.04668)
			(xy 314.348022 -313.998896) (xy 314.344062 -313.949842) (xy 314.005214 -313.949842) (xy 314.004719 -313.974449)
			(xy 313.996824 -314.023026) (xy 313.98124 -314.069707) (xy 313.958369 -314.113284) (xy 313.928804 -314.152628)
			(xy 313.893311 -314.18672) (xy 313.852808 -314.214676) (xy 313.808346 -314.235774) (xy 313.761075 -314.249466)
			(xy 313.71222 -314.255398) (xy 313.663045 -314.253417) (xy 313.614826 -314.243573) (xy 313.56881 -314.226121)
			(xy 313.526189 -314.201514) (xy 313.488068 -314.170389) (xy 313.455433 -314.133552) (xy 313.42913 -314.091956)
			(xy 313.409839 -314.04668) (xy 313.398062 -313.998896) (xy 313.394102 -313.949842) (xy 313.076844 -313.949842)
			(xy 313.07634 -313.97555) (xy 313.068297 -314.026332) (xy 313.052409 -314.075231) (xy 313.029066 -314.121043)
			(xy 312.998845 -314.162639) (xy 312.962489 -314.198995) (xy 312.920893 -314.229216) (xy 312.875081 -314.252559)
			(xy 312.826182 -314.268447) (xy 312.7754 -314.27649) (xy 312.723984 -314.27649) (xy 312.673202 -314.268447)
			(xy 312.624303 -314.252559) (xy 312.578491 -314.229216) (xy 312.536895 -314.198995) (xy 312.500539 -314.162639)
			(xy 312.470318 -314.121043) (xy 312.446975 -314.075231) (xy 312.431087 -314.026332) (xy 312.423044 -313.97555)
			(xy 312.104366 -313.97555) (xy 312.09665 -314.023026) (xy 312.081066 -314.069707) (xy 312.058195 -314.113284)
			(xy 312.02863 -314.152628) (xy 311.993137 -314.18672) (xy 311.952634 -314.214676) (xy 311.908172 -314.235774)
			(xy 311.860901 -314.249466) (xy 311.812046 -314.255398) (xy 311.762871 -314.253417) (xy 311.714652 -314.243573)
			(xy 311.668636 -314.226121) (xy 311.626015 -314.201514) (xy 311.587894 -314.170389) (xy 311.555259 -314.133552)
			(xy 311.528956 -314.091956) (xy 311.509665 -314.04668) (xy 311.497888 -313.998896) (xy 311.493928 -313.949842)
			(xy 311.176924 -313.949842) (xy 311.17642 -313.97555) (xy 311.168377 -314.026332) (xy 311.152489 -314.075231)
			(xy 311.129146 -314.121043) (xy 311.098925 -314.162639) (xy 311.062569 -314.198995) (xy 311.020973 -314.229216)
			(xy 310.975161 -314.252559) (xy 310.926262 -314.268447) (xy 310.87548 -314.27649) (xy 310.824064 -314.27649)
			(xy 310.773282 -314.268447) (xy 310.724383 -314.252559) (xy 310.678571 -314.229216) (xy 310.636975 -314.198995)
			(xy 310.600619 -314.162639) (xy 310.570398 -314.121043) (xy 310.547055 -314.075231) (xy 310.531167 -314.026332)
			(xy 310.523124 -313.97555) (xy 310.204446 -313.97555) (xy 310.19673 -314.023026) (xy 310.181146 -314.069707)
			(xy 310.158275 -314.113284) (xy 310.12871 -314.152628) (xy 310.093217 -314.18672) (xy 310.052714 -314.214676)
			(xy 310.008252 -314.235774) (xy 309.960981 -314.249466) (xy 309.912126 -314.255398) (xy 309.862951 -314.253417)
			(xy 309.814732 -314.243573) (xy 309.768716 -314.226121) (xy 309.726095 -314.201514) (xy 309.687974 -314.170389)
			(xy 309.655339 -314.133552) (xy 309.629036 -314.091956) (xy 309.609745 -314.04668) (xy 309.597968 -313.998896)
			(xy 309.594008 -313.949842) (xy 309.277004 -313.949842) (xy 309.2765 -313.97555) (xy 309.268457 -314.026332)
			(xy 309.252569 -314.075231) (xy 309.229226 -314.121043) (xy 309.199005 -314.162639) (xy 309.162649 -314.198995)
			(xy 309.121053 -314.229216) (xy 309.075241 -314.252559) (xy 309.026342 -314.268447) (xy 308.97556 -314.27649)
			(xy 308.924144 -314.27649) (xy 308.873362 -314.268447) (xy 308.824463 -314.252559) (xy 308.778651 -314.229216)
			(xy 308.737055 -314.198995) (xy 308.700699 -314.162639) (xy 308.670478 -314.121043) (xy 308.647135 -314.075231)
			(xy 308.631247 -314.026332) (xy 308.623204 -313.97555) (xy 308.304526 -313.97555) (xy 308.29681 -314.023026)
			(xy 308.281226 -314.069707) (xy 308.258355 -314.113284) (xy 308.22879 -314.152628) (xy 308.193297 -314.18672)
			(xy 308.152794 -314.214676) (xy 308.108332 -314.235774) (xy 308.061061 -314.249466) (xy 308.012206 -314.255398)
			(xy 307.963031 -314.253417) (xy 307.914812 -314.243573) (xy 307.868796 -314.226121) (xy 307.826175 -314.201514)
			(xy 307.788054 -314.170389) (xy 307.755419 -314.133552) (xy 307.729116 -314.091956) (xy 307.709825 -314.04668)
			(xy 307.698048 -313.998896) (xy 307.694088 -313.949842) (xy 307.377084 -313.949842) (xy 307.37658 -313.97555)
			(xy 307.368537 -314.026332) (xy 307.352649 -314.075231) (xy 307.329306 -314.121043) (xy 307.299085 -314.162639)
			(xy 307.262729 -314.198995) (xy 307.221133 -314.229216) (xy 307.175321 -314.252559) (xy 307.126422 -314.268447)
			(xy 307.07564 -314.27649) (xy 307.024224 -314.27649) (xy 306.973442 -314.268447) (xy 306.924543 -314.252559)
			(xy 306.878731 -314.229216) (xy 306.837135 -314.198995) (xy 306.800779 -314.162639) (xy 306.770558 -314.121043)
			(xy 306.747215 -314.075231) (xy 306.731327 -314.026332) (xy 306.723284 -313.97555) (xy 306.404352 -313.97555)
			(xy 306.396636 -314.023026) (xy 306.381052 -314.069707) (xy 306.358181 -314.113284) (xy 306.328616 -314.152628)
			(xy 306.293123 -314.18672) (xy 306.25262 -314.214676) (xy 306.208158 -314.235774) (xy 306.160887 -314.249466)
			(xy 306.112032 -314.255398) (xy 306.062857 -314.253417) (xy 306.014638 -314.243573) (xy 305.968622 -314.226121)
			(xy 305.926001 -314.201514) (xy 305.88788 -314.170389) (xy 305.855245 -314.133552) (xy 305.828942 -314.091956)
			(xy 305.809651 -314.04668) (xy 305.797874 -313.998896) (xy 305.793914 -313.949842) (xy 305.47691 -313.949842)
			(xy 305.476406 -313.97555) (xy 305.468363 -314.026332) (xy 305.452475 -314.075231) (xy 305.429132 -314.121043)
			(xy 305.398911 -314.162639) (xy 305.362555 -314.198995) (xy 305.320959 -314.229216) (xy 305.275147 -314.252559)
			(xy 305.226248 -314.268447) (xy 305.175466 -314.27649) (xy 305.12405 -314.27649) (xy 305.073268 -314.268447)
			(xy 305.024369 -314.252559) (xy 304.978557 -314.229216) (xy 304.936961 -314.198995) (xy 304.900605 -314.162639)
			(xy 304.870384 -314.121043) (xy 304.847041 -314.075231) (xy 304.831153 -314.026332) (xy 304.82311 -313.97555)
			(xy 304.504432 -313.97555) (xy 304.496716 -314.023026) (xy 304.481132 -314.069707) (xy 304.458261 -314.113284)
			(xy 304.428696 -314.152628) (xy 304.393203 -314.18672) (xy 304.3527 -314.214676) (xy 304.308238 -314.235774)
			(xy 304.260967 -314.249466) (xy 304.212112 -314.255398) (xy 304.162937 -314.253417) (xy 304.114718 -314.243573)
			(xy 304.068702 -314.226121) (xy 304.026081 -314.201514) (xy 303.98796 -314.170389) (xy 303.955325 -314.133552)
			(xy 303.929022 -314.091956) (xy 303.909731 -314.04668) (xy 303.897954 -313.998896) (xy 303.893994 -313.949842)
			(xy 303.57699 -313.949842) (xy 303.576486 -313.97555) (xy 303.568443 -314.026332) (xy 303.552555 -314.075231)
			(xy 303.529212 -314.121043) (xy 303.498991 -314.162639) (xy 303.462635 -314.198995) (xy 303.421039 -314.229216)
			(xy 303.375227 -314.252559) (xy 303.326328 -314.268447) (xy 303.275546 -314.27649) (xy 303.22413 -314.27649)
			(xy 303.173348 -314.268447) (xy 303.124449 -314.252559) (xy 303.078637 -314.229216) (xy 303.037041 -314.198995)
			(xy 303.000685 -314.162639) (xy 302.970464 -314.121043) (xy 302.947121 -314.075231) (xy 302.931233 -314.026332)
			(xy 302.92319 -313.97555) (xy 302.604512 -313.97555) (xy 302.596796 -314.023026) (xy 302.581212 -314.069707)
			(xy 302.558341 -314.113284) (xy 302.528776 -314.152628) (xy 302.493283 -314.18672) (xy 302.45278 -314.214676)
			(xy 302.408318 -314.235774) (xy 302.361047 -314.249466) (xy 302.312192 -314.255398) (xy 302.263017 -314.253417)
			(xy 302.214798 -314.243573) (xy 302.168782 -314.226121) (xy 302.126161 -314.201514) (xy 302.08804 -314.170389)
			(xy 302.055405 -314.133552) (xy 302.029102 -314.091956) (xy 302.009811 -314.04668) (xy 301.998034 -313.998896)
			(xy 301.994074 -313.949842) (xy 301.67707 -313.949842) (xy 301.676566 -313.97555) (xy 301.668523 -314.026332)
			(xy 301.652635 -314.075231) (xy 301.629292 -314.121043) (xy 301.599071 -314.162639) (xy 301.562715 -314.198995)
			(xy 301.521119 -314.229216) (xy 301.475307 -314.252559) (xy 301.426408 -314.268447) (xy 301.375626 -314.27649)
			(xy 301.32421 -314.27649) (xy 301.273428 -314.268447) (xy 301.224529 -314.252559) (xy 301.178717 -314.229216)
			(xy 301.137121 -314.198995) (xy 301.100765 -314.162639) (xy 301.070544 -314.121043) (xy 301.047201 -314.075231)
			(xy 301.031313 -314.026332) (xy 301.02327 -313.97555) (xy 300.704338 -313.97555) (xy 300.696622 -314.023026)
			(xy 300.681038 -314.069707) (xy 300.658167 -314.113284) (xy 300.628602 -314.152628) (xy 300.593109 -314.18672)
			(xy 300.552606 -314.214676) (xy 300.508144 -314.235774) (xy 300.460873 -314.249466) (xy 300.412018 -314.255398)
			(xy 300.362843 -314.253417) (xy 300.314624 -314.243573) (xy 300.268608 -314.226121) (xy 300.225987 -314.201514)
			(xy 300.187866 -314.170389) (xy 300.155231 -314.133552) (xy 300.128928 -314.091956) (xy 300.109637 -314.04668)
			(xy 300.09786 -313.998896) (xy 300.0939 -313.949842) (xy 299.776896 -313.949842) (xy 299.776392 -313.97555)
			(xy 299.768349 -314.026332) (xy 299.752461 -314.075231) (xy 299.729118 -314.121043) (xy 299.698897 -314.162639)
			(xy 299.662541 -314.198995) (xy 299.620945 -314.229216) (xy 299.575133 -314.252559) (xy 299.526234 -314.268447)
			(xy 299.475452 -314.27649) (xy 299.424036 -314.27649) (xy 299.373254 -314.268447) (xy 299.324355 -314.252559)
			(xy 299.278543 -314.229216) (xy 299.236947 -314.198995) (xy 299.200591 -314.162639) (xy 299.17037 -314.121043)
			(xy 299.147027 -314.075231) (xy 299.131139 -314.026332) (xy 299.123096 -313.97555) (xy 298.804418 -313.97555)
			(xy 298.796702 -314.023026) (xy 298.781118 -314.069707) (xy 298.758247 -314.113284) (xy 298.728682 -314.152628)
			(xy 298.693189 -314.18672) (xy 298.652686 -314.214676) (xy 298.608224 -314.235774) (xy 298.560953 -314.249466)
			(xy 298.512098 -314.255398) (xy 298.462923 -314.253417) (xy 298.414704 -314.243573) (xy 298.368688 -314.226121)
			(xy 298.326067 -314.201514) (xy 298.287946 -314.170389) (xy 298.255311 -314.133552) (xy 298.229008 -314.091956)
			(xy 298.209717 -314.04668) (xy 298.19794 -313.998896) (xy 298.19398 -313.949842) (xy 297.876976 -313.949842)
			(xy 297.876472 -313.97555) (xy 297.868429 -314.026332) (xy 297.852541 -314.075231) (xy 297.829198 -314.121043)
			(xy 297.798977 -314.162639) (xy 297.762621 -314.198995) (xy 297.721025 -314.229216) (xy 297.675213 -314.252559)
			(xy 297.626314 -314.268447) (xy 297.575532 -314.27649) (xy 297.524116 -314.27649) (xy 297.473334 -314.268447)
			(xy 297.424435 -314.252559) (xy 297.378623 -314.229216) (xy 297.337027 -314.198995) (xy 297.300671 -314.162639)
			(xy 297.27045 -314.121043) (xy 297.247107 -314.075231) (xy 297.231219 -314.026332) (xy 297.223176 -313.97555)
			(xy 296.904498 -313.97555) (xy 296.896782 -314.023026) (xy 296.881198 -314.069707) (xy 296.858327 -314.113284)
			(xy 296.828762 -314.152628) (xy 296.793269 -314.18672) (xy 296.752766 -314.214676) (xy 296.708304 -314.235774)
			(xy 296.661033 -314.249466) (xy 296.612178 -314.255398) (xy 296.563003 -314.253417) (xy 296.514784 -314.243573)
			(xy 296.468768 -314.226121) (xy 296.426147 -314.201514) (xy 296.388026 -314.170389) (xy 296.355391 -314.133552)
			(xy 296.329088 -314.091956) (xy 296.309797 -314.04668) (xy 296.29802 -313.998896) (xy 296.29406 -313.949842)
			(xy 295.977056 -313.949842) (xy 295.976552 -313.97555) (xy 295.968509 -314.026332) (xy 295.952621 -314.075231)
			(xy 295.929278 -314.121043) (xy 295.899057 -314.162639) (xy 295.862701 -314.198995) (xy 295.821105 -314.229216)
			(xy 295.775293 -314.252559) (xy 295.726394 -314.268447) (xy 295.675612 -314.27649) (xy 295.624196 -314.27649)
			(xy 295.573414 -314.268447) (xy 295.524515 -314.252559) (xy 295.478703 -314.229216) (xy 295.437107 -314.198995)
			(xy 295.400751 -314.162639) (xy 295.37053 -314.121043) (xy 295.347187 -314.075231) (xy 295.331299 -314.026332)
			(xy 295.323256 -313.97555) (xy 295.004324 -313.97555) (xy 294.996608 -314.023026) (xy 294.981024 -314.069707)
			(xy 294.958153 -314.113284) (xy 294.928588 -314.152628) (xy 294.893095 -314.18672) (xy 294.852592 -314.214676)
			(xy 294.80813 -314.235774) (xy 294.760859 -314.249466) (xy 294.712004 -314.255398) (xy 294.662829 -314.253417)
			(xy 294.61461 -314.243573) (xy 294.568594 -314.226121) (xy 294.525973 -314.201514) (xy 294.487852 -314.170389)
			(xy 294.455217 -314.133552) (xy 294.428914 -314.091956) (xy 294.409623 -314.04668) (xy 294.397846 -313.998896)
			(xy 294.393886 -313.949842) (xy 294.076882 -313.949842) (xy 294.076378 -313.97555) (xy 294.068335 -314.026332)
			(xy 294.052447 -314.075231) (xy 294.029104 -314.121043) (xy 293.998883 -314.162639) (xy 293.962527 -314.198995)
			(xy 293.920931 -314.229216) (xy 293.875119 -314.252559) (xy 293.82622 -314.268447) (xy 293.775438 -314.27649)
			(xy 293.724022 -314.27649) (xy 293.67324 -314.268447) (xy 293.624341 -314.252559) (xy 293.578529 -314.229216)
			(xy 293.536933 -314.198995) (xy 293.500577 -314.162639) (xy 293.470356 -314.121043) (xy 293.447013 -314.075231)
			(xy 293.431125 -314.026332) (xy 293.423082 -313.97555) (xy 293.104404 -313.97555) (xy 293.096688 -314.023026)
			(xy 293.081104 -314.069707) (xy 293.058233 -314.113284) (xy 293.028668 -314.152628) (xy 292.993175 -314.18672)
			(xy 292.952672 -314.214676) (xy 292.90821 -314.235774) (xy 292.860939 -314.249466) (xy 292.812084 -314.255398)
			(xy 292.762909 -314.253417) (xy 292.71469 -314.243573) (xy 292.668674 -314.226121) (xy 292.626053 -314.201514)
			(xy 292.587932 -314.170389) (xy 292.555297 -314.133552) (xy 292.528994 -314.091956) (xy 292.509703 -314.04668)
			(xy 292.497926 -313.998896) (xy 292.493966 -313.949842) (xy 292.176962 -313.949842) (xy 292.176458 -313.97555)
			(xy 292.168415 -314.026332) (xy 292.152527 -314.075231) (xy 292.129184 -314.121043) (xy 292.098963 -314.162639)
			(xy 292.062607 -314.198995) (xy 292.021011 -314.229216) (xy 291.975199 -314.252559) (xy 291.9263 -314.268447)
			(xy 291.875518 -314.27649) (xy 291.824102 -314.27649) (xy 291.77332 -314.268447) (xy 291.724421 -314.252559)
			(xy 291.678609 -314.229216) (xy 291.637013 -314.198995) (xy 291.600657 -314.162639) (xy 291.570436 -314.121043)
			(xy 291.547093 -314.075231) (xy 291.531205 -314.026332) (xy 291.523162 -313.97555) (xy 291.204388 -313.97555)
			(xy 291.19744 -314.020117) (xy 291.18307 -314.065104) (xy 291.161948 -314.107343) (xy 291.134576 -314.145828)
			(xy 291.101607 -314.179641) (xy 291.063827 -314.207978) (xy 291.022136 -314.230162) (xy 290.977528 -314.245665)
			(xy 290.931064 -314.254119) (xy 290.90747 -314.25515) (xy 290.897338 -314.255788) (xy 290.878799 -314.264019)
			(xy 290.86492 -314.278811) (xy 290.860988 -314.28817) (xy 290.844355 -314.331368) (xy 290.804023 -314.414691)
			(xy 290.78047 -314.45454) (xy 290.771326 -314.469526) (xy 290.77539 -314.50407) (xy 290.858702 -314.587382)
			(xy 290.87826 -314.595002) (xy 290.888928 -314.594748) (xy 290.89985 -314.594494) (xy 290.923839 -314.594968)
			(xy 290.971224 -314.602481) (xy 291.016851 -314.617313) (xy 291.059597 -314.639099) (xy 291.098409 -314.667303)
			(xy 291.132331 -314.701231) (xy 291.160528 -314.740047) (xy 291.182307 -314.782797) (xy 291.197131 -314.828427)
			(xy 291.204636 -314.875813) (xy 291.205158 -314.899802) (xy 291.544006 -314.899802) (xy 291.547966 -314.850748)
			(xy 291.559743 -314.802964) (xy 291.579034 -314.757688) (xy 291.605337 -314.716092) (xy 291.637972 -314.679255)
			(xy 291.676093 -314.64813) (xy 291.718714 -314.623523) (xy 291.76473 -314.606071) (xy 291.812949 -314.596227)
			(xy 291.862124 -314.594246) (xy 291.910979 -314.600178) (xy 291.95825 -314.61387) (xy 292.002712 -314.634968)
			(xy 292.043215 -314.662924) (xy 292.078708 -314.697016) (xy 292.108273 -314.73636) (xy 292.131144 -314.779937)
			(xy 292.146728 -314.826618) (xy 292.154623 -314.875195) (xy 292.155118 -314.899802) (xy 292.493966 -314.899802)
			(xy 292.497926 -314.850748) (xy 292.509703 -314.802964) (xy 292.528994 -314.757688) (xy 292.555297 -314.716092)
			(xy 292.587932 -314.679255) (xy 292.626053 -314.64813) (xy 292.668674 -314.623523) (xy 292.71469 -314.606071)
			(xy 292.762909 -314.596227) (xy 292.812084 -314.594246) (xy 292.860939 -314.600178) (xy 292.90821 -314.61387)
			(xy 292.952672 -314.634968) (xy 292.993175 -314.662924) (xy 293.028668 -314.697016) (xy 293.058233 -314.73636)
			(xy 293.081104 -314.779937) (xy 293.096688 -314.826618) (xy 293.104583 -314.875195) (xy 293.105078 -314.899802)
			(xy 293.443926 -314.899802) (xy 293.447886 -314.850748) (xy 293.459663 -314.802964) (xy 293.478954 -314.757688)
			(xy 293.505257 -314.716092) (xy 293.537892 -314.679255) (xy 293.576013 -314.64813) (xy 293.618634 -314.623523)
			(xy 293.66465 -314.606071) (xy 293.712869 -314.596227) (xy 293.762044 -314.594246) (xy 293.810899 -314.600178)
			(xy 293.85817 -314.61387) (xy 293.902632 -314.634968) (xy 293.943135 -314.662924) (xy 293.978628 -314.697016)
			(xy 294.008193 -314.73636) (xy 294.031064 -314.779937) (xy 294.046648 -314.826618) (xy 294.054543 -314.875195)
			(xy 294.055038 -314.899802) (xy 294.393886 -314.899802) (xy 294.397846 -314.850748) (xy 294.409623 -314.802964)
			(xy 294.428914 -314.757688) (xy 294.455217 -314.716092) (xy 294.487852 -314.679255) (xy 294.525973 -314.64813)
			(xy 294.568594 -314.623523) (xy 294.61461 -314.606071) (xy 294.662829 -314.596227) (xy 294.712004 -314.594246)
			(xy 294.760859 -314.600178) (xy 294.80813 -314.61387) (xy 294.852592 -314.634968) (xy 294.893095 -314.662924)
			(xy 294.928588 -314.697016) (xy 294.958153 -314.73636) (xy 294.981024 -314.779937) (xy 294.996608 -314.826618)
			(xy 295.004503 -314.875195) (xy 295.004998 -314.899802) (xy 295.3441 -314.899802) (xy 295.34806 -314.850748)
			(xy 295.359837 -314.802964) (xy 295.379128 -314.757688) (xy 295.405431 -314.716092) (xy 295.438066 -314.679255)
			(xy 295.476187 -314.64813) (xy 295.518808 -314.623523) (xy 295.564824 -314.606071) (xy 295.613043 -314.596227)
			(xy 295.662218 -314.594246) (xy 295.711073 -314.600178) (xy 295.758344 -314.61387) (xy 295.802806 -314.634968)
			(xy 295.843309 -314.662924) (xy 295.878802 -314.697016) (xy 295.908367 -314.73636) (xy 295.931238 -314.779937)
			(xy 295.946822 -314.826618) (xy 295.954717 -314.875195) (xy 295.955212 -314.899802) (xy 296.29406 -314.899802)
			(xy 296.29802 -314.850748) (xy 296.309797 -314.802964) (xy 296.329088 -314.757688) (xy 296.355391 -314.716092)
			(xy 296.388026 -314.679255) (xy 296.426147 -314.64813) (xy 296.468768 -314.623523) (xy 296.514784 -314.606071)
			(xy 296.563003 -314.596227) (xy 296.612178 -314.594246) (xy 296.661033 -314.600178) (xy 296.708304 -314.61387)
			(xy 296.752766 -314.634968) (xy 296.793269 -314.662924) (xy 296.828762 -314.697016) (xy 296.858327 -314.73636)
			(xy 296.881198 -314.779937) (xy 296.896782 -314.826618) (xy 296.904677 -314.875195) (xy 296.905172 -314.899802)
			(xy 297.24402 -314.899802) (xy 297.24798 -314.850748) (xy 297.259757 -314.802964) (xy 297.279048 -314.757688)
			(xy 297.305351 -314.716092) (xy 297.337986 -314.679255) (xy 297.376107 -314.64813) (xy 297.418728 -314.623523)
			(xy 297.464744 -314.606071) (xy 297.512963 -314.596227) (xy 297.562138 -314.594246) (xy 297.610993 -314.600178)
			(xy 297.658264 -314.61387) (xy 297.702726 -314.634968) (xy 297.743229 -314.662924) (xy 297.778722 -314.697016)
			(xy 297.808287 -314.73636) (xy 297.831158 -314.779937) (xy 297.846742 -314.826618) (xy 297.854637 -314.875195)
			(xy 297.855132 -314.899802) (xy 298.19398 -314.899802) (xy 298.19794 -314.850748) (xy 298.209717 -314.802964)
			(xy 298.229008 -314.757688) (xy 298.255311 -314.716092) (xy 298.287946 -314.679255) (xy 298.326067 -314.64813)
			(xy 298.368688 -314.623523) (xy 298.414704 -314.606071) (xy 298.462923 -314.596227) (xy 298.512098 -314.594246)
			(xy 298.560953 -314.600178) (xy 298.608224 -314.61387) (xy 298.652686 -314.634968) (xy 298.693189 -314.662924)
			(xy 298.728682 -314.697016) (xy 298.758247 -314.73636) (xy 298.781118 -314.779937) (xy 298.796702 -314.826618)
			(xy 298.804597 -314.875195) (xy 298.805092 -314.899802) (xy 299.14394 -314.899802) (xy 299.1479 -314.850748)
			(xy 299.159677 -314.802964) (xy 299.178968 -314.757688) (xy 299.205271 -314.716092) (xy 299.237906 -314.679255)
			(xy 299.276027 -314.64813) (xy 299.318648 -314.623523) (xy 299.364664 -314.606071) (xy 299.412883 -314.596227)
			(xy 299.462058 -314.594246) (xy 299.510913 -314.600178) (xy 299.558184 -314.61387) (xy 299.602646 -314.634968)
			(xy 299.643149 -314.662924) (xy 299.678642 -314.697016) (xy 299.708207 -314.73636) (xy 299.731078 -314.779937)
			(xy 299.746662 -314.826618) (xy 299.754557 -314.875195) (xy 299.755052 -314.899802) (xy 300.0939 -314.899802)
			(xy 300.09786 -314.850748) (xy 300.109637 -314.802964) (xy 300.128928 -314.757688) (xy 300.155231 -314.716092)
			(xy 300.187866 -314.679255) (xy 300.225987 -314.64813) (xy 300.268608 -314.623523) (xy 300.314624 -314.606071)
			(xy 300.362843 -314.596227) (xy 300.412018 -314.594246) (xy 300.460873 -314.600178) (xy 300.508144 -314.61387)
			(xy 300.552606 -314.634968) (xy 300.593109 -314.662924) (xy 300.628602 -314.697016) (xy 300.658167 -314.73636)
			(xy 300.681038 -314.779937) (xy 300.696622 -314.826618) (xy 300.704517 -314.875195) (xy 300.705012 -314.899802)
			(xy 301.044114 -314.899802) (xy 301.048074 -314.850748) (xy 301.059851 -314.802964) (xy 301.079142 -314.757688)
			(xy 301.105445 -314.716092) (xy 301.13808 -314.679255) (xy 301.176201 -314.64813) (xy 301.218822 -314.623523)
			(xy 301.264838 -314.606071) (xy 301.313057 -314.596227) (xy 301.362232 -314.594246) (xy 301.411087 -314.600178)
			(xy 301.458358 -314.61387) (xy 301.50282 -314.634968) (xy 301.543323 -314.662924) (xy 301.578816 -314.697016)
			(xy 301.608381 -314.73636) (xy 301.631252 -314.779937) (xy 301.646836 -314.826618) (xy 301.654731 -314.875195)
			(xy 301.655226 -314.899802) (xy 301.994074 -314.899802) (xy 301.998034 -314.850748) (xy 302.009811 -314.802964)
			(xy 302.029102 -314.757688) (xy 302.055405 -314.716092) (xy 302.08804 -314.679255) (xy 302.126161 -314.64813)
			(xy 302.168782 -314.623523) (xy 302.214798 -314.606071) (xy 302.263017 -314.596227) (xy 302.312192 -314.594246)
			(xy 302.361047 -314.600178) (xy 302.408318 -314.61387) (xy 302.45278 -314.634968) (xy 302.493283 -314.662924)
			(xy 302.528776 -314.697016) (xy 302.558341 -314.73636) (xy 302.581212 -314.779937) (xy 302.596796 -314.826618)
			(xy 302.604691 -314.875195) (xy 302.605186 -314.899802) (xy 302.944034 -314.899802) (xy 302.947994 -314.850748)
			(xy 302.959771 -314.802964) (xy 302.979062 -314.757688) (xy 303.005365 -314.716092) (xy 303.038 -314.679255)
			(xy 303.076121 -314.64813) (xy 303.118742 -314.623523) (xy 303.164758 -314.606071) (xy 303.212977 -314.596227)
			(xy 303.262152 -314.594246) (xy 303.311007 -314.600178) (xy 303.358278 -314.61387) (xy 303.40274 -314.634968)
			(xy 303.443243 -314.662924) (xy 303.478736 -314.697016) (xy 303.508301 -314.73636) (xy 303.531172 -314.779937)
			(xy 303.546756 -314.826618) (xy 303.554651 -314.875195) (xy 303.555146 -314.899802) (xy 303.893994 -314.899802)
			(xy 303.897954 -314.850748) (xy 303.909731 -314.802964) (xy 303.929022 -314.757688) (xy 303.955325 -314.716092)
			(xy 303.98796 -314.679255) (xy 304.026081 -314.64813) (xy 304.068702 -314.623523) (xy 304.114718 -314.606071)
			(xy 304.162937 -314.596227) (xy 304.212112 -314.594246) (xy 304.260967 -314.600178) (xy 304.308238 -314.61387)
			(xy 304.3527 -314.634968) (xy 304.393203 -314.662924) (xy 304.428696 -314.697016) (xy 304.458261 -314.73636)
			(xy 304.481132 -314.779937) (xy 304.496716 -314.826618) (xy 304.504611 -314.875195) (xy 304.505106 -314.899802)
			(xy 304.843954 -314.899802) (xy 304.847914 -314.850748) (xy 304.859691 -314.802964) (xy 304.878982 -314.757688)
			(xy 304.905285 -314.716092) (xy 304.93792 -314.679255) (xy 304.976041 -314.64813) (xy 305.018662 -314.623523)
			(xy 305.064678 -314.606071) (xy 305.112897 -314.596227) (xy 305.162072 -314.594246) (xy 305.210927 -314.600178)
			(xy 305.258198 -314.61387) (xy 305.30266 -314.634968) (xy 305.343163 -314.662924) (xy 305.378656 -314.697016)
			(xy 305.408221 -314.73636) (xy 305.431092 -314.779937) (xy 305.446676 -314.826618) (xy 305.454571 -314.875195)
			(xy 305.455066 -314.899802) (xy 305.793914 -314.899802) (xy 305.797874 -314.850748) (xy 305.809651 -314.802964)
			(xy 305.828942 -314.757688) (xy 305.855245 -314.716092) (xy 305.88788 -314.679255) (xy 305.926001 -314.64813)
			(xy 305.968622 -314.623523) (xy 306.014638 -314.606071) (xy 306.062857 -314.596227) (xy 306.112032 -314.594246)
			(xy 306.160887 -314.600178) (xy 306.208158 -314.61387) (xy 306.25262 -314.634968) (xy 306.293123 -314.662924)
			(xy 306.328616 -314.697016) (xy 306.358181 -314.73636) (xy 306.381052 -314.779937) (xy 306.396636 -314.826618)
			(xy 306.404531 -314.875195) (xy 306.405026 -314.899802) (xy 306.744128 -314.899802) (xy 306.748088 -314.850748)
			(xy 306.759865 -314.802964) (xy 306.779156 -314.757688) (xy 306.805459 -314.716092) (xy 306.838094 -314.679255)
			(xy 306.876215 -314.64813) (xy 306.918836 -314.623523) (xy 306.964852 -314.606071) (xy 307.013071 -314.596227)
			(xy 307.062246 -314.594246) (xy 307.111101 -314.600178) (xy 307.158372 -314.61387) (xy 307.202834 -314.634968)
			(xy 307.243337 -314.662924) (xy 307.27883 -314.697016) (xy 307.308395 -314.73636) (xy 307.331266 -314.779937)
			(xy 307.34685 -314.826618) (xy 307.354745 -314.875195) (xy 307.35524 -314.899802) (xy 307.694088 -314.899802)
			(xy 307.698048 -314.850748) (xy 307.709825 -314.802964) (xy 307.729116 -314.757688) (xy 307.755419 -314.716092)
			(xy 307.788054 -314.679255) (xy 307.826175 -314.64813) (xy 307.868796 -314.623523) (xy 307.914812 -314.606071)
			(xy 307.963031 -314.596227) (xy 308.012206 -314.594246) (xy 308.061061 -314.600178) (xy 308.108332 -314.61387)
			(xy 308.152794 -314.634968) (xy 308.193297 -314.662924) (xy 308.22879 -314.697016) (xy 308.258355 -314.73636)
			(xy 308.281226 -314.779937) (xy 308.29681 -314.826618) (xy 308.304705 -314.875195) (xy 308.3052 -314.899802)
			(xy 308.644048 -314.899802) (xy 308.648008 -314.850748) (xy 308.659785 -314.802964) (xy 308.679076 -314.757688)
			(xy 308.705379 -314.716092) (xy 308.738014 -314.679255) (xy 308.776135 -314.64813) (xy 308.818756 -314.623523)
			(xy 308.864772 -314.606071) (xy 308.912991 -314.596227) (xy 308.962166 -314.594246) (xy 309.011021 -314.600178)
			(xy 309.058292 -314.61387) (xy 309.102754 -314.634968) (xy 309.143257 -314.662924) (xy 309.17875 -314.697016)
			(xy 309.208315 -314.73636) (xy 309.231186 -314.779937) (xy 309.24677 -314.826618) (xy 309.254665 -314.875195)
			(xy 309.25516 -314.899802) (xy 309.594008 -314.899802) (xy 309.597968 -314.850748) (xy 309.609745 -314.802964)
			(xy 309.629036 -314.757688) (xy 309.655339 -314.716092) (xy 309.687974 -314.679255) (xy 309.726095 -314.64813)
			(xy 309.768716 -314.623523) (xy 309.814732 -314.606071) (xy 309.862951 -314.596227) (xy 309.912126 -314.594246)
			(xy 309.960981 -314.600178) (xy 310.008252 -314.61387) (xy 310.052714 -314.634968) (xy 310.093217 -314.662924)
			(xy 310.12871 -314.697016) (xy 310.158275 -314.73636) (xy 310.181146 -314.779937) (xy 310.19673 -314.826618)
			(xy 310.204625 -314.875195) (xy 310.20512 -314.899802) (xy 310.543968 -314.899802) (xy 310.547928 -314.850748)
			(xy 310.559705 -314.802964) (xy 310.578996 -314.757688) (xy 310.605299 -314.716092) (xy 310.637934 -314.679255)
			(xy 310.676055 -314.64813) (xy 310.718676 -314.623523) (xy 310.764692 -314.606071) (xy 310.812911 -314.596227)
			(xy 310.862086 -314.594246) (xy 310.910941 -314.600178) (xy 310.958212 -314.61387) (xy 311.002674 -314.634968)
			(xy 311.043177 -314.662924) (xy 311.07867 -314.697016) (xy 311.108235 -314.73636) (xy 311.131106 -314.779937)
			(xy 311.14669 -314.826618) (xy 311.154585 -314.875195) (xy 311.15508 -314.899802) (xy 311.493928 -314.899802)
			(xy 311.497888 -314.850748) (xy 311.509665 -314.802964) (xy 311.528956 -314.757688) (xy 311.555259 -314.716092)
			(xy 311.587894 -314.679255) (xy 311.626015 -314.64813) (xy 311.668636 -314.623523) (xy 311.714652 -314.606071)
			(xy 311.762871 -314.596227) (xy 311.812046 -314.594246) (xy 311.860901 -314.600178) (xy 311.908172 -314.61387)
			(xy 311.952634 -314.634968) (xy 311.993137 -314.662924) (xy 312.02863 -314.697016) (xy 312.058195 -314.73636)
			(xy 312.081066 -314.779937) (xy 312.09665 -314.826618) (xy 312.104545 -314.875195) (xy 312.10504 -314.899802)
			(xy 312.443888 -314.899802) (xy 312.447848 -314.850748) (xy 312.459625 -314.802964) (xy 312.478916 -314.757688)
			(xy 312.505219 -314.716092) (xy 312.537854 -314.679255) (xy 312.575975 -314.64813) (xy 312.618596 -314.623523)
			(xy 312.664612 -314.606071) (xy 312.712831 -314.596227) (xy 312.762006 -314.594246) (xy 312.810861 -314.600178)
			(xy 312.858132 -314.61387) (xy 312.902594 -314.634968) (xy 312.943097 -314.662924) (xy 312.97859 -314.697016)
			(xy 313.008155 -314.73636) (xy 313.031026 -314.779937) (xy 313.04661 -314.826618) (xy 313.054505 -314.875195)
			(xy 313.055 -314.899802) (xy 313.054505 -314.924409) (xy 313.054326 -314.92551) (xy 313.373258 -314.92551)
			(xy 313.373258 -314.874094) (xy 313.381301 -314.823312) (xy 313.397189 -314.774413) (xy 313.420532 -314.728601)
			(xy 313.450753 -314.687005) (xy 313.487109 -314.650649) (xy 313.528705 -314.620428) (xy 313.574517 -314.597085)
			(xy 313.623416 -314.581197) (xy 313.674198 -314.573154) (xy 313.725614 -314.573154) (xy 313.776396 -314.581197)
			(xy 313.825295 -314.597085) (xy 313.871107 -314.620428) (xy 313.912703 -314.650649) (xy 313.949059 -314.687005)
			(xy 313.97928 -314.728601) (xy 314.002623 -314.774413) (xy 314.018511 -314.823312) (xy 314.026554 -314.874094)
			(xy 314.027058 -314.899802) (xy 314.026554 -314.92551) (xy 314.323218 -314.92551) (xy 314.323218 -314.874094)
			(xy 314.331261 -314.823312) (xy 314.347149 -314.774413) (xy 314.370492 -314.728601) (xy 314.400713 -314.687005)
			(xy 314.437069 -314.650649) (xy 314.478665 -314.620428) (xy 314.524477 -314.597085) (xy 314.573376 -314.581197)
			(xy 314.624158 -314.573154) (xy 314.675574 -314.573154) (xy 314.726356 -314.581197) (xy 314.775255 -314.597085)
			(xy 314.821067 -314.620428) (xy 314.862663 -314.650649) (xy 314.899019 -314.687005) (xy 314.92924 -314.728601)
			(xy 314.952583 -314.774413) (xy 314.968471 -314.823312) (xy 314.976514 -314.874094) (xy 314.977013 -314.899548)
			(xy 315.294276 -314.899548) (xy 315.298236 -314.850494) (xy 315.310013 -314.80271) (xy 315.329304 -314.757434)
			(xy 315.355607 -314.715838) (xy 315.388242 -314.679001) (xy 315.426363 -314.647876) (xy 315.468984 -314.623269)
			(xy 315.515 -314.605817) (xy 315.563219 -314.595973) (xy 315.612394 -314.593992) (xy 315.661249 -314.599924)
			(xy 315.70852 -314.613616) (xy 315.752982 -314.634714) (xy 315.793485 -314.66267) (xy 315.828978 -314.696762)
			(xy 315.858543 -314.736106) (xy 315.881414 -314.779683) (xy 315.896998 -314.826364) (xy 315.904893 -314.874941)
			(xy 315.905388 -314.899548) (xy 315.904893 -314.924155) (xy 315.896998 -314.972732) (xy 315.881414 -315.019413)
			(xy 315.858543 -315.06299) (xy 315.828978 -315.102334) (xy 315.793485 -315.136426) (xy 315.752982 -315.164382)
			(xy 315.70852 -315.18548) (xy 315.661249 -315.199172) (xy 315.612394 -315.205104) (xy 315.563219 -315.203123)
			(xy 315.515 -315.193279) (xy 315.468984 -315.175827) (xy 315.426363 -315.15122) (xy 315.388242 -315.120095)
			(xy 315.355607 -315.083258) (xy 315.329304 -315.041662) (xy 315.310013 -314.996386) (xy 315.298236 -314.948602)
			(xy 315.294276 -314.899548) (xy 314.977013 -314.899548) (xy 314.977018 -314.899802) (xy 314.976514 -314.92551)
			(xy 314.968471 -314.976292) (xy 314.952583 -315.025191) (xy 314.92924 -315.071003) (xy 314.899019 -315.112599)
			(xy 314.862663 -315.148955) (xy 314.821067 -315.179176) (xy 314.775255 -315.202519) (xy 314.726356 -315.218407)
			(xy 314.675574 -315.22645) (xy 314.624158 -315.22645) (xy 314.573376 -315.218407) (xy 314.524477 -315.202519)
			(xy 314.478665 -315.179176) (xy 314.437069 -315.148955) (xy 314.400713 -315.112599) (xy 314.370492 -315.071003)
			(xy 314.347149 -315.025191) (xy 314.331261 -314.976292) (xy 314.323218 -314.92551) (xy 314.026554 -314.92551)
			(xy 314.018511 -314.976292) (xy 314.002623 -315.025191) (xy 313.97928 -315.071003) (xy 313.949059 -315.112599)
			(xy 313.912703 -315.148955) (xy 313.871107 -315.179176) (xy 313.825295 -315.202519) (xy 313.776396 -315.218407)
			(xy 313.725614 -315.22645) (xy 313.674198 -315.22645) (xy 313.623416 -315.218407) (xy 313.574517 -315.202519)
			(xy 313.528705 -315.179176) (xy 313.487109 -315.148955) (xy 313.450753 -315.112599) (xy 313.420532 -315.071003)
			(xy 313.397189 -315.025191) (xy 313.381301 -314.976292) (xy 313.373258 -314.92551) (xy 313.054326 -314.92551)
			(xy 313.04661 -314.972986) (xy 313.031026 -315.019667) (xy 313.008155 -315.063244) (xy 312.97859 -315.102588)
			(xy 312.943097 -315.13668) (xy 312.902594 -315.164636) (xy 312.858132 -315.185734) (xy 312.810861 -315.199426)
			(xy 312.762006 -315.205358) (xy 312.712831 -315.203377) (xy 312.664612 -315.193533) (xy 312.618596 -315.176081)
			(xy 312.575975 -315.151474) (xy 312.537854 -315.120349) (xy 312.505219 -315.083512) (xy 312.478916 -315.041916)
			(xy 312.459625 -314.99664) (xy 312.447848 -314.948856) (xy 312.443888 -314.899802) (xy 312.10504 -314.899802)
			(xy 312.104545 -314.924409) (xy 312.09665 -314.972986) (xy 312.081066 -315.019667) (xy 312.058195 -315.063244)
			(xy 312.02863 -315.102588) (xy 311.993137 -315.13668) (xy 311.952634 -315.164636) (xy 311.908172 -315.185734)
			(xy 311.860901 -315.199426) (xy 311.812046 -315.205358) (xy 311.762871 -315.203377) (xy 311.714652 -315.193533)
			(xy 311.668636 -315.176081) (xy 311.626015 -315.151474) (xy 311.587894 -315.120349) (xy 311.555259 -315.083512)
			(xy 311.528956 -315.041916) (xy 311.509665 -314.99664) (xy 311.497888 -314.948856) (xy 311.493928 -314.899802)
			(xy 311.15508 -314.899802) (xy 311.154585 -314.924409) (xy 311.14669 -314.972986) (xy 311.131106 -315.019667)
			(xy 311.108235 -315.063244) (xy 311.07867 -315.102588) (xy 311.043177 -315.13668) (xy 311.002674 -315.164636)
			(xy 310.958212 -315.185734) (xy 310.910941 -315.199426) (xy 310.862086 -315.205358) (xy 310.812911 -315.203377)
			(xy 310.764692 -315.193533) (xy 310.718676 -315.176081) (xy 310.676055 -315.151474) (xy 310.637934 -315.120349)
			(xy 310.605299 -315.083512) (xy 310.578996 -315.041916) (xy 310.559705 -314.99664) (xy 310.547928 -314.948856)
			(xy 310.543968 -314.899802) (xy 310.20512 -314.899802) (xy 310.204625 -314.924409) (xy 310.19673 -314.972986)
			(xy 310.181146 -315.019667) (xy 310.158275 -315.063244) (xy 310.12871 -315.102588) (xy 310.093217 -315.13668)
			(xy 310.052714 -315.164636) (xy 310.008252 -315.185734) (xy 309.960981 -315.199426) (xy 309.912126 -315.205358)
			(xy 309.862951 -315.203377) (xy 309.814732 -315.193533) (xy 309.768716 -315.176081) (xy 309.726095 -315.151474)
			(xy 309.687974 -315.120349) (xy 309.655339 -315.083512) (xy 309.629036 -315.041916) (xy 309.609745 -314.99664)
			(xy 309.597968 -314.948856) (xy 309.594008 -314.899802) (xy 309.25516 -314.899802) (xy 309.254665 -314.924409)
			(xy 309.24677 -314.972986) (xy 309.231186 -315.019667) (xy 309.208315 -315.063244) (xy 309.17875 -315.102588)
			(xy 309.143257 -315.13668) (xy 309.102754 -315.164636) (xy 309.058292 -315.185734) (xy 309.011021 -315.199426)
			(xy 308.962166 -315.205358) (xy 308.912991 -315.203377) (xy 308.864772 -315.193533) (xy 308.818756 -315.176081)
			(xy 308.776135 -315.151474) (xy 308.738014 -315.120349) (xy 308.705379 -315.083512) (xy 308.679076 -315.041916)
			(xy 308.659785 -314.99664) (xy 308.648008 -314.948856) (xy 308.644048 -314.899802) (xy 308.3052 -314.899802)
			(xy 308.304705 -314.924409) (xy 308.29681 -314.972986) (xy 308.281226 -315.019667) (xy 308.258355 -315.063244)
			(xy 308.22879 -315.102588) (xy 308.193297 -315.13668) (xy 308.152794 -315.164636) (xy 308.108332 -315.185734)
			(xy 308.061061 -315.199426) (xy 308.012206 -315.205358) (xy 307.963031 -315.203377) (xy 307.914812 -315.193533)
			(xy 307.868796 -315.176081) (xy 307.826175 -315.151474) (xy 307.788054 -315.120349) (xy 307.755419 -315.083512)
			(xy 307.729116 -315.041916) (xy 307.709825 -314.99664) (xy 307.698048 -314.948856) (xy 307.694088 -314.899802)
			(xy 307.35524 -314.899802) (xy 307.354745 -314.924409) (xy 307.34685 -314.972986) (xy 307.331266 -315.019667)
			(xy 307.308395 -315.063244) (xy 307.27883 -315.102588) (xy 307.243337 -315.13668) (xy 307.202834 -315.164636)
			(xy 307.158372 -315.185734) (xy 307.111101 -315.199426) (xy 307.062246 -315.205358) (xy 307.013071 -315.203377)
			(xy 306.964852 -315.193533) (xy 306.918836 -315.176081) (xy 306.876215 -315.151474) (xy 306.838094 -315.120349)
			(xy 306.805459 -315.083512) (xy 306.779156 -315.041916) (xy 306.759865 -314.99664) (xy 306.748088 -314.948856)
			(xy 306.744128 -314.899802) (xy 306.405026 -314.899802) (xy 306.404531 -314.924409) (xy 306.396636 -314.972986)
			(xy 306.381052 -315.019667) (xy 306.358181 -315.063244) (xy 306.328616 -315.102588) (xy 306.293123 -315.13668)
			(xy 306.25262 -315.164636) (xy 306.208158 -315.185734) (xy 306.160887 -315.199426) (xy 306.112032 -315.205358)
			(xy 306.062857 -315.203377) (xy 306.014638 -315.193533) (xy 305.968622 -315.176081) (xy 305.926001 -315.151474)
			(xy 305.88788 -315.120349) (xy 305.855245 -315.083512) (xy 305.828942 -315.041916) (xy 305.809651 -314.99664)
			(xy 305.797874 -314.948856) (xy 305.793914 -314.899802) (xy 305.455066 -314.899802) (xy 305.454571 -314.924409)
			(xy 305.446676 -314.972986) (xy 305.431092 -315.019667) (xy 305.408221 -315.063244) (xy 305.378656 -315.102588)
			(xy 305.343163 -315.13668) (xy 305.30266 -315.164636) (xy 305.258198 -315.185734) (xy 305.210927 -315.199426)
			(xy 305.162072 -315.205358) (xy 305.112897 -315.203377) (xy 305.064678 -315.193533) (xy 305.018662 -315.176081)
			(xy 304.976041 -315.151474) (xy 304.93792 -315.120349) (xy 304.905285 -315.083512) (xy 304.878982 -315.041916)
			(xy 304.859691 -314.99664) (xy 304.847914 -314.948856) (xy 304.843954 -314.899802) (xy 304.505106 -314.899802)
			(xy 304.504611 -314.924409) (xy 304.496716 -314.972986) (xy 304.481132 -315.019667) (xy 304.458261 -315.063244)
			(xy 304.428696 -315.102588) (xy 304.393203 -315.13668) (xy 304.3527 -315.164636) (xy 304.308238 -315.185734)
			(xy 304.260967 -315.199426) (xy 304.212112 -315.205358) (xy 304.162937 -315.203377) (xy 304.114718 -315.193533)
			(xy 304.068702 -315.176081) (xy 304.026081 -315.151474) (xy 303.98796 -315.120349) (xy 303.955325 -315.083512)
			(xy 303.929022 -315.041916) (xy 303.909731 -314.99664) (xy 303.897954 -314.948856) (xy 303.893994 -314.899802)
			(xy 303.555146 -314.899802) (xy 303.554651 -314.924409) (xy 303.546756 -314.972986) (xy 303.531172 -315.019667)
			(xy 303.508301 -315.063244) (xy 303.478736 -315.102588) (xy 303.443243 -315.13668) (xy 303.40274 -315.164636)
			(xy 303.358278 -315.185734) (xy 303.311007 -315.199426) (xy 303.262152 -315.205358) (xy 303.212977 -315.203377)
			(xy 303.164758 -315.193533) (xy 303.118742 -315.176081) (xy 303.076121 -315.151474) (xy 303.038 -315.120349)
			(xy 303.005365 -315.083512) (xy 302.979062 -315.041916) (xy 302.959771 -314.99664) (xy 302.947994 -314.948856)
			(xy 302.944034 -314.899802) (xy 302.605186 -314.899802) (xy 302.604691 -314.924409) (xy 302.596796 -314.972986)
			(xy 302.581212 -315.019667) (xy 302.558341 -315.063244) (xy 302.528776 -315.102588) (xy 302.493283 -315.13668)
			(xy 302.45278 -315.164636) (xy 302.408318 -315.185734) (xy 302.361047 -315.199426) (xy 302.312192 -315.205358)
			(xy 302.263017 -315.203377) (xy 302.214798 -315.193533) (xy 302.168782 -315.176081) (xy 302.126161 -315.151474)
			(xy 302.08804 -315.120349) (xy 302.055405 -315.083512) (xy 302.029102 -315.041916) (xy 302.009811 -314.99664)
			(xy 301.998034 -314.948856) (xy 301.994074 -314.899802) (xy 301.655226 -314.899802) (xy 301.654731 -314.924409)
			(xy 301.646836 -314.972986) (xy 301.631252 -315.019667) (xy 301.608381 -315.063244) (xy 301.578816 -315.102588)
			(xy 301.543323 -315.13668) (xy 301.50282 -315.164636) (xy 301.458358 -315.185734) (xy 301.411087 -315.199426)
			(xy 301.362232 -315.205358) (xy 301.313057 -315.203377) (xy 301.264838 -315.193533) (xy 301.218822 -315.176081)
			(xy 301.176201 -315.151474) (xy 301.13808 -315.120349) (xy 301.105445 -315.083512) (xy 301.079142 -315.041916)
			(xy 301.059851 -314.99664) (xy 301.048074 -314.948856) (xy 301.044114 -314.899802) (xy 300.705012 -314.899802)
			(xy 300.704517 -314.924409) (xy 300.696622 -314.972986) (xy 300.681038 -315.019667) (xy 300.658167 -315.063244)
			(xy 300.628602 -315.102588) (xy 300.593109 -315.13668) (xy 300.552606 -315.164636) (xy 300.508144 -315.185734)
			(xy 300.460873 -315.199426) (xy 300.412018 -315.205358) (xy 300.362843 -315.203377) (xy 300.314624 -315.193533)
			(xy 300.268608 -315.176081) (xy 300.225987 -315.151474) (xy 300.187866 -315.120349) (xy 300.155231 -315.083512)
			(xy 300.128928 -315.041916) (xy 300.109637 -314.99664) (xy 300.09786 -314.948856) (xy 300.0939 -314.899802)
			(xy 299.755052 -314.899802) (xy 299.754557 -314.924409) (xy 299.746662 -314.972986) (xy 299.731078 -315.019667)
			(xy 299.708207 -315.063244) (xy 299.678642 -315.102588) (xy 299.643149 -315.13668) (xy 299.602646 -315.164636)
			(xy 299.558184 -315.185734) (xy 299.510913 -315.199426) (xy 299.462058 -315.205358) (xy 299.412883 -315.203377)
			(xy 299.364664 -315.193533) (xy 299.318648 -315.176081) (xy 299.276027 -315.151474) (xy 299.237906 -315.120349)
			(xy 299.205271 -315.083512) (xy 299.178968 -315.041916) (xy 299.159677 -314.99664) (xy 299.1479 -314.948856)
			(xy 299.14394 -314.899802) (xy 298.805092 -314.899802) (xy 298.804597 -314.924409) (xy 298.796702 -314.972986)
			(xy 298.781118 -315.019667) (xy 298.758247 -315.063244) (xy 298.728682 -315.102588) (xy 298.693189 -315.13668)
			(xy 298.652686 -315.164636) (xy 298.608224 -315.185734) (xy 298.560953 -315.199426) (xy 298.512098 -315.205358)
			(xy 298.462923 -315.203377) (xy 298.414704 -315.193533) (xy 298.368688 -315.176081) (xy 298.326067 -315.151474)
			(xy 298.287946 -315.120349) (xy 298.255311 -315.083512) (xy 298.229008 -315.041916) (xy 298.209717 -314.99664)
			(xy 298.19794 -314.948856) (xy 298.19398 -314.899802) (xy 297.855132 -314.899802) (xy 297.854637 -314.924409)
			(xy 297.846742 -314.972986) (xy 297.831158 -315.019667) (xy 297.808287 -315.063244) (xy 297.778722 -315.102588)
			(xy 297.743229 -315.13668) (xy 297.702726 -315.164636) (xy 297.658264 -315.185734) (xy 297.610993 -315.199426)
			(xy 297.562138 -315.205358) (xy 297.512963 -315.203377) (xy 297.464744 -315.193533) (xy 297.418728 -315.176081)
			(xy 297.376107 -315.151474) (xy 297.337986 -315.120349) (xy 297.305351 -315.083512) (xy 297.279048 -315.041916)
			(xy 297.259757 -314.99664) (xy 297.24798 -314.948856) (xy 297.24402 -314.899802) (xy 296.905172 -314.899802)
			(xy 296.904677 -314.924409) (xy 296.896782 -314.972986) (xy 296.881198 -315.019667) (xy 296.858327 -315.063244)
			(xy 296.828762 -315.102588) (xy 296.793269 -315.13668) (xy 296.752766 -315.164636) (xy 296.708304 -315.185734)
			(xy 296.661033 -315.199426) (xy 296.612178 -315.205358) (xy 296.563003 -315.203377) (xy 296.514784 -315.193533)
			(xy 296.468768 -315.176081) (xy 296.426147 -315.151474) (xy 296.388026 -315.120349) (xy 296.355391 -315.083512)
			(xy 296.329088 -315.041916) (xy 296.309797 -314.99664) (xy 296.29802 -314.948856) (xy 296.29406 -314.899802)
			(xy 295.955212 -314.899802) (xy 295.954717 -314.924409) (xy 295.946822 -314.972986) (xy 295.931238 -315.019667)
			(xy 295.908367 -315.063244) (xy 295.878802 -315.102588) (xy 295.843309 -315.13668) (xy 295.802806 -315.164636)
			(xy 295.758344 -315.185734) (xy 295.711073 -315.199426) (xy 295.662218 -315.205358) (xy 295.613043 -315.203377)
			(xy 295.564824 -315.193533) (xy 295.518808 -315.176081) (xy 295.476187 -315.151474) (xy 295.438066 -315.120349)
			(xy 295.405431 -315.083512) (xy 295.379128 -315.041916) (xy 295.359837 -314.99664) (xy 295.34806 -314.948856)
			(xy 295.3441 -314.899802) (xy 295.004998 -314.899802) (xy 295.004503 -314.924409) (xy 294.996608 -314.972986)
			(xy 294.981024 -315.019667) (xy 294.958153 -315.063244) (xy 294.928588 -315.102588) (xy 294.893095 -315.13668)
			(xy 294.852592 -315.164636) (xy 294.80813 -315.185734) (xy 294.760859 -315.199426) (xy 294.712004 -315.205358)
			(xy 294.662829 -315.203377) (xy 294.61461 -315.193533) (xy 294.568594 -315.176081) (xy 294.525973 -315.151474)
			(xy 294.487852 -315.120349) (xy 294.455217 -315.083512) (xy 294.428914 -315.041916) (xy 294.409623 -314.99664)
			(xy 294.397846 -314.948856) (xy 294.393886 -314.899802) (xy 294.055038 -314.899802) (xy 294.054543 -314.924409)
			(xy 294.046648 -314.972986) (xy 294.031064 -315.019667) (xy 294.008193 -315.063244) (xy 293.978628 -315.102588)
			(xy 293.943135 -315.13668) (xy 293.902632 -315.164636) (xy 293.85817 -315.185734) (xy 293.810899 -315.199426)
			(xy 293.762044 -315.205358) (xy 293.712869 -315.203377) (xy 293.66465 -315.193533) (xy 293.618634 -315.176081)
			(xy 293.576013 -315.151474) (xy 293.537892 -315.120349) (xy 293.505257 -315.083512) (xy 293.478954 -315.041916)
			(xy 293.459663 -314.99664) (xy 293.447886 -314.948856) (xy 293.443926 -314.899802) (xy 293.105078 -314.899802)
			(xy 293.104583 -314.924409) (xy 293.096688 -314.972986) (xy 293.081104 -315.019667) (xy 293.058233 -315.063244)
			(xy 293.028668 -315.102588) (xy 292.993175 -315.13668) (xy 292.952672 -315.164636) (xy 292.90821 -315.185734)
			(xy 292.860939 -315.199426) (xy 292.812084 -315.205358) (xy 292.762909 -315.203377) (xy 292.71469 -315.193533)
			(xy 292.668674 -315.176081) (xy 292.626053 -315.151474) (xy 292.587932 -315.120349) (xy 292.555297 -315.083512)
			(xy 292.528994 -315.041916) (xy 292.509703 -314.99664) (xy 292.497926 -314.948856) (xy 292.493966 -314.899802)
			(xy 292.155118 -314.899802) (xy 292.154623 -314.924409) (xy 292.146728 -314.972986) (xy 292.131144 -315.019667)
			(xy 292.108273 -315.063244) (xy 292.078708 -315.102588) (xy 292.043215 -315.13668) (xy 292.002712 -315.164636)
			(xy 291.95825 -315.185734) (xy 291.910979 -315.199426) (xy 291.862124 -315.205358) (xy 291.812949 -315.203377)
			(xy 291.76473 -315.193533) (xy 291.718714 -315.176081) (xy 291.676093 -315.151474) (xy 291.637972 -315.120349)
			(xy 291.605337 -315.083512) (xy 291.579034 -315.041916) (xy 291.559743 -314.99664) (xy 291.547966 -314.948856)
			(xy 291.544006 -314.899802) (xy 291.205158 -314.899802) (xy 291.204904 -314.910724) (xy 291.20465 -314.921392)
			(xy 291.21227 -314.94095) (xy 291.225986 -314.954666) (xy 291.232823 -314.962068) (xy 291.240536 -314.980666)
			(xy 291.240972 -314.990734) (xy 291.240972 -315.849762) (xy 291.544006 -315.849762) (xy 291.547966 -315.800708)
			(xy 291.559743 -315.752924) (xy 291.579034 -315.707648) (xy 291.605337 -315.666052) (xy 291.637972 -315.629215)
			(xy 291.676093 -315.59809) (xy 291.718714 -315.573483) (xy 291.76473 -315.556031) (xy 291.812949 -315.546187)
			(xy 291.862124 -315.544206) (xy 291.910979 -315.550138) (xy 291.95825 -315.56383) (xy 292.002712 -315.584928)
			(xy 292.043215 -315.612884) (xy 292.078708 -315.646976) (xy 292.108273 -315.68632) (xy 292.131144 -315.729897)
			(xy 292.146728 -315.776578) (xy 292.154623 -315.825155) (xy 292.155118 -315.849762) (xy 292.154623 -315.874369)
			(xy 292.154444 -315.87547) (xy 292.473122 -315.87547) (xy 292.473122 -315.824054) (xy 292.481165 -315.773272)
			(xy 292.497053 -315.724373) (xy 292.520396 -315.678561) (xy 292.550617 -315.636965) (xy 292.586973 -315.600609)
			(xy 292.628569 -315.570388) (xy 292.674381 -315.547045) (xy 292.72328 -315.531157) (xy 292.774062 -315.523114)
			(xy 292.825478 -315.523114) (xy 292.87626 -315.531157) (xy 292.925159 -315.547045) (xy 292.970971 -315.570388)
			(xy 293.012567 -315.600609) (xy 293.048923 -315.636965) (xy 293.079144 -315.678561) (xy 293.102487 -315.724373)
			(xy 293.118375 -315.773272) (xy 293.126418 -315.824054) (xy 293.126922 -315.849762) (xy 293.443926 -315.849762)
			(xy 293.447886 -315.800708) (xy 293.459663 -315.752924) (xy 293.478954 -315.707648) (xy 293.505257 -315.666052)
			(xy 293.537892 -315.629215) (xy 293.576013 -315.59809) (xy 293.618634 -315.573483) (xy 293.66465 -315.556031)
			(xy 293.712869 -315.546187) (xy 293.762044 -315.544206) (xy 293.810899 -315.550138) (xy 293.85817 -315.56383)
			(xy 293.902632 -315.584928) (xy 293.943135 -315.612884) (xy 293.978628 -315.646976) (xy 294.008193 -315.68632)
			(xy 294.031064 -315.729897) (xy 294.046648 -315.776578) (xy 294.054543 -315.825155) (xy 294.055038 -315.849762)
			(xy 294.054543 -315.874369) (xy 294.054364 -315.87547) (xy 294.373042 -315.87547) (xy 294.373042 -315.824054)
			(xy 294.381085 -315.773272) (xy 294.396973 -315.724373) (xy 294.420316 -315.678561) (xy 294.450537 -315.636965)
			(xy 294.486893 -315.600609) (xy 294.528489 -315.570388) (xy 294.574301 -315.547045) (xy 294.6232 -315.531157)
			(xy 294.673982 -315.523114) (xy 294.725398 -315.523114) (xy 294.77618 -315.531157) (xy 294.825079 -315.547045)
			(xy 294.870891 -315.570388) (xy 294.912487 -315.600609) (xy 294.948843 -315.636965) (xy 294.979064 -315.678561)
			(xy 295.002407 -315.724373) (xy 295.018295 -315.773272) (xy 295.026338 -315.824054) (xy 295.026842 -315.849762)
			(xy 295.3441 -315.849762) (xy 295.34806 -315.800708) (xy 295.359837 -315.752924) (xy 295.379128 -315.707648)
			(xy 295.405431 -315.666052) (xy 295.438066 -315.629215) (xy 295.476187 -315.59809) (xy 295.518808 -315.573483)
			(xy 295.564824 -315.556031) (xy 295.613043 -315.546187) (xy 295.662218 -315.544206) (xy 295.711073 -315.550138)
			(xy 295.758344 -315.56383) (xy 295.802806 -315.584928) (xy 295.843309 -315.612884) (xy 295.878802 -315.646976)
			(xy 295.908367 -315.68632) (xy 295.931238 -315.729897) (xy 295.946822 -315.776578) (xy 295.954717 -315.825155)
			(xy 295.955212 -315.849762) (xy 295.954717 -315.874369) (xy 295.954538 -315.87547) (xy 296.273216 -315.87547)
			(xy 296.273216 -315.824054) (xy 296.281259 -315.773272) (xy 296.297147 -315.724373) (xy 296.32049 -315.678561)
			(xy 296.350711 -315.636965) (xy 296.387067 -315.600609) (xy 296.428663 -315.570388) (xy 296.474475 -315.547045)
			(xy 296.523374 -315.531157) (xy 296.574156 -315.523114) (xy 296.625572 -315.523114) (xy 296.676354 -315.531157)
			(xy 296.725253 -315.547045) (xy 296.771065 -315.570388) (xy 296.812661 -315.600609) (xy 296.849017 -315.636965)
			(xy 296.879238 -315.678561) (xy 296.902581 -315.724373) (xy 296.918469 -315.773272) (xy 296.926512 -315.824054)
			(xy 296.927016 -315.849762) (xy 297.24402 -315.849762) (xy 297.24798 -315.800708) (xy 297.259757 -315.752924)
			(xy 297.279048 -315.707648) (xy 297.305351 -315.666052) (xy 297.337986 -315.629215) (xy 297.376107 -315.59809)
			(xy 297.418728 -315.573483) (xy 297.464744 -315.556031) (xy 297.512963 -315.546187) (xy 297.562138 -315.544206)
			(xy 297.610993 -315.550138) (xy 297.658264 -315.56383) (xy 297.702726 -315.584928) (xy 297.743229 -315.612884)
			(xy 297.778722 -315.646976) (xy 297.808287 -315.68632) (xy 297.831158 -315.729897) (xy 297.846742 -315.776578)
			(xy 297.854637 -315.825155) (xy 297.855132 -315.849762) (xy 297.854637 -315.874369) (xy 297.854458 -315.87547)
			(xy 298.173136 -315.87547) (xy 298.173136 -315.824054) (xy 298.181179 -315.773272) (xy 298.197067 -315.724373)
			(xy 298.22041 -315.678561) (xy 298.250631 -315.636965) (xy 298.286987 -315.600609) (xy 298.328583 -315.570388)
			(xy 298.374395 -315.547045) (xy 298.423294 -315.531157) (xy 298.474076 -315.523114) (xy 298.525492 -315.523114)
			(xy 298.576274 -315.531157) (xy 298.625173 -315.547045) (xy 298.670985 -315.570388) (xy 298.712581 -315.600609)
			(xy 298.748937 -315.636965) (xy 298.779158 -315.678561) (xy 298.802501 -315.724373) (xy 298.818389 -315.773272)
			(xy 298.826432 -315.824054) (xy 298.826936 -315.849762) (xy 299.14394 -315.849762) (xy 299.1479 -315.800708)
			(xy 299.159677 -315.752924) (xy 299.178968 -315.707648) (xy 299.205271 -315.666052) (xy 299.237906 -315.629215)
			(xy 299.276027 -315.59809) (xy 299.318648 -315.573483) (xy 299.364664 -315.556031) (xy 299.412883 -315.546187)
			(xy 299.462058 -315.544206) (xy 299.510913 -315.550138) (xy 299.558184 -315.56383) (xy 299.602646 -315.584928)
			(xy 299.643149 -315.612884) (xy 299.678642 -315.646976) (xy 299.708207 -315.68632) (xy 299.731078 -315.729897)
			(xy 299.746662 -315.776578) (xy 299.754557 -315.825155) (xy 299.755052 -315.849762) (xy 299.754557 -315.874369)
			(xy 299.754378 -315.87547) (xy 300.073056 -315.87547) (xy 300.073056 -315.824054) (xy 300.081099 -315.773272)
			(xy 300.096987 -315.724373) (xy 300.12033 -315.678561) (xy 300.150551 -315.636965) (xy 300.186907 -315.600609)
			(xy 300.228503 -315.570388) (xy 300.274315 -315.547045) (xy 300.323214 -315.531157) (xy 300.373996 -315.523114)
			(xy 300.425412 -315.523114) (xy 300.476194 -315.531157) (xy 300.525093 -315.547045) (xy 300.570905 -315.570388)
			(xy 300.612501 -315.600609) (xy 300.648857 -315.636965) (xy 300.679078 -315.678561) (xy 300.702421 -315.724373)
			(xy 300.718309 -315.773272) (xy 300.726352 -315.824054) (xy 300.726856 -315.849762) (xy 301.044114 -315.849762)
			(xy 301.048074 -315.800708) (xy 301.059851 -315.752924) (xy 301.079142 -315.707648) (xy 301.105445 -315.666052)
			(xy 301.13808 -315.629215) (xy 301.176201 -315.59809) (xy 301.218822 -315.573483) (xy 301.264838 -315.556031)
			(xy 301.313057 -315.546187) (xy 301.362232 -315.544206) (xy 301.411087 -315.550138) (xy 301.458358 -315.56383)
			(xy 301.50282 -315.584928) (xy 301.543323 -315.612884) (xy 301.578816 -315.646976) (xy 301.608381 -315.68632)
			(xy 301.631252 -315.729897) (xy 301.646836 -315.776578) (xy 301.654731 -315.825155) (xy 301.655226 -315.849762)
			(xy 301.654731 -315.874369) (xy 301.654552 -315.87547) (xy 301.97323 -315.87547) (xy 301.97323 -315.824054)
			(xy 301.981273 -315.773272) (xy 301.997161 -315.724373) (xy 302.020504 -315.678561) (xy 302.050725 -315.636965)
			(xy 302.087081 -315.600609) (xy 302.128677 -315.570388) (xy 302.174489 -315.547045) (xy 302.223388 -315.531157)
			(xy 302.27417 -315.523114) (xy 302.325586 -315.523114) (xy 302.376368 -315.531157) (xy 302.425267 -315.547045)
			(xy 302.471079 -315.570388) (xy 302.512675 -315.600609) (xy 302.549031 -315.636965) (xy 302.579252 -315.678561)
			(xy 302.602595 -315.724373) (xy 302.618483 -315.773272) (xy 302.626526 -315.824054) (xy 302.62703 -315.849762)
			(xy 302.944034 -315.849762) (xy 302.947994 -315.800708) (xy 302.959771 -315.752924) (xy 302.979062 -315.707648)
			(xy 303.005365 -315.666052) (xy 303.038 -315.629215) (xy 303.076121 -315.59809) (xy 303.118742 -315.573483)
			(xy 303.164758 -315.556031) (xy 303.212977 -315.546187) (xy 303.262152 -315.544206) (xy 303.311007 -315.550138)
			(xy 303.358278 -315.56383) (xy 303.40274 -315.584928) (xy 303.443243 -315.612884) (xy 303.478736 -315.646976)
			(xy 303.508301 -315.68632) (xy 303.531172 -315.729897) (xy 303.546756 -315.776578) (xy 303.554651 -315.825155)
			(xy 303.555146 -315.849762) (xy 303.554651 -315.874369) (xy 303.554472 -315.87547) (xy 303.87315 -315.87547)
			(xy 303.87315 -315.824054) (xy 303.881193 -315.773272) (xy 303.897081 -315.724373) (xy 303.920424 -315.678561)
			(xy 303.950645 -315.636965) (xy 303.987001 -315.600609) (xy 304.028597 -315.570388) (xy 304.074409 -315.547045)
			(xy 304.123308 -315.531157) (xy 304.17409 -315.523114) (xy 304.225506 -315.523114) (xy 304.276288 -315.531157)
			(xy 304.325187 -315.547045) (xy 304.370999 -315.570388) (xy 304.412595 -315.600609) (xy 304.448951 -315.636965)
			(xy 304.479172 -315.678561) (xy 304.502515 -315.724373) (xy 304.518403 -315.773272) (xy 304.526446 -315.824054)
			(xy 304.52695 -315.849762) (xy 304.843954 -315.849762) (xy 304.847914 -315.800708) (xy 304.859691 -315.752924)
			(xy 304.878982 -315.707648) (xy 304.905285 -315.666052) (xy 304.93792 -315.629215) (xy 304.976041 -315.59809)
			(xy 305.018662 -315.573483) (xy 305.064678 -315.556031) (xy 305.112897 -315.546187) (xy 305.162072 -315.544206)
			(xy 305.210927 -315.550138) (xy 305.258198 -315.56383) (xy 305.30266 -315.584928) (xy 305.343163 -315.612884)
			(xy 305.378656 -315.646976) (xy 305.408221 -315.68632) (xy 305.431092 -315.729897) (xy 305.446676 -315.776578)
			(xy 305.454571 -315.825155) (xy 305.455066 -315.849762) (xy 305.793914 -315.849762) (xy 305.797874 -315.800708)
			(xy 305.809651 -315.752924) (xy 305.828942 -315.707648) (xy 305.855245 -315.666052) (xy 305.88788 -315.629215)
			(xy 305.926001 -315.59809) (xy 305.968622 -315.573483) (xy 306.014638 -315.556031) (xy 306.062857 -315.546187)
			(xy 306.112032 -315.544206) (xy 306.160887 -315.550138) (xy 306.208158 -315.56383) (xy 306.25262 -315.584928)
			(xy 306.293123 -315.612884) (xy 306.328616 -315.646976) (xy 306.358181 -315.68632) (xy 306.381052 -315.729897)
			(xy 306.396636 -315.776578) (xy 306.404531 -315.825155) (xy 306.405026 -315.849762) (xy 306.744128 -315.849762)
			(xy 306.748088 -315.800708) (xy 306.759865 -315.752924) (xy 306.779156 -315.707648) (xy 306.805459 -315.666052)
			(xy 306.838094 -315.629215) (xy 306.876215 -315.59809) (xy 306.918836 -315.573483) (xy 306.964852 -315.556031)
			(xy 307.013071 -315.546187) (xy 307.062246 -315.544206) (xy 307.111101 -315.550138) (xy 307.158372 -315.56383)
			(xy 307.202834 -315.584928) (xy 307.243337 -315.612884) (xy 307.27883 -315.646976) (xy 307.308395 -315.68632)
			(xy 307.331266 -315.729897) (xy 307.34685 -315.776578) (xy 307.354745 -315.825155) (xy 307.35524 -315.849762)
			(xy 307.694088 -315.849762) (xy 307.698048 -315.800708) (xy 307.709825 -315.752924) (xy 307.729116 -315.707648)
			(xy 307.755419 -315.666052) (xy 307.788054 -315.629215) (xy 307.826175 -315.59809) (xy 307.868796 -315.573483)
			(xy 307.914812 -315.556031) (xy 307.963031 -315.546187) (xy 308.012206 -315.544206) (xy 308.061061 -315.550138)
			(xy 308.108332 -315.56383) (xy 308.152794 -315.584928) (xy 308.193297 -315.612884) (xy 308.22879 -315.646976)
			(xy 308.258355 -315.68632) (xy 308.281226 -315.729897) (xy 308.29681 -315.776578) (xy 308.304705 -315.825155)
			(xy 308.3052 -315.849762) (xy 308.644048 -315.849762) (xy 308.648008 -315.800708) (xy 308.659785 -315.752924)
			(xy 308.679076 -315.707648) (xy 308.705379 -315.666052) (xy 308.738014 -315.629215) (xy 308.776135 -315.59809)
			(xy 308.818756 -315.573483) (xy 308.864772 -315.556031) (xy 308.912991 -315.546187) (xy 308.962166 -315.544206)
			(xy 309.011021 -315.550138) (xy 309.058292 -315.56383) (xy 309.102754 -315.584928) (xy 309.143257 -315.612884)
			(xy 309.17875 -315.646976) (xy 309.208315 -315.68632) (xy 309.231186 -315.729897) (xy 309.24677 -315.776578)
			(xy 309.254665 -315.825155) (xy 309.25516 -315.849762) (xy 309.594008 -315.849762) (xy 309.597968 -315.800708)
			(xy 309.609745 -315.752924) (xy 309.629036 -315.707648) (xy 309.655339 -315.666052) (xy 309.687974 -315.629215)
			(xy 309.726095 -315.59809) (xy 309.768716 -315.573483) (xy 309.814732 -315.556031) (xy 309.862951 -315.546187)
			(xy 309.912126 -315.544206) (xy 309.960981 -315.550138) (xy 310.008252 -315.56383) (xy 310.052714 -315.584928)
			(xy 310.093217 -315.612884) (xy 310.12871 -315.646976) (xy 310.158275 -315.68632) (xy 310.181146 -315.729897)
			(xy 310.19673 -315.776578) (xy 310.204625 -315.825155) (xy 310.20512 -315.849762) (xy 310.543968 -315.849762)
			(xy 310.547928 -315.800708) (xy 310.559705 -315.752924) (xy 310.578996 -315.707648) (xy 310.605299 -315.666052)
			(xy 310.637934 -315.629215) (xy 310.676055 -315.59809) (xy 310.718676 -315.573483) (xy 310.764692 -315.556031)
			(xy 310.812911 -315.546187) (xy 310.862086 -315.544206) (xy 310.910941 -315.550138) (xy 310.958212 -315.56383)
			(xy 311.002674 -315.584928) (xy 311.043177 -315.612884) (xy 311.07867 -315.646976) (xy 311.108235 -315.68632)
			(xy 311.131106 -315.729897) (xy 311.14669 -315.776578) (xy 311.154585 -315.825155) (xy 311.15508 -315.849762)
			(xy 311.493928 -315.849762) (xy 311.497888 -315.800708) (xy 311.509665 -315.752924) (xy 311.528956 -315.707648)
			(xy 311.555259 -315.666052) (xy 311.587894 -315.629215) (xy 311.626015 -315.59809) (xy 311.668636 -315.573483)
			(xy 311.714652 -315.556031) (xy 311.762871 -315.546187) (xy 311.812046 -315.544206) (xy 311.860901 -315.550138)
			(xy 311.908172 -315.56383) (xy 311.952634 -315.584928) (xy 311.993137 -315.612884) (xy 312.02863 -315.646976)
			(xy 312.058195 -315.68632) (xy 312.081066 -315.729897) (xy 312.09665 -315.776578) (xy 312.104545 -315.825155)
			(xy 312.10504 -315.849762) (xy 312.443888 -315.849762) (xy 312.447848 -315.800708) (xy 312.459625 -315.752924)
			(xy 312.478916 -315.707648) (xy 312.505219 -315.666052) (xy 312.537854 -315.629215) (xy 312.575975 -315.59809)
			(xy 312.618596 -315.573483) (xy 312.664612 -315.556031) (xy 312.712831 -315.546187) (xy 312.762006 -315.544206)
			(xy 312.810861 -315.550138) (xy 312.858132 -315.56383) (xy 312.902594 -315.584928) (xy 312.943097 -315.612884)
			(xy 312.97859 -315.646976) (xy 313.008155 -315.68632) (xy 313.031026 -315.729897) (xy 313.04661 -315.776578)
			(xy 313.054505 -315.825155) (xy 313.055 -315.849762) (xy 313.394102 -315.849762) (xy 313.398062 -315.800708)
			(xy 313.409839 -315.752924) (xy 313.42913 -315.707648) (xy 313.455433 -315.666052) (xy 313.488068 -315.629215)
			(xy 313.526189 -315.59809) (xy 313.56881 -315.573483) (xy 313.614826 -315.556031) (xy 313.663045 -315.546187)
			(xy 313.71222 -315.544206) (xy 313.761075 -315.550138) (xy 313.808346 -315.56383) (xy 313.852808 -315.584928)
			(xy 313.893311 -315.612884) (xy 313.928804 -315.646976) (xy 313.958369 -315.68632) (xy 313.98124 -315.729897)
			(xy 313.996824 -315.776578) (xy 314.004719 -315.825155) (xy 314.005214 -315.849762) (xy 314.344062 -315.849762)
			(xy 314.348022 -315.800708) (xy 314.359799 -315.752924) (xy 314.37909 -315.707648) (xy 314.405393 -315.666052)
			(xy 314.438028 -315.629215) (xy 314.476149 -315.59809) (xy 314.51877 -315.573483) (xy 314.564786 -315.556031)
			(xy 314.613005 -315.546187) (xy 314.66218 -315.544206) (xy 314.711035 -315.550138) (xy 314.758306 -315.56383)
			(xy 314.802768 -315.584928) (xy 314.843271 -315.612884) (xy 314.878764 -315.646976) (xy 314.908329 -315.68632)
			(xy 314.9312 -315.729897) (xy 314.946784 -315.776578) (xy 314.954679 -315.825155) (xy 314.955174 -315.849762)
			(xy 314.954679 -315.874369) (xy 314.946784 -315.922946) (xy 314.9312 -315.969627) (xy 314.908329 -316.013204)
			(xy 314.878764 -316.052548) (xy 314.843271 -316.08664) (xy 314.802768 -316.114596) (xy 314.758306 -316.135694)
			(xy 314.711035 -316.149386) (xy 314.66218 -316.155318) (xy 314.613005 -316.153337) (xy 314.564786 -316.143493)
			(xy 314.51877 -316.126041) (xy 314.476149 -316.101434) (xy 314.438028 -316.070309) (xy 314.405393 -316.033472)
			(xy 314.37909 -315.991876) (xy 314.359799 -315.9466) (xy 314.348022 -315.898816) (xy 314.344062 -315.849762)
			(xy 314.005214 -315.849762) (xy 314.004719 -315.874369) (xy 313.996824 -315.922946) (xy 313.98124 -315.969627)
			(xy 313.958369 -316.013204) (xy 313.928804 -316.052548) (xy 313.893311 -316.08664) (xy 313.852808 -316.114596)
			(xy 313.808346 -316.135694) (xy 313.761075 -316.149386) (xy 313.71222 -316.155318) (xy 313.663045 -316.153337)
			(xy 313.614826 -316.143493) (xy 313.56881 -316.126041) (xy 313.526189 -316.101434) (xy 313.488068 -316.070309)
			(xy 313.455433 -316.033472) (xy 313.42913 -315.991876) (xy 313.409839 -315.9466) (xy 313.398062 -315.898816)
			(xy 313.394102 -315.849762) (xy 313.055 -315.849762) (xy 313.054505 -315.874369) (xy 313.04661 -315.922946)
			(xy 313.031026 -315.969627) (xy 313.008155 -316.013204) (xy 312.97859 -316.052548) (xy 312.943097 -316.08664)
			(xy 312.902594 -316.114596) (xy 312.858132 -316.135694) (xy 312.810861 -316.149386) (xy 312.762006 -316.155318)
			(xy 312.712831 -316.153337) (xy 312.664612 -316.143493) (xy 312.618596 -316.126041) (xy 312.575975 -316.101434)
			(xy 312.537854 -316.070309) (xy 312.505219 -316.033472) (xy 312.478916 -315.991876) (xy 312.459625 -315.9466)
			(xy 312.447848 -315.898816) (xy 312.443888 -315.849762) (xy 312.10504 -315.849762) (xy 312.104545 -315.874369)
			(xy 312.09665 -315.922946) (xy 312.081066 -315.969627) (xy 312.058195 -316.013204) (xy 312.02863 -316.052548)
			(xy 311.993137 -316.08664) (xy 311.952634 -316.114596) (xy 311.908172 -316.135694) (xy 311.860901 -316.149386)
			(xy 311.812046 -316.155318) (xy 311.762871 -316.153337) (xy 311.714652 -316.143493) (xy 311.668636 -316.126041)
			(xy 311.626015 -316.101434) (xy 311.587894 -316.070309) (xy 311.555259 -316.033472) (xy 311.528956 -315.991876)
			(xy 311.509665 -315.9466) (xy 311.497888 -315.898816) (xy 311.493928 -315.849762) (xy 311.15508 -315.849762)
			(xy 311.154585 -315.874369) (xy 311.14669 -315.922946) (xy 311.131106 -315.969627) (xy 311.108235 -316.013204)
			(xy 311.07867 -316.052548) (xy 311.043177 -316.08664) (xy 311.002674 -316.114596) (xy 310.958212 -316.135694)
			(xy 310.910941 -316.149386) (xy 310.862086 -316.155318) (xy 310.812911 -316.153337) (xy 310.764692 -316.143493)
			(xy 310.718676 -316.126041) (xy 310.676055 -316.101434) (xy 310.637934 -316.070309) (xy 310.605299 -316.033472)
			(xy 310.578996 -315.991876) (xy 310.559705 -315.9466) (xy 310.547928 -315.898816) (xy 310.543968 -315.849762)
			(xy 310.20512 -315.849762) (xy 310.204625 -315.874369) (xy 310.19673 -315.922946) (xy 310.181146 -315.969627)
			(xy 310.158275 -316.013204) (xy 310.12871 -316.052548) (xy 310.093217 -316.08664) (xy 310.052714 -316.114596)
			(xy 310.008252 -316.135694) (xy 309.960981 -316.149386) (xy 309.912126 -316.155318) (xy 309.862951 -316.153337)
			(xy 309.814732 -316.143493) (xy 309.768716 -316.126041) (xy 309.726095 -316.101434) (xy 309.687974 -316.070309)
			(xy 309.655339 -316.033472) (xy 309.629036 -315.991876) (xy 309.609745 -315.9466) (xy 309.597968 -315.898816)
			(xy 309.594008 -315.849762) (xy 309.25516 -315.849762) (xy 309.254665 -315.874369) (xy 309.24677 -315.922946)
			(xy 309.231186 -315.969627) (xy 309.208315 -316.013204) (xy 309.17875 -316.052548) (xy 309.143257 -316.08664)
			(xy 309.102754 -316.114596) (xy 309.058292 -316.135694) (xy 309.011021 -316.149386) (xy 308.962166 -316.155318)
			(xy 308.912991 -316.153337) (xy 308.864772 -316.143493) (xy 308.818756 -316.126041) (xy 308.776135 -316.101434)
			(xy 308.738014 -316.070309) (xy 308.705379 -316.033472) (xy 308.679076 -315.991876) (xy 308.659785 -315.9466)
			(xy 308.648008 -315.898816) (xy 308.644048 -315.849762) (xy 308.3052 -315.849762) (xy 308.304705 -315.874369)
			(xy 308.29681 -315.922946) (xy 308.281226 -315.969627) (xy 308.258355 -316.013204) (xy 308.22879 -316.052548)
			(xy 308.193297 -316.08664) (xy 308.152794 -316.114596) (xy 308.108332 -316.135694) (xy 308.061061 -316.149386)
			(xy 308.012206 -316.155318) (xy 307.963031 -316.153337) (xy 307.914812 -316.143493) (xy 307.868796 -316.126041)
			(xy 307.826175 -316.101434) (xy 307.788054 -316.070309) (xy 307.755419 -316.033472) (xy 307.729116 -315.991876)
			(xy 307.709825 -315.9466) (xy 307.698048 -315.898816) (xy 307.694088 -315.849762) (xy 307.35524 -315.849762)
			(xy 307.354745 -315.874369) (xy 307.34685 -315.922946) (xy 307.331266 -315.969627) (xy 307.308395 -316.013204)
			(xy 307.27883 -316.052548) (xy 307.243337 -316.08664) (xy 307.202834 -316.114596) (xy 307.158372 -316.135694)
			(xy 307.111101 -316.149386) (xy 307.062246 -316.155318) (xy 307.013071 -316.153337) (xy 306.964852 -316.143493)
			(xy 306.918836 -316.126041) (xy 306.876215 -316.101434) (xy 306.838094 -316.070309) (xy 306.805459 -316.033472)
			(xy 306.779156 -315.991876) (xy 306.759865 -315.9466) (xy 306.748088 -315.898816) (xy 306.744128 -315.849762)
			(xy 306.405026 -315.849762) (xy 306.404531 -315.874369) (xy 306.396636 -315.922946) (xy 306.381052 -315.969627)
			(xy 306.358181 -316.013204) (xy 306.328616 -316.052548) (xy 306.293123 -316.08664) (xy 306.25262 -316.114596)
			(xy 306.208158 -316.135694) (xy 306.160887 -316.149386) (xy 306.112032 -316.155318) (xy 306.062857 -316.153337)
			(xy 306.014638 -316.143493) (xy 305.968622 -316.126041) (xy 305.926001 -316.101434) (xy 305.88788 -316.070309)
			(xy 305.855245 -316.033472) (xy 305.828942 -315.991876) (xy 305.809651 -315.9466) (xy 305.797874 -315.898816)
			(xy 305.793914 -315.849762) (xy 305.455066 -315.849762) (xy 305.454571 -315.874369) (xy 305.446676 -315.922946)
			(xy 305.431092 -315.969627) (xy 305.408221 -316.013204) (xy 305.378656 -316.052548) (xy 305.343163 -316.08664)
			(xy 305.30266 -316.114596) (xy 305.258198 -316.135694) (xy 305.210927 -316.149386) (xy 305.162072 -316.155318)
			(xy 305.112897 -316.153337) (xy 305.064678 -316.143493) (xy 305.018662 -316.126041) (xy 304.976041 -316.101434)
			(xy 304.93792 -316.070309) (xy 304.905285 -316.033472) (xy 304.878982 -315.991876) (xy 304.859691 -315.9466)
			(xy 304.847914 -315.898816) (xy 304.843954 -315.849762) (xy 304.52695 -315.849762) (xy 304.526446 -315.87547)
			(xy 304.518403 -315.926252) (xy 304.502515 -315.975151) (xy 304.479172 -316.020963) (xy 304.448951 -316.062559)
			(xy 304.412595 -316.098915) (xy 304.370999 -316.129136) (xy 304.325187 -316.152479) (xy 304.276288 -316.168367)
			(xy 304.225506 -316.17641) (xy 304.17409 -316.17641) (xy 304.123308 -316.168367) (xy 304.074409 -316.152479)
			(xy 304.028597 -316.129136) (xy 303.987001 -316.098915) (xy 303.950645 -316.062559) (xy 303.920424 -316.020963)
			(xy 303.897081 -315.975151) (xy 303.881193 -315.926252) (xy 303.87315 -315.87547) (xy 303.554472 -315.87547)
			(xy 303.546756 -315.922946) (xy 303.531172 -315.969627) (xy 303.508301 -316.013204) (xy 303.478736 -316.052548)
			(xy 303.443243 -316.08664) (xy 303.40274 -316.114596) (xy 303.358278 -316.135694) (xy 303.311007 -316.149386)
			(xy 303.262152 -316.155318) (xy 303.212977 -316.153337) (xy 303.164758 -316.143493) (xy 303.118742 -316.126041)
			(xy 303.076121 -316.101434) (xy 303.038 -316.070309) (xy 303.005365 -316.033472) (xy 302.979062 -315.991876)
			(xy 302.959771 -315.9466) (xy 302.947994 -315.898816) (xy 302.944034 -315.849762) (xy 302.62703 -315.849762)
			(xy 302.626526 -315.87547) (xy 302.618483 -315.926252) (xy 302.602595 -315.975151) (xy 302.579252 -316.020963)
			(xy 302.549031 -316.062559) (xy 302.512675 -316.098915) (xy 302.471079 -316.129136) (xy 302.425267 -316.152479)
			(xy 302.376368 -316.168367) (xy 302.325586 -316.17641) (xy 302.27417 -316.17641) (xy 302.223388 -316.168367)
			(xy 302.174489 -316.152479) (xy 302.128677 -316.129136) (xy 302.087081 -316.098915) (xy 302.050725 -316.062559)
			(xy 302.020504 -316.020963) (xy 301.997161 -315.975151) (xy 301.981273 -315.926252) (xy 301.97323 -315.87547)
			(xy 301.654552 -315.87547) (xy 301.646836 -315.922946) (xy 301.631252 -315.969627) (xy 301.608381 -316.013204)
			(xy 301.578816 -316.052548) (xy 301.543323 -316.08664) (xy 301.50282 -316.114596) (xy 301.458358 -316.135694)
			(xy 301.411087 -316.149386) (xy 301.362232 -316.155318) (xy 301.313057 -316.153337) (xy 301.264838 -316.143493)
			(xy 301.218822 -316.126041) (xy 301.176201 -316.101434) (xy 301.13808 -316.070309) (xy 301.105445 -316.033472)
			(xy 301.079142 -315.991876) (xy 301.059851 -315.9466) (xy 301.048074 -315.898816) (xy 301.044114 -315.849762)
			(xy 300.726856 -315.849762) (xy 300.726352 -315.87547) (xy 300.718309 -315.926252) (xy 300.702421 -315.975151)
			(xy 300.679078 -316.020963) (xy 300.648857 -316.062559) (xy 300.612501 -316.098915) (xy 300.570905 -316.129136)
			(xy 300.525093 -316.152479) (xy 300.476194 -316.168367) (xy 300.425412 -316.17641) (xy 300.373996 -316.17641)
			(xy 300.323214 -316.168367) (xy 300.274315 -316.152479) (xy 300.228503 -316.129136) (xy 300.186907 -316.098915)
			(xy 300.150551 -316.062559) (xy 300.12033 -316.020963) (xy 300.096987 -315.975151) (xy 300.081099 -315.926252)
			(xy 300.073056 -315.87547) (xy 299.754378 -315.87547) (xy 299.746662 -315.922946) (xy 299.731078 -315.969627)
			(xy 299.708207 -316.013204) (xy 299.678642 -316.052548) (xy 299.643149 -316.08664) (xy 299.602646 -316.114596)
			(xy 299.558184 -316.135694) (xy 299.510913 -316.149386) (xy 299.462058 -316.155318) (xy 299.412883 -316.153337)
			(xy 299.364664 -316.143493) (xy 299.318648 -316.126041) (xy 299.276027 -316.101434) (xy 299.237906 -316.070309)
			(xy 299.205271 -316.033472) (xy 299.178968 -315.991876) (xy 299.159677 -315.9466) (xy 299.1479 -315.898816)
			(xy 299.14394 -315.849762) (xy 298.826936 -315.849762) (xy 298.826432 -315.87547) (xy 298.818389 -315.926252)
			(xy 298.802501 -315.975151) (xy 298.779158 -316.020963) (xy 298.748937 -316.062559) (xy 298.712581 -316.098915)
			(xy 298.670985 -316.129136) (xy 298.625173 -316.152479) (xy 298.576274 -316.168367) (xy 298.525492 -316.17641)
			(xy 298.474076 -316.17641) (xy 298.423294 -316.168367) (xy 298.374395 -316.152479) (xy 298.328583 -316.129136)
			(xy 298.286987 -316.098915) (xy 298.250631 -316.062559) (xy 298.22041 -316.020963) (xy 298.197067 -315.975151)
			(xy 298.181179 -315.926252) (xy 298.173136 -315.87547) (xy 297.854458 -315.87547) (xy 297.846742 -315.922946)
			(xy 297.831158 -315.969627) (xy 297.808287 -316.013204) (xy 297.778722 -316.052548) (xy 297.743229 -316.08664)
			(xy 297.702726 -316.114596) (xy 297.658264 -316.135694) (xy 297.610993 -316.149386) (xy 297.562138 -316.155318)
			(xy 297.512963 -316.153337) (xy 297.464744 -316.143493) (xy 297.418728 -316.126041) (xy 297.376107 -316.101434)
			(xy 297.337986 -316.070309) (xy 297.305351 -316.033472) (xy 297.279048 -315.991876) (xy 297.259757 -315.9466)
			(xy 297.24798 -315.898816) (xy 297.24402 -315.849762) (xy 296.927016 -315.849762) (xy 296.926512 -315.87547)
			(xy 296.918469 -315.926252) (xy 296.902581 -315.975151) (xy 296.879238 -316.020963) (xy 296.849017 -316.062559)
			(xy 296.812661 -316.098915) (xy 296.771065 -316.129136) (xy 296.725253 -316.152479) (xy 296.676354 -316.168367)
			(xy 296.625572 -316.17641) (xy 296.574156 -316.17641) (xy 296.523374 -316.168367) (xy 296.474475 -316.152479)
			(xy 296.428663 -316.129136) (xy 296.387067 -316.098915) (xy 296.350711 -316.062559) (xy 296.32049 -316.020963)
			(xy 296.297147 -315.975151) (xy 296.281259 -315.926252) (xy 296.273216 -315.87547) (xy 295.954538 -315.87547)
			(xy 295.946822 -315.922946) (xy 295.931238 -315.969627) (xy 295.908367 -316.013204) (xy 295.878802 -316.052548)
			(xy 295.843309 -316.08664) (xy 295.802806 -316.114596) (xy 295.758344 -316.135694) (xy 295.711073 -316.149386)
			(xy 295.662218 -316.155318) (xy 295.613043 -316.153337) (xy 295.564824 -316.143493) (xy 295.518808 -316.126041)
			(xy 295.476187 -316.101434) (xy 295.438066 -316.070309) (xy 295.405431 -316.033472) (xy 295.379128 -315.991876)
			(xy 295.359837 -315.9466) (xy 295.34806 -315.898816) (xy 295.3441 -315.849762) (xy 295.026842 -315.849762)
			(xy 295.026338 -315.87547) (xy 295.018295 -315.926252) (xy 295.002407 -315.975151) (xy 294.979064 -316.020963)
			(xy 294.948843 -316.062559) (xy 294.912487 -316.098915) (xy 294.870891 -316.129136) (xy 294.825079 -316.152479)
			(xy 294.77618 -316.168367) (xy 294.725398 -316.17641) (xy 294.673982 -316.17641) (xy 294.6232 -316.168367)
			(xy 294.574301 -316.152479) (xy 294.528489 -316.129136) (xy 294.486893 -316.098915) (xy 294.450537 -316.062559)
			(xy 294.420316 -316.020963) (xy 294.396973 -315.975151) (xy 294.381085 -315.926252) (xy 294.373042 -315.87547)
			(xy 294.054364 -315.87547) (xy 294.046648 -315.922946) (xy 294.031064 -315.969627) (xy 294.008193 -316.013204)
			(xy 293.978628 -316.052548) (xy 293.943135 -316.08664) (xy 293.902632 -316.114596) (xy 293.85817 -316.135694)
			(xy 293.810899 -316.149386) (xy 293.762044 -316.155318) (xy 293.712869 -316.153337) (xy 293.66465 -316.143493)
			(xy 293.618634 -316.126041) (xy 293.576013 -316.101434) (xy 293.537892 -316.070309) (xy 293.505257 -316.033472)
			(xy 293.478954 -315.991876) (xy 293.459663 -315.9466) (xy 293.447886 -315.898816) (xy 293.443926 -315.849762)
			(xy 293.126922 -315.849762) (xy 293.126418 -315.87547) (xy 293.118375 -315.926252) (xy 293.102487 -315.975151)
			(xy 293.079144 -316.020963) (xy 293.048923 -316.062559) (xy 293.012567 -316.098915) (xy 292.970971 -316.129136)
			(xy 292.925159 -316.152479) (xy 292.87626 -316.168367) (xy 292.825478 -316.17641) (xy 292.774062 -316.17641)
			(xy 292.72328 -316.168367) (xy 292.674381 -316.152479) (xy 292.628569 -316.129136) (xy 292.586973 -316.098915)
			(xy 292.550617 -316.062559) (xy 292.520396 -316.020963) (xy 292.497053 -315.975151) (xy 292.481165 -315.926252)
			(xy 292.473122 -315.87547) (xy 292.154444 -315.87547) (xy 292.146728 -315.922946) (xy 292.131144 -315.969627)
			(xy 292.108273 -316.013204) (xy 292.078708 -316.052548) (xy 292.043215 -316.08664) (xy 292.002712 -316.114596)
			(xy 291.95825 -316.135694) (xy 291.910979 -316.149386) (xy 291.862124 -316.155318) (xy 291.812949 -316.153337)
			(xy 291.76473 -316.143493) (xy 291.718714 -316.126041) (xy 291.676093 -316.101434) (xy 291.637972 -316.070309)
			(xy 291.605337 -316.033472) (xy 291.579034 -315.991876) (xy 291.559743 -315.9466) (xy 291.547966 -315.898816)
			(xy 291.544006 -315.849762) (xy 291.240972 -315.849762) (xy 291.240972 -316.799722) (xy 291.544006 -316.799722)
			(xy 291.547966 -316.750668) (xy 291.559743 -316.702884) (xy 291.579034 -316.657608) (xy 291.605337 -316.616012)
			(xy 291.637972 -316.579175) (xy 291.676093 -316.54805) (xy 291.718714 -316.523443) (xy 291.76473 -316.505991)
			(xy 291.812949 -316.496147) (xy 291.862124 -316.494166) (xy 291.910979 -316.500098) (xy 291.95825 -316.51379)
			(xy 292.002712 -316.534888) (xy 292.043215 -316.562844) (xy 292.078708 -316.596936) (xy 292.108273 -316.63628)
			(xy 292.131144 -316.679857) (xy 292.146728 -316.726538) (xy 292.154623 -316.775115) (xy 292.155118 -316.799722)
			(xy 292.154623 -316.824329) (xy 292.154444 -316.82543) (xy 292.473122 -316.82543) (xy 292.473122 -316.774014)
			(xy 292.481165 -316.723232) (xy 292.497053 -316.674333) (xy 292.520396 -316.628521) (xy 292.550617 -316.586925)
			(xy 292.586973 -316.550569) (xy 292.628569 -316.520348) (xy 292.674381 -316.497005) (xy 292.72328 -316.481117)
			(xy 292.774062 -316.473074) (xy 292.825478 -316.473074) (xy 292.87626 -316.481117) (xy 292.925159 -316.497005)
			(xy 292.970971 -316.520348) (xy 293.012567 -316.550569) (xy 293.048923 -316.586925) (xy 293.079144 -316.628521)
			(xy 293.102487 -316.674333) (xy 293.118375 -316.723232) (xy 293.126418 -316.774014) (xy 293.126922 -316.799722)
			(xy 293.443926 -316.799722) (xy 293.447886 -316.750668) (xy 293.459663 -316.702884) (xy 293.478954 -316.657608)
			(xy 293.505257 -316.616012) (xy 293.537892 -316.579175) (xy 293.576013 -316.54805) (xy 293.618634 -316.523443)
			(xy 293.66465 -316.505991) (xy 293.712869 -316.496147) (xy 293.762044 -316.494166) (xy 293.810899 -316.500098)
			(xy 293.85817 -316.51379) (xy 293.902632 -316.534888) (xy 293.943135 -316.562844) (xy 293.978628 -316.596936)
			(xy 294.008193 -316.63628) (xy 294.031064 -316.679857) (xy 294.046648 -316.726538) (xy 294.054543 -316.775115)
			(xy 294.055038 -316.799722) (xy 294.054543 -316.824329) (xy 294.054364 -316.82543) (xy 294.373042 -316.82543)
			(xy 294.373042 -316.774014) (xy 294.381085 -316.723232) (xy 294.396973 -316.674333) (xy 294.420316 -316.628521)
			(xy 294.450537 -316.586925) (xy 294.486893 -316.550569) (xy 294.528489 -316.520348) (xy 294.574301 -316.497005)
			(xy 294.6232 -316.481117) (xy 294.673982 -316.473074) (xy 294.725398 -316.473074) (xy 294.77618 -316.481117)
			(xy 294.825079 -316.497005) (xy 294.870891 -316.520348) (xy 294.912487 -316.550569) (xy 294.948843 -316.586925)
			(xy 294.979064 -316.628521) (xy 295.002407 -316.674333) (xy 295.018295 -316.723232) (xy 295.026338 -316.774014)
			(xy 295.026842 -316.799722) (xy 295.3441 -316.799722) (xy 295.34806 -316.750668) (xy 295.359837 -316.702884)
			(xy 295.379128 -316.657608) (xy 295.405431 -316.616012) (xy 295.438066 -316.579175) (xy 295.476187 -316.54805)
			(xy 295.518808 -316.523443) (xy 295.564824 -316.505991) (xy 295.613043 -316.496147) (xy 295.662218 -316.494166)
			(xy 295.711073 -316.500098) (xy 295.758344 -316.51379) (xy 295.802806 -316.534888) (xy 295.843309 -316.562844)
			(xy 295.878802 -316.596936) (xy 295.908367 -316.63628) (xy 295.931238 -316.679857) (xy 295.946822 -316.726538)
			(xy 295.954717 -316.775115) (xy 295.955212 -316.799722) (xy 295.954717 -316.824329) (xy 295.954538 -316.82543)
			(xy 296.273216 -316.82543) (xy 296.273216 -316.774014) (xy 296.281259 -316.723232) (xy 296.297147 -316.674333)
			(xy 296.32049 -316.628521) (xy 296.350711 -316.586925) (xy 296.387067 -316.550569) (xy 296.428663 -316.520348)
			(xy 296.474475 -316.497005) (xy 296.523374 -316.481117) (xy 296.574156 -316.473074) (xy 296.625572 -316.473074)
			(xy 296.676354 -316.481117) (xy 296.725253 -316.497005) (xy 296.771065 -316.520348) (xy 296.812661 -316.550569)
			(xy 296.849017 -316.586925) (xy 296.879238 -316.628521) (xy 296.902581 -316.674333) (xy 296.918469 -316.723232)
			(xy 296.926512 -316.774014) (xy 296.927016 -316.799722) (xy 297.24402 -316.799722) (xy 297.24798 -316.750668)
			(xy 297.259757 -316.702884) (xy 297.279048 -316.657608) (xy 297.305351 -316.616012) (xy 297.337986 -316.579175)
			(xy 297.376107 -316.54805) (xy 297.418728 -316.523443) (xy 297.464744 -316.505991) (xy 297.512963 -316.496147)
			(xy 297.562138 -316.494166) (xy 297.610993 -316.500098) (xy 297.658264 -316.51379) (xy 297.702726 -316.534888)
			(xy 297.743229 -316.562844) (xy 297.778722 -316.596936) (xy 297.808287 -316.63628) (xy 297.831158 -316.679857)
			(xy 297.846742 -316.726538) (xy 297.854637 -316.775115) (xy 297.855132 -316.799722) (xy 297.854637 -316.824329)
			(xy 297.854458 -316.82543) (xy 298.173136 -316.82543) (xy 298.173136 -316.774014) (xy 298.181179 -316.723232)
			(xy 298.197067 -316.674333) (xy 298.22041 -316.628521) (xy 298.250631 -316.586925) (xy 298.286987 -316.550569)
			(xy 298.328583 -316.520348) (xy 298.374395 -316.497005) (xy 298.423294 -316.481117) (xy 298.474076 -316.473074)
			(xy 298.525492 -316.473074) (xy 298.576274 -316.481117) (xy 298.625173 -316.497005) (xy 298.670985 -316.520348)
			(xy 298.712581 -316.550569) (xy 298.748937 -316.586925) (xy 298.779158 -316.628521) (xy 298.802501 -316.674333)
			(xy 298.818389 -316.723232) (xy 298.826432 -316.774014) (xy 298.826936 -316.799722) (xy 299.14394 -316.799722)
			(xy 299.1479 -316.750668) (xy 299.159677 -316.702884) (xy 299.178968 -316.657608) (xy 299.205271 -316.616012)
			(xy 299.237906 -316.579175) (xy 299.276027 -316.54805) (xy 299.318648 -316.523443) (xy 299.364664 -316.505991)
			(xy 299.412883 -316.496147) (xy 299.462058 -316.494166) (xy 299.510913 -316.500098) (xy 299.558184 -316.51379)
			(xy 299.602646 -316.534888) (xy 299.643149 -316.562844) (xy 299.678642 -316.596936) (xy 299.708207 -316.63628)
			(xy 299.731078 -316.679857) (xy 299.746662 -316.726538) (xy 299.754557 -316.775115) (xy 299.755052 -316.799722)
			(xy 299.754557 -316.824329) (xy 299.754378 -316.82543) (xy 300.073056 -316.82543) (xy 300.073056 -316.774014)
			(xy 300.081099 -316.723232) (xy 300.096987 -316.674333) (xy 300.12033 -316.628521) (xy 300.150551 -316.586925)
			(xy 300.186907 -316.550569) (xy 300.228503 -316.520348) (xy 300.274315 -316.497005) (xy 300.323214 -316.481117)
			(xy 300.373996 -316.473074) (xy 300.425412 -316.473074) (xy 300.476194 -316.481117) (xy 300.525093 -316.497005)
			(xy 300.570905 -316.520348) (xy 300.612501 -316.550569) (xy 300.648857 -316.586925) (xy 300.679078 -316.628521)
			(xy 300.702421 -316.674333) (xy 300.718309 -316.723232) (xy 300.726352 -316.774014) (xy 300.726856 -316.799722)
			(xy 301.044114 -316.799722) (xy 301.048074 -316.750668) (xy 301.059851 -316.702884) (xy 301.079142 -316.657608)
			(xy 301.105445 -316.616012) (xy 301.13808 -316.579175) (xy 301.176201 -316.54805) (xy 301.218822 -316.523443)
			(xy 301.264838 -316.505991) (xy 301.313057 -316.496147) (xy 301.362232 -316.494166) (xy 301.411087 -316.500098)
			(xy 301.458358 -316.51379) (xy 301.50282 -316.534888) (xy 301.543323 -316.562844) (xy 301.578816 -316.596936)
			(xy 301.608381 -316.63628) (xy 301.631252 -316.679857) (xy 301.646836 -316.726538) (xy 301.654731 -316.775115)
			(xy 301.655226 -316.799722) (xy 301.654731 -316.824329) (xy 301.654552 -316.82543) (xy 301.97323 -316.82543)
			(xy 301.97323 -316.774014) (xy 301.981273 -316.723232) (xy 301.997161 -316.674333) (xy 302.020504 -316.628521)
			(xy 302.050725 -316.586925) (xy 302.087081 -316.550569) (xy 302.128677 -316.520348) (xy 302.174489 -316.497005)
			(xy 302.223388 -316.481117) (xy 302.27417 -316.473074) (xy 302.325586 -316.473074) (xy 302.376368 -316.481117)
			(xy 302.425267 -316.497005) (xy 302.471079 -316.520348) (xy 302.512675 -316.550569) (xy 302.549031 -316.586925)
			(xy 302.579252 -316.628521) (xy 302.602595 -316.674333) (xy 302.618483 -316.723232) (xy 302.626526 -316.774014)
			(xy 302.62703 -316.799722) (xy 302.944034 -316.799722) (xy 302.947994 -316.750668) (xy 302.959771 -316.702884)
			(xy 302.979062 -316.657608) (xy 303.005365 -316.616012) (xy 303.038 -316.579175) (xy 303.076121 -316.54805)
			(xy 303.118742 -316.523443) (xy 303.164758 -316.505991) (xy 303.212977 -316.496147) (xy 303.262152 -316.494166)
			(xy 303.311007 -316.500098) (xy 303.358278 -316.51379) (xy 303.40274 -316.534888) (xy 303.443243 -316.562844)
			(xy 303.478736 -316.596936) (xy 303.508301 -316.63628) (xy 303.531172 -316.679857) (xy 303.546756 -316.726538)
			(xy 303.554651 -316.775115) (xy 303.555146 -316.799722) (xy 303.554651 -316.824329) (xy 303.554472 -316.82543)
			(xy 303.87315 -316.82543) (xy 303.87315 -316.774014) (xy 303.881193 -316.723232) (xy 303.897081 -316.674333)
			(xy 303.920424 -316.628521) (xy 303.950645 -316.586925) (xy 303.987001 -316.550569) (xy 304.028597 -316.520348)
			(xy 304.074409 -316.497005) (xy 304.123308 -316.481117) (xy 304.17409 -316.473074) (xy 304.225506 -316.473074)
			(xy 304.276288 -316.481117) (xy 304.325187 -316.497005) (xy 304.370999 -316.520348) (xy 304.412595 -316.550569)
			(xy 304.448951 -316.586925) (xy 304.479172 -316.628521) (xy 304.502515 -316.674333) (xy 304.518403 -316.723232)
			(xy 304.526446 -316.774014) (xy 304.52695 -316.799722) (xy 304.843954 -316.799722) (xy 304.847914 -316.750668)
			(xy 304.859691 -316.702884) (xy 304.878982 -316.657608) (xy 304.905285 -316.616012) (xy 304.93792 -316.579175)
			(xy 304.976041 -316.54805) (xy 305.018662 -316.523443) (xy 305.064678 -316.505991) (xy 305.112897 -316.496147)
			(xy 305.162072 -316.494166) (xy 305.210927 -316.500098) (xy 305.258198 -316.51379) (xy 305.30266 -316.534888)
			(xy 305.343163 -316.562844) (xy 305.378656 -316.596936) (xy 305.408221 -316.63628) (xy 305.431092 -316.679857)
			(xy 305.446676 -316.726538) (xy 305.454571 -316.775115) (xy 305.455066 -316.799722) (xy 305.793914 -316.799722)
			(xy 305.797874 -316.750668) (xy 305.809651 -316.702884) (xy 305.828942 -316.657608) (xy 305.855245 -316.616012)
			(xy 305.88788 -316.579175) (xy 305.926001 -316.54805) (xy 305.968622 -316.523443) (xy 306.014638 -316.505991)
			(xy 306.062857 -316.496147) (xy 306.112032 -316.494166) (xy 306.160887 -316.500098) (xy 306.208158 -316.51379)
			(xy 306.25262 -316.534888) (xy 306.293123 -316.562844) (xy 306.328616 -316.596936) (xy 306.358181 -316.63628)
			(xy 306.381052 -316.679857) (xy 306.396636 -316.726538) (xy 306.404531 -316.775115) (xy 306.405026 -316.799722)
			(xy 306.744128 -316.799722) (xy 306.748088 -316.750668) (xy 306.759865 -316.702884) (xy 306.779156 -316.657608)
			(xy 306.805459 -316.616012) (xy 306.838094 -316.579175) (xy 306.876215 -316.54805) (xy 306.918836 -316.523443)
			(xy 306.964852 -316.505991) (xy 307.013071 -316.496147) (xy 307.062246 -316.494166) (xy 307.111101 -316.500098)
			(xy 307.158372 -316.51379) (xy 307.202834 -316.534888) (xy 307.243337 -316.562844) (xy 307.27883 -316.596936)
			(xy 307.308395 -316.63628) (xy 307.331266 -316.679857) (xy 307.34685 -316.726538) (xy 307.354745 -316.775115)
			(xy 307.35524 -316.799722) (xy 307.694088 -316.799722) (xy 307.698048 -316.750668) (xy 307.709825 -316.702884)
			(xy 307.729116 -316.657608) (xy 307.755419 -316.616012) (xy 307.788054 -316.579175) (xy 307.826175 -316.54805)
			(xy 307.868796 -316.523443) (xy 307.914812 -316.505991) (xy 307.963031 -316.496147) (xy 308.012206 -316.494166)
			(xy 308.061061 -316.500098) (xy 308.108332 -316.51379) (xy 308.152794 -316.534888) (xy 308.193297 -316.562844)
			(xy 308.22879 -316.596936) (xy 308.258355 -316.63628) (xy 308.281226 -316.679857) (xy 308.29681 -316.726538)
			(xy 308.304705 -316.775115) (xy 308.3052 -316.799722) (xy 308.644048 -316.799722) (xy 308.648008 -316.750668)
			(xy 308.659785 -316.702884) (xy 308.679076 -316.657608) (xy 308.705379 -316.616012) (xy 308.738014 -316.579175)
			(xy 308.776135 -316.54805) (xy 308.818756 -316.523443) (xy 308.864772 -316.505991) (xy 308.912991 -316.496147)
			(xy 308.962166 -316.494166) (xy 309.011021 -316.500098) (xy 309.058292 -316.51379) (xy 309.102754 -316.534888)
			(xy 309.143257 -316.562844) (xy 309.17875 -316.596936) (xy 309.208315 -316.63628) (xy 309.231186 -316.679857)
			(xy 309.24677 -316.726538) (xy 309.254665 -316.775115) (xy 309.25516 -316.799722) (xy 309.594008 -316.799722)
			(xy 309.597968 -316.750668) (xy 309.609745 -316.702884) (xy 309.629036 -316.657608) (xy 309.655339 -316.616012)
			(xy 309.687974 -316.579175) (xy 309.726095 -316.54805) (xy 309.768716 -316.523443) (xy 309.814732 -316.505991)
			(xy 309.862951 -316.496147) (xy 309.912126 -316.494166) (xy 309.960981 -316.500098) (xy 310.008252 -316.51379)
			(xy 310.052714 -316.534888) (xy 310.093217 -316.562844) (xy 310.12871 -316.596936) (xy 310.158275 -316.63628)
			(xy 310.181146 -316.679857) (xy 310.19673 -316.726538) (xy 310.204625 -316.775115) (xy 310.20512 -316.799722)
			(xy 310.543968 -316.799722) (xy 310.547928 -316.750668) (xy 310.559705 -316.702884) (xy 310.578996 -316.657608)
			(xy 310.605299 -316.616012) (xy 310.637934 -316.579175) (xy 310.676055 -316.54805) (xy 310.718676 -316.523443)
			(xy 310.764692 -316.505991) (xy 310.812911 -316.496147) (xy 310.862086 -316.494166) (xy 310.910941 -316.500098)
			(xy 310.958212 -316.51379) (xy 311.002674 -316.534888) (xy 311.043177 -316.562844) (xy 311.07867 -316.596936)
			(xy 311.108235 -316.63628) (xy 311.131106 -316.679857) (xy 311.14669 -316.726538) (xy 311.154585 -316.775115)
			(xy 311.15508 -316.799722) (xy 311.493928 -316.799722) (xy 311.497888 -316.750668) (xy 311.509665 -316.702884)
			(xy 311.528956 -316.657608) (xy 311.555259 -316.616012) (xy 311.587894 -316.579175) (xy 311.626015 -316.54805)
			(xy 311.668636 -316.523443) (xy 311.714652 -316.505991) (xy 311.762871 -316.496147) (xy 311.812046 -316.494166)
			(xy 311.860901 -316.500098) (xy 311.908172 -316.51379) (xy 311.952634 -316.534888) (xy 311.993137 -316.562844)
			(xy 312.02863 -316.596936) (xy 312.058195 -316.63628) (xy 312.081066 -316.679857) (xy 312.09665 -316.726538)
			(xy 312.104545 -316.775115) (xy 312.10504 -316.799722) (xy 312.443888 -316.799722) (xy 312.447848 -316.750668)
			(xy 312.459625 -316.702884) (xy 312.478916 -316.657608) (xy 312.505219 -316.616012) (xy 312.537854 -316.579175)
			(xy 312.575975 -316.54805) (xy 312.618596 -316.523443) (xy 312.664612 -316.505991) (xy 312.712831 -316.496147)
			(xy 312.762006 -316.494166) (xy 312.810861 -316.500098) (xy 312.858132 -316.51379) (xy 312.902594 -316.534888)
			(xy 312.943097 -316.562844) (xy 312.97859 -316.596936) (xy 313.008155 -316.63628) (xy 313.031026 -316.679857)
			(xy 313.04661 -316.726538) (xy 313.054505 -316.775115) (xy 313.055 -316.799722) (xy 313.394102 -316.799722)
			(xy 313.398062 -316.750668) (xy 313.409839 -316.702884) (xy 313.42913 -316.657608) (xy 313.455433 -316.616012)
			(xy 313.488068 -316.579175) (xy 313.526189 -316.54805) (xy 313.56881 -316.523443) (xy 313.614826 -316.505991)
			(xy 313.663045 -316.496147) (xy 313.71222 -316.494166) (xy 313.761075 -316.500098) (xy 313.808346 -316.51379)
			(xy 313.852808 -316.534888) (xy 313.893311 -316.562844) (xy 313.928804 -316.596936) (xy 313.958369 -316.63628)
			(xy 313.98124 -316.679857) (xy 313.996824 -316.726538) (xy 314.004719 -316.775115) (xy 314.005214 -316.799722)
			(xy 314.344062 -316.799722) (xy 314.348022 -316.750668) (xy 314.359799 -316.702884) (xy 314.37909 -316.657608)
			(xy 314.405393 -316.616012) (xy 314.438028 -316.579175) (xy 314.476149 -316.54805) (xy 314.51877 -316.523443)
			(xy 314.564786 -316.505991) (xy 314.613005 -316.496147) (xy 314.66218 -316.494166) (xy 314.711035 -316.500098)
			(xy 314.758306 -316.51379) (xy 314.802768 -316.534888) (xy 314.843271 -316.562844) (xy 314.878764 -316.596936)
			(xy 314.908329 -316.63628) (xy 314.9312 -316.679857) (xy 314.946784 -316.726538) (xy 314.954679 -316.775115)
			(xy 314.955174 -316.799722) (xy 315.294276 -316.799722) (xy 315.298236 -316.750668) (xy 315.310013 -316.702884)
			(xy 315.329304 -316.657608) (xy 315.355607 -316.616012) (xy 315.388242 -316.579175) (xy 315.426363 -316.54805)
			(xy 315.468984 -316.523443) (xy 315.515 -316.505991) (xy 315.563219 -316.496147) (xy 315.612394 -316.494166)
			(xy 315.661249 -316.500098) (xy 315.70852 -316.51379) (xy 315.752982 -316.534888) (xy 315.793485 -316.562844)
			(xy 315.828978 -316.596936) (xy 315.858543 -316.63628) (xy 315.881414 -316.679857) (xy 315.896998 -316.726538)
			(xy 315.904893 -316.775115) (xy 315.905388 -316.799722) (xy 315.904893 -316.824329) (xy 315.896998 -316.872906)
			(xy 315.881414 -316.919587) (xy 315.858543 -316.963164) (xy 315.828978 -317.002508) (xy 315.793485 -317.0366)
			(xy 315.752982 -317.064556) (xy 315.70852 -317.085654) (xy 315.661249 -317.099346) (xy 315.612394 -317.105278)
			(xy 315.563219 -317.103297) (xy 315.515 -317.093453) (xy 315.468984 -317.076001) (xy 315.426363 -317.051394)
			(xy 315.388242 -317.020269) (xy 315.355607 -316.983432) (xy 315.329304 -316.941836) (xy 315.310013 -316.89656)
			(xy 315.298236 -316.848776) (xy 315.294276 -316.799722) (xy 314.955174 -316.799722) (xy 314.954679 -316.824329)
			(xy 314.946784 -316.872906) (xy 314.9312 -316.919587) (xy 314.908329 -316.963164) (xy 314.878764 -317.002508)
			(xy 314.843271 -317.0366) (xy 314.802768 -317.064556) (xy 314.758306 -317.085654) (xy 314.711035 -317.099346)
			(xy 314.66218 -317.105278) (xy 314.613005 -317.103297) (xy 314.564786 -317.093453) (xy 314.51877 -317.076001)
			(xy 314.476149 -317.051394) (xy 314.438028 -317.020269) (xy 314.405393 -316.983432) (xy 314.37909 -316.941836)
			(xy 314.359799 -316.89656) (xy 314.348022 -316.848776) (xy 314.344062 -316.799722) (xy 314.005214 -316.799722)
			(xy 314.004719 -316.824329) (xy 313.996824 -316.872906) (xy 313.98124 -316.919587) (xy 313.958369 -316.963164)
			(xy 313.928804 -317.002508) (xy 313.893311 -317.0366) (xy 313.852808 -317.064556) (xy 313.808346 -317.085654)
			(xy 313.761075 -317.099346) (xy 313.71222 -317.105278) (xy 313.663045 -317.103297) (xy 313.614826 -317.093453)
			(xy 313.56881 -317.076001) (xy 313.526189 -317.051394) (xy 313.488068 -317.020269) (xy 313.455433 -316.983432)
			(xy 313.42913 -316.941836) (xy 313.409839 -316.89656) (xy 313.398062 -316.848776) (xy 313.394102 -316.799722)
			(xy 313.055 -316.799722) (xy 313.054505 -316.824329) (xy 313.04661 -316.872906) (xy 313.031026 -316.919587)
			(xy 313.008155 -316.963164) (xy 312.97859 -317.002508) (xy 312.943097 -317.0366) (xy 312.902594 -317.064556)
			(xy 312.858132 -317.085654) (xy 312.810861 -317.099346) (xy 312.762006 -317.105278) (xy 312.712831 -317.103297)
			(xy 312.664612 -317.093453) (xy 312.618596 -317.076001) (xy 312.575975 -317.051394) (xy 312.537854 -317.020269)
			(xy 312.505219 -316.983432) (xy 312.478916 -316.941836) (xy 312.459625 -316.89656) (xy 312.447848 -316.848776)
			(xy 312.443888 -316.799722) (xy 312.10504 -316.799722) (xy 312.104545 -316.824329) (xy 312.09665 -316.872906)
			(xy 312.081066 -316.919587) (xy 312.058195 -316.963164) (xy 312.02863 -317.002508) (xy 311.993137 -317.0366)
			(xy 311.952634 -317.064556) (xy 311.908172 -317.085654) (xy 311.860901 -317.099346) (xy 311.812046 -317.105278)
			(xy 311.762871 -317.103297) (xy 311.714652 -317.093453) (xy 311.668636 -317.076001) (xy 311.626015 -317.051394)
			(xy 311.587894 -317.020269) (xy 311.555259 -316.983432) (xy 311.528956 -316.941836) (xy 311.509665 -316.89656)
			(xy 311.497888 -316.848776) (xy 311.493928 -316.799722) (xy 311.15508 -316.799722) (xy 311.154585 -316.824329)
			(xy 311.14669 -316.872906) (xy 311.131106 -316.919587) (xy 311.108235 -316.963164) (xy 311.07867 -317.002508)
			(xy 311.043177 -317.0366) (xy 311.002674 -317.064556) (xy 310.958212 -317.085654) (xy 310.910941 -317.099346)
			(xy 310.862086 -317.105278) (xy 310.812911 -317.103297) (xy 310.764692 -317.093453) (xy 310.718676 -317.076001)
			(xy 310.676055 -317.051394) (xy 310.637934 -317.020269) (xy 310.605299 -316.983432) (xy 310.578996 -316.941836)
			(xy 310.559705 -316.89656) (xy 310.547928 -316.848776) (xy 310.543968 -316.799722) (xy 310.20512 -316.799722)
			(xy 310.204625 -316.824329) (xy 310.19673 -316.872906) (xy 310.181146 -316.919587) (xy 310.158275 -316.963164)
			(xy 310.12871 -317.002508) (xy 310.093217 -317.0366) (xy 310.052714 -317.064556) (xy 310.008252 -317.085654)
			(xy 309.960981 -317.099346) (xy 309.912126 -317.105278) (xy 309.862951 -317.103297) (xy 309.814732 -317.093453)
			(xy 309.768716 -317.076001) (xy 309.726095 -317.051394) (xy 309.687974 -317.020269) (xy 309.655339 -316.983432)
			(xy 309.629036 -316.941836) (xy 309.609745 -316.89656) (xy 309.597968 -316.848776) (xy 309.594008 -316.799722)
			(xy 309.25516 -316.799722) (xy 309.254665 -316.824329) (xy 309.24677 -316.872906) (xy 309.231186 -316.919587)
			(xy 309.208315 -316.963164) (xy 309.17875 -317.002508) (xy 309.143257 -317.0366) (xy 309.102754 -317.064556)
			(xy 309.058292 -317.085654) (xy 309.011021 -317.099346) (xy 308.962166 -317.105278) (xy 308.912991 -317.103297)
			(xy 308.864772 -317.093453) (xy 308.818756 -317.076001) (xy 308.776135 -317.051394) (xy 308.738014 -317.020269)
			(xy 308.705379 -316.983432) (xy 308.679076 -316.941836) (xy 308.659785 -316.89656) (xy 308.648008 -316.848776)
			(xy 308.644048 -316.799722) (xy 308.3052 -316.799722) (xy 308.304705 -316.824329) (xy 308.29681 -316.872906)
			(xy 308.281226 -316.919587) (xy 308.258355 -316.963164) (xy 308.22879 -317.002508) (xy 308.193297 -317.0366)
			(xy 308.152794 -317.064556) (xy 308.108332 -317.085654) (xy 308.061061 -317.099346) (xy 308.012206 -317.105278)
			(xy 307.963031 -317.103297) (xy 307.914812 -317.093453) (xy 307.868796 -317.076001) (xy 307.826175 -317.051394)
			(xy 307.788054 -317.020269) (xy 307.755419 -316.983432) (xy 307.729116 -316.941836) (xy 307.709825 -316.89656)
			(xy 307.698048 -316.848776) (xy 307.694088 -316.799722) (xy 307.35524 -316.799722) (xy 307.354745 -316.824329)
			(xy 307.34685 -316.872906) (xy 307.331266 -316.919587) (xy 307.308395 -316.963164) (xy 307.27883 -317.002508)
			(xy 307.243337 -317.0366) (xy 307.202834 -317.064556) (xy 307.158372 -317.085654) (xy 307.111101 -317.099346)
			(xy 307.062246 -317.105278) (xy 307.013071 -317.103297) (xy 306.964852 -317.093453) (xy 306.918836 -317.076001)
			(xy 306.876215 -317.051394) (xy 306.838094 -317.020269) (xy 306.805459 -316.983432) (xy 306.779156 -316.941836)
			(xy 306.759865 -316.89656) (xy 306.748088 -316.848776) (xy 306.744128 -316.799722) (xy 306.405026 -316.799722)
			(xy 306.404531 -316.824329) (xy 306.396636 -316.872906) (xy 306.381052 -316.919587) (xy 306.358181 -316.963164)
			(xy 306.328616 -317.002508) (xy 306.293123 -317.0366) (xy 306.25262 -317.064556) (xy 306.208158 -317.085654)
			(xy 306.160887 -317.099346) (xy 306.112032 -317.105278) (xy 306.062857 -317.103297) (xy 306.014638 -317.093453)
			(xy 305.968622 -317.076001) (xy 305.926001 -317.051394) (xy 305.88788 -317.020269) (xy 305.855245 -316.983432)
			(xy 305.828942 -316.941836) (xy 305.809651 -316.89656) (xy 305.797874 -316.848776) (xy 305.793914 -316.799722)
			(xy 305.455066 -316.799722) (xy 305.454571 -316.824329) (xy 305.446676 -316.872906) (xy 305.431092 -316.919587)
			(xy 305.408221 -316.963164) (xy 305.378656 -317.002508) (xy 305.343163 -317.0366) (xy 305.30266 -317.064556)
			(xy 305.258198 -317.085654) (xy 305.210927 -317.099346) (xy 305.162072 -317.105278) (xy 305.112897 -317.103297)
			(xy 305.064678 -317.093453) (xy 305.018662 -317.076001) (xy 304.976041 -317.051394) (xy 304.93792 -317.020269)
			(xy 304.905285 -316.983432) (xy 304.878982 -316.941836) (xy 304.859691 -316.89656) (xy 304.847914 -316.848776)
			(xy 304.843954 -316.799722) (xy 304.52695 -316.799722) (xy 304.526446 -316.82543) (xy 304.518403 -316.876212)
			(xy 304.502515 -316.925111) (xy 304.479172 -316.970923) (xy 304.448951 -317.012519) (xy 304.412595 -317.048875)
			(xy 304.370999 -317.079096) (xy 304.325187 -317.102439) (xy 304.276288 -317.118327) (xy 304.225506 -317.12637)
			(xy 304.17409 -317.12637) (xy 304.123308 -317.118327) (xy 304.074409 -317.102439) (xy 304.028597 -317.079096)
			(xy 303.987001 -317.048875) (xy 303.950645 -317.012519) (xy 303.920424 -316.970923) (xy 303.897081 -316.925111)
			(xy 303.881193 -316.876212) (xy 303.87315 -316.82543) (xy 303.554472 -316.82543) (xy 303.546756 -316.872906)
			(xy 303.531172 -316.919587) (xy 303.508301 -316.963164) (xy 303.478736 -317.002508) (xy 303.443243 -317.0366)
			(xy 303.40274 -317.064556) (xy 303.358278 -317.085654) (xy 303.311007 -317.099346) (xy 303.262152 -317.105278)
			(xy 303.212977 -317.103297) (xy 303.164758 -317.093453) (xy 303.118742 -317.076001) (xy 303.076121 -317.051394)
			(xy 303.038 -317.020269) (xy 303.005365 -316.983432) (xy 302.979062 -316.941836) (xy 302.959771 -316.89656)
			(xy 302.947994 -316.848776) (xy 302.944034 -316.799722) (xy 302.62703 -316.799722) (xy 302.626526 -316.82543)
			(xy 302.618483 -316.876212) (xy 302.602595 -316.925111) (xy 302.579252 -316.970923) (xy 302.549031 -317.012519)
			(xy 302.512675 -317.048875) (xy 302.471079 -317.079096) (xy 302.425267 -317.102439) (xy 302.376368 -317.118327)
			(xy 302.325586 -317.12637) (xy 302.27417 -317.12637) (xy 302.223388 -317.118327) (xy 302.174489 -317.102439)
			(xy 302.128677 -317.079096) (xy 302.087081 -317.048875) (xy 302.050725 -317.012519) (xy 302.020504 -316.970923)
			(xy 301.997161 -316.925111) (xy 301.981273 -316.876212) (xy 301.97323 -316.82543) (xy 301.654552 -316.82543)
			(xy 301.646836 -316.872906) (xy 301.631252 -316.919587) (xy 301.608381 -316.963164) (xy 301.578816 -317.002508)
			(xy 301.543323 -317.0366) (xy 301.50282 -317.064556) (xy 301.458358 -317.085654) (xy 301.411087 -317.099346)
			(xy 301.362232 -317.105278) (xy 301.313057 -317.103297) (xy 301.264838 -317.093453) (xy 301.218822 -317.076001)
			(xy 301.176201 -317.051394) (xy 301.13808 -317.020269) (xy 301.105445 -316.983432) (xy 301.079142 -316.941836)
			(xy 301.059851 -316.89656) (xy 301.048074 -316.848776) (xy 301.044114 -316.799722) (xy 300.726856 -316.799722)
			(xy 300.726352 -316.82543) (xy 300.718309 -316.876212) (xy 300.702421 -316.925111) (xy 300.679078 -316.970923)
			(xy 300.648857 -317.012519) (xy 300.612501 -317.048875) (xy 300.570905 -317.079096) (xy 300.525093 -317.102439)
			(xy 300.476194 -317.118327) (xy 300.425412 -317.12637) (xy 300.373996 -317.12637) (xy 300.323214 -317.118327)
			(xy 300.274315 -317.102439) (xy 300.228503 -317.079096) (xy 300.186907 -317.048875) (xy 300.150551 -317.012519)
			(xy 300.12033 -316.970923) (xy 300.096987 -316.925111) (xy 300.081099 -316.876212) (xy 300.073056 -316.82543)
			(xy 299.754378 -316.82543) (xy 299.746662 -316.872906) (xy 299.731078 -316.919587) (xy 299.708207 -316.963164)
			(xy 299.678642 -317.002508) (xy 299.643149 -317.0366) (xy 299.602646 -317.064556) (xy 299.558184 -317.085654)
			(xy 299.510913 -317.099346) (xy 299.462058 -317.105278) (xy 299.412883 -317.103297) (xy 299.364664 -317.093453)
			(xy 299.318648 -317.076001) (xy 299.276027 -317.051394) (xy 299.237906 -317.020269) (xy 299.205271 -316.983432)
			(xy 299.178968 -316.941836) (xy 299.159677 -316.89656) (xy 299.1479 -316.848776) (xy 299.14394 -316.799722)
			(xy 298.826936 -316.799722) (xy 298.826432 -316.82543) (xy 298.818389 -316.876212) (xy 298.802501 -316.925111)
			(xy 298.779158 -316.970923) (xy 298.748937 -317.012519) (xy 298.712581 -317.048875) (xy 298.670985 -317.079096)
			(xy 298.625173 -317.102439) (xy 298.576274 -317.118327) (xy 298.525492 -317.12637) (xy 298.474076 -317.12637)
			(xy 298.423294 -317.118327) (xy 298.374395 -317.102439) (xy 298.328583 -317.079096) (xy 298.286987 -317.048875)
			(xy 298.250631 -317.012519) (xy 298.22041 -316.970923) (xy 298.197067 -316.925111) (xy 298.181179 -316.876212)
			(xy 298.173136 -316.82543) (xy 297.854458 -316.82543) (xy 297.846742 -316.872906) (xy 297.831158 -316.919587)
			(xy 297.808287 -316.963164) (xy 297.778722 -317.002508) (xy 297.743229 -317.0366) (xy 297.702726 -317.064556)
			(xy 297.658264 -317.085654) (xy 297.610993 -317.099346) (xy 297.562138 -317.105278) (xy 297.512963 -317.103297)
			(xy 297.464744 -317.093453) (xy 297.418728 -317.076001) (xy 297.376107 -317.051394) (xy 297.337986 -317.020269)
			(xy 297.305351 -316.983432) (xy 297.279048 -316.941836) (xy 297.259757 -316.89656) (xy 297.24798 -316.848776)
			(xy 297.24402 -316.799722) (xy 296.927016 -316.799722) (xy 296.926512 -316.82543) (xy 296.918469 -316.876212)
			(xy 296.902581 -316.925111) (xy 296.879238 -316.970923) (xy 296.849017 -317.012519) (xy 296.812661 -317.048875)
			(xy 296.771065 -317.079096) (xy 296.725253 -317.102439) (xy 296.676354 -317.118327) (xy 296.625572 -317.12637)
			(xy 296.574156 -317.12637) (xy 296.523374 -317.118327) (xy 296.474475 -317.102439) (xy 296.428663 -317.079096)
			(xy 296.387067 -317.048875) (xy 296.350711 -317.012519) (xy 296.32049 -316.970923) (xy 296.297147 -316.925111)
			(xy 296.281259 -316.876212) (xy 296.273216 -316.82543) (xy 295.954538 -316.82543) (xy 295.946822 -316.872906)
			(xy 295.931238 -316.919587) (xy 295.908367 -316.963164) (xy 295.878802 -317.002508) (xy 295.843309 -317.0366)
			(xy 295.802806 -317.064556) (xy 295.758344 -317.085654) (xy 295.711073 -317.099346) (xy 295.662218 -317.105278)
			(xy 295.613043 -317.103297) (xy 295.564824 -317.093453) (xy 295.518808 -317.076001) (xy 295.476187 -317.051394)
			(xy 295.438066 -317.020269) (xy 295.405431 -316.983432) (xy 295.379128 -316.941836) (xy 295.359837 -316.89656)
			(xy 295.34806 -316.848776) (xy 295.3441 -316.799722) (xy 295.026842 -316.799722) (xy 295.026338 -316.82543)
			(xy 295.018295 -316.876212) (xy 295.002407 -316.925111) (xy 294.979064 -316.970923) (xy 294.948843 -317.012519)
			(xy 294.912487 -317.048875) (xy 294.870891 -317.079096) (xy 294.825079 -317.102439) (xy 294.77618 -317.118327)
			(xy 294.725398 -317.12637) (xy 294.673982 -317.12637) (xy 294.6232 -317.118327) (xy 294.574301 -317.102439)
			(xy 294.528489 -317.079096) (xy 294.486893 -317.048875) (xy 294.450537 -317.012519) (xy 294.420316 -316.970923)
			(xy 294.396973 -316.925111) (xy 294.381085 -316.876212) (xy 294.373042 -316.82543) (xy 294.054364 -316.82543)
			(xy 294.046648 -316.872906) (xy 294.031064 -316.919587) (xy 294.008193 -316.963164) (xy 293.978628 -317.002508)
			(xy 293.943135 -317.0366) (xy 293.902632 -317.064556) (xy 293.85817 -317.085654) (xy 293.810899 -317.099346)
			(xy 293.762044 -317.105278) (xy 293.712869 -317.103297) (xy 293.66465 -317.093453) (xy 293.618634 -317.076001)
			(xy 293.576013 -317.051394) (xy 293.537892 -317.020269) (xy 293.505257 -316.983432) (xy 293.478954 -316.941836)
			(xy 293.459663 -316.89656) (xy 293.447886 -316.848776) (xy 293.443926 -316.799722) (xy 293.126922 -316.799722)
			(xy 293.126418 -316.82543) (xy 293.118375 -316.876212) (xy 293.102487 -316.925111) (xy 293.079144 -316.970923)
			(xy 293.048923 -317.012519) (xy 293.012567 -317.048875) (xy 292.970971 -317.079096) (xy 292.925159 -317.102439)
			(xy 292.87626 -317.118327) (xy 292.825478 -317.12637) (xy 292.774062 -317.12637) (xy 292.72328 -317.118327)
			(xy 292.674381 -317.102439) (xy 292.628569 -317.079096) (xy 292.586973 -317.048875) (xy 292.550617 -317.012519)
			(xy 292.520396 -316.970923) (xy 292.497053 -316.925111) (xy 292.481165 -316.876212) (xy 292.473122 -316.82543)
			(xy 292.154444 -316.82543) (xy 292.146728 -316.872906) (xy 292.131144 -316.919587) (xy 292.108273 -316.963164)
			(xy 292.078708 -317.002508) (xy 292.043215 -317.0366) (xy 292.002712 -317.064556) (xy 291.95825 -317.085654)
			(xy 291.910979 -317.099346) (xy 291.862124 -317.105278) (xy 291.812949 -317.103297) (xy 291.76473 -317.093453)
			(xy 291.718714 -317.076001) (xy 291.676093 -317.051394) (xy 291.637972 -317.020269) (xy 291.605337 -316.983432)
			(xy 291.579034 -316.941836) (xy 291.559743 -316.89656) (xy 291.547966 -316.848776) (xy 291.544006 -316.799722)
			(xy 291.240972 -316.799722) (xy 291.240972 -318.82207) (xy 291.241476 -318.832121) (xy 291.249194 -318.850685)
			(xy 291.255958 -318.858138) (xy 291.412676 -319.014856) (xy 291.418623 -319.020418) (xy 291.433126 -319.027804)
			(xy 291.441124 -319.029334) (xy 291.475668 -319.034414) (xy 291.485396 -319.035446) (xy 291.504405 -319.030906)
			(xy 291.520301 -319.019537) (xy 291.52596 -319.011554) (xy 291.584126 -318.920876) (xy 291.584126 -318.891158)
			(xy 291.575744 -318.878458) (xy 291.563211 -318.858438) (xy 291.543421 -318.815553) (xy 291.530023 -318.770262)
			(xy 291.523297 -318.723512) (xy 291.522912 -318.699896) (xy 291.523415 -318.6742) (xy 291.531451 -318.62344)
			(xy 291.547324 -318.574561) (xy 291.570643 -318.528765) (xy 291.600836 -318.487178) (xy 291.63716 -318.450822)
			(xy 291.678721 -318.420593) (xy 291.724497 -318.397233) (xy 291.773362 -318.381318) (xy 291.824115 -318.373238)
			(xy 291.84981 -318.372744) (xy 291.882068 -318.374522) (xy 291.89299 -318.375538) (xy 291.91331 -318.368934)
			(xy 291.977064 -318.311022) (xy 291.984576 -318.303478) (xy 291.993243 -318.284059) (xy 291.993828 -318.27343)
			(xy 291.993828 -318.224916) (xy 291.993871 -318.215562) (xy 291.994888 -318.196882) (xy 291.99586 -318.187578)
			(xy 291.99713 -318.175894) (xy 291.989764 -318.154304) (xy 291.917374 -318.08166) (xy 291.895784 -318.073786)
			(xy 291.884354 -318.075056) (xy 291.84981 -318.077088) (xy 291.824127 -318.076585) (xy 291.773394 -318.068553)
			(xy 291.724541 -318.052684) (xy 291.678771 -318.02937) (xy 291.637212 -317.999183) (xy 291.600885 -317.962868)
			(xy 291.570685 -317.921318) (xy 291.547356 -317.875556) (xy 291.531472 -317.826708) (xy 291.523423 -317.775977)
			(xy 291.523408 -317.724612) (xy 291.531427 -317.673876) (xy 291.547283 -317.625019) (xy 291.570586 -317.579244)
			(xy 291.600762 -317.537676) (xy 291.637067 -317.50134) (xy 291.67861 -317.47113) (xy 291.724366 -317.447788)
			(xy 291.773209 -317.431891) (xy 291.823938 -317.42383) (xy 291.875304 -317.423801) (xy 291.926041 -317.431808)
			(xy 291.974903 -317.447651) (xy 292.020684 -317.470942) (xy 292.062259 -317.501107) (xy 292.098605 -317.537403)
			(xy 292.128826 -317.578937) (xy 292.152179 -317.624687) (xy 292.168089 -317.673527) (xy 292.176164 -317.724254)
			(xy 292.176708 -317.749936) (xy 292.17493 -317.78448) (xy 292.17366 -317.79591) (xy 292.181534 -317.8175)
			(xy 292.254178 -317.88989) (xy 292.275768 -317.897256) (xy 292.287452 -317.895986) (xy 292.296756 -317.895017)
			(xy 292.315436 -317.893999) (xy 292.32479 -317.893954) (xy 292.338444 -317.894117) (xy 292.365656 -317.896408)
			(xy 292.379146 -317.898526) (xy 292.391084 -317.900558) (xy 292.41369 -317.893446) (xy 292.490144 -317.820548)
			(xy 292.498018 -317.798196) (xy 292.496494 -317.786258) (xy 292.495505 -317.777211) (xy 292.494487 -317.759037)
			(xy 292.494462 -317.749936) (xy 292.494945 -317.725112) (xy 292.502972 -317.676116) (xy 292.51882 -317.629064)
			(xy 292.542072 -317.585197) (xy 292.572115 -317.545669) (xy 292.608157 -317.511523) (xy 292.649248 -317.483657)
			(xy 292.694307 -317.462807) (xy 292.742146 -317.449522) (xy 292.791503 -317.444152) (xy 292.841079 -317.446837)
			(xy 292.889568 -317.457509) (xy 292.935691 -317.475884) (xy 292.978233 -317.50148) (xy 293.016074 -317.533621)
			(xy 293.048216 -317.571462) (xy 293.073813 -317.614004) (xy 293.09219 -317.660127) (xy 293.102862 -317.708615)
			(xy 293.105549 -317.758191) (xy 293.10365 -317.775644) (xy 293.423082 -317.775644) (xy 293.423082 -317.724228)
			(xy 293.431125 -317.673446) (xy 293.447013 -317.624547) (xy 293.470356 -317.578735) (xy 293.500577 -317.537139)
			(xy 293.536933 -317.500783) (xy 293.578529 -317.470562) (xy 293.624341 -317.447219) (xy 293.67324 -317.431331)
			(xy 293.724022 -317.423288) (xy 293.775438 -317.423288) (xy 293.82622 -317.431331) (xy 293.875119 -317.447219)
			(xy 293.920931 -317.470562) (xy 293.962527 -317.500783) (xy 293.998883 -317.537139) (xy 294.029104 -317.578735)
			(xy 294.052447 -317.624547) (xy 294.068335 -317.673446) (xy 294.076378 -317.724228) (xy 294.076882 -317.749936)
			(xy 294.393886 -317.749936) (xy 294.397846 -317.700882) (xy 294.409623 -317.653098) (xy 294.428914 -317.607822)
			(xy 294.455217 -317.566226) (xy 294.487852 -317.529389) (xy 294.525973 -317.498264) (xy 294.568594 -317.473657)
			(xy 294.61461 -317.456205) (xy 294.662829 -317.446361) (xy 294.712004 -317.44438) (xy 294.760859 -317.450312)
			(xy 294.80813 -317.464004) (xy 294.852592 -317.485102) (xy 294.893095 -317.513058) (xy 294.928588 -317.54715)
			(xy 294.958153 -317.586494) (xy 294.981024 -317.630071) (xy 294.996608 -317.676752) (xy 295.004503 -317.725329)
			(xy 295.004998 -317.749936) (xy 295.004503 -317.774543) (xy 295.004324 -317.775644) (xy 295.323256 -317.775644)
			(xy 295.323256 -317.724228) (xy 295.331299 -317.673446) (xy 295.347187 -317.624547) (xy 295.37053 -317.578735)
			(xy 295.400751 -317.537139) (xy 295.437107 -317.500783) (xy 295.478703 -317.470562) (xy 295.524515 -317.447219)
			(xy 295.573414 -317.431331) (xy 295.624196 -317.423288) (xy 295.675612 -317.423288) (xy 295.726394 -317.431331)
			(xy 295.775293 -317.447219) (xy 295.821105 -317.470562) (xy 295.862701 -317.500783) (xy 295.899057 -317.537139)
			(xy 295.929278 -317.578735) (xy 295.952621 -317.624547) (xy 295.968509 -317.673446) (xy 295.976552 -317.724228)
			(xy 295.977056 -317.749936) (xy 296.29406 -317.749936) (xy 296.29802 -317.700882) (xy 296.309797 -317.653098)
			(xy 296.329088 -317.607822) (xy 296.355391 -317.566226) (xy 296.388026 -317.529389) (xy 296.426147 -317.498264)
			(xy 296.468768 -317.473657) (xy 296.514784 -317.456205) (xy 296.563003 -317.446361) (xy 296.612178 -317.44438)
			(xy 296.661033 -317.450312) (xy 296.708304 -317.464004) (xy 296.752766 -317.485102) (xy 296.793269 -317.513058)
			(xy 296.828762 -317.54715) (xy 296.858327 -317.586494) (xy 296.881198 -317.630071) (xy 296.896782 -317.676752)
			(xy 296.904677 -317.725329) (xy 296.905172 -317.749936) (xy 296.904677 -317.774543) (xy 296.904498 -317.775644)
			(xy 297.223176 -317.775644) (xy 297.223176 -317.724228) (xy 297.231219 -317.673446) (xy 297.247107 -317.624547)
			(xy 297.27045 -317.578735) (xy 297.300671 -317.537139) (xy 297.337027 -317.500783) (xy 297.378623 -317.470562)
			(xy 297.424435 -317.447219) (xy 297.473334 -317.431331) (xy 297.524116 -317.423288) (xy 297.575532 -317.423288)
			(xy 297.626314 -317.431331) (xy 297.675213 -317.447219) (xy 297.721025 -317.470562) (xy 297.762621 -317.500783)
			(xy 297.798977 -317.537139) (xy 297.829198 -317.578735) (xy 297.852541 -317.624547) (xy 297.868429 -317.673446)
			(xy 297.876472 -317.724228) (xy 297.876976 -317.749936) (xy 298.19398 -317.749936) (xy 298.19794 -317.700882)
			(xy 298.209717 -317.653098) (xy 298.229008 -317.607822) (xy 298.255311 -317.566226) (xy 298.287946 -317.529389)
			(xy 298.326067 -317.498264) (xy 298.368688 -317.473657) (xy 298.414704 -317.456205) (xy 298.462923 -317.446361)
			(xy 298.512098 -317.44438) (xy 298.560953 -317.450312) (xy 298.608224 -317.464004) (xy 298.652686 -317.485102)
			(xy 298.693189 -317.513058) (xy 298.728682 -317.54715) (xy 298.758247 -317.586494) (xy 298.781118 -317.630071)
			(xy 298.796702 -317.676752) (xy 298.804597 -317.725329) (xy 298.805092 -317.749936) (xy 298.804597 -317.774543)
			(xy 298.804418 -317.775644) (xy 299.123096 -317.775644) (xy 299.123096 -317.724228) (xy 299.131139 -317.673446)
			(xy 299.147027 -317.624547) (xy 299.17037 -317.578735) (xy 299.200591 -317.537139) (xy 299.236947 -317.500783)
			(xy 299.278543 -317.470562) (xy 299.324355 -317.447219) (xy 299.373254 -317.431331) (xy 299.424036 -317.423288)
			(xy 299.475452 -317.423288) (xy 299.526234 -317.431331) (xy 299.575133 -317.447219) (xy 299.620945 -317.470562)
			(xy 299.662541 -317.500783) (xy 299.698897 -317.537139) (xy 299.729118 -317.578735) (xy 299.752461 -317.624547)
			(xy 299.768349 -317.673446) (xy 299.776392 -317.724228) (xy 299.776896 -317.749936) (xy 300.0939 -317.749936)
			(xy 300.09786 -317.700882) (xy 300.109637 -317.653098) (xy 300.128928 -317.607822) (xy 300.155231 -317.566226)
			(xy 300.187866 -317.529389) (xy 300.225987 -317.498264) (xy 300.268608 -317.473657) (xy 300.314624 -317.456205)
			(xy 300.362843 -317.446361) (xy 300.412018 -317.44438) (xy 300.460873 -317.450312) (xy 300.508144 -317.464004)
			(xy 300.552606 -317.485102) (xy 300.593109 -317.513058) (xy 300.628602 -317.54715) (xy 300.658167 -317.586494)
			(xy 300.681038 -317.630071) (xy 300.696622 -317.676752) (xy 300.704517 -317.725329) (xy 300.705012 -317.749936)
			(xy 300.704517 -317.774543) (xy 300.704338 -317.775644) (xy 301.02327 -317.775644) (xy 301.02327 -317.724228)
			(xy 301.031313 -317.673446) (xy 301.047201 -317.624547) (xy 301.070544 -317.578735) (xy 301.100765 -317.537139)
			(xy 301.137121 -317.500783) (xy 301.178717 -317.470562) (xy 301.224529 -317.447219) (xy 301.273428 -317.431331)
			(xy 301.32421 -317.423288) (xy 301.375626 -317.423288) (xy 301.426408 -317.431331) (xy 301.475307 -317.447219)
			(xy 301.521119 -317.470562) (xy 301.562715 -317.500783) (xy 301.599071 -317.537139) (xy 301.629292 -317.578735)
			(xy 301.652635 -317.624547) (xy 301.668523 -317.673446) (xy 301.676566 -317.724228) (xy 301.67707 -317.749936)
			(xy 301.994074 -317.749936) (xy 301.998034 -317.700882) (xy 302.009811 -317.653098) (xy 302.029102 -317.607822)
			(xy 302.055405 -317.566226) (xy 302.08804 -317.529389) (xy 302.126161 -317.498264) (xy 302.168782 -317.473657)
			(xy 302.214798 -317.456205) (xy 302.263017 -317.446361) (xy 302.312192 -317.44438) (xy 302.361047 -317.450312)
			(xy 302.408318 -317.464004) (xy 302.45278 -317.485102) (xy 302.493283 -317.513058) (xy 302.528776 -317.54715)
			(xy 302.558341 -317.586494) (xy 302.581212 -317.630071) (xy 302.596796 -317.676752) (xy 302.604691 -317.725329)
			(xy 302.605186 -317.749936) (xy 302.604691 -317.774543) (xy 302.604512 -317.775644) (xy 302.92319 -317.775644)
			(xy 302.92319 -317.724228) (xy 302.931233 -317.673446) (xy 302.947121 -317.624547) (xy 302.970464 -317.578735)
			(xy 303.000685 -317.537139) (xy 303.037041 -317.500783) (xy 303.078637 -317.470562) (xy 303.124449 -317.447219)
			(xy 303.173348 -317.431331) (xy 303.22413 -317.423288) (xy 303.275546 -317.423288) (xy 303.326328 -317.431331)
			(xy 303.375227 -317.447219) (xy 303.421039 -317.470562) (xy 303.462635 -317.500783) (xy 303.498991 -317.537139)
			(xy 303.529212 -317.578735) (xy 303.552555 -317.624547) (xy 303.568443 -317.673446) (xy 303.576486 -317.724228)
			(xy 303.57699 -317.749936) (xy 303.893994 -317.749936) (xy 303.897954 -317.700882) (xy 303.909731 -317.653098)
			(xy 303.929022 -317.607822) (xy 303.955325 -317.566226) (xy 303.98796 -317.529389) (xy 304.026081 -317.498264)
			(xy 304.068702 -317.473657) (xy 304.114718 -317.456205) (xy 304.162937 -317.446361) (xy 304.212112 -317.44438)
			(xy 304.260967 -317.450312) (xy 304.308238 -317.464004) (xy 304.3527 -317.485102) (xy 304.393203 -317.513058)
			(xy 304.428696 -317.54715) (xy 304.458261 -317.586494) (xy 304.481132 -317.630071) (xy 304.496716 -317.676752)
			(xy 304.504611 -317.725329) (xy 304.505106 -317.749936) (xy 304.504611 -317.774543) (xy 304.504432 -317.775644)
			(xy 304.82311 -317.775644) (xy 304.82311 -317.724228) (xy 304.831153 -317.673446) (xy 304.847041 -317.624547)
			(xy 304.870384 -317.578735) (xy 304.900605 -317.537139) (xy 304.936961 -317.500783) (xy 304.978557 -317.470562)
			(xy 305.024369 -317.447219) (xy 305.073268 -317.431331) (xy 305.12405 -317.423288) (xy 305.175466 -317.423288)
			(xy 305.226248 -317.431331) (xy 305.275147 -317.447219) (xy 305.320959 -317.470562) (xy 305.362555 -317.500783)
			(xy 305.398911 -317.537139) (xy 305.429132 -317.578735) (xy 305.452475 -317.624547) (xy 305.468363 -317.673446)
			(xy 305.476406 -317.724228) (xy 305.47691 -317.749936) (xy 305.793914 -317.749936) (xy 305.797874 -317.700882)
			(xy 305.809651 -317.653098) (xy 305.828942 -317.607822) (xy 305.855245 -317.566226) (xy 305.88788 -317.529389)
			(xy 305.926001 -317.498264) (xy 305.968622 -317.473657) (xy 306.014638 -317.456205) (xy 306.062857 -317.446361)
			(xy 306.112032 -317.44438) (xy 306.160887 -317.450312) (xy 306.208158 -317.464004) (xy 306.25262 -317.485102)
			(xy 306.293123 -317.513058) (xy 306.328616 -317.54715) (xy 306.358181 -317.586494) (xy 306.381052 -317.630071)
			(xy 306.396636 -317.676752) (xy 306.404531 -317.725329) (xy 306.405026 -317.749936) (xy 306.744128 -317.749936)
			(xy 306.748088 -317.700882) (xy 306.759865 -317.653098) (xy 306.779156 -317.607822) (xy 306.805459 -317.566226)
			(xy 306.838094 -317.529389) (xy 306.876215 -317.498264) (xy 306.918836 -317.473657) (xy 306.964852 -317.456205)
			(xy 307.013071 -317.446361) (xy 307.062246 -317.44438) (xy 307.111101 -317.450312) (xy 307.158372 -317.464004)
			(xy 307.202834 -317.485102) (xy 307.243337 -317.513058) (xy 307.27883 -317.54715) (xy 307.308395 -317.586494)
			(xy 307.331266 -317.630071) (xy 307.34685 -317.676752) (xy 307.354745 -317.725329) (xy 307.35524 -317.749936)
			(xy 307.694088 -317.749936) (xy 307.698048 -317.700882) (xy 307.709825 -317.653098) (xy 307.729116 -317.607822)
			(xy 307.755419 -317.566226) (xy 307.788054 -317.529389) (xy 307.826175 -317.498264) (xy 307.868796 -317.473657)
			(xy 307.914812 -317.456205) (xy 307.963031 -317.446361) (xy 308.012206 -317.44438) (xy 308.061061 -317.450312)
			(xy 308.108332 -317.464004) (xy 308.152794 -317.485102) (xy 308.193297 -317.513058) (xy 308.22879 -317.54715)
			(xy 308.258355 -317.586494) (xy 308.281226 -317.630071) (xy 308.29681 -317.676752) (xy 308.304705 -317.725329)
			(xy 308.3052 -317.749936) (xy 308.644048 -317.749936) (xy 308.648008 -317.700882) (xy 308.659785 -317.653098)
			(xy 308.679076 -317.607822) (xy 308.705379 -317.566226) (xy 308.738014 -317.529389) (xy 308.776135 -317.498264)
			(xy 308.818756 -317.473657) (xy 308.864772 -317.456205) (xy 308.912991 -317.446361) (xy 308.962166 -317.44438)
			(xy 309.011021 -317.450312) (xy 309.058292 -317.464004) (xy 309.102754 -317.485102) (xy 309.143257 -317.513058)
			(xy 309.17875 -317.54715) (xy 309.208315 -317.586494) (xy 309.231186 -317.630071) (xy 309.24677 -317.676752)
			(xy 309.254665 -317.725329) (xy 309.25516 -317.749936) (xy 309.594008 -317.749936) (xy 309.597968 -317.700882)
			(xy 309.609745 -317.653098) (xy 309.629036 -317.607822) (xy 309.655339 -317.566226) (xy 309.687974 -317.529389)
			(xy 309.726095 -317.498264) (xy 309.768716 -317.473657) (xy 309.814732 -317.456205) (xy 309.862951 -317.446361)
			(xy 309.912126 -317.44438) (xy 309.960981 -317.450312) (xy 310.008252 -317.464004) (xy 310.052714 -317.485102)
			(xy 310.093217 -317.513058) (xy 310.12871 -317.54715) (xy 310.158275 -317.586494) (xy 310.181146 -317.630071)
			(xy 310.19673 -317.676752) (xy 310.204625 -317.725329) (xy 310.20512 -317.749936) (xy 310.543968 -317.749936)
			(xy 310.547928 -317.700882) (xy 310.559705 -317.653098) (xy 310.578996 -317.607822) (xy 310.605299 -317.566226)
			(xy 310.637934 -317.529389) (xy 310.676055 -317.498264) (xy 310.718676 -317.473657) (xy 310.764692 -317.456205)
			(xy 310.812911 -317.446361) (xy 310.862086 -317.44438) (xy 310.910941 -317.450312) (xy 310.958212 -317.464004)
			(xy 311.002674 -317.485102) (xy 311.043177 -317.513058) (xy 311.07867 -317.54715) (xy 311.108235 -317.586494)
			(xy 311.131106 -317.630071) (xy 311.14669 -317.676752) (xy 311.154585 -317.725329) (xy 311.15508 -317.749936)
			(xy 311.493928 -317.749936) (xy 311.497888 -317.700882) (xy 311.509665 -317.653098) (xy 311.528956 -317.607822)
			(xy 311.555259 -317.566226) (xy 311.587894 -317.529389) (xy 311.626015 -317.498264) (xy 311.668636 -317.473657)
			(xy 311.714652 -317.456205) (xy 311.762871 -317.446361) (xy 311.812046 -317.44438) (xy 311.860901 -317.450312)
			(xy 311.908172 -317.464004) (xy 311.952634 -317.485102) (xy 311.993137 -317.513058) (xy 312.02863 -317.54715)
			(xy 312.058195 -317.586494) (xy 312.081066 -317.630071) (xy 312.09665 -317.676752) (xy 312.104545 -317.725329)
			(xy 312.10504 -317.749936) (xy 312.443888 -317.749936) (xy 312.447848 -317.700882) (xy 312.459625 -317.653098)
			(xy 312.478916 -317.607822) (xy 312.505219 -317.566226) (xy 312.537854 -317.529389) (xy 312.575975 -317.498264)
			(xy 312.618596 -317.473657) (xy 312.664612 -317.456205) (xy 312.712831 -317.446361) (xy 312.762006 -317.44438)
			(xy 312.810861 -317.450312) (xy 312.858132 -317.464004) (xy 312.902594 -317.485102) (xy 312.943097 -317.513058)
			(xy 312.97859 -317.54715) (xy 313.008155 -317.586494) (xy 313.031026 -317.630071) (xy 313.04661 -317.676752)
			(xy 313.054505 -317.725329) (xy 313.055 -317.749936) (xy 313.394102 -317.749936) (xy 313.398062 -317.700882)
			(xy 313.409839 -317.653098) (xy 313.42913 -317.607822) (xy 313.455433 -317.566226) (xy 313.488068 -317.529389)
			(xy 313.526189 -317.498264) (xy 313.56881 -317.473657) (xy 313.614826 -317.456205) (xy 313.663045 -317.446361)
			(xy 313.71222 -317.44438) (xy 313.761075 -317.450312) (xy 313.808346 -317.464004) (xy 313.852808 -317.485102)
			(xy 313.893311 -317.513058) (xy 313.928804 -317.54715) (xy 313.958369 -317.586494) (xy 313.98124 -317.630071)
			(xy 313.996824 -317.676752) (xy 314.004719 -317.725329) (xy 314.005214 -317.749936) (xy 314.344062 -317.749936)
			(xy 314.348022 -317.700882) (xy 314.359799 -317.653098) (xy 314.37909 -317.607822) (xy 314.405393 -317.566226)
			(xy 314.438028 -317.529389) (xy 314.476149 -317.498264) (xy 314.51877 -317.473657) (xy 314.564786 -317.456205)
			(xy 314.613005 -317.446361) (xy 314.66218 -317.44438) (xy 314.711035 -317.450312) (xy 314.758306 -317.464004)
			(xy 314.802768 -317.485102) (xy 314.843271 -317.513058) (xy 314.878764 -317.54715) (xy 314.908329 -317.586494)
			(xy 314.9312 -317.630071) (xy 314.946784 -317.676752) (xy 314.954679 -317.725329) (xy 314.955174 -317.749936)
			(xy 314.954679 -317.774543) (xy 314.946784 -317.82312) (xy 314.9312 -317.869801) (xy 314.908329 -317.913378)
			(xy 314.878764 -317.952722) (xy 314.843271 -317.986814) (xy 314.802768 -318.01477) (xy 314.758306 -318.035868)
			(xy 314.711035 -318.04956) (xy 314.66218 -318.055492) (xy 314.613005 -318.053511) (xy 314.564786 -318.043667)
			(xy 314.51877 -318.026215) (xy 314.476149 -318.001608) (xy 314.438028 -317.970483) (xy 314.405393 -317.933646)
			(xy 314.37909 -317.89205) (xy 314.359799 -317.846774) (xy 314.348022 -317.79899) (xy 314.344062 -317.749936)
			(xy 314.005214 -317.749936) (xy 314.004719 -317.774543) (xy 313.996824 -317.82312) (xy 313.98124 -317.869801)
			(xy 313.958369 -317.913378) (xy 313.928804 -317.952722) (xy 313.893311 -317.986814) (xy 313.852808 -318.01477)
			(xy 313.808346 -318.035868) (xy 313.761075 -318.04956) (xy 313.71222 -318.055492) (xy 313.663045 -318.053511)
			(xy 313.614826 -318.043667) (xy 313.56881 -318.026215) (xy 313.526189 -318.001608) (xy 313.488068 -317.970483)
			(xy 313.455433 -317.933646) (xy 313.42913 -317.89205) (xy 313.409839 -317.846774) (xy 313.398062 -317.79899)
			(xy 313.394102 -317.749936) (xy 313.055 -317.749936) (xy 313.054505 -317.774543) (xy 313.04661 -317.82312)
			(xy 313.031026 -317.869801) (xy 313.008155 -317.913378) (xy 312.97859 -317.952722) (xy 312.943097 -317.986814)
			(xy 312.902594 -318.01477) (xy 312.858132 -318.035868) (xy 312.810861 -318.04956) (xy 312.762006 -318.055492)
			(xy 312.712831 -318.053511) (xy 312.664612 -318.043667) (xy 312.618596 -318.026215) (xy 312.575975 -318.001608)
			(xy 312.537854 -317.970483) (xy 312.505219 -317.933646) (xy 312.478916 -317.89205) (xy 312.459625 -317.846774)
			(xy 312.447848 -317.79899) (xy 312.443888 -317.749936) (xy 312.10504 -317.749936) (xy 312.104545 -317.774543)
			(xy 312.09665 -317.82312) (xy 312.081066 -317.869801) (xy 312.058195 -317.913378) (xy 312.02863 -317.952722)
			(xy 311.993137 -317.986814) (xy 311.952634 -318.01477) (xy 311.908172 -318.035868) (xy 311.860901 -318.04956)
			(xy 311.812046 -318.055492) (xy 311.762871 -318.053511) (xy 311.714652 -318.043667) (xy 311.668636 -318.026215)
			(xy 311.626015 -318.001608) (xy 311.587894 -317.970483) (xy 311.555259 -317.933646) (xy 311.528956 -317.89205)
			(xy 311.509665 -317.846774) (xy 311.497888 -317.79899) (xy 311.493928 -317.749936) (xy 311.15508 -317.749936)
			(xy 311.154585 -317.774543) (xy 311.14669 -317.82312) (xy 311.131106 -317.869801) (xy 311.108235 -317.913378)
			(xy 311.07867 -317.952722) (xy 311.043177 -317.986814) (xy 311.002674 -318.01477) (xy 310.958212 -318.035868)
			(xy 310.910941 -318.04956) (xy 310.862086 -318.055492) (xy 310.812911 -318.053511) (xy 310.764692 -318.043667)
			(xy 310.718676 -318.026215) (xy 310.676055 -318.001608) (xy 310.637934 -317.970483) (xy 310.605299 -317.933646)
			(xy 310.578996 -317.89205) (xy 310.559705 -317.846774) (xy 310.547928 -317.79899) (xy 310.543968 -317.749936)
			(xy 310.20512 -317.749936) (xy 310.204625 -317.774543) (xy 310.19673 -317.82312) (xy 310.181146 -317.869801)
			(xy 310.158275 -317.913378) (xy 310.12871 -317.952722) (xy 310.093217 -317.986814) (xy 310.052714 -318.01477)
			(xy 310.008252 -318.035868) (xy 309.960981 -318.04956) (xy 309.912126 -318.055492) (xy 309.862951 -318.053511)
			(xy 309.814732 -318.043667) (xy 309.768716 -318.026215) (xy 309.726095 -318.001608) (xy 309.687974 -317.970483)
			(xy 309.655339 -317.933646) (xy 309.629036 -317.89205) (xy 309.609745 -317.846774) (xy 309.597968 -317.79899)
			(xy 309.594008 -317.749936) (xy 309.25516 -317.749936) (xy 309.254665 -317.774543) (xy 309.24677 -317.82312)
			(xy 309.231186 -317.869801) (xy 309.208315 -317.913378) (xy 309.17875 -317.952722) (xy 309.143257 -317.986814)
			(xy 309.102754 -318.01477) (xy 309.058292 -318.035868) (xy 309.011021 -318.04956) (xy 308.962166 -318.055492)
			(xy 308.912991 -318.053511) (xy 308.864772 -318.043667) (xy 308.818756 -318.026215) (xy 308.776135 -318.001608)
			(xy 308.738014 -317.970483) (xy 308.705379 -317.933646) (xy 308.679076 -317.89205) (xy 308.659785 -317.846774)
			(xy 308.648008 -317.79899) (xy 308.644048 -317.749936) (xy 308.3052 -317.749936) (xy 308.304705 -317.774543)
			(xy 308.29681 -317.82312) (xy 308.281226 -317.869801) (xy 308.258355 -317.913378) (xy 308.22879 -317.952722)
			(xy 308.193297 -317.986814) (xy 308.152794 -318.01477) (xy 308.108332 -318.035868) (xy 308.061061 -318.04956)
			(xy 308.012206 -318.055492) (xy 307.963031 -318.053511) (xy 307.914812 -318.043667) (xy 307.868796 -318.026215)
			(xy 307.826175 -318.001608) (xy 307.788054 -317.970483) (xy 307.755419 -317.933646) (xy 307.729116 -317.89205)
			(xy 307.709825 -317.846774) (xy 307.698048 -317.79899) (xy 307.694088 -317.749936) (xy 307.35524 -317.749936)
			(xy 307.354745 -317.774543) (xy 307.34685 -317.82312) (xy 307.331266 -317.869801) (xy 307.308395 -317.913378)
			(xy 307.27883 -317.952722) (xy 307.243337 -317.986814) (xy 307.202834 -318.01477) (xy 307.158372 -318.035868)
			(xy 307.111101 -318.04956) (xy 307.062246 -318.055492) (xy 307.013071 -318.053511) (xy 306.964852 -318.043667)
			(xy 306.918836 -318.026215) (xy 306.876215 -318.001608) (xy 306.838094 -317.970483) (xy 306.805459 -317.933646)
			(xy 306.779156 -317.89205) (xy 306.759865 -317.846774) (xy 306.748088 -317.79899) (xy 306.744128 -317.749936)
			(xy 306.405026 -317.749936) (xy 306.404531 -317.774543) (xy 306.396636 -317.82312) (xy 306.381052 -317.869801)
			(xy 306.358181 -317.913378) (xy 306.328616 -317.952722) (xy 306.293123 -317.986814) (xy 306.25262 -318.01477)
			(xy 306.208158 -318.035868) (xy 306.160887 -318.04956) (xy 306.112032 -318.055492) (xy 306.062857 -318.053511)
			(xy 306.014638 -318.043667) (xy 305.968622 -318.026215) (xy 305.926001 -318.001608) (xy 305.88788 -317.970483)
			(xy 305.855245 -317.933646) (xy 305.828942 -317.89205) (xy 305.809651 -317.846774) (xy 305.797874 -317.79899)
			(xy 305.793914 -317.749936) (xy 305.47691 -317.749936) (xy 305.476406 -317.775644) (xy 305.468363 -317.826426)
			(xy 305.452475 -317.875325) (xy 305.429132 -317.921137) (xy 305.398911 -317.962733) (xy 305.362555 -317.999089)
			(xy 305.320959 -318.02931) (xy 305.275147 -318.052653) (xy 305.226248 -318.068541) (xy 305.175466 -318.076584)
			(xy 305.12405 -318.076584) (xy 305.073268 -318.068541) (xy 305.024369 -318.052653) (xy 304.978557 -318.02931)
			(xy 304.936961 -317.999089) (xy 304.900605 -317.962733) (xy 304.870384 -317.921137) (xy 304.847041 -317.875325)
			(xy 304.831153 -317.826426) (xy 304.82311 -317.775644) (xy 304.504432 -317.775644) (xy 304.496716 -317.82312)
			(xy 304.481132 -317.869801) (xy 304.458261 -317.913378) (xy 304.428696 -317.952722) (xy 304.393203 -317.986814)
			(xy 304.3527 -318.01477) (xy 304.308238 -318.035868) (xy 304.260967 -318.04956) (xy 304.212112 -318.055492)
			(xy 304.162937 -318.053511) (xy 304.114718 -318.043667) (xy 304.068702 -318.026215) (xy 304.026081 -318.001608)
			(xy 303.98796 -317.970483) (xy 303.955325 -317.933646) (xy 303.929022 -317.89205) (xy 303.909731 -317.846774)
			(xy 303.897954 -317.79899) (xy 303.893994 -317.749936) (xy 303.57699 -317.749936) (xy 303.576486 -317.775644)
			(xy 303.568443 -317.826426) (xy 303.552555 -317.875325) (xy 303.529212 -317.921137) (xy 303.498991 -317.962733)
			(xy 303.462635 -317.999089) (xy 303.421039 -318.02931) (xy 303.375227 -318.052653) (xy 303.326328 -318.068541)
			(xy 303.275546 -318.076584) (xy 303.22413 -318.076584) (xy 303.173348 -318.068541) (xy 303.124449 -318.052653)
			(xy 303.078637 -318.02931) (xy 303.037041 -317.999089) (xy 303.000685 -317.962733) (xy 302.970464 -317.921137)
			(xy 302.947121 -317.875325) (xy 302.931233 -317.826426) (xy 302.92319 -317.775644) (xy 302.604512 -317.775644)
			(xy 302.596796 -317.82312) (xy 302.581212 -317.869801) (xy 302.558341 -317.913378) (xy 302.528776 -317.952722)
			(xy 302.493283 -317.986814) (xy 302.45278 -318.01477) (xy 302.408318 -318.035868) (xy 302.361047 -318.04956)
			(xy 302.312192 -318.055492) (xy 302.263017 -318.053511) (xy 302.214798 -318.043667) (xy 302.168782 -318.026215)
			(xy 302.126161 -318.001608) (xy 302.08804 -317.970483) (xy 302.055405 -317.933646) (xy 302.029102 -317.89205)
			(xy 302.009811 -317.846774) (xy 301.998034 -317.79899) (xy 301.994074 -317.749936) (xy 301.67707 -317.749936)
			(xy 301.676566 -317.775644) (xy 301.668523 -317.826426) (xy 301.652635 -317.875325) (xy 301.629292 -317.921137)
			(xy 301.599071 -317.962733) (xy 301.562715 -317.999089) (xy 301.521119 -318.02931) (xy 301.475307 -318.052653)
			(xy 301.426408 -318.068541) (xy 301.375626 -318.076584) (xy 301.32421 -318.076584) (xy 301.273428 -318.068541)
			(xy 301.224529 -318.052653) (xy 301.178717 -318.02931) (xy 301.137121 -317.999089) (xy 301.100765 -317.962733)
			(xy 301.070544 -317.921137) (xy 301.047201 -317.875325) (xy 301.031313 -317.826426) (xy 301.02327 -317.775644)
			(xy 300.704338 -317.775644) (xy 300.696622 -317.82312) (xy 300.681038 -317.869801) (xy 300.658167 -317.913378)
			(xy 300.628602 -317.952722) (xy 300.593109 -317.986814) (xy 300.552606 -318.01477) (xy 300.508144 -318.035868)
			(xy 300.460873 -318.04956) (xy 300.412018 -318.055492) (xy 300.362843 -318.053511) (xy 300.314624 -318.043667)
			(xy 300.268608 -318.026215) (xy 300.225987 -318.001608) (xy 300.187866 -317.970483) (xy 300.155231 -317.933646)
			(xy 300.128928 -317.89205) (xy 300.109637 -317.846774) (xy 300.09786 -317.79899) (xy 300.0939 -317.749936)
			(xy 299.776896 -317.749936) (xy 299.776392 -317.775644) (xy 299.768349 -317.826426) (xy 299.752461 -317.875325)
			(xy 299.729118 -317.921137) (xy 299.698897 -317.962733) (xy 299.662541 -317.999089) (xy 299.620945 -318.02931)
			(xy 299.575133 -318.052653) (xy 299.526234 -318.068541) (xy 299.475452 -318.076584) (xy 299.424036 -318.076584)
			(xy 299.373254 -318.068541) (xy 299.324355 -318.052653) (xy 299.278543 -318.02931) (xy 299.236947 -317.999089)
			(xy 299.200591 -317.962733) (xy 299.17037 -317.921137) (xy 299.147027 -317.875325) (xy 299.131139 -317.826426)
			(xy 299.123096 -317.775644) (xy 298.804418 -317.775644) (xy 298.796702 -317.82312) (xy 298.781118 -317.869801)
			(xy 298.758247 -317.913378) (xy 298.728682 -317.952722) (xy 298.693189 -317.986814) (xy 298.652686 -318.01477)
			(xy 298.608224 -318.035868) (xy 298.560953 -318.04956) (xy 298.512098 -318.055492) (xy 298.462923 -318.053511)
			(xy 298.414704 -318.043667) (xy 298.368688 -318.026215) (xy 298.326067 -318.001608) (xy 298.287946 -317.970483)
			(xy 298.255311 -317.933646) (xy 298.229008 -317.89205) (xy 298.209717 -317.846774) (xy 298.19794 -317.79899)
			(xy 298.19398 -317.749936) (xy 297.876976 -317.749936) (xy 297.876472 -317.775644) (xy 297.868429 -317.826426)
			(xy 297.852541 -317.875325) (xy 297.829198 -317.921137) (xy 297.798977 -317.962733) (xy 297.762621 -317.999089)
			(xy 297.721025 -318.02931) (xy 297.675213 -318.052653) (xy 297.626314 -318.068541) (xy 297.575532 -318.076584)
			(xy 297.524116 -318.076584) (xy 297.473334 -318.068541) (xy 297.424435 -318.052653) (xy 297.378623 -318.02931)
			(xy 297.337027 -317.999089) (xy 297.300671 -317.962733) (xy 297.27045 -317.921137) (xy 297.247107 -317.875325)
			(xy 297.231219 -317.826426) (xy 297.223176 -317.775644) (xy 296.904498 -317.775644) (xy 296.896782 -317.82312)
			(xy 296.881198 -317.869801) (xy 296.858327 -317.913378) (xy 296.828762 -317.952722) (xy 296.793269 -317.986814)
			(xy 296.752766 -318.01477) (xy 296.708304 -318.035868) (xy 296.661033 -318.04956) (xy 296.612178 -318.055492)
			(xy 296.563003 -318.053511) (xy 296.514784 -318.043667) (xy 296.468768 -318.026215) (xy 296.426147 -318.001608)
			(xy 296.388026 -317.970483) (xy 296.355391 -317.933646) (xy 296.329088 -317.89205) (xy 296.309797 -317.846774)
			(xy 296.29802 -317.79899) (xy 296.29406 -317.749936) (xy 295.977056 -317.749936) (xy 295.976552 -317.775644)
			(xy 295.968509 -317.826426) (xy 295.952621 -317.875325) (xy 295.929278 -317.921137) (xy 295.899057 -317.962733)
			(xy 295.862701 -317.999089) (xy 295.821105 -318.02931) (xy 295.775293 -318.052653) (xy 295.726394 -318.068541)
			(xy 295.675612 -318.076584) (xy 295.624196 -318.076584) (xy 295.573414 -318.068541) (xy 295.524515 -318.052653)
			(xy 295.478703 -318.02931) (xy 295.437107 -317.999089) (xy 295.400751 -317.962733) (xy 295.37053 -317.921137)
			(xy 295.347187 -317.875325) (xy 295.331299 -317.826426) (xy 295.323256 -317.775644) (xy 295.004324 -317.775644)
			(xy 294.996608 -317.82312) (xy 294.981024 -317.869801) (xy 294.958153 -317.913378) (xy 294.928588 -317.952722)
			(xy 294.893095 -317.986814) (xy 294.852592 -318.01477) (xy 294.80813 -318.035868) (xy 294.760859 -318.04956)
			(xy 294.712004 -318.055492) (xy 294.662829 -318.053511) (xy 294.61461 -318.043667) (xy 294.568594 -318.026215)
			(xy 294.525973 -318.001608) (xy 294.487852 -317.970483) (xy 294.455217 -317.933646) (xy 294.428914 -317.89205)
			(xy 294.409623 -317.846774) (xy 294.397846 -317.79899) (xy 294.393886 -317.749936) (xy 294.076882 -317.749936)
			(xy 294.076378 -317.775644) (xy 294.068335 -317.826426) (xy 294.052447 -317.875325) (xy 294.029104 -317.921137)
			(xy 293.998883 -317.962733) (xy 293.962527 -317.999089) (xy 293.920931 -318.02931) (xy 293.875119 -318.052653)
			(xy 293.82622 -318.068541) (xy 293.775438 -318.076584) (xy 293.724022 -318.076584) (xy 293.67324 -318.068541)
			(xy 293.624341 -318.052653) (xy 293.578529 -318.02931) (xy 293.536933 -317.999089) (xy 293.500577 -317.962733)
			(xy 293.470356 -317.921137) (xy 293.447013 -317.875325) (xy 293.431125 -317.826426) (xy 293.423082 -317.775644)
			(xy 293.10365 -317.775644) (xy 293.100179 -317.807549) (xy 293.086895 -317.855387) (xy 293.066046 -317.900446)
			(xy 293.038181 -317.941539) (xy 293.004036 -317.977581) (xy 292.964508 -318.007625) (xy 292.920641 -318.030877)
			(xy 292.87359 -318.046727) (xy 292.824594 -318.054754) (xy 292.79977 -318.055244) (xy 292.790669 -318.055204)
			(xy 292.772497 -318.054185) (xy 292.763448 -318.053212) (xy 292.75151 -318.051688) (xy 292.729158 -318.059562)
			(xy 292.65626 -318.136016) (xy 292.649148 -318.158622) (xy 292.65118 -318.17056) (xy 292.653309 -318.184048)
			(xy 292.655597 -318.211262) (xy 292.655752 -318.224916) (xy 292.655752 -318.295274) (xy 292.656208 -318.305934)
			(xy 292.66489 -318.325403) (xy 292.672516 -318.332866) (xy 292.736778 -318.390778) (xy 292.757098 -318.397382)
			(xy 292.76802 -318.396366) (xy 292.79977 -318.394588) (xy 292.82503 -318.395078) (xy 292.874861 -318.403389)
			(xy 292.922644 -318.419789) (xy 292.967076 -318.443831) (xy 293.006944 -318.474858) (xy 293.041162 -318.512024)
			(xy 293.068795 -318.554316) (xy 293.089089 -318.60058) (xy 293.101492 -318.649553) (xy 293.105664 -318.6999)
			(xy 293.103534 -318.725604) (xy 293.423082 -318.725604) (xy 293.423082 -318.674188) (xy 293.431125 -318.623406)
			(xy 293.447013 -318.574507) (xy 293.470356 -318.528695) (xy 293.500577 -318.487099) (xy 293.536933 -318.450743)
			(xy 293.578529 -318.420522) (xy 293.624341 -318.397179) (xy 293.67324 -318.381291) (xy 293.724022 -318.373248)
			(xy 293.775438 -318.373248) (xy 293.82622 -318.381291) (xy 293.875119 -318.397179) (xy 293.920931 -318.420522)
			(xy 293.962527 -318.450743) (xy 293.998883 -318.487099) (xy 294.029104 -318.528695) (xy 294.052447 -318.574507)
			(xy 294.068335 -318.623406) (xy 294.076378 -318.674188) (xy 294.076882 -318.699896) (xy 294.393886 -318.699896)
			(xy 294.397846 -318.650842) (xy 294.409623 -318.603058) (xy 294.428914 -318.557782) (xy 294.455217 -318.516186)
			(xy 294.487852 -318.479349) (xy 294.525973 -318.448224) (xy 294.568594 -318.423617) (xy 294.61461 -318.406165)
			(xy 294.662829 -318.396321) (xy 294.712004 -318.39434) (xy 294.760859 -318.400272) (xy 294.80813 -318.413964)
			(xy 294.852592 -318.435062) (xy 294.893095 -318.463018) (xy 294.928588 -318.49711) (xy 294.958153 -318.536454)
			(xy 294.981024 -318.580031) (xy 294.996608 -318.626712) (xy 295.004503 -318.675289) (xy 295.004998 -318.699896)
			(xy 295.004503 -318.724503) (xy 295.004324 -318.725604) (xy 295.323256 -318.725604) (xy 295.323256 -318.674188)
			(xy 295.331299 -318.623406) (xy 295.347187 -318.574507) (xy 295.37053 -318.528695) (xy 295.400751 -318.487099)
			(xy 295.437107 -318.450743) (xy 295.478703 -318.420522) (xy 295.524515 -318.397179) (xy 295.573414 -318.381291)
			(xy 295.624196 -318.373248) (xy 295.675612 -318.373248) (xy 295.726394 -318.381291) (xy 295.775293 -318.397179)
			(xy 295.821105 -318.420522) (xy 295.862701 -318.450743) (xy 295.899057 -318.487099) (xy 295.929278 -318.528695)
			(xy 295.952621 -318.574507) (xy 295.968509 -318.623406) (xy 295.976552 -318.674188) (xy 295.977056 -318.699896)
			(xy 296.29406 -318.699896) (xy 296.29802 -318.650842) (xy 296.309797 -318.603058) (xy 296.329088 -318.557782)
			(xy 296.355391 -318.516186) (xy 296.388026 -318.479349) (xy 296.426147 -318.448224) (xy 296.468768 -318.423617)
			(xy 296.514784 -318.406165) (xy 296.563003 -318.396321) (xy 296.612178 -318.39434) (xy 296.661033 -318.400272)
			(xy 296.708304 -318.413964) (xy 296.752766 -318.435062) (xy 296.793269 -318.463018) (xy 296.828762 -318.49711)
			(xy 296.858327 -318.536454) (xy 296.881198 -318.580031) (xy 296.896782 -318.626712) (xy 296.904677 -318.675289)
			(xy 296.905172 -318.699896) (xy 296.904677 -318.724503) (xy 296.904498 -318.725604) (xy 297.223176 -318.725604)
			(xy 297.223176 -318.674188) (xy 297.231219 -318.623406) (xy 297.247107 -318.574507) (xy 297.27045 -318.528695)
			(xy 297.300671 -318.487099) (xy 297.337027 -318.450743) (xy 297.378623 -318.420522) (xy 297.424435 -318.397179)
			(xy 297.473334 -318.381291) (xy 297.524116 -318.373248) (xy 297.575532 -318.373248) (xy 297.626314 -318.381291)
			(xy 297.675213 -318.397179) (xy 297.721025 -318.420522) (xy 297.762621 -318.450743) (xy 297.798977 -318.487099)
			(xy 297.829198 -318.528695) (xy 297.852541 -318.574507) (xy 297.868429 -318.623406) (xy 297.876472 -318.674188)
			(xy 297.876976 -318.699896) (xy 298.19398 -318.699896) (xy 298.19794 -318.650842) (xy 298.209717 -318.603058)
			(xy 298.229008 -318.557782) (xy 298.255311 -318.516186) (xy 298.287946 -318.479349) (xy 298.326067 -318.448224)
			(xy 298.368688 -318.423617) (xy 298.414704 -318.406165) (xy 298.462923 -318.396321) (xy 298.512098 -318.39434)
			(xy 298.560953 -318.400272) (xy 298.608224 -318.413964) (xy 298.652686 -318.435062) (xy 298.693189 -318.463018)
			(xy 298.728682 -318.49711) (xy 298.758247 -318.536454) (xy 298.781118 -318.580031) (xy 298.796702 -318.626712)
			(xy 298.804597 -318.675289) (xy 298.805092 -318.699896) (xy 298.804597 -318.724503) (xy 298.804418 -318.725604)
			(xy 299.123096 -318.725604) (xy 299.123096 -318.674188) (xy 299.131139 -318.623406) (xy 299.147027 -318.574507)
			(xy 299.17037 -318.528695) (xy 299.200591 -318.487099) (xy 299.236947 -318.450743) (xy 299.278543 -318.420522)
			(xy 299.324355 -318.397179) (xy 299.373254 -318.381291) (xy 299.424036 -318.373248) (xy 299.475452 -318.373248)
			(xy 299.526234 -318.381291) (xy 299.575133 -318.397179) (xy 299.620945 -318.420522) (xy 299.662541 -318.450743)
			(xy 299.698897 -318.487099) (xy 299.729118 -318.528695) (xy 299.752461 -318.574507) (xy 299.768349 -318.623406)
			(xy 299.776392 -318.674188) (xy 299.776896 -318.699896) (xy 300.0939 -318.699896) (xy 300.09786 -318.650842)
			(xy 300.109637 -318.603058) (xy 300.128928 -318.557782) (xy 300.155231 -318.516186) (xy 300.187866 -318.479349)
			(xy 300.225987 -318.448224) (xy 300.268608 -318.423617) (xy 300.314624 -318.406165) (xy 300.362843 -318.396321)
			(xy 300.412018 -318.39434) (xy 300.460873 -318.400272) (xy 300.508144 -318.413964) (xy 300.552606 -318.435062)
			(xy 300.593109 -318.463018) (xy 300.628602 -318.49711) (xy 300.658167 -318.536454) (xy 300.681038 -318.580031)
			(xy 300.696622 -318.626712) (xy 300.704517 -318.675289) (xy 300.705012 -318.699896) (xy 300.704517 -318.724503)
			(xy 300.704338 -318.725604) (xy 301.02327 -318.725604) (xy 301.02327 -318.674188) (xy 301.031313 -318.623406)
			(xy 301.047201 -318.574507) (xy 301.070544 -318.528695) (xy 301.100765 -318.487099) (xy 301.137121 -318.450743)
			(xy 301.178717 -318.420522) (xy 301.224529 -318.397179) (xy 301.273428 -318.381291) (xy 301.32421 -318.373248)
			(xy 301.375626 -318.373248) (xy 301.426408 -318.381291) (xy 301.475307 -318.397179) (xy 301.521119 -318.420522)
			(xy 301.562715 -318.450743) (xy 301.599071 -318.487099) (xy 301.629292 -318.528695) (xy 301.652635 -318.574507)
			(xy 301.668523 -318.623406) (xy 301.676566 -318.674188) (xy 301.67707 -318.699896) (xy 301.994074 -318.699896)
			(xy 301.998034 -318.650842) (xy 302.009811 -318.603058) (xy 302.029102 -318.557782) (xy 302.055405 -318.516186)
			(xy 302.08804 -318.479349) (xy 302.126161 -318.448224) (xy 302.168782 -318.423617) (xy 302.214798 -318.406165)
			(xy 302.263017 -318.396321) (xy 302.312192 -318.39434) (xy 302.361047 -318.400272) (xy 302.408318 -318.413964)
			(xy 302.45278 -318.435062) (xy 302.493283 -318.463018) (xy 302.528776 -318.49711) (xy 302.558341 -318.536454)
			(xy 302.581212 -318.580031) (xy 302.596796 -318.626712) (xy 302.604691 -318.675289) (xy 302.605186 -318.699896)
			(xy 302.604691 -318.724503) (xy 302.604512 -318.725604) (xy 302.92319 -318.725604) (xy 302.92319 -318.674188)
			(xy 302.931233 -318.623406) (xy 302.947121 -318.574507) (xy 302.970464 -318.528695) (xy 303.000685 -318.487099)
			(xy 303.037041 -318.450743) (xy 303.078637 -318.420522) (xy 303.124449 -318.397179) (xy 303.173348 -318.381291)
			(xy 303.22413 -318.373248) (xy 303.275546 -318.373248) (xy 303.326328 -318.381291) (xy 303.375227 -318.397179)
			(xy 303.421039 -318.420522) (xy 303.462635 -318.450743) (xy 303.498991 -318.487099) (xy 303.529212 -318.528695)
			(xy 303.552555 -318.574507) (xy 303.568443 -318.623406) (xy 303.576486 -318.674188) (xy 303.57699 -318.699896)
			(xy 303.893994 -318.699896) (xy 303.897954 -318.650842) (xy 303.909731 -318.603058) (xy 303.929022 -318.557782)
			(xy 303.955325 -318.516186) (xy 303.98796 -318.479349) (xy 304.026081 -318.448224) (xy 304.068702 -318.423617)
			(xy 304.114718 -318.406165) (xy 304.162937 -318.396321) (xy 304.212112 -318.39434) (xy 304.260967 -318.400272)
			(xy 304.308238 -318.413964) (xy 304.3527 -318.435062) (xy 304.393203 -318.463018) (xy 304.428696 -318.49711)
			(xy 304.458261 -318.536454) (xy 304.481132 -318.580031) (xy 304.496716 -318.626712) (xy 304.504611 -318.675289)
			(xy 304.505106 -318.699896) (xy 304.504611 -318.724503) (xy 304.504432 -318.725604) (xy 304.82311 -318.725604)
			(xy 304.82311 -318.674188) (xy 304.831153 -318.623406) (xy 304.847041 -318.574507) (xy 304.870384 -318.528695)
			(xy 304.900605 -318.487099) (xy 304.936961 -318.450743) (xy 304.978557 -318.420522) (xy 305.024369 -318.397179)
			(xy 305.073268 -318.381291) (xy 305.12405 -318.373248) (xy 305.175466 -318.373248) (xy 305.226248 -318.381291)
			(xy 305.275147 -318.397179) (xy 305.320959 -318.420522) (xy 305.362555 -318.450743) (xy 305.398911 -318.487099)
			(xy 305.429132 -318.528695) (xy 305.452475 -318.574507) (xy 305.468363 -318.623406) (xy 305.476406 -318.674188)
			(xy 305.47691 -318.699896) (xy 305.793914 -318.699896) (xy 305.797874 -318.650842) (xy 305.809651 -318.603058)
			(xy 305.828942 -318.557782) (xy 305.855245 -318.516186) (xy 305.88788 -318.479349) (xy 305.926001 -318.448224)
			(xy 305.968622 -318.423617) (xy 306.014638 -318.406165) (xy 306.062857 -318.396321) (xy 306.112032 -318.39434)
			(xy 306.160887 -318.400272) (xy 306.208158 -318.413964) (xy 306.25262 -318.435062) (xy 306.293123 -318.463018)
			(xy 306.328616 -318.49711) (xy 306.358181 -318.536454) (xy 306.381052 -318.580031) (xy 306.396636 -318.626712)
			(xy 306.404531 -318.675289) (xy 306.405026 -318.699896) (xy 306.744128 -318.699896) (xy 306.748088 -318.650842)
			(xy 306.759865 -318.603058) (xy 306.779156 -318.557782) (xy 306.805459 -318.516186) (xy 306.838094 -318.479349)
			(xy 306.876215 -318.448224) (xy 306.918836 -318.423617) (xy 306.964852 -318.406165) (xy 307.013071 -318.396321)
			(xy 307.062246 -318.39434) (xy 307.111101 -318.400272) (xy 307.158372 -318.413964) (xy 307.202834 -318.435062)
			(xy 307.243337 -318.463018) (xy 307.27883 -318.49711) (xy 307.308395 -318.536454) (xy 307.331266 -318.580031)
			(xy 307.34685 -318.626712) (xy 307.354745 -318.675289) (xy 307.35524 -318.699896) (xy 307.694088 -318.699896)
			(xy 307.698048 -318.650842) (xy 307.709825 -318.603058) (xy 307.729116 -318.557782) (xy 307.755419 -318.516186)
			(xy 307.788054 -318.479349) (xy 307.826175 -318.448224) (xy 307.868796 -318.423617) (xy 307.914812 -318.406165)
			(xy 307.963031 -318.396321) (xy 308.012206 -318.39434) (xy 308.061061 -318.400272) (xy 308.108332 -318.413964)
			(xy 308.152794 -318.435062) (xy 308.193297 -318.463018) (xy 308.22879 -318.49711) (xy 308.258355 -318.536454)
			(xy 308.281226 -318.580031) (xy 308.29681 -318.626712) (xy 308.304705 -318.675289) (xy 308.3052 -318.699896)
			(xy 308.644048 -318.699896) (xy 308.648008 -318.650842) (xy 308.659785 -318.603058) (xy 308.679076 -318.557782)
			(xy 308.705379 -318.516186) (xy 308.738014 -318.479349) (xy 308.776135 -318.448224) (xy 308.818756 -318.423617)
			(xy 308.864772 -318.406165) (xy 308.912991 -318.396321) (xy 308.962166 -318.39434) (xy 309.011021 -318.400272)
			(xy 309.058292 -318.413964) (xy 309.102754 -318.435062) (xy 309.143257 -318.463018) (xy 309.17875 -318.49711)
			(xy 309.208315 -318.536454) (xy 309.231186 -318.580031) (xy 309.24677 -318.626712) (xy 309.254665 -318.675289)
			(xy 309.25516 -318.699896) (xy 309.594008 -318.699896) (xy 309.597968 -318.650842) (xy 309.609745 -318.603058)
			(xy 309.629036 -318.557782) (xy 309.655339 -318.516186) (xy 309.687974 -318.479349) (xy 309.726095 -318.448224)
			(xy 309.768716 -318.423617) (xy 309.814732 -318.406165) (xy 309.862951 -318.396321) (xy 309.912126 -318.39434)
			(xy 309.960981 -318.400272) (xy 310.008252 -318.413964) (xy 310.052714 -318.435062) (xy 310.093217 -318.463018)
			(xy 310.12871 -318.49711) (xy 310.158275 -318.536454) (xy 310.181146 -318.580031) (xy 310.19673 -318.626712)
			(xy 310.204625 -318.675289) (xy 310.20512 -318.699896) (xy 310.543968 -318.699896) (xy 310.547928 -318.650842)
			(xy 310.559705 -318.603058) (xy 310.578996 -318.557782) (xy 310.605299 -318.516186) (xy 310.637934 -318.479349)
			(xy 310.676055 -318.448224) (xy 310.718676 -318.423617) (xy 310.764692 -318.406165) (xy 310.812911 -318.396321)
			(xy 310.862086 -318.39434) (xy 310.910941 -318.400272) (xy 310.958212 -318.413964) (xy 311.002674 -318.435062)
			(xy 311.043177 -318.463018) (xy 311.07867 -318.49711) (xy 311.108235 -318.536454) (xy 311.131106 -318.580031)
			(xy 311.14669 -318.626712) (xy 311.154585 -318.675289) (xy 311.15508 -318.699896) (xy 311.493928 -318.699896)
			(xy 311.497888 -318.650842) (xy 311.509665 -318.603058) (xy 311.528956 -318.557782) (xy 311.555259 -318.516186)
			(xy 311.587894 -318.479349) (xy 311.626015 -318.448224) (xy 311.668636 -318.423617) (xy 311.714652 -318.406165)
			(xy 311.762871 -318.396321) (xy 311.812046 -318.39434) (xy 311.860901 -318.400272) (xy 311.908172 -318.413964)
			(xy 311.952634 -318.435062) (xy 311.993137 -318.463018) (xy 312.02863 -318.49711) (xy 312.058195 -318.536454)
			(xy 312.081066 -318.580031) (xy 312.09665 -318.626712) (xy 312.104545 -318.675289) (xy 312.10504 -318.699896)
			(xy 312.443888 -318.699896) (xy 312.447848 -318.650842) (xy 312.459625 -318.603058) (xy 312.478916 -318.557782)
			(xy 312.505219 -318.516186) (xy 312.537854 -318.479349) (xy 312.575975 -318.448224) (xy 312.618596 -318.423617)
			(xy 312.664612 -318.406165) (xy 312.712831 -318.396321) (xy 312.762006 -318.39434) (xy 312.810861 -318.400272)
			(xy 312.858132 -318.413964) (xy 312.902594 -318.435062) (xy 312.943097 -318.463018) (xy 312.97859 -318.49711)
			(xy 313.008155 -318.536454) (xy 313.031026 -318.580031) (xy 313.04661 -318.626712) (xy 313.054505 -318.675289)
			(xy 313.055 -318.699896) (xy 313.394102 -318.699896) (xy 313.398062 -318.650842) (xy 313.409839 -318.603058)
			(xy 313.42913 -318.557782) (xy 313.455433 -318.516186) (xy 313.488068 -318.479349) (xy 313.526189 -318.448224)
			(xy 313.56881 -318.423617) (xy 313.614826 -318.406165) (xy 313.663045 -318.396321) (xy 313.71222 -318.39434)
			(xy 313.761075 -318.400272) (xy 313.808346 -318.413964) (xy 313.852808 -318.435062) (xy 313.893311 -318.463018)
			(xy 313.928804 -318.49711) (xy 313.958369 -318.536454) (xy 313.98124 -318.580031) (xy 313.996824 -318.626712)
			(xy 314.004719 -318.675289) (xy 314.005214 -318.699896) (xy 314.004719 -318.724503) (xy 313.996824 -318.77308)
			(xy 313.98124 -318.819761) (xy 313.958369 -318.863338) (xy 313.928804 -318.902682) (xy 313.893311 -318.936774)
			(xy 313.852808 -318.96473) (xy 313.808346 -318.985828) (xy 313.761075 -318.99952) (xy 313.71222 -319.005452)
			(xy 313.663045 -319.003471) (xy 313.614826 -318.993627) (xy 313.56881 -318.976175) (xy 313.526189 -318.951568)
			(xy 313.488068 -318.920443) (xy 313.455433 -318.883606) (xy 313.42913 -318.84201) (xy 313.409839 -318.796734)
			(xy 313.398062 -318.74895) (xy 313.394102 -318.699896) (xy 313.055 -318.699896) (xy 313.054505 -318.724503)
			(xy 313.04661 -318.77308) (xy 313.031026 -318.819761) (xy 313.008155 -318.863338) (xy 312.97859 -318.902682)
			(xy 312.943097 -318.936774) (xy 312.902594 -318.96473) (xy 312.858132 -318.985828) (xy 312.810861 -318.99952)
			(xy 312.762006 -319.005452) (xy 312.712831 -319.003471) (xy 312.664612 -318.993627) (xy 312.618596 -318.976175)
			(xy 312.575975 -318.951568) (xy 312.537854 -318.920443) (xy 312.505219 -318.883606) (xy 312.478916 -318.84201)
			(xy 312.459625 -318.796734) (xy 312.447848 -318.74895) (xy 312.443888 -318.699896) (xy 312.10504 -318.699896)
			(xy 312.104545 -318.724503) (xy 312.09665 -318.77308) (xy 312.081066 -318.819761) (xy 312.058195 -318.863338)
			(xy 312.02863 -318.902682) (xy 311.993137 -318.936774) (xy 311.952634 -318.96473) (xy 311.908172 -318.985828)
			(xy 311.860901 -318.99952) (xy 311.812046 -319.005452) (xy 311.762871 -319.003471) (xy 311.714652 -318.993627)
			(xy 311.668636 -318.976175) (xy 311.626015 -318.951568) (xy 311.587894 -318.920443) (xy 311.555259 -318.883606)
			(xy 311.528956 -318.84201) (xy 311.509665 -318.796734) (xy 311.497888 -318.74895) (xy 311.493928 -318.699896)
			(xy 311.15508 -318.699896) (xy 311.154585 -318.724503) (xy 311.14669 -318.77308) (xy 311.131106 -318.819761)
			(xy 311.108235 -318.863338) (xy 311.07867 -318.902682) (xy 311.043177 -318.936774) (xy 311.002674 -318.96473)
			(xy 310.958212 -318.985828) (xy 310.910941 -318.99952) (xy 310.862086 -319.005452) (xy 310.812911 -319.003471)
			(xy 310.764692 -318.993627) (xy 310.718676 -318.976175) (xy 310.676055 -318.951568) (xy 310.637934 -318.920443)
			(xy 310.605299 -318.883606) (xy 310.578996 -318.84201) (xy 310.559705 -318.796734) (xy 310.547928 -318.74895)
			(xy 310.543968 -318.699896) (xy 310.20512 -318.699896) (xy 310.204625 -318.724503) (xy 310.19673 -318.77308)
			(xy 310.181146 -318.819761) (xy 310.158275 -318.863338) (xy 310.12871 -318.902682) (xy 310.093217 -318.936774)
			(xy 310.052714 -318.96473) (xy 310.008252 -318.985828) (xy 309.960981 -318.99952) (xy 309.912126 -319.005452)
			(xy 309.862951 -319.003471) (xy 309.814732 -318.993627) (xy 309.768716 -318.976175) (xy 309.726095 -318.951568)
			(xy 309.687974 -318.920443) (xy 309.655339 -318.883606) (xy 309.629036 -318.84201) (xy 309.609745 -318.796734)
			(xy 309.597968 -318.74895) (xy 309.594008 -318.699896) (xy 309.25516 -318.699896) (xy 309.254665 -318.724503)
			(xy 309.24677 -318.77308) (xy 309.231186 -318.819761) (xy 309.208315 -318.863338) (xy 309.17875 -318.902682)
			(xy 309.143257 -318.936774) (xy 309.102754 -318.96473) (xy 309.058292 -318.985828) (xy 309.011021 -318.99952)
			(xy 308.962166 -319.005452) (xy 308.912991 -319.003471) (xy 308.864772 -318.993627) (xy 308.818756 -318.976175)
			(xy 308.776135 -318.951568) (xy 308.738014 -318.920443) (xy 308.705379 -318.883606) (xy 308.679076 -318.84201)
			(xy 308.659785 -318.796734) (xy 308.648008 -318.74895) (xy 308.644048 -318.699896) (xy 308.3052 -318.699896)
			(xy 308.304705 -318.724503) (xy 308.29681 -318.77308) (xy 308.281226 -318.819761) (xy 308.258355 -318.863338)
			(xy 308.22879 -318.902682) (xy 308.193297 -318.936774) (xy 308.152794 -318.96473) (xy 308.108332 -318.985828)
			(xy 308.061061 -318.99952) (xy 308.012206 -319.005452) (xy 307.963031 -319.003471) (xy 307.914812 -318.993627)
			(xy 307.868796 -318.976175) (xy 307.826175 -318.951568) (xy 307.788054 -318.920443) (xy 307.755419 -318.883606)
			(xy 307.729116 -318.84201) (xy 307.709825 -318.796734) (xy 307.698048 -318.74895) (xy 307.694088 -318.699896)
			(xy 307.35524 -318.699896) (xy 307.354745 -318.724503) (xy 307.34685 -318.77308) (xy 307.331266 -318.819761)
			(xy 307.308395 -318.863338) (xy 307.27883 -318.902682) (xy 307.243337 -318.936774) (xy 307.202834 -318.96473)
			(xy 307.158372 -318.985828) (xy 307.111101 -318.99952) (xy 307.062246 -319.005452) (xy 307.013071 -319.003471)
			(xy 306.964852 -318.993627) (xy 306.918836 -318.976175) (xy 306.876215 -318.951568) (xy 306.838094 -318.920443)
			(xy 306.805459 -318.883606) (xy 306.779156 -318.84201) (xy 306.759865 -318.796734) (xy 306.748088 -318.74895)
			(xy 306.744128 -318.699896) (xy 306.405026 -318.699896) (xy 306.404531 -318.724503) (xy 306.396636 -318.77308)
			(xy 306.381052 -318.819761) (xy 306.358181 -318.863338) (xy 306.328616 -318.902682) (xy 306.293123 -318.936774)
			(xy 306.25262 -318.96473) (xy 306.208158 -318.985828) (xy 306.160887 -318.99952) (xy 306.112032 -319.005452)
			(xy 306.062857 -319.003471) (xy 306.014638 -318.993627) (xy 305.968622 -318.976175) (xy 305.926001 -318.951568)
			(xy 305.88788 -318.920443) (xy 305.855245 -318.883606) (xy 305.828942 -318.84201) (xy 305.809651 -318.796734)
			(xy 305.797874 -318.74895) (xy 305.793914 -318.699896) (xy 305.47691 -318.699896) (xy 305.476406 -318.725604)
			(xy 305.468363 -318.776386) (xy 305.452475 -318.825285) (xy 305.429132 -318.871097) (xy 305.398911 -318.912693)
			(xy 305.362555 -318.949049) (xy 305.320959 -318.97927) (xy 305.275147 -319.002613) (xy 305.226248 -319.018501)
			(xy 305.175466 -319.026544) (xy 305.12405 -319.026544) (xy 305.073268 -319.018501) (xy 305.024369 -319.002613)
			(xy 304.978557 -318.97927) (xy 304.936961 -318.949049) (xy 304.900605 -318.912693) (xy 304.870384 -318.871097)
			(xy 304.847041 -318.825285) (xy 304.831153 -318.776386) (xy 304.82311 -318.725604) (xy 304.504432 -318.725604)
			(xy 304.496716 -318.77308) (xy 304.481132 -318.819761) (xy 304.458261 -318.863338) (xy 304.428696 -318.902682)
			(xy 304.393203 -318.936774) (xy 304.3527 -318.96473) (xy 304.308238 -318.985828) (xy 304.260967 -318.99952)
			(xy 304.212112 -319.005452) (xy 304.162937 -319.003471) (xy 304.114718 -318.993627) (xy 304.068702 -318.976175)
			(xy 304.026081 -318.951568) (xy 303.98796 -318.920443) (xy 303.955325 -318.883606) (xy 303.929022 -318.84201)
			(xy 303.909731 -318.796734) (xy 303.897954 -318.74895) (xy 303.893994 -318.699896) (xy 303.57699 -318.699896)
			(xy 303.576486 -318.725604) (xy 303.568443 -318.776386) (xy 303.552555 -318.825285) (xy 303.529212 -318.871097)
			(xy 303.498991 -318.912693) (xy 303.462635 -318.949049) (xy 303.421039 -318.97927) (xy 303.375227 -319.002613)
			(xy 303.326328 -319.018501) (xy 303.275546 -319.026544) (xy 303.22413 -319.026544) (xy 303.173348 -319.018501)
			(xy 303.124449 -319.002613) (xy 303.078637 -318.97927) (xy 303.037041 -318.949049) (xy 303.000685 -318.912693)
			(xy 302.970464 -318.871097) (xy 302.947121 -318.825285) (xy 302.931233 -318.776386) (xy 302.92319 -318.725604)
			(xy 302.604512 -318.725604) (xy 302.596796 -318.77308) (xy 302.581212 -318.819761) (xy 302.558341 -318.863338)
			(xy 302.528776 -318.902682) (xy 302.493283 -318.936774) (xy 302.45278 -318.96473) (xy 302.408318 -318.985828)
			(xy 302.361047 -318.99952) (xy 302.312192 -319.005452) (xy 302.263017 -319.003471) (xy 302.214798 -318.993627)
			(xy 302.168782 -318.976175) (xy 302.126161 -318.951568) (xy 302.08804 -318.920443) (xy 302.055405 -318.883606)
			(xy 302.029102 -318.84201) (xy 302.009811 -318.796734) (xy 301.998034 -318.74895) (xy 301.994074 -318.699896)
			(xy 301.67707 -318.699896) (xy 301.676566 -318.725604) (xy 301.668523 -318.776386) (xy 301.652635 -318.825285)
			(xy 301.629292 -318.871097) (xy 301.599071 -318.912693) (xy 301.562715 -318.949049) (xy 301.521119 -318.97927)
			(xy 301.475307 -319.002613) (xy 301.426408 -319.018501) (xy 301.375626 -319.026544) (xy 301.32421 -319.026544)
			(xy 301.273428 -319.018501) (xy 301.224529 -319.002613) (xy 301.178717 -318.97927) (xy 301.137121 -318.949049)
			(xy 301.100765 -318.912693) (xy 301.070544 -318.871097) (xy 301.047201 -318.825285) (xy 301.031313 -318.776386)
			(xy 301.02327 -318.725604) (xy 300.704338 -318.725604) (xy 300.696622 -318.77308) (xy 300.681038 -318.819761)
			(xy 300.658167 -318.863338) (xy 300.628602 -318.902682) (xy 300.593109 -318.936774) (xy 300.552606 -318.96473)
			(xy 300.508144 -318.985828) (xy 300.460873 -318.99952) (xy 300.412018 -319.005452) (xy 300.362843 -319.003471)
			(xy 300.314624 -318.993627) (xy 300.268608 -318.976175) (xy 300.225987 -318.951568) (xy 300.187866 -318.920443)
			(xy 300.155231 -318.883606) (xy 300.128928 -318.84201) (xy 300.109637 -318.796734) (xy 300.09786 -318.74895)
			(xy 300.0939 -318.699896) (xy 299.776896 -318.699896) (xy 299.776392 -318.725604) (xy 299.768349 -318.776386)
			(xy 299.752461 -318.825285) (xy 299.729118 -318.871097) (xy 299.698897 -318.912693) (xy 299.662541 -318.949049)
			(xy 299.620945 -318.97927) (xy 299.575133 -319.002613) (xy 299.526234 -319.018501) (xy 299.475452 -319.026544)
			(xy 299.424036 -319.026544) (xy 299.373254 -319.018501) (xy 299.324355 -319.002613) (xy 299.278543 -318.97927)
			(xy 299.236947 -318.949049) (xy 299.200591 -318.912693) (xy 299.17037 -318.871097) (xy 299.147027 -318.825285)
			(xy 299.131139 -318.776386) (xy 299.123096 -318.725604) (xy 298.804418 -318.725604) (xy 298.796702 -318.77308)
			(xy 298.781118 -318.819761) (xy 298.758247 -318.863338) (xy 298.728682 -318.902682) (xy 298.693189 -318.936774)
			(xy 298.652686 -318.96473) (xy 298.608224 -318.985828) (xy 298.560953 -318.99952) (xy 298.512098 -319.005452)
			(xy 298.462923 -319.003471) (xy 298.414704 -318.993627) (xy 298.368688 -318.976175) (xy 298.326067 -318.951568)
			(xy 298.287946 -318.920443) (xy 298.255311 -318.883606) (xy 298.229008 -318.84201) (xy 298.209717 -318.796734)
			(xy 298.19794 -318.74895) (xy 298.19398 -318.699896) (xy 297.876976 -318.699896) (xy 297.876472 -318.725604)
			(xy 297.868429 -318.776386) (xy 297.852541 -318.825285) (xy 297.829198 -318.871097) (xy 297.798977 -318.912693)
			(xy 297.762621 -318.949049) (xy 297.721025 -318.97927) (xy 297.675213 -319.002613) (xy 297.626314 -319.018501)
			(xy 297.575532 -319.026544) (xy 297.524116 -319.026544) (xy 297.473334 -319.018501) (xy 297.424435 -319.002613)
			(xy 297.378623 -318.97927) (xy 297.337027 -318.949049) (xy 297.300671 -318.912693) (xy 297.27045 -318.871097)
			(xy 297.247107 -318.825285) (xy 297.231219 -318.776386) (xy 297.223176 -318.725604) (xy 296.904498 -318.725604)
			(xy 296.896782 -318.77308) (xy 296.881198 -318.819761) (xy 296.858327 -318.863338) (xy 296.828762 -318.902682)
			(xy 296.793269 -318.936774) (xy 296.752766 -318.96473) (xy 296.708304 -318.985828) (xy 296.661033 -318.99952)
			(xy 296.612178 -319.005452) (xy 296.563003 -319.003471) (xy 296.514784 -318.993627) (xy 296.468768 -318.976175)
			(xy 296.426147 -318.951568) (xy 296.388026 -318.920443) (xy 296.355391 -318.883606) (xy 296.329088 -318.84201)
			(xy 296.309797 -318.796734) (xy 296.29802 -318.74895) (xy 296.29406 -318.699896) (xy 295.977056 -318.699896)
			(xy 295.976552 -318.725604) (xy 295.968509 -318.776386) (xy 295.952621 -318.825285) (xy 295.929278 -318.871097)
			(xy 295.899057 -318.912693) (xy 295.862701 -318.949049) (xy 295.821105 -318.97927) (xy 295.775293 -319.002613)
			(xy 295.726394 -319.018501) (xy 295.675612 -319.026544) (xy 295.624196 -319.026544) (xy 295.573414 -319.018501)
			(xy 295.524515 -319.002613) (xy 295.478703 -318.97927) (xy 295.437107 -318.949049) (xy 295.400751 -318.912693)
			(xy 295.37053 -318.871097) (xy 295.347187 -318.825285) (xy 295.331299 -318.776386) (xy 295.323256 -318.725604)
			(xy 295.004324 -318.725604) (xy 294.996608 -318.77308) (xy 294.981024 -318.819761) (xy 294.958153 -318.863338)
			(xy 294.928588 -318.902682) (xy 294.893095 -318.936774) (xy 294.852592 -318.96473) (xy 294.80813 -318.985828)
			(xy 294.760859 -318.99952) (xy 294.712004 -319.005452) (xy 294.662829 -319.003471) (xy 294.61461 -318.993627)
			(xy 294.568594 -318.976175) (xy 294.525973 -318.951568) (xy 294.487852 -318.920443) (xy 294.455217 -318.883606)
			(xy 294.428914 -318.84201) (xy 294.409623 -318.796734) (xy 294.397846 -318.74895) (xy 294.393886 -318.699896)
			(xy 294.076882 -318.699896) (xy 294.076378 -318.725604) (xy 294.068335 -318.776386) (xy 294.052447 -318.825285)
			(xy 294.029104 -318.871097) (xy 293.998883 -318.912693) (xy 293.962527 -318.949049) (xy 293.920931 -318.97927)
			(xy 293.875119 -319.002613) (xy 293.82622 -319.018501) (xy 293.775438 -319.026544) (xy 293.724022 -319.026544)
			(xy 293.67324 -319.018501) (xy 293.624341 -319.002613) (xy 293.578529 -318.97927) (xy 293.536933 -318.949049)
			(xy 293.500577 -318.912693) (xy 293.470356 -318.871097) (xy 293.447013 -318.825285) (xy 293.431125 -318.776386)
			(xy 293.423082 -318.725604) (xy 293.103534 -318.725604) (xy 293.101492 -318.750247) (xy 293.089089 -318.79922)
			(xy 293.068795 -318.845484) (xy 293.041162 -318.887776) (xy 293.006944 -318.924942) (xy 292.967076 -318.955969)
			(xy 292.922644 -318.980011) (xy 292.874861 -318.996411) (xy 292.82503 -319.004722) (xy 292.79977 -319.005204)
			(xy 292.76802 -319.003426) (xy 292.757098 -319.00241) (xy 292.736778 -319.009014) (xy 292.672516 -319.066926)
			(xy 292.665014 -319.074474) (xy 292.656369 -319.093893) (xy 292.655752 -319.104518) (xy 292.655752 -319.16624)
			(xy 292.656129 -319.175319) (xy 292.66247 -319.192336) (xy 292.674344 -319.206075) (xy 292.690261 -319.214816)
			(xy 292.699186 -319.216532) (xy 293.656512 -319.35928) (xy 293.666926 -319.356232) (xy 293.687207 -319.350882)
			(xy 293.728758 -319.345146) (xy 293.74973 -319.344802) (xy 293.771502 -319.345195) (xy 293.814603 -319.351386)
			(xy 293.856391 -319.363624) (xy 293.896022 -319.381663) (xy 293.914576 -319.393062) (xy 293.92372 -319.398904)
			(xy 294.126666 -319.42913) (xy 294.17518 -319.437512) (xy 295.23563 -319.649348) (xy 295.245219 -319.65081)
			(xy 295.264275 -319.647274) (xy 295.272714 -319.64249) (xy 295.340278 -319.600072) (xy 295.351708 -319.584324)
			(xy 295.353994 -319.574926) (xy 295.360713 -319.55059) (xy 295.381022 -319.504374) (xy 295.408658 -319.462129)
			(xy 295.442866 -319.425004) (xy 295.482715 -319.394013) (xy 295.527119 -319.37) (xy 295.574869 -319.353618)
			(xy 295.624663 -319.345314) (xy 295.649904 -319.344802) (xy 295.673897 -319.345249) (xy 295.721291 -319.352756)
			(xy 295.766928 -319.367585) (xy 295.809682 -319.389371) (xy 295.848503 -319.417576) (xy 295.882433 -319.451508)
			(xy 295.910637 -319.49033) (xy 295.932421 -319.533085) (xy 295.947248 -319.578723) (xy 295.954753 -319.626117)
			(xy 295.955212 -319.65011) (xy 297.24402 -319.65011) (xy 297.24798 -319.601056) (xy 297.259757 -319.553272)
			(xy 297.279048 -319.507996) (xy 297.305351 -319.4664) (xy 297.337986 -319.429563) (xy 297.376107 -319.398438)
			(xy 297.418728 -319.373831) (xy 297.464744 -319.356379) (xy 297.512963 -319.346535) (xy 297.562138 -319.344554)
			(xy 297.610993 -319.350486) (xy 297.658264 -319.364178) (xy 297.702726 -319.385276) (xy 297.743229 -319.413232)
			(xy 297.778722 -319.447324) (xy 297.808287 -319.486668) (xy 297.831158 -319.530245) (xy 297.846742 -319.576926)
			(xy 297.854637 -319.625503) (xy 297.855132 -319.65011) (xy 299.14394 -319.65011) (xy 299.1479 -319.601056)
			(xy 299.159677 -319.553272) (xy 299.178968 -319.507996) (xy 299.205271 -319.4664) (xy 299.237906 -319.429563)
			(xy 299.276027 -319.398438) (xy 299.318648 -319.373831) (xy 299.364664 -319.356379) (xy 299.412883 -319.346535)
			(xy 299.462058 -319.344554) (xy 299.510913 -319.350486) (xy 299.558184 -319.364178) (xy 299.602646 -319.385276)
			(xy 299.643149 -319.413232) (xy 299.678642 -319.447324) (xy 299.708207 -319.486668) (xy 299.731078 -319.530245)
			(xy 299.746662 -319.576926) (xy 299.754557 -319.625503) (xy 299.755052 -319.65011) (xy 301.044114 -319.65011)
			(xy 301.048074 -319.601056) (xy 301.059851 -319.553272) (xy 301.079142 -319.507996) (xy 301.105445 -319.4664)
			(xy 301.13808 -319.429563) (xy 301.176201 -319.398438) (xy 301.218822 -319.373831) (xy 301.264838 -319.356379)
			(xy 301.313057 -319.346535) (xy 301.362232 -319.344554) (xy 301.411087 -319.350486) (xy 301.458358 -319.364178)
			(xy 301.50282 -319.385276) (xy 301.543323 -319.413232) (xy 301.578816 -319.447324) (xy 301.608381 -319.486668)
			(xy 301.631252 -319.530245) (xy 301.646836 -319.576926) (xy 301.654731 -319.625503) (xy 301.655226 -319.65011)
			(xy 302.944034 -319.65011) (xy 302.947994 -319.601056) (xy 302.959771 -319.553272) (xy 302.979062 -319.507996)
			(xy 303.005365 -319.4664) (xy 303.038 -319.429563) (xy 303.076121 -319.398438) (xy 303.118742 -319.373831)
			(xy 303.164758 -319.356379) (xy 303.212977 -319.346535) (xy 303.262152 -319.344554) (xy 303.311007 -319.350486)
			(xy 303.358278 -319.364178) (xy 303.40274 -319.385276) (xy 303.443243 -319.413232) (xy 303.478736 -319.447324)
			(xy 303.508301 -319.486668) (xy 303.531172 -319.530245) (xy 303.546756 -319.576926) (xy 303.554651 -319.625503)
			(xy 303.555146 -319.65011) (xy 304.843954 -319.65011) (xy 304.847914 -319.601056) (xy 304.859691 -319.553272)
			(xy 304.878982 -319.507996) (xy 304.905285 -319.4664) (xy 304.93792 -319.429563) (xy 304.976041 -319.398438)
			(xy 305.018662 -319.373831) (xy 305.064678 -319.356379) (xy 305.112897 -319.346535) (xy 305.162072 -319.344554)
			(xy 305.210927 -319.350486) (xy 305.258198 -319.364178) (xy 305.30266 -319.385276) (xy 305.343163 -319.413232)
			(xy 305.378656 -319.447324) (xy 305.408221 -319.486668) (xy 305.431092 -319.530245) (xy 305.446676 -319.576926)
			(xy 305.454571 -319.625503) (xy 305.455066 -319.65011) (xy 306.744128 -319.65011) (xy 306.748088 -319.601056)
			(xy 306.759865 -319.553272) (xy 306.779156 -319.507996) (xy 306.805459 -319.4664) (xy 306.838094 -319.429563)
			(xy 306.876215 -319.398438) (xy 306.918836 -319.373831) (xy 306.964852 -319.356379) (xy 307.013071 -319.346535)
			(xy 307.062246 -319.344554) (xy 307.111101 -319.350486) (xy 307.158372 -319.364178) (xy 307.202834 -319.385276)
			(xy 307.243337 -319.413232) (xy 307.27883 -319.447324) (xy 307.308395 -319.486668) (xy 307.331266 -319.530245)
			(xy 307.34685 -319.576926) (xy 307.354745 -319.625503) (xy 307.35524 -319.65011) (xy 308.644048 -319.65011)
			(xy 308.648008 -319.601056) (xy 308.659785 -319.553272) (xy 308.679076 -319.507996) (xy 308.705379 -319.4664)
			(xy 308.738014 -319.429563) (xy 308.776135 -319.398438) (xy 308.818756 -319.373831) (xy 308.864772 -319.356379)
			(xy 308.912991 -319.346535) (xy 308.962166 -319.344554) (xy 309.011021 -319.350486) (xy 309.058292 -319.364178)
			(xy 309.102754 -319.385276) (xy 309.143257 -319.413232) (xy 309.17875 -319.447324) (xy 309.208315 -319.486668)
			(xy 309.231186 -319.530245) (xy 309.24677 -319.576926) (xy 309.254665 -319.625503) (xy 309.25516 -319.65011)
			(xy 310.543968 -319.65011) (xy 310.547928 -319.601056) (xy 310.559705 -319.553272) (xy 310.578996 -319.507996)
			(xy 310.605299 -319.4664) (xy 310.637934 -319.429563) (xy 310.676055 -319.398438) (xy 310.718676 -319.373831)
			(xy 310.764692 -319.356379) (xy 310.812911 -319.346535) (xy 310.862086 -319.344554) (xy 310.910941 -319.350486)
			(xy 310.958212 -319.364178) (xy 311.002674 -319.385276) (xy 311.043177 -319.413232) (xy 311.07867 -319.447324)
			(xy 311.108235 -319.486668) (xy 311.131106 -319.530245) (xy 311.14669 -319.576926) (xy 311.154585 -319.625503)
			(xy 311.15508 -319.65011) (xy 312.443888 -319.65011) (xy 312.447848 -319.601056) (xy 312.459625 -319.553272)
			(xy 312.478916 -319.507996) (xy 312.505219 -319.4664) (xy 312.537854 -319.429563) (xy 312.575975 -319.398438)
			(xy 312.618596 -319.373831) (xy 312.664612 -319.356379) (xy 312.712831 -319.346535) (xy 312.762006 -319.344554)
			(xy 312.810861 -319.350486) (xy 312.858132 -319.364178) (xy 312.902594 -319.385276) (xy 312.943097 -319.413232)
			(xy 312.97859 -319.447324) (xy 313.008155 -319.486668) (xy 313.031026 -319.530245) (xy 313.04661 -319.576926)
			(xy 313.054505 -319.625503) (xy 313.055 -319.65011) (xy 313.054505 -319.674717) (xy 313.04661 -319.723294)
			(xy 313.031026 -319.769975) (xy 313.008155 -319.813552) (xy 312.97859 -319.852896) (xy 312.943097 -319.886988)
			(xy 312.902594 -319.914944) (xy 312.858132 -319.936042) (xy 312.810861 -319.949734) (xy 312.762006 -319.955666)
			(xy 312.712831 -319.953685) (xy 312.664612 -319.943841) (xy 312.618596 -319.926389) (xy 312.575975 -319.901782)
			(xy 312.537854 -319.870657) (xy 312.505219 -319.83382) (xy 312.478916 -319.792224) (xy 312.459625 -319.746948)
			(xy 312.447848 -319.699164) (xy 312.443888 -319.65011) (xy 311.15508 -319.65011) (xy 311.154585 -319.674717)
			(xy 311.14669 -319.723294) (xy 311.131106 -319.769975) (xy 311.108235 -319.813552) (xy 311.07867 -319.852896)
			(xy 311.043177 -319.886988) (xy 311.002674 -319.914944) (xy 310.958212 -319.936042) (xy 310.910941 -319.949734)
			(xy 310.862086 -319.955666) (xy 310.812911 -319.953685) (xy 310.764692 -319.943841) (xy 310.718676 -319.926389)
			(xy 310.676055 -319.901782) (xy 310.637934 -319.870657) (xy 310.605299 -319.83382) (xy 310.578996 -319.792224)
			(xy 310.559705 -319.746948) (xy 310.547928 -319.699164) (xy 310.543968 -319.65011) (xy 309.25516 -319.65011)
			(xy 309.254665 -319.674717) (xy 309.24677 -319.723294) (xy 309.231186 -319.769975) (xy 309.208315 -319.813552)
			(xy 309.17875 -319.852896) (xy 309.143257 -319.886988) (xy 309.102754 -319.914944) (xy 309.058292 -319.936042)
			(xy 309.011021 -319.949734) (xy 308.962166 -319.955666) (xy 308.912991 -319.953685) (xy 308.864772 -319.943841)
			(xy 308.818756 -319.926389) (xy 308.776135 -319.901782) (xy 308.738014 -319.870657) (xy 308.705379 -319.83382)
			(xy 308.679076 -319.792224) (xy 308.659785 -319.746948) (xy 308.648008 -319.699164) (xy 308.644048 -319.65011)
			(xy 307.35524 -319.65011) (xy 307.354745 -319.674717) (xy 307.34685 -319.723294) (xy 307.331266 -319.769975)
			(xy 307.308395 -319.813552) (xy 307.27883 -319.852896) (xy 307.243337 -319.886988) (xy 307.202834 -319.914944)
			(xy 307.158372 -319.936042) (xy 307.111101 -319.949734) (xy 307.062246 -319.955666) (xy 307.013071 -319.953685)
			(xy 306.964852 -319.943841) (xy 306.918836 -319.926389) (xy 306.876215 -319.901782) (xy 306.838094 -319.870657)
			(xy 306.805459 -319.83382) (xy 306.779156 -319.792224) (xy 306.759865 -319.746948) (xy 306.748088 -319.699164)
			(xy 306.744128 -319.65011) (xy 305.455066 -319.65011) (xy 305.454571 -319.674717) (xy 305.446676 -319.723294)
			(xy 305.431092 -319.769975) (xy 305.408221 -319.813552) (xy 305.378656 -319.852896) (xy 305.343163 -319.886988)
			(xy 305.30266 -319.914944) (xy 305.258198 -319.936042) (xy 305.210927 -319.949734) (xy 305.162072 -319.955666)
			(xy 305.112897 -319.953685) (xy 305.064678 -319.943841) (xy 305.018662 -319.926389) (xy 304.976041 -319.901782)
			(xy 304.93792 -319.870657) (xy 304.905285 -319.83382) (xy 304.878982 -319.792224) (xy 304.859691 -319.746948)
			(xy 304.847914 -319.699164) (xy 304.843954 -319.65011) (xy 303.555146 -319.65011) (xy 303.554651 -319.674717)
			(xy 303.546756 -319.723294) (xy 303.531172 -319.769975) (xy 303.508301 -319.813552) (xy 303.478736 -319.852896)
			(xy 303.443243 -319.886988) (xy 303.40274 -319.914944) (xy 303.358278 -319.936042) (xy 303.311007 -319.949734)
			(xy 303.262152 -319.955666) (xy 303.212977 -319.953685) (xy 303.164758 -319.943841) (xy 303.118742 -319.926389)
			(xy 303.076121 -319.901782) (xy 303.038 -319.870657) (xy 303.005365 -319.83382) (xy 302.979062 -319.792224)
			(xy 302.959771 -319.746948) (xy 302.947994 -319.699164) (xy 302.944034 -319.65011) (xy 301.655226 -319.65011)
			(xy 301.654731 -319.674717) (xy 301.646836 -319.723294) (xy 301.631252 -319.769975) (xy 301.608381 -319.813552)
			(xy 301.578816 -319.852896) (xy 301.543323 -319.886988) (xy 301.50282 -319.914944) (xy 301.458358 -319.936042)
			(xy 301.411087 -319.949734) (xy 301.362232 -319.955666) (xy 301.313057 -319.953685) (xy 301.264838 -319.943841)
			(xy 301.218822 -319.926389) (xy 301.176201 -319.901782) (xy 301.13808 -319.870657) (xy 301.105445 -319.83382)
			(xy 301.079142 -319.792224) (xy 301.059851 -319.746948) (xy 301.048074 -319.699164) (xy 301.044114 -319.65011)
			(xy 299.755052 -319.65011) (xy 299.754557 -319.674717) (xy 299.746662 -319.723294) (xy 299.731078 -319.769975)
			(xy 299.708207 -319.813552) (xy 299.678642 -319.852896) (xy 299.643149 -319.886988) (xy 299.602646 -319.914944)
			(xy 299.558184 -319.936042) (xy 299.510913 -319.949734) (xy 299.462058 -319.955666) (xy 299.412883 -319.953685)
			(xy 299.364664 -319.943841) (xy 299.318648 -319.926389) (xy 299.276027 -319.901782) (xy 299.237906 -319.870657)
			(xy 299.205271 -319.83382) (xy 299.178968 -319.792224) (xy 299.159677 -319.746948) (xy 299.1479 -319.699164)
			(xy 299.14394 -319.65011) (xy 297.855132 -319.65011) (xy 297.854637 -319.674717) (xy 297.846742 -319.723294)
			(xy 297.831158 -319.769975) (xy 297.808287 -319.813552) (xy 297.778722 -319.852896) (xy 297.743229 -319.886988)
			(xy 297.702726 -319.914944) (xy 297.658264 -319.936042) (xy 297.610993 -319.949734) (xy 297.562138 -319.955666)
			(xy 297.512963 -319.953685) (xy 297.464744 -319.943841) (xy 297.418728 -319.926389) (xy 297.376107 -319.901782)
			(xy 297.337986 -319.870657) (xy 297.305351 -319.83382) (xy 297.279048 -319.792224) (xy 297.259757 -319.746948)
			(xy 297.24798 -319.699164) (xy 297.24402 -319.65011) (xy 295.955212 -319.65011) (xy 295.955098 -319.661201)
			(xy 295.953445 -319.683321) (xy 295.95191 -319.694306) (xy 295.95064 -319.703958) (xy 295.955212 -319.722754)
			(xy 296.001186 -319.788032) (xy 296.007079 -319.795717) (xy 296.023276 -319.806301) (xy 296.032682 -319.808606)
			(xy 301.499654 -320.900044) (xy 317.098687 -320.900044) (xy 317.102693 -320.704989) (xy 317.114703 -320.510263)
			(xy 317.134698 -320.316194) (xy 317.162643 -320.12311) (xy 317.198492 -319.931335) (xy 317.242184 -319.741195)
			(xy 317.293645 -319.553008) (xy 317.352789 -319.367093) (xy 317.419516 -319.183762) (xy 317.493713 -319.003326)
			(xy 317.575255 -318.826088) (xy 317.664006 -318.652347) (xy 317.759814 -318.482396) (xy 317.862519 -318.316522)
			(xy 317.971947 -318.155004) (xy 318.087914 -317.998115) (xy 318.210225 -317.84612) (xy 318.338672 -317.699274)
			(xy 318.47304 -317.557825) (xy 318.613102 -317.422012) (xy 318.758621 -317.292063) (xy 318.909353 -317.168199)
			(xy 319.065043 -317.050627) (xy 319.225429 -316.939547) (xy 319.39024 -316.835144) (xy 319.559198 -316.737596)
			(xy 319.732019 -316.647067) (xy 319.908411 -316.563709) (xy 320.088076 -316.487663) (xy 320.270711 -316.419058)
			(xy 320.45601 -316.358008) (xy 320.643658 -316.304618) (xy 320.83334 -316.258976) (xy 321.024737 -316.22116)
			(xy 321.217524 -316.191234) (xy 321.411377 -316.169248) (xy 321.60597 -316.155239) (xy 321.800973 -316.149231)
			(xy 321.996059 -316.151234) (xy 322.190898 -316.161245) (xy 322.385162 -316.179246) (xy 322.578523 -316.205208)
			(xy 322.770656 -316.239086) (xy 322.961235 -316.280823) (xy 323.14994 -316.33035) (xy 323.336453 -316.387582)
			(xy 323.390944 -316.406784) (xy 331.6384 -316.406784) (xy 331.642471 -316.351162) (xy 331.654597 -316.296725)
			(xy 331.67452 -316.244634) (xy 331.701816 -316.195999) (xy 331.735902 -316.151856) (xy 331.776051 -316.113147)
			(xy 331.821409 -316.080696) (xy 331.871009 -316.055195) (xy 331.923793 -316.037188) (xy 331.978636 -316.027058)
			(xy 332.03437 -316.025021) (xy 332.089807 -316.031121) (xy 332.143764 -316.045227) (xy 332.195093 -316.067039)
			(xy 332.242699 -316.096093) (xy 332.285567 -316.131768) (xy 332.322784 -316.173305) (xy 332.353557 -316.219818)
			(xy 332.377229 -316.270315) (xy 332.393297 -316.323722) (xy 332.401417 -316.378898) (xy 332.401926 -316.406784)
			(xy 332.401417 -316.43467) (xy 332.393297 -316.489846) (xy 332.377229 -316.543253) (xy 332.353557 -316.59375)
			(xy 332.322784 -316.640263) (xy 332.285567 -316.6818) (xy 332.242699 -316.717475) (xy 332.195093 -316.746529)
			(xy 332.143764 -316.768341) (xy 332.089807 -316.782447) (xy 332.03437 -316.788547) (xy 331.978636 -316.78651)
			(xy 331.923793 -316.77638) (xy 331.871009 -316.758373) (xy 331.821409 -316.732872) (xy 331.776051 -316.700421)
			(xy 331.735902 -316.661712) (xy 331.701816 -316.617569) (xy 331.67452 -316.568934) (xy 331.654597 -316.516843)
			(xy 331.642471 -316.462406) (xy 331.6384 -316.406784) (xy 323.390944 -316.406784) (xy 323.520459 -316.452423)
			(xy 323.701647 -316.524764) (xy 323.879713 -316.604482) (xy 324.054356 -316.691444) (xy 324.225282 -316.785503)
			(xy 324.392201 -316.886499) (xy 324.554834 -316.994264) (xy 324.712905 -317.108614) (xy 324.866148 -317.229357)
			(xy 325.014305 -317.356291) (xy 325.157126 -317.489199) (xy 325.29437 -317.627859) (xy 325.425806 -317.772037)
			(xy 325.551211 -317.92149) (xy 325.670375 -318.075964) (xy 325.783096 -318.235201) (xy 325.889185 -318.398932)
			(xy 325.988463 -318.566879) (xy 326.080761 -318.738762) (xy 326.165926 -318.914288) (xy 326.243812 -319.093163)
			(xy 326.314289 -319.275085) (xy 326.377237 -319.459747) (xy 326.432552 -319.646837) (xy 326.480138 -319.836041)
			(xy 326.519917 -320.027038) (xy 326.528802 -320.08064) (xy 338.422996 -320.08064) (xy 338.423507 -320.051722)
			(xy 338.432232 -319.994549) (xy 338.449489 -319.939349) (xy 338.474882 -319.887386) (xy 338.507829 -319.839853)
			(xy 338.547574 -319.797838) (xy 338.570062 -319.77965) (xy 338.578807 -319.772073) (xy 338.588997 -319.751325)
			(xy 338.58962 -319.739772) (xy 338.58962 -319.659508) (xy 338.589038 -319.647942) (xy 338.578851 -319.627171)
			(xy 338.570062 -319.61963) (xy 338.547585 -319.601432) (xy 338.507851 -319.559412) (xy 338.474912 -319.511879)
			(xy 338.449523 -319.459919) (xy 338.432265 -319.404723) (xy 338.423533 -319.347555) (xy 338.422996 -319.31864)
			(xy 338.423493 -319.291388) (xy 338.431244 -319.237438) (xy 338.446595 -319.185141) (xy 338.469233 -319.13556)
			(xy 338.498698 -319.089707) (xy 338.534388 -319.048514) (xy 338.575578 -319.012819) (xy 338.621429 -318.983351)
			(xy 338.671007 -318.960708) (xy 338.723303 -318.945352) (xy 338.777252 -318.937595) (xy 338.804504 -318.937132)
			(xy 338.833422 -318.937635) (xy 338.890594 -318.946366) (xy 338.945794 -318.963626) (xy 338.997756 -318.98902)
			(xy 339.045289 -319.021967) (xy 339.087305 -319.061711) (xy 339.105494 -319.084198) (xy 339.113063 -319.092952)
			(xy 339.133816 -319.10314) (xy 339.145372 -319.103756) (xy 339.225636 -319.103756) (xy 339.237201 -319.103164)
			(xy 339.257974 -319.092986) (xy 339.265514 -319.084198) (xy 339.282267 -319.063415) (xy 339.320621 -319.026285)
			(xy 339.363775 -318.994863) (xy 339.410889 -318.969764) (xy 339.461041 -318.951478) (xy 339.513252 -318.940361)
			(xy 339.566504 -318.936631) (xy 339.619756 -318.940361) (xy 339.671967 -318.951478) (xy 339.722119 -318.969764)
			(xy 339.769233 -318.994863) (xy 339.812387 -319.026285) (xy 339.850741 -319.063415) (xy 339.867494 -319.084198)
			(xy 339.875063 -319.092952) (xy 339.895816 -319.10314) (xy 339.907372 -319.103756) (xy 339.987636 -319.103756)
			(xy 339.999201 -319.103164) (xy 340.019974 -319.092986) (xy 340.027514 -319.084198) (xy 340.044267 -319.063415)
			(xy 340.082621 -319.026285) (xy 340.125775 -318.994863) (xy 340.172889 -318.969764) (xy 340.223041 -318.951478)
			(xy 340.275252 -318.940361) (xy 340.328504 -318.936631) (xy 340.381756 -318.940361) (xy 340.433967 -318.951478)
			(xy 340.484119 -318.969764) (xy 340.531233 -318.994863) (xy 340.574387 -319.026285) (xy 340.612741 -319.063415)
			(xy 340.629494 -319.084198) (xy 340.637063 -319.092952) (xy 340.657816 -319.10314) (xy 340.669372 -319.103756)
			(xy 340.749636 -319.103756) (xy 340.761201 -319.103164) (xy 340.781974 -319.092986) (xy 340.789514 -319.084198)
			(xy 340.806267 -319.063415) (xy 340.844621 -319.026285) (xy 340.887775 -318.994863) (xy 340.934889 -318.969764)
			(xy 340.985041 -318.951478) (xy 341.037252 -318.940361) (xy 341.090504 -318.936631) (xy 341.143756 -318.940361)
			(xy 341.195967 -318.951478) (xy 341.246119 -318.969764) (xy 341.293233 -318.994863) (xy 341.336387 -319.026285)
			(xy 341.374741 -319.063415) (xy 341.391494 -319.084198) (xy 341.399063 -319.092952) (xy 341.419816 -319.10314)
			(xy 341.431372 -319.103756) (xy 341.511636 -319.103756) (xy 341.523201 -319.103164) (xy 341.543974 -319.092986)
			(xy 341.551514 -319.084198) (xy 341.568267 -319.063415) (xy 341.606621 -319.026285) (xy 341.649775 -318.994863)
			(xy 341.696889 -318.969764) (xy 341.747041 -318.951478) (xy 341.799252 -318.940361) (xy 341.852504 -318.936631)
			(xy 341.905756 -318.940361) (xy 341.957967 -318.951478) (xy 342.008119 -318.969764) (xy 342.055233 -318.994863)
			(xy 342.098387 -319.026285) (xy 342.136741 -319.063415) (xy 342.153494 -319.084198) (xy 342.161063 -319.092952)
			(xy 342.181816 -319.10314) (xy 342.193372 -319.103756) (xy 342.273636 -319.103756) (xy 342.285201 -319.103164)
			(xy 342.305974 -319.092986) (xy 342.313514 -319.084198) (xy 342.330267 -319.063415) (xy 342.368621 -319.026285)
			(xy 342.411775 -318.994863) (xy 342.458889 -318.969764) (xy 342.509041 -318.951478) (xy 342.561252 -318.940361)
			(xy 342.614504 -318.936631) (xy 342.667756 -318.940361) (xy 342.719967 -318.951478) (xy 342.770119 -318.969764)
			(xy 342.817233 -318.994863) (xy 342.860387 -319.026285) (xy 342.898741 -319.063415) (xy 342.915494 -319.084198)
			(xy 342.923063 -319.092952) (xy 342.943816 -319.10314) (xy 342.955372 -319.103756) (xy 343.035636 -319.103756)
			(xy 343.047201 -319.103164) (xy 343.067974 -319.092986) (xy 343.075514 -319.084198) (xy 343.092267 -319.063415)
			(xy 343.130621 -319.026285) (xy 343.173775 -318.994863) (xy 343.220889 -318.969764) (xy 343.271041 -318.951478)
			(xy 343.323252 -318.940361) (xy 343.376504 -318.936631) (xy 343.429756 -318.940361) (xy 343.481967 -318.951478)
			(xy 343.532119 -318.969764) (xy 343.579233 -318.994863) (xy 343.622387 -319.026285) (xy 343.660741 -319.063415)
			(xy 343.677494 -319.084198) (xy 343.685063 -319.092952) (xy 343.705816 -319.10314) (xy 343.717372 -319.103756)
			(xy 343.797636 -319.103756) (xy 343.809201 -319.103164) (xy 343.829974 -319.092986) (xy 343.837514 -319.084198)
			(xy 343.854267 -319.063415) (xy 343.892621 -319.026285) (xy 343.935775 -318.994863) (xy 343.982889 -318.969764)
			(xy 344.033041 -318.951478) (xy 344.085252 -318.940361) (xy 344.138504 -318.936631) (xy 344.191756 -318.940361)
			(xy 344.243967 -318.951478) (xy 344.294119 -318.969764) (xy 344.341233 -318.994863) (xy 344.384387 -319.026285)
			(xy 344.422741 -319.063415) (xy 344.439494 -319.084198) (xy 344.447063 -319.092952) (xy 344.467816 -319.10314)
			(xy 344.479372 -319.103756) (xy 344.559636 -319.103756) (xy 344.571201 -319.103164) (xy 344.591974 -319.092986)
			(xy 344.599514 -319.084198) (xy 344.616267 -319.063415) (xy 344.654621 -319.026285) (xy 344.697775 -318.994863)
			(xy 344.744889 -318.969764) (xy 344.795041 -318.951478) (xy 344.847252 -318.940361) (xy 344.900504 -318.936631)
			(xy 344.953756 -318.940361) (xy 345.005967 -318.951478) (xy 345.056119 -318.969764) (xy 345.103233 -318.994863)
			(xy 345.146387 -319.026285) (xy 345.184741 -319.063415) (xy 345.201494 -319.084198) (xy 345.209063 -319.092952)
			(xy 345.229816 -319.10314) (xy 345.241372 -319.103756) (xy 345.321636 -319.103756) (xy 345.333201 -319.103164)
			(xy 345.353974 -319.092986) (xy 345.361514 -319.084198) (xy 345.378267 -319.063415) (xy 345.416621 -319.026285)
			(xy 345.459775 -318.994863) (xy 345.506889 -318.969764) (xy 345.557041 -318.951478) (xy 345.609252 -318.940361)
			(xy 345.662504 -318.936631) (xy 345.715756 -318.940361) (xy 345.767967 -318.951478) (xy 345.818119 -318.969764)
			(xy 345.865233 -318.994863) (xy 345.908387 -319.026285) (xy 345.946741 -319.063415) (xy 345.963494 -319.084198)
			(xy 345.971063 -319.092952) (xy 345.991816 -319.10314) (xy 346.003372 -319.103756) (xy 346.083636 -319.103756)
			(xy 346.095201 -319.103164) (xy 346.115974 -319.092986) (xy 346.123514 -319.084198) (xy 346.140267 -319.063415)
			(xy 346.178621 -319.026285) (xy 346.221775 -318.994863) (xy 346.268889 -318.969764) (xy 346.319041 -318.951478)
			(xy 346.371252 -318.940361) (xy 346.424504 -318.936631) (xy 346.477756 -318.940361) (xy 346.529967 -318.951478)
			(xy 346.580119 -318.969764) (xy 346.627233 -318.994863) (xy 346.670387 -319.026285) (xy 346.708741 -319.063415)
			(xy 346.725494 -319.084198) (xy 346.733063 -319.092952) (xy 346.753816 -319.10314) (xy 346.765372 -319.103756)
			(xy 346.845636 -319.103756) (xy 346.857201 -319.103164) (xy 346.877974 -319.092986) (xy 346.885514 -319.084198)
			(xy 346.903697 -319.061707) (xy 346.945718 -319.021973) (xy 346.993255 -318.989035) (xy 347.045218 -318.963647)
			(xy 347.100417 -318.946393) (xy 347.157588 -318.937666) (xy 347.186504 -318.937132) (xy 347.213759 -318.937552)
			(xy 347.267713 -318.94531) (xy 347.320014 -318.960669) (xy 347.369597 -318.983315) (xy 347.415452 -319.012787)
			(xy 347.456646 -319.048485) (xy 347.49234 -319.089683) (xy 347.521806 -319.135541) (xy 347.544447 -319.185127)
			(xy 347.559799 -319.23743) (xy 347.567551 -319.291385) (xy 347.568012 -319.31864) (xy 347.567484 -319.347557)
			(xy 347.558761 -319.404729) (xy 347.541508 -319.459929) (xy 347.516118 -319.511892) (xy 347.483174 -319.559426)
			(xy 347.443432 -319.601441) (xy 347.420946 -319.61963) (xy 347.412166 -319.627174) (xy 347.401994 -319.647947)
			(xy 347.401388 -319.659508) (xy 347.401388 -319.739772) (xy 347.401979 -319.751337) (xy 347.41216 -319.772108)
			(xy 347.420946 -319.77965) (xy 347.443415 -319.797858) (xy 347.483149 -319.839875) (xy 347.516088 -319.887407)
			(xy 347.541479 -319.939365) (xy 347.558739 -319.994559) (xy 347.567474 -320.051725) (xy 347.568012 -320.08064)
			(xy 347.567559 -320.107892) (xy 347.559798 -320.161841) (xy 347.544438 -320.214136) (xy 347.521792 -320.263713)
			(xy 347.492322 -320.309563) (xy 347.456627 -320.350753) (xy 347.415434 -320.386444) (xy 347.369581 -320.415909)
			(xy 347.320002 -320.43855) (xy 347.267706 -320.453905) (xy 347.213756 -320.461662) (xy 347.186504 -320.462148)
			(xy 347.157586 -320.461646) (xy 347.100413 -320.452917) (xy 347.045213 -320.435657) (xy 346.993251 -320.410262)
			(xy 346.945718 -320.377315) (xy 346.903703 -320.33757) (xy 346.885514 -320.315082) (xy 346.877945 -320.306328)
			(xy 346.857192 -320.296141) (xy 346.845636 -320.295524) (xy 346.765372 -320.295524) (xy 346.753808 -320.296127)
			(xy 346.733036 -320.306298) (xy 346.725494 -320.315082) (xy 346.708741 -320.335865) (xy 346.670387 -320.372995)
			(xy 346.627233 -320.404417) (xy 346.580119 -320.429516) (xy 346.529967 -320.447802) (xy 346.477756 -320.458919)
			(xy 346.424504 -320.462649) (xy 346.371252 -320.458919) (xy 346.319041 -320.447802) (xy 346.268889 -320.429516)
			(xy 346.221775 -320.404417) (xy 346.178621 -320.372995) (xy 346.140267 -320.335865) (xy 346.123514 -320.315082)
			(xy 346.115945 -320.306328) (xy 346.095192 -320.296141) (xy 346.083636 -320.295524) (xy 346.003372 -320.295524)
			(xy 345.991808 -320.296127) (xy 345.971036 -320.306298) (xy 345.963494 -320.315082) (xy 345.946741 -320.335865)
			(xy 345.908387 -320.372995) (xy 345.865233 -320.404417) (xy 345.818119 -320.429516) (xy 345.767967 -320.447802)
			(xy 345.715756 -320.458919) (xy 345.662504 -320.462649) (xy 345.609252 -320.458919) (xy 345.557041 -320.447802)
			(xy 345.506889 -320.429516) (xy 345.459775 -320.404417) (xy 345.416621 -320.372995) (xy 345.378267 -320.335865)
			(xy 345.361514 -320.315082) (xy 345.353945 -320.306328) (xy 345.333192 -320.296141) (xy 345.321636 -320.295524)
			(xy 345.241372 -320.295524) (xy 345.229808 -320.296127) (xy 345.209036 -320.306298) (xy 345.201494 -320.315082)
			(xy 345.184741 -320.335865) (xy 345.146387 -320.372995) (xy 345.103233 -320.404417) (xy 345.056119 -320.429516)
			(xy 345.005967 -320.447802) (xy 344.953756 -320.458919) (xy 344.900504 -320.462649) (xy 344.847252 -320.458919)
			(xy 344.795041 -320.447802) (xy 344.744889 -320.429516) (xy 344.697775 -320.404417) (xy 344.654621 -320.372995)
			(xy 344.616267 -320.335865) (xy 344.599514 -320.315082) (xy 344.591945 -320.306328) (xy 344.571192 -320.296141)
			(xy 344.559636 -320.295524) (xy 344.479372 -320.295524) (xy 344.467808 -320.296127) (xy 344.447036 -320.306298)
			(xy 344.439494 -320.315082) (xy 344.422741 -320.335865) (xy 344.384387 -320.372995) (xy 344.341233 -320.404417)
			(xy 344.294119 -320.429516) (xy 344.243967 -320.447802) (xy 344.191756 -320.458919) (xy 344.138504 -320.462649)
			(xy 344.085252 -320.458919) (xy 344.033041 -320.447802) (xy 343.982889 -320.429516) (xy 343.935775 -320.404417)
			(xy 343.892621 -320.372995) (xy 343.854267 -320.335865) (xy 343.837514 -320.315082) (xy 343.829945 -320.306328)
			(xy 343.809192 -320.296141) (xy 343.797636 -320.295524) (xy 343.717372 -320.295524) (xy 343.705808 -320.296127)
			(xy 343.685036 -320.306298) (xy 343.677494 -320.315082) (xy 343.660741 -320.335865) (xy 343.622387 -320.372995)
			(xy 343.579233 -320.404417) (xy 343.532119 -320.429516) (xy 343.481967 -320.447802) (xy 343.429756 -320.458919)
			(xy 343.376504 -320.462649) (xy 343.323252 -320.458919) (xy 343.271041 -320.447802) (xy 343.220889 -320.429516)
			(xy 343.173775 -320.404417) (xy 343.130621 -320.372995) (xy 343.092267 -320.335865) (xy 343.075514 -320.315082)
			(xy 343.067945 -320.306328) (xy 343.047192 -320.296141) (xy 343.035636 -320.295524) (xy 342.955372 -320.295524)
			(xy 342.943808 -320.296127) (xy 342.923036 -320.306298) (xy 342.915494 -320.315082) (xy 342.898741 -320.335865)
			(xy 342.860387 -320.372995) (xy 342.817233 -320.404417) (xy 342.770119 -320.429516) (xy 342.719967 -320.447802)
			(xy 342.667756 -320.458919) (xy 342.614504 -320.462649) (xy 342.561252 -320.458919) (xy 342.509041 -320.447802)
			(xy 342.458889 -320.429516) (xy 342.411775 -320.404417) (xy 342.368621 -320.372995) (xy 342.330267 -320.335865)
			(xy 342.313514 -320.315082) (xy 342.305945 -320.306328) (xy 342.285192 -320.296141) (xy 342.273636 -320.295524)
			(xy 342.193372 -320.295524) (xy 342.181808 -320.296127) (xy 342.161036 -320.306298) (xy 342.153494 -320.315082)
			(xy 342.136741 -320.335865) (xy 342.098387 -320.372995) (xy 342.055233 -320.404417) (xy 342.008119 -320.429516)
			(xy 341.957967 -320.447802) (xy 341.905756 -320.458919) (xy 341.852504 -320.462649) (xy 341.799252 -320.458919)
			(xy 341.747041 -320.447802) (xy 341.696889 -320.429516) (xy 341.649775 -320.404417) (xy 341.606621 -320.372995)
			(xy 341.568267 -320.335865) (xy 341.551514 -320.315082) (xy 341.543945 -320.306328) (xy 341.523192 -320.296141)
			(xy 341.511636 -320.295524) (xy 341.431372 -320.295524) (xy 341.419808 -320.296127) (xy 341.399036 -320.306298)
			(xy 341.391494 -320.315082) (xy 341.374741 -320.335865) (xy 341.336387 -320.372995) (xy 341.293233 -320.404417)
			(xy 341.246119 -320.429516) (xy 341.195967 -320.447802) (xy 341.143756 -320.458919) (xy 341.090504 -320.462649)
			(xy 341.037252 -320.458919) (xy 340.985041 -320.447802) (xy 340.934889 -320.429516) (xy 340.887775 -320.404417)
			(xy 340.844621 -320.372995) (xy 340.806267 -320.335865) (xy 340.789514 -320.315082) (xy 340.781945 -320.306328)
			(xy 340.761192 -320.296141) (xy 340.749636 -320.295524) (xy 340.669372 -320.295524) (xy 340.657808 -320.296127)
			(xy 340.637036 -320.306298) (xy 340.629494 -320.315082) (xy 340.612741 -320.335865) (xy 340.574387 -320.372995)
			(xy 340.531233 -320.404417) (xy 340.484119 -320.429516) (xy 340.433967 -320.447802) (xy 340.381756 -320.458919)
			(xy 340.328504 -320.462649) (xy 340.275252 -320.458919) (xy 340.223041 -320.447802) (xy 340.172889 -320.429516)
			(xy 340.125775 -320.404417) (xy 340.082621 -320.372995) (xy 340.044267 -320.335865) (xy 340.027514 -320.315082)
			(xy 340.019945 -320.306328) (xy 339.999192 -320.296141) (xy 339.987636 -320.295524) (xy 339.907372 -320.295524)
			(xy 339.895808 -320.296127) (xy 339.875036 -320.306298) (xy 339.867494 -320.315082) (xy 339.850741 -320.335865)
			(xy 339.812387 -320.372995) (xy 339.769233 -320.404417) (xy 339.722119 -320.429516) (xy 339.671967 -320.447802)
			(xy 339.619756 -320.458919) (xy 339.566504 -320.462649) (xy 339.513252 -320.458919) (xy 339.461041 -320.447802)
			(xy 339.410889 -320.429516) (xy 339.363775 -320.404417) (xy 339.320621 -320.372995) (xy 339.282267 -320.335865)
			(xy 339.265514 -320.315082) (xy 339.257945 -320.306328) (xy 339.237192 -320.296141) (xy 339.225636 -320.295524)
			(xy 339.145372 -320.295524) (xy 339.133808 -320.296127) (xy 339.113036 -320.306298) (xy 339.105494 -320.315082)
			(xy 339.087302 -320.337565) (xy 339.045283 -320.377301) (xy 338.997748 -320.41024) (xy 338.945787 -320.435629)
			(xy 338.89059 -320.452885) (xy 338.83342 -320.461614) (xy 338.804504 -320.462148) (xy 338.777255 -320.461619)
			(xy 338.723311 -320.453864) (xy 338.671019 -320.438511) (xy 338.621445 -320.415873) (xy 338.575596 -320.386411)
			(xy 338.534407 -320.350724) (xy 338.498715 -320.309539) (xy 338.469248 -320.263694) (xy 338.446604 -320.214122)
			(xy 338.431246 -320.161832) (xy 338.423485 -320.107889) (xy 338.422996 -320.08064) (xy 326.528802 -320.08064)
			(xy 326.551821 -320.219508) (xy 326.575796 -320.413126) (xy 326.591802 -320.607564) (xy 326.599811 -320.802496)
			(xy 326.600312 -320.900044) (xy 326.599811 -320.997592) (xy 326.591802 -321.192524) (xy 326.575796 -321.386962)
			(xy 326.551821 -321.58058) (xy 326.519917 -321.77305) (xy 326.480138 -321.964047) (xy 326.432552 -322.153251)
			(xy 326.377237 -322.340341) (xy 326.314289 -322.525003) (xy 326.243812 -322.706925) (xy 326.165926 -322.8858)
			(xy 326.080761 -323.061326) (xy 325.988463 -323.233209) (xy 325.889185 -323.401156) (xy 325.783096 -323.564887)
			(xy 325.670375 -323.724124) (xy 325.551211 -323.878598) (xy 325.425806 -324.028051) (xy 325.29437 -324.172229)
			(xy 325.249775 -324.217284) (xy 331.920086 -324.217284) (xy 331.924157 -324.161662) (xy 331.936283 -324.107225)
			(xy 331.956206 -324.055134) (xy 331.983502 -324.006499) (xy 332.017588 -323.962356) (xy 332.057737 -323.923647)
			(xy 332.103095 -323.891196) (xy 332.152695 -323.865695) (xy 332.205479 -323.847688) (xy 332.260322 -323.837558)
			(xy 332.316056 -323.835521) (xy 332.371493 -323.841621) (xy 332.42545 -323.855727) (xy 332.476779 -323.877539)
			(xy 332.524385 -323.906593) (xy 332.567253 -323.942268) (xy 332.60447 -323.983805) (xy 332.635243 -324.030318)
			(xy 332.658915 -324.080815) (xy 332.674983 -324.134222) (xy 332.683103 -324.189398) (xy 332.683612 -324.217284)
			(xy 332.683103 -324.24517) (xy 332.674983 -324.300346) (xy 332.658915 -324.353753) (xy 332.635243 -324.40425)
			(xy 332.60447 -324.450763) (xy 332.567253 -324.4923) (xy 332.524385 -324.527975) (xy 332.476779 -324.557029)
			(xy 332.42545 -324.578841) (xy 332.371493 -324.592947) (xy 332.316056 -324.599047) (xy 332.260322 -324.59701)
			(xy 332.205479 -324.58688) (xy 332.152695 -324.568873) (xy 332.103095 -324.543372) (xy 332.057737 -324.510921)
			(xy 332.017588 -324.472212) (xy 331.983502 -324.428069) (xy 331.956206 -324.379434) (xy 331.936283 -324.327343)
			(xy 331.924157 -324.272906) (xy 331.920086 -324.217284) (xy 325.249775 -324.217284) (xy 325.157126 -324.310889)
			(xy 325.014305 -324.443797) (xy 324.866148 -324.570731) (xy 324.712905 -324.691474) (xy 324.554834 -324.805824)
			(xy 324.392201 -324.913589) (xy 324.225282 -325.014585) (xy 324.054356 -325.108644) (xy 323.879713 -325.195606)
			(xy 323.701647 -325.275324) (xy 323.520459 -325.347665) (xy 323.336453 -325.412506) (xy 323.14994 -325.469738)
			(xy 322.961235 -325.519265) (xy 322.770656 -325.561002) (xy 322.578523 -325.59488) (xy 322.385162 -325.620842)
			(xy 322.190898 -325.638843) (xy 321.996059 -325.648854) (xy 321.800973 -325.650857) (xy 321.60597 -325.644849)
			(xy 321.411377 -325.63084) (xy 321.217524 -325.608854) (xy 321.024737 -325.578928) (xy 320.83334 -325.541112)
			(xy 320.643658 -325.49547) (xy 320.45601 -325.44208) (xy 320.270711 -325.38103) (xy 320.088076 -325.312425)
			(xy 319.908411 -325.236379) (xy 319.732019 -325.153021) (xy 319.559198 -325.062492) (xy 319.39024 -324.964944)
			(xy 319.225429 -324.860541) (xy 319.065043 -324.749461) (xy 318.909353 -324.631889) (xy 318.758621 -324.508025)
			(xy 318.613102 -324.378076) (xy 318.47304 -324.242263) (xy 318.338672 -324.100814) (xy 318.210225 -323.953968)
			(xy 318.087914 -323.801973) (xy 317.971947 -323.645084) (xy 317.862519 -323.483566) (xy 317.759814 -323.317692)
			(xy 317.664006 -323.147741) (xy 317.575255 -322.974) (xy 317.493713 -322.796762) (xy 317.419516 -322.616326)
			(xy 317.352789 -322.432995) (xy 317.293645 -322.24708) (xy 317.242184 -322.058893) (xy 317.198492 -321.868753)
			(xy 317.162643 -321.676978) (xy 317.134698 -321.483894) (xy 317.114703 -321.289825) (xy 317.102693 -321.095099)
			(xy 317.098687 -320.900044) (xy 301.499654 -320.900044) (xy 315.621924 -323.719444) (xy 315.674796 -323.730752)
			(xy 315.777897 -323.763336) (xy 315.827664 -323.784468) (xy 320.892334 -326.009548) (xy 331.878208 -326.009548)
			(xy 331.878208 -325.955052) (xy 331.885963 -325.90111) (xy 331.901316 -325.848822) (xy 331.923954 -325.79925)
			(xy 331.953416 -325.753404) (xy 331.989102 -325.712218) (xy 332.030286 -325.676529) (xy 332.07613 -325.647065)
			(xy 332.125701 -325.624424) (xy 332.177989 -325.609068) (xy 332.23193 -325.60131) (xy 332.259178 -325.600822)
			(xy 332.29036 -325.601455) (xy 332.35189 -325.611625) (xy 332.410952 -325.63165) (xy 332.438756 -325.64578)
			(xy 332.448662 -325.65086) (xy 332.469744 -325.652384) (xy 332.561946 -325.618348) (xy 332.577186 -325.603616)
			(xy 332.58125 -325.593202) (xy 332.592142 -325.566797) (xy 332.620668 -325.517315) (xy 332.656255 -325.47264)
			(xy 332.698105 -325.43377) (xy 332.745282 -325.401575) (xy 332.796734 -325.376775) (xy 332.851307 -325.359924)
			(xy 332.907784 -325.351398) (xy 332.936342 -325.350886) (xy 332.963591 -325.351387) (xy 333.017533 -325.359148)
			(xy 333.069822 -325.374506) (xy 333.119393 -325.39715) (xy 333.165238 -325.426617) (xy 333.206422 -325.462308)
			(xy 333.242109 -325.503496) (xy 333.271571 -325.549344) (xy 333.294208 -325.598917) (xy 333.309561 -325.651208)
			(xy 333.317316 -325.705151) (xy 333.317316 -325.759649) (xy 333.309561 -325.813592) (xy 333.294208 -325.865883)
			(xy 333.271571 -325.915456) (xy 333.242109 -325.961304) (xy 333.206422 -326.002492) (xy 333.165238 -326.038183)
			(xy 333.119393 -326.06765) (xy 333.069822 -326.090294) (xy 333.017533 -326.105652) (xy 332.963591 -326.113413)
			(xy 332.936342 -326.113902) (xy 332.905161 -326.113259) (xy 332.843631 -326.103093) (xy 332.784569 -326.083072)
			(xy 332.756764 -326.068944) (xy 332.746858 -326.063864) (xy 332.725776 -326.06234) (xy 332.633574 -326.096376)
			(xy 332.618334 -326.111108) (xy 332.61427 -326.121522) (xy 332.603375 -326.147925) (xy 332.574847 -326.197406)
			(xy 332.539261 -326.24208) (xy 332.497411 -326.280949) (xy 332.450234 -326.313144) (xy 332.398784 -326.337945)
			(xy 332.344211 -326.354797) (xy 332.287736 -326.363325) (xy 332.259178 -326.363838) (xy 332.23193 -326.36329)
			(xy 332.177989 -326.355532) (xy 332.125701 -326.340176) (xy 332.07613 -326.317535) (xy 332.030286 -326.288071)
			(xy 331.989102 -326.252382) (xy 331.953416 -326.211196) (xy 331.923954 -326.16535) (xy 331.901316 -326.115778)
			(xy 331.885963 -326.06349) (xy 331.878208 -326.009548) (xy 320.892334 -326.009548) (xy 321.255898 -326.169274)
			(xy 321.266566 -326.172576) (xy 323.521832 -326.624188) (xy 323.547232 -326.629522) (xy 323.57441 -326.636126)
			(xy 323.62775 -326.651366) (xy 323.649086 -326.658478) (xy 323.699378 -326.677274) (xy 323.699886 -326.677528)
			(xy 324.45833 -326.973438) (xy 324.916176 -327.152) (xy 330.808582 -327.152) (xy 330.812653 -327.096378)
			(xy 330.824779 -327.041941) (xy 330.844702 -326.98985) (xy 330.871998 -326.941215) (xy 330.906084 -326.897072)
			(xy 330.946233 -326.858363) (xy 330.991591 -326.825912) (xy 331.041191 -326.800411) (xy 331.093975 -326.782404)
			(xy 331.148818 -326.772274) (xy 331.204552 -326.770237) (xy 331.259989 -326.776337) (xy 331.313946 -326.790443)
			(xy 331.365275 -326.812255) (xy 331.412881 -326.841309) (xy 331.455749 -326.876984) (xy 331.492966 -326.918521)
			(xy 331.523739 -326.965034) (xy 331.547411 -327.015531) (xy 331.563479 -327.068938) (xy 331.571599 -327.124114)
			(xy 331.572108 -327.152) (xy 331.571599 -327.179886) (xy 331.563479 -327.235062) (xy 331.547411 -327.288469)
			(xy 331.523739 -327.338966) (xy 331.492966 -327.385479) (xy 331.455749 -327.427016) (xy 331.412881 -327.462691)
			(xy 331.365275 -327.491745) (xy 331.313946 -327.513557) (xy 331.259989 -327.527663) (xy 331.204552 -327.533763)
			(xy 331.148818 -327.531726) (xy 331.093975 -327.521596) (xy 331.041191 -327.503589) (xy 330.991591 -327.478088)
			(xy 330.946233 -327.445637) (xy 330.906084 -327.406928) (xy 330.871998 -327.362785) (xy 330.844702 -327.31415)
			(xy 330.824779 -327.262059) (xy 330.812653 -327.207622) (xy 330.808582 -327.152) (xy 324.916176 -327.152)
			(xy 327.118134 -328.010774) (xy 334.46288 -328.010774) (xy 334.466951 -327.955152) (xy 334.479077 -327.900715)
			(xy 334.499 -327.848624) (xy 334.526296 -327.799989) (xy 334.560382 -327.755846) (xy 334.600531 -327.717137)
			(xy 334.645889 -327.684686) (xy 334.695489 -327.659185) (xy 334.748273 -327.641178) (xy 334.803116 -327.631048)
			(xy 334.85885 -327.629011) (xy 334.914287 -327.635111) (xy 334.968244 -327.649217) (xy 335.019573 -327.671029)
			(xy 335.067179 -327.700083) (xy 335.110047 -327.735758) (xy 335.147264 -327.777295) (xy 335.178037 -327.823808)
			(xy 335.201709 -327.874305) (xy 335.217777 -327.927712) (xy 335.225897 -327.982888) (xy 335.226406 -328.010774)
			(xy 335.225897 -328.03866) (xy 335.217777 -328.093836) (xy 335.201709 -328.147243) (xy 335.178037 -328.19774)
			(xy 335.147264 -328.244253) (xy 335.110047 -328.28579) (xy 335.067179 -328.321465) (xy 335.019573 -328.350519)
			(xy 334.968244 -328.372331) (xy 334.914287 -328.386437) (xy 334.85885 -328.392537) (xy 334.803116 -328.3905)
			(xy 334.748273 -328.38037) (xy 334.695489 -328.362363) (xy 334.645889 -328.336862) (xy 334.600531 -328.304411)
			(xy 334.560382 -328.265702) (xy 334.526296 -328.221559) (xy 334.499 -328.172924) (xy 334.479077 -328.120833)
			(xy 334.466951 -328.066396) (xy 334.46288 -328.010774) (xy 327.118134 -328.010774) (xy 329.723231 -329.026774)
			(xy 334.46288 -329.026774) (xy 334.466951 -328.971152) (xy 334.479077 -328.916715) (xy 334.499 -328.864624)
			(xy 334.526296 -328.815989) (xy 334.560382 -328.771846) (xy 334.600531 -328.733137) (xy 334.645889 -328.700686)
			(xy 334.695489 -328.675185) (xy 334.748273 -328.657178) (xy 334.803116 -328.647048) (xy 334.85885 -328.645011)
			(xy 334.914287 -328.651111) (xy 334.968244 -328.665217) (xy 335.019573 -328.687029) (xy 335.067179 -328.716083)
			(xy 335.110047 -328.751758) (xy 335.147264 -328.793295) (xy 335.178037 -328.839808) (xy 335.201709 -328.890305)
			(xy 335.217777 -328.943712) (xy 335.225897 -328.998888) (xy 335.226406 -329.026774) (xy 335.225897 -329.05466)
			(xy 335.217777 -329.109836) (xy 335.201709 -329.163243) (xy 335.178037 -329.21374) (xy 335.147264 -329.260253)
			(xy 335.110047 -329.30179) (xy 335.067179 -329.337465) (xy 335.019573 -329.366519) (xy 334.968244 -329.388331)
			(xy 334.914287 -329.402437) (xy 334.85885 -329.408537) (xy 334.803116 -329.4065) (xy 334.748273 -329.39637)
			(xy 334.695489 -329.378363) (xy 334.645889 -329.352862) (xy 334.600531 -329.320411) (xy 334.560382 -329.281702)
			(xy 334.526296 -329.237559) (xy 334.499 -329.188924) (xy 334.479077 -329.136833) (xy 334.466951 -329.082396)
			(xy 334.46288 -329.026774) (xy 329.723231 -329.026774) (xy 331.101978 -329.564492) (xy 337.455762 -329.564492)
			(xy 337.459833 -329.50887) (xy 337.471959 -329.454433) (xy 337.491882 -329.402342) (xy 337.519178 -329.353707)
			(xy 337.553264 -329.309564) (xy 337.593413 -329.270855) (xy 337.638771 -329.238404) (xy 337.688371 -329.212903)
			(xy 337.741155 -329.194896) (xy 337.795998 -329.184766) (xy 337.851732 -329.182729) (xy 337.907169 -329.188829)
			(xy 337.961126 -329.202935) (xy 338.012455 -329.224747) (xy 338.060061 -329.253801) (xy 338.102929 -329.289476)
			(xy 338.140146 -329.331013) (xy 338.170919 -329.377526) (xy 338.194591 -329.428023) (xy 338.210659 -329.48143)
			(xy 338.218779 -329.536606) (xy 338.219288 -329.564492) (xy 338.827362 -329.564492) (xy 338.831433 -329.50887)
			(xy 338.843559 -329.454433) (xy 338.863482 -329.402342) (xy 338.890778 -329.353707) (xy 338.924864 -329.309564)
			(xy 338.965013 -329.270855) (xy 339.010371 -329.238404) (xy 339.059971 -329.212903) (xy 339.112755 -329.194896)
			(xy 339.167598 -329.184766) (xy 339.223332 -329.182729) (xy 339.278769 -329.188829) (xy 339.332726 -329.202935)
			(xy 339.384055 -329.224747) (xy 339.431661 -329.253801) (xy 339.474529 -329.289476) (xy 339.511746 -329.331013)
			(xy 339.542519 -329.377526) (xy 339.566191 -329.428023) (xy 339.582259 -329.48143) (xy 339.590379 -329.536606)
			(xy 339.590888 -329.564492) (xy 340.198962 -329.564492) (xy 340.203033 -329.50887) (xy 340.215159 -329.454433)
			(xy 340.235082 -329.402342) (xy 340.262378 -329.353707) (xy 340.296464 -329.309564) (xy 340.336613 -329.270855)
			(xy 340.381971 -329.238404) (xy 340.431571 -329.212903) (xy 340.484355 -329.194896) (xy 340.539198 -329.184766)
			(xy 340.594932 -329.182729) (xy 340.650369 -329.188829) (xy 340.704326 -329.202935) (xy 340.755655 -329.224747)
			(xy 340.803261 -329.253801) (xy 340.846129 -329.289476) (xy 340.883346 -329.331013) (xy 340.914119 -329.377526)
			(xy 340.937791 -329.428023) (xy 340.953859 -329.48143) (xy 340.961979 -329.536606) (xy 340.962488 -329.564492)
			(xy 341.570562 -329.564492) (xy 341.574633 -329.50887) (xy 341.586759 -329.454433) (xy 341.606682 -329.402342)
			(xy 341.633978 -329.353707) (xy 341.668064 -329.309564) (xy 341.708213 -329.270855) (xy 341.753571 -329.238404)
			(xy 341.803171 -329.212903) (xy 341.855955 -329.194896) (xy 341.910798 -329.184766) (xy 341.966532 -329.182729)
			(xy 342.021969 -329.188829) (xy 342.075926 -329.202935) (xy 342.127255 -329.224747) (xy 342.174861 -329.253801)
			(xy 342.217729 -329.289476) (xy 342.254946 -329.331013) (xy 342.285719 -329.377526) (xy 342.309391 -329.428023)
			(xy 342.325459 -329.48143) (xy 342.333579 -329.536606) (xy 342.334088 -329.564492) (xy 342.942162 -329.564492)
			(xy 342.946233 -329.50887) (xy 342.958359 -329.454433) (xy 342.978282 -329.402342) (xy 343.005578 -329.353707)
			(xy 343.039664 -329.309564) (xy 343.079813 -329.270855) (xy 343.125171 -329.238404) (xy 343.174771 -329.212903)
			(xy 343.227555 -329.194896) (xy 343.282398 -329.184766) (xy 343.338132 -329.182729) (xy 343.393569 -329.188829)
			(xy 343.447526 -329.202935) (xy 343.498855 -329.224747) (xy 343.546461 -329.253801) (xy 343.589329 -329.289476)
			(xy 343.626546 -329.331013) (xy 343.657319 -329.377526) (xy 343.680991 -329.428023) (xy 343.697059 -329.48143)
			(xy 343.705179 -329.536606) (xy 343.705688 -329.564492) (xy 344.313762 -329.564492) (xy 344.317833 -329.50887)
			(xy 344.329959 -329.454433) (xy 344.349882 -329.402342) (xy 344.377178 -329.353707) (xy 344.411264 -329.309564)
			(xy 344.451413 -329.270855) (xy 344.496771 -329.238404) (xy 344.546371 -329.212903) (xy 344.599155 -329.194896)
			(xy 344.653998 -329.184766) (xy 344.709732 -329.182729) (xy 344.765169 -329.188829) (xy 344.819126 -329.202935)
			(xy 344.870455 -329.224747) (xy 344.918061 -329.253801) (xy 344.960929 -329.289476) (xy 344.998146 -329.331013)
			(xy 345.028919 -329.377526) (xy 345.052591 -329.428023) (xy 345.068659 -329.48143) (xy 345.076779 -329.536606)
			(xy 345.077288 -329.564492) (xy 345.076779 -329.592378) (xy 345.068659 -329.647554) (xy 345.052591 -329.700961)
			(xy 345.028919 -329.751458) (xy 344.998146 -329.797971) (xy 344.960929 -329.839508) (xy 344.918061 -329.875183)
			(xy 344.870455 -329.904237) (xy 344.819126 -329.926049) (xy 344.765169 -329.940155) (xy 344.709732 -329.946255)
			(xy 344.653998 -329.944218) (xy 344.599155 -329.934088) (xy 344.546371 -329.916081) (xy 344.496771 -329.89058)
			(xy 344.451413 -329.858129) (xy 344.411264 -329.81942) (xy 344.377178 -329.775277) (xy 344.349882 -329.726642)
			(xy 344.329959 -329.674551) (xy 344.317833 -329.620114) (xy 344.313762 -329.564492) (xy 343.705688 -329.564492)
			(xy 343.705179 -329.592378) (xy 343.697059 -329.647554) (xy 343.680991 -329.700961) (xy 343.657319 -329.751458)
			(xy 343.626546 -329.797971) (xy 343.589329 -329.839508) (xy 343.546461 -329.875183) (xy 343.498855 -329.904237)
			(xy 343.447526 -329.926049) (xy 343.393569 -329.940155) (xy 343.338132 -329.946255) (xy 343.282398 -329.944218)
			(xy 343.227555 -329.934088) (xy 343.174771 -329.916081) (xy 343.125171 -329.89058) (xy 343.079813 -329.858129)
			(xy 343.039664 -329.81942) (xy 343.005578 -329.775277) (xy 342.978282 -329.726642) (xy 342.958359 -329.674551)
			(xy 342.946233 -329.620114) (xy 342.942162 -329.564492) (xy 342.334088 -329.564492) (xy 342.333579 -329.592378)
			(xy 342.325459 -329.647554) (xy 342.309391 -329.700961) (xy 342.285719 -329.751458) (xy 342.254946 -329.797971)
			(xy 342.217729 -329.839508) (xy 342.174861 -329.875183) (xy 342.127255 -329.904237) (xy 342.075926 -329.926049)
			(xy 342.021969 -329.940155) (xy 341.966532 -329.946255) (xy 341.910798 -329.944218) (xy 341.855955 -329.934088)
			(xy 341.803171 -329.916081) (xy 341.753571 -329.89058) (xy 341.708213 -329.858129) (xy 341.668064 -329.81942)
			(xy 341.633978 -329.775277) (xy 341.606682 -329.726642) (xy 341.586759 -329.674551) (xy 341.574633 -329.620114)
			(xy 341.570562 -329.564492) (xy 340.962488 -329.564492) (xy 340.961979 -329.592378) (xy 340.953859 -329.647554)
			(xy 340.937791 -329.700961) (xy 340.914119 -329.751458) (xy 340.883346 -329.797971) (xy 340.846129 -329.839508)
			(xy 340.803261 -329.875183) (xy 340.755655 -329.904237) (xy 340.704326 -329.926049) (xy 340.650369 -329.940155)
			(xy 340.594932 -329.946255) (xy 340.539198 -329.944218) (xy 340.484355 -329.934088) (xy 340.431571 -329.916081)
			(xy 340.381971 -329.89058) (xy 340.336613 -329.858129) (xy 340.296464 -329.81942) (xy 340.262378 -329.775277)
			(xy 340.235082 -329.726642) (xy 340.215159 -329.674551) (xy 340.203033 -329.620114) (xy 340.198962 -329.564492)
			(xy 339.590888 -329.564492) (xy 339.590379 -329.592378) (xy 339.582259 -329.647554) (xy 339.566191 -329.700961)
			(xy 339.542519 -329.751458) (xy 339.511746 -329.797971) (xy 339.474529 -329.839508) (xy 339.431661 -329.875183)
			(xy 339.384055 -329.904237) (xy 339.332726 -329.926049) (xy 339.278769 -329.940155) (xy 339.223332 -329.946255)
			(xy 339.167598 -329.944218) (xy 339.112755 -329.934088) (xy 339.059971 -329.916081) (xy 339.010371 -329.89058)
			(xy 338.965013 -329.858129) (xy 338.924864 -329.81942) (xy 338.890778 -329.775277) (xy 338.863482 -329.726642)
			(xy 338.843559 -329.674551) (xy 338.831433 -329.620114) (xy 338.827362 -329.564492) (xy 338.219288 -329.564492)
			(xy 338.218779 -329.592378) (xy 338.210659 -329.647554) (xy 338.194591 -329.700961) (xy 338.170919 -329.751458)
			(xy 338.140146 -329.797971) (xy 338.102929 -329.839508) (xy 338.060061 -329.875183) (xy 338.012455 -329.904237)
			(xy 337.961126 -329.926049) (xy 337.907169 -329.940155) (xy 337.851732 -329.946255) (xy 337.795998 -329.944218)
			(xy 337.741155 -329.934088) (xy 337.688371 -329.916081) (xy 337.638771 -329.89058) (xy 337.593413 -329.858129)
			(xy 337.553264 -329.81942) (xy 337.519178 -329.775277) (xy 337.491882 -329.726642) (xy 337.471959 -329.674551)
			(xy 337.459833 -329.620114) (xy 337.455762 -329.564492) (xy 331.101978 -329.564492) (xy 332.56474 -330.134976)
			(xy 332.569203 -330.136606) (xy 332.578533 -330.1384) (xy 332.583282 -330.138532)
		)
		(stroke
			(width 0)
			(type solid)
		)
		(fill yes)
		(layer "In13.Cu")
		(net "P0V8_PEX2")
	)
	(gr_poly
		(pts
			(xy 104.632506 -330.12126) (xy 104.638348 -330.106782) (xy 104.649447 -330.080758) (xy 104.678203 -330.032036)
			(xy 104.713839 -329.988095) (xy 104.755575 -329.949899) (xy 104.802493 -329.918285) (xy 104.853566 -329.893948)
			(xy 104.907674 -329.87742) (xy 104.963628 -329.869065) (xy 105.020204 -329.869065) (xy 105.076158 -329.87742)
			(xy 105.130266 -329.893948) (xy 105.181339 -329.918285) (xy 105.228257 -329.949899) (xy 105.269993 -329.988095)
			(xy 105.305629 -330.032036) (xy 105.334385 -330.080758) (xy 105.345484 -330.106782) (xy 105.351326 -330.12126)
			(xy 105.37698 -330.138532) (xy 105.923334 -330.138532) (xy 105.948988 -330.12126) (xy 105.95483 -330.106782)
			(xy 105.965929 -330.080758) (xy 105.994685 -330.032036) (xy 106.030321 -329.988095) (xy 106.072057 -329.949899)
			(xy 106.118975 -329.918285) (xy 106.170048 -329.893948) (xy 106.224156 -329.87742) (xy 106.28011 -329.869065)
			(xy 106.336686 -329.869065) (xy 106.39264 -329.87742) (xy 106.446748 -329.893948) (xy 106.497821 -329.918285)
			(xy 106.544739 -329.949899) (xy 106.586475 -329.988095) (xy 106.622111 -330.032036) (xy 106.650867 -330.080758)
			(xy 106.661966 -330.106782) (xy 106.667808 -330.12126) (xy 106.693462 -330.138532) (xy 107.238038 -330.138532)
			(xy 107.264454 -330.119736) (xy 107.269788 -330.104242) (xy 107.279359 -330.078167) (xy 107.304972 -330.028882)
			(xy 107.337463 -329.983833) (xy 107.376142 -329.943972) (xy 107.420194 -329.910141) (xy 107.468686 -329.883057)
			(xy 107.520593 -329.863291) (xy 107.574818 -329.851262) (xy 107.630214 -329.847224) (xy 107.68561 -329.851262)
			(xy 107.739835 -329.863291) (xy 107.791742 -329.883057) (xy 107.840234 -329.910141) (xy 107.884286 -329.943972)
			(xy 107.922965 -329.983833) (xy 107.955456 -330.028882) (xy 107.981069 -330.078167) (xy 107.99064 -330.104242)
			(xy 107.995974 -330.119736) (xy 108.02239 -330.138532) (xy 114.35715 -330.138532) (xy 114.365532 -330.13777)
			(xy 114.373134 -330.13625) (xy 114.386959 -330.129254) (xy 114.39271 -330.124054) (xy 114.540538 -329.976226)
			(xy 114.546395 -329.969941) (xy 114.55388 -329.95449) (xy 114.555814 -329.937431) (xy 114.554254 -329.928982)
			(xy 114.53241 -329.832462) (xy 114.515392 -329.813158) (xy 114.502946 -329.808586) (xy 114.475535 -329.79825)
			(xy 114.424012 -329.770377) (xy 114.377359 -329.73495) (xy 114.336675 -329.692803) (xy 114.302917 -329.644928)
			(xy 114.276881 -329.592453) (xy 114.259179 -329.536612) (xy 114.250228 -329.47872) (xy 114.249708 -329.44943)
			(xy 114.250169 -329.422176) (xy 114.257923 -329.368223) (xy 114.273276 -329.315922) (xy 114.295917 -329.266339)
			(xy 114.325385 -329.220484) (xy 114.361079 -329.179289) (xy 114.402272 -329.143593) (xy 114.448127 -329.114124)
			(xy 114.497709 -329.091481) (xy 114.550009 -329.076126) (xy 114.603962 -329.06837) (xy 114.631216 -329.067922)
			(xy 114.660505 -329.068458) (xy 114.718393 -329.077418) (xy 114.774231 -329.095123) (xy 114.826705 -329.121158)
			(xy 114.874581 -329.154911) (xy 114.916733 -329.195587) (xy 114.952169 -329.24223) (xy 114.980057 -329.293743)
			(xy 114.990372 -329.32116) (xy 114.994944 -329.333606) (xy 115.014248 -329.350624) (xy 115.110514 -329.372468)
			(xy 115.121231 -329.374415) (xy 115.142548 -329.370054) (xy 115.151662 -329.364086) (xy 115.155726 -329.361038)
			(xy 117.151658 -327.365106) (xy 117.160127 -327.355597) (xy 117.16733 -327.331206) (xy 117.165374 -327.318624)
			(xy 117.144546 -327.222358) (xy 117.127528 -327.2028) (xy 117.11559 -327.198228) (xy 117.088723 -327.187565)
			(xy 117.038298 -327.159308) (xy 116.992711 -327.123769) (xy 116.953006 -327.081762) (xy 116.92009 -327.034247)
			(xy 116.894717 -326.982312) (xy 116.877466 -326.927144) (xy 116.868733 -326.870005) (xy 116.868194 -326.841104)
			(xy 116.868657 -326.813851) (xy 116.876414 -326.7599) (xy 116.891769 -326.707602) (xy 116.914412 -326.658021)
			(xy 116.94388 -326.612168) (xy 116.979573 -326.570975) (xy 117.020766 -326.535281) (xy 117.066619 -326.505813)
			(xy 117.1162 -326.48317) (xy 117.168498 -326.467814) (xy 117.222449 -326.460057) (xy 117.249702 -326.459596)
			(xy 117.276477 -326.460048) (xy 117.329502 -326.467535) (xy 117.380959 -326.482362) (xy 117.429838 -326.504237)
			(xy 117.475178 -326.53273) (xy 117.51609 -326.567283) (xy 117.551769 -326.607216) (xy 117.581515 -326.651745)
			(xy 117.604743 -326.699996) (xy 117.620997 -326.75102) (xy 117.625876 -326.77735) (xy 117.627146 -326.785478)
			(xy 117.634258 -326.799194) (xy 117.6401 -326.804782) (xy 117.647466 -326.811622) (xy 117.665999 -326.819364)
			(xy 117.686083 -326.819364) (xy 117.704616 -326.811622) (xy 117.711982 -326.804782) (xy 117.756432 -326.760332)
			(xy 117.763275 -326.752933) (xy 117.770996 -326.734334) (xy 117.771418 -326.724264) (xy 117.771418 -319.04051)
			(xy 117.770961 -319.030358) (xy 117.763091 -319.011638) (xy 117.756178 -319.004188) (xy 117.696234 -318.946022)
			(xy 117.677692 -318.938656) (xy 117.667024 -318.93891) (xy 117.656864 -318.939164) (xy 117.629618 -318.938675)
			(xy 117.57568 -318.930916) (xy 117.523396 -318.915559) (xy 117.473829 -318.892919) (xy 117.427988 -318.863455)
			(xy 117.386807 -318.827767) (xy 117.351124 -318.786583) (xy 117.321664 -318.74074) (xy 117.299028 -318.691171)
			(xy 117.283677 -318.638885) (xy 117.275922 -318.584946) (xy 117.275922 -318.530454) (xy 117.283677 -318.476515)
			(xy 117.299028 -318.424229) (xy 117.321664 -318.37466) (xy 117.351124 -318.328817) (xy 117.386807 -318.287633)
			(xy 117.427988 -318.251945) (xy 117.473829 -318.222481) (xy 117.523396 -318.199841) (xy 117.57568 -318.184484)
			(xy 117.629618 -318.176725) (xy 117.656864 -318.176148) (xy 117.671012 -318.176251) (xy 117.699236 -318.178281)
			(xy 117.713252 -318.180212) (xy 117.716808 -318.180974) (xy 117.720618 -318.180974) (xy 117.730635 -318.180551)
			(xy 117.749141 -318.172877) (xy 117.763301 -318.158704) (xy 117.770959 -318.140191) (xy 117.771418 -318.130174)
			(xy 117.771418 -318.120522) (xy 117.771002 -318.110497) (xy 117.763337 -318.091969) (xy 117.749165 -318.077785)
			(xy 117.730643 -318.070106) (xy 117.720618 -318.069722) (xy 117.716808 -318.069722) (xy 117.713252 -318.070484)
			(xy 117.699236 -318.072419) (xy 117.671013 -318.07445) (xy 117.656864 -318.074548) (xy 117.629612 -318.07406)
			(xy 117.575662 -318.066298) (xy 117.523366 -318.050938) (xy 117.473788 -318.028293) (xy 117.427938 -317.998822)
			(xy 117.386747 -317.963127) (xy 117.351056 -317.921934) (xy 117.32159 -317.87608) (xy 117.298949 -317.8265)
			(xy 117.283594 -317.774203) (xy 117.275838 -317.720252) (xy 117.275838 -317.665748) (xy 117.283594 -317.611797)
			(xy 117.298949 -317.5595) (xy 117.32159 -317.50992) (xy 117.351056 -317.464066) (xy 117.386747 -317.422873)
			(xy 117.427938 -317.387178) (xy 117.473788 -317.357707) (xy 117.523366 -317.335062) (xy 117.575662 -317.319702)
			(xy 117.629612 -317.31194) (xy 117.656864 -317.311532) (xy 117.667024 -317.311786) (xy 117.677692 -317.31204)
			(xy 117.696234 -317.304674) (xy 117.756178 -317.246508) (xy 117.763128 -317.239084) (xy 117.770992 -317.220347)
			(xy 117.771418 -317.210186) (xy 117.771418 -316.472824) (xy 117.770964 -316.462671) (xy 117.763098 -316.443948)
			(xy 117.756178 -316.436502) (xy 117.696234 -316.378336) (xy 117.677692 -316.37097) (xy 117.667024 -316.371224)
			(xy 117.656864 -316.371478) (xy 117.629617 -316.370989) (xy 117.575677 -316.363229) (xy 117.523391 -316.347872)
			(xy 117.473822 -316.325231) (xy 117.42798 -316.295766) (xy 117.386797 -316.260077) (xy 117.351112 -316.218891)
			(xy 117.321652 -316.173046) (xy 117.299015 -316.123475) (xy 117.283663 -316.071188) (xy 117.275908 -316.017247)
			(xy 117.275908 -315.962753) (xy 117.283663 -315.908812) (xy 117.299015 -315.856525) (xy 117.321652 -315.806954)
			(xy 117.351112 -315.761109) (xy 117.386797 -315.719923) (xy 117.42798 -315.684234) (xy 117.473822 -315.654769)
			(xy 117.523391 -315.632128) (xy 117.575677 -315.616771) (xy 117.629617 -315.609011) (xy 117.656864 -315.608462)
			(xy 117.667024 -315.608716) (xy 117.677692 -315.60897) (xy 117.696234 -315.601604) (xy 117.756178 -315.543438)
			(xy 117.763133 -315.536015) (xy 117.771008 -315.517279) (xy 117.771418 -315.507116) (xy 117.771418 -294.218106)
			(xy 117.763798 -294.19931) (xy 117.756432 -294.192198) (xy 117.552724 -293.98849) (xy 117.545326 -293.981646)
			(xy 117.526726 -293.973925) (xy 117.516656 -293.973504) (xy 116.471446 -293.973504) (xy 116.458238 -293.971726)
			(xy 116.454936 -293.97071) (xy 116.451634 -293.96944) (xy 116.447181 -293.967774) (xy 116.437845 -293.965986)
			(xy 116.433092 -293.965884) (xy 101.227128 -293.965884) (xy 101.217064 -293.965447) (xy 101.19848 -293.957713)
			(xy 101.19106 -293.950898) (xy 100.578158 -293.337996) (xy 100.571046 -293.33063) (xy 100.55225 -293.32301)
			(xy 99.858576 -293.32301) (xy 99.853496 -293.324026) (xy 99.766653 -293.3409) (xy 99.591669 -293.36708)
			(xy 99.415604 -293.384572) (xy 99.23889 -293.393331) (xy 99.150424 -293.393876) (xy 99.149916 -293.393876)
			(xy 99.064856 -293.393378) (xy 98.894928 -293.385284) (xy 98.725578 -293.369114) (xy 98.557189 -293.344904)
			(xy 98.390143 -293.312709) (xy 98.224818 -293.272602) (xy 98.061588 -293.224674) (xy 97.900824 -293.169034)
			(xy 97.74289 -293.105807) (xy 97.588143 -293.035137) (xy 97.436934 -292.957184) (xy 97.289605 -292.872124)
			(xy 97.14649 -292.78015) (xy 97.007914 -292.681471) (xy 96.87419 -292.57631) (xy 96.745622 -292.464905)
			(xy 96.6225 -292.347509) (xy 96.505103 -292.224387) (xy 96.393698 -292.095819) (xy 96.288536 -291.962096)
			(xy 96.189856 -291.82352) (xy 96.097882 -291.680405) (xy 96.012822 -291.533077) (xy 95.934868 -291.381868)
			(xy 95.864198 -291.227121) (xy 95.80097 -291.069187) (xy 95.745329 -290.908423) (xy 95.697401 -290.745194)
			(xy 95.657293 -290.579869) (xy 95.625098 -290.412823) (xy 95.600887 -290.244434) (xy 95.584717 -290.075084)
			(xy 95.576622 -289.905156) (xy 95.576136 -289.820096) (xy 95.576604 -289.73791) (xy 95.584161 -289.573712)
			(xy 95.59926 -289.410035) (xy 95.621868 -289.247225) (xy 95.651937 -289.085627) (xy 95.689404 -288.925582)
			(xy 95.734189 -288.767429) (xy 95.786198 -288.611502) (xy 95.845322 -288.458131) (xy 95.911434 -288.307641)
			(xy 95.984395 -288.160349) (xy 96.06405 -288.016567) (xy 96.106742 -287.946338) (xy 96.113346 -287.93567)
			(xy 96.115124 -287.911032) (xy 96.071944 -287.811464) (xy 96.05264 -287.79597) (xy 96.040448 -287.79343)
			(xy 96.012065 -287.787123) (xy 95.957493 -287.767067) (xy 95.906597 -287.738964) (xy 95.860553 -287.703464)
			(xy 95.820429 -287.661388) (xy 95.787152 -287.613713) (xy 95.761495 -287.56154) (xy 95.744051 -287.506078)
			(xy 95.735223 -287.448612) (xy 95.734632 -287.419542) (xy 95.735083 -287.392756) (xy 95.742576 -287.339712)
			(xy 95.757421 -287.288238) (xy 95.779325 -287.239349) (xy 95.807857 -287.194008) (xy 95.842455 -287.153108)
			(xy 95.882438 -287.117453) (xy 95.927018 -287.087746) (xy 95.975318 -287.064572) (xy 96.026386 -287.048388)
			(xy 96.079217 -287.039512) (xy 96.10598 -287.038288) (xy 96.115886 -287.03778) (xy 96.133666 -287.03016)
			(xy 96.197166 -286.965644) (xy 96.204786 -286.94761) (xy 96.204786 -286.937704) (xy 96.205564 -286.910175)
			(xy 96.214065 -286.855762) (xy 96.230298 -286.803137) (xy 96.253927 -286.753392) (xy 96.284461 -286.707559)
			(xy 96.321266 -286.666591) (xy 96.363577 -286.631339) (xy 96.410516 -286.602535) (xy 96.461108 -286.580777)
			(xy 96.514302 -286.566516) (xy 96.54159 -286.5628) (xy 96.54667 -286.562292) (xy 96.546924 -286.562292)
			(xy 96.54921 -286.562038) (xy 96.587564 -286.56026) (xy 96.599984 -286.560377) (xy 96.624768 -286.56203)
			(xy 96.637094 -286.563562) (xy 96.664188 -286.567679) (xy 96.716899 -286.582671) (xy 96.766923 -286.60505)
			(xy 96.81323 -286.634355) (xy 96.854869 -286.669985) (xy 96.890981 -286.711205) (xy 96.920824 -286.757169)
			(xy 96.943784 -286.806928) (xy 96.952054 -286.833056) (xy 96.95561 -286.84474) (xy 96.972374 -286.86252)
			(xy 97.057718 -286.892492) (xy 97.065523 -286.8949) (xy 97.081846 -286.895163) (xy 97.089722 -286.893)
			(xy 97.107248 -286.887412) (xy 97.113598 -286.883094) (xy 97.18234 -286.836019) (xy 97.323554 -286.747565)
			(xy 97.468737 -286.665789) (xy 97.617574 -286.590869) (xy 97.769741 -286.522967) (xy 97.924908 -286.462232)
			(xy 98.082736 -286.408795) (xy 98.242884 -286.362772) (xy 98.405003 -286.324263) (xy 98.568741 -286.293353)
			(xy 98.733741 -286.270107) (xy 98.899645 -286.254578) (xy 99.066093 -286.246798) (xy 99.149408 -286.246316)
			(xy 99.149916 -286.246316) (xy 99.230942 -286.247332) (xy 99.241356 -286.247586) (xy 99.260152 -286.24022)
			(xy 99.319588 -286.182054) (xy 99.326545 -286.174632) (xy 99.334424 -286.155895) (xy 99.334828 -286.145732)
			(xy 99.334828 -265.274552) (xy 99.327208 -265.255756) (xy 99.319842 -265.248644) (xy 99.069652 -264.998454)
			(xy 99.062253 -264.991609) (xy 99.043655 -264.983884) (xy 99.033584 -264.983468) (xy 66.255392 -264.983468)
			(xy 66.242184 -264.98169) (xy 66.238882 -264.980674) (xy 66.23558 -264.979404) (xy 66.231128 -264.977732)
			(xy 66.221792 -264.975932) (xy 66.217038 -264.975848) (xy 51.36515 -264.975848) (xy 51.346354 -264.983468)
			(xy 51.339242 -264.990834) (xy 49.194212 -267.135864) (xy 49.187375 -267.143266) (xy 49.179662 -267.161864)
			(xy 49.179226 -267.171932) (xy 49.179226 -270.89989) (xy 84.898745 -270.89989) (xy 84.902751 -270.704835)
			(xy 84.914761 -270.510109) (xy 84.934756 -270.31604) (xy 84.962701 -270.122956) (xy 84.99855 -269.931181)
			(xy 85.042242 -269.741041) (xy 85.093703 -269.552854) (xy 85.152847 -269.366939) (xy 85.219574 -269.183608)
			(xy 85.293771 -269.003172) (xy 85.375313 -268.825934) (xy 85.464064 -268.652193) (xy 85.559872 -268.482242)
			(xy 85.662577 -268.316368) (xy 85.772005 -268.15485) (xy 85.887972 -267.997961) (xy 86.010283 -267.845966)
			(xy 86.13873 -267.69912) (xy 86.273098 -267.557671) (xy 86.41316 -267.421858) (xy 86.558679 -267.291909)
			(xy 86.709411 -267.168045) (xy 86.865101 -267.050473) (xy 87.025487 -266.939393) (xy 87.190298 -266.83499)
			(xy 87.359256 -266.737442) (xy 87.532077 -266.646913) (xy 87.708469 -266.563555) (xy 87.888134 -266.487509)
			(xy 88.070769 -266.418904) (xy 88.256068 -266.357854) (xy 88.443716 -266.304464) (xy 88.633398 -266.258822)
			(xy 88.824795 -266.221006) (xy 89.017582 -266.19108) (xy 89.211435 -266.169094) (xy 89.406028 -266.155085)
			(xy 89.601031 -266.149077) (xy 89.796117 -266.15108) (xy 89.990956 -266.161091) (xy 90.18522 -266.179092)
			(xy 90.378581 -266.205054) (xy 90.570714 -266.238932) (xy 90.761293 -266.280669) (xy 90.949998 -266.330196)
			(xy 91.136511 -266.387428) (xy 91.320517 -266.452269) (xy 91.501705 -266.52461) (xy 91.679771 -266.604328)
			(xy 91.854414 -266.69129) (xy 92.02534 -266.785349) (xy 92.192259 -266.886345) (xy 92.354892 -266.99411)
			(xy 92.512963 -267.10846) (xy 92.666206 -267.229203) (xy 92.814363 -267.356137) (xy 92.957184 -267.489045)
			(xy 93.094428 -267.627705) (xy 93.225864 -267.771883) (xy 93.351269 -267.921336) (xy 93.470433 -268.07581)
			(xy 93.583154 -268.235047) (xy 93.689243 -268.398778) (xy 93.788521 -268.566725) (xy 93.880819 -268.738608)
			(xy 93.965984 -268.914134) (xy 94.04387 -269.093009) (xy 94.114347 -269.274931) (xy 94.177295 -269.459593)
			(xy 94.23261 -269.646683) (xy 94.280196 -269.835887) (xy 94.319975 -270.026884) (xy 94.351879 -270.219354)
			(xy 94.375854 -270.412972) (xy 94.39186 -270.60741) (xy 94.399869 -270.802342) (xy 94.40037 -270.89989)
			(xy 94.399869 -270.997438) (xy 94.39186 -271.19237) (xy 94.375854 -271.386808) (xy 94.351879 -271.580426)
			(xy 94.319975 -271.772896) (xy 94.280196 -271.963893) (xy 94.23261 -272.153097) (xy 94.177295 -272.340187)
			(xy 94.114347 -272.524849) (xy 94.04387 -272.706771) (xy 93.965984 -272.885646) (xy 93.880819 -273.061172)
			(xy 93.788521 -273.233055) (xy 93.689243 -273.401002) (xy 93.583154 -273.564733) (xy 93.470433 -273.72397)
			(xy 93.351269 -273.878444) (xy 93.225864 -274.027897) (xy 93.094428 -274.172075) (xy 92.957184 -274.310735)
			(xy 92.814363 -274.443643) (xy 92.666206 -274.570577) (xy 92.512963 -274.69132) (xy 92.354892 -274.80567)
			(xy 92.192259 -274.913435) (xy 92.02534 -275.014431) (xy 91.854414 -275.10849) (xy 91.679771 -275.195452)
			(xy 91.501705 -275.27517) (xy 91.320517 -275.347511) (xy 91.136511 -275.412352) (xy 90.949998 -275.469584)
			(xy 90.761293 -275.519111) (xy 90.570714 -275.560848) (xy 90.378581 -275.594726) (xy 90.18522 -275.620688)
			(xy 89.990956 -275.638689) (xy 89.796117 -275.6487) (xy 89.601031 -275.650703) (xy 89.406028 -275.644695)
			(xy 89.211435 -275.630686) (xy 89.017582 -275.6087) (xy 88.824795 -275.578774) (xy 88.633398 -275.540958)
			(xy 88.443716 -275.495316) (xy 88.256068 -275.441926) (xy 88.070769 -275.380876) (xy 87.888134 -275.312271)
			(xy 87.708469 -275.236225) (xy 87.532077 -275.152867) (xy 87.359256 -275.062338) (xy 87.190298 -274.96479)
			(xy 87.025487 -274.860387) (xy 86.865101 -274.749307) (xy 86.709411 -274.631735) (xy 86.558679 -274.507871)
			(xy 86.41316 -274.377922) (xy 86.273098 -274.242109) (xy 86.13873 -274.10066) (xy 86.010283 -273.953814)
			(xy 85.887972 -273.801819) (xy 85.772005 -273.64493) (xy 85.662577 -273.483412) (xy 85.559872 -273.317538)
			(xy 85.464064 -273.147587) (xy 85.375313 -272.973846) (xy 85.293771 -272.796608) (xy 85.219574 -272.616172)
			(xy 85.152847 -272.432841) (xy 85.093703 -272.246926) (xy 85.042242 -272.058739) (xy 84.99855 -271.868599)
			(xy 84.962701 -271.676824) (xy 84.934756 -271.48374) (xy 84.914761 -271.289671) (xy 84.902751 -271.094945)
			(xy 84.898745 -270.89989) (xy 49.179226 -270.89989) (xy 49.179226 -271.539462) (xy 49.178792 -271.549528)
			(xy 49.171065 -271.568118) (xy 49.16424 -271.57553) (xy 49.156874 -271.582642) (xy 49.149254 -271.601438)
			(xy 49.149254 -272.14957) (xy 49.843702 -272.14957) (xy 49.847662 -272.100516) (xy 49.859439 -272.052732)
			(xy 49.87873 -272.007456) (xy 49.905033 -271.96586) (xy 49.937668 -271.929023) (xy 49.975789 -271.897898)
			(xy 50.01841 -271.873291) (xy 50.064426 -271.855839) (xy 50.112645 -271.845995) (xy 50.16182 -271.844014)
			(xy 50.210675 -271.849946) (xy 50.257946 -271.863638) (xy 50.302408 -271.884736) (xy 50.342911 -271.912692)
			(xy 50.378404 -271.946784) (xy 50.407969 -271.986128) (xy 50.43084 -272.029705) (xy 50.446424 -272.076386)
			(xy 50.454319 -272.124963) (xy 50.454814 -272.14957) (xy 51.743876 -272.14957) (xy 51.747836 -272.100516)
			(xy 51.759613 -272.052732) (xy 51.778904 -272.007456) (xy 51.805207 -271.96586) (xy 51.837842 -271.929023)
			(xy 51.875963 -271.897898) (xy 51.918584 -271.873291) (xy 51.9646 -271.855839) (xy 52.012819 -271.845995)
			(xy 52.061994 -271.844014) (xy 52.110849 -271.849946) (xy 52.15812 -271.863638) (xy 52.202582 -271.884736)
			(xy 52.243085 -271.912692) (xy 52.278578 -271.946784) (xy 52.308143 -271.986128) (xy 52.331014 -272.029705)
			(xy 52.346598 -272.076386) (xy 52.354493 -272.124963) (xy 52.354988 -272.14957) (xy 53.643796 -272.14957)
			(xy 53.647756 -272.100516) (xy 53.659533 -272.052732) (xy 53.678824 -272.007456) (xy 53.705127 -271.96586)
			(xy 53.737762 -271.929023) (xy 53.775883 -271.897898) (xy 53.818504 -271.873291) (xy 53.86452 -271.855839)
			(xy 53.912739 -271.845995) (xy 53.961914 -271.844014) (xy 54.010769 -271.849946) (xy 54.05804 -271.863638)
			(xy 54.102502 -271.884736) (xy 54.143005 -271.912692) (xy 54.178498 -271.946784) (xy 54.208063 -271.986128)
			(xy 54.230934 -272.029705) (xy 54.246518 -272.076386) (xy 54.254413 -272.124963) (xy 54.254908 -272.14957)
			(xy 55.543716 -272.14957) (xy 55.547676 -272.100516) (xy 55.559453 -272.052732) (xy 55.578744 -272.007456)
			(xy 55.605047 -271.96586) (xy 55.637682 -271.929023) (xy 55.675803 -271.897898) (xy 55.718424 -271.873291)
			(xy 55.76444 -271.855839) (xy 55.812659 -271.845995) (xy 55.861834 -271.844014) (xy 55.910689 -271.849946)
			(xy 55.95796 -271.863638) (xy 56.002422 -271.884736) (xy 56.042925 -271.912692) (xy 56.078418 -271.946784)
			(xy 56.107983 -271.986128) (xy 56.130854 -272.029705) (xy 56.146438 -272.076386) (xy 56.154333 -272.124963)
			(xy 56.154828 -272.14957) (xy 57.44389 -272.14957) (xy 57.44785 -272.100516) (xy 57.459627 -272.052732)
			(xy 57.478918 -272.007456) (xy 57.505221 -271.96586) (xy 57.537856 -271.929023) (xy 57.575977 -271.897898)
			(xy 57.618598 -271.873291) (xy 57.664614 -271.855839) (xy 57.712833 -271.845995) (xy 57.762008 -271.844014)
			(xy 57.810863 -271.849946) (xy 57.858134 -271.863638) (xy 57.902596 -271.884736) (xy 57.943099 -271.912692)
			(xy 57.978592 -271.946784) (xy 58.008157 -271.986128) (xy 58.031028 -272.029705) (xy 58.046612 -272.076386)
			(xy 58.054507 -272.124963) (xy 58.054997 -272.149316) (xy 59.34381 -272.149316) (xy 59.34777 -272.100262)
			(xy 59.359547 -272.052478) (xy 59.378838 -272.007202) (xy 59.405141 -271.965606) (xy 59.437776 -271.928769)
			(xy 59.475897 -271.897644) (xy 59.518518 -271.873037) (xy 59.564534 -271.855585) (xy 59.612753 -271.845741)
			(xy 59.661928 -271.84376) (xy 59.710783 -271.849692) (xy 59.758054 -271.863384) (xy 59.802516 -271.884482)
			(xy 59.843019 -271.912438) (xy 59.878512 -271.94653) (xy 59.908077 -271.985874) (xy 59.930948 -272.029451)
			(xy 59.946532 -272.076132) (xy 59.954427 -272.124709) (xy 59.954922 -272.149316) (xy 59.954917 -272.14957)
			(xy 61.24373 -272.14957) (xy 61.24769 -272.100516) (xy 61.259467 -272.052732) (xy 61.278758 -272.007456)
			(xy 61.305061 -271.96586) (xy 61.337696 -271.929023) (xy 61.375817 -271.897898) (xy 61.418438 -271.873291)
			(xy 61.464454 -271.855839) (xy 61.512673 -271.845995) (xy 61.561848 -271.844014) (xy 61.610703 -271.849946)
			(xy 61.657974 -271.863638) (xy 61.702436 -271.884736) (xy 61.742939 -271.912692) (xy 61.778432 -271.946784)
			(xy 61.807997 -271.986128) (xy 61.830868 -272.029705) (xy 61.846452 -272.076386) (xy 61.854347 -272.124963)
			(xy 61.854842 -272.14957) (xy 63.143904 -272.14957) (xy 63.147864 -272.100516) (xy 63.159641 -272.052732)
			(xy 63.178932 -272.007456) (xy 63.205235 -271.96586) (xy 63.23787 -271.929023) (xy 63.275991 -271.897898)
			(xy 63.318612 -271.873291) (xy 63.364628 -271.855839) (xy 63.412847 -271.845995) (xy 63.462022 -271.844014)
			(xy 63.510877 -271.849946) (xy 63.558148 -271.863638) (xy 63.60261 -271.884736) (xy 63.643113 -271.912692)
			(xy 63.678606 -271.946784) (xy 63.708171 -271.986128) (xy 63.731042 -272.029705) (xy 63.746626 -272.076386)
			(xy 63.754521 -272.124963) (xy 63.755016 -272.14957) (xy 65.043824 -272.14957) (xy 65.047784 -272.100516)
			(xy 65.059561 -272.052732) (xy 65.078852 -272.007456) (xy 65.105155 -271.96586) (xy 65.13779 -271.929023)
			(xy 65.175911 -271.897898) (xy 65.218532 -271.873291) (xy 65.264548 -271.855839) (xy 65.312767 -271.845995)
			(xy 65.361942 -271.844014) (xy 65.410797 -271.849946) (xy 65.458068 -271.863638) (xy 65.50253 -271.884736)
			(xy 65.543033 -271.912692) (xy 65.578526 -271.946784) (xy 65.608091 -271.986128) (xy 65.630962 -272.029705)
			(xy 65.646546 -272.076386) (xy 65.654441 -272.124963) (xy 65.654936 -272.14957) (xy 66.943744 -272.14957)
			(xy 66.947704 -272.100516) (xy 66.959481 -272.052732) (xy 66.978772 -272.007456) (xy 67.005075 -271.96586)
			(xy 67.03771 -271.929023) (xy 67.075831 -271.897898) (xy 67.118452 -271.873291) (xy 67.164468 -271.855839)
			(xy 67.212687 -271.845995) (xy 67.261862 -271.844014) (xy 67.310717 -271.849946) (xy 67.357988 -271.863638)
			(xy 67.40245 -271.884736) (xy 67.442953 -271.912692) (xy 67.478446 -271.946784) (xy 67.508011 -271.986128)
			(xy 67.530882 -272.029705) (xy 67.546466 -272.076386) (xy 67.554361 -272.124963) (xy 67.554856 -272.14957)
			(xy 68.843918 -272.14957) (xy 68.847878 -272.100516) (xy 68.859655 -272.052732) (xy 68.878946 -272.007456)
			(xy 68.905249 -271.96586) (xy 68.937884 -271.929023) (xy 68.976005 -271.897898) (xy 69.018626 -271.873291)
			(xy 69.064642 -271.855839) (xy 69.112861 -271.845995) (xy 69.162036 -271.844014) (xy 69.210891 -271.849946)
			(xy 69.258162 -271.863638) (xy 69.302624 -271.884736) (xy 69.343127 -271.912692) (xy 69.37862 -271.946784)
			(xy 69.408185 -271.986128) (xy 69.431056 -272.029705) (xy 69.44664 -272.076386) (xy 69.454535 -272.124963)
			(xy 69.45503 -272.14957) (xy 70.743838 -272.14957) (xy 70.747798 -272.100516) (xy 70.759575 -272.052732)
			(xy 70.778866 -272.007456) (xy 70.805169 -271.96586) (xy 70.837804 -271.929023) (xy 70.875925 -271.897898)
			(xy 70.918546 -271.873291) (xy 70.964562 -271.855839) (xy 71.012781 -271.845995) (xy 71.061956 -271.844014)
			(xy 71.110811 -271.849946) (xy 71.158082 -271.863638) (xy 71.202544 -271.884736) (xy 71.243047 -271.912692)
			(xy 71.27854 -271.946784) (xy 71.308105 -271.986128) (xy 71.330976 -272.029705) (xy 71.34656 -272.076386)
			(xy 71.354455 -272.124963) (xy 71.35495 -272.14957) (xy 72.643758 -272.14957) (xy 72.647718 -272.100516)
			(xy 72.659495 -272.052732) (xy 72.678786 -272.007456) (xy 72.705089 -271.96586) (xy 72.737724 -271.929023)
			(xy 72.775845 -271.897898) (xy 72.818466 -271.873291) (xy 72.864482 -271.855839) (xy 72.912701 -271.845995)
			(xy 72.961876 -271.844014) (xy 73.010731 -271.849946) (xy 73.058002 -271.863638) (xy 73.102464 -271.884736)
			(xy 73.142967 -271.912692) (xy 73.17846 -271.946784) (xy 73.208025 -271.986128) (xy 73.230896 -272.029705)
			(xy 73.24648 -272.076386) (xy 73.254375 -272.124963) (xy 73.25487 -272.14957) (xy 74.543932 -272.14957)
			(xy 74.547892 -272.100516) (xy 74.559669 -272.052732) (xy 74.57896 -272.007456) (xy 74.605263 -271.96586)
			(xy 74.637898 -271.929023) (xy 74.676019 -271.897898) (xy 74.71864 -271.873291) (xy 74.764656 -271.855839)
			(xy 74.812875 -271.845995) (xy 74.86205 -271.844014) (xy 74.910905 -271.849946) (xy 74.958176 -271.863638)
			(xy 75.002638 -271.884736) (xy 75.043141 -271.912692) (xy 75.078634 -271.946784) (xy 75.108199 -271.986128)
			(xy 75.13107 -272.029705) (xy 75.146654 -272.076386) (xy 75.154549 -272.124963) (xy 75.155044 -272.14957)
			(xy 76.444106 -272.14957) (xy 76.448066 -272.100516) (xy 76.459843 -272.052732) (xy 76.479134 -272.007456)
			(xy 76.505437 -271.96586) (xy 76.538072 -271.929023) (xy 76.576193 -271.897898) (xy 76.618814 -271.873291)
			(xy 76.66483 -271.855839) (xy 76.713049 -271.845995) (xy 76.762224 -271.844014) (xy 76.811079 -271.849946)
			(xy 76.85835 -271.863638) (xy 76.902812 -271.884736) (xy 76.943315 -271.912692) (xy 76.978808 -271.946784)
			(xy 77.008373 -271.986128) (xy 77.031244 -272.029705) (xy 77.046828 -272.076386) (xy 77.054723 -272.124963)
			(xy 77.055218 -272.14957) (xy 78.344026 -272.14957) (xy 78.347986 -272.100516) (xy 78.359763 -272.052732)
			(xy 78.379054 -272.007456) (xy 78.405357 -271.96586) (xy 78.437992 -271.929023) (xy 78.476113 -271.897898)
			(xy 78.518734 -271.873291) (xy 78.56475 -271.855839) (xy 78.612969 -271.845995) (xy 78.662144 -271.844014)
			(xy 78.710999 -271.849946) (xy 78.75827 -271.863638) (xy 78.802732 -271.884736) (xy 78.843235 -271.912692)
			(xy 78.878728 -271.946784) (xy 78.908293 -271.986128) (xy 78.931164 -272.029705) (xy 78.946748 -272.076386)
			(xy 78.954643 -272.124963) (xy 78.955138 -272.14957) (xy 80.243946 -272.14957) (xy 80.247906 -272.100516)
			(xy 80.259683 -272.052732) (xy 80.278974 -272.007456) (xy 80.305277 -271.96586) (xy 80.337912 -271.929023)
			(xy 80.376033 -271.897898) (xy 80.418654 -271.873291) (xy 80.46467 -271.855839) (xy 80.512889 -271.845995)
			(xy 80.562064 -271.844014) (xy 80.610919 -271.849946) (xy 80.65819 -271.863638) (xy 80.702652 -271.884736)
			(xy 80.743155 -271.912692) (xy 80.778648 -271.946784) (xy 80.808213 -271.986128) (xy 80.831084 -272.029705)
			(xy 80.846668 -272.076386) (xy 80.854563 -272.124963) (xy 80.855058 -272.14957) (xy 80.854563 -272.174177)
			(xy 80.846668 -272.222754) (xy 80.831084 -272.269435) (xy 80.808213 -272.313012) (xy 80.778648 -272.352356)
			(xy 80.743155 -272.386448) (xy 80.702652 -272.414404) (xy 80.65819 -272.435502) (xy 80.610919 -272.449194)
			(xy 80.562064 -272.455126) (xy 80.512889 -272.453145) (xy 80.46467 -272.443301) (xy 80.418654 -272.425849)
			(xy 80.376033 -272.401242) (xy 80.337912 -272.370117) (xy 80.305277 -272.33328) (xy 80.278974 -272.291684)
			(xy 80.259683 -272.246408) (xy 80.247906 -272.198624) (xy 80.243946 -272.14957) (xy 78.955138 -272.14957)
			(xy 78.954643 -272.174177) (xy 78.946748 -272.222754) (xy 78.931164 -272.269435) (xy 78.908293 -272.313012)
			(xy 78.878728 -272.352356) (xy 78.843235 -272.386448) (xy 78.802732 -272.414404) (xy 78.75827 -272.435502)
			(xy 78.710999 -272.449194) (xy 78.662144 -272.455126) (xy 78.612969 -272.453145) (xy 78.56475 -272.443301)
			(xy 78.518734 -272.425849) (xy 78.476113 -272.401242) (xy 78.437992 -272.370117) (xy 78.405357 -272.33328)
			(xy 78.379054 -272.291684) (xy 78.359763 -272.246408) (xy 78.347986 -272.198624) (xy 78.344026 -272.14957)
			(xy 77.055218 -272.14957) (xy 77.054723 -272.174177) (xy 77.046828 -272.222754) (xy 77.031244 -272.269435)
			(xy 77.008373 -272.313012) (xy 76.978808 -272.352356) (xy 76.943315 -272.386448) (xy 76.902812 -272.414404)
			(xy 76.85835 -272.435502) (xy 76.811079 -272.449194) (xy 76.762224 -272.455126) (xy 76.713049 -272.453145)
			(xy 76.66483 -272.443301) (xy 76.618814 -272.425849) (xy 76.576193 -272.401242) (xy 76.538072 -272.370117)
			(xy 76.505437 -272.33328) (xy 76.479134 -272.291684) (xy 76.459843 -272.246408) (xy 76.448066 -272.198624)
			(xy 76.444106 -272.14957) (xy 75.155044 -272.14957) (xy 75.154549 -272.174177) (xy 75.146654 -272.222754)
			(xy 75.13107 -272.269435) (xy 75.108199 -272.313012) (xy 75.078634 -272.352356) (xy 75.043141 -272.386448)
			(xy 75.002638 -272.414404) (xy 74.958176 -272.435502) (xy 74.910905 -272.449194) (xy 74.86205 -272.455126)
			(xy 74.812875 -272.453145) (xy 74.764656 -272.443301) (xy 74.71864 -272.425849) (xy 74.676019 -272.401242)
			(xy 74.637898 -272.370117) (xy 74.605263 -272.33328) (xy 74.57896 -272.291684) (xy 74.559669 -272.246408)
			(xy 74.547892 -272.198624) (xy 74.543932 -272.14957) (xy 73.25487 -272.14957) (xy 73.254375 -272.174177)
			(xy 73.24648 -272.222754) (xy 73.230896 -272.269435) (xy 73.208025 -272.313012) (xy 73.17846 -272.352356)
			(xy 73.142967 -272.386448) (xy 73.102464 -272.414404) (xy 73.058002 -272.435502) (xy 73.010731 -272.449194)
			(xy 72.961876 -272.455126) (xy 72.912701 -272.453145) (xy 72.864482 -272.443301) (xy 72.818466 -272.425849)
			(xy 72.775845 -272.401242) (xy 72.737724 -272.370117) (xy 72.705089 -272.33328) (xy 72.678786 -272.291684)
			(xy 72.659495 -272.246408) (xy 72.647718 -272.198624) (xy 72.643758 -272.14957) (xy 71.35495 -272.14957)
			(xy 71.354455 -272.174177) (xy 71.34656 -272.222754) (xy 71.330976 -272.269435) (xy 71.308105 -272.313012)
			(xy 71.27854 -272.352356) (xy 71.243047 -272.386448) (xy 71.202544 -272.414404) (xy 71.158082 -272.435502)
			(xy 71.110811 -272.449194) (xy 71.061956 -272.455126) (xy 71.012781 -272.453145) (xy 70.964562 -272.443301)
			(xy 70.918546 -272.425849) (xy 70.875925 -272.401242) (xy 70.837804 -272.370117) (xy 70.805169 -272.33328)
			(xy 70.778866 -272.291684) (xy 70.759575 -272.246408) (xy 70.747798 -272.198624) (xy 70.743838 -272.14957)
			(xy 69.45503 -272.14957) (xy 69.454535 -272.174177) (xy 69.44664 -272.222754) (xy 69.431056 -272.269435)
			(xy 69.408185 -272.313012) (xy 69.37862 -272.352356) (xy 69.343127 -272.386448) (xy 69.302624 -272.414404)
			(xy 69.258162 -272.435502) (xy 69.210891 -272.449194) (xy 69.162036 -272.455126) (xy 69.112861 -272.453145)
			(xy 69.064642 -272.443301) (xy 69.018626 -272.425849) (xy 68.976005 -272.401242) (xy 68.937884 -272.370117)
			(xy 68.905249 -272.33328) (xy 68.878946 -272.291684) (xy 68.859655 -272.246408) (xy 68.847878 -272.198624)
			(xy 68.843918 -272.14957) (xy 67.554856 -272.14957) (xy 67.554361 -272.174177) (xy 67.546466 -272.222754)
			(xy 67.530882 -272.269435) (xy 67.508011 -272.313012) (xy 67.478446 -272.352356) (xy 67.442953 -272.386448)
			(xy 67.40245 -272.414404) (xy 67.357988 -272.435502) (xy 67.310717 -272.449194) (xy 67.261862 -272.455126)
			(xy 67.212687 -272.453145) (xy 67.164468 -272.443301) (xy 67.118452 -272.425849) (xy 67.075831 -272.401242)
			(xy 67.03771 -272.370117) (xy 67.005075 -272.33328) (xy 66.978772 -272.291684) (xy 66.959481 -272.246408)
			(xy 66.947704 -272.198624) (xy 66.943744 -272.14957) (xy 65.654936 -272.14957) (xy 65.654441 -272.174177)
			(xy 65.646546 -272.222754) (xy 65.630962 -272.269435) (xy 65.608091 -272.313012) (xy 65.578526 -272.352356)
			(xy 65.543033 -272.386448) (xy 65.50253 -272.414404) (xy 65.458068 -272.435502) (xy 65.410797 -272.449194)
			(xy 65.361942 -272.455126) (xy 65.312767 -272.453145) (xy 65.264548 -272.443301) (xy 65.218532 -272.425849)
			(xy 65.175911 -272.401242) (xy 65.13779 -272.370117) (xy 65.105155 -272.33328) (xy 65.078852 -272.291684)
			(xy 65.059561 -272.246408) (xy 65.047784 -272.198624) (xy 65.043824 -272.14957) (xy 63.755016 -272.14957)
			(xy 63.754521 -272.174177) (xy 63.746626 -272.222754) (xy 63.731042 -272.269435) (xy 63.708171 -272.313012)
			(xy 63.678606 -272.352356) (xy 63.643113 -272.386448) (xy 63.60261 -272.414404) (xy 63.558148 -272.435502)
			(xy 63.510877 -272.449194) (xy 63.462022 -272.455126) (xy 63.412847 -272.453145) (xy 63.364628 -272.443301)
			(xy 63.318612 -272.425849) (xy 63.275991 -272.401242) (xy 63.23787 -272.370117) (xy 63.205235 -272.33328)
			(xy 63.178932 -272.291684) (xy 63.159641 -272.246408) (xy 63.147864 -272.198624) (xy 63.143904 -272.14957)
			(xy 61.854842 -272.14957) (xy 61.854347 -272.174177) (xy 61.846452 -272.222754) (xy 61.830868 -272.269435)
			(xy 61.807997 -272.313012) (xy 61.778432 -272.352356) (xy 61.742939 -272.386448) (xy 61.702436 -272.414404)
			(xy 61.657974 -272.435502) (xy 61.610703 -272.449194) (xy 61.561848 -272.455126) (xy 61.512673 -272.453145)
			(xy 61.464454 -272.443301) (xy 61.418438 -272.425849) (xy 61.375817 -272.401242) (xy 61.337696 -272.370117)
			(xy 61.305061 -272.33328) (xy 61.278758 -272.291684) (xy 61.259467 -272.246408) (xy 61.24769 -272.198624)
			(xy 61.24373 -272.14957) (xy 59.954917 -272.14957) (xy 59.954427 -272.173923) (xy 59.946532 -272.2225)
			(xy 59.930948 -272.269181) (xy 59.908077 -272.312758) (xy 59.878512 -272.352102) (xy 59.843019 -272.386194)
			(xy 59.802516 -272.41415) (xy 59.758054 -272.435248) (xy 59.710783 -272.44894) (xy 59.661928 -272.454872)
			(xy 59.612753 -272.452891) (xy 59.564534 -272.443047) (xy 59.518518 -272.425595) (xy 59.475897 -272.400988)
			(xy 59.437776 -272.369863) (xy 59.405141 -272.333026) (xy 59.378838 -272.29143) (xy 59.359547 -272.246154)
			(xy 59.34777 -272.19837) (xy 59.34381 -272.149316) (xy 58.054997 -272.149316) (xy 58.055002 -272.14957)
			(xy 58.054507 -272.174177) (xy 58.046612 -272.222754) (xy 58.031028 -272.269435) (xy 58.008157 -272.313012)
			(xy 57.978592 -272.352356) (xy 57.943099 -272.386448) (xy 57.902596 -272.414404) (xy 57.858134 -272.435502)
			(xy 57.810863 -272.449194) (xy 57.762008 -272.455126) (xy 57.712833 -272.453145) (xy 57.664614 -272.443301)
			(xy 57.618598 -272.425849) (xy 57.575977 -272.401242) (xy 57.537856 -272.370117) (xy 57.505221 -272.33328)
			(xy 57.478918 -272.291684) (xy 57.459627 -272.246408) (xy 57.44785 -272.198624) (xy 57.44389 -272.14957)
			(xy 56.154828 -272.14957) (xy 56.154333 -272.174177) (xy 56.146438 -272.222754) (xy 56.130854 -272.269435)
			(xy 56.107983 -272.313012) (xy 56.078418 -272.352356) (xy 56.042925 -272.386448) (xy 56.002422 -272.414404)
			(xy 55.95796 -272.435502) (xy 55.910689 -272.449194) (xy 55.861834 -272.455126) (xy 55.812659 -272.453145)
			(xy 55.76444 -272.443301) (xy 55.718424 -272.425849) (xy 55.675803 -272.401242) (xy 55.637682 -272.370117)
			(xy 55.605047 -272.33328) (xy 55.578744 -272.291684) (xy 55.559453 -272.246408) (xy 55.547676 -272.198624)
			(xy 55.543716 -272.14957) (xy 54.254908 -272.14957) (xy 54.254413 -272.174177) (xy 54.246518 -272.222754)
			(xy 54.230934 -272.269435) (xy 54.208063 -272.313012) (xy 54.178498 -272.352356) (xy 54.143005 -272.386448)
			(xy 54.102502 -272.414404) (xy 54.05804 -272.435502) (xy 54.010769 -272.449194) (xy 53.961914 -272.455126)
			(xy 53.912739 -272.453145) (xy 53.86452 -272.443301) (xy 53.818504 -272.425849) (xy 53.775883 -272.401242)
			(xy 53.737762 -272.370117) (xy 53.705127 -272.33328) (xy 53.678824 -272.291684) (xy 53.659533 -272.246408)
			(xy 53.647756 -272.198624) (xy 53.643796 -272.14957) (xy 52.354988 -272.14957) (xy 52.354493 -272.174177)
			(xy 52.346598 -272.222754) (xy 52.331014 -272.269435) (xy 52.308143 -272.313012) (xy 52.278578 -272.352356)
			(xy 52.243085 -272.386448) (xy 52.202582 -272.414404) (xy 52.15812 -272.435502) (xy 52.110849 -272.449194)
			(xy 52.061994 -272.455126) (xy 52.012819 -272.453145) (xy 51.9646 -272.443301) (xy 51.918584 -272.425849)
			(xy 51.875963 -272.401242) (xy 51.837842 -272.370117) (xy 51.805207 -272.33328) (xy 51.778904 -272.291684)
			(xy 51.759613 -272.246408) (xy 51.747836 -272.198624) (xy 51.743876 -272.14957) (xy 50.454814 -272.14957)
			(xy 50.454319 -272.174177) (xy 50.446424 -272.222754) (xy 50.43084 -272.269435) (xy 50.407969 -272.313012)
			(xy 50.378404 -272.352356) (xy 50.342911 -272.386448) (xy 50.302408 -272.414404) (xy 50.257946 -272.435502)
			(xy 50.210675 -272.449194) (xy 50.16182 -272.455126) (xy 50.112645 -272.453145) (xy 50.064426 -272.443301)
			(xy 50.01841 -272.425849) (xy 49.975789 -272.401242) (xy 49.937668 -272.370117) (xy 49.905033 -272.33328)
			(xy 49.87873 -272.291684) (xy 49.859439 -272.246408) (xy 49.847662 -272.198624) (xy 49.843702 -272.14957)
			(xy 49.149254 -272.14957) (xy 49.149254 -272.722594) (xy 49.149678 -272.732664) (xy 49.157396 -272.751264)
			(xy 49.16424 -272.758662) (xy 49.18583 -272.780252) (xy 49.192642 -272.786455) (xy 49.209435 -272.794001)
			(xy 49.218596 -272.794984) (xy 49.242793 -272.796944) (xy 49.290163 -272.80756) (xy 49.335256 -272.825535)
			(xy 49.376938 -272.850417) (xy 49.414159 -272.88158) (xy 49.445982 -272.918239) (xy 49.471604 -272.95947)
			(xy 49.490381 -273.004236) (xy 49.50184 -273.051408) (xy 49.505692 -273.099799) (xy 49.503647 -273.125492)
			(xy 49.823112 -273.125492) (xy 49.823112 -273.074076) (xy 49.831155 -273.023294) (xy 49.847043 -272.974395)
			(xy 49.870386 -272.928583) (xy 49.900607 -272.886987) (xy 49.936963 -272.850631) (xy 49.978559 -272.82041)
			(xy 50.024371 -272.797067) (xy 50.07327 -272.781179) (xy 50.124052 -272.773136) (xy 50.175468 -272.773136)
			(xy 50.22625 -272.781179) (xy 50.275149 -272.797067) (xy 50.320961 -272.82041) (xy 50.362557 -272.850631)
			(xy 50.398913 -272.886987) (xy 50.429134 -272.928583) (xy 50.452477 -272.974395) (xy 50.468365 -273.023294)
			(xy 50.476408 -273.074076) (xy 50.476912 -273.099784) (xy 50.79417 -273.099784) (xy 50.79813 -273.05073)
			(xy 50.809907 -273.002946) (xy 50.829198 -272.95767) (xy 50.855501 -272.916074) (xy 50.888136 -272.879237)
			(xy 50.926257 -272.848112) (xy 50.968878 -272.823505) (xy 51.014894 -272.806053) (xy 51.063113 -272.796209)
			(xy 51.112288 -272.794228) (xy 51.161143 -272.80016) (xy 51.208414 -272.813852) (xy 51.252876 -272.83495)
			(xy 51.293379 -272.862906) (xy 51.328872 -272.896998) (xy 51.358437 -272.936342) (xy 51.381308 -272.979919)
			(xy 51.396892 -273.0266) (xy 51.404787 -273.075177) (xy 51.405282 -273.099784) (xy 51.404787 -273.124391)
			(xy 51.404608 -273.125492) (xy 51.723286 -273.125492) (xy 51.723286 -273.074076) (xy 51.731329 -273.023294)
			(xy 51.747217 -272.974395) (xy 51.77056 -272.928583) (xy 51.800781 -272.886987) (xy 51.837137 -272.850631)
			(xy 51.878733 -272.82041) (xy 51.924545 -272.797067) (xy 51.973444 -272.781179) (xy 52.024226 -272.773136)
			(xy 52.075642 -272.773136) (xy 52.126424 -272.781179) (xy 52.175323 -272.797067) (xy 52.221135 -272.82041)
			(xy 52.262731 -272.850631) (xy 52.299087 -272.886987) (xy 52.329308 -272.928583) (xy 52.352651 -272.974395)
			(xy 52.368539 -273.023294) (xy 52.376582 -273.074076) (xy 52.377086 -273.099784) (xy 52.69409 -273.099784)
			(xy 52.69805 -273.05073) (xy 52.709827 -273.002946) (xy 52.729118 -272.95767) (xy 52.755421 -272.916074)
			(xy 52.788056 -272.879237) (xy 52.826177 -272.848112) (xy 52.868798 -272.823505) (xy 52.914814 -272.806053)
			(xy 52.963033 -272.796209) (xy 53.012208 -272.794228) (xy 53.061063 -272.80016) (xy 53.108334 -272.813852)
			(xy 53.152796 -272.83495) (xy 53.193299 -272.862906) (xy 53.228792 -272.896998) (xy 53.258357 -272.936342)
			(xy 53.281228 -272.979919) (xy 53.296812 -273.0266) (xy 53.304707 -273.075177) (xy 53.305202 -273.099784)
			(xy 53.304707 -273.124391) (xy 53.304528 -273.125492) (xy 53.623206 -273.125492) (xy 53.623206 -273.074076)
			(xy 53.631249 -273.023294) (xy 53.647137 -272.974395) (xy 53.67048 -272.928583) (xy 53.700701 -272.886987)
			(xy 53.737057 -272.850631) (xy 53.778653 -272.82041) (xy 53.824465 -272.797067) (xy 53.873364 -272.781179)
			(xy 53.924146 -272.773136) (xy 53.975562 -272.773136) (xy 54.026344 -272.781179) (xy 54.075243 -272.797067)
			(xy 54.121055 -272.82041) (xy 54.162651 -272.850631) (xy 54.199007 -272.886987) (xy 54.229228 -272.928583)
			(xy 54.252571 -272.974395) (xy 54.268459 -273.023294) (xy 54.276502 -273.074076) (xy 54.277006 -273.099784)
			(xy 54.59401 -273.099784) (xy 54.59797 -273.05073) (xy 54.609747 -273.002946) (xy 54.629038 -272.95767)
			(xy 54.655341 -272.916074) (xy 54.687976 -272.879237) (xy 54.726097 -272.848112) (xy 54.768718 -272.823505)
			(xy 54.814734 -272.806053) (xy 54.862953 -272.796209) (xy 54.912128 -272.794228) (xy 54.960983 -272.80016)
			(xy 55.008254 -272.813852) (xy 55.052716 -272.83495) (xy 55.093219 -272.862906) (xy 55.128712 -272.896998)
			(xy 55.158277 -272.936342) (xy 55.181148 -272.979919) (xy 55.196732 -273.0266) (xy 55.204627 -273.075177)
			(xy 55.205122 -273.099784) (xy 55.204627 -273.124391) (xy 55.204448 -273.125492) (xy 55.523126 -273.125492)
			(xy 55.523126 -273.074076) (xy 55.531169 -273.023294) (xy 55.547057 -272.974395) (xy 55.5704 -272.928583)
			(xy 55.600621 -272.886987) (xy 55.636977 -272.850631) (xy 55.678573 -272.82041) (xy 55.724385 -272.797067)
			(xy 55.773284 -272.781179) (xy 55.824066 -272.773136) (xy 55.875482 -272.773136) (xy 55.926264 -272.781179)
			(xy 55.975163 -272.797067) (xy 56.020975 -272.82041) (xy 56.062571 -272.850631) (xy 56.098927 -272.886987)
			(xy 56.129148 -272.928583) (xy 56.152491 -272.974395) (xy 56.168379 -273.023294) (xy 56.176422 -273.074076)
			(xy 56.176926 -273.099784) (xy 56.494184 -273.099784) (xy 56.498144 -273.05073) (xy 56.509921 -273.002946)
			(xy 56.529212 -272.95767) (xy 56.555515 -272.916074) (xy 56.58815 -272.879237) (xy 56.626271 -272.848112)
			(xy 56.668892 -272.823505) (xy 56.714908 -272.806053) (xy 56.763127 -272.796209) (xy 56.812302 -272.794228)
			(xy 56.861157 -272.80016) (xy 56.908428 -272.813852) (xy 56.95289 -272.83495) (xy 56.993393 -272.862906)
			(xy 57.028886 -272.896998) (xy 57.058451 -272.936342) (xy 57.081322 -272.979919) (xy 57.096906 -273.0266)
			(xy 57.104801 -273.075177) (xy 57.105296 -273.099784) (xy 57.104801 -273.124391) (xy 57.104622 -273.125492)
			(xy 57.4233 -273.125492) (xy 57.4233 -273.074076) (xy 57.431343 -273.023294) (xy 57.447231 -272.974395)
			(xy 57.470574 -272.928583) (xy 57.500795 -272.886987) (xy 57.537151 -272.850631) (xy 57.578747 -272.82041)
			(xy 57.624559 -272.797067) (xy 57.673458 -272.781179) (xy 57.72424 -272.773136) (xy 57.775656 -272.773136)
			(xy 57.826438 -272.781179) (xy 57.875337 -272.797067) (xy 57.921149 -272.82041) (xy 57.962745 -272.850631)
			(xy 57.999101 -272.886987) (xy 58.029322 -272.928583) (xy 58.052665 -272.974395) (xy 58.068553 -273.023294)
			(xy 58.076596 -273.074076) (xy 58.0771 -273.099784) (xy 58.394104 -273.099784) (xy 58.398064 -273.05073)
			(xy 58.409841 -273.002946) (xy 58.429132 -272.95767) (xy 58.455435 -272.916074) (xy 58.48807 -272.879237)
			(xy 58.526191 -272.848112) (xy 58.568812 -272.823505) (xy 58.614828 -272.806053) (xy 58.663047 -272.796209)
			(xy 58.712222 -272.794228) (xy 58.761077 -272.80016) (xy 58.808348 -272.813852) (xy 58.85281 -272.83495)
			(xy 58.893313 -272.862906) (xy 58.928806 -272.896998) (xy 58.958371 -272.936342) (xy 58.981242 -272.979919)
			(xy 58.996826 -273.0266) (xy 59.004721 -273.075177) (xy 59.005216 -273.099784) (xy 59.004721 -273.124391)
			(xy 59.004583 -273.125238) (xy 59.322966 -273.125238) (xy 59.322966 -273.073822) (xy 59.331009 -273.02304)
			(xy 59.346897 -272.974141) (xy 59.37024 -272.928329) (xy 59.400461 -272.886733) (xy 59.436817 -272.850377)
			(xy 59.478413 -272.820156) (xy 59.524225 -272.796813) (xy 59.573124 -272.780925) (xy 59.623906 -272.772882)
			(xy 59.675322 -272.772882) (xy 59.726104 -272.780925) (xy 59.775003 -272.796813) (xy 59.820815 -272.820156)
			(xy 59.862411 -272.850377) (xy 59.898767 -272.886733) (xy 59.928988 -272.928329) (xy 59.952331 -272.974141)
			(xy 59.968219 -273.02304) (xy 59.976262 -273.073822) (xy 59.976766 -273.09953) (xy 59.976761 -273.099784)
			(xy 60.294024 -273.099784) (xy 60.297984 -273.05073) (xy 60.309761 -273.002946) (xy 60.329052 -272.95767)
			(xy 60.355355 -272.916074) (xy 60.38799 -272.879237) (xy 60.426111 -272.848112) (xy 60.468732 -272.823505)
			(xy 60.514748 -272.806053) (xy 60.562967 -272.796209) (xy 60.612142 -272.794228) (xy 60.660997 -272.80016)
			(xy 60.708268 -272.813852) (xy 60.75273 -272.83495) (xy 60.793233 -272.862906) (xy 60.828726 -272.896998)
			(xy 60.858291 -272.936342) (xy 60.881162 -272.979919) (xy 60.896746 -273.0266) (xy 60.904641 -273.075177)
			(xy 60.905136 -273.099784) (xy 60.904641 -273.124391) (xy 60.904462 -273.125492) (xy 61.222886 -273.125492)
			(xy 61.222886 -273.074076) (xy 61.230929 -273.023294) (xy 61.246817 -272.974395) (xy 61.27016 -272.928583)
			(xy 61.300381 -272.886987) (xy 61.336737 -272.850631) (xy 61.378333 -272.82041) (xy 61.424145 -272.797067)
			(xy 61.473044 -272.781179) (xy 61.523826 -272.773136) (xy 61.575242 -272.773136) (xy 61.626024 -272.781179)
			(xy 61.674923 -272.797067) (xy 61.720735 -272.82041) (xy 61.762331 -272.850631) (xy 61.798687 -272.886987)
			(xy 61.828908 -272.928583) (xy 61.852251 -272.974395) (xy 61.868139 -273.023294) (xy 61.876182 -273.074076)
			(xy 61.876686 -273.099784) (xy 62.193944 -273.099784) (xy 62.197904 -273.05073) (xy 62.209681 -273.002946)
			(xy 62.228972 -272.95767) (xy 62.255275 -272.916074) (xy 62.28791 -272.879237) (xy 62.326031 -272.848112)
			(xy 62.368652 -272.823505) (xy 62.414668 -272.806053) (xy 62.462887 -272.796209) (xy 62.512062 -272.794228)
			(xy 62.560917 -272.80016) (xy 62.608188 -272.813852) (xy 62.65265 -272.83495) (xy 62.693153 -272.862906)
			(xy 62.728646 -272.896998) (xy 62.758211 -272.936342) (xy 62.781082 -272.979919) (xy 62.796666 -273.0266)
			(xy 62.804561 -273.075177) (xy 62.805056 -273.099784) (xy 62.804561 -273.124391) (xy 62.804382 -273.125492)
			(xy 63.12306 -273.125492) (xy 63.12306 -273.074076) (xy 63.131103 -273.023294) (xy 63.146991 -272.974395)
			(xy 63.170334 -272.928583) (xy 63.200555 -272.886987) (xy 63.236911 -272.850631) (xy 63.278507 -272.82041)
			(xy 63.324319 -272.797067) (xy 63.373218 -272.781179) (xy 63.424 -272.773136) (xy 63.475416 -272.773136)
			(xy 63.526198 -272.781179) (xy 63.575097 -272.797067) (xy 63.620909 -272.82041) (xy 63.662505 -272.850631)
			(xy 63.698861 -272.886987) (xy 63.729082 -272.928583) (xy 63.752425 -272.974395) (xy 63.768313 -273.023294)
			(xy 63.776356 -273.074076) (xy 63.77686 -273.099784) (xy 64.094118 -273.099784) (xy 64.098078 -273.05073)
			(xy 64.109855 -273.002946) (xy 64.129146 -272.95767) (xy 64.155449 -272.916074) (xy 64.188084 -272.879237)
			(xy 64.226205 -272.848112) (xy 64.268826 -272.823505) (xy 64.314842 -272.806053) (xy 64.363061 -272.796209)
			(xy 64.412236 -272.794228) (xy 64.461091 -272.80016) (xy 64.508362 -272.813852) (xy 64.552824 -272.83495)
			(xy 64.593327 -272.862906) (xy 64.62882 -272.896998) (xy 64.658385 -272.936342) (xy 64.681256 -272.979919)
			(xy 64.69684 -273.0266) (xy 64.704735 -273.075177) (xy 64.70523 -273.099784) (xy 64.704735 -273.124391)
			(xy 64.704556 -273.125492) (xy 65.02298 -273.125492) (xy 65.02298 -273.074076) (xy 65.031023 -273.023294)
			(xy 65.046911 -272.974395) (xy 65.070254 -272.928583) (xy 65.100475 -272.886987) (xy 65.136831 -272.850631)
			(xy 65.178427 -272.82041) (xy 65.224239 -272.797067) (xy 65.273138 -272.781179) (xy 65.32392 -272.773136)
			(xy 65.375336 -272.773136) (xy 65.426118 -272.781179) (xy 65.475017 -272.797067) (xy 65.520829 -272.82041)
			(xy 65.562425 -272.850631) (xy 65.598781 -272.886987) (xy 65.629002 -272.928583) (xy 65.652345 -272.974395)
			(xy 65.668233 -273.023294) (xy 65.676276 -273.074076) (xy 65.67678 -273.099784) (xy 65.994038 -273.099784)
			(xy 65.997998 -273.05073) (xy 66.009775 -273.002946) (xy 66.029066 -272.95767) (xy 66.055369 -272.916074)
			(xy 66.088004 -272.879237) (xy 66.126125 -272.848112) (xy 66.168746 -272.823505) (xy 66.214762 -272.806053)
			(xy 66.262981 -272.796209) (xy 66.312156 -272.794228) (xy 66.361011 -272.80016) (xy 66.408282 -272.813852)
			(xy 66.452744 -272.83495) (xy 66.493247 -272.862906) (xy 66.52874 -272.896998) (xy 66.558305 -272.936342)
			(xy 66.581176 -272.979919) (xy 66.59676 -273.0266) (xy 66.604655 -273.075177) (xy 66.60515 -273.099784)
			(xy 66.604655 -273.124391) (xy 66.604476 -273.125492) (xy 66.9229 -273.125492) (xy 66.9229 -273.074076)
			(xy 66.930943 -273.023294) (xy 66.946831 -272.974395) (xy 66.970174 -272.928583) (xy 67.000395 -272.886987)
			(xy 67.036751 -272.850631) (xy 67.078347 -272.82041) (xy 67.124159 -272.797067) (xy 67.173058 -272.781179)
			(xy 67.22384 -272.773136) (xy 67.275256 -272.773136) (xy 67.326038 -272.781179) (xy 67.374937 -272.797067)
			(xy 67.420749 -272.82041) (xy 67.462345 -272.850631) (xy 67.498701 -272.886987) (xy 67.528922 -272.928583)
			(xy 67.552265 -272.974395) (xy 67.568153 -273.023294) (xy 67.576196 -273.074076) (xy 67.5767 -273.099784)
			(xy 67.893958 -273.099784) (xy 67.897918 -273.05073) (xy 67.909695 -273.002946) (xy 67.928986 -272.95767)
			(xy 67.955289 -272.916074) (xy 67.987924 -272.879237) (xy 68.026045 -272.848112) (xy 68.068666 -272.823505)
			(xy 68.114682 -272.806053) (xy 68.162901 -272.796209) (xy 68.212076 -272.794228) (xy 68.260931 -272.80016)
			(xy 68.308202 -272.813852) (xy 68.352664 -272.83495) (xy 68.393167 -272.862906) (xy 68.42866 -272.896998)
			(xy 68.458225 -272.936342) (xy 68.481096 -272.979919) (xy 68.49668 -273.0266) (xy 68.504575 -273.075177)
			(xy 68.50507 -273.099784) (xy 68.504575 -273.124391) (xy 68.504396 -273.125492) (xy 68.823074 -273.125492)
			(xy 68.823074 -273.074076) (xy 68.831117 -273.023294) (xy 68.847005 -272.974395) (xy 68.870348 -272.928583)
			(xy 68.900569 -272.886987) (xy 68.936925 -272.850631) (xy 68.978521 -272.82041) (xy 69.024333 -272.797067)
			(xy 69.073232 -272.781179) (xy 69.124014 -272.773136) (xy 69.17543 -272.773136) (xy 69.226212 -272.781179)
			(xy 69.275111 -272.797067) (xy 69.320923 -272.82041) (xy 69.362519 -272.850631) (xy 69.398875 -272.886987)
			(xy 69.429096 -272.928583) (xy 69.452439 -272.974395) (xy 69.468327 -273.023294) (xy 69.47637 -273.074076)
			(xy 69.476874 -273.099784) (xy 69.794132 -273.099784) (xy 69.798092 -273.05073) (xy 69.809869 -273.002946)
			(xy 69.82916 -272.95767) (xy 69.855463 -272.916074) (xy 69.888098 -272.879237) (xy 69.926219 -272.848112)
			(xy 69.96884 -272.823505) (xy 70.014856 -272.806053) (xy 70.063075 -272.796209) (xy 70.11225 -272.794228)
			(xy 70.161105 -272.80016) (xy 70.208376 -272.813852) (xy 70.252838 -272.83495) (xy 70.293341 -272.862906)
			(xy 70.328834 -272.896998) (xy 70.358399 -272.936342) (xy 70.38127 -272.979919) (xy 70.396854 -273.0266)
			(xy 70.404749 -273.075177) (xy 70.405244 -273.099784) (xy 70.404749 -273.124391) (xy 70.40457 -273.125492)
			(xy 70.722994 -273.125492) (xy 70.722994 -273.074076) (xy 70.731037 -273.023294) (xy 70.746925 -272.974395)
			(xy 70.770268 -272.928583) (xy 70.800489 -272.886987) (xy 70.836845 -272.850631) (xy 70.878441 -272.82041)
			(xy 70.924253 -272.797067) (xy 70.973152 -272.781179) (xy 71.023934 -272.773136) (xy 71.07535 -272.773136)
			(xy 71.126132 -272.781179) (xy 71.175031 -272.797067) (xy 71.220843 -272.82041) (xy 71.262439 -272.850631)
			(xy 71.298795 -272.886987) (xy 71.329016 -272.928583) (xy 71.352359 -272.974395) (xy 71.368247 -273.023294)
			(xy 71.37629 -273.074076) (xy 71.376794 -273.099784) (xy 71.694052 -273.099784) (xy 71.698012 -273.05073)
			(xy 71.709789 -273.002946) (xy 71.72908 -272.95767) (xy 71.755383 -272.916074) (xy 71.788018 -272.879237)
			(xy 71.826139 -272.848112) (xy 71.86876 -272.823505) (xy 71.914776 -272.806053) (xy 71.962995 -272.796209)
			(xy 72.01217 -272.794228) (xy 72.061025 -272.80016) (xy 72.108296 -272.813852) (xy 72.152758 -272.83495)
			(xy 72.193261 -272.862906) (xy 72.228754 -272.896998) (xy 72.258319 -272.936342) (xy 72.28119 -272.979919)
			(xy 72.296774 -273.0266) (xy 72.304669 -273.075177) (xy 72.305164 -273.099784) (xy 72.304669 -273.124391)
			(xy 72.30449 -273.125492) (xy 72.622914 -273.125492) (xy 72.622914 -273.074076) (xy 72.630957 -273.023294)
			(xy 72.646845 -272.974395) (xy 72.670188 -272.928583) (xy 72.700409 -272.886987) (xy 72.736765 -272.850631)
			(xy 72.778361 -272.82041) (xy 72.824173 -272.797067) (xy 72.873072 -272.781179) (xy 72.923854 -272.773136)
			(xy 72.97527 -272.773136) (xy 73.026052 -272.781179) (xy 73.074951 -272.797067) (xy 73.120763 -272.82041)
			(xy 73.162359 -272.850631) (xy 73.198715 -272.886987) (xy 73.228936 -272.928583) (xy 73.252279 -272.974395)
			(xy 73.268167 -273.023294) (xy 73.27621 -273.074076) (xy 73.276714 -273.099784) (xy 73.593972 -273.099784)
			(xy 73.597932 -273.05073) (xy 73.609709 -273.002946) (xy 73.629 -272.95767) (xy 73.655303 -272.916074)
			(xy 73.687938 -272.879237) (xy 73.726059 -272.848112) (xy 73.76868 -272.823505) (xy 73.814696 -272.806053)
			(xy 73.862915 -272.796209) (xy 73.91209 -272.794228) (xy 73.960945 -272.80016) (xy 74.008216 -272.813852)
			(xy 74.052678 -272.83495) (xy 74.093181 -272.862906) (xy 74.128674 -272.896998) (xy 74.158239 -272.936342)
			(xy 74.18111 -272.979919) (xy 74.196694 -273.0266) (xy 74.204589 -273.075177) (xy 74.205084 -273.099784)
			(xy 74.204589 -273.124391) (xy 74.20441 -273.125492) (xy 74.523088 -273.125492) (xy 74.523088 -273.074076)
			(xy 74.531131 -273.023294) (xy 74.547019 -272.974395) (xy 74.570362 -272.928583) (xy 74.600583 -272.886987)
			(xy 74.636939 -272.850631) (xy 74.678535 -272.82041) (xy 74.724347 -272.797067) (xy 74.773246 -272.781179)
			(xy 74.824028 -272.773136) (xy 74.875444 -272.773136) (xy 74.926226 -272.781179) (xy 74.975125 -272.797067)
			(xy 75.020937 -272.82041) (xy 75.062533 -272.850631) (xy 75.098889 -272.886987) (xy 75.12911 -272.928583)
			(xy 75.152453 -272.974395) (xy 75.168341 -273.023294) (xy 75.176384 -273.074076) (xy 75.176888 -273.099784)
			(xy 75.494146 -273.099784) (xy 75.498106 -273.05073) (xy 75.509883 -273.002946) (xy 75.529174 -272.95767)
			(xy 75.555477 -272.916074) (xy 75.588112 -272.879237) (xy 75.626233 -272.848112) (xy 75.668854 -272.823505)
			(xy 75.71487 -272.806053) (xy 75.763089 -272.796209) (xy 75.812264 -272.794228) (xy 75.861119 -272.80016)
			(xy 75.90839 -272.813852) (xy 75.952852 -272.83495) (xy 75.993355 -272.862906) (xy 76.028848 -272.896998)
			(xy 76.058413 -272.936342) (xy 76.081284 -272.979919) (xy 76.096868 -273.0266) (xy 76.104763 -273.075177)
			(xy 76.105258 -273.099784) (xy 76.104763 -273.124391) (xy 76.104584 -273.125492) (xy 76.423008 -273.125492)
			(xy 76.423008 -273.074076) (xy 76.431051 -273.023294) (xy 76.446939 -272.974395) (xy 76.470282 -272.928583)
			(xy 76.500503 -272.886987) (xy 76.536859 -272.850631) (xy 76.578455 -272.82041) (xy 76.624267 -272.797067)
			(xy 76.673166 -272.781179) (xy 76.723948 -272.773136) (xy 76.775364 -272.773136) (xy 76.826146 -272.781179)
			(xy 76.875045 -272.797067) (xy 76.920857 -272.82041) (xy 76.962453 -272.850631) (xy 76.998809 -272.886987)
			(xy 77.02903 -272.928583) (xy 77.052373 -272.974395) (xy 77.068261 -273.023294) (xy 77.076304 -273.074076)
			(xy 77.076808 -273.099784) (xy 77.39432 -273.099784) (xy 77.39828 -273.05073) (xy 77.410057 -273.002946)
			(xy 77.429348 -272.95767) (xy 77.455651 -272.916074) (xy 77.488286 -272.879237) (xy 77.526407 -272.848112)
			(xy 77.569028 -272.823505) (xy 77.615044 -272.806053) (xy 77.663263 -272.796209) (xy 77.712438 -272.794228)
			(xy 77.761293 -272.80016) (xy 77.808564 -272.813852) (xy 77.853026 -272.83495) (xy 77.893529 -272.862906)
			(xy 77.929022 -272.896998) (xy 77.958587 -272.936342) (xy 77.981458 -272.979919) (xy 77.997042 -273.0266)
			(xy 78.004937 -273.075177) (xy 78.005432 -273.099784) (xy 78.004937 -273.124391) (xy 78.004758 -273.125492)
			(xy 78.322928 -273.125492) (xy 78.322928 -273.074076) (xy 78.330971 -273.023294) (xy 78.346859 -272.974395)
			(xy 78.370202 -272.928583) (xy 78.400423 -272.886987) (xy 78.436779 -272.850631) (xy 78.478375 -272.82041)
			(xy 78.524187 -272.797067) (xy 78.573086 -272.781179) (xy 78.623868 -272.773136) (xy 78.675284 -272.773136)
			(xy 78.726066 -272.781179) (xy 78.774965 -272.797067) (xy 78.820777 -272.82041) (xy 78.862373 -272.850631)
			(xy 78.898729 -272.886987) (xy 78.92895 -272.928583) (xy 78.952293 -272.974395) (xy 78.968181 -273.023294)
			(xy 78.976224 -273.074076) (xy 78.976728 -273.099784) (xy 79.29424 -273.099784) (xy 79.2982 -273.05073)
			(xy 79.309977 -273.002946) (xy 79.329268 -272.95767) (xy 79.355571 -272.916074) (xy 79.388206 -272.879237)
			(xy 79.426327 -272.848112) (xy 79.468948 -272.823505) (xy 79.514964 -272.806053) (xy 79.563183 -272.796209)
			(xy 79.612358 -272.794228) (xy 79.661213 -272.80016) (xy 79.708484 -272.813852) (xy 79.752946 -272.83495)
			(xy 79.793449 -272.862906) (xy 79.828942 -272.896998) (xy 79.858507 -272.936342) (xy 79.881378 -272.979919)
			(xy 79.896962 -273.0266) (xy 79.904857 -273.075177) (xy 79.905352 -273.099784) (xy 79.904857 -273.124391)
			(xy 79.904678 -273.125492) (xy 80.222848 -273.125492) (xy 80.222848 -273.074076) (xy 80.230891 -273.023294)
			(xy 80.246779 -272.974395) (xy 80.270122 -272.928583) (xy 80.300343 -272.886987) (xy 80.336699 -272.850631)
			(xy 80.378295 -272.82041) (xy 80.424107 -272.797067) (xy 80.473006 -272.781179) (xy 80.523788 -272.773136)
			(xy 80.575204 -272.773136) (xy 80.625986 -272.781179) (xy 80.674885 -272.797067) (xy 80.720697 -272.82041)
			(xy 80.762293 -272.850631) (xy 80.798649 -272.886987) (xy 80.82887 -272.928583) (xy 80.852213 -272.974395)
			(xy 80.868101 -273.023294) (xy 80.876144 -273.074076) (xy 80.876648 -273.099784) (xy 81.19416 -273.099784)
			(xy 81.19812 -273.05073) (xy 81.209897 -273.002946) (xy 81.229188 -272.95767) (xy 81.255491 -272.916074)
			(xy 81.288126 -272.879237) (xy 81.326247 -272.848112) (xy 81.368868 -272.823505) (xy 81.414884 -272.806053)
			(xy 81.463103 -272.796209) (xy 81.512278 -272.794228) (xy 81.561133 -272.80016) (xy 81.608404 -272.813852)
			(xy 81.652866 -272.83495) (xy 81.693369 -272.862906) (xy 81.728862 -272.896998) (xy 81.758427 -272.936342)
			(xy 81.781298 -272.979919) (xy 81.796882 -273.0266) (xy 81.804777 -273.075177) (xy 81.805272 -273.099784)
			(xy 81.804777 -273.124391) (xy 81.796882 -273.172968) (xy 81.781298 -273.219649) (xy 81.758427 -273.263226)
			(xy 81.728862 -273.30257) (xy 81.693369 -273.336662) (xy 81.652866 -273.364618) (xy 81.608404 -273.385716)
			(xy 81.561133 -273.399408) (xy 81.512278 -273.40534) (xy 81.463103 -273.403359) (xy 81.414884 -273.393515)
			(xy 81.368868 -273.376063) (xy 81.326247 -273.351456) (xy 81.288126 -273.320331) (xy 81.255491 -273.283494)
			(xy 81.229188 -273.241898) (xy 81.209897 -273.196622) (xy 81.19812 -273.148838) (xy 81.19416 -273.099784)
			(xy 80.876648 -273.099784) (xy 80.876144 -273.125492) (xy 80.868101 -273.176274) (xy 80.852213 -273.225173)
			(xy 80.82887 -273.270985) (xy 80.798649 -273.312581) (xy 80.762293 -273.348937) (xy 80.720697 -273.379158)
			(xy 80.674885 -273.402501) (xy 80.625986 -273.418389) (xy 80.575204 -273.426432) (xy 80.523788 -273.426432)
			(xy 80.473006 -273.418389) (xy 80.424107 -273.402501) (xy 80.378295 -273.379158) (xy 80.336699 -273.348937)
			(xy 80.300343 -273.312581) (xy 80.270122 -273.270985) (xy 80.246779 -273.225173) (xy 80.230891 -273.176274)
			(xy 80.222848 -273.125492) (xy 79.904678 -273.125492) (xy 79.896962 -273.172968) (xy 79.881378 -273.219649)
			(xy 79.858507 -273.263226) (xy 79.828942 -273.30257) (xy 79.793449 -273.336662) (xy 79.752946 -273.364618)
			(xy 79.708484 -273.385716) (xy 79.661213 -273.399408) (xy 79.612358 -273.40534) (xy 79.563183 -273.403359)
			(xy 79.514964 -273.393515) (xy 79.468948 -273.376063) (xy 79.426327 -273.351456) (xy 79.388206 -273.320331)
			(xy 79.355571 -273.283494) (xy 79.329268 -273.241898) (xy 79.309977 -273.196622) (xy 79.2982 -273.148838)
			(xy 79.29424 -273.099784) (xy 78.976728 -273.099784) (xy 78.976224 -273.125492) (xy 78.968181 -273.176274)
			(xy 78.952293 -273.225173) (xy 78.92895 -273.270985) (xy 78.898729 -273.312581) (xy 78.862373 -273.348937)
			(xy 78.820777 -273.379158) (xy 78.774965 -273.402501) (xy 78.726066 -273.418389) (xy 78.675284 -273.426432)
			(xy 78.623868 -273.426432) (xy 78.573086 -273.418389) (xy 78.524187 -273.402501) (xy 78.478375 -273.379158)
			(xy 78.436779 -273.348937) (xy 78.400423 -273.312581) (xy 78.370202 -273.270985) (xy 78.346859 -273.225173)
			(xy 78.330971 -273.176274) (xy 78.322928 -273.125492) (xy 78.004758 -273.125492) (xy 77.997042 -273.172968)
			(xy 77.981458 -273.219649) (xy 77.958587 -273.263226) (xy 77.929022 -273.30257) (xy 77.893529 -273.336662)
			(xy 77.853026 -273.364618) (xy 77.808564 -273.385716) (xy 77.761293 -273.399408) (xy 77.712438 -273.40534)
			(xy 77.663263 -273.403359) (xy 77.615044 -273.393515) (xy 77.569028 -273.376063) (xy 77.526407 -273.351456)
			(xy 77.488286 -273.320331) (xy 77.455651 -273.283494) (xy 77.429348 -273.241898) (xy 77.410057 -273.196622)
			(xy 77.39828 -273.148838) (xy 77.39432 -273.099784) (xy 77.076808 -273.099784) (xy 77.076304 -273.125492)
			(xy 77.068261 -273.176274) (xy 77.052373 -273.225173) (xy 77.02903 -273.270985) (xy 76.998809 -273.312581)
			(xy 76.962453 -273.348937) (xy 76.920857 -273.379158) (xy 76.875045 -273.402501) (xy 76.826146 -273.418389)
			(xy 76.775364 -273.426432) (xy 76.723948 -273.426432) (xy 76.673166 -273.418389) (xy 76.624267 -273.402501)
			(xy 76.578455 -273.379158) (xy 76.536859 -273.348937) (xy 76.500503 -273.312581) (xy 76.470282 -273.270985)
			(xy 76.446939 -273.225173) (xy 76.431051 -273.176274) (xy 76.423008 -273.125492) (xy 76.104584 -273.125492)
			(xy 76.096868 -273.172968) (xy 76.081284 -273.219649) (xy 76.058413 -273.263226) (xy 76.028848 -273.30257)
			(xy 75.993355 -273.336662) (xy 75.952852 -273.364618) (xy 75.90839 -273.385716) (xy 75.861119 -273.399408)
			(xy 75.812264 -273.40534) (xy 75.763089 -273.403359) (xy 75.71487 -273.393515) (xy 75.668854 -273.376063)
			(xy 75.626233 -273.351456) (xy 75.588112 -273.320331) (xy 75.555477 -273.283494) (xy 75.529174 -273.241898)
			(xy 75.509883 -273.196622) (xy 75.498106 -273.148838) (xy 75.494146 -273.099784) (xy 75.176888 -273.099784)
			(xy 75.176384 -273.125492) (xy 75.168341 -273.176274) (xy 75.152453 -273.225173) (xy 75.12911 -273.270985)
			(xy 75.098889 -273.312581) (xy 75.062533 -273.348937) (xy 75.020937 -273.379158) (xy 74.975125 -273.402501)
			(xy 74.926226 -273.418389) (xy 74.875444 -273.426432) (xy 74.824028 -273.426432) (xy 74.773246 -273.418389)
			(xy 74.724347 -273.402501) (xy 74.678535 -273.379158) (xy 74.636939 -273.348937) (xy 74.600583 -273.312581)
			(xy 74.570362 -273.270985) (xy 74.547019 -273.225173) (xy 74.531131 -273.176274) (xy 74.523088 -273.125492)
			(xy 74.20441 -273.125492) (xy 74.196694 -273.172968) (xy 74.18111 -273.219649) (xy 74.158239 -273.263226)
			(xy 74.128674 -273.30257) (xy 74.093181 -273.336662) (xy 74.052678 -273.364618) (xy 74.008216 -273.385716)
			(xy 73.960945 -273.399408) (xy 73.91209 -273.40534) (xy 73.862915 -273.403359) (xy 73.814696 -273.393515)
			(xy 73.76868 -273.376063) (xy 73.726059 -273.351456) (xy 73.687938 -273.320331) (xy 73.655303 -273.283494)
			(xy 73.629 -273.241898) (xy 73.609709 -273.196622) (xy 73.597932 -273.148838) (xy 73.593972 -273.099784)
			(xy 73.276714 -273.099784) (xy 73.27621 -273.125492) (xy 73.268167 -273.176274) (xy 73.252279 -273.225173)
			(xy 73.228936 -273.270985) (xy 73.198715 -273.312581) (xy 73.162359 -273.348937) (xy 73.120763 -273.379158)
			(xy 73.074951 -273.402501) (xy 73.026052 -273.418389) (xy 72.97527 -273.426432) (xy 72.923854 -273.426432)
			(xy 72.873072 -273.418389) (xy 72.824173 -273.402501) (xy 72.778361 -273.379158) (xy 72.736765 -273.348937)
			(xy 72.700409 -273.312581) (xy 72.670188 -273.270985) (xy 72.646845 -273.225173) (xy 72.630957 -273.176274)
			(xy 72.622914 -273.125492) (xy 72.30449 -273.125492) (xy 72.296774 -273.172968) (xy 72.28119 -273.219649)
			(xy 72.258319 -273.263226) (xy 72.228754 -273.30257) (xy 72.193261 -273.336662) (xy 72.152758 -273.364618)
			(xy 72.108296 -273.385716) (xy 72.061025 -273.399408) (xy 72.01217 -273.40534) (xy 71.962995 -273.403359)
			(xy 71.914776 -273.393515) (xy 71.86876 -273.376063) (xy 71.826139 -273.351456) (xy 71.788018 -273.320331)
			(xy 71.755383 -273.283494) (xy 71.72908 -273.241898) (xy 71.709789 -273.196622) (xy 71.698012 -273.148838)
			(xy 71.694052 -273.099784) (xy 71.376794 -273.099784) (xy 71.37629 -273.125492) (xy 71.368247 -273.176274)
			(xy 71.352359 -273.225173) (xy 71.329016 -273.270985) (xy 71.298795 -273.312581) (xy 71.262439 -273.348937)
			(xy 71.220843 -273.379158) (xy 71.175031 -273.402501) (xy 71.126132 -273.418389) (xy 71.07535 -273.426432)
			(xy 71.023934 -273.426432) (xy 70.973152 -273.418389) (xy 70.924253 -273.402501) (xy 70.878441 -273.379158)
			(xy 70.836845 -273.348937) (xy 70.800489 -273.312581) (xy 70.770268 -273.270985) (xy 70.746925 -273.225173)
			(xy 70.731037 -273.176274) (xy 70.722994 -273.125492) (xy 70.40457 -273.125492) (xy 70.396854 -273.172968)
			(xy 70.38127 -273.219649) (xy 70.358399 -273.263226) (xy 70.328834 -273.30257) (xy 70.293341 -273.336662)
			(xy 70.252838 -273.364618) (xy 70.208376 -273.385716) (xy 70.161105 -273.399408) (xy 70.11225 -273.40534)
			(xy 70.063075 -273.403359) (xy 70.014856 -273.393515) (xy 69.96884 -273.376063) (xy 69.926219 -273.351456)
			(xy 69.888098 -273.320331) (xy 69.855463 -273.283494) (xy 69.82916 -273.241898) (xy 69.809869 -273.196622)
			(xy 69.798092 -273.148838) (xy 69.794132 -273.099784) (xy 69.476874 -273.099784) (xy 69.47637 -273.125492)
			(xy 69.468327 -273.176274) (xy 69.452439 -273.225173) (xy 69.429096 -273.270985) (xy 69.398875 -273.312581)
			(xy 69.362519 -273.348937) (xy 69.320923 -273.379158) (xy 69.275111 -273.402501) (xy 69.226212 -273.418389)
			(xy 69.17543 -273.426432) (xy 69.124014 -273.426432) (xy 69.073232 -273.418389) (xy 69.024333 -273.402501)
			(xy 68.978521 -273.379158) (xy 68.936925 -273.348937) (xy 68.900569 -273.312581) (xy 68.870348 -273.270985)
			(xy 68.847005 -273.225173) (xy 68.831117 -273.176274) (xy 68.823074 -273.125492) (xy 68.504396 -273.125492)
			(xy 68.49668 -273.172968) (xy 68.481096 -273.219649) (xy 68.458225 -273.263226) (xy 68.42866 -273.30257)
			(xy 68.393167 -273.336662) (xy 68.352664 -273.364618) (xy 68.308202 -273.385716) (xy 68.260931 -273.399408)
			(xy 68.212076 -273.40534) (xy 68.162901 -273.403359) (xy 68.114682 -273.393515) (xy 68.068666 -273.376063)
			(xy 68.026045 -273.351456) (xy 67.987924 -273.320331) (xy 67.955289 -273.283494) (xy 67.928986 -273.241898)
			(xy 67.909695 -273.196622) (xy 67.897918 -273.148838) (xy 67.893958 -273.099784) (xy 67.5767 -273.099784)
			(xy 67.576196 -273.125492) (xy 67.568153 -273.176274) (xy 67.552265 -273.225173) (xy 67.528922 -273.270985)
			(xy 67.498701 -273.312581) (xy 67.462345 -273.348937) (xy 67.420749 -273.379158) (xy 67.374937 -273.402501)
			(xy 67.326038 -273.418389) (xy 67.275256 -273.426432) (xy 67.22384 -273.426432) (xy 67.173058 -273.418389)
			(xy 67.124159 -273.402501) (xy 67.078347 -273.379158) (xy 67.036751 -273.348937) (xy 67.000395 -273.312581)
			(xy 66.970174 -273.270985) (xy 66.946831 -273.225173) (xy 66.930943 -273.176274) (xy 66.9229 -273.125492)
			(xy 66.604476 -273.125492) (xy 66.59676 -273.172968) (xy 66.581176 -273.219649) (xy 66.558305 -273.263226)
			(xy 66.52874 -273.30257) (xy 66.493247 -273.336662) (xy 66.452744 -273.364618) (xy 66.408282 -273.385716)
			(xy 66.361011 -273.399408) (xy 66.312156 -273.40534) (xy 66.262981 -273.403359) (xy 66.214762 -273.393515)
			(xy 66.168746 -273.376063) (xy 66.126125 -273.351456) (xy 66.088004 -273.320331) (xy 66.055369 -273.283494)
			(xy 66.029066 -273.241898) (xy 66.009775 -273.196622) (xy 65.997998 -273.148838) (xy 65.994038 -273.099784)
			(xy 65.67678 -273.099784) (xy 65.676276 -273.125492) (xy 65.668233 -273.176274) (xy 65.652345 -273.225173)
			(xy 65.629002 -273.270985) (xy 65.598781 -273.312581) (xy 65.562425 -273.348937) (xy 65.520829 -273.379158)
			(xy 65.475017 -273.402501) (xy 65.426118 -273.418389) (xy 65.375336 -273.426432) (xy 65.32392 -273.426432)
			(xy 65.273138 -273.418389) (xy 65.224239 -273.402501) (xy 65.178427 -273.379158) (xy 65.136831 -273.348937)
			(xy 65.100475 -273.312581) (xy 65.070254 -273.270985) (xy 65.046911 -273.225173) (xy 65.031023 -273.176274)
			(xy 65.02298 -273.125492) (xy 64.704556 -273.125492) (xy 64.69684 -273.172968) (xy 64.681256 -273.219649)
			(xy 64.658385 -273.263226) (xy 64.62882 -273.30257) (xy 64.593327 -273.336662) (xy 64.552824 -273.364618)
			(xy 64.508362 -273.385716) (xy 64.461091 -273.399408) (xy 64.412236 -273.40534) (xy 64.363061 -273.403359)
			(xy 64.314842 -273.393515) (xy 64.268826 -273.376063) (xy 64.226205 -273.351456) (xy 64.188084 -273.320331)
			(xy 64.155449 -273.283494) (xy 64.129146 -273.241898) (xy 64.109855 -273.196622) (xy 64.098078 -273.148838)
			(xy 64.094118 -273.099784) (xy 63.77686 -273.099784) (xy 63.776356 -273.125492) (xy 63.768313 -273.176274)
			(xy 63.752425 -273.225173) (xy 63.729082 -273.270985) (xy 63.698861 -273.312581) (xy 63.662505 -273.348937)
			(xy 63.620909 -273.379158) (xy 63.575097 -273.402501) (xy 63.526198 -273.418389) (xy 63.475416 -273.426432)
			(xy 63.424 -273.426432) (xy 63.373218 -273.418389) (xy 63.324319 -273.402501) (xy 63.278507 -273.379158)
			(xy 63.236911 -273.348937) (xy 63.200555 -273.312581) (xy 63.170334 -273.270985) (xy 63.146991 -273.225173)
			(xy 63.131103 -273.176274) (xy 63.12306 -273.125492) (xy 62.804382 -273.125492) (xy 62.796666 -273.172968)
			(xy 62.781082 -273.219649) (xy 62.758211 -273.263226) (xy 62.728646 -273.30257) (xy 62.693153 -273.336662)
			(xy 62.65265 -273.364618) (xy 62.608188 -273.385716) (xy 62.560917 -273.399408) (xy 62.512062 -273.40534)
			(xy 62.462887 -273.403359) (xy 62.414668 -273.393515) (xy 62.368652 -273.376063) (xy 62.326031 -273.351456)
			(xy 62.28791 -273.320331) (xy 62.255275 -273.283494) (xy 62.228972 -273.241898) (xy 62.209681 -273.196622)
			(xy 62.197904 -273.148838) (xy 62.193944 -273.099784) (xy 61.876686 -273.099784) (xy 61.876182 -273.125492)
			(xy 61.868139 -273.176274) (xy 61.852251 -273.225173) (xy 61.828908 -273.270985) (xy 61.798687 -273.312581)
			(xy 61.762331 -273.348937) (xy 61.720735 -273.379158) (xy 61.674923 -273.402501) (xy 61.626024 -273.418389)
			(xy 61.575242 -273.426432) (xy 61.523826 -273.426432) (xy 61.473044 -273.418389) (xy 61.424145 -273.402501)
			(xy 61.378333 -273.379158) (xy 61.336737 -273.348937) (xy 61.300381 -273.312581) (xy 61.27016 -273.270985)
			(xy 61.246817 -273.225173) (xy 61.230929 -273.176274) (xy 61.222886 -273.125492) (xy 60.904462 -273.125492)
			(xy 60.896746 -273.172968) (xy 60.881162 -273.219649) (xy 60.858291 -273.263226) (xy 60.828726 -273.30257)
			(xy 60.793233 -273.336662) (xy 60.75273 -273.364618) (xy 60.708268 -273.385716) (xy 60.660997 -273.399408)
			(xy 60.612142 -273.40534) (xy 60.562967 -273.403359) (xy 60.514748 -273.393515) (xy 60.468732 -273.376063)
			(xy 60.426111 -273.351456) (xy 60.38799 -273.320331) (xy 60.355355 -273.283494) (xy 60.329052 -273.241898)
			(xy 60.309761 -273.196622) (xy 60.297984 -273.148838) (xy 60.294024 -273.099784) (xy 59.976761 -273.099784)
			(xy 59.976262 -273.125238) (xy 59.968219 -273.17602) (xy 59.952331 -273.224919) (xy 59.928988 -273.270731)
			(xy 59.898767 -273.312327) (xy 59.862411 -273.348683) (xy 59.820815 -273.378904) (xy 59.775003 -273.402247)
			(xy 59.726104 -273.418135) (xy 59.675322 -273.426178) (xy 59.623906 -273.426178) (xy 59.573124 -273.418135)
			(xy 59.524225 -273.402247) (xy 59.478413 -273.378904) (xy 59.436817 -273.348683) (xy 59.400461 -273.312327)
			(xy 59.37024 -273.270731) (xy 59.346897 -273.224919) (xy 59.331009 -273.17602) (xy 59.322966 -273.125238)
			(xy 59.004583 -273.125238) (xy 58.996826 -273.172968) (xy 58.981242 -273.219649) (xy 58.958371 -273.263226)
			(xy 58.928806 -273.30257) (xy 58.893313 -273.336662) (xy 58.85281 -273.364618) (xy 58.808348 -273.385716)
			(xy 58.761077 -273.399408) (xy 58.712222 -273.40534) (xy 58.663047 -273.403359) (xy 58.614828 -273.393515)
			(xy 58.568812 -273.376063) (xy 58.526191 -273.351456) (xy 58.48807 -273.320331) (xy 58.455435 -273.283494)
			(xy 58.429132 -273.241898) (xy 58.409841 -273.196622) (xy 58.398064 -273.148838) (xy 58.394104 -273.099784)
			(xy 58.0771 -273.099784) (xy 58.076596 -273.125492) (xy 58.068553 -273.176274) (xy 58.052665 -273.225173)
			(xy 58.029322 -273.270985) (xy 57.999101 -273.312581) (xy 57.962745 -273.348937) (xy 57.921149 -273.379158)
			(xy 57.875337 -273.402501) (xy 57.826438 -273.418389) (xy 57.775656 -273.426432) (xy 57.72424 -273.426432)
			(xy 57.673458 -273.418389) (xy 57.624559 -273.402501) (xy 57.578747 -273.379158) (xy 57.537151 -273.348937)
			(xy 57.500795 -273.312581) (xy 57.470574 -273.270985) (xy 57.447231 -273.225173) (xy 57.431343 -273.176274)
			(xy 57.4233 -273.125492) (xy 57.104622 -273.125492) (xy 57.096906 -273.172968) (xy 57.081322 -273.219649)
			(xy 57.058451 -273.263226) (xy 57.028886 -273.30257) (xy 56.993393 -273.336662) (xy 56.95289 -273.364618)
			(xy 56.908428 -273.385716) (xy 56.861157 -273.399408) (xy 56.812302 -273.40534) (xy 56.763127 -273.403359)
			(xy 56.714908 -273.393515) (xy 56.668892 -273.376063) (xy 56.626271 -273.351456) (xy 56.58815 -273.320331)
			(xy 56.555515 -273.283494) (xy 56.529212 -273.241898) (xy 56.509921 -273.196622) (xy 56.498144 -273.148838)
			(xy 56.494184 -273.099784) (xy 56.176926 -273.099784) (xy 56.176422 -273.125492) (xy 56.168379 -273.176274)
			(xy 56.152491 -273.225173) (xy 56.129148 -273.270985) (xy 56.098927 -273.312581) (xy 56.062571 -273.348937)
			(xy 56.020975 -273.379158) (xy 55.975163 -273.402501) (xy 55.926264 -273.418389) (xy 55.875482 -273.426432)
			(xy 55.824066 -273.426432) (xy 55.773284 -273.418389) (xy 55.724385 -273.402501) (xy 55.678573 -273.379158)
			(xy 55.636977 -273.348937) (xy 55.600621 -273.312581) (xy 55.5704 -273.270985) (xy 55.547057 -273.225173)
			(xy 55.531169 -273.176274) (xy 55.523126 -273.125492) (xy 55.204448 -273.125492) (xy 55.196732 -273.172968)
			(xy 55.181148 -273.219649) (xy 55.158277 -273.263226) (xy 55.128712 -273.30257) (xy 55.093219 -273.336662)
			(xy 55.052716 -273.364618) (xy 55.008254 -273.385716) (xy 54.960983 -273.399408) (xy 54.912128 -273.40534)
			(xy 54.862953 -273.403359) (xy 54.814734 -273.393515) (xy 54.768718 -273.376063) (xy 54.726097 -273.351456)
			(xy 54.687976 -273.320331) (xy 54.655341 -273.283494) (xy 54.629038 -273.241898) (xy 54.609747 -273.196622)
			(xy 54.59797 -273.148838) (xy 54.59401 -273.099784) (xy 54.277006 -273.099784) (xy 54.276502 -273.125492)
			(xy 54.268459 -273.176274) (xy 54.252571 -273.225173) (xy 54.229228 -273.270985) (xy 54.199007 -273.312581)
			(xy 54.162651 -273.348937) (xy 54.121055 -273.379158) (xy 54.075243 -273.402501) (xy 54.026344 -273.418389)
			(xy 53.975562 -273.426432) (xy 53.924146 -273.426432) (xy 53.873364 -273.418389) (xy 53.824465 -273.402501)
			(xy 53.778653 -273.379158) (xy 53.737057 -273.348937) (xy 53.700701 -273.312581) (xy 53.67048 -273.270985)
			(xy 53.647137 -273.225173) (xy 53.631249 -273.176274) (xy 53.623206 -273.125492) (xy 53.304528 -273.125492)
			(xy 53.296812 -273.172968) (xy 53.281228 -273.219649) (xy 53.258357 -273.263226) (xy 53.228792 -273.30257)
			(xy 53.193299 -273.336662) (xy 53.152796 -273.364618) (xy 53.108334 -273.385716) (xy 53.061063 -273.399408)
			(xy 53.012208 -273.40534) (xy 52.963033 -273.403359) (xy 52.914814 -273.393515) (xy 52.868798 -273.376063)
			(xy 52.826177 -273.351456) (xy 52.788056 -273.320331) (xy 52.755421 -273.283494) (xy 52.729118 -273.241898)
			(xy 52.709827 -273.196622) (xy 52.69805 -273.148838) (xy 52.69409 -273.099784) (xy 52.377086 -273.099784)
			(xy 52.376582 -273.125492) (xy 52.368539 -273.176274) (xy 52.352651 -273.225173) (xy 52.329308 -273.270985)
			(xy 52.299087 -273.312581) (xy 52.262731 -273.348937) (xy 52.221135 -273.379158) (xy 52.175323 -273.402501)
			(xy 52.126424 -273.418389) (xy 52.075642 -273.426432) (xy 52.024226 -273.426432) (xy 51.973444 -273.418389)
			(xy 51.924545 -273.402501) (xy 51.878733 -273.379158) (xy 51.837137 -273.348937) (xy 51.800781 -273.312581)
			(xy 51.77056 -273.270985) (xy 51.747217 -273.225173) (xy 51.731329 -273.176274) (xy 51.723286 -273.125492)
			(xy 51.404608 -273.125492) (xy 51.396892 -273.172968) (xy 51.381308 -273.219649) (xy 51.358437 -273.263226)
			(xy 51.328872 -273.30257) (xy 51.293379 -273.336662) (xy 51.252876 -273.364618) (xy 51.208414 -273.385716)
			(xy 51.161143 -273.399408) (xy 51.112288 -273.40534) (xy 51.063113 -273.403359) (xy 51.014894 -273.393515)
			(xy 50.968878 -273.376063) (xy 50.926257 -273.351456) (xy 50.888136 -273.320331) (xy 50.855501 -273.283494)
			(xy 50.829198 -273.241898) (xy 50.809907 -273.196622) (xy 50.79813 -273.148838) (xy 50.79417 -273.099784)
			(xy 50.476912 -273.099784) (xy 50.476408 -273.125492) (xy 50.468365 -273.176274) (xy 50.452477 -273.225173)
			(xy 50.429134 -273.270985) (xy 50.398913 -273.312581) (xy 50.362557 -273.348937) (xy 50.320961 -273.379158)
			(xy 50.275149 -273.402501) (xy 50.22625 -273.418389) (xy 50.175468 -273.426432) (xy 50.124052 -273.426432)
			(xy 50.07327 -273.418389) (xy 50.024371 -273.402501) (xy 49.978559 -273.379158) (xy 49.936963 -273.348937)
			(xy 49.900607 -273.312581) (xy 49.870386 -273.270985) (xy 49.847043 -273.225173) (xy 49.831155 -273.176274)
			(xy 49.823112 -273.125492) (xy 49.503647 -273.125492) (xy 49.50184 -273.14819) (xy 49.490382 -273.195362)
			(xy 49.471605 -273.240128) (xy 49.445983 -273.28136) (xy 49.414161 -273.318019) (xy 49.37694 -273.349182)
			(xy 49.335258 -273.374065) (xy 49.290164 -273.39204) (xy 49.242795 -273.402655) (xy 49.218596 -273.404584)
			(xy 49.209422 -273.40552) (xy 49.192613 -273.413069) (xy 49.18583 -273.419316) (xy 49.16424 -273.440906)
			(xy 49.15739 -273.448303) (xy 49.149652 -273.466901) (xy 49.149254 -273.476974) (xy 49.149254 -273.672554)
			(xy 49.149689 -273.682619) (xy 49.157423 -273.701204) (xy 49.16424 -273.708622) (xy 49.18583 -273.730212)
			(xy 49.192645 -273.73641) (xy 49.209438 -273.743946) (xy 49.218596 -273.744944) (xy 49.242788 -273.746905)
			(xy 49.290148 -273.757518) (xy 49.335233 -273.77549) (xy 49.376906 -273.800368) (xy 49.41412 -273.831526)
			(xy 49.445935 -273.868178) (xy 49.471552 -273.909401) (xy 49.490325 -273.954158) (xy 49.501781 -274.001321)
			(xy 49.505632 -274.049703) (xy 49.503582 -274.075452) (xy 49.823112 -274.075452) (xy 49.823112 -274.024036)
			(xy 49.831155 -273.973254) (xy 49.847043 -273.924355) (xy 49.870386 -273.878543) (xy 49.900607 -273.836947)
			(xy 49.936963 -273.800591) (xy 49.978559 -273.77037) (xy 50.024371 -273.747027) (xy 50.07327 -273.731139)
			(xy 50.124052 -273.723096) (xy 50.175468 -273.723096) (xy 50.22625 -273.731139) (xy 50.275149 -273.747027)
			(xy 50.320961 -273.77037) (xy 50.362557 -273.800591) (xy 50.398913 -273.836947) (xy 50.429134 -273.878543)
			(xy 50.452477 -273.924355) (xy 50.468365 -273.973254) (xy 50.476408 -274.024036) (xy 50.476912 -274.049744)
			(xy 50.79417 -274.049744) (xy 50.79813 -274.00069) (xy 50.809907 -273.952906) (xy 50.829198 -273.90763)
			(xy 50.855501 -273.866034) (xy 50.888136 -273.829197) (xy 50.926257 -273.798072) (xy 50.968878 -273.773465)
			(xy 51.014894 -273.756013) (xy 51.063113 -273.746169) (xy 51.112288 -273.744188) (xy 51.161143 -273.75012)
			(xy 51.208414 -273.763812) (xy 51.252876 -273.78491) (xy 51.293379 -273.812866) (xy 51.328872 -273.846958)
			(xy 51.358437 -273.886302) (xy 51.381308 -273.929879) (xy 51.396892 -273.97656) (xy 51.404787 -274.025137)
			(xy 51.405282 -274.049744) (xy 51.404787 -274.074351) (xy 51.404608 -274.075452) (xy 51.723286 -274.075452)
			(xy 51.723286 -274.024036) (xy 51.731329 -273.973254) (xy 51.747217 -273.924355) (xy 51.77056 -273.878543)
			(xy 51.800781 -273.836947) (xy 51.837137 -273.800591) (xy 51.878733 -273.77037) (xy 51.924545 -273.747027)
			(xy 51.973444 -273.731139) (xy 52.024226 -273.723096) (xy 52.075642 -273.723096) (xy 52.126424 -273.731139)
			(xy 52.175323 -273.747027) (xy 52.221135 -273.77037) (xy 52.262731 -273.800591) (xy 52.299087 -273.836947)
			(xy 52.329308 -273.878543) (xy 52.352651 -273.924355) (xy 52.368539 -273.973254) (xy 52.376582 -274.024036)
			(xy 52.377086 -274.049744) (xy 52.69409 -274.049744) (xy 52.69805 -274.00069) (xy 52.709827 -273.952906)
			(xy 52.729118 -273.90763) (xy 52.755421 -273.866034) (xy 52.788056 -273.829197) (xy 52.826177 -273.798072)
			(xy 52.868798 -273.773465) (xy 52.914814 -273.756013) (xy 52.963033 -273.746169) (xy 53.012208 -273.744188)
			(xy 53.061063 -273.75012) (xy 53.108334 -273.763812) (xy 53.152796 -273.78491) (xy 53.193299 -273.812866)
			(xy 53.228792 -273.846958) (xy 53.258357 -273.886302) (xy 53.281228 -273.929879) (xy 53.296812 -273.97656)
			(xy 53.304707 -274.025137) (xy 53.305202 -274.049744) (xy 53.304707 -274.074351) (xy 53.304528 -274.075452)
			(xy 53.623206 -274.075452) (xy 53.623206 -274.024036) (xy 53.631249 -273.973254) (xy 53.647137 -273.924355)
			(xy 53.67048 -273.878543) (xy 53.700701 -273.836947) (xy 53.737057 -273.800591) (xy 53.778653 -273.77037)
			(xy 53.824465 -273.747027) (xy 53.873364 -273.731139) (xy 53.924146 -273.723096) (xy 53.975562 -273.723096)
			(xy 54.026344 -273.731139) (xy 54.075243 -273.747027) (xy 54.121055 -273.77037) (xy 54.162651 -273.800591)
			(xy 54.199007 -273.836947) (xy 54.229228 -273.878543) (xy 54.252571 -273.924355) (xy 54.268459 -273.973254)
			(xy 54.276502 -274.024036) (xy 54.277006 -274.049744) (xy 54.59401 -274.049744) (xy 54.59797 -274.00069)
			(xy 54.609747 -273.952906) (xy 54.629038 -273.90763) (xy 54.655341 -273.866034) (xy 54.687976 -273.829197)
			(xy 54.726097 -273.798072) (xy 54.768718 -273.773465) (xy 54.814734 -273.756013) (xy 54.862953 -273.746169)
			(xy 54.912128 -273.744188) (xy 54.960983 -273.75012) (xy 55.008254 -273.763812) (xy 55.052716 -273.78491)
			(xy 55.093219 -273.812866) (xy 55.128712 -273.846958) (xy 55.158277 -273.886302) (xy 55.181148 -273.929879)
			(xy 55.196732 -273.97656) (xy 55.204627 -274.025137) (xy 55.205122 -274.049744) (xy 55.204627 -274.074351)
			(xy 55.204448 -274.075452) (xy 55.523126 -274.075452) (xy 55.523126 -274.024036) (xy 55.531169 -273.973254)
			(xy 55.547057 -273.924355) (xy 55.5704 -273.878543) (xy 55.600621 -273.836947) (xy 55.636977 -273.800591)
			(xy 55.678573 -273.77037) (xy 55.724385 -273.747027) (xy 55.773284 -273.731139) (xy 55.824066 -273.723096)
			(xy 55.875482 -273.723096) (xy 55.926264 -273.731139) (xy 55.975163 -273.747027) (xy 56.020975 -273.77037)
			(xy 56.062571 -273.800591) (xy 56.098927 -273.836947) (xy 56.129148 -273.878543) (xy 56.152491 -273.924355)
			(xy 56.168379 -273.973254) (xy 56.176422 -274.024036) (xy 56.176926 -274.049744) (xy 56.494184 -274.049744)
			(xy 56.498144 -274.00069) (xy 56.509921 -273.952906) (xy 56.529212 -273.90763) (xy 56.555515 -273.866034)
			(xy 56.58815 -273.829197) (xy 56.626271 -273.798072) (xy 56.668892 -273.773465) (xy 56.714908 -273.756013)
			(xy 56.763127 -273.746169) (xy 56.812302 -273.744188) (xy 56.861157 -273.75012) (xy 56.908428 -273.763812)
			(xy 56.95289 -273.78491) (xy 56.993393 -273.812866) (xy 57.028886 -273.846958) (xy 57.058451 -273.886302)
			(xy 57.081322 -273.929879) (xy 57.096906 -273.97656) (xy 57.104801 -274.025137) (xy 57.105296 -274.049744)
			(xy 57.104801 -274.074351) (xy 57.104622 -274.075452) (xy 57.4233 -274.075452) (xy 57.4233 -274.024036)
			(xy 57.431343 -273.973254) (xy 57.447231 -273.924355) (xy 57.470574 -273.878543) (xy 57.500795 -273.836947)
			(xy 57.537151 -273.800591) (xy 57.578747 -273.77037) (xy 57.624559 -273.747027) (xy 57.673458 -273.731139)
			(xy 57.72424 -273.723096) (xy 57.775656 -273.723096) (xy 57.826438 -273.731139) (xy 57.875337 -273.747027)
			(xy 57.921149 -273.77037) (xy 57.962745 -273.800591) (xy 57.999101 -273.836947) (xy 58.029322 -273.878543)
			(xy 58.052665 -273.924355) (xy 58.068553 -273.973254) (xy 58.076596 -274.024036) (xy 58.0771 -274.049744)
			(xy 58.394104 -274.049744) (xy 58.398064 -274.00069) (xy 58.409841 -273.952906) (xy 58.429132 -273.90763)
			(xy 58.455435 -273.866034) (xy 58.48807 -273.829197) (xy 58.526191 -273.798072) (xy 58.568812 -273.773465)
			(xy 58.614828 -273.756013) (xy 58.663047 -273.746169) (xy 58.712222 -273.744188) (xy 58.761077 -273.75012)
			(xy 58.808348 -273.763812) (xy 58.85281 -273.78491) (xy 58.893313 -273.812866) (xy 58.928806 -273.846958)
			(xy 58.958371 -273.886302) (xy 58.981242 -273.929879) (xy 58.996826 -273.97656) (xy 59.004721 -274.025137)
			(xy 59.005216 -274.049744) (xy 59.004721 -274.074351) (xy 59.004583 -274.075198) (xy 59.322966 -274.075198)
			(xy 59.322966 -274.023782) (xy 59.331009 -273.973) (xy 59.346897 -273.924101) (xy 59.37024 -273.878289)
			(xy 59.400461 -273.836693) (xy 59.436817 -273.800337) (xy 59.478413 -273.770116) (xy 59.524225 -273.746773)
			(xy 59.573124 -273.730885) (xy 59.623906 -273.722842) (xy 59.675322 -273.722842) (xy 59.726104 -273.730885)
			(xy 59.775003 -273.746773) (xy 59.820815 -273.770116) (xy 59.862411 -273.800337) (xy 59.898767 -273.836693)
			(xy 59.928988 -273.878289) (xy 59.952331 -273.924101) (xy 59.968219 -273.973) (xy 59.976262 -274.023782)
			(xy 59.976766 -274.04949) (xy 59.976761 -274.049744) (xy 60.294024 -274.049744) (xy 60.297984 -274.00069)
			(xy 60.309761 -273.952906) (xy 60.329052 -273.90763) (xy 60.355355 -273.866034) (xy 60.38799 -273.829197)
			(xy 60.426111 -273.798072) (xy 60.468732 -273.773465) (xy 60.514748 -273.756013) (xy 60.562967 -273.746169)
			(xy 60.612142 -273.744188) (xy 60.660997 -273.75012) (xy 60.708268 -273.763812) (xy 60.75273 -273.78491)
			(xy 60.793233 -273.812866) (xy 60.828726 -273.846958) (xy 60.858291 -273.886302) (xy 60.881162 -273.929879)
			(xy 60.896746 -273.97656) (xy 60.904641 -274.025137) (xy 60.905136 -274.049744) (xy 60.904641 -274.074351)
			(xy 60.904462 -274.075452) (xy 61.222886 -274.075452) (xy 61.222886 -274.024036) (xy 61.230929 -273.973254)
			(xy 61.246817 -273.924355) (xy 61.27016 -273.878543) (xy 61.300381 -273.836947) (xy 61.336737 -273.800591)
			(xy 61.378333 -273.77037) (xy 61.424145 -273.747027) (xy 61.473044 -273.731139) (xy 61.523826 -273.723096)
			(xy 61.575242 -273.723096) (xy 61.626024 -273.731139) (xy 61.674923 -273.747027) (xy 61.720735 -273.77037)
			(xy 61.762331 -273.800591) (xy 61.798687 -273.836947) (xy 61.828908 -273.878543) (xy 61.852251 -273.924355)
			(xy 61.868139 -273.973254) (xy 61.876182 -274.024036) (xy 61.876686 -274.049744) (xy 62.193944 -274.049744)
			(xy 62.197904 -274.00069) (xy 62.209681 -273.952906) (xy 62.228972 -273.90763) (xy 62.255275 -273.866034)
			(xy 62.28791 -273.829197) (xy 62.326031 -273.798072) (xy 62.368652 -273.773465) (xy 62.414668 -273.756013)
			(xy 62.462887 -273.746169) (xy 62.512062 -273.744188) (xy 62.560917 -273.75012) (xy 62.608188 -273.763812)
			(xy 62.65265 -273.78491) (xy 62.693153 -273.812866) (xy 62.728646 -273.846958) (xy 62.758211 -273.886302)
			(xy 62.781082 -273.929879) (xy 62.796666 -273.97656) (xy 62.804561 -274.025137) (xy 62.805056 -274.049744)
			(xy 62.804561 -274.074351) (xy 62.804382 -274.075452) (xy 63.12306 -274.075452) (xy 63.12306 -274.024036)
			(xy 63.131103 -273.973254) (xy 63.146991 -273.924355) (xy 63.170334 -273.878543) (xy 63.200555 -273.836947)
			(xy 63.236911 -273.800591) (xy 63.278507 -273.77037) (xy 63.324319 -273.747027) (xy 63.373218 -273.731139)
			(xy 63.424 -273.723096) (xy 63.475416 -273.723096) (xy 63.526198 -273.731139) (xy 63.575097 -273.747027)
			(xy 63.620909 -273.77037) (xy 63.662505 -273.800591) (xy 63.698861 -273.836947) (xy 63.729082 -273.878543)
			(xy 63.752425 -273.924355) (xy 63.768313 -273.973254) (xy 63.776356 -274.024036) (xy 63.77686 -274.049744)
			(xy 64.094118 -274.049744) (xy 64.098078 -274.00069) (xy 64.109855 -273.952906) (xy 64.129146 -273.90763)
			(xy 64.155449 -273.866034) (xy 64.188084 -273.829197) (xy 64.226205 -273.798072) (xy 64.268826 -273.773465)
			(xy 64.314842 -273.756013) (xy 64.363061 -273.746169) (xy 64.412236 -273.744188) (xy 64.461091 -273.75012)
			(xy 64.508362 -273.763812) (xy 64.552824 -273.78491) (xy 64.593327 -273.812866) (xy 64.62882 -273.846958)
			(xy 64.658385 -273.886302) (xy 64.681256 -273.929879) (xy 64.69684 -273.97656) (xy 64.704735 -274.025137)
			(xy 64.70523 -274.049744) (xy 64.704735 -274.074351) (xy 64.704556 -274.075452) (xy 65.02298 -274.075452)
			(xy 65.02298 -274.024036) (xy 65.031023 -273.973254) (xy 65.046911 -273.924355) (xy 65.070254 -273.878543)
			(xy 65.100475 -273.836947) (xy 65.136831 -273.800591) (xy 65.178427 -273.77037) (xy 65.224239 -273.747027)
			(xy 65.273138 -273.731139) (xy 65.32392 -273.723096) (xy 65.375336 -273.723096) (xy 65.426118 -273.731139)
			(xy 65.475017 -273.747027) (xy 65.520829 -273.77037) (xy 65.562425 -273.800591) (xy 65.598781 -273.836947)
			(xy 65.629002 -273.878543) (xy 65.652345 -273.924355) (xy 65.668233 -273.973254) (xy 65.676276 -274.024036)
			(xy 65.67678 -274.049744) (xy 65.994038 -274.049744) (xy 65.997998 -274.00069) (xy 66.009775 -273.952906)
			(xy 66.029066 -273.90763) (xy 66.055369 -273.866034) (xy 66.088004 -273.829197) (xy 66.126125 -273.798072)
			(xy 66.168746 -273.773465) (xy 66.214762 -273.756013) (xy 66.262981 -273.746169) (xy 66.312156 -273.744188)
			(xy 66.361011 -273.75012) (xy 66.408282 -273.763812) (xy 66.452744 -273.78491) (xy 66.493247 -273.812866)
			(xy 66.52874 -273.846958) (xy 66.558305 -273.886302) (xy 66.581176 -273.929879) (xy 66.59676 -273.97656)
			(xy 66.604655 -274.025137) (xy 66.60515 -274.049744) (xy 66.604655 -274.074351) (xy 66.604476 -274.075452)
			(xy 66.9229 -274.075452) (xy 66.9229 -274.024036) (xy 66.930943 -273.973254) (xy 66.946831 -273.924355)
			(xy 66.970174 -273.878543) (xy 67.000395 -273.836947) (xy 67.036751 -273.800591) (xy 67.078347 -273.77037)
			(xy 67.124159 -273.747027) (xy 67.173058 -273.731139) (xy 67.22384 -273.723096) (xy 67.275256 -273.723096)
			(xy 67.326038 -273.731139) (xy 67.374937 -273.747027) (xy 67.420749 -273.77037) (xy 67.462345 -273.800591)
			(xy 67.498701 -273.836947) (xy 67.528922 -273.878543) (xy 67.552265 -273.924355) (xy 67.568153 -273.973254)
			(xy 67.576196 -274.024036) (xy 67.5767 -274.049744) (xy 67.893958 -274.049744) (xy 67.897918 -274.00069)
			(xy 67.909695 -273.952906) (xy 67.928986 -273.90763) (xy 67.955289 -273.866034) (xy 67.987924 -273.829197)
			(xy 68.026045 -273.798072) (xy 68.068666 -273.773465) (xy 68.114682 -273.756013) (xy 68.162901 -273.746169)
			(xy 68.212076 -273.744188) (xy 68.260931 -273.75012) (xy 68.308202 -273.763812) (xy 68.352664 -273.78491)
			(xy 68.393167 -273.812866) (xy 68.42866 -273.846958) (xy 68.458225 -273.886302) (xy 68.481096 -273.929879)
			(xy 68.49668 -273.97656) (xy 68.504575 -274.025137) (xy 68.50507 -274.049744) (xy 68.504575 -274.074351)
			(xy 68.504396 -274.075452) (xy 68.823074 -274.075452) (xy 68.823074 -274.024036) (xy 68.831117 -273.973254)
			(xy 68.847005 -273.924355) (xy 68.870348 -273.878543) (xy 68.900569 -273.836947) (xy 68.936925 -273.800591)
			(xy 68.978521 -273.77037) (xy 69.024333 -273.747027) (xy 69.073232 -273.731139) (xy 69.124014 -273.723096)
			(xy 69.17543 -273.723096) (xy 69.226212 -273.731139) (xy 69.275111 -273.747027) (xy 69.320923 -273.77037)
			(xy 69.362519 -273.800591) (xy 69.398875 -273.836947) (xy 69.429096 -273.878543) (xy 69.452439 -273.924355)
			(xy 69.468327 -273.973254) (xy 69.47637 -274.024036) (xy 69.476874 -274.049744) (xy 69.794132 -274.049744)
			(xy 69.798092 -274.00069) (xy 69.809869 -273.952906) (xy 69.82916 -273.90763) (xy 69.855463 -273.866034)
			(xy 69.888098 -273.829197) (xy 69.926219 -273.798072) (xy 69.96884 -273.773465) (xy 70.014856 -273.756013)
			(xy 70.063075 -273.746169) (xy 70.11225 -273.744188) (xy 70.161105 -273.75012) (xy 70.208376 -273.763812)
			(xy 70.252838 -273.78491) (xy 70.293341 -273.812866) (xy 70.328834 -273.846958) (xy 70.358399 -273.886302)
			(xy 70.38127 -273.929879) (xy 70.396854 -273.97656) (xy 70.404749 -274.025137) (xy 70.405244 -274.049744)
			(xy 70.404749 -274.074351) (xy 70.40457 -274.075452) (xy 70.722994 -274.075452) (xy 70.722994 -274.024036)
			(xy 70.731037 -273.973254) (xy 70.746925 -273.924355) (xy 70.770268 -273.878543) (xy 70.800489 -273.836947)
			(xy 70.836845 -273.800591) (xy 70.878441 -273.77037) (xy 70.924253 -273.747027) (xy 70.973152 -273.731139)
			(xy 71.023934 -273.723096) (xy 71.07535 -273.723096) (xy 71.126132 -273.731139) (xy 71.175031 -273.747027)
			(xy 71.220843 -273.77037) (xy 71.262439 -273.800591) (xy 71.298795 -273.836947) (xy 71.329016 -273.878543)
			(xy 71.352359 -273.924355) (xy 71.368247 -273.973254) (xy 71.37629 -274.024036) (xy 71.376794 -274.049744)
			(xy 71.694052 -274.049744) (xy 71.698012 -274.00069) (xy 71.709789 -273.952906) (xy 71.72908 -273.90763)
			(xy 71.755383 -273.866034) (xy 71.788018 -273.829197) (xy 71.826139 -273.798072) (xy 71.86876 -273.773465)
			(xy 71.914776 -273.756013) (xy 71.962995 -273.746169) (xy 72.01217 -273.744188) (xy 72.061025 -273.75012)
			(xy 72.108296 -273.763812) (xy 72.152758 -273.78491) (xy 72.193261 -273.812866) (xy 72.228754 -273.846958)
			(xy 72.258319 -273.886302) (xy 72.28119 -273.929879) (xy 72.296774 -273.97656) (xy 72.304669 -274.025137)
			(xy 72.305164 -274.049744) (xy 72.304669 -274.074351) (xy 72.30449 -274.075452) (xy 72.622914 -274.075452)
			(xy 72.622914 -274.024036) (xy 72.630957 -273.973254) (xy 72.646845 -273.924355) (xy 72.670188 -273.878543)
			(xy 72.700409 -273.836947) (xy 72.736765 -273.800591) (xy 72.778361 -273.77037) (xy 72.824173 -273.747027)
			(xy 72.873072 -273.731139) (xy 72.923854 -273.723096) (xy 72.97527 -273.723096) (xy 73.026052 -273.731139)
			(xy 73.074951 -273.747027) (xy 73.120763 -273.77037) (xy 73.162359 -273.800591) (xy 73.198715 -273.836947)
			(xy 73.228936 -273.878543) (xy 73.252279 -273.924355) (xy 73.268167 -273.973254) (xy 73.27621 -274.024036)
			(xy 73.276714 -274.049744) (xy 73.593972 -274.049744) (xy 73.597932 -274.00069) (xy 73.609709 -273.952906)
			(xy 73.629 -273.90763) (xy 73.655303 -273.866034) (xy 73.687938 -273.829197) (xy 73.726059 -273.798072)
			(xy 73.76868 -273.773465) (xy 73.814696 -273.756013) (xy 73.862915 -273.746169) (xy 73.91209 -273.744188)
			(xy 73.960945 -273.75012) (xy 74.008216 -273.763812) (xy 74.052678 -273.78491) (xy 74.093181 -273.812866)
			(xy 74.128674 -273.846958) (xy 74.158239 -273.886302) (xy 74.18111 -273.929879) (xy 74.196694 -273.97656)
			(xy 74.204589 -274.025137) (xy 74.205084 -274.049744) (xy 74.204589 -274.074351) (xy 74.20441 -274.075452)
			(xy 74.523088 -274.075452) (xy 74.523088 -274.024036) (xy 74.531131 -273.973254) (xy 74.547019 -273.924355)
			(xy 74.570362 -273.878543) (xy 74.600583 -273.836947) (xy 74.636939 -273.800591) (xy 74.678535 -273.77037)
			(xy 74.724347 -273.747027) (xy 74.773246 -273.731139) (xy 74.824028 -273.723096) (xy 74.875444 -273.723096)
			(xy 74.926226 -273.731139) (xy 74.975125 -273.747027) (xy 75.020937 -273.77037) (xy 75.062533 -273.800591)
			(xy 75.098889 -273.836947) (xy 75.12911 -273.878543) (xy 75.152453 -273.924355) (xy 75.168341 -273.973254)
			(xy 75.176384 -274.024036) (xy 75.176888 -274.049744) (xy 75.4944 -274.049744) (xy 75.49836 -274.00069)
			(xy 75.510137 -273.952906) (xy 75.529428 -273.90763) (xy 75.555731 -273.866034) (xy 75.588366 -273.829197)
			(xy 75.626487 -273.798072) (xy 75.669108 -273.773465) (xy 75.715124 -273.756013) (xy 75.763343 -273.746169)
			(xy 75.812518 -273.744188) (xy 75.861373 -273.75012) (xy 75.908644 -273.763812) (xy 75.953106 -273.78491)
			(xy 75.993609 -273.812866) (xy 76.029102 -273.846958) (xy 76.058667 -273.886302) (xy 76.081538 -273.929879)
			(xy 76.097122 -273.97656) (xy 76.105017 -274.025137) (xy 76.105512 -274.049744) (xy 76.105017 -274.074351)
			(xy 76.104838 -274.075452) (xy 76.423008 -274.075452) (xy 76.423008 -274.024036) (xy 76.431051 -273.973254)
			(xy 76.446939 -273.924355) (xy 76.470282 -273.878543) (xy 76.500503 -273.836947) (xy 76.536859 -273.800591)
			(xy 76.578455 -273.77037) (xy 76.624267 -273.747027) (xy 76.673166 -273.731139) (xy 76.723948 -273.723096)
			(xy 76.775364 -273.723096) (xy 76.826146 -273.731139) (xy 76.875045 -273.747027) (xy 76.920857 -273.77037)
			(xy 76.962453 -273.800591) (xy 76.998809 -273.836947) (xy 77.02903 -273.878543) (xy 77.052373 -273.924355)
			(xy 77.068261 -273.973254) (xy 77.076304 -274.024036) (xy 77.076808 -274.049744) (xy 77.39432 -274.049744)
			(xy 77.39828 -274.00069) (xy 77.410057 -273.952906) (xy 77.429348 -273.90763) (xy 77.455651 -273.866034)
			(xy 77.488286 -273.829197) (xy 77.526407 -273.798072) (xy 77.569028 -273.773465) (xy 77.615044 -273.756013)
			(xy 77.663263 -273.746169) (xy 77.712438 -273.744188) (xy 77.761293 -273.75012) (xy 77.808564 -273.763812)
			(xy 77.853026 -273.78491) (xy 77.893529 -273.812866) (xy 77.929022 -273.846958) (xy 77.958587 -273.886302)
			(xy 77.981458 -273.929879) (xy 77.997042 -273.97656) (xy 78.004937 -274.025137) (xy 78.005432 -274.049744)
			(xy 78.004937 -274.074351) (xy 78.004758 -274.075452) (xy 78.322928 -274.075452) (xy 78.322928 -274.024036)
			(xy 78.330971 -273.973254) (xy 78.346859 -273.924355) (xy 78.370202 -273.878543) (xy 78.400423 -273.836947)
			(xy 78.436779 -273.800591) (xy 78.478375 -273.77037) (xy 78.524187 -273.747027) (xy 78.573086 -273.731139)
			(xy 78.623868 -273.723096) (xy 78.675284 -273.723096) (xy 78.726066 -273.731139) (xy 78.774965 -273.747027)
			(xy 78.820777 -273.77037) (xy 78.862373 -273.800591) (xy 78.898729 -273.836947) (xy 78.92895 -273.878543)
			(xy 78.952293 -273.924355) (xy 78.968181 -273.973254) (xy 78.976224 -274.024036) (xy 78.976728 -274.049744)
			(xy 79.29424 -274.049744) (xy 79.2982 -274.00069) (xy 79.309977 -273.952906) (xy 79.329268 -273.90763)
			(xy 79.355571 -273.866034) (xy 79.388206 -273.829197) (xy 79.426327 -273.798072) (xy 79.468948 -273.773465)
			(xy 79.514964 -273.756013) (xy 79.563183 -273.746169) (xy 79.612358 -273.744188) (xy 79.661213 -273.75012)
			(xy 79.708484 -273.763812) (xy 79.752946 -273.78491) (xy 79.793449 -273.812866) (xy 79.828942 -273.846958)
			(xy 79.858507 -273.886302) (xy 79.881378 -273.929879) (xy 79.896962 -273.97656) (xy 79.904857 -274.025137)
			(xy 79.905352 -274.049744) (xy 79.904857 -274.074351) (xy 79.904678 -274.075452) (xy 80.222848 -274.075452)
			(xy 80.222848 -274.024036) (xy 80.230891 -273.973254) (xy 80.246779 -273.924355) (xy 80.270122 -273.878543)
			(xy 80.300343 -273.836947) (xy 80.336699 -273.800591) (xy 80.378295 -273.77037) (xy 80.424107 -273.747027)
			(xy 80.473006 -273.731139) (xy 80.523788 -273.723096) (xy 80.575204 -273.723096) (xy 80.625986 -273.731139)
			(xy 80.674885 -273.747027) (xy 80.720697 -273.77037) (xy 80.762293 -273.800591) (xy 80.798649 -273.836947)
			(xy 80.82887 -273.878543) (xy 80.852213 -273.924355) (xy 80.868101 -273.973254) (xy 80.876144 -274.024036)
			(xy 80.876648 -274.049744) (xy 81.19416 -274.049744) (xy 81.19812 -274.00069) (xy 81.209897 -273.952906)
			(xy 81.229188 -273.90763) (xy 81.255491 -273.866034) (xy 81.288126 -273.829197) (xy 81.326247 -273.798072)
			(xy 81.368868 -273.773465) (xy 81.414884 -273.756013) (xy 81.463103 -273.746169) (xy 81.512278 -273.744188)
			(xy 81.561133 -273.75012) (xy 81.608404 -273.763812) (xy 81.652866 -273.78491) (xy 81.693369 -273.812866)
			(xy 81.728862 -273.846958) (xy 81.758427 -273.886302) (xy 81.781298 -273.929879) (xy 81.796882 -273.97656)
			(xy 81.804777 -274.025137) (xy 81.805272 -274.049744) (xy 82.14412 -274.049744) (xy 82.14808 -274.00069)
			(xy 82.159857 -273.952906) (xy 82.179148 -273.90763) (xy 82.205451 -273.866034) (xy 82.238086 -273.829197)
			(xy 82.276207 -273.798072) (xy 82.318828 -273.773465) (xy 82.364844 -273.756013) (xy 82.413063 -273.746169)
			(xy 82.462238 -273.744188) (xy 82.511093 -273.75012) (xy 82.558364 -273.763812) (xy 82.602826 -273.78491)
			(xy 82.643329 -273.812866) (xy 82.678822 -273.846958) (xy 82.708387 -273.886302) (xy 82.731258 -273.929879)
			(xy 82.746842 -273.97656) (xy 82.754737 -274.025137) (xy 82.755232 -274.049744) (xy 82.754737 -274.074351)
			(xy 82.746842 -274.122928) (xy 82.731258 -274.169609) (xy 82.708387 -274.213186) (xy 82.678822 -274.25253)
			(xy 82.643329 -274.286622) (xy 82.602826 -274.314578) (xy 82.558364 -274.335676) (xy 82.511093 -274.349368)
			(xy 82.462238 -274.3553) (xy 82.413063 -274.353319) (xy 82.364844 -274.343475) (xy 82.318828 -274.326023)
			(xy 82.276207 -274.301416) (xy 82.238086 -274.270291) (xy 82.205451 -274.233454) (xy 82.179148 -274.191858)
			(xy 82.159857 -274.146582) (xy 82.14808 -274.098798) (xy 82.14412 -274.049744) (xy 81.805272 -274.049744)
			(xy 81.804777 -274.074351) (xy 81.796882 -274.122928) (xy 81.781298 -274.169609) (xy 81.758427 -274.213186)
			(xy 81.728862 -274.25253) (xy 81.693369 -274.286622) (xy 81.652866 -274.314578) (xy 81.608404 -274.335676)
			(xy 81.561133 -274.349368) (xy 81.512278 -274.3553) (xy 81.463103 -274.353319) (xy 81.414884 -274.343475)
			(xy 81.368868 -274.326023) (xy 81.326247 -274.301416) (xy 81.288126 -274.270291) (xy 81.255491 -274.233454)
			(xy 81.229188 -274.191858) (xy 81.209897 -274.146582) (xy 81.19812 -274.098798) (xy 81.19416 -274.049744)
			(xy 80.876648 -274.049744) (xy 80.876144 -274.075452) (xy 80.868101 -274.126234) (xy 80.852213 -274.175133)
			(xy 80.82887 -274.220945) (xy 80.798649 -274.262541) (xy 80.762293 -274.298897) (xy 80.720697 -274.329118)
			(xy 80.674885 -274.352461) (xy 80.625986 -274.368349) (xy 80.575204 -274.376392) (xy 80.523788 -274.376392)
			(xy 80.473006 -274.368349) (xy 80.424107 -274.352461) (xy 80.378295 -274.329118) (xy 80.336699 -274.298897)
			(xy 80.300343 -274.262541) (xy 80.270122 -274.220945) (xy 80.246779 -274.175133) (xy 80.230891 -274.126234)
			(xy 80.222848 -274.075452) (xy 79.904678 -274.075452) (xy 79.896962 -274.122928) (xy 79.881378 -274.169609)
			(xy 79.858507 -274.213186) (xy 79.828942 -274.25253) (xy 79.793449 -274.286622) (xy 79.752946 -274.314578)
			(xy 79.708484 -274.335676) (xy 79.661213 -274.349368) (xy 79.612358 -274.3553) (xy 79.563183 -274.353319)
			(xy 79.514964 -274.343475) (xy 79.468948 -274.326023) (xy 79.426327 -274.301416) (xy 79.388206 -274.270291)
			(xy 79.355571 -274.233454) (xy 79.329268 -274.191858) (xy 79.309977 -274.146582) (xy 79.2982 -274.098798)
			(xy 79.29424 -274.049744) (xy 78.976728 -274.049744) (xy 78.976224 -274.075452) (xy 78.968181 -274.126234)
			(xy 78.952293 -274.175133) (xy 78.92895 -274.220945) (xy 78.898729 -274.262541) (xy 78.862373 -274.298897)
			(xy 78.820777 -274.329118) (xy 78.774965 -274.352461) (xy 78.726066 -274.368349) (xy 78.675284 -274.376392)
			(xy 78.623868 -274.376392) (xy 78.573086 -274.368349) (xy 78.524187 -274.352461) (xy 78.478375 -274.329118)
			(xy 78.436779 -274.298897) (xy 78.400423 -274.262541) (xy 78.370202 -274.220945) (xy 78.346859 -274.175133)
			(xy 78.330971 -274.126234) (xy 78.322928 -274.075452) (xy 78.004758 -274.075452) (xy 77.997042 -274.122928)
			(xy 77.981458 -274.169609) (xy 77.958587 -274.213186) (xy 77.929022 -274.25253) (xy 77.893529 -274.286622)
			(xy 77.853026 -274.314578) (xy 77.808564 -274.335676) (xy 77.761293 -274.349368) (xy 77.712438 -274.3553)
			(xy 77.663263 -274.353319) (xy 77.615044 -274.343475) (xy 77.569028 -274.326023) (xy 77.526407 -274.301416)
			(xy 77.488286 -274.270291) (xy 77.455651 -274.233454) (xy 77.429348 -274.191858) (xy 77.410057 -274.146582)
			(xy 77.39828 -274.098798) (xy 77.39432 -274.049744) (xy 77.076808 -274.049744) (xy 77.076304 -274.075452)
			(xy 77.068261 -274.126234) (xy 77.052373 -274.175133) (xy 77.02903 -274.220945) (xy 76.998809 -274.262541)
			(xy 76.962453 -274.298897) (xy 76.920857 -274.329118) (xy 76.875045 -274.352461) (xy 76.826146 -274.368349)
			(xy 76.775364 -274.376392) (xy 76.723948 -274.376392) (xy 76.673166 -274.368349) (xy 76.624267 -274.352461)
			(xy 76.578455 -274.329118) (xy 76.536859 -274.298897) (xy 76.500503 -274.262541) (xy 76.470282 -274.220945)
			(xy 76.446939 -274.175133) (xy 76.431051 -274.126234) (xy 76.423008 -274.075452) (xy 76.104838 -274.075452)
			(xy 76.097122 -274.122928) (xy 76.081538 -274.169609) (xy 76.058667 -274.213186) (xy 76.029102 -274.25253)
			(xy 75.993609 -274.286622) (xy 75.953106 -274.314578) (xy 75.908644 -274.335676) (xy 75.861373 -274.349368)
			(xy 75.812518 -274.3553) (xy 75.763343 -274.353319) (xy 75.715124 -274.343475) (xy 75.669108 -274.326023)
			(xy 75.626487 -274.301416) (xy 75.588366 -274.270291) (xy 75.555731 -274.233454) (xy 75.529428 -274.191858)
			(xy 75.510137 -274.146582) (xy 75.49836 -274.098798) (xy 75.4944 -274.049744) (xy 75.176888 -274.049744)
			(xy 75.176384 -274.075452) (xy 75.168341 -274.126234) (xy 75.152453 -274.175133) (xy 75.12911 -274.220945)
			(xy 75.098889 -274.262541) (xy 75.062533 -274.298897) (xy 75.020937 -274.329118) (xy 74.975125 -274.352461)
			(xy 74.926226 -274.368349) (xy 74.875444 -274.376392) (xy 74.824028 -274.376392) (xy 74.773246 -274.368349)
			(xy 74.724347 -274.352461) (xy 74.678535 -274.329118) (xy 74.636939 -274.298897) (xy 74.600583 -274.262541)
			(xy 74.570362 -274.220945) (xy 74.547019 -274.175133) (xy 74.531131 -274.126234) (xy 74.523088 -274.075452)
			(xy 74.20441 -274.075452) (xy 74.196694 -274.122928) (xy 74.18111 -274.169609) (xy 74.158239 -274.213186)
			(xy 74.128674 -274.25253) (xy 74.093181 -274.286622) (xy 74.052678 -274.314578) (xy 74.008216 -274.335676)
			(xy 73.960945 -274.349368) (xy 73.91209 -274.3553) (xy 73.862915 -274.353319) (xy 73.814696 -274.343475)
			(xy 73.76868 -274.326023) (xy 73.726059 -274.301416) (xy 73.687938 -274.270291) (xy 73.655303 -274.233454)
			(xy 73.629 -274.191858) (xy 73.609709 -274.146582) (xy 73.597932 -274.098798) (xy 73.593972 -274.049744)
			(xy 73.276714 -274.049744) (xy 73.27621 -274.075452) (xy 73.268167 -274.126234) (xy 73.252279 -274.175133)
			(xy 73.228936 -274.220945) (xy 73.198715 -274.262541) (xy 73.162359 -274.298897) (xy 73.120763 -274.329118)
			(xy 73.074951 -274.352461) (xy 73.026052 -274.368349) (xy 72.97527 -274.376392) (xy 72.923854 -274.376392)
			(xy 72.873072 -274.368349) (xy 72.824173 -274.352461) (xy 72.778361 -274.329118) (xy 72.736765 -274.298897)
			(xy 72.700409 -274.262541) (xy 72.670188 -274.220945) (xy 72.646845 -274.175133) (xy 72.630957 -274.126234)
			(xy 72.622914 -274.075452) (xy 72.30449 -274.075452) (xy 72.296774 -274.122928) (xy 72.28119 -274.169609)
			(xy 72.258319 -274.213186) (xy 72.228754 -274.25253) (xy 72.193261 -274.286622) (xy 72.152758 -274.314578)
			(xy 72.108296 -274.335676) (xy 72.061025 -274.349368) (xy 72.01217 -274.3553) (xy 71.962995 -274.353319)
			(xy 71.914776 -274.343475) (xy 71.86876 -274.326023) (xy 71.826139 -274.301416) (xy 71.788018 -274.270291)
			(xy 71.755383 -274.233454) (xy 71.72908 -274.191858) (xy 71.709789 -274.146582) (xy 71.698012 -274.098798)
			(xy 71.694052 -274.049744) (xy 71.376794 -274.049744) (xy 71.37629 -274.075452) (xy 71.368247 -274.126234)
			(xy 71.352359 -274.175133) (xy 71.329016 -274.220945) (xy 71.298795 -274.262541) (xy 71.262439 -274.298897)
			(xy 71.220843 -274.329118) (xy 71.175031 -274.352461) (xy 71.126132 -274.368349) (xy 71.07535 -274.376392)
			(xy 71.023934 -274.376392) (xy 70.973152 -274.368349) (xy 70.924253 -274.352461) (xy 70.878441 -274.329118)
			(xy 70.836845 -274.298897) (xy 70.800489 -274.262541) (xy 70.770268 -274.220945) (xy 70.746925 -274.175133)
			(xy 70.731037 -274.126234) (xy 70.722994 -274.075452) (xy 70.40457 -274.075452) (xy 70.396854 -274.122928)
			(xy 70.38127 -274.169609) (xy 70.358399 -274.213186) (xy 70.328834 -274.25253) (xy 70.293341 -274.286622)
			(xy 70.252838 -274.314578) (xy 70.208376 -274.335676) (xy 70.161105 -274.349368) (xy 70.11225 -274.3553)
			(xy 70.063075 -274.353319) (xy 70.014856 -274.343475) (xy 69.96884 -274.326023) (xy 69.926219 -274.301416)
			(xy 69.888098 -274.270291) (xy 69.855463 -274.233454) (xy 69.82916 -274.191858) (xy 69.809869 -274.146582)
			(xy 69.798092 -274.098798) (xy 69.794132 -274.049744) (xy 69.476874 -274.049744) (xy 69.47637 -274.075452)
			(xy 69.468327 -274.126234) (xy 69.452439 -274.175133) (xy 69.429096 -274.220945) (xy 69.398875 -274.262541)
			(xy 69.362519 -274.298897) (xy 69.320923 -274.329118) (xy 69.275111 -274.352461) (xy 69.226212 -274.368349)
			(xy 69.17543 -274.376392) (xy 69.124014 -274.376392) (xy 69.073232 -274.368349) (xy 69.024333 -274.352461)
			(xy 68.978521 -274.329118) (xy 68.936925 -274.298897) (xy 68.900569 -274.262541) (xy 68.870348 -274.220945)
			(xy 68.847005 -274.175133) (xy 68.831117 -274.126234) (xy 68.823074 -274.075452) (xy 68.504396 -274.075452)
			(xy 68.49668 -274.122928) (xy 68.481096 -274.169609) (xy 68.458225 -274.213186) (xy 68.42866 -274.25253)
			(xy 68.393167 -274.286622) (xy 68.352664 -274.314578) (xy 68.308202 -274.335676) (xy 68.260931 -274.349368)
			(xy 68.212076 -274.3553) (xy 68.162901 -274.353319) (xy 68.114682 -274.343475) (xy 68.068666 -274.326023)
			(xy 68.026045 -274.301416) (xy 67.987924 -274.270291) (xy 67.955289 -274.233454) (xy 67.928986 -274.191858)
			(xy 67.909695 -274.146582) (xy 67.897918 -274.098798) (xy 67.893958 -274.049744) (xy 67.5767 -274.049744)
			(xy 67.576196 -274.075452) (xy 67.568153 -274.126234) (xy 67.552265 -274.175133) (xy 67.528922 -274.220945)
			(xy 67.498701 -274.262541) (xy 67.462345 -274.298897) (xy 67.420749 -274.329118) (xy 67.374937 -274.352461)
			(xy 67.326038 -274.368349) (xy 67.275256 -274.376392) (xy 67.22384 -274.376392) (xy 67.173058 -274.368349)
			(xy 67.124159 -274.352461) (xy 67.078347 -274.329118) (xy 67.036751 -274.298897) (xy 67.000395 -274.262541)
			(xy 66.970174 -274.220945) (xy 66.946831 -274.175133) (xy 66.930943 -274.126234) (xy 66.9229 -274.075452)
			(xy 66.604476 -274.075452) (xy 66.59676 -274.122928) (xy 66.581176 -274.169609) (xy 66.558305 -274.213186)
			(xy 66.52874 -274.25253) (xy 66.493247 -274.286622) (xy 66.452744 -274.314578) (xy 66.408282 -274.335676)
			(xy 66.361011 -274.349368) (xy 66.312156 -274.3553) (xy 66.262981 -274.353319) (xy 66.214762 -274.343475)
			(xy 66.168746 -274.326023) (xy 66.126125 -274.301416) (xy 66.088004 -274.270291) (xy 66.055369 -274.233454)
			(xy 66.029066 -274.191858) (xy 66.009775 -274.146582) (xy 65.997998 -274.098798) (xy 65.994038 -274.049744)
			(xy 65.67678 -274.049744) (xy 65.676276 -274.075452) (xy 65.668233 -274.126234) (xy 65.652345 -274.175133)
			(xy 65.629002 -274.220945) (xy 65.598781 -274.262541) (xy 65.562425 -274.298897) (xy 65.520829 -274.329118)
			(xy 65.475017 -274.352461) (xy 65.426118 -274.368349) (xy 65.375336 -274.376392) (xy 65.32392 -274.376392)
			(xy 65.273138 -274.368349) (xy 65.224239 -274.352461) (xy 65.178427 -274.329118) (xy 65.136831 -274.298897)
			(xy 65.100475 -274.262541) (xy 65.070254 -274.220945) (xy 65.046911 -274.175133) (xy 65.031023 -274.126234)
			(xy 65.02298 -274.075452) (xy 64.704556 -274.075452) (xy 64.69684 -274.122928) (xy 64.681256 -274.169609)
			(xy 64.658385 -274.213186) (xy 64.62882 -274.25253) (xy 64.593327 -274.286622) (xy 64.552824 -274.314578)
			(xy 64.508362 -274.335676) (xy 64.461091 -274.349368) (xy 64.412236 -274.3553) (xy 64.363061 -274.353319)
			(xy 64.314842 -274.343475) (xy 64.268826 -274.326023) (xy 64.226205 -274.301416) (xy 64.188084 -274.270291)
			(xy 64.155449 -274.233454) (xy 64.129146 -274.191858) (xy 64.109855 -274.146582) (xy 64.098078 -274.098798)
			(xy 64.094118 -274.049744) (xy 63.77686 -274.049744) (xy 63.776356 -274.075452) (xy 63.768313 -274.126234)
			(xy 63.752425 -274.175133) (xy 63.729082 -274.220945) (xy 63.698861 -274.262541) (xy 63.662505 -274.298897)
			(xy 63.620909 -274.329118) (xy 63.575097 -274.352461) (xy 63.526198 -274.368349) (xy 63.475416 -274.376392)
			(xy 63.424 -274.376392) (xy 63.373218 -274.368349) (xy 63.324319 -274.352461) (xy 63.278507 -274.329118)
			(xy 63.236911 -274.298897) (xy 63.200555 -274.262541) (xy 63.170334 -274.220945) (xy 63.146991 -274.175133)
			(xy 63.131103 -274.126234) (xy 63.12306 -274.075452) (xy 62.804382 -274.075452) (xy 62.796666 -274.122928)
			(xy 62.781082 -274.169609) (xy 62.758211 -274.213186) (xy 62.728646 -274.25253) (xy 62.693153 -274.286622)
			(xy 62.65265 -274.314578) (xy 62.608188 -274.335676) (xy 62.560917 -274.349368) (xy 62.512062 -274.3553)
			(xy 62.462887 -274.353319) (xy 62.414668 -274.343475) (xy 62.368652 -274.326023) (xy 62.326031 -274.301416)
			(xy 62.28791 -274.270291) (xy 62.255275 -274.233454) (xy 62.228972 -274.191858) (xy 62.209681 -274.146582)
			(xy 62.197904 -274.098798) (xy 62.193944 -274.049744) (xy 61.876686 -274.049744) (xy 61.876182 -274.075452)
			(xy 61.868139 -274.126234) (xy 61.852251 -274.175133) (xy 61.828908 -274.220945) (xy 61.798687 -274.262541)
			(xy 61.762331 -274.298897) (xy 61.720735 -274.329118) (xy 61.674923 -274.352461) (xy 61.626024 -274.368349)
			(xy 61.575242 -274.376392) (xy 61.523826 -274.376392) (xy 61.473044 -274.368349) (xy 61.424145 -274.352461)
			(xy 61.378333 -274.329118) (xy 61.336737 -274.298897) (xy 61.300381 -274.262541) (xy 61.27016 -274.220945)
			(xy 61.246817 -274.175133) (xy 61.230929 -274.126234) (xy 61.222886 -274.075452) (xy 60.904462 -274.075452)
			(xy 60.896746 -274.122928) (xy 60.881162 -274.169609) (xy 60.858291 -274.213186) (xy 60.828726 -274.25253)
			(xy 60.793233 -274.286622) (xy 60.75273 -274.314578) (xy 60.708268 -274.335676) (xy 60.660997 -274.349368)
			(xy 60.612142 -274.3553) (xy 60.562967 -274.353319) (xy 60.514748 -274.343475) (xy 60.468732 -274.326023)
			(xy 60.426111 -274.301416) (xy 60.38799 -274.270291) (xy 60.355355 -274.233454) (xy 60.329052 -274.191858)
			(xy 60.309761 -274.146582) (xy 60.297984 -274.098798) (xy 60.294024 -274.049744) (xy 59.976761 -274.049744)
			(xy 59.976262 -274.075198) (xy 59.968219 -274.12598) (xy 59.952331 -274.174879) (xy 59.928988 -274.220691)
			(xy 59.898767 -274.262287) (xy 59.862411 -274.298643) (xy 59.820815 -274.328864) (xy 59.775003 -274.352207)
			(xy 59.726104 -274.368095) (xy 59.675322 -274.376138) (xy 59.623906 -274.376138) (xy 59.573124 -274.368095)
			(xy 59.524225 -274.352207) (xy 59.478413 -274.328864) (xy 59.436817 -274.298643) (xy 59.400461 -274.262287)
			(xy 59.37024 -274.220691) (xy 59.346897 -274.174879) (xy 59.331009 -274.12598) (xy 59.322966 -274.075198)
			(xy 59.004583 -274.075198) (xy 58.996826 -274.122928) (xy 58.981242 -274.169609) (xy 58.958371 -274.213186)
			(xy 58.928806 -274.25253) (xy 58.893313 -274.286622) (xy 58.85281 -274.314578) (xy 58.808348 -274.335676)
			(xy 58.761077 -274.349368) (xy 58.712222 -274.3553) (xy 58.663047 -274.353319) (xy 58.614828 -274.343475)
			(xy 58.568812 -274.326023) (xy 58.526191 -274.301416) (xy 58.48807 -274.270291) (xy 58.455435 -274.233454)
			(xy 58.429132 -274.191858) (xy 58.409841 -274.146582) (xy 58.398064 -274.098798) (xy 58.394104 -274.049744)
			(xy 58.0771 -274.049744) (xy 58.076596 -274.075452) (xy 58.068553 -274.126234) (xy 58.052665 -274.175133)
			(xy 58.029322 -274.220945) (xy 57.999101 -274.262541) (xy 57.962745 -274.298897) (xy 57.921149 -274.329118)
			(xy 57.875337 -274.352461) (xy 57.826438 -274.368349) (xy 57.775656 -274.376392) (xy 57.72424 -274.376392)
			(xy 57.673458 -274.368349) (xy 57.624559 -274.352461) (xy 57.578747 -274.329118) (xy 57.537151 -274.298897)
			(xy 57.500795 -274.262541) (xy 57.470574 -274.220945) (xy 57.447231 -274.175133) (xy 57.431343 -274.126234)
			(xy 57.4233 -274.075452) (xy 57.104622 -274.075452) (xy 57.096906 -274.122928) (xy 57.081322 -274.169609)
			(xy 57.058451 -274.213186) (xy 57.028886 -274.25253) (xy 56.993393 -274.286622) (xy 56.95289 -274.314578)
			(xy 56.908428 -274.335676) (xy 56.861157 -274.349368) (xy 56.812302 -274.3553) (xy 56.763127 -274.353319)
			(xy 56.714908 -274.343475) (xy 56.668892 -274.326023) (xy 56.626271 -274.301416) (xy 56.58815 -274.270291)
			(xy 56.555515 -274.233454) (xy 56.529212 -274.191858) (xy 56.509921 -274.146582) (xy 56.498144 -274.098798)
			(xy 56.494184 -274.049744) (xy 56.176926 -274.049744) (xy 56.176422 -274.075452) (xy 56.168379 -274.126234)
			(xy 56.152491 -274.175133) (xy 56.129148 -274.220945) (xy 56.098927 -274.262541) (xy 56.062571 -274.298897)
			(xy 56.020975 -274.329118) (xy 55.975163 -274.352461) (xy 55.926264 -274.368349) (xy 55.875482 -274.376392)
			(xy 55.824066 -274.376392) (xy 55.773284 -274.368349) (xy 55.724385 -274.352461) (xy 55.678573 -274.329118)
			(xy 55.636977 -274.298897) (xy 55.600621 -274.262541) (xy 55.5704 -274.220945) (xy 55.547057 -274.175133)
			(xy 55.531169 -274.126234) (xy 55.523126 -274.075452) (xy 55.204448 -274.075452) (xy 55.196732 -274.122928)
			(xy 55.181148 -274.169609) (xy 55.158277 -274.213186) (xy 55.128712 -274.25253) (xy 55.093219 -274.286622)
			(xy 55.052716 -274.314578) (xy 55.008254 -274.335676) (xy 54.960983 -274.349368) (xy 54.912128 -274.3553)
			(xy 54.862953 -274.353319) (xy 54.814734 -274.343475) (xy 54.768718 -274.326023) (xy 54.726097 -274.301416)
			(xy 54.687976 -274.270291) (xy 54.655341 -274.233454) (xy 54.629038 -274.191858) (xy 54.609747 -274.146582)
			(xy 54.59797 -274.098798) (xy 54.59401 -274.049744) (xy 54.277006 -274.049744) (xy 54.276502 -274.075452)
			(xy 54.268459 -274.126234) (xy 54.252571 -274.175133) (xy 54.229228 -274.220945) (xy 54.199007 -274.262541)
			(xy 54.162651 -274.298897) (xy 54.121055 -274.329118) (xy 54.075243 -274.352461) (xy 54.026344 -274.368349)
			(xy 53.975562 -274.376392) (xy 53.924146 -274.376392) (xy 53.873364 -274.368349) (xy 53.824465 -274.352461)
			(xy 53.778653 -274.329118) (xy 53.737057 -274.298897) (xy 53.700701 -274.262541) (xy 53.67048 -274.220945)
			(xy 53.647137 -274.175133) (xy 53.631249 -274.126234) (xy 53.623206 -274.075452) (xy 53.304528 -274.075452)
			(xy 53.296812 -274.122928) (xy 53.281228 -274.169609) (xy 53.258357 -274.213186) (xy 53.228792 -274.25253)
			(xy 53.193299 -274.286622) (xy 53.152796 -274.314578) (xy 53.108334 -274.335676) (xy 53.061063 -274.349368)
			(xy 53.012208 -274.3553) (xy 52.963033 -274.353319) (xy 52.914814 -274.343475) (xy 52.868798 -274.326023)
			(xy 52.826177 -274.301416) (xy 52.788056 -274.270291) (xy 52.755421 -274.233454) (xy 52.729118 -274.191858)
			(xy 52.709827 -274.146582) (xy 52.69805 -274.098798) (xy 52.69409 -274.049744) (xy 52.377086 -274.049744)
			(xy 52.376582 -274.075452) (xy 52.368539 -274.126234) (xy 52.352651 -274.175133) (xy 52.329308 -274.220945)
			(xy 52.299087 -274.262541) (xy 52.262731 -274.298897) (xy 52.221135 -274.329118) (xy 52.175323 -274.352461)
			(xy 52.126424 -274.368349) (xy 52.075642 -274.376392) (xy 52.024226 -274.376392) (xy 51.973444 -274.368349)
			(xy 51.924545 -274.352461) (xy 51.878733 -274.329118) (xy 51.837137 -274.298897) (xy 51.800781 -274.262541)
			(xy 51.77056 -274.220945) (xy 51.747217 -274.175133) (xy 51.731329 -274.126234) (xy 51.723286 -274.075452)
			(xy 51.404608 -274.075452) (xy 51.396892 -274.122928) (xy 51.381308 -274.169609) (xy 51.358437 -274.213186)
			(xy 51.328872 -274.25253) (xy 51.293379 -274.286622) (xy 51.252876 -274.314578) (xy 51.208414 -274.335676)
			(xy 51.161143 -274.349368) (xy 51.112288 -274.3553) (xy 51.063113 -274.353319) (xy 51.014894 -274.343475)
			(xy 50.968878 -274.326023) (xy 50.926257 -274.301416) (xy 50.888136 -274.270291) (xy 50.855501 -274.233454)
			(xy 50.829198 -274.191858) (xy 50.809907 -274.146582) (xy 50.79813 -274.098798) (xy 50.79417 -274.049744)
			(xy 50.476912 -274.049744) (xy 50.476408 -274.075452) (xy 50.468365 -274.126234) (xy 50.452477 -274.175133)
			(xy 50.429134 -274.220945) (xy 50.398913 -274.262541) (xy 50.362557 -274.298897) (xy 50.320961 -274.329118)
			(xy 50.275149 -274.352461) (xy 50.22625 -274.368349) (xy 50.175468 -274.376392) (xy 50.124052 -274.376392)
			(xy 50.07327 -274.368349) (xy 50.024371 -274.352461) (xy 49.978559 -274.329118) (xy 49.936963 -274.298897)
			(xy 49.900607 -274.262541) (xy 49.870386 -274.220945) (xy 49.847043 -274.175133) (xy 49.831155 -274.126234)
			(xy 49.823112 -274.075452) (xy 49.503582 -274.075452) (xy 49.50178 -274.098084) (xy 49.490323 -274.145247)
			(xy 49.47155 -274.190004) (xy 49.445932 -274.231227) (xy 49.414116 -274.267878) (xy 49.376902 -274.299035)
			(xy 49.335228 -274.323912) (xy 49.290143 -274.341883) (xy 49.242783 -274.352496) (xy 49.218596 -274.354544)
			(xy 49.209421 -274.355478) (xy 49.192608 -274.363023) (xy 49.18583 -274.369276) (xy 49.16424 -274.390866)
			(xy 49.1574 -274.398266) (xy 49.149683 -274.416865) (xy 49.149254 -274.426934) (xy 49.149254 -274.601178)
			(xy 49.149789 -274.611166) (xy 49.157503 -274.629599) (xy 49.16424 -274.636992) (xy 49.18583 -274.658582)
			(xy 49.192669 -274.664893) (xy 49.209597 -274.672588) (xy 49.21885 -274.673568) (xy 49.244837 -274.675568)
			(xy 49.295736 -274.686773) (xy 49.344214 -274.70591) (xy 49.389042 -274.732495) (xy 49.429084 -274.765855)
			(xy 49.463328 -274.805145) (xy 49.490906 -274.849369) (xy 49.511118 -274.897408) (xy 49.523455 -274.948045)
			(xy 49.527599 -274.999958) (xy 49.843956 -274.999958) (xy 49.847916 -274.950904) (xy 49.859693 -274.90312)
			(xy 49.878984 -274.857844) (xy 49.905287 -274.816248) (xy 49.937922 -274.779411) (xy 49.976043 -274.748286)
			(xy 50.018664 -274.723679) (xy 50.06468 -274.706227) (xy 50.112899 -274.696383) (xy 50.162074 -274.694402)
			(xy 50.210929 -274.700334) (xy 50.2582 -274.714026) (xy 50.302662 -274.735124) (xy 50.343165 -274.76308)
			(xy 50.378658 -274.797172) (xy 50.408223 -274.836516) (xy 50.431094 -274.880093) (xy 50.446678 -274.926774)
			(xy 50.454573 -274.975351) (xy 50.455068 -274.999958) (xy 50.454573 -275.024565) (xy 50.454394 -275.025666)
			(xy 50.773326 -275.025666) (xy 50.773326 -274.97425) (xy 50.781369 -274.923468) (xy 50.797257 -274.874569)
			(xy 50.8206 -274.828757) (xy 50.850821 -274.787161) (xy 50.887177 -274.750805) (xy 50.928773 -274.720584)
			(xy 50.974585 -274.697241) (xy 51.023484 -274.681353) (xy 51.074266 -274.67331) (xy 51.125682 -274.67331)
			(xy 51.176464 -274.681353) (xy 51.225363 -274.697241) (xy 51.271175 -274.720584) (xy 51.312771 -274.750805)
			(xy 51.349127 -274.787161) (xy 51.379348 -274.828757) (xy 51.402691 -274.874569) (xy 51.418579 -274.923468)
			(xy 51.426622 -274.97425) (xy 51.427126 -274.999958) (xy 51.74413 -274.999958) (xy 51.74809 -274.950904)
			(xy 51.759867 -274.90312) (xy 51.779158 -274.857844) (xy 51.805461 -274.816248) (xy 51.838096 -274.779411)
			(xy 51.876217 -274.748286) (xy 51.918838 -274.723679) (xy 51.964854 -274.706227) (xy 52.013073 -274.696383)
			(xy 52.062248 -274.694402) (xy 52.111103 -274.700334) (xy 52.158374 -274.714026) (xy 52.202836 -274.735124)
			(xy 52.243339 -274.76308) (xy 52.278832 -274.797172) (xy 52.308397 -274.836516) (xy 52.331268 -274.880093)
			(xy 52.346852 -274.926774) (xy 52.354747 -274.975351) (xy 52.355242 -274.999958) (xy 52.354747 -275.024565)
			(xy 52.354568 -275.025666) (xy 52.673246 -275.025666) (xy 52.673246 -274.97425) (xy 52.681289 -274.923468)
			(xy 52.697177 -274.874569) (xy 52.72052 -274.828757) (xy 52.750741 -274.787161) (xy 52.787097 -274.750805)
			(xy 52.828693 -274.720584) (xy 52.874505 -274.697241) (xy 52.923404 -274.681353) (xy 52.974186 -274.67331)
			(xy 53.025602 -274.67331) (xy 53.076384 -274.681353) (xy 53.125283 -274.697241) (xy 53.171095 -274.720584)
			(xy 53.212691 -274.750805) (xy 53.249047 -274.787161) (xy 53.279268 -274.828757) (xy 53.302611 -274.874569)
			(xy 53.318499 -274.923468) (xy 53.326542 -274.97425) (xy 53.327046 -274.999958) (xy 53.64405 -274.999958)
			(xy 53.64801 -274.950904) (xy 53.659787 -274.90312) (xy 53.679078 -274.857844) (xy 53.705381 -274.816248)
			(xy 53.738016 -274.779411) (xy 53.776137 -274.748286) (xy 53.818758 -274.723679) (xy 53.864774 -274.706227)
			(xy 53.912993 -274.696383) (xy 53.962168 -274.694402) (xy 54.011023 -274.700334) (xy 54.058294 -274.714026)
			(xy 54.102756 -274.735124) (xy 54.143259 -274.76308) (xy 54.178752 -274.797172) (xy 54.208317 -274.836516)
			(xy 54.231188 -274.880093) (xy 54.246772 -274.926774) (xy 54.254667 -274.975351) (xy 54.255162 -274.999958)
			(xy 54.254667 -275.024565) (xy 54.254488 -275.025666) (xy 54.573166 -275.025666) (xy 54.573166 -274.97425)
			(xy 54.581209 -274.923468) (xy 54.597097 -274.874569) (xy 54.62044 -274.828757) (xy 54.650661 -274.787161)
			(xy 54.687017 -274.750805) (xy 54.728613 -274.720584) (xy 54.774425 -274.697241) (xy 54.823324 -274.681353)
			(xy 54.874106 -274.67331) (xy 54.925522 -274.67331) (xy 54.976304 -274.681353) (xy 55.025203 -274.697241)
			(xy 55.071015 -274.720584) (xy 55.112611 -274.750805) (xy 55.148967 -274.787161) (xy 55.179188 -274.828757)
			(xy 55.202531 -274.874569) (xy 55.218419 -274.923468) (xy 55.226462 -274.97425) (xy 55.226966 -274.999958)
			(xy 55.54397 -274.999958) (xy 55.54793 -274.950904) (xy 55.559707 -274.90312) (xy 55.578998 -274.857844)
			(xy 55.605301 -274.816248) (xy 55.637936 -274.779411) (xy 55.676057 -274.748286) (xy 55.718678 -274.723679)
			(xy 55.764694 -274.706227) (xy 55.812913 -274.696383) (xy 55.862088 -274.694402) (xy 55.910943 -274.700334)
			(xy 55.958214 -274.714026) (xy 56.002676 -274.735124) (xy 56.043179 -274.76308) (xy 56.078672 -274.797172)
			(xy 56.108237 -274.836516) (xy 56.131108 -274.880093) (xy 56.146692 -274.926774) (xy 56.154587 -274.975351)
			(xy 56.155082 -274.999958) (xy 56.154587 -275.024565) (xy 56.154408 -275.025666) (xy 56.47334 -275.025666)
			(xy 56.47334 -274.97425) (xy 56.481383 -274.923468) (xy 56.497271 -274.874569) (xy 56.520614 -274.828757)
			(xy 56.550835 -274.787161) (xy 56.587191 -274.750805) (xy 56.628787 -274.720584) (xy 56.674599 -274.697241)
			(xy 56.723498 -274.681353) (xy 56.77428 -274.67331) (xy 56.825696 -274.67331) (xy 56.876478 -274.681353)
			(xy 56.925377 -274.697241) (xy 56.971189 -274.720584) (xy 57.012785 -274.750805) (xy 57.049141 -274.787161)
			(xy 57.079362 -274.828757) (xy 57.102705 -274.874569) (xy 57.118593 -274.923468) (xy 57.126636 -274.97425)
			(xy 57.12714 -274.999958) (xy 57.444144 -274.999958) (xy 57.448104 -274.950904) (xy 57.459881 -274.90312)
			(xy 57.479172 -274.857844) (xy 57.505475 -274.816248) (xy 57.53811 -274.779411) (xy 57.576231 -274.748286)
			(xy 57.618852 -274.723679) (xy 57.664868 -274.706227) (xy 57.713087 -274.696383) (xy 57.762262 -274.694402)
			(xy 57.811117 -274.700334) (xy 57.858388 -274.714026) (xy 57.90285 -274.735124) (xy 57.943353 -274.76308)
			(xy 57.978846 -274.797172) (xy 58.008411 -274.836516) (xy 58.031282 -274.880093) (xy 58.046866 -274.926774)
			(xy 58.054761 -274.975351) (xy 58.055256 -274.999958) (xy 58.054761 -275.024565) (xy 58.054582 -275.025666)
			(xy 58.37326 -275.025666) (xy 58.37326 -274.97425) (xy 58.381303 -274.923468) (xy 58.397191 -274.874569)
			(xy 58.420534 -274.828757) (xy 58.450755 -274.787161) (xy 58.487111 -274.750805) (xy 58.528707 -274.720584)
			(xy 58.574519 -274.697241) (xy 58.623418 -274.681353) (xy 58.6742 -274.67331) (xy 58.725616 -274.67331)
			(xy 58.776398 -274.681353) (xy 58.825297 -274.697241) (xy 58.871109 -274.720584) (xy 58.912705 -274.750805)
			(xy 58.949061 -274.787161) (xy 58.979282 -274.828757) (xy 59.002625 -274.874569) (xy 59.018513 -274.923468)
			(xy 59.026556 -274.97425) (xy 59.02706 -274.999958) (xy 59.344064 -274.999958) (xy 59.348024 -274.950904)
			(xy 59.359801 -274.90312) (xy 59.379092 -274.857844) (xy 59.405395 -274.816248) (xy 59.43803 -274.779411)
			(xy 59.476151 -274.748286) (xy 59.518772 -274.723679) (xy 59.564788 -274.706227) (xy 59.613007 -274.696383)
			(xy 59.662182 -274.694402) (xy 59.711037 -274.700334) (xy 59.758308 -274.714026) (xy 59.80277 -274.735124)
			(xy 59.843273 -274.76308) (xy 59.878766 -274.797172) (xy 59.908331 -274.836516) (xy 59.931202 -274.880093)
			(xy 59.946786 -274.926774) (xy 59.954681 -274.975351) (xy 59.955176 -274.999958) (xy 59.954681 -275.024565)
			(xy 59.954543 -275.025412) (xy 60.272926 -275.025412) (xy 60.272926 -274.973996) (xy 60.280969 -274.923214)
			(xy 60.296857 -274.874315) (xy 60.3202 -274.828503) (xy 60.350421 -274.786907) (xy 60.386777 -274.750551)
			(xy 60.428373 -274.72033) (xy 60.474185 -274.696987) (xy 60.523084 -274.681099) (xy 60.573866 -274.673056)
			(xy 60.625282 -274.673056) (xy 60.676064 -274.681099) (xy 60.724963 -274.696987) (xy 60.770775 -274.72033)
			(xy 60.812371 -274.750551) (xy 60.848727 -274.786907) (xy 60.878948 -274.828503) (xy 60.902291 -274.874315)
			(xy 60.918179 -274.923214) (xy 60.926222 -274.973996) (xy 60.926726 -274.999704) (xy 60.926721 -274.999958)
			(xy 61.243984 -274.999958) (xy 61.247944 -274.950904) (xy 61.259721 -274.90312) (xy 61.279012 -274.857844)
			(xy 61.305315 -274.816248) (xy 61.33795 -274.779411) (xy 61.376071 -274.748286) (xy 61.418692 -274.723679)
			(xy 61.464708 -274.706227) (xy 61.512927 -274.696383) (xy 61.562102 -274.694402) (xy 61.610957 -274.700334)
			(xy 61.658228 -274.714026) (xy 61.70269 -274.735124) (xy 61.743193 -274.76308) (xy 61.778686 -274.797172)
			(xy 61.808251 -274.836516) (xy 61.831122 -274.880093) (xy 61.846706 -274.926774) (xy 61.854601 -274.975351)
			(xy 61.855096 -274.999958) (xy 61.854601 -275.024565) (xy 61.854422 -275.025666) (xy 62.172846 -275.025666)
			(xy 62.172846 -274.97425) (xy 62.180889 -274.923468) (xy 62.196777 -274.874569) (xy 62.22012 -274.828757)
			(xy 62.250341 -274.787161) (xy 62.286697 -274.750805) (xy 62.328293 -274.720584) (xy 62.374105 -274.697241)
			(xy 62.423004 -274.681353) (xy 62.473786 -274.67331) (xy 62.525202 -274.67331) (xy 62.575984 -274.681353)
			(xy 62.624883 -274.697241) (xy 62.670695 -274.720584) (xy 62.712291 -274.750805) (xy 62.748647 -274.787161)
			(xy 62.778868 -274.828757) (xy 62.802211 -274.874569) (xy 62.818099 -274.923468) (xy 62.826142 -274.97425)
			(xy 62.826646 -274.999958) (xy 63.144158 -274.999958) (xy 63.148118 -274.950904) (xy 63.159895 -274.90312)
			(xy 63.179186 -274.857844) (xy 63.205489 -274.816248) (xy 63.238124 -274.779411) (xy 63.276245 -274.748286)
			(xy 63.318866 -274.723679) (xy 63.364882 -274.706227) (xy 63.413101 -274.696383) (xy 63.462276 -274.694402)
			(xy 63.511131 -274.700334) (xy 63.558402 -274.714026) (xy 63.602864 -274.735124) (xy 63.643367 -274.76308)
			(xy 63.67886 -274.797172) (xy 63.708425 -274.836516) (xy 63.731296 -274.880093) (xy 63.74688 -274.926774)
			(xy 63.754775 -274.975351) (xy 63.75527 -274.999958) (xy 63.754775 -275.024565) (xy 63.754637 -275.025412)
			(xy 64.07302 -275.025412) (xy 64.07302 -274.973996) (xy 64.081063 -274.923214) (xy 64.096951 -274.874315)
			(xy 64.120294 -274.828503) (xy 64.150515 -274.786907) (xy 64.186871 -274.750551) (xy 64.228467 -274.72033)
			(xy 64.274279 -274.696987) (xy 64.323178 -274.681099) (xy 64.37396 -274.673056) (xy 64.425376 -274.673056)
			(xy 64.476158 -274.681099) (xy 64.525057 -274.696987) (xy 64.570869 -274.72033) (xy 64.612465 -274.750551)
			(xy 64.648821 -274.786907) (xy 64.679042 -274.828503) (xy 64.702385 -274.874315) (xy 64.718273 -274.923214)
			(xy 64.726316 -274.973996) (xy 64.72682 -274.999704) (xy 64.726815 -274.999958) (xy 65.044078 -274.999958)
			(xy 65.048038 -274.950904) (xy 65.059815 -274.90312) (xy 65.079106 -274.857844) (xy 65.105409 -274.816248)
			(xy 65.138044 -274.779411) (xy 65.176165 -274.748286) (xy 65.218786 -274.723679) (xy 65.264802 -274.706227)
			(xy 65.313021 -274.696383) (xy 65.362196 -274.694402) (xy 65.411051 -274.700334) (xy 65.458322 -274.714026)
			(xy 65.502784 -274.735124) (xy 65.543287 -274.76308) (xy 65.57878 -274.797172) (xy 65.608345 -274.836516)
			(xy 65.631216 -274.880093) (xy 65.6468 -274.926774) (xy 65.654695 -274.975351) (xy 65.65519 -274.999958)
			(xy 65.654695 -275.024565) (xy 65.654516 -275.025666) (xy 65.97294 -275.025666) (xy 65.97294 -274.97425)
			(xy 65.980983 -274.923468) (xy 65.996871 -274.874569) (xy 66.020214 -274.828757) (xy 66.050435 -274.787161)
			(xy 66.086791 -274.750805) (xy 66.128387 -274.720584) (xy 66.174199 -274.697241) (xy 66.223098 -274.681353)
			(xy 66.27388 -274.67331) (xy 66.325296 -274.67331) (xy 66.376078 -274.681353) (xy 66.424977 -274.697241)
			(xy 66.470789 -274.720584) (xy 66.512385 -274.750805) (xy 66.548741 -274.787161) (xy 66.578962 -274.828757)
			(xy 66.602305 -274.874569) (xy 66.618193 -274.923468) (xy 66.626236 -274.97425) (xy 66.62674 -274.999958)
			(xy 66.943998 -274.999958) (xy 66.947958 -274.950904) (xy 66.959735 -274.90312) (xy 66.979026 -274.857844)
			(xy 67.005329 -274.816248) (xy 67.037964 -274.779411) (xy 67.076085 -274.748286) (xy 67.118706 -274.723679)
			(xy 67.164722 -274.706227) (xy 67.212941 -274.696383) (xy 67.262116 -274.694402) (xy 67.310971 -274.700334)
			(xy 67.358242 -274.714026) (xy 67.402704 -274.735124) (xy 67.443207 -274.76308) (xy 67.4787 -274.797172)
			(xy 67.508265 -274.836516) (xy 67.531136 -274.880093) (xy 67.54672 -274.926774) (xy 67.554615 -274.975351)
			(xy 67.55511 -274.999958) (xy 67.554615 -275.024565) (xy 67.554477 -275.025412) (xy 67.87286 -275.025412)
			(xy 67.87286 -274.973996) (xy 67.880903 -274.923214) (xy 67.896791 -274.874315) (xy 67.920134 -274.828503)
			(xy 67.950355 -274.786907) (xy 67.986711 -274.750551) (xy 68.028307 -274.72033) (xy 68.074119 -274.696987)
			(xy 68.123018 -274.681099) (xy 68.1738 -274.673056) (xy 68.225216 -274.673056) (xy 68.275998 -274.681099)
			(xy 68.324897 -274.696987) (xy 68.370709 -274.72033) (xy 68.412305 -274.750551) (xy 68.448661 -274.786907)
			(xy 68.478882 -274.828503) (xy 68.502225 -274.874315) (xy 68.518113 -274.923214) (xy 68.526156 -274.973996)
			(xy 68.52666 -274.999704) (xy 68.526655 -274.999958) (xy 68.844172 -274.999958) (xy 68.848132 -274.950904)
			(xy 68.859909 -274.90312) (xy 68.8792 -274.857844) (xy 68.905503 -274.816248) (xy 68.938138 -274.779411)
			(xy 68.976259 -274.748286) (xy 69.01888 -274.723679) (xy 69.064896 -274.706227) (xy 69.113115 -274.696383)
			(xy 69.16229 -274.694402) (xy 69.211145 -274.700334) (xy 69.258416 -274.714026) (xy 69.302878 -274.735124)
			(xy 69.343381 -274.76308) (xy 69.378874 -274.797172) (xy 69.408439 -274.836516) (xy 69.43131 -274.880093)
			(xy 69.446894 -274.926774) (xy 69.454789 -274.975351) (xy 69.455284 -274.999958) (xy 69.454789 -275.024565)
			(xy 69.45461 -275.025666) (xy 69.77278 -275.025666) (xy 69.77278 -274.97425) (xy 69.780823 -274.923468)
			(xy 69.796711 -274.874569) (xy 69.820054 -274.828757) (xy 69.850275 -274.787161) (xy 69.886631 -274.750805)
			(xy 69.928227 -274.720584) (xy 69.974039 -274.697241) (xy 70.022938 -274.681353) (xy 70.07372 -274.67331)
			(xy 70.125136 -274.67331) (xy 70.175918 -274.681353) (xy 70.224817 -274.697241) (xy 70.270629 -274.720584)
			(xy 70.312225 -274.750805) (xy 70.348581 -274.787161) (xy 70.378802 -274.828757) (xy 70.402145 -274.874569)
			(xy 70.418033 -274.923468) (xy 70.426076 -274.97425) (xy 70.42658 -274.999958) (xy 70.744092 -274.999958)
			(xy 70.748052 -274.950904) (xy 70.759829 -274.90312) (xy 70.77912 -274.857844) (xy 70.805423 -274.816248)
			(xy 70.838058 -274.779411) (xy 70.876179 -274.748286) (xy 70.9188 -274.723679) (xy 70.964816 -274.706227)
			(xy 71.013035 -274.696383) (xy 71.06221 -274.694402) (xy 71.111065 -274.700334) (xy 71.158336 -274.714026)
			(xy 71.202798 -274.735124) (xy 71.243301 -274.76308) (xy 71.278794 -274.797172) (xy 71.308359 -274.836516)
			(xy 71.33123 -274.880093) (xy 71.346814 -274.926774) (xy 71.354709 -274.975351) (xy 71.355204 -274.999958)
			(xy 71.354709 -275.024565) (xy 71.354571 -275.025412) (xy 71.672954 -275.025412) (xy 71.672954 -274.973996)
			(xy 71.680997 -274.923214) (xy 71.696885 -274.874315) (xy 71.720228 -274.828503) (xy 71.750449 -274.786907)
			(xy 71.786805 -274.750551) (xy 71.828401 -274.72033) (xy 71.874213 -274.696987) (xy 71.923112 -274.681099)
			(xy 71.973894 -274.673056) (xy 72.02531 -274.673056) (xy 72.076092 -274.681099) (xy 72.124991 -274.696987)
			(xy 72.170803 -274.72033) (xy 72.212399 -274.750551) (xy 72.248755 -274.786907) (xy 72.278976 -274.828503)
			(xy 72.302319 -274.874315) (xy 72.318207 -274.923214) (xy 72.32625 -274.973996) (xy 72.326754 -274.999704)
			(xy 72.326749 -274.999958) (xy 72.644012 -274.999958) (xy 72.647972 -274.950904) (xy 72.659749 -274.90312)
			(xy 72.67904 -274.857844) (xy 72.705343 -274.816248) (xy 72.737978 -274.779411) (xy 72.776099 -274.748286)
			(xy 72.81872 -274.723679) (xy 72.864736 -274.706227) (xy 72.912955 -274.696383) (xy 72.96213 -274.694402)
			(xy 73.010985 -274.700334) (xy 73.058256 -274.714026) (xy 73.102718 -274.735124) (xy 73.143221 -274.76308)
			(xy 73.178714 -274.797172) (xy 73.208279 -274.836516) (xy 73.23115 -274.880093) (xy 73.246734 -274.926774)
			(xy 73.254629 -274.975351) (xy 73.255124 -274.999958) (xy 73.254629 -275.024565) (xy 73.25445 -275.025666)
			(xy 73.572874 -275.025666) (xy 73.572874 -274.97425) (xy 73.580917 -274.923468) (xy 73.596805 -274.874569)
			(xy 73.620148 -274.828757) (xy 73.650369 -274.787161) (xy 73.686725 -274.750805) (xy 73.728321 -274.720584)
			(xy 73.774133 -274.697241) (xy 73.823032 -274.681353) (xy 73.873814 -274.67331) (xy 73.92523 -274.67331)
			(xy 73.976012 -274.681353) (xy 74.024911 -274.697241) (xy 74.070723 -274.720584) (xy 74.112319 -274.750805)
			(xy 74.148675 -274.787161) (xy 74.178896 -274.828757) (xy 74.202239 -274.874569) (xy 74.218127 -274.923468)
			(xy 74.22617 -274.97425) (xy 74.226674 -274.999958) (xy 74.543932 -274.999958) (xy 74.547892 -274.950904)
			(xy 74.559669 -274.90312) (xy 74.57896 -274.857844) (xy 74.605263 -274.816248) (xy 74.637898 -274.779411)
			(xy 74.676019 -274.748286) (xy 74.71864 -274.723679) (xy 74.764656 -274.706227) (xy 74.812875 -274.696383)
			(xy 74.86205 -274.694402) (xy 74.910905 -274.700334) (xy 74.958176 -274.714026) (xy 75.002638 -274.735124)
			(xy 75.043141 -274.76308) (xy 75.078634 -274.797172) (xy 75.108199 -274.836516) (xy 75.13107 -274.880093)
			(xy 75.146654 -274.926774) (xy 75.154549 -274.975351) (xy 75.155044 -274.999958) (xy 75.154549 -275.024565)
			(xy 75.154411 -275.025412) (xy 75.473048 -275.025412) (xy 75.473048 -274.973996) (xy 75.481091 -274.923214)
			(xy 75.496979 -274.874315) (xy 75.520322 -274.828503) (xy 75.550543 -274.786907) (xy 75.586899 -274.750551)
			(xy 75.628495 -274.72033) (xy 75.674307 -274.696987) (xy 75.723206 -274.681099) (xy 75.773988 -274.673056)
			(xy 75.825404 -274.673056) (xy 75.876186 -274.681099) (xy 75.925085 -274.696987) (xy 75.970897 -274.72033)
			(xy 76.012493 -274.750551) (xy 76.048849 -274.786907) (xy 76.07907 -274.828503) (xy 76.102413 -274.874315)
			(xy 76.118301 -274.923214) (xy 76.126344 -274.973996) (xy 76.126848 -274.999704) (xy 76.126843 -274.999958)
			(xy 76.443852 -274.999958) (xy 76.447812 -274.950904) (xy 76.459589 -274.90312) (xy 76.47888 -274.857844)
			(xy 76.505183 -274.816248) (xy 76.537818 -274.779411) (xy 76.575939 -274.748286) (xy 76.61856 -274.723679)
			(xy 76.664576 -274.706227) (xy 76.712795 -274.696383) (xy 76.76197 -274.694402) (xy 76.810825 -274.700334)
			(xy 76.858096 -274.714026) (xy 76.902558 -274.735124) (xy 76.943061 -274.76308) (xy 76.978554 -274.797172)
			(xy 77.008119 -274.836516) (xy 77.03099 -274.880093) (xy 77.046574 -274.926774) (xy 77.054469 -274.975351)
			(xy 77.054964 -274.999958) (xy 77.054469 -275.024565) (xy 77.05429 -275.025666) (xy 77.372968 -275.025666)
			(xy 77.372968 -274.97425) (xy 77.381011 -274.923468) (xy 77.396899 -274.874569) (xy 77.420242 -274.828757)
			(xy 77.450463 -274.787161) (xy 77.486819 -274.750805) (xy 77.528415 -274.720584) (xy 77.574227 -274.697241)
			(xy 77.623126 -274.681353) (xy 77.673908 -274.67331) (xy 77.725324 -274.67331) (xy 77.776106 -274.681353)
			(xy 77.825005 -274.697241) (xy 77.870817 -274.720584) (xy 77.912413 -274.750805) (xy 77.948769 -274.787161)
			(xy 77.97899 -274.828757) (xy 78.002333 -274.874569) (xy 78.018221 -274.923468) (xy 78.026264 -274.97425)
			(xy 78.026768 -274.999958) (xy 78.343772 -274.999958) (xy 78.347732 -274.950904) (xy 78.359509 -274.90312)
			(xy 78.3788 -274.857844) (xy 78.405103 -274.816248) (xy 78.437738 -274.779411) (xy 78.475859 -274.748286)
			(xy 78.51848 -274.723679) (xy 78.564496 -274.706227) (xy 78.612715 -274.696383) (xy 78.66189 -274.694402)
			(xy 78.710745 -274.700334) (xy 78.758016 -274.714026) (xy 78.802478 -274.735124) (xy 78.842981 -274.76308)
			(xy 78.878474 -274.797172) (xy 78.908039 -274.836516) (xy 78.93091 -274.880093) (xy 78.946494 -274.926774)
			(xy 78.954389 -274.975351) (xy 78.954884 -274.999958) (xy 78.954389 -275.024565) (xy 78.95421 -275.025666)
			(xy 79.272888 -275.025666) (xy 79.272888 -274.97425) (xy 79.280931 -274.923468) (xy 79.296819 -274.874569)
			(xy 79.320162 -274.828757) (xy 79.350383 -274.787161) (xy 79.386739 -274.750805) (xy 79.428335 -274.720584)
			(xy 79.474147 -274.697241) (xy 79.523046 -274.681353) (xy 79.573828 -274.67331) (xy 79.625244 -274.67331)
			(xy 79.676026 -274.681353) (xy 79.724925 -274.697241) (xy 79.770737 -274.720584) (xy 79.812333 -274.750805)
			(xy 79.848689 -274.787161) (xy 79.87891 -274.828757) (xy 79.902253 -274.874569) (xy 79.918141 -274.923468)
			(xy 79.926184 -274.97425) (xy 79.926688 -274.999958) (xy 80.243946 -274.999958) (xy 80.247906 -274.950904)
			(xy 80.259683 -274.90312) (xy 80.278974 -274.857844) (xy 80.305277 -274.816248) (xy 80.337912 -274.779411)
			(xy 80.376033 -274.748286) (xy 80.418654 -274.723679) (xy 80.46467 -274.706227) (xy 80.512889 -274.696383)
			(xy 80.562064 -274.694402) (xy 80.610919 -274.700334) (xy 80.65819 -274.714026) (xy 80.702652 -274.735124)
			(xy 80.743155 -274.76308) (xy 80.778648 -274.797172) (xy 80.808213 -274.836516) (xy 80.831084 -274.880093)
			(xy 80.846668 -274.926774) (xy 80.854563 -274.975351) (xy 80.855058 -274.999958) (xy 80.854563 -275.024565)
			(xy 80.854425 -275.025412) (xy 81.173316 -275.025412) (xy 81.173316 -274.973996) (xy 81.181359 -274.923214)
			(xy 81.197247 -274.874315) (xy 81.22059 -274.828503) (xy 81.250811 -274.786907) (xy 81.287167 -274.750551)
			(xy 81.328763 -274.72033) (xy 81.374575 -274.696987) (xy 81.423474 -274.681099) (xy 81.474256 -274.673056)
			(xy 81.525672 -274.673056) (xy 81.576454 -274.681099) (xy 81.625353 -274.696987) (xy 81.671165 -274.72033)
			(xy 81.712761 -274.750551) (xy 81.749117 -274.786907) (xy 81.779338 -274.828503) (xy 81.802681 -274.874315)
			(xy 81.818569 -274.923214) (xy 81.826612 -274.973996) (xy 81.827116 -274.999704) (xy 81.826612 -275.025412)
			(xy 82.123276 -275.025412) (xy 82.123276 -274.973996) (xy 82.131319 -274.923214) (xy 82.147207 -274.874315)
			(xy 82.17055 -274.828503) (xy 82.200771 -274.786907) (xy 82.237127 -274.750551) (xy 82.278723 -274.72033)
			(xy 82.324535 -274.696987) (xy 82.373434 -274.681099) (xy 82.424216 -274.673056) (xy 82.475632 -274.673056)
			(xy 82.526414 -274.681099) (xy 82.575313 -274.696987) (xy 82.621125 -274.72033) (xy 82.662721 -274.750551)
			(xy 82.699077 -274.786907) (xy 82.729298 -274.828503) (xy 82.752641 -274.874315) (xy 82.768529 -274.923214)
			(xy 82.776572 -274.973996) (xy 82.777076 -274.999704) (xy 82.777071 -274.999958) (xy 83.094334 -274.999958)
			(xy 83.098294 -274.950904) (xy 83.110071 -274.90312) (xy 83.129362 -274.857844) (xy 83.155665 -274.816248)
			(xy 83.1883 -274.779411) (xy 83.226421 -274.748286) (xy 83.269042 -274.723679) (xy 83.315058 -274.706227)
			(xy 83.363277 -274.696383) (xy 83.412452 -274.694402) (xy 83.461307 -274.700334) (xy 83.508578 -274.714026)
			(xy 83.55304 -274.735124) (xy 83.593543 -274.76308) (xy 83.629036 -274.797172) (xy 83.658601 -274.836516)
			(xy 83.681472 -274.880093) (xy 83.697056 -274.926774) (xy 83.704951 -274.975351) (xy 83.705446 -274.999958)
			(xy 83.704951 -275.024565) (xy 83.697056 -275.073142) (xy 83.681472 -275.119823) (xy 83.658601 -275.1634)
			(xy 83.629036 -275.202744) (xy 83.593543 -275.236836) (xy 83.55304 -275.264792) (xy 83.508578 -275.28589)
			(xy 83.461307 -275.299582) (xy 83.412452 -275.305514) (xy 83.363277 -275.303533) (xy 83.315058 -275.293689)
			(xy 83.269042 -275.276237) (xy 83.226421 -275.25163) (xy 83.1883 -275.220505) (xy 83.155665 -275.183668)
			(xy 83.129362 -275.142072) (xy 83.110071 -275.096796) (xy 83.098294 -275.049012) (xy 83.094334 -274.999958)
			(xy 82.777071 -274.999958) (xy 82.776572 -275.025412) (xy 82.768529 -275.076194) (xy 82.752641 -275.125093)
			(xy 82.729298 -275.170905) (xy 82.699077 -275.212501) (xy 82.662721 -275.248857) (xy 82.621125 -275.279078)
			(xy 82.575313 -275.302421) (xy 82.526414 -275.318309) (xy 82.475632 -275.326352) (xy 82.424216 -275.326352)
			(xy 82.373434 -275.318309) (xy 82.324535 -275.302421) (xy 82.278723 -275.279078) (xy 82.237127 -275.248857)
			(xy 82.200771 -275.212501) (xy 82.17055 -275.170905) (xy 82.147207 -275.125093) (xy 82.131319 -275.076194)
			(xy 82.123276 -275.025412) (xy 81.826612 -275.025412) (xy 81.818569 -275.076194) (xy 81.802681 -275.125093)
			(xy 81.779338 -275.170905) (xy 81.749117 -275.212501) (xy 81.712761 -275.248857) (xy 81.671165 -275.279078)
			(xy 81.625353 -275.302421) (xy 81.576454 -275.318309) (xy 81.525672 -275.326352) (xy 81.474256 -275.326352)
			(xy 81.423474 -275.318309) (xy 81.374575 -275.302421) (xy 81.328763 -275.279078) (xy 81.287167 -275.248857)
			(xy 81.250811 -275.212501) (xy 81.22059 -275.170905) (xy 81.197247 -275.125093) (xy 81.181359 -275.076194)
			(xy 81.173316 -275.025412) (xy 80.854425 -275.025412) (xy 80.846668 -275.073142) (xy 80.831084 -275.119823)
			(xy 80.808213 -275.1634) (xy 80.778648 -275.202744) (xy 80.743155 -275.236836) (xy 80.702652 -275.264792)
			(xy 80.65819 -275.28589) (xy 80.610919 -275.299582) (xy 80.562064 -275.305514) (xy 80.512889 -275.303533)
			(xy 80.46467 -275.293689) (xy 80.418654 -275.276237) (xy 80.376033 -275.25163) (xy 80.337912 -275.220505)
			(xy 80.305277 -275.183668) (xy 80.278974 -275.142072) (xy 80.259683 -275.096796) (xy 80.247906 -275.049012)
			(xy 80.243946 -274.999958) (xy 79.926688 -274.999958) (xy 79.926184 -275.025666) (xy 79.918141 -275.076448)
			(xy 79.902253 -275.125347) (xy 79.87891 -275.171159) (xy 79.848689 -275.212755) (xy 79.812333 -275.249111)
			(xy 79.770737 -275.279332) (xy 79.724925 -275.302675) (xy 79.676026 -275.318563) (xy 79.625244 -275.326606)
			(xy 79.573828 -275.326606) (xy 79.523046 -275.318563) (xy 79.474147 -275.302675) (xy 79.428335 -275.279332)
			(xy 79.386739 -275.249111) (xy 79.350383 -275.212755) (xy 79.320162 -275.171159) (xy 79.296819 -275.125347)
			(xy 79.280931 -275.076448) (xy 79.272888 -275.025666) (xy 78.95421 -275.025666) (xy 78.946494 -275.073142)
			(xy 78.93091 -275.119823) (xy 78.908039 -275.1634) (xy 78.878474 -275.202744) (xy 78.842981 -275.236836)
			(xy 78.802478 -275.264792) (xy 78.758016 -275.28589) (xy 78.710745 -275.299582) (xy 78.66189 -275.305514)
			(xy 78.612715 -275.303533) (xy 78.564496 -275.293689) (xy 78.51848 -275.276237) (xy 78.475859 -275.25163)
			(xy 78.437738 -275.220505) (xy 78.405103 -275.183668) (xy 78.3788 -275.142072) (xy 78.359509 -275.096796)
			(xy 78.347732 -275.049012) (xy 78.343772 -274.999958) (xy 78.026768 -274.999958) (xy 78.026264 -275.025666)
			(xy 78.018221 -275.076448) (xy 78.002333 -275.125347) (xy 77.97899 -275.171159) (xy 77.948769 -275.212755)
			(xy 77.912413 -275.249111) (xy 77.870817 -275.279332) (xy 77.825005 -275.302675) (xy 77.776106 -275.318563)
			(xy 77.725324 -275.326606) (xy 77.673908 -275.326606) (xy 77.623126 -275.318563) (xy 77.574227 -275.302675)
			(xy 77.528415 -275.279332) (xy 77.486819 -275.249111) (xy 77.450463 -275.212755) (xy 77.420242 -275.171159)
			(xy 77.396899 -275.125347) (xy 77.381011 -275.076448) (xy 77.372968 -275.025666) (xy 77.05429 -275.025666)
			(xy 77.046574 -275.073142) (xy 77.03099 -275.119823) (xy 77.008119 -275.1634) (xy 76.978554 -275.202744)
			(xy 76.943061 -275.236836) (xy 76.902558 -275.264792) (xy 76.858096 -275.28589) (xy 76.810825 -275.299582)
			(xy 76.76197 -275.305514) (xy 76.712795 -275.303533) (xy 76.664576 -275.293689) (xy 76.61856 -275.276237)
			(xy 76.575939 -275.25163) (xy 76.537818 -275.220505) (xy 76.505183 -275.183668) (xy 76.47888 -275.142072)
			(xy 76.459589 -275.096796) (xy 76.447812 -275.049012) (xy 76.443852 -274.999958) (xy 76.126843 -274.999958)
			(xy 76.126344 -275.025412) (xy 76.118301 -275.076194) (xy 76.102413 -275.125093) (xy 76.07907 -275.170905)
			(xy 76.048849 -275.212501) (xy 76.012493 -275.248857) (xy 75.970897 -275.279078) (xy 75.925085 -275.302421)
			(xy 75.876186 -275.318309) (xy 75.825404 -275.326352) (xy 75.773988 -275.326352) (xy 75.723206 -275.318309)
			(xy 75.674307 -275.302421) (xy 75.628495 -275.279078) (xy 75.586899 -275.248857) (xy 75.550543 -275.212501)
			(xy 75.520322 -275.170905) (xy 75.496979 -275.125093) (xy 75.481091 -275.076194) (xy 75.473048 -275.025412)
			(xy 75.154411 -275.025412) (xy 75.146654 -275.073142) (xy 75.13107 -275.119823) (xy 75.108199 -275.1634)
			(xy 75.078634 -275.202744) (xy 75.043141 -275.236836) (xy 75.002638 -275.264792) (xy 74.958176 -275.28589)
			(xy 74.910905 -275.299582) (xy 74.86205 -275.305514) (xy 74.812875 -275.303533) (xy 74.764656 -275.293689)
			(xy 74.71864 -275.276237) (xy 74.676019 -275.25163) (xy 74.637898 -275.220505) (xy 74.605263 -275.183668)
			(xy 74.57896 -275.142072) (xy 74.559669 -275.096796) (xy 74.547892 -275.049012) (xy 74.543932 -274.999958)
			(xy 74.226674 -274.999958) (xy 74.22617 -275.025666) (xy 74.218127 -275.076448) (xy 74.202239 -275.125347)
			(xy 74.178896 -275.171159) (xy 74.148675 -275.212755) (xy 74.112319 -275.249111) (xy 74.070723 -275.279332)
			(xy 74.024911 -275.302675) (xy 73.976012 -275.318563) (xy 73.92523 -275.326606) (xy 73.873814 -275.326606)
			(xy 73.823032 -275.318563) (xy 73.774133 -275.302675) (xy 73.728321 -275.279332) (xy 73.686725 -275.249111)
			(xy 73.650369 -275.212755) (xy 73.620148 -275.171159) (xy 73.596805 -275.125347) (xy 73.580917 -275.076448)
			(xy 73.572874 -275.025666) (xy 73.25445 -275.025666) (xy 73.246734 -275.073142) (xy 73.23115 -275.119823)
			(xy 73.208279 -275.1634) (xy 73.178714 -275.202744) (xy 73.143221 -275.236836) (xy 73.102718 -275.264792)
			(xy 73.058256 -275.28589) (xy 73.010985 -275.299582) (xy 72.96213 -275.305514) (xy 72.912955 -275.303533)
			(xy 72.864736 -275.293689) (xy 72.81872 -275.276237) (xy 72.776099 -275.25163) (xy 72.737978 -275.220505)
			(xy 72.705343 -275.183668) (xy 72.67904 -275.142072) (xy 72.659749 -275.096796) (xy 72.647972 -275.049012)
			(xy 72.644012 -274.999958) (xy 72.326749 -274.999958) (xy 72.32625 -275.025412) (xy 72.318207 -275.076194)
			(xy 72.302319 -275.125093) (xy 72.278976 -275.170905) (xy 72.248755 -275.212501) (xy 72.212399 -275.248857)
			(xy 72.170803 -275.279078) (xy 72.124991 -275.302421) (xy 72.076092 -275.318309) (xy 72.02531 -275.326352)
			(xy 71.973894 -275.326352) (xy 71.923112 -275.318309) (xy 71.874213 -275.302421) (xy 71.828401 -275.279078)
			(xy 71.786805 -275.248857) (xy 71.750449 -275.212501) (xy 71.720228 -275.170905) (xy 71.696885 -275.125093)
			(xy 71.680997 -275.076194) (xy 71.672954 -275.025412) (xy 71.354571 -275.025412) (xy 71.346814 -275.073142)
			(xy 71.33123 -275.119823) (xy 71.308359 -275.1634) (xy 71.278794 -275.202744) (xy 71.243301 -275.236836)
			(xy 71.202798 -275.264792) (xy 71.158336 -275.28589) (xy 71.111065 -275.299582) (xy 71.06221 -275.305514)
			(xy 71.013035 -275.303533) (xy 70.964816 -275.293689) (xy 70.9188 -275.276237) (xy 70.876179 -275.25163)
			(xy 70.838058 -275.220505) (xy 70.805423 -275.183668) (xy 70.77912 -275.142072) (xy 70.759829 -275.096796)
			(xy 70.748052 -275.049012) (xy 70.744092 -274.999958) (xy 70.42658 -274.999958) (xy 70.426076 -275.025666)
			(xy 70.418033 -275.076448) (xy 70.402145 -275.125347) (xy 70.378802 -275.171159) (xy 70.348581 -275.212755)
			(xy 70.312225 -275.249111) (xy 70.270629 -275.279332) (xy 70.224817 -275.302675) (xy 70.175918 -275.318563)
			(xy 70.125136 -275.326606) (xy 70.07372 -275.326606) (xy 70.022938 -275.318563) (xy 69.974039 -275.302675)
			(xy 69.928227 -275.279332) (xy 69.886631 -275.249111) (xy 69.850275 -275.212755) (xy 69.820054 -275.171159)
			(xy 69.796711 -275.125347) (xy 69.780823 -275.076448) (xy 69.77278 -275.025666) (xy 69.45461 -275.025666)
			(xy 69.446894 -275.073142) (xy 69.43131 -275.119823) (xy 69.408439 -275.1634) (xy 69.378874 -275.202744)
			(xy 69.343381 -275.236836) (xy 69.302878 -275.264792) (xy 69.258416 -275.28589) (xy 69.211145 -275.299582)
			(xy 69.16229 -275.305514) (xy 69.113115 -275.303533) (xy 69.064896 -275.293689) (xy 69.01888 -275.276237)
			(xy 68.976259 -275.25163) (xy 68.938138 -275.220505) (xy 68.905503 -275.183668) (xy 68.8792 -275.142072)
			(xy 68.859909 -275.096796) (xy 68.848132 -275.049012) (xy 68.844172 -274.999958) (xy 68.526655 -274.999958)
			(xy 68.526156 -275.025412) (xy 68.518113 -275.076194) (xy 68.502225 -275.125093) (xy 68.478882 -275.170905)
			(xy 68.448661 -275.212501) (xy 68.412305 -275.248857) (xy 68.370709 -275.279078) (xy 68.324897 -275.302421)
			(xy 68.275998 -275.318309) (xy 68.225216 -275.326352) (xy 68.1738 -275.326352) (xy 68.123018 -275.318309)
			(xy 68.074119 -275.302421) (xy 68.028307 -275.279078) (xy 67.986711 -275.248857) (xy 67.950355 -275.212501)
			(xy 67.920134 -275.170905) (xy 67.896791 -275.125093) (xy 67.880903 -275.076194) (xy 67.87286 -275.025412)
			(xy 67.554477 -275.025412) (xy 67.54672 -275.073142) (xy 67.531136 -275.119823) (xy 67.508265 -275.1634)
			(xy 67.4787 -275.202744) (xy 67.443207 -275.236836) (xy 67.402704 -275.264792) (xy 67.358242 -275.28589)
			(xy 67.310971 -275.299582) (xy 67.262116 -275.305514) (xy 67.212941 -275.303533) (xy 67.164722 -275.293689)
			(xy 67.118706 -275.276237) (xy 67.076085 -275.25163) (xy 67.037964 -275.220505) (xy 67.005329 -275.183668)
			(xy 66.979026 -275.142072) (xy 66.959735 -275.096796) (xy 66.947958 -275.049012) (xy 66.943998 -274.999958)
			(xy 66.62674 -274.999958) (xy 66.626236 -275.025666) (xy 66.618193 -275.076448) (xy 66.602305 -275.125347)
			(xy 66.578962 -275.171159) (xy 66.548741 -275.212755) (xy 66.512385 -275.249111) (xy 66.470789 -275.279332)
			(xy 66.424977 -275.302675) (xy 66.376078 -275.318563) (xy 66.325296 -275.326606) (xy 66.27388 -275.326606)
			(xy 66.223098 -275.318563) (xy 66.174199 -275.302675) (xy 66.128387 -275.279332) (xy 66.086791 -275.249111)
			(xy 66.050435 -275.212755) (xy 66.020214 -275.171159) (xy 65.996871 -275.125347) (xy 65.980983 -275.076448)
			(xy 65.97294 -275.025666) (xy 65.654516 -275.025666) (xy 65.6468 -275.073142) (xy 65.631216 -275.119823)
			(xy 65.608345 -275.1634) (xy 65.57878 -275.202744) (xy 65.543287 -275.236836) (xy 65.502784 -275.264792)
			(xy 65.458322 -275.28589) (xy 65.411051 -275.299582) (xy 65.362196 -275.305514) (xy 65.313021 -275.303533)
			(xy 65.264802 -275.293689) (xy 65.218786 -275.276237) (xy 65.176165 -275.25163) (xy 65.138044 -275.220505)
			(xy 65.105409 -275.183668) (xy 65.079106 -275.142072) (xy 65.059815 -275.096796) (xy 65.048038 -275.049012)
			(xy 65.044078 -274.999958) (xy 64.726815 -274.999958) (xy 64.726316 -275.025412) (xy 64.718273 -275.076194)
			(xy 64.702385 -275.125093) (xy 64.679042 -275.170905) (xy 64.648821 -275.212501) (xy 64.612465 -275.248857)
			(xy 64.570869 -275.279078) (xy 64.525057 -275.302421) (xy 64.476158 -275.318309) (xy 64.425376 -275.326352)
			(xy 64.37396 -275.326352) (xy 64.323178 -275.318309) (xy 64.274279 -275.302421) (xy 64.228467 -275.279078)
			(xy 64.186871 -275.248857) (xy 64.150515 -275.212501) (xy 64.120294 -275.170905) (xy 64.096951 -275.125093)
			(xy 64.081063 -275.076194) (xy 64.07302 -275.025412) (xy 63.754637 -275.025412) (xy 63.74688 -275.073142)
			(xy 63.731296 -275.119823) (xy 63.708425 -275.1634) (xy 63.67886 -275.202744) (xy 63.643367 -275.236836)
			(xy 63.602864 -275.264792) (xy 63.558402 -275.28589) (xy 63.511131 -275.299582) (xy 63.462276 -275.305514)
			(xy 63.413101 -275.303533) (xy 63.364882 -275.293689) (xy 63.318866 -275.276237) (xy 63.276245 -275.25163)
			(xy 63.238124 -275.220505) (xy 63.205489 -275.183668) (xy 63.179186 -275.142072) (xy 63.159895 -275.096796)
			(xy 63.148118 -275.049012) (xy 63.144158 -274.999958) (xy 62.826646 -274.999958) (xy 62.826142 -275.025666)
			(xy 62.818099 -275.076448) (xy 62.802211 -275.125347) (xy 62.778868 -275.171159) (xy 62.748647 -275.212755)
			(xy 62.712291 -275.249111) (xy 62.670695 -275.279332) (xy 62.624883 -275.302675) (xy 62.575984 -275.318563)
			(xy 62.525202 -275.326606) (xy 62.473786 -275.326606) (xy 62.423004 -275.318563) (xy 62.374105 -275.302675)
			(xy 62.328293 -275.279332) (xy 62.286697 -275.249111) (xy 62.250341 -275.212755) (xy 62.22012 -275.171159)
			(xy 62.196777 -275.125347) (xy 62.180889 -275.076448) (xy 62.172846 -275.025666) (xy 61.854422 -275.025666)
			(xy 61.846706 -275.073142) (xy 61.831122 -275.119823) (xy 61.808251 -275.1634) (xy 61.778686 -275.202744)
			(xy 61.743193 -275.236836) (xy 61.70269 -275.264792) (xy 61.658228 -275.28589) (xy 61.610957 -275.299582)
			(xy 61.562102 -275.305514) (xy 61.512927 -275.303533) (xy 61.464708 -275.293689) (xy 61.418692 -275.276237)
			(xy 61.376071 -275.25163) (xy 61.33795 -275.220505) (xy 61.305315 -275.183668) (xy 61.279012 -275.142072)
			(xy 61.259721 -275.096796) (xy 61.247944 -275.049012) (xy 61.243984 -274.999958) (xy 60.926721 -274.999958)
			(xy 60.926222 -275.025412) (xy 60.918179 -275.076194) (xy 60.902291 -275.125093) (xy 60.878948 -275.170905)
			(xy 60.848727 -275.212501) (xy 60.812371 -275.248857) (xy 60.770775 -275.279078) (xy 60.724963 -275.302421)
			(xy 60.676064 -275.318309) (xy 60.625282 -275.326352) (xy 60.573866 -275.326352) (xy 60.523084 -275.318309)
			(xy 60.474185 -275.302421) (xy 60.428373 -275.279078) (xy 60.386777 -275.248857) (xy 60.350421 -275.212501)
			(xy 60.3202 -275.170905) (xy 60.296857 -275.125093) (xy 60.280969 -275.076194) (xy 60.272926 -275.025412)
			(xy 59.954543 -275.025412) (xy 59.946786 -275.073142) (xy 59.931202 -275.119823) (xy 59.908331 -275.1634)
			(xy 59.878766 -275.202744) (xy 59.843273 -275.236836) (xy 59.80277 -275.264792) (xy 59.758308 -275.28589)
			(xy 59.711037 -275.299582) (xy 59.662182 -275.305514) (xy 59.613007 -275.303533) (xy 59.564788 -275.293689)
			(xy 59.518772 -275.276237) (xy 59.476151 -275.25163) (xy 59.43803 -275.220505) (xy 59.405395 -275.183668)
			(xy 59.379092 -275.142072) (xy 59.359801 -275.096796) (xy 59.348024 -275.049012) (xy 59.344064 -274.999958)
			(xy 59.02706 -274.999958) (xy 59.026556 -275.025666) (xy 59.018513 -275.076448) (xy 59.002625 -275.125347)
			(xy 58.979282 -275.171159) (xy 58.949061 -275.212755) (xy 58.912705 -275.249111) (xy 58.871109 -275.279332)
			(xy 58.825297 -275.302675) (xy 58.776398 -275.318563) (xy 58.725616 -275.326606) (xy 58.6742 -275.326606)
			(xy 58.623418 -275.318563) (xy 58.574519 -275.302675) (xy 58.528707 -275.279332) (xy 58.487111 -275.249111)
			(xy 58.450755 -275.212755) (xy 58.420534 -275.171159) (xy 58.397191 -275.125347) (xy 58.381303 -275.076448)
			(xy 58.37326 -275.025666) (xy 58.054582 -275.025666) (xy 58.046866 -275.073142) (xy 58.031282 -275.119823)
			(xy 58.008411 -275.1634) (xy 57.978846 -275.202744) (xy 57.943353 -275.236836) (xy 57.90285 -275.264792)
			(xy 57.858388 -275.28589) (xy 57.811117 -275.299582) (xy 57.762262 -275.305514) (xy 57.713087 -275.303533)
			(xy 57.664868 -275.293689) (xy 57.618852 -275.276237) (xy 57.576231 -275.25163) (xy 57.53811 -275.220505)
			(xy 57.505475 -275.183668) (xy 57.479172 -275.142072) (xy 57.459881 -275.096796) (xy 57.448104 -275.049012)
			(xy 57.444144 -274.999958) (xy 57.12714 -274.999958) (xy 57.126636 -275.025666) (xy 57.118593 -275.076448)
			(xy 57.102705 -275.125347) (xy 57.079362 -275.171159) (xy 57.049141 -275.212755) (xy 57.012785 -275.249111)
			(xy 56.971189 -275.279332) (xy 56.925377 -275.302675) (xy 56.876478 -275.318563) (xy 56.825696 -275.326606)
			(xy 56.77428 -275.326606) (xy 56.723498 -275.318563) (xy 56.674599 -275.302675) (xy 56.628787 -275.279332)
			(xy 56.587191 -275.249111) (xy 56.550835 -275.212755) (xy 56.520614 -275.171159) (xy 56.497271 -275.125347)
			(xy 56.481383 -275.076448) (xy 56.47334 -275.025666) (xy 56.154408 -275.025666) (xy 56.146692 -275.073142)
			(xy 56.131108 -275.119823) (xy 56.108237 -275.1634) (xy 56.078672 -275.202744) (xy 56.043179 -275.236836)
			(xy 56.002676 -275.264792) (xy 55.958214 -275.28589) (xy 55.910943 -275.299582) (xy 55.862088 -275.305514)
			(xy 55.812913 -275.303533) (xy 55.764694 -275.293689) (xy 55.718678 -275.276237) (xy 55.676057 -275.25163)
			(xy 55.637936 -275.220505) (xy 55.605301 -275.183668) (xy 55.578998 -275.142072) (xy 55.559707 -275.096796)
			(xy 55.54793 -275.049012) (xy 55.54397 -274.999958) (xy 55.226966 -274.999958) (xy 55.226462 -275.025666)
			(xy 55.218419 -275.076448) (xy 55.202531 -275.125347) (xy 55.179188 -275.171159) (xy 55.148967 -275.212755)
			(xy 55.112611 -275.249111) (xy 55.071015 -275.279332) (xy 55.025203 -275.302675) (xy 54.976304 -275.318563)
			(xy 54.925522 -275.326606) (xy 54.874106 -275.326606) (xy 54.823324 -275.318563) (xy 54.774425 -275.302675)
			(xy 54.728613 -275.279332) (xy 54.687017 -275.249111) (xy 54.650661 -275.212755) (xy 54.62044 -275.171159)
			(xy 54.597097 -275.125347) (xy 54.581209 -275.076448) (xy 54.573166 -275.025666) (xy 54.254488 -275.025666)
			(xy 54.246772 -275.073142) (xy 54.231188 -275.119823) (xy 54.208317 -275.1634) (xy 54.178752 -275.202744)
			(xy 54.143259 -275.236836) (xy 54.102756 -275.264792) (xy 54.058294 -275.28589) (xy 54.011023 -275.299582)
			(xy 53.962168 -275.305514) (xy 53.912993 -275.303533) (xy 53.864774 -275.293689) (xy 53.818758 -275.276237)
			(xy 53.776137 -275.25163) (xy 53.738016 -275.220505) (xy 53.705381 -275.183668) (xy 53.679078 -275.142072)
			(xy 53.659787 -275.096796) (xy 53.64801 -275.049012) (xy 53.64405 -274.999958) (xy 53.327046 -274.999958)
			(xy 53.326542 -275.025666) (xy 53.318499 -275.076448) (xy 53.302611 -275.125347) (xy 53.279268 -275.171159)
			(xy 53.249047 -275.212755) (xy 53.212691 -275.249111) (xy 53.171095 -275.279332) (xy 53.125283 -275.302675)
			(xy 53.076384 -275.318563) (xy 53.025602 -275.326606) (xy 52.974186 -275.326606) (xy 52.923404 -275.318563)
			(xy 52.874505 -275.302675) (xy 52.828693 -275.279332) (xy 52.787097 -275.249111) (xy 52.750741 -275.212755)
			(xy 52.72052 -275.171159) (xy 52.697177 -275.125347) (xy 52.681289 -275.076448) (xy 52.673246 -275.025666)
			(xy 52.354568 -275.025666) (xy 52.346852 -275.073142) (xy 52.331268 -275.119823) (xy 52.308397 -275.1634)
			(xy 52.278832 -275.202744) (xy 52.243339 -275.236836) (xy 52.202836 -275.264792) (xy 52.158374 -275.28589)
			(xy 52.111103 -275.299582) (xy 52.062248 -275.305514) (xy 52.013073 -275.303533) (xy 51.964854 -275.293689)
			(xy 51.918838 -275.276237) (xy 51.876217 -275.25163) (xy 51.838096 -275.220505) (xy 51.805461 -275.183668)
			(xy 51.779158 -275.142072) (xy 51.759867 -275.096796) (xy 51.74809 -275.049012) (xy 51.74413 -274.999958)
			(xy 51.427126 -274.999958) (xy 51.426622 -275.025666) (xy 51.418579 -275.076448) (xy 51.402691 -275.125347)
			(xy 51.379348 -275.171159) (xy 51.349127 -275.212755) (xy 51.312771 -275.249111) (xy 51.271175 -275.279332)
			(xy 51.225363 -275.302675) (xy 51.176464 -275.318563) (xy 51.125682 -275.326606) (xy 51.074266 -275.326606)
			(xy 51.023484 -275.318563) (xy 50.974585 -275.302675) (xy 50.928773 -275.279332) (xy 50.887177 -275.249111)
			(xy 50.850821 -275.212755) (xy 50.8206 -275.171159) (xy 50.797257 -275.125347) (xy 50.781369 -275.076448)
			(xy 50.773326 -275.025666) (xy 50.454394 -275.025666) (xy 50.446678 -275.073142) (xy 50.431094 -275.119823)
			(xy 50.408223 -275.1634) (xy 50.378658 -275.202744) (xy 50.343165 -275.236836) (xy 50.302662 -275.264792)
			(xy 50.2582 -275.28589) (xy 50.210929 -275.299582) (xy 50.162074 -275.305514) (xy 50.112899 -275.303533)
			(xy 50.06468 -275.293689) (xy 50.018664 -275.276237) (xy 49.976043 -275.25163) (xy 49.937922 -275.220505)
			(xy 49.905287 -275.183668) (xy 49.878984 -275.142072) (xy 49.859693 -275.096796) (xy 49.847916 -275.049012)
			(xy 49.843956 -274.999958) (xy 49.527599 -274.999958) (xy 49.527602 -274.999998) (xy 49.523455 -275.05195)
			(xy 49.51112 -275.102588) (xy 49.490908 -275.150627) (xy 49.463331 -275.194851) (xy 49.429088 -275.234141)
			(xy 49.389045 -275.267502) (xy 49.344218 -275.294088) (xy 49.295741 -275.313226) (xy 49.244842 -275.324431)
			(xy 49.21885 -275.326348) (xy 49.20959 -275.327311) (xy 49.192654 -275.335001) (xy 49.18583 -275.341334)
			(xy 49.16424 -275.362924) (xy 49.157429 -275.370269) (xy 49.149699 -275.388731) (xy 49.149254 -275.398738)
			(xy 49.149254 -275.551138) (xy 49.1498 -275.561121) (xy 49.157529 -275.579538) (xy 49.16424 -275.586952)
			(xy 49.18583 -275.608542) (xy 49.192672 -275.614847) (xy 49.2096 -275.622533) (xy 49.21885 -275.623528)
			(xy 49.244832 -275.625528) (xy 49.295722 -275.636731) (xy 49.344191 -275.655866) (xy 49.38901 -275.682446)
			(xy 49.429045 -275.7158) (xy 49.463282 -275.755083) (xy 49.490854 -275.799299) (xy 49.511063 -275.84733)
			(xy 49.523396 -275.897958) (xy 49.527542 -275.949901) (xy 49.527541 -275.949918) (xy 49.843956 -275.949918)
			(xy 49.847916 -275.900864) (xy 49.859693 -275.85308) (xy 49.878984 -275.807804) (xy 49.905287 -275.766208)
			(xy 49.937922 -275.729371) (xy 49.976043 -275.698246) (xy 50.018664 -275.673639) (xy 50.06468 -275.656187)
			(xy 50.112899 -275.646343) (xy 50.162074 -275.644362) (xy 50.210929 -275.650294) (xy 50.2582 -275.663986)
			(xy 50.302662 -275.685084) (xy 50.343165 -275.71304) (xy 50.378658 -275.747132) (xy 50.408223 -275.786476)
			(xy 50.431094 -275.830053) (xy 50.446678 -275.876734) (xy 50.454573 -275.925311) (xy 50.455068 -275.949918)
			(xy 50.454573 -275.974525) (xy 50.454394 -275.975626) (xy 50.773326 -275.975626) (xy 50.773326 -275.92421)
			(xy 50.781369 -275.873428) (xy 50.797257 -275.824529) (xy 50.8206 -275.778717) (xy 50.850821 -275.737121)
			(xy 50.887177 -275.700765) (xy 50.928773 -275.670544) (xy 50.974585 -275.647201) (xy 51.023484 -275.631313)
			(xy 51.074266 -275.62327) (xy 51.125682 -275.62327) (xy 51.176464 -275.631313) (xy 51.225363 -275.647201)
			(xy 51.271175 -275.670544) (xy 51.312771 -275.700765) (xy 51.349127 -275.737121) (xy 51.379348 -275.778717)
			(xy 51.402691 -275.824529) (xy 51.418579 -275.873428) (xy 51.426622 -275.92421) (xy 51.427126 -275.949918)
			(xy 51.74413 -275.949918) (xy 51.74809 -275.900864) (xy 51.759867 -275.85308) (xy 51.779158 -275.807804)
			(xy 51.805461 -275.766208) (xy 51.838096 -275.729371) (xy 51.876217 -275.698246) (xy 51.918838 -275.673639)
			(xy 51.964854 -275.656187) (xy 52.013073 -275.646343) (xy 52.062248 -275.644362) (xy 52.111103 -275.650294)
			(xy 52.158374 -275.663986) (xy 52.202836 -275.685084) (xy 52.243339 -275.71304) (xy 52.278832 -275.747132)
			(xy 52.308397 -275.786476) (xy 52.331268 -275.830053) (xy 52.346852 -275.876734) (xy 52.354747 -275.925311)
			(xy 52.355242 -275.949918) (xy 52.354747 -275.974525) (xy 52.354568 -275.975626) (xy 52.673246 -275.975626)
			(xy 52.673246 -275.92421) (xy 52.681289 -275.873428) (xy 52.697177 -275.824529) (xy 52.72052 -275.778717)
			(xy 52.750741 -275.737121) (xy 52.787097 -275.700765) (xy 52.828693 -275.670544) (xy 52.874505 -275.647201)
			(xy 52.923404 -275.631313) (xy 52.974186 -275.62327) (xy 53.025602 -275.62327) (xy 53.076384 -275.631313)
			(xy 53.125283 -275.647201) (xy 53.171095 -275.670544) (xy 53.212691 -275.700765) (xy 53.249047 -275.737121)
			(xy 53.279268 -275.778717) (xy 53.302611 -275.824529) (xy 53.318499 -275.873428) (xy 53.326542 -275.92421)
			(xy 53.327046 -275.949918) (xy 53.64405 -275.949918) (xy 53.64801 -275.900864) (xy 53.659787 -275.85308)
			(xy 53.679078 -275.807804) (xy 53.705381 -275.766208) (xy 53.738016 -275.729371) (xy 53.776137 -275.698246)
			(xy 53.818758 -275.673639) (xy 53.864774 -275.656187) (xy 53.912993 -275.646343) (xy 53.962168 -275.644362)
			(xy 54.011023 -275.650294) (xy 54.058294 -275.663986) (xy 54.102756 -275.685084) (xy 54.143259 -275.71304)
			(xy 54.178752 -275.747132) (xy 54.208317 -275.786476) (xy 54.231188 -275.830053) (xy 54.246772 -275.876734)
			(xy 54.254667 -275.925311) (xy 54.255162 -275.949918) (xy 54.254667 -275.974525) (xy 54.254488 -275.975626)
			(xy 54.573166 -275.975626) (xy 54.573166 -275.92421) (xy 54.581209 -275.873428) (xy 54.597097 -275.824529)
			(xy 54.62044 -275.778717) (xy 54.650661 -275.737121) (xy 54.687017 -275.700765) (xy 54.728613 -275.670544)
			(xy 54.774425 -275.647201) (xy 54.823324 -275.631313) (xy 54.874106 -275.62327) (xy 54.925522 -275.62327)
			(xy 54.976304 -275.631313) (xy 55.025203 -275.647201) (xy 55.071015 -275.670544) (xy 55.112611 -275.700765)
			(xy 55.148967 -275.737121) (xy 55.179188 -275.778717) (xy 55.202531 -275.824529) (xy 55.218419 -275.873428)
			(xy 55.226462 -275.92421) (xy 55.226966 -275.949918) (xy 55.54397 -275.949918) (xy 55.54793 -275.900864)
			(xy 55.559707 -275.85308) (xy 55.578998 -275.807804) (xy 55.605301 -275.766208) (xy 55.637936 -275.729371)
			(xy 55.676057 -275.698246) (xy 55.718678 -275.673639) (xy 55.764694 -275.656187) (xy 55.812913 -275.646343)
			(xy 55.862088 -275.644362) (xy 55.910943 -275.650294) (xy 55.958214 -275.663986) (xy 56.002676 -275.685084)
			(xy 56.043179 -275.71304) (xy 56.078672 -275.747132) (xy 56.108237 -275.786476) (xy 56.131108 -275.830053)
			(xy 56.146692 -275.876734) (xy 56.154587 -275.925311) (xy 56.155082 -275.949918) (xy 56.154587 -275.974525)
			(xy 56.154408 -275.975626) (xy 56.47334 -275.975626) (xy 56.47334 -275.92421) (xy 56.481383 -275.873428)
			(xy 56.497271 -275.824529) (xy 56.520614 -275.778717) (xy 56.550835 -275.737121) (xy 56.587191 -275.700765)
			(xy 56.628787 -275.670544) (xy 56.674599 -275.647201) (xy 56.723498 -275.631313) (xy 56.77428 -275.62327)
			(xy 56.825696 -275.62327) (xy 56.876478 -275.631313) (xy 56.925377 -275.647201) (xy 56.971189 -275.670544)
			(xy 57.012785 -275.700765) (xy 57.049141 -275.737121) (xy 57.079362 -275.778717) (xy 57.102705 -275.824529)
			(xy 57.118593 -275.873428) (xy 57.126636 -275.92421) (xy 57.12714 -275.949918) (xy 57.444144 -275.949918)
			(xy 57.448104 -275.900864) (xy 57.459881 -275.85308) (xy 57.479172 -275.807804) (xy 57.505475 -275.766208)
			(xy 57.53811 -275.729371) (xy 57.576231 -275.698246) (xy 57.618852 -275.673639) (xy 57.664868 -275.656187)
			(xy 57.713087 -275.646343) (xy 57.762262 -275.644362) (xy 57.811117 -275.650294) (xy 57.858388 -275.663986)
			(xy 57.90285 -275.685084) (xy 57.943353 -275.71304) (xy 57.978846 -275.747132) (xy 58.008411 -275.786476)
			(xy 58.031282 -275.830053) (xy 58.046866 -275.876734) (xy 58.054761 -275.925311) (xy 58.055256 -275.949918)
			(xy 58.054761 -275.974525) (xy 58.054582 -275.975626) (xy 58.37326 -275.975626) (xy 58.37326 -275.92421)
			(xy 58.381303 -275.873428) (xy 58.397191 -275.824529) (xy 58.420534 -275.778717) (xy 58.450755 -275.737121)
			(xy 58.487111 -275.700765) (xy 58.528707 -275.670544) (xy 58.574519 -275.647201) (xy 58.623418 -275.631313)
			(xy 58.6742 -275.62327) (xy 58.725616 -275.62327) (xy 58.776398 -275.631313) (xy 58.825297 -275.647201)
			(xy 58.871109 -275.670544) (xy 58.912705 -275.700765) (xy 58.949061 -275.737121) (xy 58.979282 -275.778717)
			(xy 59.002625 -275.824529) (xy 59.018513 -275.873428) (xy 59.026556 -275.92421) (xy 59.02706 -275.949918)
			(xy 59.344064 -275.949918) (xy 59.348024 -275.900864) (xy 59.359801 -275.85308) (xy 59.379092 -275.807804)
			(xy 59.405395 -275.766208) (xy 59.43803 -275.729371) (xy 59.476151 -275.698246) (xy 59.518772 -275.673639)
			(xy 59.564788 -275.656187) (xy 59.613007 -275.646343) (xy 59.662182 -275.644362) (xy 59.711037 -275.650294)
			(xy 59.758308 -275.663986) (xy 59.80277 -275.685084) (xy 59.843273 -275.71304) (xy 59.878766 -275.747132)
			(xy 59.908331 -275.786476) (xy 59.931202 -275.830053) (xy 59.946786 -275.876734) (xy 59.954681 -275.925311)
			(xy 59.955176 -275.949918) (xy 59.954681 -275.974525) (xy 59.954543 -275.975372) (xy 60.272926 -275.975372)
			(xy 60.272926 -275.923956) (xy 60.280969 -275.873174) (xy 60.296857 -275.824275) (xy 60.3202 -275.778463)
			(xy 60.350421 -275.736867) (xy 60.386777 -275.700511) (xy 60.428373 -275.67029) (xy 60.474185 -275.646947)
			(xy 60.523084 -275.631059) (xy 60.573866 -275.623016) (xy 60.625282 -275.623016) (xy 60.676064 -275.631059)
			(xy 60.724963 -275.646947) (xy 60.770775 -275.67029) (xy 60.812371 -275.700511) (xy 60.848727 -275.736867)
			(xy 60.878948 -275.778463) (xy 60.902291 -275.824275) (xy 60.918179 -275.873174) (xy 60.926222 -275.923956)
			(xy 60.926726 -275.949664) (xy 60.926721 -275.949918) (xy 61.243984 -275.949918) (xy 61.247944 -275.900864)
			(xy 61.259721 -275.85308) (xy 61.279012 -275.807804) (xy 61.305315 -275.766208) (xy 61.33795 -275.729371)
			(xy 61.376071 -275.698246) (xy 61.418692 -275.673639) (xy 61.464708 -275.656187) (xy 61.512927 -275.646343)
			(xy 61.562102 -275.644362) (xy 61.610957 -275.650294) (xy 61.658228 -275.663986) (xy 61.70269 -275.685084)
			(xy 61.743193 -275.71304) (xy 61.778686 -275.747132) (xy 61.808251 -275.786476) (xy 61.831122 -275.830053)
			(xy 61.846706 -275.876734) (xy 61.854601 -275.925311) (xy 61.855096 -275.949918) (xy 61.854601 -275.974525)
			(xy 61.854422 -275.975626) (xy 62.172846 -275.975626) (xy 62.172846 -275.92421) (xy 62.180889 -275.873428)
			(xy 62.196777 -275.824529) (xy 62.22012 -275.778717) (xy 62.250341 -275.737121) (xy 62.286697 -275.700765)
			(xy 62.328293 -275.670544) (xy 62.374105 -275.647201) (xy 62.423004 -275.631313) (xy 62.473786 -275.62327)
			(xy 62.525202 -275.62327) (xy 62.575984 -275.631313) (xy 62.624883 -275.647201) (xy 62.670695 -275.670544)
			(xy 62.712291 -275.700765) (xy 62.748647 -275.737121) (xy 62.778868 -275.778717) (xy 62.802211 -275.824529)
			(xy 62.818099 -275.873428) (xy 62.826142 -275.92421) (xy 62.826646 -275.949918) (xy 63.144158 -275.949918)
			(xy 63.148118 -275.900864) (xy 63.159895 -275.85308) (xy 63.179186 -275.807804) (xy 63.205489 -275.766208)
			(xy 63.238124 -275.729371) (xy 63.276245 -275.698246) (xy 63.318866 -275.673639) (xy 63.364882 -275.656187)
			(xy 63.413101 -275.646343) (xy 63.462276 -275.644362) (xy 63.511131 -275.650294) (xy 63.558402 -275.663986)
			(xy 63.602864 -275.685084) (xy 63.643367 -275.71304) (xy 63.67886 -275.747132) (xy 63.708425 -275.786476)
			(xy 63.731296 -275.830053) (xy 63.74688 -275.876734) (xy 63.754775 -275.925311) (xy 63.75527 -275.949918)
			(xy 63.754775 -275.974525) (xy 63.754637 -275.975372) (xy 64.07302 -275.975372) (xy 64.07302 -275.923956)
			(xy 64.081063 -275.873174) (xy 64.096951 -275.824275) (xy 64.120294 -275.778463) (xy 64.150515 -275.736867)
			(xy 64.186871 -275.700511) (xy 64.228467 -275.67029) (xy 64.274279 -275.646947) (xy 64.323178 -275.631059)
			(xy 64.37396 -275.623016) (xy 64.425376 -275.623016) (xy 64.476158 -275.631059) (xy 64.525057 -275.646947)
			(xy 64.570869 -275.67029) (xy 64.612465 -275.700511) (xy 64.648821 -275.736867) (xy 64.679042 -275.778463)
			(xy 64.702385 -275.824275) (xy 64.718273 -275.873174) (xy 64.726316 -275.923956) (xy 64.72682 -275.949664)
			(xy 64.726815 -275.949918) (xy 65.044078 -275.949918) (xy 65.048038 -275.900864) (xy 65.059815 -275.85308)
			(xy 65.079106 -275.807804) (xy 65.105409 -275.766208) (xy 65.138044 -275.729371) (xy 65.176165 -275.698246)
			(xy 65.218786 -275.673639) (xy 65.264802 -275.656187) (xy 65.313021 -275.646343) (xy 65.362196 -275.644362)
			(xy 65.411051 -275.650294) (xy 65.458322 -275.663986) (xy 65.502784 -275.685084) (xy 65.543287 -275.71304)
			(xy 65.57878 -275.747132) (xy 65.608345 -275.786476) (xy 65.631216 -275.830053) (xy 65.6468 -275.876734)
			(xy 65.654695 -275.925311) (xy 65.65519 -275.949918) (xy 65.654695 -275.974525) (xy 65.654516 -275.975626)
			(xy 65.97294 -275.975626) (xy 65.97294 -275.92421) (xy 65.980983 -275.873428) (xy 65.996871 -275.824529)
			(xy 66.020214 -275.778717) (xy 66.050435 -275.737121) (xy 66.086791 -275.700765) (xy 66.128387 -275.670544)
			(xy 66.174199 -275.647201) (xy 66.223098 -275.631313) (xy 66.27388 -275.62327) (xy 66.325296 -275.62327)
			(xy 66.376078 -275.631313) (xy 66.424977 -275.647201) (xy 66.470789 -275.670544) (xy 66.512385 -275.700765)
			(xy 66.548741 -275.737121) (xy 66.578962 -275.778717) (xy 66.602305 -275.824529) (xy 66.618193 -275.873428)
			(xy 66.626236 -275.92421) (xy 66.62674 -275.949918) (xy 66.943998 -275.949918) (xy 66.947958 -275.900864)
			(xy 66.959735 -275.85308) (xy 66.979026 -275.807804) (xy 67.005329 -275.766208) (xy 67.037964 -275.729371)
			(xy 67.076085 -275.698246) (xy 67.118706 -275.673639) (xy 67.164722 -275.656187) (xy 67.212941 -275.646343)
			(xy 67.262116 -275.644362) (xy 67.310971 -275.650294) (xy 67.358242 -275.663986) (xy 67.402704 -275.685084)
			(xy 67.443207 -275.71304) (xy 67.4787 -275.747132) (xy 67.508265 -275.786476) (xy 67.531136 -275.830053)
			(xy 67.54672 -275.876734) (xy 67.554615 -275.925311) (xy 67.55511 -275.949918) (xy 67.554615 -275.974525)
			(xy 67.554477 -275.975372) (xy 67.87286 -275.975372) (xy 67.87286 -275.923956) (xy 67.880903 -275.873174)
			(xy 67.896791 -275.824275) (xy 67.920134 -275.778463) (xy 67.950355 -275.736867) (xy 67.986711 -275.700511)
			(xy 68.028307 -275.67029) (xy 68.074119 -275.646947) (xy 68.123018 -275.631059) (xy 68.1738 -275.623016)
			(xy 68.225216 -275.623016) (xy 68.275998 -275.631059) (xy 68.324897 -275.646947) (xy 68.370709 -275.67029)
			(xy 68.412305 -275.700511) (xy 68.448661 -275.736867) (xy 68.478882 -275.778463) (xy 68.502225 -275.824275)
			(xy 68.518113 -275.873174) (xy 68.526156 -275.923956) (xy 68.52666 -275.949664) (xy 68.526655 -275.949918)
			(xy 68.844172 -275.949918) (xy 68.848132 -275.900864) (xy 68.859909 -275.85308) (xy 68.8792 -275.807804)
			(xy 68.905503 -275.766208) (xy 68.938138 -275.729371) (xy 68.976259 -275.698246) (xy 69.01888 -275.673639)
			(xy 69.064896 -275.656187) (xy 69.113115 -275.646343) (xy 69.16229 -275.644362) (xy 69.211145 -275.650294)
			(xy 69.258416 -275.663986) (xy 69.302878 -275.685084) (xy 69.343381 -275.71304) (xy 69.378874 -275.747132)
			(xy 69.408439 -275.786476) (xy 69.43131 -275.830053) (xy 69.446894 -275.876734) (xy 69.454789 -275.925311)
			(xy 69.455284 -275.949918) (xy 69.454789 -275.974525) (xy 69.45461 -275.975626) (xy 69.77278 -275.975626)
			(xy 69.77278 -275.92421) (xy 69.780823 -275.873428) (xy 69.796711 -275.824529) (xy 69.820054 -275.778717)
			(xy 69.850275 -275.737121) (xy 69.886631 -275.700765) (xy 69.928227 -275.670544) (xy 69.974039 -275.647201)
			(xy 70.022938 -275.631313) (xy 70.07372 -275.62327) (xy 70.125136 -275.62327) (xy 70.175918 -275.631313)
			(xy 70.224817 -275.647201) (xy 70.270629 -275.670544) (xy 70.312225 -275.700765) (xy 70.348581 -275.737121)
			(xy 70.378802 -275.778717) (xy 70.402145 -275.824529) (xy 70.418033 -275.873428) (xy 70.426076 -275.92421)
			(xy 70.42658 -275.949918) (xy 70.744092 -275.949918) (xy 70.748052 -275.900864) (xy 70.759829 -275.85308)
			(xy 70.77912 -275.807804) (xy 70.805423 -275.766208) (xy 70.838058 -275.729371) (xy 70.876179 -275.698246)
			(xy 70.9188 -275.673639) (xy 70.964816 -275.656187) (xy 71.013035 -275.646343) (xy 71.06221 -275.644362)
			(xy 71.111065 -275.650294) (xy 71.158336 -275.663986) (xy 71.202798 -275.685084) (xy 71.243301 -275.71304)
			(xy 71.278794 -275.747132) (xy 71.308359 -275.786476) (xy 71.33123 -275.830053) (xy 71.346814 -275.876734)
			(xy 71.354709 -275.925311) (xy 71.355204 -275.949918) (xy 71.354709 -275.974525) (xy 71.354571 -275.975372)
			(xy 71.672954 -275.975372) (xy 71.672954 -275.923956) (xy 71.680997 -275.873174) (xy 71.696885 -275.824275)
			(xy 71.720228 -275.778463) (xy 71.750449 -275.736867) (xy 71.786805 -275.700511) (xy 71.828401 -275.67029)
			(xy 71.874213 -275.646947) (xy 71.923112 -275.631059) (xy 71.973894 -275.623016) (xy 72.02531 -275.623016)
			(xy 72.076092 -275.631059) (xy 72.124991 -275.646947) (xy 72.170803 -275.67029) (xy 72.212399 -275.700511)
			(xy 72.248755 -275.736867) (xy 72.278976 -275.778463) (xy 72.302319 -275.824275) (xy 72.318207 -275.873174)
			(xy 72.32625 -275.923956) (xy 72.326754 -275.949664) (xy 72.326749 -275.949918) (xy 72.644012 -275.949918)
			(xy 72.647972 -275.900864) (xy 72.659749 -275.85308) (xy 72.67904 -275.807804) (xy 72.705343 -275.766208)
			(xy 72.737978 -275.729371) (xy 72.776099 -275.698246) (xy 72.81872 -275.673639) (xy 72.864736 -275.656187)
			(xy 72.912955 -275.646343) (xy 72.96213 -275.644362) (xy 73.010985 -275.650294) (xy 73.058256 -275.663986)
			(xy 73.102718 -275.685084) (xy 73.143221 -275.71304) (xy 73.178714 -275.747132) (xy 73.208279 -275.786476)
			(xy 73.23115 -275.830053) (xy 73.246734 -275.876734) (xy 73.254629 -275.925311) (xy 73.255124 -275.949918)
			(xy 73.254629 -275.974525) (xy 73.25445 -275.975626) (xy 73.572874 -275.975626) (xy 73.572874 -275.92421)
			(xy 73.580917 -275.873428) (xy 73.596805 -275.824529) (xy 73.620148 -275.778717) (xy 73.650369 -275.737121)
			(xy 73.686725 -275.700765) (xy 73.728321 -275.670544) (xy 73.774133 -275.647201) (xy 73.823032 -275.631313)
			(xy 73.873814 -275.62327) (xy 73.92523 -275.62327) (xy 73.976012 -275.631313) (xy 74.024911 -275.647201)
			(xy 74.070723 -275.670544) (xy 74.112319 -275.700765) (xy 74.148675 -275.737121) (xy 74.178896 -275.778717)
			(xy 74.202239 -275.824529) (xy 74.218127 -275.873428) (xy 74.22617 -275.92421) (xy 74.226674 -275.949918)
			(xy 74.544186 -275.949918) (xy 74.548146 -275.900864) (xy 74.559923 -275.85308) (xy 74.579214 -275.807804)
			(xy 74.605517 -275.766208) (xy 74.638152 -275.729371) (xy 74.676273 -275.698246) (xy 74.718894 -275.673639)
			(xy 74.76491 -275.656187) (xy 74.813129 -275.646343) (xy 74.862304 -275.644362) (xy 74.911159 -275.650294)
			(xy 74.95843 -275.663986) (xy 75.002892 -275.685084) (xy 75.043395 -275.71304) (xy 75.078888 -275.747132)
			(xy 75.108453 -275.786476) (xy 75.131324 -275.830053) (xy 75.146908 -275.876734) (xy 75.154803 -275.925311)
			(xy 75.155298 -275.949918) (xy 75.154803 -275.974525) (xy 75.154665 -275.975372) (xy 75.473048 -275.975372)
			(xy 75.473048 -275.923956) (xy 75.481091 -275.873174) (xy 75.496979 -275.824275) (xy 75.520322 -275.778463)
			(xy 75.550543 -275.736867) (xy 75.586899 -275.700511) (xy 75.628495 -275.67029) (xy 75.674307 -275.646947)
			(xy 75.723206 -275.631059) (xy 75.773988 -275.623016) (xy 75.825404 -275.623016) (xy 75.876186 -275.631059)
			(xy 75.925085 -275.646947) (xy 75.970897 -275.67029) (xy 76.012493 -275.700511) (xy 76.048849 -275.736867)
			(xy 76.07907 -275.778463) (xy 76.102413 -275.824275) (xy 76.118301 -275.873174) (xy 76.126344 -275.923956)
			(xy 76.126848 -275.949664) (xy 76.126843 -275.949918) (xy 76.444106 -275.949918) (xy 76.448066 -275.900864)
			(xy 76.459843 -275.85308) (xy 76.479134 -275.807804) (xy 76.505437 -275.766208) (xy 76.538072 -275.729371)
			(xy 76.576193 -275.698246) (xy 76.618814 -275.673639) (xy 76.66483 -275.656187) (xy 76.713049 -275.646343)
			(xy 76.762224 -275.644362) (xy 76.811079 -275.650294) (xy 76.85835 -275.663986) (xy 76.902812 -275.685084)
			(xy 76.943315 -275.71304) (xy 76.978808 -275.747132) (xy 77.008373 -275.786476) (xy 77.031244 -275.830053)
			(xy 77.046828 -275.876734) (xy 77.054723 -275.925311) (xy 77.055218 -275.949918) (xy 77.054723 -275.974525)
			(xy 77.054544 -275.975626) (xy 77.372968 -275.975626) (xy 77.372968 -275.92421) (xy 77.381011 -275.873428)
			(xy 77.396899 -275.824529) (xy 77.420242 -275.778717) (xy 77.450463 -275.737121) (xy 77.486819 -275.700765)
			(xy 77.528415 -275.670544) (xy 77.574227 -275.647201) (xy 77.623126 -275.631313) (xy 77.673908 -275.62327)
			(xy 77.725324 -275.62327) (xy 77.776106 -275.631313) (xy 77.825005 -275.647201) (xy 77.870817 -275.670544)
			(xy 77.912413 -275.700765) (xy 77.948769 -275.737121) (xy 77.97899 -275.778717) (xy 78.002333 -275.824529)
			(xy 78.018221 -275.873428) (xy 78.026264 -275.92421) (xy 78.026768 -275.949918) (xy 78.344026 -275.949918)
			(xy 78.347986 -275.900864) (xy 78.359763 -275.85308) (xy 78.379054 -275.807804) (xy 78.405357 -275.766208)
			(xy 78.437992 -275.729371) (xy 78.476113 -275.698246) (xy 78.518734 -275.673639) (xy 78.56475 -275.656187)
			(xy 78.612969 -275.646343) (xy 78.662144 -275.644362) (xy 78.710999 -275.650294) (xy 78.75827 -275.663986)
			(xy 78.802732 -275.685084) (xy 78.843235 -275.71304) (xy 78.878728 -275.747132) (xy 78.908293 -275.786476)
			(xy 78.931164 -275.830053) (xy 78.946748 -275.876734) (xy 78.954643 -275.925311) (xy 78.955138 -275.949918)
			(xy 78.954643 -275.974525) (xy 78.954464 -275.975626) (xy 79.272888 -275.975626) (xy 79.272888 -275.92421)
			(xy 79.280931 -275.873428) (xy 79.296819 -275.824529) (xy 79.320162 -275.778717) (xy 79.350383 -275.737121)
			(xy 79.386739 -275.700765) (xy 79.428335 -275.670544) (xy 79.474147 -275.647201) (xy 79.523046 -275.631313)
			(xy 79.573828 -275.62327) (xy 79.625244 -275.62327) (xy 79.676026 -275.631313) (xy 79.724925 -275.647201)
			(xy 79.770737 -275.670544) (xy 79.812333 -275.700765) (xy 79.848689 -275.737121) (xy 79.87891 -275.778717)
			(xy 79.902253 -275.824529) (xy 79.918141 -275.873428) (xy 79.926184 -275.92421) (xy 79.926688 -275.949918)
			(xy 80.2442 -275.949918) (xy 80.24816 -275.900864) (xy 80.259937 -275.85308) (xy 80.279228 -275.807804)
			(xy 80.305531 -275.766208) (xy 80.338166 -275.729371) (xy 80.376287 -275.698246) (xy 80.418908 -275.673639)
			(xy 80.464924 -275.656187) (xy 80.513143 -275.646343) (xy 80.562318 -275.644362) (xy 80.611173 -275.650294)
			(xy 80.658444 -275.663986) (xy 80.702906 -275.685084) (xy 80.743409 -275.71304) (xy 80.778902 -275.747132)
			(xy 80.808467 -275.786476) (xy 80.831338 -275.830053) (xy 80.846922 -275.876734) (xy 80.854817 -275.925311)
			(xy 80.855312 -275.949918) (xy 81.19416 -275.949918) (xy 81.19812 -275.900864) (xy 81.209897 -275.85308)
			(xy 81.229188 -275.807804) (xy 81.255491 -275.766208) (xy 81.288126 -275.729371) (xy 81.326247 -275.698246)
			(xy 81.368868 -275.673639) (xy 81.414884 -275.656187) (xy 81.463103 -275.646343) (xy 81.512278 -275.644362)
			(xy 81.561133 -275.650294) (xy 81.608404 -275.663986) (xy 81.652866 -275.685084) (xy 81.693369 -275.71304)
			(xy 81.728862 -275.747132) (xy 81.758427 -275.786476) (xy 81.781298 -275.830053) (xy 81.796882 -275.876734)
			(xy 81.804777 -275.925311) (xy 81.805272 -275.949918) (xy 82.14412 -275.949918) (xy 82.14808 -275.900864)
			(xy 82.159857 -275.85308) (xy 82.179148 -275.807804) (xy 82.205451 -275.766208) (xy 82.238086 -275.729371)
			(xy 82.276207 -275.698246) (xy 82.318828 -275.673639) (xy 82.364844 -275.656187) (xy 82.413063 -275.646343)
			(xy 82.462238 -275.644362) (xy 82.511093 -275.650294) (xy 82.558364 -275.663986) (xy 82.602826 -275.685084)
			(xy 82.643329 -275.71304) (xy 82.678822 -275.747132) (xy 82.708387 -275.786476) (xy 82.731258 -275.830053)
			(xy 82.746842 -275.876734) (xy 82.754737 -275.925311) (xy 82.755232 -275.949918) (xy 82.754737 -275.974525)
			(xy 82.746842 -276.023102) (xy 82.731258 -276.069783) (xy 82.708387 -276.11336) (xy 82.678822 -276.152704)
			(xy 82.643329 -276.186796) (xy 82.602826 -276.214752) (xy 82.558364 -276.23585) (xy 82.511093 -276.249542)
			(xy 82.462238 -276.255474) (xy 82.413063 -276.253493) (xy 82.364844 -276.243649) (xy 82.318828 -276.226197)
			(xy 82.276207 -276.20159) (xy 82.238086 -276.170465) (xy 82.205451 -276.133628) (xy 82.179148 -276.092032)
			(xy 82.159857 -276.046756) (xy 82.14808 -275.998972) (xy 82.14412 -275.949918) (xy 81.805272 -275.949918)
			(xy 81.804777 -275.974525) (xy 81.796882 -276.023102) (xy 81.781298 -276.069783) (xy 81.758427 -276.11336)
			(xy 81.728862 -276.152704) (xy 81.693369 -276.186796) (xy 81.652866 -276.214752) (xy 81.608404 -276.23585)
			(xy 81.561133 -276.249542) (xy 81.512278 -276.255474) (xy 81.463103 -276.253493) (xy 81.414884 -276.243649)
			(xy 81.368868 -276.226197) (xy 81.326247 -276.20159) (xy 81.288126 -276.170465) (xy 81.255491 -276.133628)
			(xy 81.229188 -276.092032) (xy 81.209897 -276.046756) (xy 81.19812 -275.998972) (xy 81.19416 -275.949918)
			(xy 80.855312 -275.949918) (xy 80.854817 -275.974525) (xy 80.846922 -276.023102) (xy 80.831338 -276.069783)
			(xy 80.808467 -276.11336) (xy 80.778902 -276.152704) (xy 80.743409 -276.186796) (xy 80.702906 -276.214752)
			(xy 80.658444 -276.23585) (xy 80.611173 -276.249542) (xy 80.562318 -276.255474) (xy 80.513143 -276.253493)
			(xy 80.464924 -276.243649) (xy 80.418908 -276.226197) (xy 80.376287 -276.20159) (xy 80.338166 -276.170465)
			(xy 80.305531 -276.133628) (xy 80.279228 -276.092032) (xy 80.259937 -276.046756) (xy 80.24816 -275.998972)
			(xy 80.2442 -275.949918) (xy 79.926688 -275.949918) (xy 79.926184 -275.975626) (xy 79.918141 -276.026408)
			(xy 79.902253 -276.075307) (xy 79.87891 -276.121119) (xy 79.848689 -276.162715) (xy 79.812333 -276.199071)
			(xy 79.770737 -276.229292) (xy 79.724925 -276.252635) (xy 79.676026 -276.268523) (xy 79.625244 -276.276566)
			(xy 79.573828 -276.276566) (xy 79.523046 -276.268523) (xy 79.474147 -276.252635) (xy 79.428335 -276.229292)
			(xy 79.386739 -276.199071) (xy 79.350383 -276.162715) (xy 79.320162 -276.121119) (xy 79.296819 -276.075307)
			(xy 79.280931 -276.026408) (xy 79.272888 -275.975626) (xy 78.954464 -275.975626) (xy 78.946748 -276.023102)
			(xy 78.931164 -276.069783) (xy 78.908293 -276.11336) (xy 78.878728 -276.152704) (xy 78.843235 -276.186796)
			(xy 78.802732 -276.214752) (xy 78.75827 -276.23585) (xy 78.710999 -276.249542) (xy 78.662144 -276.255474)
			(xy 78.612969 -276.253493) (xy 78.56475 -276.243649) (xy 78.518734 -276.226197) (xy 78.476113 -276.20159)
			(xy 78.437992 -276.170465) (xy 78.405357 -276.133628) (xy 78.379054 -276.092032) (xy 78.359763 -276.046756)
			(xy 78.347986 -275.998972) (xy 78.344026 -275.949918) (xy 78.026768 -275.949918) (xy 78.026264 -275.975626)
			(xy 78.018221 -276.026408) (xy 78.002333 -276.075307) (xy 77.97899 -276.121119) (xy 77.948769 -276.162715)
			(xy 77.912413 -276.199071) (xy 77.870817 -276.229292) (xy 77.825005 -276.252635) (xy 77.776106 -276.268523)
			(xy 77.725324 -276.276566) (xy 77.673908 -276.276566) (xy 77.623126 -276.268523) (xy 77.574227 -276.252635)
			(xy 77.528415 -276.229292) (xy 77.486819 -276.199071) (xy 77.450463 -276.162715) (xy 77.420242 -276.121119)
			(xy 77.396899 -276.075307) (xy 77.381011 -276.026408) (xy 77.372968 -275.975626) (xy 77.054544 -275.975626)
			(xy 77.046828 -276.023102) (xy 77.031244 -276.069783) (xy 77.008373 -276.11336) (xy 76.978808 -276.152704)
			(xy 76.943315 -276.186796) (xy 76.902812 -276.214752) (xy 76.85835 -276.23585) (xy 76.811079 -276.249542)
			(xy 76.762224 -276.255474) (xy 76.713049 -276.253493) (xy 76.66483 -276.243649) (xy 76.618814 -276.226197)
			(xy 76.576193 -276.20159) (xy 76.538072 -276.170465) (xy 76.505437 -276.133628) (xy 76.479134 -276.092032)
			(xy 76.459843 -276.046756) (xy 76.448066 -275.998972) (xy 76.444106 -275.949918) (xy 76.126843 -275.949918)
			(xy 76.126344 -275.975372) (xy 76.118301 -276.026154) (xy 76.102413 -276.075053) (xy 76.07907 -276.120865)
			(xy 76.048849 -276.162461) (xy 76.012493 -276.198817) (xy 75.970897 -276.229038) (xy 75.925085 -276.252381)
			(xy 75.876186 -276.268269) (xy 75.825404 -276.276312) (xy 75.773988 -276.276312) (xy 75.723206 -276.268269)
			(xy 75.674307 -276.252381) (xy 75.628495 -276.229038) (xy 75.586899 -276.198817) (xy 75.550543 -276.162461)
			(xy 75.520322 -276.120865) (xy 75.496979 -276.075053) (xy 75.481091 -276.026154) (xy 75.473048 -275.975372)
			(xy 75.154665 -275.975372) (xy 75.146908 -276.023102) (xy 75.131324 -276.069783) (xy 75.108453 -276.11336)
			(xy 75.078888 -276.152704) (xy 75.043395 -276.186796) (xy 75.002892 -276.214752) (xy 74.95843 -276.23585)
			(xy 74.911159 -276.249542) (xy 74.862304 -276.255474) (xy 74.813129 -276.253493) (xy 74.76491 -276.243649)
			(xy 74.718894 -276.226197) (xy 74.676273 -276.20159) (xy 74.638152 -276.170465) (xy 74.605517 -276.133628)
			(xy 74.579214 -276.092032) (xy 74.559923 -276.046756) (xy 74.548146 -275.998972) (xy 74.544186 -275.949918)
			(xy 74.226674 -275.949918) (xy 74.22617 -275.975626) (xy 74.218127 -276.026408) (xy 74.202239 -276.075307)
			(xy 74.178896 -276.121119) (xy 74.148675 -276.162715) (xy 74.112319 -276.199071) (xy 74.070723 -276.229292)
			(xy 74.024911 -276.252635) (xy 73.976012 -276.268523) (xy 73.92523 -276.276566) (xy 73.873814 -276.276566)
			(xy 73.823032 -276.268523) (xy 73.774133 -276.252635) (xy 73.728321 -276.229292) (xy 73.686725 -276.199071)
			(xy 73.650369 -276.162715) (xy 73.620148 -276.121119) (xy 73.596805 -276.075307) (xy 73.580917 -276.026408)
			(xy 73.572874 -275.975626) (xy 73.25445 -275.975626) (xy 73.246734 -276.023102) (xy 73.23115 -276.069783)
			(xy 73.208279 -276.11336) (xy 73.178714 -276.152704) (xy 73.143221 -276.186796) (xy 73.102718 -276.214752)
			(xy 73.058256 -276.23585) (xy 73.010985 -276.249542) (xy 72.96213 -276.255474) (xy 72.912955 -276.253493)
			(xy 72.864736 -276.243649) (xy 72.81872 -276.226197) (xy 72.776099 -276.20159) (xy 72.737978 -276.170465)
			(xy 72.705343 -276.133628) (xy 72.67904 -276.092032) (xy 72.659749 -276.046756) (xy 72.647972 -275.998972)
			(xy 72.644012 -275.949918) (xy 72.326749 -275.949918) (xy 72.32625 -275.975372) (xy 72.318207 -276.026154)
			(xy 72.302319 -276.075053) (xy 72.278976 -276.120865) (xy 72.248755 -276.162461) (xy 72.212399 -276.198817)
			(xy 72.170803 -276.229038) (xy 72.124991 -276.252381) (xy 72.076092 -276.268269) (xy 72.02531 -276.276312)
			(xy 71.973894 -276.276312) (xy 71.923112 -276.268269) (xy 71.874213 -276.252381) (xy 71.828401 -276.229038)
			(xy 71.786805 -276.198817) (xy 71.750449 -276.162461) (xy 71.720228 -276.120865) (xy 71.696885 -276.075053)
			(xy 71.680997 -276.026154) (xy 71.672954 -275.975372) (xy 71.354571 -275.975372) (xy 71.346814 -276.023102)
			(xy 71.33123 -276.069783) (xy 71.308359 -276.11336) (xy 71.278794 -276.152704) (xy 71.243301 -276.186796)
			(xy 71.202798 -276.214752) (xy 71.158336 -276.23585) (xy 71.111065 -276.249542) (xy 71.06221 -276.255474)
			(xy 71.013035 -276.253493) (xy 70.964816 -276.243649) (xy 70.9188 -276.226197) (xy 70.876179 -276.20159)
			(xy 70.838058 -276.170465) (xy 70.805423 -276.133628) (xy 70.77912 -276.092032) (xy 70.759829 -276.046756)
			(xy 70.748052 -275.998972) (xy 70.744092 -275.949918) (xy 70.42658 -275.949918) (xy 70.426076 -275.975626)
			(xy 70.418033 -276.026408) (xy 70.402145 -276.075307) (xy 70.378802 -276.121119) (xy 70.348581 -276.162715)
			(xy 70.312225 -276.199071) (xy 70.270629 -276.229292) (xy 70.224817 -276.252635) (xy 70.175918 -276.268523)
			(xy 70.125136 -276.276566) (xy 70.07372 -276.276566) (xy 70.022938 -276.268523) (xy 69.974039 -276.252635)
			(xy 69.928227 -276.229292) (xy 69.886631 -276.199071) (xy 69.850275 -276.162715) (xy 69.820054 -276.121119)
			(xy 69.796711 -276.075307) (xy 69.780823 -276.026408) (xy 69.77278 -275.975626) (xy 69.45461 -275.975626)
			(xy 69.446894 -276.023102) (xy 69.43131 -276.069783) (xy 69.408439 -276.11336) (xy 69.378874 -276.152704)
			(xy 69.343381 -276.186796) (xy 69.302878 -276.214752) (xy 69.258416 -276.23585) (xy 69.211145 -276.249542)
			(xy 69.16229 -276.255474) (xy 69.113115 -276.253493) (xy 69.064896 -276.243649) (xy 69.01888 -276.226197)
			(xy 68.976259 -276.20159) (xy 68.938138 -276.170465) (xy 68.905503 -276.133628) (xy 68.8792 -276.092032)
			(xy 68.859909 -276.046756) (xy 68.848132 -275.998972) (xy 68.844172 -275.949918) (xy 68.526655 -275.949918)
			(xy 68.526156 -275.975372) (xy 68.518113 -276.026154) (xy 68.502225 -276.075053) (xy 68.478882 -276.120865)
			(xy 68.448661 -276.162461) (xy 68.412305 -276.198817) (xy 68.370709 -276.229038) (xy 68.324897 -276.252381)
			(xy 68.275998 -276.268269) (xy 68.225216 -276.276312) (xy 68.1738 -276.276312) (xy 68.123018 -276.268269)
			(xy 68.074119 -276.252381) (xy 68.028307 -276.229038) (xy 67.986711 -276.198817) (xy 67.950355 -276.162461)
			(xy 67.920134 -276.120865) (xy 67.896791 -276.075053) (xy 67.880903 -276.026154) (xy 67.87286 -275.975372)
			(xy 67.554477 -275.975372) (xy 67.54672 -276.023102) (xy 67.531136 -276.069783) (xy 67.508265 -276.11336)
			(xy 67.4787 -276.152704) (xy 67.443207 -276.186796) (xy 67.402704 -276.214752) (xy 67.358242 -276.23585)
			(xy 67.310971 -276.249542) (xy 67.262116 -276.255474) (xy 67.212941 -276.253493) (xy 67.164722 -276.243649)
			(xy 67.118706 -276.226197) (xy 67.076085 -276.20159) (xy 67.037964 -276.170465) (xy 67.005329 -276.133628)
			(xy 66.979026 -276.092032) (xy 66.959735 -276.046756) (xy 66.947958 -275.998972) (xy 66.943998 -275.949918)
			(xy 66.62674 -275.949918) (xy 66.626236 -275.975626) (xy 66.618193 -276.026408) (xy 66.602305 -276.075307)
			(xy 66.578962 -276.121119) (xy 66.548741 -276.162715) (xy 66.512385 -276.199071) (xy 66.470789 -276.229292)
			(xy 66.424977 -276.252635) (xy 66.376078 -276.268523) (xy 66.325296 -276.276566) (xy 66.27388 -276.276566)
			(xy 66.223098 -276.268523) (xy 66.174199 -276.252635) (xy 66.128387 -276.229292) (xy 66.086791 -276.199071)
			(xy 66.050435 -276.162715) (xy 66.020214 -276.121119) (xy 65.996871 -276.075307) (xy 65.980983 -276.026408)
			(xy 65.97294 -275.975626) (xy 65.654516 -275.975626) (xy 65.6468 -276.023102) (xy 65.631216 -276.069783)
			(xy 65.608345 -276.11336) (xy 65.57878 -276.152704) (xy 65.543287 -276.186796) (xy 65.502784 -276.214752)
			(xy 65.458322 -276.23585) (xy 65.411051 -276.249542) (xy 65.362196 -276.255474) (xy 65.313021 -276.253493)
			(xy 65.264802 -276.243649) (xy 65.218786 -276.226197) (xy 65.176165 -276.20159) (xy 65.138044 -276.170465)
			(xy 65.105409 -276.133628) (xy 65.079106 -276.092032) (xy 65.059815 -276.046756) (xy 65.048038 -275.998972)
			(xy 65.044078 -275.949918) (xy 64.726815 -275.949918) (xy 64.726316 -275.975372) (xy 64.718273 -276.026154)
			(xy 64.702385 -276.075053) (xy 64.679042 -276.120865) (xy 64.648821 -276.162461) (xy 64.612465 -276.198817)
			(xy 64.570869 -276.229038) (xy 64.525057 -276.252381) (xy 64.476158 -276.268269) (xy 64.425376 -276.276312)
			(xy 64.37396 -276.276312) (xy 64.323178 -276.268269) (xy 64.274279 -276.252381) (xy 64.228467 -276.229038)
			(xy 64.186871 -276.198817) (xy 64.150515 -276.162461) (xy 64.120294 -276.120865) (xy 64.096951 -276.075053)
			(xy 64.081063 -276.026154) (xy 64.07302 -275.975372) (xy 63.754637 -275.975372) (xy 63.74688 -276.023102)
			(xy 63.731296 -276.069783) (xy 63.708425 -276.11336) (xy 63.67886 -276.152704) (xy 63.643367 -276.186796)
			(xy 63.602864 -276.214752) (xy 63.558402 -276.23585) (xy 63.511131 -276.249542) (xy 63.462276 -276.255474)
			(xy 63.413101 -276.253493) (xy 63.364882 -276.243649) (xy 63.318866 -276.226197) (xy 63.276245 -276.20159)
			(xy 63.238124 -276.170465) (xy 63.205489 -276.133628) (xy 63.179186 -276.092032) (xy 63.159895 -276.046756)
			(xy 63.148118 -275.998972) (xy 63.144158 -275.949918) (xy 62.826646 -275.949918) (xy 62.826142 -275.975626)
			(xy 62.818099 -276.026408) (xy 62.802211 -276.075307) (xy 62.778868 -276.121119) (xy 62.748647 -276.162715)
			(xy 62.712291 -276.199071) (xy 62.670695 -276.229292) (xy 62.624883 -276.252635) (xy 62.575984 -276.268523)
			(xy 62.525202 -276.276566) (xy 62.473786 -276.276566) (xy 62.423004 -276.268523) (xy 62.374105 -276.252635)
			(xy 62.328293 -276.229292) (xy 62.286697 -276.199071) (xy 62.250341 -276.162715) (xy 62.22012 -276.121119)
			(xy 62.196777 -276.075307) (xy 62.180889 -276.026408) (xy 62.172846 -275.975626) (xy 61.854422 -275.975626)
			(xy 61.846706 -276.023102) (xy 61.831122 -276.069783) (xy 61.808251 -276.11336) (xy 61.778686 -276.152704)
			(xy 61.743193 -276.186796) (xy 61.70269 -276.214752) (xy 61.658228 -276.23585) (xy 61.610957 -276.249542)
			(xy 61.562102 -276.255474) (xy 61.512927 -276.253493) (xy 61.464708 -276.243649) (xy 61.418692 -276.226197)
			(xy 61.376071 -276.20159) (xy 61.33795 -276.170465) (xy 61.305315 -276.133628) (xy 61.279012 -276.092032)
			(xy 61.259721 -276.046756) (xy 61.247944 -275.998972) (xy 61.243984 -275.949918) (xy 60.926721 -275.949918)
			(xy 60.926222 -275.975372) (xy 60.918179 -276.026154) (xy 60.902291 -276.075053) (xy 60.878948 -276.120865)
			(xy 60.848727 -276.162461) (xy 60.812371 -276.198817) (xy 60.770775 -276.229038) (xy 60.724963 -276.252381)
			(xy 60.676064 -276.268269) (xy 60.625282 -276.276312) (xy 60.573866 -276.276312) (xy 60.523084 -276.268269)
			(xy 60.474185 -276.252381) (xy 60.428373 -276.229038) (xy 60.386777 -276.198817) (xy 60.350421 -276.162461)
			(xy 60.3202 -276.120865) (xy 60.296857 -276.075053) (xy 60.280969 -276.026154) (xy 60.272926 -275.975372)
			(xy 59.954543 -275.975372) (xy 59.946786 -276.023102) (xy 59.931202 -276.069783) (xy 59.908331 -276.11336)
			(xy 59.878766 -276.152704) (xy 59.843273 -276.186796) (xy 59.80277 -276.214752) (xy 59.758308 -276.23585)
			(xy 59.711037 -276.249542) (xy 59.662182 -276.255474) (xy 59.613007 -276.253493) (xy 59.564788 -276.243649)
			(xy 59.518772 -276.226197) (xy 59.476151 -276.20159) (xy 59.43803 -276.170465) (xy 59.405395 -276.133628)
			(xy 59.379092 -276.092032) (xy 59.359801 -276.046756) (xy 59.348024 -275.998972) (xy 59.344064 -275.949918)
			(xy 59.02706 -275.949918) (xy 59.026556 -275.975626) (xy 59.018513 -276.026408) (xy 59.002625 -276.075307)
			(xy 58.979282 -276.121119) (xy 58.949061 -276.162715) (xy 58.912705 -276.199071) (xy 58.871109 -276.229292)
			(xy 58.825297 -276.252635) (xy 58.776398 -276.268523) (xy 58.725616 -276.276566) (xy 58.6742 -276.276566)
			(xy 58.623418 -276.268523) (xy 58.574519 -276.252635) (xy 58.528707 -276.229292) (xy 58.487111 -276.199071)
			(xy 58.450755 -276.162715) (xy 58.420534 -276.121119) (xy 58.397191 -276.075307) (xy 58.381303 -276.026408)
			(xy 58.37326 -275.975626) (xy 58.054582 -275.975626) (xy 58.046866 -276.023102) (xy 58.031282 -276.069783)
			(xy 58.008411 -276.11336) (xy 57.978846 -276.152704) (xy 57.943353 -276.186796) (xy 57.90285 -276.214752)
			(xy 57.858388 -276.23585) (xy 57.811117 -276.249542) (xy 57.762262 -276.255474) (xy 57.713087 -276.253493)
			(xy 57.664868 -276.243649) (xy 57.618852 -276.226197) (xy 57.576231 -276.20159) (xy 57.53811 -276.170465)
			(xy 57.505475 -276.133628) (xy 57.479172 -276.092032) (xy 57.459881 -276.046756) (xy 57.448104 -275.998972)
			(xy 57.444144 -275.949918) (xy 57.12714 -275.949918) (xy 57.126636 -275.975626) (xy 57.118593 -276.026408)
			(xy 57.102705 -276.075307) (xy 57.079362 -276.121119) (xy 57.049141 -276.162715) (xy 57.012785 -276.199071)
			(xy 56.971189 -276.229292) (xy 56.925377 -276.252635) (xy 56.876478 -276.268523) (xy 56.825696 -276.276566)
			(xy 56.77428 -276.276566) (xy 56.723498 -276.268523) (xy 56.674599 -276.252635) (xy 56.628787 -276.229292)
			(xy 56.587191 -276.199071) (xy 56.550835 -276.162715) (xy 56.520614 -276.121119) (xy 56.497271 -276.075307)
			(xy 56.481383 -276.026408) (xy 56.47334 -275.975626) (xy 56.154408 -275.975626) (xy 56.146692 -276.023102)
			(xy 56.131108 -276.069783) (xy 56.108237 -276.11336) (xy 56.078672 -276.152704) (xy 56.043179 -276.186796)
			(xy 56.002676 -276.214752) (xy 55.958214 -276.23585) (xy 55.910943 -276.249542) (xy 55.862088 -276.255474)
			(xy 55.812913 -276.253493) (xy 55.764694 -276.243649) (xy 55.718678 -276.226197) (xy 55.676057 -276.20159)
			(xy 55.637936 -276.170465) (xy 55.605301 -276.133628) (xy 55.578998 -276.092032) (xy 55.559707 -276.046756)
			(xy 55.54793 -275.998972) (xy 55.54397 -275.949918) (xy 55.226966 -275.949918) (xy 55.226462 -275.975626)
			(xy 55.218419 -276.026408) (xy 55.202531 -276.075307) (xy 55.179188 -276.121119) (xy 55.148967 -276.162715)
			(xy 55.112611 -276.199071) (xy 55.071015 -276.229292) (xy 55.025203 -276.252635) (xy 54.976304 -276.268523)
			(xy 54.925522 -276.276566) (xy 54.874106 -276.276566) (xy 54.823324 -276.268523) (xy 54.774425 -276.252635)
			(xy 54.728613 -276.229292) (xy 54.687017 -276.199071) (xy 54.650661 -276.162715) (xy 54.62044 -276.121119)
			(xy 54.597097 -276.075307) (xy 54.581209 -276.026408) (xy 54.573166 -275.975626) (xy 54.254488 -275.975626)
			(xy 54.246772 -276.023102) (xy 54.231188 -276.069783) (xy 54.208317 -276.11336) (xy 54.178752 -276.152704)
			(xy 54.143259 -276.186796) (xy 54.102756 -276.214752) (xy 54.058294 -276.23585) (xy 54.011023 -276.249542)
			(xy 53.962168 -276.255474) (xy 53.912993 -276.253493) (xy 53.864774 -276.243649) (xy 53.818758 -276.226197)
			(xy 53.776137 -276.20159) (xy 53.738016 -276.170465) (xy 53.705381 -276.133628) (xy 53.679078 -276.092032)
			(xy 53.659787 -276.046756) (xy 53.64801 -275.998972) (xy 53.64405 -275.949918) (xy 53.327046 -275.949918)
			(xy 53.326542 -275.975626) (xy 53.318499 -276.026408) (xy 53.302611 -276.075307) (xy 53.279268 -276.121119)
			(xy 53.249047 -276.162715) (xy 53.212691 -276.199071) (xy 53.171095 -276.229292) (xy 53.125283 -276.252635)
			(xy 53.076384 -276.268523) (xy 53.025602 -276.276566) (xy 52.974186 -276.276566) (xy 52.923404 -276.268523)
			(xy 52.874505 -276.252635) (xy 52.828693 -276.229292) (xy 52.787097 -276.199071) (xy 52.750741 -276.162715)
			(xy 52.72052 -276.121119) (xy 52.697177 -276.075307) (xy 52.681289 -276.026408) (xy 52.673246 -275.975626)
			(xy 52.354568 -275.975626) (xy 52.346852 -276.023102) (xy 52.331268 -276.069783) (xy 52.308397 -276.11336)
			(xy 52.278832 -276.152704) (xy 52.243339 -276.186796) (xy 52.202836 -276.214752) (xy 52.158374 -276.23585)
			(xy 52.111103 -276.249542) (xy 52.062248 -276.255474) (xy 52.013073 -276.253493) (xy 51.964854 -276.243649)
			(xy 51.918838 -276.226197) (xy 51.876217 -276.20159) (xy 51.838096 -276.170465) (xy 51.805461 -276.133628)
			(xy 51.779158 -276.092032) (xy 51.759867 -276.046756) (xy 51.74809 -275.998972) (xy 51.74413 -275.949918)
			(xy 51.427126 -275.949918) (xy 51.426622 -275.975626) (xy 51.418579 -276.026408) (xy 51.402691 -276.075307)
			(xy 51.379348 -276.121119) (xy 51.349127 -276.162715) (xy 51.312771 -276.199071) (xy 51.271175 -276.229292)
			(xy 51.225363 -276.252635) (xy 51.176464 -276.268523) (xy 51.125682 -276.276566) (xy 51.074266 -276.276566)
			(xy 51.023484 -276.268523) (xy 50.974585 -276.252635) (xy 50.928773 -276.229292) (xy 50.887177 -276.199071)
			(xy 50.850821 -276.162715) (xy 50.8206 -276.121119) (xy 50.797257 -276.075307) (xy 50.781369 -276.026408)
			(xy 50.773326 -275.975626) (xy 50.454394 -275.975626) (xy 50.446678 -276.023102) (xy 50.431094 -276.069783)
			(xy 50.408223 -276.11336) (xy 50.378658 -276.152704) (xy 50.343165 -276.186796) (xy 50.302662 -276.214752)
			(xy 50.2582 -276.23585) (xy 50.210929 -276.249542) (xy 50.162074 -276.255474) (xy 50.112899 -276.253493)
			(xy 50.06468 -276.243649) (xy 50.018664 -276.226197) (xy 49.976043 -276.20159) (xy 49.937922 -276.170465)
			(xy 49.905287 -276.133628) (xy 49.878984 -276.092032) (xy 49.859693 -276.046756) (xy 49.847916 -275.998972)
			(xy 49.843956 -275.949918) (xy 49.527541 -275.949918) (xy 49.523396 -276.001844) (xy 49.511062 -276.052472)
			(xy 49.490853 -276.100502) (xy 49.463281 -276.144719) (xy 49.429043 -276.184001) (xy 49.389008 -276.217355)
			(xy 49.344189 -276.243935) (xy 49.29572 -276.263069) (xy 49.24483 -276.274273) (xy 49.21885 -276.276308)
			(xy 49.209592 -276.277273) (xy 49.192661 -276.28497) (xy 49.18583 -276.291294) (xy 49.16424 -276.312884)
			(xy 49.157438 -276.320232) (xy 49.14973 -276.338695) (xy 49.149254 -276.348698) (xy 49.149254 -276.522688)
			(xy 49.149676 -276.532758) (xy 49.157394 -276.55136) (xy 49.16424 -276.558756) (xy 49.18583 -276.580346)
			(xy 49.192641 -276.58655) (xy 49.209435 -276.594097) (xy 49.218596 -276.595078) (xy 49.242794 -276.597038)
			(xy 49.290164 -276.607654) (xy 49.335258 -276.625629) (xy 49.376941 -276.650512) (xy 49.414163 -276.681675)
			(xy 49.445986 -276.718335) (xy 49.471609 -276.759567) (xy 49.490387 -276.804333) (xy 49.501846 -276.851507)
			(xy 49.505696 -276.899878) (xy 49.843956 -276.899878) (xy 49.847916 -276.850824) (xy 49.859693 -276.80304)
			(xy 49.878984 -276.757764) (xy 49.905287 -276.716168) (xy 49.937922 -276.679331) (xy 49.976043 -276.648206)
			(xy 50.018664 -276.623599) (xy 50.06468 -276.606147) (xy 50.112899 -276.596303) (xy 50.162074 -276.594322)
			(xy 50.210929 -276.600254) (xy 50.2582 -276.613946) (xy 50.302662 -276.635044) (xy 50.343165 -276.663)
			(xy 50.378658 -276.697092) (xy 50.408223 -276.736436) (xy 50.431094 -276.780013) (xy 50.446678 -276.826694)
			(xy 50.454573 -276.875271) (xy 50.455068 -276.899878) (xy 50.79417 -276.899878) (xy 50.79813 -276.850824)
			(xy 50.809907 -276.80304) (xy 50.829198 -276.757764) (xy 50.855501 -276.716168) (xy 50.888136 -276.679331)
			(xy 50.926257 -276.648206) (xy 50.968878 -276.623599) (xy 51.014894 -276.606147) (xy 51.063113 -276.596303)
			(xy 51.112288 -276.594322) (xy 51.161143 -276.600254) (xy 51.208414 -276.613946) (xy 51.252876 -276.635044)
			(xy 51.293379 -276.663) (xy 51.328872 -276.697092) (xy 51.358437 -276.736436) (xy 51.381308 -276.780013)
			(xy 51.396892 -276.826694) (xy 51.404787 -276.875271) (xy 51.405282 -276.899878) (xy 51.74413 -276.899878)
			(xy 51.74809 -276.850824) (xy 51.759867 -276.80304) (xy 51.779158 -276.757764) (xy 51.805461 -276.716168)
			(xy 51.838096 -276.679331) (xy 51.876217 -276.648206) (xy 51.918838 -276.623599) (xy 51.964854 -276.606147)
			(xy 52.013073 -276.596303) (xy 52.062248 -276.594322) (xy 52.111103 -276.600254) (xy 52.158374 -276.613946)
			(xy 52.202836 -276.635044) (xy 52.243339 -276.663) (xy 52.278832 -276.697092) (xy 52.308397 -276.736436)
			(xy 52.331268 -276.780013) (xy 52.346852 -276.826694) (xy 52.354747 -276.875271) (xy 52.355242 -276.899878)
			(xy 52.69409 -276.899878) (xy 52.69805 -276.850824) (xy 52.709827 -276.80304) (xy 52.729118 -276.757764)
			(xy 52.755421 -276.716168) (xy 52.788056 -276.679331) (xy 52.826177 -276.648206) (xy 52.868798 -276.623599)
			(xy 52.914814 -276.606147) (xy 52.963033 -276.596303) (xy 53.012208 -276.594322) (xy 53.061063 -276.600254)
			(xy 53.108334 -276.613946) (xy 53.152796 -276.635044) (xy 53.193299 -276.663) (xy 53.228792 -276.697092)
			(xy 53.258357 -276.736436) (xy 53.281228 -276.780013) (xy 53.296812 -276.826694) (xy 53.304707 -276.875271)
			(xy 53.305202 -276.899878) (xy 53.64405 -276.899878) (xy 53.64801 -276.850824) (xy 53.659787 -276.80304)
			(xy 53.679078 -276.757764) (xy 53.705381 -276.716168) (xy 53.738016 -276.679331) (xy 53.776137 -276.648206)
			(xy 53.818758 -276.623599) (xy 53.864774 -276.606147) (xy 53.912993 -276.596303) (xy 53.962168 -276.594322)
			(xy 54.011023 -276.600254) (xy 54.058294 -276.613946) (xy 54.102756 -276.635044) (xy 54.143259 -276.663)
			(xy 54.178752 -276.697092) (xy 54.208317 -276.736436) (xy 54.231188 -276.780013) (xy 54.246772 -276.826694)
			(xy 54.254667 -276.875271) (xy 54.255162 -276.899878) (xy 54.59401 -276.899878) (xy 54.59797 -276.850824)
			(xy 54.609747 -276.80304) (xy 54.629038 -276.757764) (xy 54.655341 -276.716168) (xy 54.687976 -276.679331)
			(xy 54.726097 -276.648206) (xy 54.768718 -276.623599) (xy 54.814734 -276.606147) (xy 54.862953 -276.596303)
			(xy 54.912128 -276.594322) (xy 54.960983 -276.600254) (xy 55.008254 -276.613946) (xy 55.052716 -276.635044)
			(xy 55.093219 -276.663) (xy 55.128712 -276.697092) (xy 55.158277 -276.736436) (xy 55.181148 -276.780013)
			(xy 55.196732 -276.826694) (xy 55.204627 -276.875271) (xy 55.205122 -276.899878) (xy 55.54397 -276.899878)
			(xy 55.54793 -276.850824) (xy 55.559707 -276.80304) (xy 55.578998 -276.757764) (xy 55.605301 -276.716168)
			(xy 55.637936 -276.679331) (xy 55.676057 -276.648206) (xy 55.718678 -276.623599) (xy 55.764694 -276.606147)
			(xy 55.812913 -276.596303) (xy 55.862088 -276.594322) (xy 55.910943 -276.600254) (xy 55.958214 -276.613946)
			(xy 56.002676 -276.635044) (xy 56.043179 -276.663) (xy 56.078672 -276.697092) (xy 56.108237 -276.736436)
			(xy 56.131108 -276.780013) (xy 56.146692 -276.826694) (xy 56.154587 -276.875271) (xy 56.155082 -276.899878)
			(xy 56.494184 -276.899878) (xy 56.498144 -276.850824) (xy 56.509921 -276.80304) (xy 56.529212 -276.757764)
			(xy 56.555515 -276.716168) (xy 56.58815 -276.679331) (xy 56.626271 -276.648206) (xy 56.668892 -276.623599)
			(xy 56.714908 -276.606147) (xy 56.763127 -276.596303) (xy 56.812302 -276.594322) (xy 56.861157 -276.600254)
			(xy 56.908428 -276.613946) (xy 56.95289 -276.635044) (xy 56.993393 -276.663) (xy 57.028886 -276.697092)
			(xy 57.058451 -276.736436) (xy 57.081322 -276.780013) (xy 57.096906 -276.826694) (xy 57.104801 -276.875271)
			(xy 57.105296 -276.899878) (xy 57.444144 -276.899878) (xy 57.448104 -276.850824) (xy 57.459881 -276.80304)
			(xy 57.479172 -276.757764) (xy 57.505475 -276.716168) (xy 57.53811 -276.679331) (xy 57.576231 -276.648206)
			(xy 57.618852 -276.623599) (xy 57.664868 -276.606147) (xy 57.713087 -276.596303) (xy 57.762262 -276.594322)
			(xy 57.811117 -276.600254) (xy 57.858388 -276.613946) (xy 57.90285 -276.635044) (xy 57.943353 -276.663)
			(xy 57.978846 -276.697092) (xy 58.008411 -276.736436) (xy 58.031282 -276.780013) (xy 58.046866 -276.826694)
			(xy 58.054761 -276.875271) (xy 58.055256 -276.899878) (xy 58.394104 -276.899878) (xy 58.398064 -276.850824)
			(xy 58.409841 -276.80304) (xy 58.429132 -276.757764) (xy 58.455435 -276.716168) (xy 58.48807 -276.679331)
			(xy 58.526191 -276.648206) (xy 58.568812 -276.623599) (xy 58.614828 -276.606147) (xy 58.663047 -276.596303)
			(xy 58.712222 -276.594322) (xy 58.761077 -276.600254) (xy 58.808348 -276.613946) (xy 58.85281 -276.635044)
			(xy 58.893313 -276.663) (xy 58.928806 -276.697092) (xy 58.958371 -276.736436) (xy 58.981242 -276.780013)
			(xy 58.996826 -276.826694) (xy 59.004721 -276.875271) (xy 59.005216 -276.899878) (xy 59.344064 -276.899878)
			(xy 59.348024 -276.850824) (xy 59.359801 -276.80304) (xy 59.379092 -276.757764) (xy 59.405395 -276.716168)
			(xy 59.43803 -276.679331) (xy 59.476151 -276.648206) (xy 59.518772 -276.623599) (xy 59.564788 -276.606147)
			(xy 59.613007 -276.596303) (xy 59.662182 -276.594322) (xy 59.711037 -276.600254) (xy 59.758308 -276.613946)
			(xy 59.80277 -276.635044) (xy 59.843273 -276.663) (xy 59.878766 -276.697092) (xy 59.908331 -276.736436)
			(xy 59.931202 -276.780013) (xy 59.946786 -276.826694) (xy 59.954681 -276.875271) (xy 59.955176 -276.899878)
			(xy 60.294024 -276.899878) (xy 60.297984 -276.850824) (xy 60.309761 -276.80304) (xy 60.329052 -276.757764)
			(xy 60.355355 -276.716168) (xy 60.38799 -276.679331) (xy 60.426111 -276.648206) (xy 60.468732 -276.623599)
			(xy 60.514748 -276.606147) (xy 60.562967 -276.596303) (xy 60.612142 -276.594322) (xy 60.660997 -276.600254)
			(xy 60.708268 -276.613946) (xy 60.75273 -276.635044) (xy 60.793233 -276.663) (xy 60.828726 -276.697092)
			(xy 60.858291 -276.736436) (xy 60.881162 -276.780013) (xy 60.896746 -276.826694) (xy 60.904641 -276.875271)
			(xy 60.905136 -276.899878) (xy 61.243984 -276.899878) (xy 61.247944 -276.850824) (xy 61.259721 -276.80304)
			(xy 61.279012 -276.757764) (xy 61.305315 -276.716168) (xy 61.33795 -276.679331) (xy 61.376071 -276.648206)
			(xy 61.418692 -276.623599) (xy 61.464708 -276.606147) (xy 61.512927 -276.596303) (xy 61.562102 -276.594322)
			(xy 61.610957 -276.600254) (xy 61.658228 -276.613946) (xy 61.70269 -276.635044) (xy 61.743193 -276.663)
			(xy 61.778686 -276.697092) (xy 61.808251 -276.736436) (xy 61.831122 -276.780013) (xy 61.846706 -276.826694)
			(xy 61.854601 -276.875271) (xy 61.855096 -276.899878) (xy 62.193944 -276.899878) (xy 62.197904 -276.850824)
			(xy 62.209681 -276.80304) (xy 62.228972 -276.757764) (xy 62.255275 -276.716168) (xy 62.28791 -276.679331)
			(xy 62.326031 -276.648206) (xy 62.368652 -276.623599) (xy 62.414668 -276.606147) (xy 62.462887 -276.596303)
			(xy 62.512062 -276.594322) (xy 62.560917 -276.600254) (xy 62.608188 -276.613946) (xy 62.65265 -276.635044)
			(xy 62.693153 -276.663) (xy 62.728646 -276.697092) (xy 62.758211 -276.736436) (xy 62.781082 -276.780013)
			(xy 62.796666 -276.826694) (xy 62.804561 -276.875271) (xy 62.805056 -276.899878) (xy 63.144158 -276.899878)
			(xy 63.148118 -276.850824) (xy 63.159895 -276.80304) (xy 63.179186 -276.757764) (xy 63.205489 -276.716168)
			(xy 63.238124 -276.679331) (xy 63.276245 -276.648206) (xy 63.318866 -276.623599) (xy 63.364882 -276.606147)
			(xy 63.413101 -276.596303) (xy 63.462276 -276.594322) (xy 63.511131 -276.600254) (xy 63.558402 -276.613946)
			(xy 63.602864 -276.635044) (xy 63.643367 -276.663) (xy 63.67886 -276.697092) (xy 63.708425 -276.736436)
			(xy 63.731296 -276.780013) (xy 63.74688 -276.826694) (xy 63.754775 -276.875271) (xy 63.75527 -276.899878)
			(xy 64.094118 -276.899878) (xy 64.098078 -276.850824) (xy 64.109855 -276.80304) (xy 64.129146 -276.757764)
			(xy 64.155449 -276.716168) (xy 64.188084 -276.679331) (xy 64.226205 -276.648206) (xy 64.268826 -276.623599)
			(xy 64.314842 -276.606147) (xy 64.363061 -276.596303) (xy 64.412236 -276.594322) (xy 64.461091 -276.600254)
			(xy 64.508362 -276.613946) (xy 64.552824 -276.635044) (xy 64.593327 -276.663) (xy 64.62882 -276.697092)
			(xy 64.658385 -276.736436) (xy 64.681256 -276.780013) (xy 64.69684 -276.826694) (xy 64.704735 -276.875271)
			(xy 64.70523 -276.899878) (xy 65.044078 -276.899878) (xy 65.048038 -276.850824) (xy 65.059815 -276.80304)
			(xy 65.079106 -276.757764) (xy 65.105409 -276.716168) (xy 65.138044 -276.679331) (xy 65.176165 -276.648206)
			(xy 65.218786 -276.623599) (xy 65.264802 -276.606147) (xy 65.313021 -276.596303) (xy 65.362196 -276.594322)
			(xy 65.411051 -276.600254) (xy 65.458322 -276.613946) (xy 65.502784 -276.635044) (xy 65.543287 -276.663)
			(xy 65.57878 -276.697092) (xy 65.608345 -276.736436) (xy 65.631216 -276.780013) (xy 65.6468 -276.826694)
			(xy 65.654695 -276.875271) (xy 65.65519 -276.899878) (xy 65.994038 -276.899878) (xy 65.997998 -276.850824)
			(xy 66.009775 -276.80304) (xy 66.029066 -276.757764) (xy 66.055369 -276.716168) (xy 66.088004 -276.679331)
			(xy 66.126125 -276.648206) (xy 66.168746 -276.623599) (xy 66.214762 -276.606147) (xy 66.262981 -276.596303)
			(xy 66.312156 -276.594322) (xy 66.361011 -276.600254) (xy 66.408282 -276.613946) (xy 66.452744 -276.635044)
			(xy 66.493247 -276.663) (xy 66.52874 -276.697092) (xy 66.558305 -276.736436) (xy 66.581176 -276.780013)
			(xy 66.59676 -276.826694) (xy 66.604655 -276.875271) (xy 66.60515 -276.899878) (xy 66.943998 -276.899878)
			(xy 66.947958 -276.850824) (xy 66.959735 -276.80304) (xy 66.979026 -276.757764) (xy 67.005329 -276.716168)
			(xy 67.037964 -276.679331) (xy 67.076085 -276.648206) (xy 67.118706 -276.623599) (xy 67.164722 -276.606147)
			(xy 67.212941 -276.596303) (xy 67.262116 -276.594322) (xy 67.310971 -276.600254) (xy 67.358242 -276.613946)
			(xy 67.402704 -276.635044) (xy 67.443207 -276.663) (xy 67.4787 -276.697092) (xy 67.508265 -276.736436)
			(xy 67.531136 -276.780013) (xy 67.54672 -276.826694) (xy 67.554615 -276.875271) (xy 67.55511 -276.899878)
			(xy 67.893958 -276.899878) (xy 67.897918 -276.850824) (xy 67.909695 -276.80304) (xy 67.928986 -276.757764)
			(xy 67.955289 -276.716168) (xy 67.987924 -276.679331) (xy 68.026045 -276.648206) (xy 68.068666 -276.623599)
			(xy 68.114682 -276.606147) (xy 68.162901 -276.596303) (xy 68.212076 -276.594322) (xy 68.260931 -276.600254)
			(xy 68.308202 -276.613946) (xy 68.352664 -276.635044) (xy 68.393167 -276.663) (xy 68.42866 -276.697092)
			(xy 68.458225 -276.736436) (xy 68.481096 -276.780013) (xy 68.49668 -276.826694) (xy 68.504575 -276.875271)
			(xy 68.50507 -276.899878) (xy 68.844172 -276.899878) (xy 68.848132 -276.850824) (xy 68.859909 -276.80304)
			(xy 68.8792 -276.757764) (xy 68.905503 -276.716168) (xy 68.938138 -276.679331) (xy 68.976259 -276.648206)
			(xy 69.01888 -276.623599) (xy 69.064896 -276.606147) (xy 69.113115 -276.596303) (xy 69.16229 -276.594322)
			(xy 69.211145 -276.600254) (xy 69.258416 -276.613946) (xy 69.302878 -276.635044) (xy 69.343381 -276.663)
			(xy 69.378874 -276.697092) (xy 69.408439 -276.736436) (xy 69.43131 -276.780013) (xy 69.446894 -276.826694)
			(xy 69.454789 -276.875271) (xy 69.455284 -276.899878) (xy 69.794132 -276.899878) (xy 69.798092 -276.850824)
			(xy 69.809869 -276.80304) (xy 69.82916 -276.757764) (xy 69.855463 -276.716168) (xy 69.888098 -276.679331)
			(xy 69.926219 -276.648206) (xy 69.96884 -276.623599) (xy 70.014856 -276.606147) (xy 70.063075 -276.596303)
			(xy 70.11225 -276.594322) (xy 70.161105 -276.600254) (xy 70.208376 -276.613946) (xy 70.252838 -276.635044)
			(xy 70.293341 -276.663) (xy 70.328834 -276.697092) (xy 70.358399 -276.736436) (xy 70.38127 -276.780013)
			(xy 70.396854 -276.826694) (xy 70.404749 -276.875271) (xy 70.405244 -276.899878) (xy 70.744092 -276.899878)
			(xy 70.748052 -276.850824) (xy 70.759829 -276.80304) (xy 70.77912 -276.757764) (xy 70.805423 -276.716168)
			(xy 70.838058 -276.679331) (xy 70.876179 -276.648206) (xy 70.9188 -276.623599) (xy 70.964816 -276.606147)
			(xy 71.013035 -276.596303) (xy 71.06221 -276.594322) (xy 71.111065 -276.600254) (xy 71.158336 -276.613946)
			(xy 71.202798 -276.635044) (xy 71.243301 -276.663) (xy 71.278794 -276.697092) (xy 71.308359 -276.736436)
			(xy 71.33123 -276.780013) (xy 71.346814 -276.826694) (xy 71.354709 -276.875271) (xy 71.355204 -276.899878)
			(xy 71.694052 -276.899878) (xy 71.698012 -276.850824) (xy 71.709789 -276.80304) (xy 71.72908 -276.757764)
			(xy 71.755383 -276.716168) (xy 71.788018 -276.679331) (xy 71.826139 -276.648206) (xy 71.86876 -276.623599)
			(xy 71.914776 -276.606147) (xy 71.962995 -276.596303) (xy 72.01217 -276.594322) (xy 72.061025 -276.600254)
			(xy 72.108296 -276.613946) (xy 72.152758 -276.635044) (xy 72.193261 -276.663) (xy 72.228754 -276.697092)
			(xy 72.258319 -276.736436) (xy 72.28119 -276.780013) (xy 72.296774 -276.826694) (xy 72.304669 -276.875271)
			(xy 72.305164 -276.899878) (xy 72.644012 -276.899878) (xy 72.647972 -276.850824) (xy 72.659749 -276.80304)
			(xy 72.67904 -276.757764) (xy 72.705343 -276.716168) (xy 72.737978 -276.679331) (xy 72.776099 -276.648206)
			(xy 72.81872 -276.623599) (xy 72.864736 -276.606147) (xy 72.912955 -276.596303) (xy 72.96213 -276.594322)
			(xy 73.010985 -276.600254) (xy 73.058256 -276.613946) (xy 73.102718 -276.635044) (xy 73.143221 -276.663)
			(xy 73.178714 -276.697092) (xy 73.208279 -276.736436) (xy 73.23115 -276.780013) (xy 73.246734 -276.826694)
			(xy 73.254629 -276.875271) (xy 73.255124 -276.899878) (xy 73.593718 -276.899878) (xy 73.597678 -276.850824)
			(xy 73.609455 -276.80304) (xy 73.628746 -276.757764) (xy 73.655049 -276.716168) (xy 73.687684 -276.679331)
			(xy 73.725805 -276.648206) (xy 73.768426 -276.623599) (xy 73.814442 -276.606147) (xy 73.862661 -276.596303)
			(xy 73.911836 -276.594322) (xy 73.960691 -276.600254) (xy 74.007962 -276.613946) (xy 74.052424 -276.635044)
			(xy 74.092927 -276.663) (xy 74.12842 -276.697092) (xy 74.157985 -276.736436) (xy 74.180856 -276.780013)
			(xy 74.19644 -276.826694) (xy 74.204335 -276.875271) (xy 74.20483 -276.899878) (xy 74.543932 -276.899878)
			(xy 74.547892 -276.850824) (xy 74.559669 -276.80304) (xy 74.57896 -276.757764) (xy 74.605263 -276.716168)
			(xy 74.637898 -276.679331) (xy 74.676019 -276.648206) (xy 74.71864 -276.623599) (xy 74.764656 -276.606147)
			(xy 74.812875 -276.596303) (xy 74.86205 -276.594322) (xy 74.910905 -276.600254) (xy 74.958176 -276.613946)
			(xy 75.002638 -276.635044) (xy 75.043141 -276.663) (xy 75.078634 -276.697092) (xy 75.108199 -276.736436)
			(xy 75.13107 -276.780013) (xy 75.146654 -276.826694) (xy 75.154549 -276.875271) (xy 75.155044 -276.899878)
			(xy 75.493892 -276.899878) (xy 75.497852 -276.850824) (xy 75.509629 -276.80304) (xy 75.52892 -276.757764)
			(xy 75.555223 -276.716168) (xy 75.587858 -276.679331) (xy 75.625979 -276.648206) (xy 75.6686 -276.623599)
			(xy 75.714616 -276.606147) (xy 75.762835 -276.596303) (xy 75.81201 -276.594322) (xy 75.860865 -276.600254)
			(xy 75.908136 -276.613946) (xy 75.952598 -276.635044) (xy 75.993101 -276.663) (xy 76.028594 -276.697092)
			(xy 76.058159 -276.736436) (xy 76.08103 -276.780013) (xy 76.096614 -276.826694) (xy 76.104509 -276.875271)
			(xy 76.105004 -276.899878) (xy 76.443852 -276.899878) (xy 76.447812 -276.850824) (xy 76.459589 -276.80304)
			(xy 76.47888 -276.757764) (xy 76.505183 -276.716168) (xy 76.537818 -276.679331) (xy 76.575939 -276.648206)
			(xy 76.61856 -276.623599) (xy 76.664576 -276.606147) (xy 76.712795 -276.596303) (xy 76.76197 -276.594322)
			(xy 76.810825 -276.600254) (xy 76.858096 -276.613946) (xy 76.902558 -276.635044) (xy 76.943061 -276.663)
			(xy 76.978554 -276.697092) (xy 77.008119 -276.736436) (xy 77.03099 -276.780013) (xy 77.046574 -276.826694)
			(xy 77.054469 -276.875271) (xy 77.054964 -276.899878) (xy 77.393812 -276.899878) (xy 77.397772 -276.850824)
			(xy 77.409549 -276.80304) (xy 77.42884 -276.757764) (xy 77.455143 -276.716168) (xy 77.487778 -276.679331)
			(xy 77.525899 -276.648206) (xy 77.56852 -276.623599) (xy 77.614536 -276.606147) (xy 77.662755 -276.596303)
			(xy 77.71193 -276.594322) (xy 77.760785 -276.600254) (xy 77.808056 -276.613946) (xy 77.852518 -276.635044)
			(xy 77.893021 -276.663) (xy 77.928514 -276.697092) (xy 77.958079 -276.736436) (xy 77.98095 -276.780013)
			(xy 77.996534 -276.826694) (xy 78.004429 -276.875271) (xy 78.004924 -276.899878) (xy 78.343772 -276.899878)
			(xy 78.347732 -276.850824) (xy 78.359509 -276.80304) (xy 78.3788 -276.757764) (xy 78.405103 -276.716168)
			(xy 78.437738 -276.679331) (xy 78.475859 -276.648206) (xy 78.51848 -276.623599) (xy 78.564496 -276.606147)
			(xy 78.612715 -276.596303) (xy 78.66189 -276.594322) (xy 78.710745 -276.600254) (xy 78.758016 -276.613946)
			(xy 78.802478 -276.635044) (xy 78.842981 -276.663) (xy 78.878474 -276.697092) (xy 78.908039 -276.736436)
			(xy 78.93091 -276.780013) (xy 78.946494 -276.826694) (xy 78.954389 -276.875271) (xy 78.954884 -276.899878)
			(xy 79.293732 -276.899878) (xy 79.297692 -276.850824) (xy 79.309469 -276.80304) (xy 79.32876 -276.757764)
			(xy 79.355063 -276.716168) (xy 79.387698 -276.679331) (xy 79.425819 -276.648206) (xy 79.46844 -276.623599)
			(xy 79.514456 -276.606147) (xy 79.562675 -276.596303) (xy 79.61185 -276.594322) (xy 79.660705 -276.600254)
			(xy 79.707976 -276.613946) (xy 79.752438 -276.635044) (xy 79.792941 -276.663) (xy 79.828434 -276.697092)
			(xy 79.857999 -276.736436) (xy 79.88087 -276.780013) (xy 79.896454 -276.826694) (xy 79.904349 -276.875271)
			(xy 79.904844 -276.899878) (xy 80.243946 -276.899878) (xy 80.247906 -276.850824) (xy 80.259683 -276.80304)
			(xy 80.278974 -276.757764) (xy 80.305277 -276.716168) (xy 80.337912 -276.679331) (xy 80.376033 -276.648206)
			(xy 80.418654 -276.623599) (xy 80.46467 -276.606147) (xy 80.512889 -276.596303) (xy 80.562064 -276.594322)
			(xy 80.610919 -276.600254) (xy 80.65819 -276.613946) (xy 80.702652 -276.635044) (xy 80.743155 -276.663)
			(xy 80.778648 -276.697092) (xy 80.808213 -276.736436) (xy 80.831084 -276.780013) (xy 80.846668 -276.826694)
			(xy 80.854563 -276.875271) (xy 80.855058 -276.899878) (xy 80.854563 -276.924485) (xy 80.854384 -276.925586)
			(xy 81.173316 -276.925586) (xy 81.173316 -276.87417) (xy 81.181359 -276.823388) (xy 81.197247 -276.774489)
			(xy 81.22059 -276.728677) (xy 81.250811 -276.687081) (xy 81.287167 -276.650725) (xy 81.328763 -276.620504)
			(xy 81.374575 -276.597161) (xy 81.423474 -276.581273) (xy 81.474256 -276.57323) (xy 81.525672 -276.57323)
			(xy 81.576454 -276.581273) (xy 81.625353 -276.597161) (xy 81.671165 -276.620504) (xy 81.712761 -276.650725)
			(xy 81.749117 -276.687081) (xy 81.779338 -276.728677) (xy 81.802681 -276.774489) (xy 81.818569 -276.823388)
			(xy 81.826612 -276.87417) (xy 81.827116 -276.899878) (xy 81.826612 -276.925586) (xy 82.123276 -276.925586)
			(xy 82.123276 -276.87417) (xy 82.131319 -276.823388) (xy 82.147207 -276.774489) (xy 82.17055 -276.728677)
			(xy 82.200771 -276.687081) (xy 82.237127 -276.650725) (xy 82.278723 -276.620504) (xy 82.324535 -276.597161)
			(xy 82.373434 -276.581273) (xy 82.424216 -276.57323) (xy 82.475632 -276.57323) (xy 82.526414 -276.581273)
			(xy 82.575313 -276.597161) (xy 82.621125 -276.620504) (xy 82.662721 -276.650725) (xy 82.699077 -276.687081)
			(xy 82.729298 -276.728677) (xy 82.752641 -276.774489) (xy 82.768529 -276.823388) (xy 82.776572 -276.87417)
			(xy 82.777076 -276.899878) (xy 82.777071 -276.900132) (xy 83.094334 -276.900132) (xy 83.098294 -276.851078)
			(xy 83.110071 -276.803294) (xy 83.129362 -276.758018) (xy 83.155665 -276.716422) (xy 83.1883 -276.679585)
			(xy 83.226421 -276.64846) (xy 83.269042 -276.623853) (xy 83.315058 -276.606401) (xy 83.363277 -276.596557)
			(xy 83.412452 -276.594576) (xy 83.461307 -276.600508) (xy 83.508578 -276.6142) (xy 83.55304 -276.635298)
			(xy 83.593543 -276.663254) (xy 83.629036 -276.697346) (xy 83.658601 -276.73669) (xy 83.681472 -276.780267)
			(xy 83.697056 -276.826948) (xy 83.704951 -276.875525) (xy 83.705446 -276.900132) (xy 83.704951 -276.924739)
			(xy 83.697056 -276.973316) (xy 83.681472 -277.019997) (xy 83.658601 -277.063574) (xy 83.629036 -277.102918)
			(xy 83.593543 -277.13701) (xy 83.55304 -277.164966) (xy 83.508578 -277.186064) (xy 83.461307 -277.199756)
			(xy 83.412452 -277.205688) (xy 83.363277 -277.203707) (xy 83.315058 -277.193863) (xy 83.269042 -277.176411)
			(xy 83.226421 -277.151804) (xy 83.1883 -277.120679) (xy 83.155665 -277.083842) (xy 83.129362 -277.042246)
			(xy 83.110071 -276.99697) (xy 83.098294 -276.949186) (xy 83.094334 -276.900132) (xy 82.777071 -276.900132)
			(xy 82.776572 -276.925586) (xy 82.768529 -276.976368) (xy 82.752641 -277.025267) (xy 82.729298 -277.071079)
			(xy 82.699077 -277.112675) (xy 82.662721 -277.149031) (xy 82.621125 -277.179252) (xy 82.575313 -277.202595)
			(xy 82.526414 -277.218483) (xy 82.475632 -277.226526) (xy 82.424216 -277.226526) (xy 82.373434 -277.218483)
			(xy 82.324535 -277.202595) (xy 82.278723 -277.179252) (xy 82.237127 -277.149031) (xy 82.200771 -277.112675)
			(xy 82.17055 -277.071079) (xy 82.147207 -277.025267) (xy 82.131319 -276.976368) (xy 82.123276 -276.925586)
			(xy 81.826612 -276.925586) (xy 81.818569 -276.976368) (xy 81.802681 -277.025267) (xy 81.779338 -277.071079)
			(xy 81.749117 -277.112675) (xy 81.712761 -277.149031) (xy 81.671165 -277.179252) (xy 81.625353 -277.202595)
			(xy 81.576454 -277.218483) (xy 81.525672 -277.226526) (xy 81.474256 -277.226526) (xy 81.423474 -277.218483)
			(xy 81.374575 -277.202595) (xy 81.328763 -277.179252) (xy 81.287167 -277.149031) (xy 81.250811 -277.112675)
			(xy 81.22059 -277.071079) (xy 81.197247 -277.025267) (xy 81.181359 -276.976368) (xy 81.173316 -276.925586)
			(xy 80.854384 -276.925586) (xy 80.846668 -276.973062) (xy 80.831084 -277.019743) (xy 80.808213 -277.06332)
			(xy 80.778648 -277.102664) (xy 80.743155 -277.136756) (xy 80.702652 -277.164712) (xy 80.65819 -277.18581)
			(xy 80.610919 -277.199502) (xy 80.562064 -277.205434) (xy 80.512889 -277.203453) (xy 80.46467 -277.193609)
			(xy 80.418654 -277.176157) (xy 80.376033 -277.15155) (xy 80.337912 -277.120425) (xy 80.305277 -277.083588)
			(xy 80.278974 -277.041992) (xy 80.259683 -276.996716) (xy 80.247906 -276.948932) (xy 80.243946 -276.899878)
			(xy 79.904844 -276.899878) (xy 79.904349 -276.924485) (xy 79.896454 -276.973062) (xy 79.88087 -277.019743)
			(xy 79.857999 -277.06332) (xy 79.828434 -277.102664) (xy 79.792941 -277.136756) (xy 79.752438 -277.164712)
			(xy 79.707976 -277.18581) (xy 79.660705 -277.199502) (xy 79.61185 -277.205434) (xy 79.562675 -277.203453)
			(xy 79.514456 -277.193609) (xy 79.46844 -277.176157) (xy 79.425819 -277.15155) (xy 79.387698 -277.120425)
			(xy 79.355063 -277.083588) (xy 79.32876 -277.041992) (xy 79.309469 -276.996716) (xy 79.297692 -276.948932)
			(xy 79.293732 -276.899878) (xy 78.954884 -276.899878) (xy 78.954389 -276.924485) (xy 78.946494 -276.973062)
			(xy 78.93091 -277.019743) (xy 78.908039 -277.06332) (xy 78.878474 -277.102664) (xy 78.842981 -277.136756)
			(xy 78.802478 -277.164712) (xy 78.758016 -277.18581) (xy 78.710745 -277.199502) (xy 78.66189 -277.205434)
			(xy 78.612715 -277.203453) (xy 78.564496 -277.193609) (xy 78.51848 -277.176157) (xy 78.475859 -277.15155)
			(xy 78.437738 -277.120425) (xy 78.405103 -277.083588) (xy 78.3788 -277.041992) (xy 78.359509 -276.996716)
			(xy 78.347732 -276.948932) (xy 78.343772 -276.899878) (xy 78.004924 -276.899878) (xy 78.004429 -276.924485)
			(xy 77.996534 -276.973062) (xy 77.98095 -277.019743) (xy 77.958079 -277.06332) (xy 77.928514 -277.102664)
			(xy 77.893021 -277.136756) (xy 77.852518 -277.164712) (xy 77.808056 -277.18581) (xy 77.760785 -277.199502)
			(xy 77.71193 -277.205434) (xy 77.662755 -277.203453) (xy 77.614536 -277.193609) (xy 77.56852 -277.176157)
			(xy 77.525899 -277.15155) (xy 77.487778 -277.120425) (xy 77.455143 -277.083588) (xy 77.42884 -277.041992)
			(xy 77.409549 -276.996716) (xy 77.397772 -276.948932) (xy 77.393812 -276.899878) (xy 77.054964 -276.899878)
			(xy 77.054469 -276.924485) (xy 77.046574 -276.973062) (xy 77.03099 -277.019743) (xy 77.008119 -277.06332)
			(xy 76.978554 -277.102664) (xy 76.943061 -277.136756) (xy 76.902558 -277.164712) (xy 76.858096 -277.18581)
			(xy 76.810825 -277.199502) (xy 76.76197 -277.205434) (xy 76.712795 -277.203453) (xy 76.664576 -277.193609)
			(xy 76.61856 -277.176157) (xy 76.575939 -277.15155) (xy 76.537818 -277.120425) (xy 76.505183 -277.083588)
			(xy 76.47888 -277.041992) (xy 76.459589 -276.996716) (xy 76.447812 -276.948932) (xy 76.443852 -276.899878)
			(xy 76.105004 -276.899878) (xy 76.104509 -276.924485) (xy 76.096614 -276.973062) (xy 76.08103 -277.019743)
			(xy 76.058159 -277.06332) (xy 76.028594 -277.102664) (xy 75.993101 -277.136756) (xy 75.952598 -277.164712)
			(xy 75.908136 -277.18581) (xy 75.860865 -277.199502) (xy 75.81201 -277.205434) (xy 75.762835 -277.203453)
			(xy 75.714616 -277.193609) (xy 75.6686 -277.176157) (xy 75.625979 -277.15155) (xy 75.587858 -277.120425)
			(xy 75.555223 -277.083588) (xy 75.52892 -277.041992) (xy 75.509629 -276.996716) (xy 75.497852 -276.948932)
			(xy 75.493892 -276.899878) (xy 75.155044 -276.899878) (xy 75.154549 -276.924485) (xy 75.146654 -276.973062)
			(xy 75.13107 -277.019743) (xy 75.108199 -277.06332) (xy 75.078634 -277.102664) (xy 75.043141 -277.136756)
			(xy 75.002638 -277.164712) (xy 74.958176 -277.18581) (xy 74.910905 -277.199502) (xy 74.86205 -277.205434)
			(xy 74.812875 -277.203453) (xy 74.764656 -277.193609) (xy 74.71864 -277.176157) (xy 74.676019 -277.15155)
			(xy 74.637898 -277.120425) (xy 74.605263 -277.083588) (xy 74.57896 -277.041992) (xy 74.559669 -276.996716)
			(xy 74.547892 -276.948932) (xy 74.543932 -276.899878) (xy 74.20483 -276.899878) (xy 74.204335 -276.924485)
			(xy 74.19644 -276.973062) (xy 74.180856 -277.019743) (xy 74.157985 -277.06332) (xy 74.12842 -277.102664)
			(xy 74.092927 -277.136756) (xy 74.052424 -277.164712) (xy 74.007962 -277.18581) (xy 73.960691 -277.199502)
			(xy 73.911836 -277.205434) (xy 73.862661 -277.203453) (xy 73.814442 -277.193609) (xy 73.768426 -277.176157)
			(xy 73.725805 -277.15155) (xy 73.687684 -277.120425) (xy 73.655049 -277.083588) (xy 73.628746 -277.041992)
			(xy 73.609455 -276.996716) (xy 73.597678 -276.948932) (xy 73.593718 -276.899878) (xy 73.255124 -276.899878)
			(xy 73.254629 -276.924485) (xy 73.246734 -276.973062) (xy 73.23115 -277.019743) (xy 73.208279 -277.06332)
			(xy 73.178714 -277.102664) (xy 73.143221 -277.136756) (xy 73.102718 -277.164712) (xy 73.058256 -277.18581)
			(xy 73.010985 -277.199502) (xy 72.96213 -277.205434) (xy 72.912955 -277.203453) (xy 72.864736 -277.193609)
			(xy 72.81872 -277.176157) (xy 72.776099 -277.15155) (xy 72.737978 -277.120425) (xy 72.705343 -277.083588)
			(xy 72.67904 -277.041992) (xy 72.659749 -276.996716) (xy 72.647972 -276.948932) (xy 72.644012 -276.899878)
			(xy 72.305164 -276.899878) (xy 72.304669 -276.924485) (xy 72.296774 -276.973062) (xy 72.28119 -277.019743)
			(xy 72.258319 -277.06332) (xy 72.228754 -277.102664) (xy 72.193261 -277.136756) (xy 72.152758 -277.164712)
			(xy 72.108296 -277.18581) (xy 72.061025 -277.199502) (xy 72.01217 -277.205434) (xy 71.962995 -277.203453)
			(xy 71.914776 -277.193609) (xy 71.86876 -277.176157) (xy 71.826139 -277.15155) (xy 71.788018 -277.120425)
			(xy 71.755383 -277.083588) (xy 71.72908 -277.041992) (xy 71.709789 -276.996716) (xy 71.698012 -276.948932)
			(xy 71.694052 -276.899878) (xy 71.355204 -276.899878) (xy 71.354709 -276.924485) (xy 71.346814 -276.973062)
			(xy 71.33123 -277.019743) (xy 71.308359 -277.06332) (xy 71.278794 -277.102664) (xy 71.243301 -277.136756)
			(xy 71.202798 -277.164712) (xy 71.158336 -277.18581) (xy 71.111065 -277.199502) (xy 71.06221 -277.205434)
			(xy 71.013035 -277.203453) (xy 70.964816 -277.193609) (xy 70.9188 -277.176157) (xy 70.876179 -277.15155)
			(xy 70.838058 -277.120425) (xy 70.805423 -277.083588) (xy 70.77912 -277.041992) (xy 70.759829 -276.996716)
			(xy 70.748052 -276.948932) (xy 70.744092 -276.899878) (xy 70.405244 -276.899878) (xy 70.404749 -276.924485)
			(xy 70.396854 -276.973062) (xy 70.38127 -277.019743) (xy 70.358399 -277.06332) (xy 70.328834 -277.102664)
			(xy 70.293341 -277.136756) (xy 70.252838 -277.164712) (xy 70.208376 -277.18581) (xy 70.161105 -277.199502)
			(xy 70.11225 -277.205434) (xy 70.063075 -277.203453) (xy 70.014856 -277.193609) (xy 69.96884 -277.176157)
			(xy 69.926219 -277.15155) (xy 69.888098 -277.120425) (xy 69.855463 -277.083588) (xy 69.82916 -277.041992)
			(xy 69.809869 -276.996716) (xy 69.798092 -276.948932) (xy 69.794132 -276.899878) (xy 69.455284 -276.899878)
			(xy 69.454789 -276.924485) (xy 69.446894 -276.973062) (xy 69.43131 -277.019743) (xy 69.408439 -277.06332)
			(xy 69.378874 -277.102664) (xy 69.343381 -277.136756) (xy 69.302878 -277.164712) (xy 69.258416 -277.18581)
			(xy 69.211145 -277.199502) (xy 69.16229 -277.205434) (xy 69.113115 -277.203453) (xy 69.064896 -277.193609)
			(xy 69.01888 -277.176157) (xy 68.976259 -277.15155) (xy 68.938138 -277.120425) (xy 68.905503 -277.083588)
			(xy 68.8792 -277.041992) (xy 68.859909 -276.996716) (xy 68.848132 -276.948932) (xy 68.844172 -276.899878)
			(xy 68.50507 -276.899878) (xy 68.504575 -276.924485) (xy 68.49668 -276.973062) (xy 68.481096 -277.019743)
			(xy 68.458225 -277.06332) (xy 68.42866 -277.102664) (xy 68.393167 -277.136756) (xy 68.352664 -277.164712)
			(xy 68.308202 -277.18581) (xy 68.260931 -277.199502) (xy 68.212076 -277.205434) (xy 68.162901 -277.203453)
			(xy 68.114682 -277.193609) (xy 68.068666 -277.176157) (xy 68.026045 -277.15155) (xy 67.987924 -277.120425)
			(xy 67.955289 -277.083588) (xy 67.928986 -277.041992) (xy 67.909695 -276.996716) (xy 67.897918 -276.948932)
			(xy 67.893958 -276.899878) (xy 67.55511 -276.899878) (xy 67.554615 -276.924485) (xy 67.54672 -276.973062)
			(xy 67.531136 -277.019743) (xy 67.508265 -277.06332) (xy 67.4787 -277.102664) (xy 67.443207 -277.136756)
			(xy 67.402704 -277.164712) (xy 67.358242 -277.18581) (xy 67.310971 -277.199502) (xy 67.262116 -277.205434)
			(xy 67.212941 -277.203453) (xy 67.164722 -277.193609) (xy 67.118706 -277.176157) (xy 67.076085 -277.15155)
			(xy 67.037964 -277.120425) (xy 67.005329 -277.083588) (xy 66.979026 -277.041992) (xy 66.959735 -276.996716)
			(xy 66.947958 -276.948932) (xy 66.943998 -276.899878) (xy 66.60515 -276.899878) (xy 66.604655 -276.924485)
			(xy 66.59676 -276.973062) (xy 66.581176 -277.019743) (xy 66.558305 -277.06332) (xy 66.52874 -277.102664)
			(xy 66.493247 -277.136756) (xy 66.452744 -277.164712) (xy 66.408282 -277.18581) (xy 66.361011 -277.199502)
			(xy 66.312156 -277.205434) (xy 66.262981 -277.203453) (xy 66.214762 -277.193609) (xy 66.168746 -277.176157)
			(xy 66.126125 -277.15155) (xy 66.088004 -277.120425) (xy 66.055369 -277.083588) (xy 66.029066 -277.041992)
			(xy 66.009775 -276.996716) (xy 65.997998 -276.948932) (xy 65.994038 -276.899878) (xy 65.65519 -276.899878)
			(xy 65.654695 -276.924485) (xy 65.6468 -276.973062) (xy 65.631216 -277.019743) (xy 65.608345 -277.06332)
			(xy 65.57878 -277.102664) (xy 65.543287 -277.136756) (xy 65.502784 -277.164712) (xy 65.458322 -277.18581)
			(xy 65.411051 -277.199502) (xy 65.362196 -277.205434) (xy 65.313021 -277.203453) (xy 65.264802 -277.193609)
			(xy 65.218786 -277.176157) (xy 65.176165 -277.15155) (xy 65.138044 -277.120425) (xy 65.105409 -277.083588)
			(xy 65.079106 -277.041992) (xy 65.059815 -276.996716) (xy 65.048038 -276.948932) (xy 65.044078 -276.899878)
			(xy 64.70523 -276.899878) (xy 64.704735 -276.924485) (xy 64.69684 -276.973062) (xy 64.681256 -277.019743)
			(xy 64.658385 -277.06332) (xy 64.62882 -277.102664) (xy 64.593327 -277.136756) (xy 64.552824 -277.164712)
			(xy 64.508362 -277.18581) (xy 64.461091 -277.199502) (xy 64.412236 -277.205434) (xy 64.363061 -277.203453)
			(xy 64.314842 -277.193609) (xy 64.268826 -277.176157) (xy 64.226205 -277.15155) (xy 64.188084 -277.120425)
			(xy 64.155449 -277.083588) (xy 64.129146 -277.041992) (xy 64.109855 -276.996716) (xy 64.098078 -276.948932)
			(xy 64.094118 -276.899878) (xy 63.75527 -276.899878) (xy 63.754775 -276.924485) (xy 63.74688 -276.973062)
			(xy 63.731296 -277.019743) (xy 63.708425 -277.06332) (xy 63.67886 -277.102664) (xy 63.643367 -277.136756)
			(xy 63.602864 -277.164712) (xy 63.558402 -277.18581) (xy 63.511131 -277.199502) (xy 63.462276 -277.205434)
			(xy 63.413101 -277.203453) (xy 63.364882 -277.193609) (xy 63.318866 -277.176157) (xy 63.276245 -277.15155)
			(xy 63.238124 -277.120425) (xy 63.205489 -277.083588) (xy 63.179186 -277.041992) (xy 63.159895 -276.996716)
			(xy 63.148118 -276.948932) (xy 63.144158 -276.899878) (xy 62.805056 -276.899878) (xy 62.804561 -276.924485)
			(xy 62.796666 -276.973062) (xy 62.781082 -277.019743) (xy 62.758211 -277.06332) (xy 62.728646 -277.102664)
			(xy 62.693153 -277.136756) (xy 62.65265 -277.164712) (xy 62.608188 -277.18581) (xy 62.560917 -277.199502)
			(xy 62.512062 -277.205434) (xy 62.462887 -277.203453) (xy 62.414668 -277.193609) (xy 62.368652 -277.176157)
			(xy 62.326031 -277.15155) (xy 62.28791 -277.120425) (xy 62.255275 -277.083588) (xy 62.228972 -277.041992)
			(xy 62.209681 -276.996716) (xy 62.197904 -276.948932) (xy 62.193944 -276.899878) (xy 61.855096 -276.899878)
			(xy 61.854601 -276.924485) (xy 61.846706 -276.973062) (xy 61.831122 -277.019743) (xy 61.808251 -277.06332)
			(xy 61.778686 -277.102664) (xy 61.743193 -277.136756) (xy 61.70269 -277.164712) (xy 61.658228 -277.18581)
			(xy 61.610957 -277.199502) (xy 61.562102 -277.205434) (xy 61.512927 -277.203453) (xy 61.464708 -277.193609)
			(xy 61.418692 -277.176157) (xy 61.376071 -277.15155) (xy 61.33795 -277.120425) (xy 61.305315 -277.083588)
			(xy 61.279012 -277.041992) (xy 61.259721 -276.996716) (xy 61.247944 -276.948932) (xy 61.243984 -276.899878)
			(xy 60.905136 -276.899878) (xy 60.904641 -276.924485) (xy 60.896746 -276.973062) (xy 60.881162 -277.019743)
			(xy 60.858291 -277.06332) (xy 60.828726 -277.102664) (xy 60.793233 -277.136756) (xy 60.75273 -277.164712)
			(xy 60.708268 -277.18581) (xy 60.660997 -277.199502) (xy 60.612142 -277.205434) (xy 60.562967 -277.203453)
			(xy 60.514748 -277.193609) (xy 60.468732 -277.176157) (xy 60.426111 -277.15155) (xy 60.38799 -277.120425)
			(xy 60.355355 -277.083588) (xy 60.329052 -277.041992) (xy 60.309761 -276.996716) (xy 60.297984 -276.948932)
			(xy 60.294024 -276.899878) (xy 59.955176 -276.899878) (xy 59.954681 -276.924485) (xy 59.946786 -276.973062)
			(xy 59.931202 -277.019743) (xy 59.908331 -277.06332) (xy 59.878766 -277.102664) (xy 59.843273 -277.136756)
			(xy 59.80277 -277.164712) (xy 59.758308 -277.18581) (xy 59.711037 -277.199502) (xy 59.662182 -277.205434)
			(xy 59.613007 -277.203453) (xy 59.564788 -277.193609) (xy 59.518772 -277.176157) (xy 59.476151 -277.15155)
			(xy 59.43803 -277.120425) (xy 59.405395 -277.083588) (xy 59.379092 -277.041992) (xy 59.359801 -276.996716)
			(xy 59.348024 -276.948932) (xy 59.344064 -276.899878) (xy 59.005216 -276.899878) (xy 59.004721 -276.924485)
			(xy 58.996826 -276.973062) (xy 58.981242 -277.019743) (xy 58.958371 -277.06332) (xy 58.928806 -277.102664)
			(xy 58.893313 -277.136756) (xy 58.85281 -277.164712) (xy 58.808348 -277.18581) (xy 58.761077 -277.199502)
			(xy 58.712222 -277.205434) (xy 58.663047 -277.203453) (xy 58.614828 -277.193609) (xy 58.568812 -277.176157)
			(xy 58.526191 -277.15155) (xy 58.48807 -277.120425) (xy 58.455435 -277.083588) (xy 58.429132 -277.041992)
			(xy 58.409841 -276.996716) (xy 58.398064 -276.948932) (xy 58.394104 -276.899878) (xy 58.055256 -276.899878)
			(xy 58.054761 -276.924485) (xy 58.046866 -276.973062) (xy 58.031282 -277.019743) (xy 58.008411 -277.06332)
			(xy 57.978846 -277.102664) (xy 57.943353 -277.136756) (xy 57.90285 -277.164712) (xy 57.858388 -277.18581)
			(xy 57.811117 -277.199502) (xy 57.762262 -277.205434) (xy 57.713087 -277.203453) (xy 57.664868 -277.193609)
			(xy 57.618852 -277.176157) (xy 57.576231 -277.15155) (xy 57.53811 -277.120425) (xy 57.505475 -277.083588)
			(xy 57.479172 -277.041992) (xy 57.459881 -276.996716) (xy 57.448104 -276.948932) (xy 57.444144 -276.899878)
			(xy 57.105296 -276.899878) (xy 57.104801 -276.924485) (xy 57.096906 -276.973062) (xy 57.081322 -277.019743)
			(xy 57.058451 -277.06332) (xy 57.028886 -277.102664) (xy 56.993393 -277.136756) (xy 56.95289 -277.164712)
			(xy 56.908428 -277.18581) (xy 56.861157 -277.199502) (xy 56.812302 -277.205434) (xy 56.763127 -277.203453)
			(xy 56.714908 -277.193609) (xy 56.668892 -277.176157) (xy 56.626271 -277.15155) (xy 56.58815 -277.120425)
			(xy 56.555515 -277.083588) (xy 56.529212 -277.041992) (xy 56.509921 -276.996716) (xy 56.498144 -276.948932)
			(xy 56.494184 -276.899878) (xy 56.155082 -276.899878) (xy 56.154587 -276.924485) (xy 56.146692 -276.973062)
			(xy 56.131108 -277.019743) (xy 56.108237 -277.06332) (xy 56.078672 -277.102664) (xy 56.043179 -277.136756)
			(xy 56.002676 -277.164712) (xy 55.958214 -277.18581) (xy 55.910943 -277.199502) (xy 55.862088 -277.205434)
			(xy 55.812913 -277.203453) (xy 55.764694 -277.193609) (xy 55.718678 -277.176157) (xy 55.676057 -277.15155)
			(xy 55.637936 -277.120425) (xy 55.605301 -277.083588) (xy 55.578998 -277.041992) (xy 55.559707 -276.996716)
			(xy 55.54793 -276.948932) (xy 55.54397 -276.899878) (xy 55.205122 -276.899878) (xy 55.204627 -276.924485)
			(xy 55.196732 -276.973062) (xy 55.181148 -277.019743) (xy 55.158277 -277.06332) (xy 55.128712 -277.102664)
			(xy 55.093219 -277.136756) (xy 55.052716 -277.164712) (xy 55.008254 -277.18581) (xy 54.960983 -277.199502)
			(xy 54.912128 -277.205434) (xy 54.862953 -277.203453) (xy 54.814734 -277.193609) (xy 54.768718 -277.176157)
			(xy 54.726097 -277.15155) (xy 54.687976 -277.120425) (xy 54.655341 -277.083588) (xy 54.629038 -277.041992)
			(xy 54.609747 -276.996716) (xy 54.59797 -276.948932) (xy 54.59401 -276.899878) (xy 54.255162 -276.899878)
			(xy 54.254667 -276.924485) (xy 54.246772 -276.973062) (xy 54.231188 -277.019743) (xy 54.208317 -277.06332)
			(xy 54.178752 -277.102664) (xy 54.143259 -277.136756) (xy 54.102756 -277.164712) (xy 54.058294 -277.18581)
			(xy 54.011023 -277.199502) (xy 53.962168 -277.205434) (xy 53.912993 -277.203453) (xy 53.864774 -277.193609)
			(xy 53.818758 -277.176157) (xy 53.776137 -277.15155) (xy 53.738016 -277.120425) (xy 53.705381 -277.083588)
			(xy 53.679078 -277.041992) (xy 53.659787 -276.996716) (xy 53.64801 -276.948932) (xy 53.64405 -276.899878)
			(xy 53.305202 -276.899878) (xy 53.304707 -276.924485) (xy 53.296812 -276.973062) (xy 53.281228 -277.019743)
			(xy 53.258357 -277.06332) (xy 53.228792 -277.102664) (xy 53.193299 -277.136756) (xy 53.152796 -277.164712)
			(xy 53.108334 -277.18581) (xy 53.061063 -277.199502) (xy 53.012208 -277.205434) (xy 52.963033 -277.203453)
			(xy 52.914814 -277.193609) (xy 52.868798 -277.176157) (xy 52.826177 -277.15155) (xy 52.788056 -277.120425)
			(xy 52.755421 -277.083588) (xy 52.729118 -277.041992) (xy 52.709827 -276.996716) (xy 52.69805 -276.948932)
			(xy 52.69409 -276.899878) (xy 52.355242 -276.899878) (xy 52.354747 -276.924485) (xy 52.346852 -276.973062)
			(xy 52.331268 -277.019743) (xy 52.308397 -277.06332) (xy 52.278832 -277.102664) (xy 52.243339 -277.136756)
			(xy 52.202836 -277.164712) (xy 52.158374 -277.18581) (xy 52.111103 -277.199502) (xy 52.062248 -277.205434)
			(xy 52.013073 -277.203453) (xy 51.964854 -277.193609) (xy 51.918838 -277.176157) (xy 51.876217 -277.15155)
			(xy 51.838096 -277.120425) (xy 51.805461 -277.083588) (xy 51.779158 -277.041992) (xy 51.759867 -276.996716)
			(xy 51.74809 -276.948932) (xy 51.74413 -276.899878) (xy 51.405282 -276.899878) (xy 51.404787 -276.924485)
			(xy 51.396892 -276.973062) (xy 51.381308 -277.019743) (xy 51.358437 -277.06332) (xy 51.328872 -277.102664)
			(xy 51.293379 -277.136756) (xy 51.252876 -277.164712) (xy 51.208414 -277.18581) (xy 51.161143 -277.199502)
			(xy 51.112288 -277.205434) (xy 51.063113 -277.203453) (xy 51.014894 -277.193609) (xy 50.968878 -277.176157)
			(xy 50.926257 -277.15155) (xy 50.888136 -277.120425) (xy 50.855501 -277.083588) (xy 50.829198 -277.041992)
			(xy 50.809907 -276.996716) (xy 50.79813 -276.948932) (xy 50.79417 -276.899878) (xy 50.455068 -276.899878)
			(xy 50.454573 -276.924485) (xy 50.446678 -276.973062) (xy 50.431094 -277.019743) (xy 50.408223 -277.06332)
			(xy 50.378658 -277.102664) (xy 50.343165 -277.136756) (xy 50.302662 -277.164712) (xy 50.2582 -277.18581)
			(xy 50.210929 -277.199502) (xy 50.162074 -277.205434) (xy 50.112899 -277.203453) (xy 50.06468 -277.193609)
			(xy 50.018664 -277.176157) (xy 49.976043 -277.15155) (xy 49.937922 -277.120425) (xy 49.905287 -277.083588)
			(xy 49.878984 -277.041992) (xy 49.859693 -276.996716) (xy 49.847916 -276.948932) (xy 49.843956 -276.899878)
			(xy 49.505696 -276.899878) (xy 49.505698 -276.899899) (xy 49.501846 -276.948291) (xy 49.490387 -276.995464)
			(xy 49.47161 -277.040231) (xy 49.445988 -277.081463) (xy 49.414165 -277.118123) (xy 49.376944 -277.149287)
			(xy 49.335261 -277.17417) (xy 49.290167 -277.192146) (xy 49.242796 -277.202761) (xy 49.218596 -277.204678)
			(xy 49.209421 -277.205613) (xy 49.192612 -277.213162) (xy 49.18583 -277.21941) (xy 49.16424 -277.241)
			(xy 49.157389 -277.248397) (xy 49.149648 -277.266995) (xy 49.149254 -277.277068) (xy 49.149254 -277.472648)
			(xy 49.149687 -277.482713) (xy 49.15742 -277.5013) (xy 49.16424 -277.508716) (xy 49.18583 -277.530306)
			(xy 49.192644 -277.536504) (xy 49.209437 -277.544042) (xy 49.218596 -277.545038) (xy 49.242789 -277.546999)
			(xy 49.29015 -277.557612) (xy 49.335235 -277.575585) (xy 49.37691 -277.600463) (xy 49.414124 -277.631621)
			(xy 49.44594 -277.668274) (xy 49.471557 -277.709498) (xy 49.49033 -277.754256) (xy 49.501787 -277.80142)
			(xy 49.505638 -277.849802) (xy 49.503588 -277.875546) (xy 49.823112 -277.875546) (xy 49.823112 -277.82413)
			(xy 49.831155 -277.773348) (xy 49.847043 -277.724449) (xy 49.870386 -277.678637) (xy 49.900607 -277.637041)
			(xy 49.936963 -277.600685) (xy 49.978559 -277.570464) (xy 50.024371 -277.547121) (xy 50.07327 -277.531233)
			(xy 50.124052 -277.52319) (xy 50.175468 -277.52319) (xy 50.22625 -277.531233) (xy 50.275149 -277.547121)
			(xy 50.320961 -277.570464) (xy 50.362557 -277.600685) (xy 50.398913 -277.637041) (xy 50.429134 -277.678637)
			(xy 50.452477 -277.724449) (xy 50.468365 -277.773348) (xy 50.476408 -277.82413) (xy 50.476912 -277.849838)
			(xy 50.79417 -277.849838) (xy 50.79813 -277.800784) (xy 50.809907 -277.753) (xy 50.829198 -277.707724)
			(xy 50.855501 -277.666128) (xy 50.888136 -277.629291) (xy 50.926257 -277.598166) (xy 50.968878 -277.573559)
			(xy 51.014894 -277.556107) (xy 51.063113 -277.546263) (xy 51.112288 -277.544282) (xy 51.161143 -277.550214)
			(xy 51.208414 -277.563906) (xy 51.252876 -277.585004) (xy 51.293379 -277.61296) (xy 51.328872 -277.647052)
			(xy 51.358437 -277.686396) (xy 51.381308 -277.729973) (xy 51.396892 -277.776654) (xy 51.404787 -277.825231)
			(xy 51.405282 -277.849838) (xy 51.404787 -277.874445) (xy 51.404608 -277.875546) (xy 51.723286 -277.875546)
			(xy 51.723286 -277.82413) (xy 51.731329 -277.773348) (xy 51.747217 -277.724449) (xy 51.77056 -277.678637)
			(xy 51.800781 -277.637041) (xy 51.837137 -277.600685) (xy 51.878733 -277.570464) (xy 51.924545 -277.547121)
			(xy 51.973444 -277.531233) (xy 52.024226 -277.52319) (xy 52.075642 -277.52319) (xy 52.126424 -277.531233)
			(xy 52.175323 -277.547121) (xy 52.221135 -277.570464) (xy 52.262731 -277.600685) (xy 52.299087 -277.637041)
			(xy 52.329308 -277.678637) (xy 52.352651 -277.724449) (xy 52.368539 -277.773348) (xy 52.376582 -277.82413)
			(xy 52.377086 -277.849838) (xy 52.69409 -277.849838) (xy 52.69805 -277.800784) (xy 52.709827 -277.753)
			(xy 52.729118 -277.707724) (xy 52.755421 -277.666128) (xy 52.788056 -277.629291) (xy 52.826177 -277.598166)
			(xy 52.868798 -277.573559) (xy 52.914814 -277.556107) (xy 52.963033 -277.546263) (xy 53.012208 -277.544282)
			(xy 53.061063 -277.550214) (xy 53.108334 -277.563906) (xy 53.152796 -277.585004) (xy 53.193299 -277.61296)
			(xy 53.228792 -277.647052) (xy 53.258357 -277.686396) (xy 53.281228 -277.729973) (xy 53.296812 -277.776654)
			(xy 53.304707 -277.825231) (xy 53.305202 -277.849838) (xy 53.304707 -277.874445) (xy 53.304528 -277.875546)
			(xy 53.623206 -277.875546) (xy 53.623206 -277.82413) (xy 53.631249 -277.773348) (xy 53.647137 -277.724449)
			(xy 53.67048 -277.678637) (xy 53.700701 -277.637041) (xy 53.737057 -277.600685) (xy 53.778653 -277.570464)
			(xy 53.824465 -277.547121) (xy 53.873364 -277.531233) (xy 53.924146 -277.52319) (xy 53.975562 -277.52319)
			(xy 54.026344 -277.531233) (xy 54.075243 -277.547121) (xy 54.121055 -277.570464) (xy 54.162651 -277.600685)
			(xy 54.199007 -277.637041) (xy 54.229228 -277.678637) (xy 54.252571 -277.724449) (xy 54.268459 -277.773348)
			(xy 54.276502 -277.82413) (xy 54.277006 -277.849838) (xy 54.59401 -277.849838) (xy 54.59797 -277.800784)
			(xy 54.609747 -277.753) (xy 54.629038 -277.707724) (xy 54.655341 -277.666128) (xy 54.687976 -277.629291)
			(xy 54.726097 -277.598166) (xy 54.768718 -277.573559) (xy 54.814734 -277.556107) (xy 54.862953 -277.546263)
			(xy 54.912128 -277.544282) (xy 54.960983 -277.550214) (xy 55.008254 -277.563906) (xy 55.052716 -277.585004)
			(xy 55.093219 -277.61296) (xy 55.128712 -277.647052) (xy 55.158277 -277.686396) (xy 55.181148 -277.729973)
			(xy 55.196732 -277.776654) (xy 55.204627 -277.825231) (xy 55.205122 -277.849838) (xy 55.204627 -277.874445)
			(xy 55.204448 -277.875546) (xy 55.523126 -277.875546) (xy 55.523126 -277.82413) (xy 55.531169 -277.773348)
			(xy 55.547057 -277.724449) (xy 55.5704 -277.678637) (xy 55.600621 -277.637041) (xy 55.636977 -277.600685)
			(xy 55.678573 -277.570464) (xy 55.724385 -277.547121) (xy 55.773284 -277.531233) (xy 55.824066 -277.52319)
			(xy 55.875482 -277.52319) (xy 55.926264 -277.531233) (xy 55.975163 -277.547121) (xy 56.020975 -277.570464)
			(xy 56.062571 -277.600685) (xy 56.098927 -277.637041) (xy 56.129148 -277.678637) (xy 56.152491 -277.724449)
			(xy 56.168379 -277.773348) (xy 56.176422 -277.82413) (xy 56.176926 -277.849838) (xy 56.494184 -277.849838)
			(xy 56.498144 -277.800784) (xy 56.509921 -277.753) (xy 56.529212 -277.707724) (xy 56.555515 -277.666128)
			(xy 56.58815 -277.629291) (xy 56.626271 -277.598166) (xy 56.668892 -277.573559) (xy 56.714908 -277.556107)
			(xy 56.763127 -277.546263) (xy 56.812302 -277.544282) (xy 56.861157 -277.550214) (xy 56.908428 -277.563906)
			(xy 56.95289 -277.585004) (xy 56.993393 -277.61296) (xy 57.028886 -277.647052) (xy 57.058451 -277.686396)
			(xy 57.081322 -277.729973) (xy 57.096906 -277.776654) (xy 57.104801 -277.825231) (xy 57.105296 -277.849838)
			(xy 57.104801 -277.874445) (xy 57.104622 -277.875546) (xy 57.4233 -277.875546) (xy 57.4233 -277.82413)
			(xy 57.431343 -277.773348) (xy 57.447231 -277.724449) (xy 57.470574 -277.678637) (xy 57.500795 -277.637041)
			(xy 57.537151 -277.600685) (xy 57.578747 -277.570464) (xy 57.624559 -277.547121) (xy 57.673458 -277.531233)
			(xy 57.72424 -277.52319) (xy 57.775656 -277.52319) (xy 57.826438 -277.531233) (xy 57.875337 -277.547121)
			(xy 57.921149 -277.570464) (xy 57.962745 -277.600685) (xy 57.999101 -277.637041) (xy 58.029322 -277.678637)
			(xy 58.052665 -277.724449) (xy 58.068553 -277.773348) (xy 58.076596 -277.82413) (xy 58.0771 -277.849838)
			(xy 58.394104 -277.849838) (xy 58.398064 -277.800784) (xy 58.409841 -277.753) (xy 58.429132 -277.707724)
			(xy 58.455435 -277.666128) (xy 58.48807 -277.629291) (xy 58.526191 -277.598166) (xy 58.568812 -277.573559)
			(xy 58.614828 -277.556107) (xy 58.663047 -277.546263) (xy 58.712222 -277.544282) (xy 58.761077 -277.550214)
			(xy 58.808348 -277.563906) (xy 58.85281 -277.585004) (xy 58.893313 -277.61296) (xy 58.928806 -277.647052)
			(xy 58.958371 -277.686396) (xy 58.981242 -277.729973) (xy 58.996826 -277.776654) (xy 59.004721 -277.825231)
			(xy 59.005216 -277.849838) (xy 59.004721 -277.874445) (xy 59.004542 -277.875546) (xy 59.322966 -277.875546)
			(xy 59.322966 -277.82413) (xy 59.331009 -277.773348) (xy 59.346897 -277.724449) (xy 59.37024 -277.678637)
			(xy 59.400461 -277.637041) (xy 59.436817 -277.600685) (xy 59.478413 -277.570464) (xy 59.524225 -277.547121)
			(xy 59.573124 -277.531233) (xy 59.623906 -277.52319) (xy 59.675322 -277.52319) (xy 59.726104 -277.531233)
			(xy 59.775003 -277.547121) (xy 59.820815 -277.570464) (xy 59.862411 -277.600685) (xy 59.898767 -277.637041)
			(xy 59.928988 -277.678637) (xy 59.952331 -277.724449) (xy 59.968219 -277.773348) (xy 59.976262 -277.82413)
			(xy 59.976766 -277.849838) (xy 60.294024 -277.849838) (xy 60.297984 -277.800784) (xy 60.309761 -277.753)
			(xy 60.329052 -277.707724) (xy 60.355355 -277.666128) (xy 60.38799 -277.629291) (xy 60.426111 -277.598166)
			(xy 60.468732 -277.573559) (xy 60.514748 -277.556107) (xy 60.562967 -277.546263) (xy 60.612142 -277.544282)
			(xy 60.660997 -277.550214) (xy 60.708268 -277.563906) (xy 60.75273 -277.585004) (xy 60.793233 -277.61296)
			(xy 60.828726 -277.647052) (xy 60.858291 -277.686396) (xy 60.881162 -277.729973) (xy 60.896746 -277.776654)
			(xy 60.904641 -277.825231) (xy 60.905136 -277.849838) (xy 60.904641 -277.874445) (xy 60.904462 -277.875546)
			(xy 61.222886 -277.875546) (xy 61.222886 -277.82413) (xy 61.230929 -277.773348) (xy 61.246817 -277.724449)
			(xy 61.27016 -277.678637) (xy 61.300381 -277.637041) (xy 61.336737 -277.600685) (xy 61.378333 -277.570464)
			(xy 61.424145 -277.547121) (xy 61.473044 -277.531233) (xy 61.523826 -277.52319) (xy 61.575242 -277.52319)
			(xy 61.626024 -277.531233) (xy 61.674923 -277.547121) (xy 61.720735 -277.570464) (xy 61.762331 -277.600685)
			(xy 61.798687 -277.637041) (xy 61.828908 -277.678637) (xy 61.852251 -277.724449) (xy 61.868139 -277.773348)
			(xy 61.876182 -277.82413) (xy 61.876686 -277.849838) (xy 62.193944 -277.849838) (xy 62.197904 -277.800784)
			(xy 62.209681 -277.753) (xy 62.228972 -277.707724) (xy 62.255275 -277.666128) (xy 62.28791 -277.629291)
			(xy 62.326031 -277.598166) (xy 62.368652 -277.573559) (xy 62.414668 -277.556107) (xy 62.462887 -277.546263)
			(xy 62.512062 -277.544282) (xy 62.560917 -277.550214) (xy 62.608188 -277.563906) (xy 62.65265 -277.585004)
			(xy 62.693153 -277.61296) (xy 62.728646 -277.647052) (xy 62.758211 -277.686396) (xy 62.781082 -277.729973)
			(xy 62.796666 -277.776654) (xy 62.804561 -277.825231) (xy 62.805056 -277.849838) (xy 62.804561 -277.874445)
			(xy 62.804382 -277.875546) (xy 63.12306 -277.875546) (xy 63.12306 -277.82413) (xy 63.131103 -277.773348)
			(xy 63.146991 -277.724449) (xy 63.170334 -277.678637) (xy 63.200555 -277.637041) (xy 63.236911 -277.600685)
			(xy 63.278507 -277.570464) (xy 63.324319 -277.547121) (xy 63.373218 -277.531233) (xy 63.424 -277.52319)
			(xy 63.475416 -277.52319) (xy 63.526198 -277.531233) (xy 63.575097 -277.547121) (xy 63.620909 -277.570464)
			(xy 63.662505 -277.600685) (xy 63.698861 -277.637041) (xy 63.729082 -277.678637) (xy 63.752425 -277.724449)
			(xy 63.768313 -277.773348) (xy 63.776356 -277.82413) (xy 63.77686 -277.849838) (xy 64.094118 -277.849838)
			(xy 64.098078 -277.800784) (xy 64.109855 -277.753) (xy 64.129146 -277.707724) (xy 64.155449 -277.666128)
			(xy 64.188084 -277.629291) (xy 64.226205 -277.598166) (xy 64.268826 -277.573559) (xy 64.314842 -277.556107)
			(xy 64.363061 -277.546263) (xy 64.412236 -277.544282) (xy 64.461091 -277.550214) (xy 64.508362 -277.563906)
			(xy 64.552824 -277.585004) (xy 64.593327 -277.61296) (xy 64.62882 -277.647052) (xy 64.658385 -277.686396)
			(xy 64.681256 -277.729973) (xy 64.69684 -277.776654) (xy 64.704735 -277.825231) (xy 64.70523 -277.849838)
			(xy 64.704735 -277.874445) (xy 64.704556 -277.875546) (xy 65.02298 -277.875546) (xy 65.02298 -277.82413)
			(xy 65.031023 -277.773348) (xy 65.046911 -277.724449) (xy 65.070254 -277.678637) (xy 65.100475 -277.637041)
			(xy 65.136831 -277.600685) (xy 65.178427 -277.570464) (xy 65.224239 -277.547121) (xy 65.273138 -277.531233)
			(xy 65.32392 -277.52319) (xy 65.375336 -277.52319) (xy 65.426118 -277.531233) (xy 65.475017 -277.547121)
			(xy 65.520829 -277.570464) (xy 65.562425 -277.600685) (xy 65.598781 -277.637041) (xy 65.629002 -277.678637)
			(xy 65.652345 -277.724449) (xy 65.668233 -277.773348) (xy 65.676276 -277.82413) (xy 65.67678 -277.849838)
			(xy 65.994038 -277.849838) (xy 65.997998 -277.800784) (xy 66.009775 -277.753) (xy 66.029066 -277.707724)
			(xy 66.055369 -277.666128) (xy 66.088004 -277.629291) (xy 66.126125 -277.598166) (xy 66.168746 -277.573559)
			(xy 66.214762 -277.556107) (xy 66.262981 -277.546263) (xy 66.312156 -277.544282) (xy 66.361011 -277.550214)
			(xy 66.408282 -277.563906) (xy 66.452744 -277.585004) (xy 66.493247 -277.61296) (xy 66.52874 -277.647052)
			(xy 66.558305 -277.686396) (xy 66.581176 -277.729973) (xy 66.59676 -277.776654) (xy 66.604655 -277.825231)
			(xy 66.60515 -277.849838) (xy 66.604655 -277.874445) (xy 66.604476 -277.875546) (xy 66.9229 -277.875546)
			(xy 66.9229 -277.82413) (xy 66.930943 -277.773348) (xy 66.946831 -277.724449) (xy 66.970174 -277.678637)
			(xy 67.000395 -277.637041) (xy 67.036751 -277.600685) (xy 67.078347 -277.570464) (xy 67.124159 -277.547121)
			(xy 67.173058 -277.531233) (xy 67.22384 -277.52319) (xy 67.275256 -277.52319) (xy 67.326038 -277.531233)
			(xy 67.374937 -277.547121) (xy 67.420749 -277.570464) (xy 67.462345 -277.600685) (xy 67.498701 -277.637041)
			(xy 67.528922 -277.678637) (xy 67.552265 -277.724449) (xy 67.568153 -277.773348) (xy 67.576196 -277.82413)
			(xy 67.5767 -277.849838) (xy 67.893958 -277.849838) (xy 67.897918 -277.800784) (xy 67.909695 -277.753)
			(xy 67.928986 -277.707724) (xy 67.955289 -277.666128) (xy 67.987924 -277.629291) (xy 68.026045 -277.598166)
			(xy 68.068666 -277.573559) (xy 68.114682 -277.556107) (xy 68.162901 -277.546263) (xy 68.212076 -277.544282)
			(xy 68.260931 -277.550214) (xy 68.308202 -277.563906) (xy 68.352664 -277.585004) (xy 68.393167 -277.61296)
			(xy 68.42866 -277.647052) (xy 68.458225 -277.686396) (xy 68.481096 -277.729973) (xy 68.49668 -277.776654)
			(xy 68.504575 -277.825231) (xy 68.50507 -277.849838) (xy 68.504575 -277.874445) (xy 68.504396 -277.875546)
			(xy 68.823074 -277.875546) (xy 68.823074 -277.82413) (xy 68.831117 -277.773348) (xy 68.847005 -277.724449)
			(xy 68.870348 -277.678637) (xy 68.900569 -277.637041) (xy 68.936925 -277.600685) (xy 68.978521 -277.570464)
			(xy 69.024333 -277.547121) (xy 69.073232 -277.531233) (xy 69.124014 -277.52319) (xy 69.17543 -277.52319)
			(xy 69.226212 -277.531233) (xy 69.275111 -277.547121) (xy 69.320923 -277.570464) (xy 69.362519 -277.600685)
			(xy 69.398875 -277.637041) (xy 69.429096 -277.678637) (xy 69.452439 -277.724449) (xy 69.468327 -277.773348)
			(xy 69.47637 -277.82413) (xy 69.476874 -277.849838) (xy 69.794132 -277.849838) (xy 69.798092 -277.800784)
			(xy 69.809869 -277.753) (xy 69.82916 -277.707724) (xy 69.855463 -277.666128) (xy 69.888098 -277.629291)
			(xy 69.926219 -277.598166) (xy 69.96884 -277.573559) (xy 70.014856 -277.556107) (xy 70.063075 -277.546263)
			(xy 70.11225 -277.544282) (xy 70.161105 -277.550214) (xy 70.208376 -277.563906) (xy 70.252838 -277.585004)
			(xy 70.293341 -277.61296) (xy 70.328834 -277.647052) (xy 70.358399 -277.686396) (xy 70.38127 -277.729973)
			(xy 70.396854 -277.776654) (xy 70.404749 -277.825231) (xy 70.405244 -277.849838) (xy 70.404749 -277.874445)
			(xy 70.40457 -277.875546) (xy 70.722994 -277.875546) (xy 70.722994 -277.82413) (xy 70.731037 -277.773348)
			(xy 70.746925 -277.724449) (xy 70.770268 -277.678637) (xy 70.800489 -277.637041) (xy 70.836845 -277.600685)
			(xy 70.878441 -277.570464) (xy 70.924253 -277.547121) (xy 70.973152 -277.531233) (xy 71.023934 -277.52319)
			(xy 71.07535 -277.52319) (xy 71.126132 -277.531233) (xy 71.175031 -277.547121) (xy 71.220843 -277.570464)
			(xy 71.262439 -277.600685) (xy 71.298795 -277.637041) (xy 71.329016 -277.678637) (xy 71.352359 -277.724449)
			(xy 71.368247 -277.773348) (xy 71.37629 -277.82413) (xy 71.376794 -277.849838) (xy 71.694052 -277.849838)
			(xy 71.698012 -277.800784) (xy 71.709789 -277.753) (xy 71.72908 -277.707724) (xy 71.755383 -277.666128)
			(xy 71.788018 -277.629291) (xy 71.826139 -277.598166) (xy 71.86876 -277.573559) (xy 71.914776 -277.556107)
			(xy 71.962995 -277.546263) (xy 72.01217 -277.544282) (xy 72.061025 -277.550214) (xy 72.108296 -277.563906)
			(xy 72.152758 -277.585004) (xy 72.193261 -277.61296) (xy 72.228754 -277.647052) (xy 72.258319 -277.686396)
			(xy 72.28119 -277.729973) (xy 72.296774 -277.776654) (xy 72.304669 -277.825231) (xy 72.305164 -277.849838)
			(xy 72.304669 -277.874445) (xy 72.30449 -277.875546) (xy 72.622914 -277.875546) (xy 72.622914 -277.82413)
			(xy 72.630957 -277.773348) (xy 72.646845 -277.724449) (xy 72.670188 -277.678637) (xy 72.700409 -277.637041)
			(xy 72.736765 -277.600685) (xy 72.778361 -277.570464) (xy 72.824173 -277.547121) (xy 72.873072 -277.531233)
			(xy 72.923854 -277.52319) (xy 72.97527 -277.52319) (xy 73.026052 -277.531233) (xy 73.074951 -277.547121)
			(xy 73.120763 -277.570464) (xy 73.162359 -277.600685) (xy 73.198715 -277.637041) (xy 73.228936 -277.678637)
			(xy 73.252279 -277.724449) (xy 73.268167 -277.773348) (xy 73.27621 -277.82413) (xy 73.276714 -277.849838)
			(xy 73.593972 -277.849838) (xy 73.597932 -277.800784) (xy 73.609709 -277.753) (xy 73.629 -277.707724)
			(xy 73.655303 -277.666128) (xy 73.687938 -277.629291) (xy 73.726059 -277.598166) (xy 73.76868 -277.573559)
			(xy 73.814696 -277.556107) (xy 73.862915 -277.546263) (xy 73.91209 -277.544282) (xy 73.960945 -277.550214)
			(xy 74.008216 -277.563906) (xy 74.052678 -277.585004) (xy 74.093181 -277.61296) (xy 74.128674 -277.647052)
			(xy 74.158239 -277.686396) (xy 74.18111 -277.729973) (xy 74.196694 -277.776654) (xy 74.204589 -277.825231)
			(xy 74.205084 -277.849838) (xy 74.204589 -277.874445) (xy 74.20441 -277.875546) (xy 74.523088 -277.875546)
			(xy 74.523088 -277.82413) (xy 74.531131 -277.773348) (xy 74.547019 -277.724449) (xy 74.570362 -277.678637)
			(xy 74.600583 -277.637041) (xy 74.636939 -277.600685) (xy 74.678535 -277.570464) (xy 74.724347 -277.547121)
			(xy 74.773246 -277.531233) (xy 74.824028 -277.52319) (xy 74.875444 -277.52319) (xy 74.926226 -277.531233)
			(xy 74.975125 -277.547121) (xy 75.020937 -277.570464) (xy 75.062533 -277.600685) (xy 75.098889 -277.637041)
			(xy 75.12911 -277.678637) (xy 75.152453 -277.724449) (xy 75.168341 -277.773348) (xy 75.176384 -277.82413)
			(xy 75.176888 -277.849838) (xy 75.494146 -277.849838) (xy 75.498106 -277.800784) (xy 75.509883 -277.753)
			(xy 75.529174 -277.707724) (xy 75.555477 -277.666128) (xy 75.588112 -277.629291) (xy 75.626233 -277.598166)
			(xy 75.668854 -277.573559) (xy 75.71487 -277.556107) (xy 75.763089 -277.546263) (xy 75.812264 -277.544282)
			(xy 75.861119 -277.550214) (xy 75.90839 -277.563906) (xy 75.952852 -277.585004) (xy 75.993355 -277.61296)
			(xy 76.028848 -277.647052) (xy 76.058413 -277.686396) (xy 76.081284 -277.729973) (xy 76.096868 -277.776654)
			(xy 76.104763 -277.825231) (xy 76.105258 -277.849838) (xy 76.104763 -277.874445) (xy 76.104584 -277.875546)
			(xy 76.423008 -277.875546) (xy 76.423008 -277.82413) (xy 76.431051 -277.773348) (xy 76.446939 -277.724449)
			(xy 76.470282 -277.678637) (xy 76.500503 -277.637041) (xy 76.536859 -277.600685) (xy 76.578455 -277.570464)
			(xy 76.624267 -277.547121) (xy 76.673166 -277.531233) (xy 76.723948 -277.52319) (xy 76.775364 -277.52319)
			(xy 76.826146 -277.531233) (xy 76.875045 -277.547121) (xy 76.920857 -277.570464) (xy 76.962453 -277.600685)
			(xy 76.998809 -277.637041) (xy 77.02903 -277.678637) (xy 77.052373 -277.724449) (xy 77.068261 -277.773348)
			(xy 77.076304 -277.82413) (xy 77.076808 -277.849838) (xy 77.394066 -277.849838) (xy 77.398026 -277.800784)
			(xy 77.409803 -277.753) (xy 77.429094 -277.707724) (xy 77.455397 -277.666128) (xy 77.488032 -277.629291)
			(xy 77.526153 -277.598166) (xy 77.568774 -277.573559) (xy 77.61479 -277.556107) (xy 77.663009 -277.546263)
			(xy 77.712184 -277.544282) (xy 77.761039 -277.550214) (xy 77.80831 -277.563906) (xy 77.852772 -277.585004)
			(xy 77.893275 -277.61296) (xy 77.928768 -277.647052) (xy 77.958333 -277.686396) (xy 77.981204 -277.729973)
			(xy 77.996788 -277.776654) (xy 78.004683 -277.825231) (xy 78.005178 -277.849838) (xy 78.004683 -277.874445)
			(xy 78.004504 -277.875546) (xy 78.322928 -277.875546) (xy 78.322928 -277.82413) (xy 78.330971 -277.773348)
			(xy 78.346859 -277.724449) (xy 78.370202 -277.678637) (xy 78.400423 -277.637041) (xy 78.436779 -277.600685)
			(xy 78.478375 -277.570464) (xy 78.524187 -277.547121) (xy 78.573086 -277.531233) (xy 78.623868 -277.52319)
			(xy 78.675284 -277.52319) (xy 78.726066 -277.531233) (xy 78.774965 -277.547121) (xy 78.820777 -277.570464)
			(xy 78.862373 -277.600685) (xy 78.898729 -277.637041) (xy 78.92895 -277.678637) (xy 78.952293 -277.724449)
			(xy 78.968181 -277.773348) (xy 78.976224 -277.82413) (xy 78.976728 -277.849838) (xy 79.293986 -277.849838)
			(xy 79.297946 -277.800784) (xy 79.309723 -277.753) (xy 79.329014 -277.707724) (xy 79.355317 -277.666128)
			(xy 79.387952 -277.629291) (xy 79.426073 -277.598166) (xy 79.468694 -277.573559) (xy 79.51471 -277.556107)
			(xy 79.562929 -277.546263) (xy 79.612104 -277.544282) (xy 79.660959 -277.550214) (xy 79.70823 -277.563906)
			(xy 79.752692 -277.585004) (xy 79.793195 -277.61296) (xy 79.828688 -277.647052) (xy 79.858253 -277.686396)
			(xy 79.881124 -277.729973) (xy 79.896708 -277.776654) (xy 79.904603 -277.825231) (xy 79.905098 -277.849838)
			(xy 79.904603 -277.874445) (xy 79.904424 -277.875546) (xy 80.223102 -277.875546) (xy 80.223102 -277.82413)
			(xy 80.231145 -277.773348) (xy 80.247033 -277.724449) (xy 80.270376 -277.678637) (xy 80.300597 -277.637041)
			(xy 80.336953 -277.600685) (xy 80.378549 -277.570464) (xy 80.424361 -277.547121) (xy 80.47326 -277.531233)
			(xy 80.524042 -277.52319) (xy 80.575458 -277.52319) (xy 80.62624 -277.531233) (xy 80.675139 -277.547121)
			(xy 80.720951 -277.570464) (xy 80.762547 -277.600685) (xy 80.798903 -277.637041) (xy 80.829124 -277.678637)
			(xy 80.852467 -277.724449) (xy 80.868355 -277.773348) (xy 80.876398 -277.82413) (xy 80.876902 -277.849838)
			(xy 81.19416 -277.849838) (xy 81.19812 -277.800784) (xy 81.209897 -277.753) (xy 81.229188 -277.707724)
			(xy 81.255491 -277.666128) (xy 81.288126 -277.629291) (xy 81.326247 -277.598166) (xy 81.368868 -277.573559)
			(xy 81.414884 -277.556107) (xy 81.463103 -277.546263) (xy 81.512278 -277.544282) (xy 81.561133 -277.550214)
			(xy 81.608404 -277.563906) (xy 81.652866 -277.585004) (xy 81.693369 -277.61296) (xy 81.728862 -277.647052)
			(xy 81.758427 -277.686396) (xy 81.781298 -277.729973) (xy 81.796882 -277.776654) (xy 81.804777 -277.825231)
			(xy 81.805272 -277.849838) (xy 82.14412 -277.849838) (xy 82.14808 -277.800784) (xy 82.159857 -277.753)
			(xy 82.179148 -277.707724) (xy 82.205451 -277.666128) (xy 82.238086 -277.629291) (xy 82.276207 -277.598166)
			(xy 82.318828 -277.573559) (xy 82.364844 -277.556107) (xy 82.413063 -277.546263) (xy 82.462238 -277.544282)
			(xy 82.511093 -277.550214) (xy 82.558364 -277.563906) (xy 82.602826 -277.585004) (xy 82.643329 -277.61296)
			(xy 82.678822 -277.647052) (xy 82.708387 -277.686396) (xy 82.731258 -277.729973) (xy 82.746842 -277.776654)
			(xy 82.754737 -277.825231) (xy 82.755232 -277.849838) (xy 82.754737 -277.874445) (xy 82.746842 -277.923022)
			(xy 82.731258 -277.969703) (xy 82.708387 -278.01328) (xy 82.678822 -278.052624) (xy 82.643329 -278.086716)
			(xy 82.602826 -278.114672) (xy 82.558364 -278.13577) (xy 82.511093 -278.149462) (xy 82.462238 -278.155394)
			(xy 82.413063 -278.153413) (xy 82.364844 -278.143569) (xy 82.318828 -278.126117) (xy 82.276207 -278.10151)
			(xy 82.238086 -278.070385) (xy 82.205451 -278.033548) (xy 82.179148 -277.991952) (xy 82.159857 -277.946676)
			(xy 82.14808 -277.898892) (xy 82.14412 -277.849838) (xy 81.805272 -277.849838) (xy 81.804777 -277.874445)
			(xy 81.796882 -277.923022) (xy 81.781298 -277.969703) (xy 81.758427 -278.01328) (xy 81.728862 -278.052624)
			(xy 81.693369 -278.086716) (xy 81.652866 -278.114672) (xy 81.608404 -278.13577) (xy 81.561133 -278.149462)
			(xy 81.512278 -278.155394) (xy 81.463103 -278.153413) (xy 81.414884 -278.143569) (xy 81.368868 -278.126117)
			(xy 81.326247 -278.10151) (xy 81.288126 -278.070385) (xy 81.255491 -278.033548) (xy 81.229188 -277.991952)
			(xy 81.209897 -277.946676) (xy 81.19812 -277.898892) (xy 81.19416 -277.849838) (xy 80.876902 -277.849838)
			(xy 80.876398 -277.875546) (xy 80.868355 -277.926328) (xy 80.852467 -277.975227) (xy 80.829124 -278.021039)
			(xy 80.798903 -278.062635) (xy 80.762547 -278.098991) (xy 80.720951 -278.129212) (xy 80.675139 -278.152555)
			(xy 80.62624 -278.168443) (xy 80.575458 -278.176486) (xy 80.524042 -278.176486) (xy 80.47326 -278.168443)
			(xy 80.424361 -278.152555) (xy 80.378549 -278.129212) (xy 80.336953 -278.098991) (xy 80.300597 -278.062635)
			(xy 80.270376 -278.021039) (xy 80.247033 -277.975227) (xy 80.231145 -277.926328) (xy 80.223102 -277.875546)
			(xy 79.904424 -277.875546) (xy 79.896708 -277.923022) (xy 79.881124 -277.969703) (xy 79.858253 -278.01328)
			(xy 79.828688 -278.052624) (xy 79.793195 -278.086716) (xy 79.752692 -278.114672) (xy 79.70823 -278.13577)
			(xy 79.660959 -278.149462) (xy 79.612104 -278.155394) (xy 79.562929 -278.153413) (xy 79.51471 -278.143569)
			(xy 79.468694 -278.126117) (xy 79.426073 -278.10151) (xy 79.387952 -278.070385) (xy 79.355317 -278.033548)
			(xy 79.329014 -277.991952) (xy 79.309723 -277.946676) (xy 79.297946 -277.898892) (xy 79.293986 -277.849838)
			(xy 78.976728 -277.849838) (xy 78.976224 -277.875546) (xy 78.968181 -277.926328) (xy 78.952293 -277.975227)
			(xy 78.92895 -278.021039) (xy 78.898729 -278.062635) (xy 78.862373 -278.098991) (xy 78.820777 -278.129212)
			(xy 78.774965 -278.152555) (xy 78.726066 -278.168443) (xy 78.675284 -278.176486) (xy 78.623868 -278.176486)
			(xy 78.573086 -278.168443) (xy 78.524187 -278.152555) (xy 78.478375 -278.129212) (xy 78.436779 -278.098991)
			(xy 78.400423 -278.062635) (xy 78.370202 -278.021039) (xy 78.346859 -277.975227) (xy 78.330971 -277.926328)
			(xy 78.322928 -277.875546) (xy 78.004504 -277.875546) (xy 77.996788 -277.923022) (xy 77.981204 -277.969703)
			(xy 77.958333 -278.01328) (xy 77.928768 -278.052624) (xy 77.893275 -278.086716) (xy 77.852772 -278.114672)
			(xy 77.80831 -278.13577) (xy 77.761039 -278.149462) (xy 77.712184 -278.155394) (xy 77.663009 -278.153413)
			(xy 77.61479 -278.143569) (xy 77.568774 -278.126117) (xy 77.526153 -278.10151) (xy 77.488032 -278.070385)
			(xy 77.455397 -278.033548) (xy 77.429094 -277.991952) (xy 77.409803 -277.946676) (xy 77.398026 -277.898892)
			(xy 77.394066 -277.849838) (xy 77.076808 -277.849838) (xy 77.076304 -277.875546) (xy 77.068261 -277.926328)
			(xy 77.052373 -277.975227) (xy 77.02903 -278.021039) (xy 76.998809 -278.062635) (xy 76.962453 -278.098991)
			(xy 76.920857 -278.129212) (xy 76.875045 -278.152555) (xy 76.826146 -278.168443) (xy 76.775364 -278.176486)
			(xy 76.723948 -278.176486) (xy 76.673166 -278.168443) (xy 76.624267 -278.152555) (xy 76.578455 -278.129212)
			(xy 76.536859 -278.098991) (xy 76.500503 -278.062635) (xy 76.470282 -278.021039) (xy 76.446939 -277.975227)
			(xy 76.431051 -277.926328) (xy 76.423008 -277.875546) (xy 76.104584 -277.875546) (xy 76.096868 -277.923022)
			(xy 76.081284 -277.969703) (xy 76.058413 -278.01328) (xy 76.028848 -278.052624) (xy 75.993355 -278.086716)
			(xy 75.952852 -278.114672) (xy 75.90839 -278.13577) (xy 75.861119 -278.149462) (xy 75.812264 -278.155394)
			(xy 75.763089 -278.153413) (xy 75.71487 -278.143569) (xy 75.668854 -278.126117) (xy 75.626233 -278.10151)
			(xy 75.588112 -278.070385) (xy 75.555477 -278.033548) (xy 75.529174 -277.991952) (xy 75.509883 -277.946676)
			(xy 75.498106 -277.898892) (xy 75.494146 -277.849838) (xy 75.176888 -277.849838) (xy 75.176384 -277.875546)
			(xy 75.168341 -277.926328) (xy 75.152453 -277.975227) (xy 75.12911 -278.021039) (xy 75.098889 -278.062635)
			(xy 75.062533 -278.098991) (xy 75.020937 -278.129212) (xy 74.975125 -278.152555) (xy 74.926226 -278.168443)
			(xy 74.875444 -278.176486) (xy 74.824028 -278.176486) (xy 74.773246 -278.168443) (xy 74.724347 -278.152555)
			(xy 74.678535 -278.129212) (xy 74.636939 -278.098991) (xy 74.600583 -278.062635) (xy 74.570362 -278.021039)
			(xy 74.547019 -277.975227) (xy 74.531131 -277.926328) (xy 74.523088 -277.875546) (xy 74.20441 -277.875546)
			(xy 74.196694 -277.923022) (xy 74.18111 -277.969703) (xy 74.158239 -278.01328) (xy 74.128674 -278.052624)
			(xy 74.093181 -278.086716) (xy 74.052678 -278.114672) (xy 74.008216 -278.13577) (xy 73.960945 -278.149462)
			(xy 73.91209 -278.155394) (xy 73.862915 -278.153413) (xy 73.814696 -278.143569) (xy 73.76868 -278.126117)
			(xy 73.726059 -278.10151) (xy 73.687938 -278.070385) (xy 73.655303 -278.033548) (xy 73.629 -277.991952)
			(xy 73.609709 -277.946676) (xy 73.597932 -277.898892) (xy 73.593972 -277.849838) (xy 73.276714 -277.849838)
			(xy 73.27621 -277.875546) (xy 73.268167 -277.926328) (xy 73.252279 -277.975227) (xy 73.228936 -278.021039)
			(xy 73.198715 -278.062635) (xy 73.162359 -278.098991) (xy 73.120763 -278.129212) (xy 73.074951 -278.152555)
			(xy 73.026052 -278.168443) (xy 72.97527 -278.176486) (xy 72.923854 -278.176486) (xy 72.873072 -278.168443)
			(xy 72.824173 -278.152555) (xy 72.778361 -278.129212) (xy 72.736765 -278.098991) (xy 72.700409 -278.062635)
			(xy 72.670188 -278.021039) (xy 72.646845 -277.975227) (xy 72.630957 -277.926328) (xy 72.622914 -277.875546)
			(xy 72.30449 -277.875546) (xy 72.296774 -277.923022) (xy 72.28119 -277.969703) (xy 72.258319 -278.01328)
			(xy 72.228754 -278.052624) (xy 72.193261 -278.086716) (xy 72.152758 -278.114672) (xy 72.108296 -278.13577)
			(xy 72.061025 -278.149462) (xy 72.01217 -278.155394) (xy 71.962995 -278.153413) (xy 71.914776 -278.143569)
			(xy 71.86876 -278.126117) (xy 71.826139 -278.10151) (xy 71.788018 -278.070385) (xy 71.755383 -278.033548)
			(xy 71.72908 -277.991952) (xy 71.709789 -277.946676) (xy 71.698012 -277.898892) (xy 71.694052 -277.849838)
			(xy 71.376794 -277.849838) (xy 71.37629 -277.875546) (xy 71.368247 -277.926328) (xy 71.352359 -277.975227)
			(xy 71.329016 -278.021039) (xy 71.298795 -278.062635) (xy 71.262439 -278.098991) (xy 71.220843 -278.129212)
			(xy 71.175031 -278.152555) (xy 71.126132 -278.168443) (xy 71.07535 -278.176486) (xy 71.023934 -278.176486)
			(xy 70.973152 -278.168443) (xy 70.924253 -278.152555) (xy 70.878441 -278.129212) (xy 70.836845 -278.098991)
			(xy 70.800489 -278.062635) (xy 70.770268 -278.021039) (xy 70.746925 -277.975227) (xy 70.731037 -277.926328)
			(xy 70.722994 -277.875546) (xy 70.40457 -277.875546) (xy 70.396854 -277.923022) (xy 70.38127 -277.969703)
			(xy 70.358399 -278.01328) (xy 70.328834 -278.052624) (xy 70.293341 -278.086716) (xy 70.252838 -278.114672)
			(xy 70.208376 -278.13577) (xy 70.161105 -278.149462) (xy 70.11225 -278.155394) (xy 70.063075 -278.153413)
			(xy 70.014856 -278.143569) (xy 69.96884 -278.126117) (xy 69.926219 -278.10151) (xy 69.888098 -278.070385)
			(xy 69.855463 -278.033548) (xy 69.82916 -277.991952) (xy 69.809869 -277.946676) (xy 69.798092 -277.898892)
			(xy 69.794132 -277.849838) (xy 69.476874 -277.849838) (xy 69.47637 -277.875546) (xy 69.468327 -277.926328)
			(xy 69.452439 -277.975227) (xy 69.429096 -278.021039) (xy 69.398875 -278.062635) (xy 69.362519 -278.098991)
			(xy 69.320923 -278.129212) (xy 69.275111 -278.152555) (xy 69.226212 -278.168443) (xy 69.17543 -278.176486)
			(xy 69.124014 -278.176486) (xy 69.073232 -278.168443) (xy 69.024333 -278.152555) (xy 68.978521 -278.129212)
			(xy 68.936925 -278.098991) (xy 68.900569 -278.062635) (xy 68.870348 -278.021039) (xy 68.847005 -277.975227)
			(xy 68.831117 -277.926328) (xy 68.823074 -277.875546) (xy 68.504396 -277.875546) (xy 68.49668 -277.923022)
			(xy 68.481096 -277.969703) (xy 68.458225 -278.01328) (xy 68.42866 -278.052624) (xy 68.393167 -278.086716)
			(xy 68.352664 -278.114672) (xy 68.308202 -278.13577) (xy 68.260931 -278.149462) (xy 68.212076 -278.155394)
			(xy 68.162901 -278.153413) (xy 68.114682 -278.143569) (xy 68.068666 -278.126117) (xy 68.026045 -278.10151)
			(xy 67.987924 -278.070385) (xy 67.955289 -278.033548) (xy 67.928986 -277.991952) (xy 67.909695 -277.946676)
			(xy 67.897918 -277.898892) (xy 67.893958 -277.849838) (xy 67.5767 -277.849838) (xy 67.576196 -277.875546)
			(xy 67.568153 -277.926328) (xy 67.552265 -277.975227) (xy 67.528922 -278.021039) (xy 67.498701 -278.062635)
			(xy 67.462345 -278.098991) (xy 67.420749 -278.129212) (xy 67.374937 -278.152555) (xy 67.326038 -278.168443)
			(xy 67.275256 -278.176486) (xy 67.22384 -278.176486) (xy 67.173058 -278.168443) (xy 67.124159 -278.152555)
			(xy 67.078347 -278.129212) (xy 67.036751 -278.098991) (xy 67.000395 -278.062635) (xy 66.970174 -278.021039)
			(xy 66.946831 -277.975227) (xy 66.930943 -277.926328) (xy 66.9229 -277.875546) (xy 66.604476 -277.875546)
			(xy 66.59676 -277.923022) (xy 66.581176 -277.969703) (xy 66.558305 -278.01328) (xy 66.52874 -278.052624)
			(xy 66.493247 -278.086716) (xy 66.452744 -278.114672) (xy 66.408282 -278.13577) (xy 66.361011 -278.149462)
			(xy 66.312156 -278.155394) (xy 66.262981 -278.153413) (xy 66.214762 -278.143569) (xy 66.168746 -278.126117)
			(xy 66.126125 -278.10151) (xy 66.088004 -278.070385) (xy 66.055369 -278.033548) (xy 66.029066 -277.991952)
			(xy 66.009775 -277.946676) (xy 65.997998 -277.898892) (xy 65.994038 -277.849838) (xy 65.67678 -277.849838)
			(xy 65.676276 -277.875546) (xy 65.668233 -277.926328) (xy 65.652345 -277.975227) (xy 65.629002 -278.021039)
			(xy 65.598781 -278.062635) (xy 65.562425 -278.098991) (xy 65.520829 -278.129212) (xy 65.475017 -278.152555)
			(xy 65.426118 -278.168443) (xy 65.375336 -278.176486) (xy 65.32392 -278.176486) (xy 65.273138 -278.168443)
			(xy 65.224239 -278.152555) (xy 65.178427 -278.129212) (xy 65.136831 -278.098991) (xy 65.100475 -278.062635)
			(xy 65.070254 -278.021039) (xy 65.046911 -277.975227) (xy 65.031023 -277.926328) (xy 65.02298 -277.875546)
			(xy 64.704556 -277.875546) (xy 64.69684 -277.923022) (xy 64.681256 -277.969703) (xy 64.658385 -278.01328)
			(xy 64.62882 -278.052624) (xy 64.593327 -278.086716) (xy 64.552824 -278.114672) (xy 64.508362 -278.13577)
			(xy 64.461091 -278.149462) (xy 64.412236 -278.155394) (xy 64.363061 -278.153413) (xy 64.314842 -278.143569)
			(xy 64.268826 -278.126117) (xy 64.226205 -278.10151) (xy 64.188084 -278.070385) (xy 64.155449 -278.033548)
			(xy 64.129146 -277.991952) (xy 64.109855 -277.946676) (xy 64.098078 -277.898892) (xy 64.094118 -277.849838)
			(xy 63.77686 -277.849838) (xy 63.776356 -277.875546) (xy 63.768313 -277.926328) (xy 63.752425 -277.975227)
			(xy 63.729082 -278.021039) (xy 63.698861 -278.062635) (xy 63.662505 -278.098991) (xy 63.620909 -278.129212)
			(xy 63.575097 -278.152555) (xy 63.526198 -278.168443) (xy 63.475416 -278.176486) (xy 63.424 -278.176486)
			(xy 63.373218 -278.168443) (xy 63.324319 -278.152555) (xy 63.278507 -278.129212) (xy 63.236911 -278.098991)
			(xy 63.200555 -278.062635) (xy 63.170334 -278.021039) (xy 63.146991 -277.975227) (xy 63.131103 -277.926328)
			(xy 63.12306 -277.875546) (xy 62.804382 -277.875546) (xy 62.796666 -277.923022) (xy 62.781082 -277.969703)
			(xy 62.758211 -278.01328) (xy 62.728646 -278.052624) (xy 62.693153 -278.086716) (xy 62.65265 -278.114672)
			(xy 62.608188 -278.13577) (xy 62.560917 -278.149462) (xy 62.512062 -278.155394) (xy 62.462887 -278.153413)
			(xy 62.414668 -278.143569) (xy 62.368652 -278.126117) (xy 62.326031 -278.10151) (xy 62.28791 -278.070385)
			(xy 62.255275 -278.033548) (xy 62.228972 -277.991952) (xy 62.209681 -277.946676) (xy 62.197904 -277.898892)
			(xy 62.193944 -277.849838) (xy 61.876686 -277.849838) (xy 61.876182 -277.875546) (xy 61.868139 -277.926328)
			(xy 61.852251 -277.975227) (xy 61.828908 -278.021039) (xy 61.798687 -278.062635) (xy 61.762331 -278.098991)
			(xy 61.720735 -278.129212) (xy 61.674923 -278.152555) (xy 61.626024 -278.168443) (xy 61.575242 -278.176486)
			(xy 61.523826 -278.176486) (xy 61.473044 -278.168443) (xy 61.424145 -278.152555) (xy 61.378333 -278.129212)
			(xy 61.336737 -278.098991) (xy 61.300381 -278.062635) (xy 61.27016 -278.021039) (xy 61.246817 -277.975227)
			(xy 61.230929 -277.926328) (xy 61.222886 -277.875546) (xy 60.904462 -277.875546) (xy 60.896746 -277.923022)
			(xy 60.881162 -277.969703) (xy 60.858291 -278.01328) (xy 60.828726 -278.052624) (xy 60.793233 -278.086716)
			(xy 60.75273 -278.114672) (xy 60.708268 -278.13577) (xy 60.660997 -278.149462) (xy 60.612142 -278.155394)
			(xy 60.562967 -278.153413) (xy 60.514748 -278.143569) (xy 60.468732 -278.126117) (xy 60.426111 -278.10151)
			(xy 60.38799 -278.070385) (xy 60.355355 -278.033548) (xy 60.329052 -277.991952) (xy 60.309761 -277.946676)
			(xy 60.297984 -277.898892) (xy 60.294024 -277.849838) (xy 59.976766 -277.849838) (xy 59.976262 -277.875546)
			(xy 59.968219 -277.926328) (xy 59.952331 -277.975227) (xy 59.928988 -278.021039) (xy 59.898767 -278.062635)
			(xy 59.862411 -278.098991) (xy 59.820815 -278.129212) (xy 59.775003 -278.152555) (xy 59.726104 -278.168443)
			(xy 59.675322 -278.176486) (xy 59.623906 -278.176486) (xy 59.573124 -278.168443) (xy 59.524225 -278.152555)
			(xy 59.478413 -278.129212) (xy 59.436817 -278.098991) (xy 59.400461 -278.062635) (xy 59.37024 -278.021039)
			(xy 59.346897 -277.975227) (xy 59.331009 -277.926328) (xy 59.322966 -277.875546) (xy 59.004542 -277.875546)
			(xy 58.996826 -277.923022) (xy 58.981242 -277.969703) (xy 58.958371 -278.01328) (xy 58.928806 -278.052624)
			(xy 58.893313 -278.086716) (xy 58.85281 -278.114672) (xy 58.808348 -278.13577) (xy 58.761077 -278.149462)
			(xy 58.712222 -278.155394) (xy 58.663047 -278.153413) (xy 58.614828 -278.143569) (xy 58.568812 -278.126117)
			(xy 58.526191 -278.10151) (xy 58.48807 -278.070385) (xy 58.455435 -278.033548) (xy 58.429132 -277.991952)
			(xy 58.409841 -277.946676) (xy 58.398064 -277.898892) (xy 58.394104 -277.849838) (xy 58.0771 -277.849838)
			(xy 58.076596 -277.875546) (xy 58.068553 -277.926328) (xy 58.052665 -277.975227) (xy 58.029322 -278.021039)
			(xy 57.999101 -278.062635) (xy 57.962745 -278.098991) (xy 57.921149 -278.129212) (xy 57.875337 -278.152555)
			(xy 57.826438 -278.168443) (xy 57.775656 -278.176486) (xy 57.72424 -278.176486) (xy 57.673458 -278.168443)
			(xy 57.624559 -278.152555) (xy 57.578747 -278.129212) (xy 57.537151 -278.098991) (xy 57.500795 -278.062635)
			(xy 57.470574 -278.021039) (xy 57.447231 -277.975227) (xy 57.431343 -277.926328) (xy 57.4233 -277.875546)
			(xy 57.104622 -277.875546) (xy 57.096906 -277.923022) (xy 57.081322 -277.969703) (xy 57.058451 -278.01328)
			(xy 57.028886 -278.052624) (xy 56.993393 -278.086716) (xy 56.95289 -278.114672) (xy 56.908428 -278.13577)
			(xy 56.861157 -278.149462) (xy 56.812302 -278.155394) (xy 56.763127 -278.153413) (xy 56.714908 -278.143569)
			(xy 56.668892 -278.126117) (xy 56.626271 -278.10151) (xy 56.58815 -278.070385) (xy 56.555515 -278.033548)
			(xy 56.529212 -277.991952) (xy 56.509921 -277.946676) (xy 56.498144 -277.898892) (xy 56.494184 -277.849838)
			(xy 56.176926 -277.849838) (xy 56.176422 -277.875546) (xy 56.168379 -277.926328) (xy 56.152491 -277.975227)
			(xy 56.129148 -278.021039) (xy 56.098927 -278.062635) (xy 56.062571 -278.098991) (xy 56.020975 -278.129212)
			(xy 55.975163 -278.152555) (xy 55.926264 -278.168443) (xy 55.875482 -278.176486) (xy 55.824066 -278.176486)
			(xy 55.773284 -278.168443) (xy 55.724385 -278.152555) (xy 55.678573 -278.129212) (xy 55.636977 -278.098991)
			(xy 55.600621 -278.062635) (xy 55.5704 -278.021039) (xy 55.547057 -277.975227) (xy 55.531169 -277.926328)
			(xy 55.523126 -277.875546) (xy 55.204448 -277.875546) (xy 55.196732 -277.923022) (xy 55.181148 -277.969703)
			(xy 55.158277 -278.01328) (xy 55.128712 -278.052624) (xy 55.093219 -278.086716) (xy 55.052716 -278.114672)
			(xy 55.008254 -278.13577) (xy 54.960983 -278.149462) (xy 54.912128 -278.155394) (xy 54.862953 -278.153413)
			(xy 54.814734 -278.143569) (xy 54.768718 -278.126117) (xy 54.726097 -278.10151) (xy 54.687976 -278.070385)
			(xy 54.655341 -278.033548) (xy 54.629038 -277.991952) (xy 54.609747 -277.946676) (xy 54.59797 -277.898892)
			(xy 54.59401 -277.849838) (xy 54.277006 -277.849838) (xy 54.276502 -277.875546) (xy 54.268459 -277.926328)
			(xy 54.252571 -277.975227) (xy 54.229228 -278.021039) (xy 54.199007 -278.062635) (xy 54.162651 -278.098991)
			(xy 54.121055 -278.129212) (xy 54.075243 -278.152555) (xy 54.026344 -278.168443) (xy 53.975562 -278.176486)
			(xy 53.924146 -278.176486) (xy 53.873364 -278.168443) (xy 53.824465 -278.152555) (xy 53.778653 -278.129212)
			(xy 53.737057 -278.098991) (xy 53.700701 -278.062635) (xy 53.67048 -278.021039) (xy 53.647137 -277.975227)
			(xy 53.631249 -277.926328) (xy 53.623206 -277.875546) (xy 53.304528 -277.875546) (xy 53.296812 -277.923022)
			(xy 53.281228 -277.969703) (xy 53.258357 -278.01328) (xy 53.228792 -278.052624) (xy 53.193299 -278.086716)
			(xy 53.152796 -278.114672) (xy 53.108334 -278.13577) (xy 53.061063 -278.149462) (xy 53.012208 -278.155394)
			(xy 52.963033 -278.153413) (xy 52.914814 -278.143569) (xy 52.868798 -278.126117) (xy 52.826177 -278.10151)
			(xy 52.788056 -278.070385) (xy 52.755421 -278.033548) (xy 52.729118 -277.991952) (xy 52.709827 -277.946676)
			(xy 52.69805 -277.898892) (xy 52.69409 -277.849838) (xy 52.377086 -277.849838) (xy 52.376582 -277.875546)
			(xy 52.368539 -277.926328) (xy 52.352651 -277.975227) (xy 52.329308 -278.021039) (xy 52.299087 -278.062635)
			(xy 52.262731 -278.098991) (xy 52.221135 -278.129212) (xy 52.175323 -278.152555) (xy 52.126424 -278.168443)
			(xy 52.075642 -278.176486) (xy 52.024226 -278.176486) (xy 51.973444 -278.168443) (xy 51.924545 -278.152555)
			(xy 51.878733 -278.129212) (xy 51.837137 -278.098991) (xy 51.800781 -278.062635) (xy 51.77056 -278.021039)
			(xy 51.747217 -277.975227) (xy 51.731329 -277.926328) (xy 51.723286 -277.875546) (xy 51.404608 -277.875546)
			(xy 51.396892 -277.923022) (xy 51.381308 -277.969703) (xy 51.358437 -278.01328) (xy 51.328872 -278.052624)
			(xy 51.293379 -278.086716) (xy 51.252876 -278.114672) (xy 51.208414 -278.13577) (xy 51.161143 -278.149462)
			(xy 51.112288 -278.155394) (xy 51.063113 -278.153413) (xy 51.014894 -278.143569) (xy 50.968878 -278.126117)
			(xy 50.926257 -278.10151) (xy 50.888136 -278.070385) (xy 50.855501 -278.033548) (xy 50.829198 -277.991952)
			(xy 50.809907 -277.946676) (xy 50.79813 -277.898892) (xy 50.79417 -277.849838) (xy 50.476912 -277.849838)
			(xy 50.476408 -277.875546) (xy 50.468365 -277.926328) (xy 50.452477 -277.975227) (xy 50.429134 -278.021039)
			(xy 50.398913 -278.062635) (xy 50.362557 -278.098991) (xy 50.320961 -278.129212) (xy 50.275149 -278.152555)
			(xy 50.22625 -278.168443) (xy 50.175468 -278.176486) (xy 50.124052 -278.176486) (xy 50.07327 -278.168443)
			(xy 50.024371 -278.152555) (xy 49.978559 -278.129212) (xy 49.936963 -278.098991) (xy 49.900607 -278.062635)
			(xy 49.870386 -278.021039) (xy 49.847043 -277.975227) (xy 49.831155 -277.926328) (xy 49.823112 -277.875546)
			(xy 49.503588 -277.875546) (xy 49.501786 -277.898185) (xy 49.490329 -277.945349) (xy 49.471555 -277.990106)
			(xy 49.445937 -278.03133) (xy 49.41412 -278.067982) (xy 49.376906 -278.09914) (xy 49.335231 -278.124017)
			(xy 49.290145 -278.141989) (xy 49.242784 -278.152602) (xy 49.218596 -278.154638) (xy 49.20942 -278.155572)
			(xy 49.192607 -278.163116) (xy 49.18583 -278.16937) (xy 49.16424 -278.19096) (xy 49.157399 -278.19836)
			(xy 49.14968 -278.216958) (xy 49.149254 -278.227028) (xy 49.149254 -278.422608) (xy 49.14968 -278.432676)
			(xy 49.157403 -278.451274) (xy 49.16424 -278.458676) (xy 49.18583 -278.480266) (xy 49.192642 -278.486468)
			(xy 49.209436 -278.494012) (xy 49.218596 -278.494998) (xy 49.242792 -278.496959) (xy 49.290159 -278.507574)
			(xy 49.335251 -278.525548) (xy 49.376931 -278.550429) (xy 49.41415 -278.581591) (xy 49.445971 -278.618248)
			(xy 49.471592 -278.659478) (xy 49.490368 -278.704241) (xy 49.501826 -278.751411) (xy 49.505677 -278.7998)
			(xy 49.503631 -278.825506) (xy 49.823112 -278.825506) (xy 49.823112 -278.77409) (xy 49.831155 -278.723308)
			(xy 49.847043 -278.674409) (xy 49.870386 -278.628597) (xy 49.900607 -278.587001) (xy 49.936963 -278.550645)
			(xy 49.978559 -278.520424) (xy 50.024371 -278.497081) (xy 50.07327 -278.481193) (xy 50.124052 -278.47315)
			(xy 50.175468 -278.47315) (xy 50.22625 -278.481193) (xy 50.275149 -278.497081) (xy 50.320961 -278.520424)
			(xy 50.362557 -278.550645) (xy 50.398913 -278.587001) (xy 50.429134 -278.628597) (xy 50.452477 -278.674409)
			(xy 50.468365 -278.723308) (xy 50.476408 -278.77409) (xy 50.476912 -278.799798) (xy 50.79417 -278.799798)
			(xy 50.79813 -278.750744) (xy 50.809907 -278.70296) (xy 50.829198 -278.657684) (xy 50.855501 -278.616088)
			(xy 50.888136 -278.579251) (xy 50.926257 -278.548126) (xy 50.968878 -278.523519) (xy 51.014894 -278.506067)
			(xy 51.063113 -278.496223) (xy 51.112288 -278.494242) (xy 51.161143 -278.500174) (xy 51.208414 -278.513866)
			(xy 51.252876 -278.534964) (xy 51.293379 -278.56292) (xy 51.328872 -278.597012) (xy 51.358437 -278.636356)
			(xy 51.381308 -278.679933) (xy 51.396892 -278.726614) (xy 51.404787 -278.775191) (xy 51.405282 -278.799798)
			(xy 51.404787 -278.824405) (xy 51.404608 -278.825506) (xy 51.723286 -278.825506) (xy 51.723286 -278.77409)
			(xy 51.731329 -278.723308) (xy 51.747217 -278.674409) (xy 51.77056 -278.628597) (xy 51.800781 -278.587001)
			(xy 51.837137 -278.550645) (xy 51.878733 -278.520424) (xy 51.924545 -278.497081) (xy 51.973444 -278.481193)
			(xy 52.024226 -278.47315) (xy 52.075642 -278.47315) (xy 52.126424 -278.481193) (xy 52.175323 -278.497081)
			(xy 52.221135 -278.520424) (xy 52.262731 -278.550645) (xy 52.299087 -278.587001) (xy 52.329308 -278.628597)
			(xy 52.352651 -278.674409) (xy 52.368539 -278.723308) (xy 52.376582 -278.77409) (xy 52.377086 -278.799798)
			(xy 52.69409 -278.799798) (xy 52.69805 -278.750744) (xy 52.709827 -278.70296) (xy 52.729118 -278.657684)
			(xy 52.755421 -278.616088) (xy 52.788056 -278.579251) (xy 52.826177 -278.548126) (xy 52.868798 -278.523519)
			(xy 52.914814 -278.506067) (xy 52.963033 -278.496223) (xy 53.012208 -278.494242) (xy 53.061063 -278.500174)
			(xy 53.108334 -278.513866) (xy 53.152796 -278.534964) (xy 53.193299 -278.56292) (xy 53.228792 -278.597012)
			(xy 53.258357 -278.636356) (xy 53.281228 -278.679933) (xy 53.296812 -278.726614) (xy 53.304707 -278.775191)
			(xy 53.305202 -278.799798) (xy 53.304707 -278.824405) (xy 53.304528 -278.825506) (xy 53.623206 -278.825506)
			(xy 53.623206 -278.77409) (xy 53.631249 -278.723308) (xy 53.647137 -278.674409) (xy 53.67048 -278.628597)
			(xy 53.700701 -278.587001) (xy 53.737057 -278.550645) (xy 53.778653 -278.520424) (xy 53.824465 -278.497081)
			(xy 53.873364 -278.481193) (xy 53.924146 -278.47315) (xy 53.975562 -278.47315) (xy 54.026344 -278.481193)
			(xy 54.075243 -278.497081) (xy 54.121055 -278.520424) (xy 54.162651 -278.550645) (xy 54.199007 -278.587001)
			(xy 54.229228 -278.628597) (xy 54.252571 -278.674409) (xy 54.268459 -278.723308) (xy 54.276502 -278.77409)
			(xy 54.277006 -278.799798) (xy 54.59401 -278.799798) (xy 54.59797 -278.750744) (xy 54.609747 -278.70296)
			(xy 54.629038 -278.657684) (xy 54.655341 -278.616088) (xy 54.687976 -278.579251) (xy 54.726097 -278.548126)
			(xy 54.768718 -278.523519) (xy 54.814734 -278.506067) (xy 54.862953 -278.496223) (xy 54.912128 -278.494242)
			(xy 54.960983 -278.500174) (xy 55.008254 -278.513866) (xy 55.052716 -278.534964) (xy 55.093219 -278.56292)
			(xy 55.128712 -278.597012) (xy 55.158277 -278.636356) (xy 55.181148 -278.679933) (xy 55.196732 -278.726614)
			(xy 55.204627 -278.775191) (xy 55.205122 -278.799798) (xy 55.204627 -278.824405) (xy 55.204448 -278.825506)
			(xy 55.523126 -278.825506) (xy 55.523126 -278.77409) (xy 55.531169 -278.723308) (xy 55.547057 -278.674409)
			(xy 55.5704 -278.628597) (xy 55.600621 -278.587001) (xy 55.636977 -278.550645) (xy 55.678573 -278.520424)
			(xy 55.724385 -278.497081) (xy 55.773284 -278.481193) (xy 55.824066 -278.47315) (xy 55.875482 -278.47315)
			(xy 55.926264 -278.481193) (xy 55.975163 -278.497081) (xy 56.020975 -278.520424) (xy 56.062571 -278.550645)
			(xy 56.098927 -278.587001) (xy 56.129148 -278.628597) (xy 56.152491 -278.674409) (xy 56.168379 -278.723308)
			(xy 56.176422 -278.77409) (xy 56.176926 -278.799798) (xy 56.494184 -278.799798) (xy 56.498144 -278.750744)
			(xy 56.509921 -278.70296) (xy 56.529212 -278.657684) (xy 56.555515 -278.616088) (xy 56.58815 -278.579251)
			(xy 56.626271 -278.548126) (xy 56.668892 -278.523519) (xy 56.714908 -278.506067) (xy 56.763127 -278.496223)
			(xy 56.812302 -278.494242) (xy 56.861157 -278.500174) (xy 56.908428 -278.513866) (xy 56.95289 -278.534964)
			(xy 56.993393 -278.56292) (xy 57.028886 -278.597012) (xy 57.058451 -278.636356) (xy 57.081322 -278.679933)
			(xy 57.096906 -278.726614) (xy 57.104801 -278.775191) (xy 57.105296 -278.799798) (xy 57.104801 -278.824405)
			(xy 57.104622 -278.825506) (xy 57.4233 -278.825506) (xy 57.4233 -278.77409) (xy 57.431343 -278.723308)
			(xy 57.447231 -278.674409) (xy 57.470574 -278.628597) (xy 57.500795 -278.587001) (xy 57.537151 -278.550645)
			(xy 57.578747 -278.520424) (xy 57.624559 -278.497081) (xy 57.673458 -278.481193) (xy 57.72424 -278.47315)
			(xy 57.775656 -278.47315) (xy 57.826438 -278.481193) (xy 57.875337 -278.497081) (xy 57.921149 -278.520424)
			(xy 57.962745 -278.550645) (xy 57.999101 -278.587001) (xy 58.029322 -278.628597) (xy 58.052665 -278.674409)
			(xy 58.068553 -278.723308) (xy 58.076596 -278.77409) (xy 58.0771 -278.799798) (xy 58.394104 -278.799798)
			(xy 58.398064 -278.750744) (xy 58.409841 -278.70296) (xy 58.429132 -278.657684) (xy 58.455435 -278.616088)
			(xy 58.48807 -278.579251) (xy 58.526191 -278.548126) (xy 58.568812 -278.523519) (xy 58.614828 -278.506067)
			(xy 58.663047 -278.496223) (xy 58.712222 -278.494242) (xy 58.761077 -278.500174) (xy 58.808348 -278.513866)
			(xy 58.85281 -278.534964) (xy 58.893313 -278.56292) (xy 58.928806 -278.597012) (xy 58.958371 -278.636356)
			(xy 58.981242 -278.679933) (xy 58.996826 -278.726614) (xy 59.004721 -278.775191) (xy 59.005216 -278.799798)
			(xy 59.004721 -278.824405) (xy 59.004542 -278.825506) (xy 59.322966 -278.825506) (xy 59.322966 -278.77409)
			(xy 59.331009 -278.723308) (xy 59.346897 -278.674409) (xy 59.37024 -278.628597) (xy 59.400461 -278.587001)
			(xy 59.436817 -278.550645) (xy 59.478413 -278.520424) (xy 59.524225 -278.497081) (xy 59.573124 -278.481193)
			(xy 59.623906 -278.47315) (xy 59.675322 -278.47315) (xy 59.726104 -278.481193) (xy 59.775003 -278.497081)
			(xy 59.820815 -278.520424) (xy 59.862411 -278.550645) (xy 59.898767 -278.587001) (xy 59.928988 -278.628597)
			(xy 59.952331 -278.674409) (xy 59.968219 -278.723308) (xy 59.976262 -278.77409) (xy 59.976766 -278.799798)
			(xy 60.294024 -278.799798) (xy 60.297984 -278.750744) (xy 60.309761 -278.70296) (xy 60.329052 -278.657684)
			(xy 60.355355 -278.616088) (xy 60.38799 -278.579251) (xy 60.426111 -278.548126) (xy 60.468732 -278.523519)
			(xy 60.514748 -278.506067) (xy 60.562967 -278.496223) (xy 60.612142 -278.494242) (xy 60.660997 -278.500174)
			(xy 60.708268 -278.513866) (xy 60.75273 -278.534964) (xy 60.793233 -278.56292) (xy 60.828726 -278.597012)
			(xy 60.858291 -278.636356) (xy 60.881162 -278.679933) (xy 60.896746 -278.726614) (xy 60.904641 -278.775191)
			(xy 60.905136 -278.799798) (xy 60.904641 -278.824405) (xy 60.904462 -278.825506) (xy 61.222886 -278.825506)
			(xy 61.222886 -278.77409) (xy 61.230929 -278.723308) (xy 61.246817 -278.674409) (xy 61.27016 -278.628597)
			(xy 61.300381 -278.587001) (xy 61.336737 -278.550645) (xy 61.378333 -278.520424) (xy 61.424145 -278.497081)
			(xy 61.473044 -278.481193) (xy 61.523826 -278.47315) (xy 61.575242 -278.47315) (xy 61.626024 -278.481193)
			(xy 61.674923 -278.497081) (xy 61.720735 -278.520424) (xy 61.762331 -278.550645) (xy 61.798687 -278.587001)
			(xy 61.828908 -278.628597) (xy 61.852251 -278.674409) (xy 61.868139 -278.723308) (xy 61.876182 -278.77409)
			(xy 61.876686 -278.799798) (xy 62.193944 -278.799798) (xy 62.197904 -278.750744) (xy 62.209681 -278.70296)
			(xy 62.228972 -278.657684) (xy 62.255275 -278.616088) (xy 62.28791 -278.579251) (xy 62.326031 -278.548126)
			(xy 62.368652 -278.523519) (xy 62.414668 -278.506067) (xy 62.462887 -278.496223) (xy 62.512062 -278.494242)
			(xy 62.560917 -278.500174) (xy 62.608188 -278.513866) (xy 62.65265 -278.534964) (xy 62.693153 -278.56292)
			(xy 62.728646 -278.597012) (xy 62.758211 -278.636356) (xy 62.781082 -278.679933) (xy 62.796666 -278.726614)
			(xy 62.804561 -278.775191) (xy 62.805056 -278.799798) (xy 62.804561 -278.824405) (xy 62.804382 -278.825506)
			(xy 63.12306 -278.825506) (xy 63.12306 -278.77409) (xy 63.131103 -278.723308) (xy 63.146991 -278.674409)
			(xy 63.170334 -278.628597) (xy 63.200555 -278.587001) (xy 63.236911 -278.550645) (xy 63.278507 -278.520424)
			(xy 63.324319 -278.497081) (xy 63.373218 -278.481193) (xy 63.424 -278.47315) (xy 63.475416 -278.47315)
			(xy 63.526198 -278.481193) (xy 63.575097 -278.497081) (xy 63.620909 -278.520424) (xy 63.662505 -278.550645)
			(xy 63.698861 -278.587001) (xy 63.729082 -278.628597) (xy 63.752425 -278.674409) (xy 63.768313 -278.723308)
			(xy 63.776356 -278.77409) (xy 63.77686 -278.799798) (xy 64.094118 -278.799798) (xy 64.098078 -278.750744)
			(xy 64.109855 -278.70296) (xy 64.129146 -278.657684) (xy 64.155449 -278.616088) (xy 64.188084 -278.579251)
			(xy 64.226205 -278.548126) (xy 64.268826 -278.523519) (xy 64.314842 -278.506067) (xy 64.363061 -278.496223)
			(xy 64.412236 -278.494242) (xy 64.461091 -278.500174) (xy 64.508362 -278.513866) (xy 64.552824 -278.534964)
			(xy 64.593327 -278.56292) (xy 64.62882 -278.597012) (xy 64.658385 -278.636356) (xy 64.681256 -278.679933)
			(xy 64.69684 -278.726614) (xy 64.704735 -278.775191) (xy 64.70523 -278.799798) (xy 64.704735 -278.824405)
			(xy 64.704556 -278.825506) (xy 65.02298 -278.825506) (xy 65.02298 -278.77409) (xy 65.031023 -278.723308)
			(xy 65.046911 -278.674409) (xy 65.070254 -278.628597) (xy 65.100475 -278.587001) (xy 65.136831 -278.550645)
			(xy 65.178427 -278.520424) (xy 65.224239 -278.497081) (xy 65.273138 -278.481193) (xy 65.32392 -278.47315)
			(xy 65.375336 -278.47315) (xy 65.426118 -278.481193) (xy 65.475017 -278.497081) (xy 65.520829 -278.520424)
			(xy 65.562425 -278.550645) (xy 65.598781 -278.587001) (xy 65.629002 -278.628597) (xy 65.652345 -278.674409)
			(xy 65.668233 -278.723308) (xy 65.676276 -278.77409) (xy 65.67678 -278.799798) (xy 65.994038 -278.799798)
			(xy 65.997998 -278.750744) (xy 66.009775 -278.70296) (xy 66.029066 -278.657684) (xy 66.055369 -278.616088)
			(xy 66.088004 -278.579251) (xy 66.126125 -278.548126) (xy 66.168746 -278.523519) (xy 66.214762 -278.506067)
			(xy 66.262981 -278.496223) (xy 66.312156 -278.494242) (xy 66.361011 -278.500174) (xy 66.408282 -278.513866)
			(xy 66.452744 -278.534964) (xy 66.493247 -278.56292) (xy 66.52874 -278.597012) (xy 66.558305 -278.636356)
			(xy 66.581176 -278.679933) (xy 66.59676 -278.726614) (xy 66.604655 -278.775191) (xy 66.60515 -278.799798)
			(xy 66.604655 -278.824405) (xy 66.604476 -278.825506) (xy 66.9229 -278.825506) (xy 66.9229 -278.77409)
			(xy 66.930943 -278.723308) (xy 66.946831 -278.674409) (xy 66.970174 -278.628597) (xy 67.000395 -278.587001)
			(xy 67.036751 -278.550645) (xy 67.078347 -278.520424) (xy 67.124159 -278.497081) (xy 67.173058 -278.481193)
			(xy 67.22384 -278.47315) (xy 67.275256 -278.47315) (xy 67.326038 -278.481193) (xy 67.374937 -278.497081)
			(xy 67.420749 -278.520424) (xy 67.462345 -278.550645) (xy 67.498701 -278.587001) (xy 67.528922 -278.628597)
			(xy 67.552265 -278.674409) (xy 67.568153 -278.723308) (xy 67.576196 -278.77409) (xy 67.5767 -278.799798)
			(xy 67.893958 -278.799798) (xy 67.897918 -278.750744) (xy 67.909695 -278.70296) (xy 67.928986 -278.657684)
			(xy 67.955289 -278.616088) (xy 67.987924 -278.579251) (xy 68.026045 -278.548126) (xy 68.068666 -278.523519)
			(xy 68.114682 -278.506067) (xy 68.162901 -278.496223) (xy 68.212076 -278.494242) (xy 68.260931 -278.500174)
			(xy 68.308202 -278.513866) (xy 68.352664 -278.534964) (xy 68.393167 -278.56292) (xy 68.42866 -278.597012)
			(xy 68.458225 -278.636356) (xy 68.481096 -278.679933) (xy 68.49668 -278.726614) (xy 68.504575 -278.775191)
			(xy 68.50507 -278.799798) (xy 68.504575 -278.824405) (xy 68.504396 -278.825506) (xy 68.823074 -278.825506)
			(xy 68.823074 -278.77409) (xy 68.831117 -278.723308) (xy 68.847005 -278.674409) (xy 68.870348 -278.628597)
			(xy 68.900569 -278.587001) (xy 68.936925 -278.550645) (xy 68.978521 -278.520424) (xy 69.024333 -278.497081)
			(xy 69.073232 -278.481193) (xy 69.124014 -278.47315) (xy 69.17543 -278.47315) (xy 69.226212 -278.481193)
			(xy 69.275111 -278.497081) (xy 69.320923 -278.520424) (xy 69.362519 -278.550645) (xy 69.398875 -278.587001)
			(xy 69.429096 -278.628597) (xy 69.452439 -278.674409) (xy 69.468327 -278.723308) (xy 69.47637 -278.77409)
			(xy 69.476874 -278.799798) (xy 69.794132 -278.799798) (xy 69.798092 -278.750744) (xy 69.809869 -278.70296)
			(xy 69.82916 -278.657684) (xy 69.855463 -278.616088) (xy 69.888098 -278.579251) (xy 69.926219 -278.548126)
			(xy 69.96884 -278.523519) (xy 70.014856 -278.506067) (xy 70.063075 -278.496223) (xy 70.11225 -278.494242)
			(xy 70.161105 -278.500174) (xy 70.208376 -278.513866) (xy 70.252838 -278.534964) (xy 70.293341 -278.56292)
			(xy 70.328834 -278.597012) (xy 70.358399 -278.636356) (xy 70.38127 -278.679933) (xy 70.396854 -278.726614)
			(xy 70.404749 -278.775191) (xy 70.405244 -278.799798) (xy 70.404749 -278.824405) (xy 70.40457 -278.825506)
			(xy 70.722994 -278.825506) (xy 70.722994 -278.77409) (xy 70.731037 -278.723308) (xy 70.746925 -278.674409)
			(xy 70.770268 -278.628597) (xy 70.800489 -278.587001) (xy 70.836845 -278.550645) (xy 70.878441 -278.520424)
			(xy 70.924253 -278.497081) (xy 70.973152 -278.481193) (xy 71.023934 -278.47315) (xy 71.07535 -278.47315)
			(xy 71.126132 -278.481193) (xy 71.175031 -278.497081) (xy 71.220843 -278.520424) (xy 71.262439 -278.550645)
			(xy 71.298795 -278.587001) (xy 71.329016 -278.628597) (xy 71.352359 -278.674409) (xy 71.368247 -278.723308)
			(xy 71.37629 -278.77409) (xy 71.376794 -278.799798) (xy 71.694052 -278.799798) (xy 71.698012 -278.750744)
			(xy 71.709789 -278.70296) (xy 71.72908 -278.657684) (xy 71.755383 -278.616088) (xy 71.788018 -278.579251)
			(xy 71.826139 -278.548126) (xy 71.86876 -278.523519) (xy 71.914776 -278.506067) (xy 71.962995 -278.496223)
			(xy 72.01217 -278.494242) (xy 72.061025 -278.500174) (xy 72.108296 -278.513866) (xy 72.152758 -278.534964)
			(xy 72.193261 -278.56292) (xy 72.228754 -278.597012) (xy 72.258319 -278.636356) (xy 72.28119 -278.679933)
			(xy 72.296774 -278.726614) (xy 72.304669 -278.775191) (xy 72.305164 -278.799798) (xy 72.304669 -278.824405)
			(xy 72.30449 -278.825506) (xy 72.622914 -278.825506) (xy 72.622914 -278.77409) (xy 72.630957 -278.723308)
			(xy 72.646845 -278.674409) (xy 72.670188 -278.628597) (xy 72.700409 -278.587001) (xy 72.736765 -278.550645)
			(xy 72.778361 -278.520424) (xy 72.824173 -278.497081) (xy 72.873072 -278.481193) (xy 72.923854 -278.47315)
			(xy 72.97527 -278.47315) (xy 73.026052 -278.481193) (xy 73.074951 -278.497081) (xy 73.120763 -278.520424)
			(xy 73.162359 -278.550645) (xy 73.198715 -278.587001) (xy 73.228936 -278.628597) (xy 73.252279 -278.674409)
			(xy 73.268167 -278.723308) (xy 73.27621 -278.77409) (xy 73.276714 -278.799798) (xy 73.593972 -278.799798)
			(xy 73.597932 -278.750744) (xy 73.609709 -278.70296) (xy 73.629 -278.657684) (xy 73.655303 -278.616088)
			(xy 73.687938 -278.579251) (xy 73.726059 -278.548126) (xy 73.76868 -278.523519) (xy 73.814696 -278.506067)
			(xy 73.862915 -278.496223) (xy 73.91209 -278.494242) (xy 73.960945 -278.500174) (xy 74.008216 -278.513866)
			(xy 74.052678 -278.534964) (xy 74.093181 -278.56292) (xy 74.128674 -278.597012) (xy 74.158239 -278.636356)
			(xy 74.18111 -278.679933) (xy 74.196694 -278.726614) (xy 74.204589 -278.775191) (xy 74.205084 -278.799798)
			(xy 74.204589 -278.824405) (xy 74.20441 -278.825506) (xy 74.523088 -278.825506) (xy 74.523088 -278.77409)
			(xy 74.531131 -278.723308) (xy 74.547019 -278.674409) (xy 74.570362 -278.628597) (xy 74.600583 -278.587001)
			(xy 74.636939 -278.550645) (xy 74.678535 -278.520424) (xy 74.724347 -278.497081) (xy 74.773246 -278.481193)
			(xy 74.824028 -278.47315) (xy 74.875444 -278.47315) (xy 74.926226 -278.481193) (xy 74.975125 -278.497081)
			(xy 75.020937 -278.520424) (xy 75.062533 -278.550645) (xy 75.098889 -278.587001) (xy 75.12911 -278.628597)
			(xy 75.152453 -278.674409) (xy 75.168341 -278.723308) (xy 75.176384 -278.77409) (xy 75.176888 -278.799798)
			(xy 75.494146 -278.799798) (xy 75.498106 -278.750744) (xy 75.509883 -278.70296) (xy 75.529174 -278.657684)
			(xy 75.555477 -278.616088) (xy 75.588112 -278.579251) (xy 75.626233 -278.548126) (xy 75.668854 -278.523519)
			(xy 75.71487 -278.506067) (xy 75.763089 -278.496223) (xy 75.812264 -278.494242) (xy 75.861119 -278.500174)
			(xy 75.90839 -278.513866) (xy 75.952852 -278.534964) (xy 75.993355 -278.56292) (xy 76.028848 -278.597012)
			(xy 76.058413 -278.636356) (xy 76.081284 -278.679933) (xy 76.096868 -278.726614) (xy 76.104763 -278.775191)
			(xy 76.105258 -278.799798) (xy 76.104763 -278.824405) (xy 76.104584 -278.825506) (xy 76.423008 -278.825506)
			(xy 76.423008 -278.77409) (xy 76.431051 -278.723308) (xy 76.446939 -278.674409) (xy 76.470282 -278.628597)
			(xy 76.500503 -278.587001) (xy 76.536859 -278.550645) (xy 76.578455 -278.520424) (xy 76.624267 -278.497081)
			(xy 76.673166 -278.481193) (xy 76.723948 -278.47315) (xy 76.775364 -278.47315) (xy 76.826146 -278.481193)
			(xy 76.875045 -278.497081) (xy 76.920857 -278.520424) (xy 76.962453 -278.550645) (xy 76.998809 -278.587001)
			(xy 77.02903 -278.628597) (xy 77.052373 -278.674409) (xy 77.068261 -278.723308) (xy 77.076304 -278.77409)
			(xy 77.076808 -278.799798) (xy 77.394066 -278.799798) (xy 77.398026 -278.750744) (xy 77.409803 -278.70296)
			(xy 77.429094 -278.657684) (xy 77.455397 -278.616088) (xy 77.488032 -278.579251) (xy 77.526153 -278.548126)
			(xy 77.568774 -278.523519) (xy 77.61479 -278.506067) (xy 77.663009 -278.496223) (xy 77.712184 -278.494242)
			(xy 77.761039 -278.500174) (xy 77.80831 -278.513866) (xy 77.852772 -278.534964) (xy 77.893275 -278.56292)
			(xy 77.928768 -278.597012) (xy 77.958333 -278.636356) (xy 77.981204 -278.679933) (xy 77.996788 -278.726614)
			(xy 78.004683 -278.775191) (xy 78.005178 -278.799798) (xy 78.004683 -278.824405) (xy 78.004504 -278.825506)
			(xy 78.322928 -278.825506) (xy 78.322928 -278.77409) (xy 78.330971 -278.723308) (xy 78.346859 -278.674409)
			(xy 78.370202 -278.628597) (xy 78.400423 -278.587001) (xy 78.436779 -278.550645) (xy 78.478375 -278.520424)
			(xy 78.524187 -278.497081) (xy 78.573086 -278.481193) (xy 78.623868 -278.47315) (xy 78.675284 -278.47315)
			(xy 78.726066 -278.481193) (xy 78.774965 -278.497081) (xy 78.820777 -278.520424) (xy 78.862373 -278.550645)
			(xy 78.898729 -278.587001) (xy 78.92895 -278.628597) (xy 78.952293 -278.674409) (xy 78.968181 -278.723308)
			(xy 78.976224 -278.77409) (xy 78.976728 -278.799798) (xy 79.293986 -278.799798) (xy 79.297946 -278.750744)
			(xy 79.309723 -278.70296) (xy 79.329014 -278.657684) (xy 79.355317 -278.616088) (xy 79.387952 -278.579251)
			(xy 79.426073 -278.548126) (xy 79.468694 -278.523519) (xy 79.51471 -278.506067) (xy 79.562929 -278.496223)
			(xy 79.612104 -278.494242) (xy 79.660959 -278.500174) (xy 79.70823 -278.513866) (xy 79.752692 -278.534964)
			(xy 79.793195 -278.56292) (xy 79.828688 -278.597012) (xy 79.858253 -278.636356) (xy 79.881124 -278.679933)
			(xy 79.896708 -278.726614) (xy 79.904603 -278.775191) (xy 79.905098 -278.799798) (xy 79.904603 -278.824405)
			(xy 79.904424 -278.825506) (xy 80.223102 -278.825506) (xy 80.223102 -278.77409) (xy 80.231145 -278.723308)
			(xy 80.247033 -278.674409) (xy 80.270376 -278.628597) (xy 80.300597 -278.587001) (xy 80.336953 -278.550645)
			(xy 80.378549 -278.520424) (xy 80.424361 -278.497081) (xy 80.47326 -278.481193) (xy 80.524042 -278.47315)
			(xy 80.575458 -278.47315) (xy 80.62624 -278.481193) (xy 80.675139 -278.497081) (xy 80.720951 -278.520424)
			(xy 80.762547 -278.550645) (xy 80.798903 -278.587001) (xy 80.829124 -278.628597) (xy 80.852467 -278.674409)
			(xy 80.868355 -278.723308) (xy 80.876398 -278.77409) (xy 80.876902 -278.799798) (xy 81.19416 -278.799798)
			(xy 81.19812 -278.750744) (xy 81.209897 -278.70296) (xy 81.229188 -278.657684) (xy 81.255491 -278.616088)
			(xy 81.288126 -278.579251) (xy 81.326247 -278.548126) (xy 81.368868 -278.523519) (xy 81.414884 -278.506067)
			(xy 81.463103 -278.496223) (xy 81.512278 -278.494242) (xy 81.561133 -278.500174) (xy 81.608404 -278.513866)
			(xy 81.652866 -278.534964) (xy 81.693369 -278.56292) (xy 81.728862 -278.597012) (xy 81.758427 -278.636356)
			(xy 81.781298 -278.679933) (xy 81.796882 -278.726614) (xy 81.804777 -278.775191) (xy 81.805272 -278.799798)
			(xy 82.14412 -278.799798) (xy 82.14808 -278.750744) (xy 82.159857 -278.70296) (xy 82.179148 -278.657684)
			(xy 82.205451 -278.616088) (xy 82.238086 -278.579251) (xy 82.276207 -278.548126) (xy 82.318828 -278.523519)
			(xy 82.364844 -278.506067) (xy 82.413063 -278.496223) (xy 82.462238 -278.494242) (xy 82.511093 -278.500174)
			(xy 82.558364 -278.513866) (xy 82.602826 -278.534964) (xy 82.643329 -278.56292) (xy 82.678822 -278.597012)
			(xy 82.708387 -278.636356) (xy 82.731258 -278.679933) (xy 82.746842 -278.726614) (xy 82.754737 -278.775191)
			(xy 82.755232 -278.799798) (xy 82.754737 -278.824405) (xy 82.746842 -278.872982) (xy 82.731258 -278.919663)
			(xy 82.708387 -278.96324) (xy 82.678822 -279.002584) (xy 82.643329 -279.036676) (xy 82.602826 -279.064632)
			(xy 82.558364 -279.08573) (xy 82.511093 -279.099422) (xy 82.462238 -279.105354) (xy 82.413063 -279.103373)
			(xy 82.364844 -279.093529) (xy 82.318828 -279.076077) (xy 82.276207 -279.05147) (xy 82.238086 -279.020345)
			(xy 82.205451 -278.983508) (xy 82.179148 -278.941912) (xy 82.159857 -278.896636) (xy 82.14808 -278.848852)
			(xy 82.14412 -278.799798) (xy 81.805272 -278.799798) (xy 81.804777 -278.824405) (xy 81.796882 -278.872982)
			(xy 81.781298 -278.919663) (xy 81.758427 -278.96324) (xy 81.728862 -279.002584) (xy 81.693369 -279.036676)
			(xy 81.652866 -279.064632) (xy 81.608404 -279.08573) (xy 81.561133 -279.099422) (xy 81.512278 -279.105354)
			(xy 81.463103 -279.103373) (xy 81.414884 -279.093529) (xy 81.368868 -279.076077) (xy 81.326247 -279.05147)
			(xy 81.288126 -279.020345) (xy 81.255491 -278.983508) (xy 81.229188 -278.941912) (xy 81.209897 -278.896636)
			(xy 81.19812 -278.848852) (xy 81.19416 -278.799798) (xy 80.876902 -278.799798) (xy 80.876398 -278.825506)
			(xy 80.868355 -278.876288) (xy 80.852467 -278.925187) (xy 80.829124 -278.970999) (xy 80.798903 -279.012595)
			(xy 80.762547 -279.048951) (xy 80.720951 -279.079172) (xy 80.675139 -279.102515) (xy 80.62624 -279.118403)
			(xy 80.575458 -279.126446) (xy 80.524042 -279.126446) (xy 80.47326 -279.118403) (xy 80.424361 -279.102515)
			(xy 80.378549 -279.079172) (xy 80.336953 -279.048951) (xy 80.300597 -279.012595) (xy 80.270376 -278.970999)
			(xy 80.247033 -278.925187) (xy 80.231145 -278.876288) (xy 80.223102 -278.825506) (xy 79.904424 -278.825506)
			(xy 79.896708 -278.872982) (xy 79.881124 -278.919663) (xy 79.858253 -278.96324) (xy 79.828688 -279.002584)
			(xy 79.793195 -279.036676) (xy 79.752692 -279.064632) (xy 79.70823 -279.08573) (xy 79.660959 -279.099422)
			(xy 79.612104 -279.105354) (xy 79.562929 -279.103373) (xy 79.51471 -279.093529) (xy 79.468694 -279.076077)
			(xy 79.426073 -279.05147) (xy 79.387952 -279.020345) (xy 79.355317 -278.983508) (xy 79.329014 -278.941912)
			(xy 79.309723 -278.896636) (xy 79.297946 -278.848852) (xy 79.293986 -278.799798) (xy 78.976728 -278.799798)
			(xy 78.976224 -278.825506) (xy 78.968181 -278.876288) (xy 78.952293 -278.925187) (xy 78.92895 -278.970999)
			(xy 78.898729 -279.012595) (xy 78.862373 -279.048951) (xy 78.820777 -279.079172) (xy 78.774965 -279.102515)
			(xy 78.726066 -279.118403) (xy 78.675284 -279.126446) (xy 78.623868 -279.126446) (xy 78.573086 -279.118403)
			(xy 78.524187 -279.102515) (xy 78.478375 -279.079172) (xy 78.436779 -279.048951) (xy 78.400423 -279.012595)
			(xy 78.370202 -278.970999) (xy 78.346859 -278.925187) (xy 78.330971 -278.876288) (xy 78.322928 -278.825506)
			(xy 78.004504 -278.825506) (xy 77.996788 -278.872982) (xy 77.981204 -278.919663) (xy 77.958333 -278.96324)
			(xy 77.928768 -279.002584) (xy 77.893275 -279.036676) (xy 77.852772 -279.064632) (xy 77.80831 -279.08573)
			(xy 77.761039 -279.099422) (xy 77.712184 -279.105354) (xy 77.663009 -279.103373) (xy 77.61479 -279.093529)
			(xy 77.568774 -279.076077) (xy 77.526153 -279.05147) (xy 77.488032 -279.020345) (xy 77.455397 -278.983508)
			(xy 77.429094 -278.941912) (xy 77.409803 -278.896636) (xy 77.398026 -278.848852) (xy 77.394066 -278.799798)
			(xy 77.076808 -278.799798) (xy 77.076304 -278.825506) (xy 77.068261 -278.876288) (xy 77.052373 -278.925187)
			(xy 77.02903 -278.970999) (xy 76.998809 -279.012595) (xy 76.962453 -279.048951) (xy 76.920857 -279.079172)
			(xy 76.875045 -279.102515) (xy 76.826146 -279.118403) (xy 76.775364 -279.126446) (xy 76.723948 -279.126446)
			(xy 76.673166 -279.118403) (xy 76.624267 -279.102515) (xy 76.578455 -279.079172) (xy 76.536859 -279.048951)
			(xy 76.500503 -279.012595) (xy 76.470282 -278.970999) (xy 76.446939 -278.925187) (xy 76.431051 -278.876288)
			(xy 76.423008 -278.825506) (xy 76.104584 -278.825506) (xy 76.096868 -278.872982) (xy 76.081284 -278.919663)
			(xy 76.058413 -278.96324) (xy 76.028848 -279.002584) (xy 75.993355 -279.036676) (xy 75.952852 -279.064632)
			(xy 75.90839 -279.08573) (xy 75.861119 -279.099422) (xy 75.812264 -279.105354) (xy 75.763089 -279.103373)
			(xy 75.71487 -279.093529) (xy 75.668854 -279.076077) (xy 75.626233 -279.05147) (xy 75.588112 -279.020345)
			(xy 75.555477 -278.983508) (xy 75.529174 -278.941912) (xy 75.509883 -278.896636) (xy 75.498106 -278.848852)
			(xy 75.494146 -278.799798) (xy 75.176888 -278.799798) (xy 75.176384 -278.825506) (xy 75.168341 -278.876288)
			(xy 75.152453 -278.925187) (xy 75.12911 -278.970999) (xy 75.098889 -279.012595) (xy 75.062533 -279.048951)
			(xy 75.020937 -279.079172) (xy 74.975125 -279.102515) (xy 74.926226 -279.118403) (xy 74.875444 -279.126446)
			(xy 74.824028 -279.126446) (xy 74.773246 -279.118403) (xy 74.724347 -279.102515) (xy 74.678535 -279.079172)
			(xy 74.636939 -279.048951) (xy 74.600583 -279.012595) (xy 74.570362 -278.970999) (xy 74.547019 -278.925187)
			(xy 74.531131 -278.876288) (xy 74.523088 -278.825506) (xy 74.20441 -278.825506) (xy 74.196694 -278.872982)
			(xy 74.18111 -278.919663) (xy 74.158239 -278.96324) (xy 74.128674 -279.002584) (xy 74.093181 -279.036676)
			(xy 74.052678 -279.064632) (xy 74.008216 -279.08573) (xy 73.960945 -279.099422) (xy 73.91209 -279.105354)
			(xy 73.862915 -279.103373) (xy 73.814696 -279.093529) (xy 73.76868 -279.076077) (xy 73.726059 -279.05147)
			(xy 73.687938 -279.020345) (xy 73.655303 -278.983508) (xy 73.629 -278.941912) (xy 73.609709 -278.896636)
			(xy 73.597932 -278.848852) (xy 73.593972 -278.799798) (xy 73.276714 -278.799798) (xy 73.27621 -278.825506)
			(xy 73.268167 -278.876288) (xy 73.252279 -278.925187) (xy 73.228936 -278.970999) (xy 73.198715 -279.012595)
			(xy 73.162359 -279.048951) (xy 73.120763 -279.079172) (xy 73.074951 -279.102515) (xy 73.026052 -279.118403)
			(xy 72.97527 -279.126446) (xy 72.923854 -279.126446) (xy 72.873072 -279.118403) (xy 72.824173 -279.102515)
			(xy 72.778361 -279.079172) (xy 72.736765 -279.048951) (xy 72.700409 -279.012595) (xy 72.670188 -278.970999)
			(xy 72.646845 -278.925187) (xy 72.630957 -278.876288) (xy 72.622914 -278.825506) (xy 72.30449 -278.825506)
			(xy 72.296774 -278.872982) (xy 72.28119 -278.919663) (xy 72.258319 -278.96324) (xy 72.228754 -279.002584)
			(xy 72.193261 -279.036676) (xy 72.152758 -279.064632) (xy 72.108296 -279.08573) (xy 72.061025 -279.099422)
			(xy 72.01217 -279.105354) (xy 71.962995 -279.103373) (xy 71.914776 -279.093529) (xy 71.86876 -279.076077)
			(xy 71.826139 -279.05147) (xy 71.788018 -279.020345) (xy 71.755383 -278.983508) (xy 71.72908 -278.941912)
			(xy 71.709789 -278.896636) (xy 71.698012 -278.848852) (xy 71.694052 -278.799798) (xy 71.376794 -278.799798)
			(xy 71.37629 -278.825506) (xy 71.368247 -278.876288) (xy 71.352359 -278.925187) (xy 71.329016 -278.970999)
			(xy 71.298795 -279.012595) (xy 71.262439 -279.048951) (xy 71.220843 -279.079172) (xy 71.175031 -279.102515)
			(xy 71.126132 -279.118403) (xy 71.07535 -279.126446) (xy 71.023934 -279.126446) (xy 70.973152 -279.118403)
			(xy 70.924253 -279.102515) (xy 70.878441 -279.079172) (xy 70.836845 -279.048951) (xy 70.800489 -279.012595)
			(xy 70.770268 -278.970999) (xy 70.746925 -278.925187) (xy 70.731037 -278.876288) (xy 70.722994 -278.825506)
			(xy 70.40457 -278.825506) (xy 70.396854 -278.872982) (xy 70.38127 -278.919663) (xy 70.358399 -278.96324)
			(xy 70.328834 -279.002584) (xy 70.293341 -279.036676) (xy 70.252838 -279.064632) (xy 70.208376 -279.08573)
			(xy 70.161105 -279.099422) (xy 70.11225 -279.105354) (xy 70.063075 -279.103373) (xy 70.014856 -279.093529)
			(xy 69.96884 -279.076077) (xy 69.926219 -279.05147) (xy 69.888098 -279.020345) (xy 69.855463 -278.983508)
			(xy 69.82916 -278.941912) (xy 69.809869 -278.896636) (xy 69.798092 -278.848852) (xy 69.794132 -278.799798)
			(xy 69.476874 -278.799798) (xy 69.47637 -278.825506) (xy 69.468327 -278.876288) (xy 69.452439 -278.925187)
			(xy 69.429096 -278.970999) (xy 69.398875 -279.012595) (xy 69.362519 -279.048951) (xy 69.320923 -279.079172)
			(xy 69.275111 -279.102515) (xy 69.226212 -279.118403) (xy 69.17543 -279.126446) (xy 69.124014 -279.126446)
			(xy 69.073232 -279.118403) (xy 69.024333 -279.102515) (xy 68.978521 -279.079172) (xy 68.936925 -279.048951)
			(xy 68.900569 -279.012595) (xy 68.870348 -278.970999) (xy 68.847005 -278.925187) (xy 68.831117 -278.876288)
			(xy 68.823074 -278.825506) (xy 68.504396 -278.825506) (xy 68.49668 -278.872982) (xy 68.481096 -278.919663)
			(xy 68.458225 -278.96324) (xy 68.42866 -279.002584) (xy 68.393167 -279.036676) (xy 68.352664 -279.064632)
			(xy 68.308202 -279.08573) (xy 68.260931 -279.099422) (xy 68.212076 -279.105354) (xy 68.162901 -279.103373)
			(xy 68.114682 -279.093529) (xy 68.068666 -279.076077) (xy 68.026045 -279.05147) (xy 67.987924 -279.020345)
			(xy 67.955289 -278.983508) (xy 67.928986 -278.941912) (xy 67.909695 -278.896636) (xy 67.897918 -278.848852)
			(xy 67.893958 -278.799798) (xy 67.5767 -278.799798) (xy 67.576196 -278.825506) (xy 67.568153 -278.876288)
			(xy 67.552265 -278.925187) (xy 67.528922 -278.970999) (xy 67.498701 -279.012595) (xy 67.462345 -279.048951)
			(xy 67.420749 -279.079172) (xy 67.374937 -279.102515) (xy 67.326038 -279.118403) (xy 67.275256 -279.126446)
			(xy 67.22384 -279.126446) (xy 67.173058 -279.118403) (xy 67.124159 -279.102515) (xy 67.078347 -279.079172)
			(xy 67.036751 -279.048951) (xy 67.000395 -279.012595) (xy 66.970174 -278.970999) (xy 66.946831 -278.925187)
			(xy 66.930943 -278.876288) (xy 66.9229 -278.825506) (xy 66.604476 -278.825506) (xy 66.59676 -278.872982)
			(xy 66.581176 -278.919663) (xy 66.558305 -278.96324) (xy 66.52874 -279.002584) (xy 66.493247 -279.036676)
			(xy 66.452744 -279.064632) (xy 66.408282 -279.08573) (xy 66.361011 -279.099422) (xy 66.312156 -279.105354)
			(xy 66.262981 -279.103373) (xy 66.214762 -279.093529) (xy 66.168746 -279.076077) (xy 66.126125 -279.05147)
			(xy 66.088004 -279.020345) (xy 66.055369 -278.983508) (xy 66.029066 -278.941912) (xy 66.009775 -278.896636)
			(xy 65.997998 -278.848852) (xy 65.994038 -278.799798) (xy 65.67678 -278.799798) (xy 65.676276 -278.825506)
			(xy 65.668233 -278.876288) (xy 65.652345 -278.925187) (xy 65.629002 -278.970999) (xy 65.598781 -279.012595)
			(xy 65.562425 -279.048951) (xy 65.520829 -279.079172) (xy 65.475017 -279.102515) (xy 65.426118 -279.118403)
			(xy 65.375336 -279.126446) (xy 65.32392 -279.126446) (xy 65.273138 -279.118403) (xy 65.224239 -279.102515)
			(xy 65.178427 -279.079172) (xy 65.136831 -279.048951) (xy 65.100475 -279.012595) (xy 65.070254 -278.970999)
			(xy 65.046911 -278.925187) (xy 65.031023 -278.876288) (xy 65.02298 -278.825506) (xy 64.704556 -278.825506)
			(xy 64.69684 -278.872982) (xy 64.681256 -278.919663) (xy 64.658385 -278.96324) (xy 64.62882 -279.002584)
			(xy 64.593327 -279.036676) (xy 64.552824 -279.064632) (xy 64.508362 -279.08573) (xy 64.461091 -279.099422)
			(xy 64.412236 -279.105354) (xy 64.363061 -279.103373) (xy 64.314842 -279.093529) (xy 64.268826 -279.076077)
			(xy 64.226205 -279.05147) (xy 64.188084 -279.020345) (xy 64.155449 -278.983508) (xy 64.129146 -278.941912)
			(xy 64.109855 -278.896636) (xy 64.098078 -278.848852) (xy 64.094118 -278.799798) (xy 63.77686 -278.799798)
			(xy 63.776356 -278.825506) (xy 63.768313 -278.876288) (xy 63.752425 -278.925187) (xy 63.729082 -278.970999)
			(xy 63.698861 -279.012595) (xy 63.662505 -279.048951) (xy 63.620909 -279.079172) (xy 63.575097 -279.102515)
			(xy 63.526198 -279.118403) (xy 63.475416 -279.126446) (xy 63.424 -279.126446) (xy 63.373218 -279.118403)
			(xy 63.324319 -279.102515) (xy 63.278507 -279.079172) (xy 63.236911 -279.048951) (xy 63.200555 -279.012595)
			(xy 63.170334 -278.970999) (xy 63.146991 -278.925187) (xy 63.131103 -278.876288) (xy 63.12306 -278.825506)
			(xy 62.804382 -278.825506) (xy 62.796666 -278.872982) (xy 62.781082 -278.919663) (xy 62.758211 -278.96324)
			(xy 62.728646 -279.002584) (xy 62.693153 -279.036676) (xy 62.65265 -279.064632) (xy 62.608188 -279.08573)
			(xy 62.560917 -279.099422) (xy 62.512062 -279.105354) (xy 62.462887 -279.103373) (xy 62.414668 -279.093529)
			(xy 62.368652 -279.076077) (xy 62.326031 -279.05147) (xy 62.28791 -279.020345) (xy 62.255275 -278.983508)
			(xy 62.228972 -278.941912) (xy 62.209681 -278.896636) (xy 62.197904 -278.848852) (xy 62.193944 -278.799798)
			(xy 61.876686 -278.799798) (xy 61.876182 -278.825506) (xy 61.868139 -278.876288) (xy 61.852251 -278.925187)
			(xy 61.828908 -278.970999) (xy 61.798687 -279.012595) (xy 61.762331 -279.048951) (xy 61.720735 -279.079172)
			(xy 61.674923 -279.102515) (xy 61.626024 -279.118403) (xy 61.575242 -279.126446) (xy 61.523826 -279.126446)
			(xy 61.473044 -279.118403) (xy 61.424145 -279.102515) (xy 61.378333 -279.079172) (xy 61.336737 -279.048951)
			(xy 61.300381 -279.012595) (xy 61.27016 -278.970999) (xy 61.246817 -278.925187) (xy 61.230929 -278.876288)
			(xy 61.222886 -278.825506) (xy 60.904462 -278.825506) (xy 60.896746 -278.872982) (xy 60.881162 -278.919663)
			(xy 60.858291 -278.96324) (xy 60.828726 -279.002584) (xy 60.793233 -279.036676) (xy 60.75273 -279.064632)
			(xy 60.708268 -279.08573) (xy 60.660997 -279.099422) (xy 60.612142 -279.105354) (xy 60.562967 -279.103373)
			(xy 60.514748 -279.093529) (xy 60.468732 -279.076077) (xy 60.426111 -279.05147) (xy 60.38799 -279.020345)
			(xy 60.355355 -278.983508) (xy 60.329052 -278.941912) (xy 60.309761 -278.896636) (xy 60.297984 -278.848852)
			(xy 60.294024 -278.799798) (xy 59.976766 -278.799798) (xy 59.976262 -278.825506) (xy 59.968219 -278.876288)
			(xy 59.952331 -278.925187) (xy 59.928988 -278.970999) (xy 59.898767 -279.012595) (xy 59.862411 -279.048951)
			(xy 59.820815 -279.079172) (xy 59.775003 -279.102515) (xy 59.726104 -279.118403) (xy 59.675322 -279.126446)
			(xy 59.623906 -279.126446) (xy 59.573124 -279.118403) (xy 59.524225 -279.102515) (xy 59.478413 -279.079172)
			(xy 59.436817 -279.048951) (xy 59.400461 -279.012595) (xy 59.37024 -278.970999) (xy 59.346897 -278.925187)
			(xy 59.331009 -278.876288) (xy 59.322966 -278.825506) (xy 59.004542 -278.825506) (xy 58.996826 -278.872982)
			(xy 58.981242 -278.919663) (xy 58.958371 -278.96324) (xy 58.928806 -279.002584) (xy 58.893313 -279.036676)
			(xy 58.85281 -279.064632) (xy 58.808348 -279.08573) (xy 58.761077 -279.099422) (xy 58.712222 -279.105354)
			(xy 58.663047 -279.103373) (xy 58.614828 -279.093529) (xy 58.568812 -279.076077) (xy 58.526191 -279.05147)
			(xy 58.48807 -279.020345) (xy 58.455435 -278.983508) (xy 58.429132 -278.941912) (xy 58.409841 -278.896636)
			(xy 58.398064 -278.848852) (xy 58.394104 -278.799798) (xy 58.0771 -278.799798) (xy 58.076596 -278.825506)
			(xy 58.068553 -278.876288) (xy 58.052665 -278.925187) (xy 58.029322 -278.970999) (xy 57.999101 -279.012595)
			(xy 57.962745 -279.048951) (xy 57.921149 -279.079172) (xy 57.875337 -279.102515) (xy 57.826438 -279.118403)
			(xy 57.775656 -279.126446) (xy 57.72424 -279.126446) (xy 57.673458 -279.118403) (xy 57.624559 -279.102515)
			(xy 57.578747 -279.079172) (xy 57.537151 -279.048951) (xy 57.500795 -279.012595) (xy 57.470574 -278.970999)
			(xy 57.447231 -278.925187) (xy 57.431343 -278.876288) (xy 57.4233 -278.825506) (xy 57.104622 -278.825506)
			(xy 57.096906 -278.872982) (xy 57.081322 -278.919663) (xy 57.058451 -278.96324) (xy 57.028886 -279.002584)
			(xy 56.993393 -279.036676) (xy 56.95289 -279.064632) (xy 56.908428 -279.08573) (xy 56.861157 -279.099422)
			(xy 56.812302 -279.105354) (xy 56.763127 -279.103373) (xy 56.714908 -279.093529) (xy 56.668892 -279.076077)
			(xy 56.626271 -279.05147) (xy 56.58815 -279.020345) (xy 56.555515 -278.983508) (xy 56.529212 -278.941912)
			(xy 56.509921 -278.896636) (xy 56.498144 -278.848852) (xy 56.494184 -278.799798) (xy 56.176926 -278.799798)
			(xy 56.176422 -278.825506) (xy 56.168379 -278.876288) (xy 56.152491 -278.925187) (xy 56.129148 -278.970999)
			(xy 56.098927 -279.012595) (xy 56.062571 -279.048951) (xy 56.020975 -279.079172) (xy 55.975163 -279.102515)
			(xy 55.926264 -279.118403) (xy 55.875482 -279.126446) (xy 55.824066 -279.126446) (xy 55.773284 -279.118403)
			(xy 55.724385 -279.102515) (xy 55.678573 -279.079172) (xy 55.636977 -279.048951) (xy 55.600621 -279.012595)
			(xy 55.5704 -278.970999) (xy 55.547057 -278.925187) (xy 55.531169 -278.876288) (xy 55.523126 -278.825506)
			(xy 55.204448 -278.825506) (xy 55.196732 -278.872982) (xy 55.181148 -278.919663) (xy 55.158277 -278.96324)
			(xy 55.128712 -279.002584) (xy 55.093219 -279.036676) (xy 55.052716 -279.064632) (xy 55.008254 -279.08573)
			(xy 54.960983 -279.099422) (xy 54.912128 -279.105354) (xy 54.862953 -279.103373) (xy 54.814734 -279.093529)
			(xy 54.768718 -279.076077) (xy 54.726097 -279.05147) (xy 54.687976 -279.020345) (xy 54.655341 -278.983508)
			(xy 54.629038 -278.941912) (xy 54.609747 -278.896636) (xy 54.59797 -278.848852) (xy 54.59401 -278.799798)
			(xy 54.277006 -278.799798) (xy 54.276502 -278.825506) (xy 54.268459 -278.876288) (xy 54.252571 -278.925187)
			(xy 54.229228 -278.970999) (xy 54.199007 -279.012595) (xy 54.162651 -279.048951) (xy 54.121055 -279.079172)
			(xy 54.075243 -279.102515) (xy 54.026344 -279.118403) (xy 53.975562 -279.126446) (xy 53.924146 -279.126446)
			(xy 53.873364 -279.118403) (xy 53.824465 -279.102515) (xy 53.778653 -279.079172) (xy 53.737057 -279.048951)
			(xy 53.700701 -279.012595) (xy 53.67048 -278.970999) (xy 53.647137 -278.925187) (xy 53.631249 -278.876288)
			(xy 53.623206 -278.825506) (xy 53.304528 -278.825506) (xy 53.296812 -278.872982) (xy 53.281228 -278.919663)
			(xy 53.258357 -278.96324) (xy 53.228792 -279.002584) (xy 53.193299 -279.036676) (xy 53.152796 -279.064632)
			(xy 53.108334 -279.08573) (xy 53.061063 -279.099422) (xy 53.012208 -279.105354) (xy 52.963033 -279.103373)
			(xy 52.914814 -279.093529) (xy 52.868798 -279.076077) (xy 52.826177 -279.05147) (xy 52.788056 -279.020345)
			(xy 52.755421 -278.983508) (xy 52.729118 -278.941912) (xy 52.709827 -278.896636) (xy 52.69805 -278.848852)
			(xy 52.69409 -278.799798) (xy 52.377086 -278.799798) (xy 52.376582 -278.825506) (xy 52.368539 -278.876288)
			(xy 52.352651 -278.925187) (xy 52.329308 -278.970999) (xy 52.299087 -279.012595) (xy 52.262731 -279.048951)
			(xy 52.221135 -279.079172) (xy 52.175323 -279.102515) (xy 52.126424 -279.118403) (xy 52.075642 -279.126446)
			(xy 52.024226 -279.126446) (xy 51.973444 -279.118403) (xy 51.924545 -279.102515) (xy 51.878733 -279.079172)
			(xy 51.837137 -279.048951) (xy 51.800781 -279.012595) (xy 51.77056 -278.970999) (xy 51.747217 -278.925187)
			(xy 51.731329 -278.876288) (xy 51.723286 -278.825506) (xy 51.404608 -278.825506) (xy 51.396892 -278.872982)
			(xy 51.381308 -278.919663) (xy 51.358437 -278.96324) (xy 51.328872 -279.002584) (xy 51.293379 -279.036676)
			(xy 51.252876 -279.064632) (xy 51.208414 -279.08573) (xy 51.161143 -279.099422) (xy 51.112288 -279.105354)
			(xy 51.063113 -279.103373) (xy 51.014894 -279.093529) (xy 50.968878 -279.076077) (xy 50.926257 -279.05147)
			(xy 50.888136 -279.020345) (xy 50.855501 -278.983508) (xy 50.829198 -278.941912) (xy 50.809907 -278.896636)
			(xy 50.79813 -278.848852) (xy 50.79417 -278.799798) (xy 50.476912 -278.799798) (xy 50.476408 -278.825506)
			(xy 50.468365 -278.876288) (xy 50.452477 -278.925187) (xy 50.429134 -278.970999) (xy 50.398913 -279.012595)
			(xy 50.362557 -279.048951) (xy 50.320961 -279.079172) (xy 50.275149 -279.102515) (xy 50.22625 -279.118403)
			(xy 50.175468 -279.126446) (xy 50.124052 -279.126446) (xy 50.07327 -279.118403) (xy 50.024371 -279.102515)
			(xy 49.978559 -279.079172) (xy 49.936963 -279.048951) (xy 49.900607 -279.012595) (xy 49.870386 -278.970999)
			(xy 49.847043 -278.925187) (xy 49.831155 -278.876288) (xy 49.823112 -278.825506) (xy 49.503631 -278.825506)
			(xy 49.501826 -278.848189) (xy 49.490368 -278.895359) (xy 49.471592 -278.940122) (xy 49.445971 -278.981352)
			(xy 49.41415 -279.018009) (xy 49.376931 -279.049171) (xy 49.335251 -279.074052) (xy 49.290159 -279.092026)
			(xy 49.242792 -279.102641) (xy 49.218596 -279.104598) (xy 49.209422 -279.105534) (xy 49.192614 -279.113085)
			(xy 49.18583 -279.11933) (xy 49.16424 -279.14092) (xy 49.157392 -279.148318) (xy 49.149659 -279.166916)
			(xy 49.149254 -279.176988) (xy 49.149254 -279.350724) (xy 49.149797 -279.360708) (xy 49.157523 -279.379129)
			(xy 49.16424 -279.386538) (xy 49.18583 -279.408128) (xy 49.192671 -279.414434) (xy 49.209599 -279.422122)
			(xy 49.21885 -279.423114) (xy 49.244833 -279.425114) (xy 49.295726 -279.436318) (xy 49.344196 -279.455453)
			(xy 49.389017 -279.482034) (xy 49.429054 -279.51539) (xy 49.463293 -279.554674) (xy 49.490866 -279.598892)
			(xy 49.511076 -279.646925) (xy 49.52341 -279.697555) (xy 49.527556 -279.7495) (xy 49.527535 -279.749758)
			(xy 49.843956 -279.749758) (xy 49.847916 -279.700704) (xy 49.859693 -279.65292) (xy 49.878984 -279.607644)
			(xy 49.905287 -279.566048) (xy 49.937922 -279.529211) (xy 49.976043 -279.498086) (xy 50.018664 -279.473479)
			(xy 50.06468 -279.456027) (xy 50.112899 -279.446183) (xy 50.162074 -279.444202) (xy 50.210929 -279.450134)
			(xy 50.2582 -279.463826) (xy 50.302662 -279.484924) (xy 50.343165 -279.51288) (xy 50.378658 -279.546972)
			(xy 50.408223 -279.586316) (xy 50.431094 -279.629893) (xy 50.446678 -279.676574) (xy 50.454573 -279.725151)
			(xy 50.455068 -279.749758) (xy 50.454573 -279.774365) (xy 50.454435 -279.775212) (xy 50.773326 -279.775212)
			(xy 50.773326 -279.723796) (xy 50.781369 -279.673014) (xy 50.797257 -279.624115) (xy 50.8206 -279.578303)
			(xy 50.850821 -279.536707) (xy 50.887177 -279.500351) (xy 50.928773 -279.47013) (xy 50.974585 -279.446787)
			(xy 51.023484 -279.430899) (xy 51.074266 -279.422856) (xy 51.125682 -279.422856) (xy 51.176464 -279.430899)
			(xy 51.225363 -279.446787) (xy 51.271175 -279.47013) (xy 51.312771 -279.500351) (xy 51.349127 -279.536707)
			(xy 51.379348 -279.578303) (xy 51.402691 -279.624115) (xy 51.418579 -279.673014) (xy 51.426622 -279.723796)
			(xy 51.427126 -279.749504) (xy 51.427121 -279.749758) (xy 51.74413 -279.749758) (xy 51.74809 -279.700704)
			(xy 51.759867 -279.65292) (xy 51.779158 -279.607644) (xy 51.805461 -279.566048) (xy 51.838096 -279.529211)
			(xy 51.876217 -279.498086) (xy 51.918838 -279.473479) (xy 51.964854 -279.456027) (xy 52.013073 -279.446183)
			(xy 52.062248 -279.444202) (xy 52.111103 -279.450134) (xy 52.158374 -279.463826) (xy 52.202836 -279.484924)
			(xy 52.243339 -279.51288) (xy 52.278832 -279.546972) (xy 52.308397 -279.586316) (xy 52.331268 -279.629893)
			(xy 52.346852 -279.676574) (xy 52.354747 -279.725151) (xy 52.355242 -279.749758) (xy 52.354747 -279.774365)
			(xy 52.354609 -279.775212) (xy 52.673246 -279.775212) (xy 52.673246 -279.723796) (xy 52.681289 -279.673014)
			(xy 52.697177 -279.624115) (xy 52.72052 -279.578303) (xy 52.750741 -279.536707) (xy 52.787097 -279.500351)
			(xy 52.828693 -279.47013) (xy 52.874505 -279.446787) (xy 52.923404 -279.430899) (xy 52.974186 -279.422856)
			(xy 53.025602 -279.422856) (xy 53.076384 -279.430899) (xy 53.125283 -279.446787) (xy 53.171095 -279.47013)
			(xy 53.212691 -279.500351) (xy 53.249047 -279.536707) (xy 53.279268 -279.578303) (xy 53.302611 -279.624115)
			(xy 53.318499 -279.673014) (xy 53.326542 -279.723796) (xy 53.327046 -279.749504) (xy 53.327041 -279.749758)
			(xy 53.64405 -279.749758) (xy 53.64801 -279.700704) (xy 53.659787 -279.65292) (xy 53.679078 -279.607644)
			(xy 53.705381 -279.566048) (xy 53.738016 -279.529211) (xy 53.776137 -279.498086) (xy 53.818758 -279.473479)
			(xy 53.864774 -279.456027) (xy 53.912993 -279.446183) (xy 53.962168 -279.444202) (xy 54.011023 -279.450134)
			(xy 54.058294 -279.463826) (xy 54.102756 -279.484924) (xy 54.143259 -279.51288) (xy 54.178752 -279.546972)
			(xy 54.208317 -279.586316) (xy 54.231188 -279.629893) (xy 54.246772 -279.676574) (xy 54.254667 -279.725151)
			(xy 54.255162 -279.749758) (xy 54.254667 -279.774365) (xy 54.254529 -279.775212) (xy 54.573166 -279.775212)
			(xy 54.573166 -279.723796) (xy 54.581209 -279.673014) (xy 54.597097 -279.624115) (xy 54.62044 -279.578303)
			(xy 54.650661 -279.536707) (xy 54.687017 -279.500351) (xy 54.728613 -279.47013) (xy 54.774425 -279.446787)
			(xy 54.823324 -279.430899) (xy 54.874106 -279.422856) (xy 54.925522 -279.422856) (xy 54.976304 -279.430899)
			(xy 55.025203 -279.446787) (xy 55.071015 -279.47013) (xy 55.112611 -279.500351) (xy 55.148967 -279.536707)
			(xy 55.179188 -279.578303) (xy 55.202531 -279.624115) (xy 55.218419 -279.673014) (xy 55.226462 -279.723796)
			(xy 55.226966 -279.749504) (xy 55.226961 -279.749758) (xy 55.54397 -279.749758) (xy 55.54793 -279.700704)
			(xy 55.559707 -279.65292) (xy 55.578998 -279.607644) (xy 55.605301 -279.566048) (xy 55.637936 -279.529211)
			(xy 55.676057 -279.498086) (xy 55.718678 -279.473479) (xy 55.764694 -279.456027) (xy 55.812913 -279.446183)
			(xy 55.862088 -279.444202) (xy 55.910943 -279.450134) (xy 55.958214 -279.463826) (xy 56.002676 -279.484924)
			(xy 56.043179 -279.51288) (xy 56.078672 -279.546972) (xy 56.108237 -279.586316) (xy 56.131108 -279.629893)
			(xy 56.146692 -279.676574) (xy 56.154587 -279.725151) (xy 56.155082 -279.749758) (xy 56.154587 -279.774365)
			(xy 56.154449 -279.775212) (xy 56.473086 -279.775212) (xy 56.473086 -279.723796) (xy 56.481129 -279.673014)
			(xy 56.497017 -279.624115) (xy 56.52036 -279.578303) (xy 56.550581 -279.536707) (xy 56.586937 -279.500351)
			(xy 56.628533 -279.47013) (xy 56.674345 -279.446787) (xy 56.723244 -279.430899) (xy 56.774026 -279.422856)
			(xy 56.825442 -279.422856) (xy 56.876224 -279.430899) (xy 56.925123 -279.446787) (xy 56.970935 -279.47013)
			(xy 57.012531 -279.500351) (xy 57.048887 -279.536707) (xy 57.079108 -279.578303) (xy 57.102451 -279.624115)
			(xy 57.118339 -279.673014) (xy 57.126382 -279.723796) (xy 57.126886 -279.749504) (xy 57.126881 -279.749758)
			(xy 57.444144 -279.749758) (xy 57.448104 -279.700704) (xy 57.459881 -279.65292) (xy 57.479172 -279.607644)
			(xy 57.505475 -279.566048) (xy 57.53811 -279.529211) (xy 57.576231 -279.498086) (xy 57.618852 -279.473479)
			(xy 57.664868 -279.456027) (xy 57.713087 -279.446183) (xy 57.762262 -279.444202) (xy 57.811117 -279.450134)
			(xy 57.858388 -279.463826) (xy 57.90285 -279.484924) (xy 57.943353 -279.51288) (xy 57.978846 -279.546972)
			(xy 58.008411 -279.586316) (xy 58.031282 -279.629893) (xy 58.046866 -279.676574) (xy 58.054761 -279.725151)
			(xy 58.055256 -279.749758) (xy 58.054761 -279.774365) (xy 58.054623 -279.775212) (xy 58.37326 -279.775212)
			(xy 58.37326 -279.723796) (xy 58.381303 -279.673014) (xy 58.397191 -279.624115) (xy 58.420534 -279.578303)
			(xy 58.450755 -279.536707) (xy 58.487111 -279.500351) (xy 58.528707 -279.47013) (xy 58.574519 -279.446787)
			(xy 58.623418 -279.430899) (xy 58.6742 -279.422856) (xy 58.725616 -279.422856) (xy 58.776398 -279.430899)
			(xy 58.825297 -279.446787) (xy 58.871109 -279.47013) (xy 58.912705 -279.500351) (xy 58.949061 -279.536707)
			(xy 58.979282 -279.578303) (xy 59.002625 -279.624115) (xy 59.018513 -279.673014) (xy 59.026556 -279.723796)
			(xy 59.02706 -279.749504) (xy 59.027055 -279.749758) (xy 59.344064 -279.749758) (xy 59.348024 -279.700704)
			(xy 59.359801 -279.65292) (xy 59.379092 -279.607644) (xy 59.405395 -279.566048) (xy 59.43803 -279.529211)
			(xy 59.476151 -279.498086) (xy 59.518772 -279.473479) (xy 59.564788 -279.456027) (xy 59.613007 -279.446183)
			(xy 59.662182 -279.444202) (xy 59.711037 -279.450134) (xy 59.758308 -279.463826) (xy 59.80277 -279.484924)
			(xy 59.843273 -279.51288) (xy 59.878766 -279.546972) (xy 59.908331 -279.586316) (xy 59.931202 -279.629893)
			(xy 59.946786 -279.676574) (xy 59.954681 -279.725151) (xy 59.955176 -279.749758) (xy 59.954681 -279.774365)
			(xy 59.954543 -279.775212) (xy 60.27318 -279.775212) (xy 60.27318 -279.723796) (xy 60.281223 -279.673014)
			(xy 60.297111 -279.624115) (xy 60.320454 -279.578303) (xy 60.350675 -279.536707) (xy 60.387031 -279.500351)
			(xy 60.428627 -279.47013) (xy 60.474439 -279.446787) (xy 60.523338 -279.430899) (xy 60.57412 -279.422856)
			(xy 60.625536 -279.422856) (xy 60.676318 -279.430899) (xy 60.725217 -279.446787) (xy 60.771029 -279.47013)
			(xy 60.812625 -279.500351) (xy 60.848981 -279.536707) (xy 60.879202 -279.578303) (xy 60.902545 -279.624115)
			(xy 60.918433 -279.673014) (xy 60.926476 -279.723796) (xy 60.92698 -279.749504) (xy 60.926975 -279.749758)
			(xy 61.243984 -279.749758) (xy 61.247944 -279.700704) (xy 61.259721 -279.65292) (xy 61.279012 -279.607644)
			(xy 61.305315 -279.566048) (xy 61.33795 -279.529211) (xy 61.376071 -279.498086) (xy 61.418692 -279.473479)
			(xy 61.464708 -279.456027) (xy 61.512927 -279.446183) (xy 61.562102 -279.444202) (xy 61.610957 -279.450134)
			(xy 61.658228 -279.463826) (xy 61.70269 -279.484924) (xy 61.743193 -279.51288) (xy 61.778686 -279.546972)
			(xy 61.808251 -279.586316) (xy 61.831122 -279.629893) (xy 61.846706 -279.676574) (xy 61.854601 -279.725151)
			(xy 61.855096 -279.749758) (xy 61.854601 -279.774365) (xy 61.854463 -279.775212) (xy 62.1731 -279.775212)
			(xy 62.1731 -279.723796) (xy 62.181143 -279.673014) (xy 62.197031 -279.624115) (xy 62.220374 -279.578303)
			(xy 62.250595 -279.536707) (xy 62.286951 -279.500351) (xy 62.328547 -279.47013) (xy 62.374359 -279.446787)
			(xy 62.423258 -279.430899) (xy 62.47404 -279.422856) (xy 62.525456 -279.422856) (xy 62.576238 -279.430899)
			(xy 62.625137 -279.446787) (xy 62.670949 -279.47013) (xy 62.712545 -279.500351) (xy 62.748901 -279.536707)
			(xy 62.779122 -279.578303) (xy 62.802465 -279.624115) (xy 62.818353 -279.673014) (xy 62.826396 -279.723796)
			(xy 62.8269 -279.749504) (xy 62.826895 -279.749758) (xy 63.144158 -279.749758) (xy 63.148118 -279.700704)
			(xy 63.159895 -279.65292) (xy 63.179186 -279.607644) (xy 63.205489 -279.566048) (xy 63.238124 -279.529211)
			(xy 63.276245 -279.498086) (xy 63.318866 -279.473479) (xy 63.364882 -279.456027) (xy 63.413101 -279.446183)
			(xy 63.462276 -279.444202) (xy 63.511131 -279.450134) (xy 63.558402 -279.463826) (xy 63.602864 -279.484924)
			(xy 63.643367 -279.51288) (xy 63.67886 -279.546972) (xy 63.708425 -279.586316) (xy 63.731296 -279.629893)
			(xy 63.74688 -279.676574) (xy 63.754775 -279.725151) (xy 63.75527 -279.749758) (xy 63.754775 -279.774365)
			(xy 63.754637 -279.775212) (xy 64.073274 -279.775212) (xy 64.073274 -279.723796) (xy 64.081317 -279.673014)
			(xy 64.097205 -279.624115) (xy 64.120548 -279.578303) (xy 64.150769 -279.536707) (xy 64.187125 -279.500351)
			(xy 64.228721 -279.47013) (xy 64.274533 -279.446787) (xy 64.323432 -279.430899) (xy 64.374214 -279.422856)
			(xy 64.42563 -279.422856) (xy 64.476412 -279.430899) (xy 64.525311 -279.446787) (xy 64.571123 -279.47013)
			(xy 64.612719 -279.500351) (xy 64.649075 -279.536707) (xy 64.679296 -279.578303) (xy 64.702639 -279.624115)
			(xy 64.718527 -279.673014) (xy 64.72657 -279.723796) (xy 64.727074 -279.749504) (xy 64.727069 -279.749758)
			(xy 65.044078 -279.749758) (xy 65.048038 -279.700704) (xy 65.059815 -279.65292) (xy 65.079106 -279.607644)
			(xy 65.105409 -279.566048) (xy 65.138044 -279.529211) (xy 65.176165 -279.498086) (xy 65.218786 -279.473479)
			(xy 65.264802 -279.456027) (xy 65.313021 -279.446183) (xy 65.362196 -279.444202) (xy 65.411051 -279.450134)
			(xy 65.458322 -279.463826) (xy 65.502784 -279.484924) (xy 65.543287 -279.51288) (xy 65.57878 -279.546972)
			(xy 65.608345 -279.586316) (xy 65.631216 -279.629893) (xy 65.6468 -279.676574) (xy 65.654695 -279.725151)
			(xy 65.65519 -279.749758) (xy 65.654695 -279.774365) (xy 65.654557 -279.775212) (xy 65.973194 -279.775212)
			(xy 65.973194 -279.723796) (xy 65.981237 -279.673014) (xy 65.997125 -279.624115) (xy 66.020468 -279.578303)
			(xy 66.050689 -279.536707) (xy 66.087045 -279.500351) (xy 66.128641 -279.47013) (xy 66.174453 -279.446787)
			(xy 66.223352 -279.430899) (xy 66.274134 -279.422856) (xy 66.32555 -279.422856) (xy 66.376332 -279.430899)
			(xy 66.425231 -279.446787) (xy 66.471043 -279.47013) (xy 66.512639 -279.500351) (xy 66.548995 -279.536707)
			(xy 66.579216 -279.578303) (xy 66.602559 -279.624115) (xy 66.618447 -279.673014) (xy 66.62649 -279.723796)
			(xy 66.626994 -279.749504) (xy 66.626989 -279.749758) (xy 66.943998 -279.749758) (xy 66.947958 -279.700704)
			(xy 66.959735 -279.65292) (xy 66.979026 -279.607644) (xy 67.005329 -279.566048) (xy 67.037964 -279.529211)
			(xy 67.076085 -279.498086) (xy 67.118706 -279.473479) (xy 67.164722 -279.456027) (xy 67.212941 -279.446183)
			(xy 67.262116 -279.444202) (xy 67.310971 -279.450134) (xy 67.358242 -279.463826) (xy 67.402704 -279.484924)
			(xy 67.443207 -279.51288) (xy 67.4787 -279.546972) (xy 67.508265 -279.586316) (xy 67.531136 -279.629893)
			(xy 67.54672 -279.676574) (xy 67.554615 -279.725151) (xy 67.55511 -279.749758) (xy 67.554615 -279.774365)
			(xy 67.554477 -279.775212) (xy 67.873114 -279.775212) (xy 67.873114 -279.723796) (xy 67.881157 -279.673014)
			(xy 67.897045 -279.624115) (xy 67.920388 -279.578303) (xy 67.950609 -279.536707) (xy 67.986965 -279.500351)
			(xy 68.028561 -279.47013) (xy 68.074373 -279.446787) (xy 68.123272 -279.430899) (xy 68.174054 -279.422856)
			(xy 68.22547 -279.422856) (xy 68.276252 -279.430899) (xy 68.325151 -279.446787) (xy 68.370963 -279.47013)
			(xy 68.412559 -279.500351) (xy 68.448915 -279.536707) (xy 68.479136 -279.578303) (xy 68.502479 -279.624115)
			(xy 68.518367 -279.673014) (xy 68.52641 -279.723796) (xy 68.526914 -279.749504) (xy 68.526909 -279.749758)
			(xy 68.844172 -279.749758) (xy 68.848132 -279.700704) (xy 68.859909 -279.65292) (xy 68.8792 -279.607644)
			(xy 68.905503 -279.566048) (xy 68.938138 -279.529211) (xy 68.976259 -279.498086) (xy 69.01888 -279.473479)
			(xy 69.064896 -279.456027) (xy 69.113115 -279.446183) (xy 69.16229 -279.444202) (xy 69.211145 -279.450134)
			(xy 69.258416 -279.463826) (xy 69.302878 -279.484924) (xy 69.343381 -279.51288) (xy 69.378874 -279.546972)
			(xy 69.408439 -279.586316) (xy 69.43131 -279.629893) (xy 69.446894 -279.676574) (xy 69.454789 -279.725151)
			(xy 69.455284 -279.749758) (xy 69.454789 -279.774365) (xy 69.454651 -279.775212) (xy 69.773288 -279.775212)
			(xy 69.773288 -279.723796) (xy 69.781331 -279.673014) (xy 69.797219 -279.624115) (xy 69.820562 -279.578303)
			(xy 69.850783 -279.536707) (xy 69.887139 -279.500351) (xy 69.928735 -279.47013) (xy 69.974547 -279.446787)
			(xy 70.023446 -279.430899) (xy 70.074228 -279.422856) (xy 70.125644 -279.422856) (xy 70.176426 -279.430899)
			(xy 70.225325 -279.446787) (xy 70.271137 -279.47013) (xy 70.312733 -279.500351) (xy 70.349089 -279.536707)
			(xy 70.37931 -279.578303) (xy 70.402653 -279.624115) (xy 70.418541 -279.673014) (xy 70.426584 -279.723796)
			(xy 70.427088 -279.749504) (xy 70.427083 -279.749758) (xy 70.744092 -279.749758) (xy 70.748052 -279.700704)
			(xy 70.759829 -279.65292) (xy 70.77912 -279.607644) (xy 70.805423 -279.566048) (xy 70.838058 -279.529211)
			(xy 70.876179 -279.498086) (xy 70.9188 -279.473479) (xy 70.964816 -279.456027) (xy 71.013035 -279.446183)
			(xy 71.06221 -279.444202) (xy 71.111065 -279.450134) (xy 71.158336 -279.463826) (xy 71.202798 -279.484924)
			(xy 71.243301 -279.51288) (xy 71.278794 -279.546972) (xy 71.308359 -279.586316) (xy 71.33123 -279.629893)
			(xy 71.346814 -279.676574) (xy 71.354709 -279.725151) (xy 71.355204 -279.749758) (xy 71.354709 -279.774365)
			(xy 71.354571 -279.775212) (xy 71.673208 -279.775212) (xy 71.673208 -279.723796) (xy 71.681251 -279.673014)
			(xy 71.697139 -279.624115) (xy 71.720482 -279.578303) (xy 71.750703 -279.536707) (xy 71.787059 -279.500351)
			(xy 71.828655 -279.47013) (xy 71.874467 -279.446787) (xy 71.923366 -279.430899) (xy 71.974148 -279.422856)
			(xy 72.025564 -279.422856) (xy 72.076346 -279.430899) (xy 72.125245 -279.446787) (xy 72.171057 -279.47013)
			(xy 72.212653 -279.500351) (xy 72.249009 -279.536707) (xy 72.27923 -279.578303) (xy 72.302573 -279.624115)
			(xy 72.318461 -279.673014) (xy 72.326504 -279.723796) (xy 72.327008 -279.749504) (xy 72.327003 -279.749758)
			(xy 72.644012 -279.749758) (xy 72.647972 -279.700704) (xy 72.659749 -279.65292) (xy 72.67904 -279.607644)
			(xy 72.705343 -279.566048) (xy 72.737978 -279.529211) (xy 72.776099 -279.498086) (xy 72.81872 -279.473479)
			(xy 72.864736 -279.456027) (xy 72.912955 -279.446183) (xy 72.96213 -279.444202) (xy 73.010985 -279.450134)
			(xy 73.058256 -279.463826) (xy 73.102718 -279.484924) (xy 73.143221 -279.51288) (xy 73.178714 -279.546972)
			(xy 73.208279 -279.586316) (xy 73.23115 -279.629893) (xy 73.246734 -279.676574) (xy 73.254629 -279.725151)
			(xy 73.255124 -279.749758) (xy 73.254629 -279.774365) (xy 73.254491 -279.775212) (xy 73.573128 -279.775212)
			(xy 73.573128 -279.723796) (xy 73.581171 -279.673014) (xy 73.597059 -279.624115) (xy 73.620402 -279.578303)
			(xy 73.650623 -279.536707) (xy 73.686979 -279.500351) (xy 73.728575 -279.47013) (xy 73.774387 -279.446787)
			(xy 73.823286 -279.430899) (xy 73.874068 -279.422856) (xy 73.925484 -279.422856) (xy 73.976266 -279.430899)
			(xy 74.025165 -279.446787) (xy 74.070977 -279.47013) (xy 74.112573 -279.500351) (xy 74.148929 -279.536707)
			(xy 74.17915 -279.578303) (xy 74.202493 -279.624115) (xy 74.218381 -279.673014) (xy 74.226424 -279.723796)
			(xy 74.226928 -279.749504) (xy 74.226923 -279.749758) (xy 74.543932 -279.749758) (xy 74.547892 -279.700704)
			(xy 74.559669 -279.65292) (xy 74.57896 -279.607644) (xy 74.605263 -279.566048) (xy 74.637898 -279.529211)
			(xy 74.676019 -279.498086) (xy 74.71864 -279.473479) (xy 74.764656 -279.456027) (xy 74.812875 -279.446183)
			(xy 74.86205 -279.444202) (xy 74.910905 -279.450134) (xy 74.958176 -279.463826) (xy 75.002638 -279.484924)
			(xy 75.043141 -279.51288) (xy 75.078634 -279.546972) (xy 75.108199 -279.586316) (xy 75.13107 -279.629893)
			(xy 75.146654 -279.676574) (xy 75.154549 -279.725151) (xy 75.155044 -279.749758) (xy 75.154549 -279.774365)
			(xy 75.154411 -279.775212) (xy 75.473302 -279.775212) (xy 75.473302 -279.723796) (xy 75.481345 -279.673014)
			(xy 75.497233 -279.624115) (xy 75.520576 -279.578303) (xy 75.550797 -279.536707) (xy 75.587153 -279.500351)
			(xy 75.628749 -279.47013) (xy 75.674561 -279.446787) (xy 75.72346 -279.430899) (xy 75.774242 -279.422856)
			(xy 75.825658 -279.422856) (xy 75.87644 -279.430899) (xy 75.925339 -279.446787) (xy 75.971151 -279.47013)
			(xy 76.012747 -279.500351) (xy 76.049103 -279.536707) (xy 76.079324 -279.578303) (xy 76.102667 -279.624115)
			(xy 76.118555 -279.673014) (xy 76.126598 -279.723796) (xy 76.127102 -279.749504) (xy 76.127097 -279.749758)
			(xy 76.444106 -279.749758) (xy 76.448066 -279.700704) (xy 76.459843 -279.65292) (xy 76.479134 -279.607644)
			(xy 76.505437 -279.566048) (xy 76.538072 -279.529211) (xy 76.576193 -279.498086) (xy 76.618814 -279.473479)
			(xy 76.66483 -279.456027) (xy 76.713049 -279.446183) (xy 76.762224 -279.444202) (xy 76.811079 -279.450134)
			(xy 76.85835 -279.463826) (xy 76.902812 -279.484924) (xy 76.943315 -279.51288) (xy 76.978808 -279.546972)
			(xy 77.008373 -279.586316) (xy 77.031244 -279.629893) (xy 77.046828 -279.676574) (xy 77.054723 -279.725151)
			(xy 77.055218 -279.749758) (xy 77.054723 -279.774365) (xy 77.054585 -279.775212) (xy 77.373222 -279.775212)
			(xy 77.373222 -279.723796) (xy 77.381265 -279.673014) (xy 77.397153 -279.624115) (xy 77.420496 -279.578303)
			(xy 77.450717 -279.536707) (xy 77.487073 -279.500351) (xy 77.528669 -279.47013) (xy 77.574481 -279.446787)
			(xy 77.62338 -279.430899) (xy 77.674162 -279.422856) (xy 77.725578 -279.422856) (xy 77.77636 -279.430899)
			(xy 77.825259 -279.446787) (xy 77.871071 -279.47013) (xy 77.912667 -279.500351) (xy 77.949023 -279.536707)
			(xy 77.979244 -279.578303) (xy 78.002587 -279.624115) (xy 78.018475 -279.673014) (xy 78.026518 -279.723796)
			(xy 78.027022 -279.749504) (xy 78.027017 -279.749758) (xy 78.344026 -279.749758) (xy 78.347986 -279.700704)
			(xy 78.359763 -279.65292) (xy 78.379054 -279.607644) (xy 78.405357 -279.566048) (xy 78.437992 -279.529211)
			(xy 78.476113 -279.498086) (xy 78.518734 -279.473479) (xy 78.56475 -279.456027) (xy 78.612969 -279.446183)
			(xy 78.662144 -279.444202) (xy 78.710999 -279.450134) (xy 78.75827 -279.463826) (xy 78.802732 -279.484924)
			(xy 78.843235 -279.51288) (xy 78.878728 -279.546972) (xy 78.908293 -279.586316) (xy 78.931164 -279.629893)
			(xy 78.946748 -279.676574) (xy 78.954643 -279.725151) (xy 78.955138 -279.749758) (xy 78.954643 -279.774365)
			(xy 78.954464 -279.775466) (xy 79.273142 -279.775466) (xy 79.273142 -279.72405) (xy 79.281185 -279.673268)
			(xy 79.297073 -279.624369) (xy 79.320416 -279.578557) (xy 79.350637 -279.536961) (xy 79.386993 -279.500605)
			(xy 79.428589 -279.470384) (xy 79.474401 -279.447041) (xy 79.5233 -279.431153) (xy 79.574082 -279.42311)
			(xy 79.625498 -279.42311) (xy 79.67628 -279.431153) (xy 79.725179 -279.447041) (xy 79.770991 -279.470384)
			(xy 79.812587 -279.500605) (xy 79.848943 -279.536961) (xy 79.879164 -279.578557) (xy 79.902507 -279.624369)
			(xy 79.918395 -279.673268) (xy 79.926438 -279.72405) (xy 79.926942 -279.749758) (xy 80.243946 -279.749758)
			(xy 80.247906 -279.700704) (xy 80.259683 -279.65292) (xy 80.278974 -279.607644) (xy 80.305277 -279.566048)
			(xy 80.337912 -279.529211) (xy 80.376033 -279.498086) (xy 80.418654 -279.473479) (xy 80.46467 -279.456027)
			(xy 80.512889 -279.446183) (xy 80.562064 -279.444202) (xy 80.610919 -279.450134) (xy 80.65819 -279.463826)
			(xy 80.702652 -279.484924) (xy 80.743155 -279.51288) (xy 80.778648 -279.546972) (xy 80.808213 -279.586316)
			(xy 80.831084 -279.629893) (xy 80.846668 -279.676574) (xy 80.854563 -279.725151) (xy 80.855058 -279.749758)
			(xy 80.854563 -279.774365) (xy 80.854384 -279.775466) (xy 81.173316 -279.775466) (xy 81.173316 -279.72405)
			(xy 81.181359 -279.673268) (xy 81.197247 -279.624369) (xy 81.22059 -279.578557) (xy 81.250811 -279.536961)
			(xy 81.287167 -279.500605) (xy 81.328763 -279.470384) (xy 81.374575 -279.447041) (xy 81.423474 -279.431153)
			(xy 81.474256 -279.42311) (xy 81.525672 -279.42311) (xy 81.576454 -279.431153) (xy 81.625353 -279.447041)
			(xy 81.671165 -279.470384) (xy 81.712761 -279.500605) (xy 81.749117 -279.536961) (xy 81.779338 -279.578557)
			(xy 81.802681 -279.624369) (xy 81.818569 -279.673268) (xy 81.826612 -279.72405) (xy 81.827116 -279.749758)
			(xy 81.826612 -279.775466) (xy 82.123276 -279.775466) (xy 82.123276 -279.72405) (xy 82.131319 -279.673268)
			(xy 82.147207 -279.624369) (xy 82.17055 -279.578557) (xy 82.200771 -279.536961) (xy 82.237127 -279.500605)
			(xy 82.278723 -279.470384) (xy 82.324535 -279.447041) (xy 82.373434 -279.431153) (xy 82.424216 -279.42311)
			(xy 82.475632 -279.42311) (xy 82.526414 -279.431153) (xy 82.575313 -279.447041) (xy 82.621125 -279.470384)
			(xy 82.662721 -279.500605) (xy 82.699077 -279.536961) (xy 82.729298 -279.578557) (xy 82.752641 -279.624369)
			(xy 82.768529 -279.673268) (xy 82.776572 -279.72405) (xy 82.777076 -279.749758) (xy 82.777071 -279.750012)
			(xy 83.094334 -279.750012) (xy 83.098294 -279.700958) (xy 83.110071 -279.653174) (xy 83.129362 -279.607898)
			(xy 83.155665 -279.566302) (xy 83.1883 -279.529465) (xy 83.226421 -279.49834) (xy 83.269042 -279.473733)
			(xy 83.315058 -279.456281) (xy 83.363277 -279.446437) (xy 83.412452 -279.444456) (xy 83.461307 -279.450388)
			(xy 83.508578 -279.46408) (xy 83.55304 -279.485178) (xy 83.593543 -279.513134) (xy 83.629036 -279.547226)
			(xy 83.658601 -279.58657) (xy 83.681472 -279.630147) (xy 83.697056 -279.676828) (xy 83.704951 -279.725405)
			(xy 83.705446 -279.750012) (xy 83.704951 -279.774619) (xy 83.697056 -279.823196) (xy 83.681472 -279.869877)
			(xy 83.658601 -279.913454) (xy 83.629036 -279.952798) (xy 83.593543 -279.98689) (xy 83.55304 -280.014846)
			(xy 83.508578 -280.035944) (xy 83.461307 -280.049636) (xy 83.412452 -280.055568) (xy 83.363277 -280.053587)
			(xy 83.315058 -280.043743) (xy 83.269042 -280.026291) (xy 83.226421 -280.001684) (xy 83.1883 -279.970559)
			(xy 83.155665 -279.933722) (xy 83.129362 -279.892126) (xy 83.110071 -279.84685) (xy 83.098294 -279.799066)
			(xy 83.094334 -279.750012) (xy 82.777071 -279.750012) (xy 82.776572 -279.775466) (xy 82.768529 -279.826248)
			(xy 82.752641 -279.875147) (xy 82.729298 -279.920959) (xy 82.699077 -279.962555) (xy 82.662721 -279.998911)
			(xy 82.621125 -280.029132) (xy 82.575313 -280.052475) (xy 82.526414 -280.068363) (xy 82.475632 -280.076406)
			(xy 82.424216 -280.076406) (xy 82.373434 -280.068363) (xy 82.324535 -280.052475) (xy 82.278723 -280.029132)
			(xy 82.237127 -279.998911) (xy 82.200771 -279.962555) (xy 82.17055 -279.920959) (xy 82.147207 -279.875147)
			(xy 82.131319 -279.826248) (xy 82.123276 -279.775466) (xy 81.826612 -279.775466) (xy 81.818569 -279.826248)
			(xy 81.802681 -279.875147) (xy 81.779338 -279.920959) (xy 81.749117 -279.962555) (xy 81.712761 -279.998911)
			(xy 81.671165 -280.029132) (xy 81.625353 -280.052475) (xy 81.576454 -280.068363) (xy 81.525672 -280.076406)
			(xy 81.474256 -280.076406) (xy 81.423474 -280.068363) (xy 81.374575 -280.052475) (xy 81.328763 -280.029132)
			(xy 81.287167 -279.998911) (xy 81.250811 -279.962555) (xy 81.22059 -279.920959) (xy 81.197247 -279.875147)
			(xy 81.181359 -279.826248) (xy 81.173316 -279.775466) (xy 80.854384 -279.775466) (xy 80.846668 -279.822942)
			(xy 80.831084 -279.869623) (xy 80.808213 -279.9132) (xy 80.778648 -279.952544) (xy 80.743155 -279.986636)
			(xy 80.702652 -280.014592) (xy 80.65819 -280.03569) (xy 80.610919 -280.049382) (xy 80.562064 -280.055314)
			(xy 80.512889 -280.053333) (xy 80.46467 -280.043489) (xy 80.418654 -280.026037) (xy 80.376033 -280.00143)
			(xy 80.337912 -279.970305) (xy 80.305277 -279.933468) (xy 80.278974 -279.891872) (xy 80.259683 -279.846596)
			(xy 80.247906 -279.798812) (xy 80.243946 -279.749758) (xy 79.926942 -279.749758) (xy 79.926438 -279.775466)
			(xy 79.918395 -279.826248) (xy 79.902507 -279.875147) (xy 79.879164 -279.920959) (xy 79.848943 -279.962555)
			(xy 79.812587 -279.998911) (xy 79.770991 -280.029132) (xy 79.725179 -280.052475) (xy 79.67628 -280.068363)
			(xy 79.625498 -280.076406) (xy 79.574082 -280.076406) (xy 79.5233 -280.068363) (xy 79.474401 -280.052475)
			(xy 79.428589 -280.029132) (xy 79.386993 -279.998911) (xy 79.350637 -279.962555) (xy 79.320416 -279.920959)
			(xy 79.297073 -279.875147) (xy 79.281185 -279.826248) (xy 79.273142 -279.775466) (xy 78.954464 -279.775466)
			(xy 78.946748 -279.822942) (xy 78.931164 -279.869623) (xy 78.908293 -279.9132) (xy 78.878728 -279.952544)
			(xy 78.843235 -279.986636) (xy 78.802732 -280.014592) (xy 78.75827 -280.03569) (xy 78.710999 -280.049382)
			(xy 78.662144 -280.055314) (xy 78.612969 -280.053333) (xy 78.56475 -280.043489) (xy 78.518734 -280.026037)
			(xy 78.476113 -280.00143) (xy 78.437992 -279.970305) (xy 78.405357 -279.933468) (xy 78.379054 -279.891872)
			(xy 78.359763 -279.846596) (xy 78.347986 -279.798812) (xy 78.344026 -279.749758) (xy 78.027017 -279.749758)
			(xy 78.026518 -279.775212) (xy 78.018475 -279.825994) (xy 78.002587 -279.874893) (xy 77.979244 -279.920705)
			(xy 77.949023 -279.962301) (xy 77.912667 -279.998657) (xy 77.871071 -280.028878) (xy 77.825259 -280.052221)
			(xy 77.77636 -280.068109) (xy 77.725578 -280.076152) (xy 77.674162 -280.076152) (xy 77.62338 -280.068109)
			(xy 77.574481 -280.052221) (xy 77.528669 -280.028878) (xy 77.487073 -279.998657) (xy 77.450717 -279.962301)
			(xy 77.420496 -279.920705) (xy 77.397153 -279.874893) (xy 77.381265 -279.825994) (xy 77.373222 -279.775212)
			(xy 77.054585 -279.775212) (xy 77.046828 -279.822942) (xy 77.031244 -279.869623) (xy 77.008373 -279.9132)
			(xy 76.978808 -279.952544) (xy 76.943315 -279.986636) (xy 76.902812 -280.014592) (xy 76.85835 -280.03569)
			(xy 76.811079 -280.049382) (xy 76.762224 -280.055314) (xy 76.713049 -280.053333) (xy 76.66483 -280.043489)
			(xy 76.618814 -280.026037) (xy 76.576193 -280.00143) (xy 76.538072 -279.970305) (xy 76.505437 -279.933468)
			(xy 76.479134 -279.891872) (xy 76.459843 -279.846596) (xy 76.448066 -279.798812) (xy 76.444106 -279.749758)
			(xy 76.127097 -279.749758) (xy 76.126598 -279.775212) (xy 76.118555 -279.825994) (xy 76.102667 -279.874893)
			(xy 76.079324 -279.920705) (xy 76.049103 -279.962301) (xy 76.012747 -279.998657) (xy 75.971151 -280.028878)
			(xy 75.925339 -280.052221) (xy 75.87644 -280.068109) (xy 75.825658 -280.076152) (xy 75.774242 -280.076152)
			(xy 75.72346 -280.068109) (xy 75.674561 -280.052221) (xy 75.628749 -280.028878) (xy 75.587153 -279.998657)
			(xy 75.550797 -279.962301) (xy 75.520576 -279.920705) (xy 75.497233 -279.874893) (xy 75.481345 -279.825994)
			(xy 75.473302 -279.775212) (xy 75.154411 -279.775212) (xy 75.146654 -279.822942) (xy 75.13107 -279.869623)
			(xy 75.108199 -279.9132) (xy 75.078634 -279.952544) (xy 75.043141 -279.986636) (xy 75.002638 -280.014592)
			(xy 74.958176 -280.03569) (xy 74.910905 -280.049382) (xy 74.86205 -280.055314) (xy 74.812875 -280.053333)
			(xy 74.764656 -280.043489) (xy 74.71864 -280.026037) (xy 74.676019 -280.00143) (xy 74.637898 -279.970305)
			(xy 74.605263 -279.933468) (xy 74.57896 -279.891872) (xy 74.559669 -279.846596) (xy 74.547892 -279.798812)
			(xy 74.543932 -279.749758) (xy 74.226923 -279.749758) (xy 74.226424 -279.775212) (xy 74.218381 -279.825994)
			(xy 74.202493 -279.874893) (xy 74.17915 -279.920705) (xy 74.148929 -279.962301) (xy 74.112573 -279.998657)
			(xy 74.070977 -280.028878) (xy 74.025165 -280.052221) (xy 73.976266 -280.068109) (xy 73.925484 -280.076152)
			(xy 73.874068 -280.076152) (xy 73.823286 -280.068109) (xy 73.774387 -280.052221) (xy 73.728575 -280.028878)
			(xy 73.686979 -279.998657) (xy 73.650623 -279.962301) (xy 73.620402 -279.920705) (xy 73.597059 -279.874893)
			(xy 73.581171 -279.825994) (xy 73.573128 -279.775212) (xy 73.254491 -279.775212) (xy 73.246734 -279.822942)
			(xy 73.23115 -279.869623) (xy 73.208279 -279.9132) (xy 73.178714 -279.952544) (xy 73.143221 -279.986636)
			(xy 73.102718 -280.014592) (xy 73.058256 -280.03569) (xy 73.010985 -280.049382) (xy 72.96213 -280.055314)
			(xy 72.912955 -280.053333) (xy 72.864736 -280.043489) (xy 72.81872 -280.026037) (xy 72.776099 -280.00143)
			(xy 72.737978 -279.970305) (xy 72.705343 -279.933468) (xy 72.67904 -279.891872) (xy 72.659749 -279.846596)
			(xy 72.647972 -279.798812) (xy 72.644012 -279.749758) (xy 72.327003 -279.749758) (xy 72.326504 -279.775212)
			(xy 72.318461 -279.825994) (xy 72.302573 -279.874893) (xy 72.27923 -279.920705) (xy 72.249009 -279.962301)
			(xy 72.212653 -279.998657) (xy 72.171057 -280.028878) (xy 72.125245 -280.052221) (xy 72.076346 -280.068109)
			(xy 72.025564 -280.076152) (xy 71.974148 -280.076152) (xy 71.923366 -280.068109) (xy 71.874467 -280.052221)
			(xy 71.828655 -280.028878) (xy 71.787059 -279.998657) (xy 71.750703 -279.962301) (xy 71.720482 -279.920705)
			(xy 71.697139 -279.874893) (xy 71.681251 -279.825994) (xy 71.673208 -279.775212) (xy 71.354571 -279.775212)
			(xy 71.346814 -279.822942) (xy 71.33123 -279.869623) (xy 71.308359 -279.9132) (xy 71.278794 -279.952544)
			(xy 71.243301 -279.986636) (xy 71.202798 -280.014592) (xy 71.158336 -280.03569) (xy 71.111065 -280.049382)
			(xy 71.06221 -280.055314) (xy 71.013035 -280.053333) (xy 70.964816 -280.043489) (xy 70.9188 -280.026037)
			(xy 70.876179 -280.00143) (xy 70.838058 -279.970305) (xy 70.805423 -279.933468) (xy 70.77912 -279.891872)
			(xy 70.759829 -279.846596) (xy 70.748052 -279.798812) (xy 70.744092 -279.749758) (xy 70.427083 -279.749758)
			(xy 70.426584 -279.775212) (xy 70.418541 -279.825994) (xy 70.402653 -279.874893) (xy 70.37931 -279.920705)
			(xy 70.349089 -279.962301) (xy 70.312733 -279.998657) (xy 70.271137 -280.028878) (xy 70.225325 -280.052221)
			(xy 70.176426 -280.068109) (xy 70.125644 -280.076152) (xy 70.074228 -280.076152) (xy 70.023446 -280.068109)
			(xy 69.974547 -280.052221) (xy 69.928735 -280.028878) (xy 69.887139 -279.998657) (xy 69.850783 -279.962301)
			(xy 69.820562 -279.920705) (xy 69.797219 -279.874893) (xy 69.781331 -279.825994) (xy 69.773288 -279.775212)
			(xy 69.454651 -279.775212) (xy 69.446894 -279.822942) (xy 69.43131 -279.869623) (xy 69.408439 -279.9132)
			(xy 69.378874 -279.952544) (xy 69.343381 -279.986636) (xy 69.302878 -280.014592) (xy 69.258416 -280.03569)
			(xy 69.211145 -280.049382) (xy 69.16229 -280.055314) (xy 69.113115 -280.053333) (xy 69.064896 -280.043489)
			(xy 69.01888 -280.026037) (xy 68.976259 -280.00143) (xy 68.938138 -279.970305) (xy 68.905503 -279.933468)
			(xy 68.8792 -279.891872) (xy 68.859909 -279.846596) (xy 68.848132 -279.798812) (xy 68.844172 -279.749758)
			(xy 68.526909 -279.749758) (xy 68.52641 -279.775212) (xy 68.518367 -279.825994) (xy 68.502479 -279.874893)
			(xy 68.479136 -279.920705) (xy 68.448915 -279.962301) (xy 68.412559 -279.998657) (xy 68.370963 -280.028878)
			(xy 68.325151 -280.052221) (xy 68.276252 -280.068109) (xy 68.22547 -280.076152) (xy 68.174054 -280.076152)
			(xy 68.123272 -280.068109) (xy 68.074373 -280.052221) (xy 68.028561 -280.028878) (xy 67.986965 -279.998657)
			(xy 67.950609 -279.962301) (xy 67.920388 -279.920705) (xy 67.897045 -279.874893) (xy 67.881157 -279.825994)
			(xy 67.873114 -279.775212) (xy 67.554477 -279.775212) (xy 67.54672 -279.822942) (xy 67.531136 -279.869623)
			(xy 67.508265 -279.9132) (xy 67.4787 -279.952544) (xy 67.443207 -279.986636) (xy 67.402704 -280.014592)
			(xy 67.358242 -280.03569) (xy 67.310971 -280.049382) (xy 67.262116 -280.055314) (xy 67.212941 -280.053333)
			(xy 67.164722 -280.043489) (xy 67.118706 -280.026037) (xy 67.076085 -280.00143) (xy 67.037964 -279.970305)
			(xy 67.005329 -279.933468) (xy 66.979026 -279.891872) (xy 66.959735 -279.846596) (xy 66.947958 -279.798812)
			(xy 66.943998 -279.749758) (xy 66.626989 -279.749758) (xy 66.62649 -279.775212) (xy 66.618447 -279.825994)
			(xy 66.602559 -279.874893) (xy 66.579216 -279.920705) (xy 66.548995 -279.962301) (xy 66.512639 -279.998657)
			(xy 66.471043 -280.028878) (xy 66.425231 -280.052221) (xy 66.376332 -280.068109) (xy 66.32555 -280.076152)
			(xy 66.274134 -280.076152) (xy 66.223352 -280.068109) (xy 66.174453 -280.052221) (xy 66.128641 -280.028878)
			(xy 66.087045 -279.998657) (xy 66.050689 -279.962301) (xy 66.020468 -279.920705) (xy 65.997125 -279.874893)
			(xy 65.981237 -279.825994) (xy 65.973194 -279.775212) (xy 65.654557 -279.775212) (xy 65.6468 -279.822942)
			(xy 65.631216 -279.869623) (xy 65.608345 -279.9132) (xy 65.57878 -279.952544) (xy 65.543287 -279.986636)
			(xy 65.502784 -280.014592) (xy 65.458322 -280.03569) (xy 65.411051 -280.049382) (xy 65.362196 -280.055314)
			(xy 65.313021 -280.053333) (xy 65.264802 -280.043489) (xy 65.218786 -280.026037) (xy 65.176165 -280.00143)
			(xy 65.138044 -279.970305) (xy 65.105409 -279.933468) (xy 65.079106 -279.891872) (xy 65.059815 -279.846596)
			(xy 65.048038 -279.798812) (xy 65.044078 -279.749758) (xy 64.727069 -279.749758) (xy 64.72657 -279.775212)
			(xy 64.718527 -279.825994) (xy 64.702639 -279.874893) (xy 64.679296 -279.920705) (xy 64.649075 -279.962301)
			(xy 64.612719 -279.998657) (xy 64.571123 -280.028878) (xy 64.525311 -280.052221) (xy 64.476412 -280.068109)
			(xy 64.42563 -280.076152) (xy 64.374214 -280.076152) (xy 64.323432 -280.068109) (xy 64.274533 -280.052221)
			(xy 64.228721 -280.028878) (xy 64.187125 -279.998657) (xy 64.150769 -279.962301) (xy 64.120548 -279.920705)
			(xy 64.097205 -279.874893) (xy 64.081317 -279.825994) (xy 64.073274 -279.775212) (xy 63.754637 -279.775212)
			(xy 63.74688 -279.822942) (xy 63.731296 -279.869623) (xy 63.708425 -279.9132) (xy 63.67886 -279.952544)
			(xy 63.643367 -279.986636) (xy 63.602864 -280.014592) (xy 63.558402 -280.03569) (xy 63.511131 -280.049382)
			(xy 63.462276 -280.055314) (xy 63.413101 -280.053333) (xy 63.364882 -280.043489) (xy 63.318866 -280.026037)
			(xy 63.276245 -280.00143) (xy 63.238124 -279.970305) (xy 63.205489 -279.933468) (xy 63.179186 -279.891872)
			(xy 63.159895 -279.846596) (xy 63.148118 -279.798812) (xy 63.144158 -279.749758) (xy 62.826895 -279.749758)
			(xy 62.826396 -279.775212) (xy 62.818353 -279.825994) (xy 62.802465 -279.874893) (xy 62.779122 -279.920705)
			(xy 62.748901 -279.962301) (xy 62.712545 -279.998657) (xy 62.670949 -280.028878) (xy 62.625137 -280.052221)
			(xy 62.576238 -280.068109) (xy 62.525456 -280.076152) (xy 62.47404 -280.076152) (xy 62.423258 -280.068109)
			(xy 62.374359 -280.052221) (xy 62.328547 -280.028878) (xy 62.286951 -279.998657) (xy 62.250595 -279.962301)
			(xy 62.220374 -279.920705) (xy 62.197031 -279.874893) (xy 62.181143 -279.825994) (xy 62.1731 -279.775212)
			(xy 61.854463 -279.775212) (xy 61.846706 -279.822942) (xy 61.831122 -279.869623) (xy 61.808251 -279.9132)
			(xy 61.778686 -279.952544) (xy 61.743193 -279.986636) (xy 61.70269 -280.014592) (xy 61.658228 -280.03569)
			(xy 61.610957 -280.049382) (xy 61.562102 -280.055314) (xy 61.512927 -280.053333) (xy 61.464708 -280.043489)
			(xy 61.418692 -280.026037) (xy 61.376071 -280.00143) (xy 61.33795 -279.970305) (xy 61.305315 -279.933468)
			(xy 61.279012 -279.891872) (xy 61.259721 -279.846596) (xy 61.247944 -279.798812) (xy 61.243984 -279.749758)
			(xy 60.926975 -279.749758) (xy 60.926476 -279.775212) (xy 60.918433 -279.825994) (xy 60.902545 -279.874893)
			(xy 60.879202 -279.920705) (xy 60.848981 -279.962301) (xy 60.812625 -279.998657) (xy 60.771029 -280.028878)
			(xy 60.725217 -280.052221) (xy 60.676318 -280.068109) (xy 60.625536 -280.076152) (xy 60.57412 -280.076152)
			(xy 60.523338 -280.068109) (xy 60.474439 -280.052221) (xy 60.428627 -280.028878) (xy 60.387031 -279.998657)
			(xy 60.350675 -279.962301) (xy 60.320454 -279.920705) (xy 60.297111 -279.874893) (xy 60.281223 -279.825994)
			(xy 60.27318 -279.775212) (xy 59.954543 -279.775212) (xy 59.946786 -279.822942) (xy 59.931202 -279.869623)
			(xy 59.908331 -279.9132) (xy 59.878766 -279.952544) (xy 59.843273 -279.986636) (xy 59.80277 -280.014592)
			(xy 59.758308 -280.03569) (xy 59.711037 -280.049382) (xy 59.662182 -280.055314) (xy 59.613007 -280.053333)
			(xy 59.564788 -280.043489) (xy 59.518772 -280.026037) (xy 59.476151 -280.00143) (xy 59.43803 -279.970305)
			(xy 59.405395 -279.933468) (xy 59.379092 -279.891872) (xy 59.359801 -279.846596) (xy 59.348024 -279.798812)
			(xy 59.344064 -279.749758) (xy 59.027055 -279.749758) (xy 59.026556 -279.775212) (xy 59.018513 -279.825994)
			(xy 59.002625 -279.874893) (xy 58.979282 -279.920705) (xy 58.949061 -279.962301) (xy 58.912705 -279.998657)
			(xy 58.871109 -280.028878) (xy 58.825297 -280.052221) (xy 58.776398 -280.068109) (xy 58.725616 -280.076152)
			(xy 58.6742 -280.076152) (xy 58.623418 -280.068109) (xy 58.574519 -280.052221) (xy 58.528707 -280.028878)
			(xy 58.487111 -279.998657) (xy 58.450755 -279.962301) (xy 58.420534 -279.920705) (xy 58.397191 -279.874893)
			(xy 58.381303 -279.825994) (xy 58.37326 -279.775212) (xy 58.054623 -279.775212) (xy 58.046866 -279.822942)
			(xy 58.031282 -279.869623) (xy 58.008411 -279.9132) (xy 57.978846 -279.952544) (xy 57.943353 -279.986636)
			(xy 57.90285 -280.014592) (xy 57.858388 -280.03569) (xy 57.811117 -280.049382) (xy 57.762262 -280.055314)
			(xy 57.713087 -280.053333) (xy 57.664868 -280.043489) (xy 57.618852 -280.026037) (xy 57.576231 -280.00143)
			(xy 57.53811 -279.970305) (xy 57.505475 -279.933468) (xy 57.479172 -279.891872) (xy 57.459881 -279.846596)
			(xy 57.448104 -279.798812) (xy 57.444144 -279.749758) (xy 57.126881 -279.749758) (xy 57.126382 -279.775212)
			(xy 57.118339 -279.825994) (xy 57.102451 -279.874893) (xy 57.079108 -279.920705) (xy 57.048887 -279.962301)
			(xy 57.012531 -279.998657) (xy 56.970935 -280.028878) (xy 56.925123 -280.052221) (xy 56.876224 -280.068109)
			(xy 56.825442 -280.076152) (xy 56.774026 -280.076152) (xy 56.723244 -280.068109) (xy 56.674345 -280.052221)
			(xy 56.628533 -280.028878) (xy 56.586937 -279.998657) (xy 56.550581 -279.962301) (xy 56.52036 -279.920705)
			(xy 56.497017 -279.874893) (xy 56.481129 -279.825994) (xy 56.473086 -279.775212) (xy 56.154449 -279.775212)
			(xy 56.146692 -279.822942) (xy 56.131108 -279.869623) (xy 56.108237 -279.9132) (xy 56.078672 -279.952544)
			(xy 56.043179 -279.986636) (xy 56.002676 -280.014592) (xy 55.958214 -280.03569) (xy 55.910943 -280.049382)
			(xy 55.862088 -280.055314) (xy 55.812913 -280.053333) (xy 55.764694 -280.043489) (xy 55.718678 -280.026037)
			(xy 55.676057 -280.00143) (xy 55.637936 -279.970305) (xy 55.605301 -279.933468) (xy 55.578998 -279.891872)
			(xy 55.559707 -279.846596) (xy 55.54793 -279.798812) (xy 55.54397 -279.749758) (xy 55.226961 -279.749758)
			(xy 55.226462 -279.775212) (xy 55.218419 -279.825994) (xy 55.202531 -279.874893) (xy 55.179188 -279.920705)
			(xy 55.148967 -279.962301) (xy 55.112611 -279.998657) (xy 55.071015 -280.028878) (xy 55.025203 -280.052221)
			(xy 54.976304 -280.068109) (xy 54.925522 -280.076152) (xy 54.874106 -280.076152) (xy 54.823324 -280.068109)
			(xy 54.774425 -280.052221) (xy 54.728613 -280.028878) (xy 54.687017 -279.998657) (xy 54.650661 -279.962301)
			(xy 54.62044 -279.920705) (xy 54.597097 -279.874893) (xy 54.581209 -279.825994) (xy 54.573166 -279.775212)
			(xy 54.254529 -279.775212) (xy 54.246772 -279.822942) (xy 54.231188 -279.869623) (xy 54.208317 -279.9132)
			(xy 54.178752 -279.952544) (xy 54.143259 -279.986636) (xy 54.102756 -280.014592) (xy 54.058294 -280.03569)
			(xy 54.011023 -280.049382) (xy 53.962168 -280.055314) (xy 53.912993 -280.053333) (xy 53.864774 -280.043489)
			(xy 53.818758 -280.026037) (xy 53.776137 -280.00143) (xy 53.738016 -279.970305) (xy 53.705381 -279.933468)
			(xy 53.679078 -279.891872) (xy 53.659787 -279.846596) (xy 53.64801 -279.798812) (xy 53.64405 -279.749758)
			(xy 53.327041 -279.749758) (xy 53.326542 -279.775212) (xy 53.318499 -279.825994) (xy 53.302611 -279.874893)
			(xy 53.279268 -279.920705) (xy 53.249047 -279.962301) (xy 53.212691 -279.998657) (xy 53.171095 -280.028878)
			(xy 53.125283 -280.052221) (xy 53.076384 -280.068109) (xy 53.025602 -280.076152) (xy 52.974186 -280.076152)
			(xy 52.923404 -280.068109) (xy 52.874505 -280.052221) (xy 52.828693 -280.028878) (xy 52.787097 -279.998657)
			(xy 52.750741 -279.962301) (xy 52.72052 -279.920705) (xy 52.697177 -279.874893) (xy 52.681289 -279.825994)
			(xy 52.673246 -279.775212) (xy 52.354609 -279.775212) (xy 52.346852 -279.822942) (xy 52.331268 -279.869623)
			(xy 52.308397 -279.9132) (xy 52.278832 -279.952544) (xy 52.243339 -279.986636) (xy 52.202836 -280.014592)
			(xy 52.158374 -280.03569) (xy 52.111103 -280.049382) (xy 52.062248 -280.055314) (xy 52.013073 -280.053333)
			(xy 51.964854 -280.043489) (xy 51.918838 -280.026037) (xy 51.876217 -280.00143) (xy 51.838096 -279.970305)
			(xy 51.805461 -279.933468) (xy 51.779158 -279.891872) (xy 51.759867 -279.846596) (xy 51.74809 -279.798812)
			(xy 51.74413 -279.749758) (xy 51.427121 -279.749758) (xy 51.426622 -279.775212) (xy 51.418579 -279.825994)
			(xy 51.402691 -279.874893) (xy 51.379348 -279.920705) (xy 51.349127 -279.962301) (xy 51.312771 -279.998657)
			(xy 51.271175 -280.028878) (xy 51.225363 -280.052221) (xy 51.176464 -280.068109) (xy 51.125682 -280.076152)
			(xy 51.074266 -280.076152) (xy 51.023484 -280.068109) (xy 50.974585 -280.052221) (xy 50.928773 -280.028878)
			(xy 50.887177 -279.998657) (xy 50.850821 -279.962301) (xy 50.8206 -279.920705) (xy 50.797257 -279.874893)
			(xy 50.781369 -279.825994) (xy 50.773326 -279.775212) (xy 50.454435 -279.775212) (xy 50.446678 -279.822942)
			(xy 50.431094 -279.869623) (xy 50.408223 -279.9132) (xy 50.378658 -279.952544) (xy 50.343165 -279.986636)
			(xy 50.302662 -280.014592) (xy 50.2582 -280.03569) (xy 50.210929 -280.049382) (xy 50.162074 -280.055314)
			(xy 50.112899 -280.053333) (xy 50.06468 -280.043489) (xy 50.018664 -280.026037) (xy 49.976043 -280.00143)
			(xy 49.937922 -279.970305) (xy 49.905287 -279.933468) (xy 49.878984 -279.891872) (xy 49.859693 -279.846596)
			(xy 49.847916 -279.798812) (xy 49.843956 -279.749758) (xy 49.527535 -279.749758) (xy 49.52341 -279.801446)
			(xy 49.511075 -279.852076) (xy 49.490866 -279.900108) (xy 49.463292 -279.944326) (xy 49.429054 -279.98361)
			(xy 49.389017 -280.016966) (xy 49.344196 -280.043548) (xy 49.295725 -280.062683) (xy 49.244833 -280.073886)
			(xy 49.21885 -280.075894) (xy 49.209592 -280.076859) (xy 49.19266 -280.084554) (xy 49.18583 -280.09088)
			(xy 49.16424 -280.11247) (xy 49.157436 -280.119817) (xy 49.149723 -280.13828) (xy 49.149254 -280.148284)
			(xy 49.149254 -280.300938) (xy 49.1498 -280.310921) (xy 49.157529 -280.329338) (xy 49.16424 -280.336752)
			(xy 49.18583 -280.358342) (xy 49.192672 -280.364647) (xy 49.2096 -280.372333) (xy 49.21885 -280.373328)
			(xy 49.244832 -280.375328) (xy 49.295722 -280.386531) (xy 49.344191 -280.405666) (xy 49.38901 -280.432246)
			(xy 49.429045 -280.4656) (xy 49.463282 -280.504883) (xy 49.490854 -280.549099) (xy 49.511063 -280.59713)
			(xy 49.523396 -280.647758) (xy 49.527542 -280.699701) (xy 49.527541 -280.699718) (xy 49.843956 -280.699718)
			(xy 49.847916 -280.650664) (xy 49.859693 -280.60288) (xy 49.878984 -280.557604) (xy 49.905287 -280.516008)
			(xy 49.937922 -280.479171) (xy 49.976043 -280.448046) (xy 50.018664 -280.423439) (xy 50.06468 -280.405987)
			(xy 50.112899 -280.396143) (xy 50.162074 -280.394162) (xy 50.210929 -280.400094) (xy 50.2582 -280.413786)
			(xy 50.302662 -280.434884) (xy 50.343165 -280.46284) (xy 50.378658 -280.496932) (xy 50.408223 -280.536276)
			(xy 50.431094 -280.579853) (xy 50.446678 -280.626534) (xy 50.454573 -280.675111) (xy 50.455068 -280.699718)
			(xy 50.454573 -280.724325) (xy 50.454394 -280.725426) (xy 50.773326 -280.725426) (xy 50.773326 -280.67401)
			(xy 50.781369 -280.623228) (xy 50.797257 -280.574329) (xy 50.8206 -280.528517) (xy 50.850821 -280.486921)
			(xy 50.887177 -280.450565) (xy 50.928773 -280.420344) (xy 50.974585 -280.397001) (xy 51.023484 -280.381113)
			(xy 51.074266 -280.37307) (xy 51.125682 -280.37307) (xy 51.176464 -280.381113) (xy 51.225363 -280.397001)
			(xy 51.271175 -280.420344) (xy 51.312771 -280.450565) (xy 51.349127 -280.486921) (xy 51.379348 -280.528517)
			(xy 51.402691 -280.574329) (xy 51.418579 -280.623228) (xy 51.426622 -280.67401) (xy 51.427126 -280.699718)
			(xy 51.74413 -280.699718) (xy 51.74809 -280.650664) (xy 51.759867 -280.60288) (xy 51.779158 -280.557604)
			(xy 51.805461 -280.516008) (xy 51.838096 -280.479171) (xy 51.876217 -280.448046) (xy 51.918838 -280.423439)
			(xy 51.964854 -280.405987) (xy 52.013073 -280.396143) (xy 52.062248 -280.394162) (xy 52.111103 -280.400094)
			(xy 52.158374 -280.413786) (xy 52.202836 -280.434884) (xy 52.243339 -280.46284) (xy 52.278832 -280.496932)
			(xy 52.308397 -280.536276) (xy 52.331268 -280.579853) (xy 52.346852 -280.626534) (xy 52.354747 -280.675111)
			(xy 52.355242 -280.699718) (xy 52.354747 -280.724325) (xy 52.354568 -280.725426) (xy 52.673246 -280.725426)
			(xy 52.673246 -280.67401) (xy 52.681289 -280.623228) (xy 52.697177 -280.574329) (xy 52.72052 -280.528517)
			(xy 52.750741 -280.486921) (xy 52.787097 -280.450565) (xy 52.828693 -280.420344) (xy 52.874505 -280.397001)
			(xy 52.923404 -280.381113) (xy 52.974186 -280.37307) (xy 53.025602 -280.37307) (xy 53.076384 -280.381113)
			(xy 53.125283 -280.397001) (xy 53.171095 -280.420344) (xy 53.212691 -280.450565) (xy 53.249047 -280.486921)
			(xy 53.279268 -280.528517) (xy 53.302611 -280.574329) (xy 53.318499 -280.623228) (xy 53.326542 -280.67401)
			(xy 53.327046 -280.699718) (xy 53.64405 -280.699718) (xy 53.64801 -280.650664) (xy 53.659787 -280.60288)
			(xy 53.679078 -280.557604) (xy 53.705381 -280.516008) (xy 53.738016 -280.479171) (xy 53.776137 -280.448046)
			(xy 53.818758 -280.423439) (xy 53.864774 -280.405987) (xy 53.912993 -280.396143) (xy 53.962168 -280.394162)
			(xy 54.011023 -280.400094) (xy 54.058294 -280.413786) (xy 54.102756 -280.434884) (xy 54.143259 -280.46284)
			(xy 54.178752 -280.496932) (xy 54.208317 -280.536276) (xy 54.231188 -280.579853) (xy 54.246772 -280.626534)
			(xy 54.254667 -280.675111) (xy 54.255162 -280.699718) (xy 54.254667 -280.724325) (xy 54.254488 -280.725426)
			(xy 54.573166 -280.725426) (xy 54.573166 -280.67401) (xy 54.581209 -280.623228) (xy 54.597097 -280.574329)
			(xy 54.62044 -280.528517) (xy 54.650661 -280.486921) (xy 54.687017 -280.450565) (xy 54.728613 -280.420344)
			(xy 54.774425 -280.397001) (xy 54.823324 -280.381113) (xy 54.874106 -280.37307) (xy 54.925522 -280.37307)
			(xy 54.976304 -280.381113) (xy 55.025203 -280.397001) (xy 55.071015 -280.420344) (xy 55.112611 -280.450565)
			(xy 55.148967 -280.486921) (xy 55.179188 -280.528517) (xy 55.202531 -280.574329) (xy 55.218419 -280.623228)
			(xy 55.226462 -280.67401) (xy 55.226966 -280.699718) (xy 55.54397 -280.699718) (xy 55.54793 -280.650664)
			(xy 55.559707 -280.60288) (xy 55.578998 -280.557604) (xy 55.605301 -280.516008) (xy 55.637936 -280.479171)
			(xy 55.676057 -280.448046) (xy 55.718678 -280.423439) (xy 55.764694 -280.405987) (xy 55.812913 -280.396143)
			(xy 55.862088 -280.394162) (xy 55.910943 -280.400094) (xy 55.958214 -280.413786) (xy 56.002676 -280.434884)
			(xy 56.043179 -280.46284) (xy 56.078672 -280.496932) (xy 56.108237 -280.536276) (xy 56.131108 -280.579853)
			(xy 56.146692 -280.626534) (xy 56.154587 -280.675111) (xy 56.155082 -280.699718) (xy 56.154587 -280.724325)
			(xy 56.154408 -280.725426) (xy 56.473086 -280.725426) (xy 56.473086 -280.67401) (xy 56.481129 -280.623228)
			(xy 56.497017 -280.574329) (xy 56.52036 -280.528517) (xy 56.550581 -280.486921) (xy 56.586937 -280.450565)
			(xy 56.628533 -280.420344) (xy 56.674345 -280.397001) (xy 56.723244 -280.381113) (xy 56.774026 -280.37307)
			(xy 56.825442 -280.37307) (xy 56.876224 -280.381113) (xy 56.925123 -280.397001) (xy 56.970935 -280.420344)
			(xy 57.012531 -280.450565) (xy 57.048887 -280.486921) (xy 57.079108 -280.528517) (xy 57.102451 -280.574329)
			(xy 57.118339 -280.623228) (xy 57.126382 -280.67401) (xy 57.126886 -280.699718) (xy 57.444144 -280.699718)
			(xy 57.448104 -280.650664) (xy 57.459881 -280.60288) (xy 57.479172 -280.557604) (xy 57.505475 -280.516008)
			(xy 57.53811 -280.479171) (xy 57.576231 -280.448046) (xy 57.618852 -280.423439) (xy 57.664868 -280.405987)
			(xy 57.713087 -280.396143) (xy 57.762262 -280.394162) (xy 57.811117 -280.400094) (xy 57.858388 -280.413786)
			(xy 57.90285 -280.434884) (xy 57.943353 -280.46284) (xy 57.978846 -280.496932) (xy 58.008411 -280.536276)
			(xy 58.031282 -280.579853) (xy 58.046866 -280.626534) (xy 58.054761 -280.675111) (xy 58.055256 -280.699718)
			(xy 58.054761 -280.724325) (xy 58.054582 -280.725426) (xy 58.37326 -280.725426) (xy 58.37326 -280.67401)
			(xy 58.381303 -280.623228) (xy 58.397191 -280.574329) (xy 58.420534 -280.528517) (xy 58.450755 -280.486921)
			(xy 58.487111 -280.450565) (xy 58.528707 -280.420344) (xy 58.574519 -280.397001) (xy 58.623418 -280.381113)
			(xy 58.6742 -280.37307) (xy 58.725616 -280.37307) (xy 58.776398 -280.381113) (xy 58.825297 -280.397001)
			(xy 58.871109 -280.420344) (xy 58.912705 -280.450565) (xy 58.949061 -280.486921) (xy 58.979282 -280.528517)
			(xy 59.002625 -280.574329) (xy 59.018513 -280.623228) (xy 59.026556 -280.67401) (xy 59.02706 -280.699718)
			(xy 59.344064 -280.699718) (xy 59.348024 -280.650664) (xy 59.359801 -280.60288) (xy 59.379092 -280.557604)
			(xy 59.405395 -280.516008) (xy 59.43803 -280.479171) (xy 59.476151 -280.448046) (xy 59.518772 -280.423439)
			(xy 59.564788 -280.405987) (xy 59.613007 -280.396143) (xy 59.662182 -280.394162) (xy 59.711037 -280.400094)
			(xy 59.758308 -280.413786) (xy 59.80277 -280.434884) (xy 59.843273 -280.46284) (xy 59.878766 -280.496932)
			(xy 59.908331 -280.536276) (xy 59.931202 -280.579853) (xy 59.946786 -280.626534) (xy 59.954681 -280.675111)
			(xy 59.955176 -280.699718) (xy 59.954681 -280.724325) (xy 59.954502 -280.725426) (xy 60.27318 -280.725426)
			(xy 60.27318 -280.67401) (xy 60.281223 -280.623228) (xy 60.297111 -280.574329) (xy 60.320454 -280.528517)
			(xy 60.350675 -280.486921) (xy 60.387031 -280.450565) (xy 60.428627 -280.420344) (xy 60.474439 -280.397001)
			(xy 60.523338 -280.381113) (xy 60.57412 -280.37307) (xy 60.625536 -280.37307) (xy 60.676318 -280.381113)
			(xy 60.725217 -280.397001) (xy 60.771029 -280.420344) (xy 60.812625 -280.450565) (xy 60.848981 -280.486921)
			(xy 60.879202 -280.528517) (xy 60.902545 -280.574329) (xy 60.918433 -280.623228) (xy 60.926476 -280.67401)
			(xy 60.92698 -280.699718) (xy 61.243984 -280.699718) (xy 61.247944 -280.650664) (xy 61.259721 -280.60288)
			(xy 61.279012 -280.557604) (xy 61.305315 -280.516008) (xy 61.33795 -280.479171) (xy 61.376071 -280.448046)
			(xy 61.418692 -280.423439) (xy 61.464708 -280.405987) (xy 61.512927 -280.396143) (xy 61.562102 -280.394162)
			(xy 61.610957 -280.400094) (xy 61.658228 -280.413786) (xy 61.70269 -280.434884) (xy 61.743193 -280.46284)
			(xy 61.778686 -280.496932) (xy 61.808251 -280.536276) (xy 61.831122 -280.579853) (xy 61.846706 -280.626534)
			(xy 61.854601 -280.675111) (xy 61.855096 -280.699718) (xy 61.854601 -280.724325) (xy 61.854422 -280.725426)
			(xy 62.1731 -280.725426) (xy 62.1731 -280.67401) (xy 62.181143 -280.623228) (xy 62.197031 -280.574329)
			(xy 62.220374 -280.528517) (xy 62.250595 -280.486921) (xy 62.286951 -280.450565) (xy 62.328547 -280.420344)
			(xy 62.374359 -280.397001) (xy 62.423258 -280.381113) (xy 62.47404 -280.37307) (xy 62.525456 -280.37307)
			(xy 62.576238 -280.381113) (xy 62.625137 -280.397001) (xy 62.670949 -280.420344) (xy 62.712545 -280.450565)
			(xy 62.748901 -280.486921) (xy 62.779122 -280.528517) (xy 62.802465 -280.574329) (xy 62.818353 -280.623228)
			(xy 62.826396 -280.67401) (xy 62.8269 -280.699718) (xy 63.144158 -280.699718) (xy 63.148118 -280.650664)
			(xy 63.159895 -280.60288) (xy 63.179186 -280.557604) (xy 63.205489 -280.516008) (xy 63.238124 -280.479171)
			(xy 63.276245 -280.448046) (xy 63.318866 -280.423439) (xy 63.364882 -280.405987) (xy 63.413101 -280.396143)
			(xy 63.462276 -280.394162) (xy 63.511131 -280.400094) (xy 63.558402 -280.413786) (xy 63.602864 -280.434884)
			(xy 63.643367 -280.46284) (xy 63.67886 -280.496932) (xy 63.708425 -280.536276) (xy 63.731296 -280.579853)
			(xy 63.74688 -280.626534) (xy 63.754775 -280.675111) (xy 63.75527 -280.699718) (xy 63.754775 -280.724325)
			(xy 63.754596 -280.725426) (xy 64.073274 -280.725426) (xy 64.073274 -280.67401) (xy 64.081317 -280.623228)
			(xy 64.097205 -280.574329) (xy 64.120548 -280.528517) (xy 64.150769 -280.486921) (xy 64.187125 -280.450565)
			(xy 64.228721 -280.420344) (xy 64.274533 -280.397001) (xy 64.323432 -280.381113) (xy 64.374214 -280.37307)
			(xy 64.42563 -280.37307) (xy 64.476412 -280.381113) (xy 64.525311 -280.397001) (xy 64.571123 -280.420344)
			(xy 64.612719 -280.450565) (xy 64.649075 -280.486921) (xy 64.679296 -280.528517) (xy 64.702639 -280.574329)
			(xy 64.718527 -280.623228) (xy 64.72657 -280.67401) (xy 64.727074 -280.699718) (xy 65.044078 -280.699718)
			(xy 65.048038 -280.650664) (xy 65.059815 -280.60288) (xy 65.079106 -280.557604) (xy 65.105409 -280.516008)
			(xy 65.138044 -280.479171) (xy 65.176165 -280.448046) (xy 65.218786 -280.423439) (xy 65.264802 -280.405987)
			(xy 65.313021 -280.396143) (xy 65.362196 -280.394162) (xy 65.411051 -280.400094) (xy 65.458322 -280.413786)
			(xy 65.502784 -280.434884) (xy 65.543287 -280.46284) (xy 65.57878 -280.496932) (xy 65.608345 -280.536276)
			(xy 65.631216 -280.579853) (xy 65.6468 -280.626534) (xy 65.654695 -280.675111) (xy 65.65519 -280.699718)
			(xy 65.654695 -280.724325) (xy 65.654516 -280.725426) (xy 65.973194 -280.725426) (xy 65.973194 -280.67401)
			(xy 65.981237 -280.623228) (xy 65.997125 -280.574329) (xy 66.020468 -280.528517) (xy 66.050689 -280.486921)
			(xy 66.087045 -280.450565) (xy 66.128641 -280.420344) (xy 66.174453 -280.397001) (xy 66.223352 -280.381113)
			(xy 66.274134 -280.37307) (xy 66.32555 -280.37307) (xy 66.376332 -280.381113) (xy 66.425231 -280.397001)
			(xy 66.471043 -280.420344) (xy 66.512639 -280.450565) (xy 66.548995 -280.486921) (xy 66.579216 -280.528517)
			(xy 66.602559 -280.574329) (xy 66.618447 -280.623228) (xy 66.62649 -280.67401) (xy 66.626994 -280.699718)
			(xy 66.943998 -280.699718) (xy 66.947958 -280.650664) (xy 66.959735 -280.60288) (xy 66.979026 -280.557604)
			(xy 67.005329 -280.516008) (xy 67.037964 -280.479171) (xy 67.076085 -280.448046) (xy 67.118706 -280.423439)
			(xy 67.164722 -280.405987) (xy 67.212941 -280.396143) (xy 67.262116 -280.394162) (xy 67.310971 -280.400094)
			(xy 67.358242 -280.413786) (xy 67.402704 -280.434884) (xy 67.443207 -280.46284) (xy 67.4787 -280.496932)
			(xy 67.508265 -280.536276) (xy 67.531136 -280.579853) (xy 67.54672 -280.626534) (xy 67.554615 -280.675111)
			(xy 67.55511 -280.699718) (xy 67.554615 -280.724325) (xy 67.554436 -280.725426) (xy 67.873114 -280.725426)
			(xy 67.873114 -280.67401) (xy 67.881157 -280.623228) (xy 67.897045 -280.574329) (xy 67.920388 -280.528517)
			(xy 67.950609 -280.486921) (xy 67.986965 -280.450565) (xy 68.028561 -280.420344) (xy 68.074373 -280.397001)
			(xy 68.123272 -280.381113) (xy 68.174054 -280.37307) (xy 68.22547 -280.37307) (xy 68.276252 -280.381113)
			(xy 68.325151 -280.397001) (xy 68.370963 -280.420344) (xy 68.412559 -280.450565) (xy 68.448915 -280.486921)
			(xy 68.479136 -280.528517) (xy 68.502479 -280.574329) (xy 68.518367 -280.623228) (xy 68.52641 -280.67401)
			(xy 68.526914 -280.699718) (xy 68.844172 -280.699718) (xy 68.848132 -280.650664) (xy 68.859909 -280.60288)
			(xy 68.8792 -280.557604) (xy 68.905503 -280.516008) (xy 68.938138 -280.479171) (xy 68.976259 -280.448046)
			(xy 69.01888 -280.423439) (xy 69.064896 -280.405987) (xy 69.113115 -280.396143) (xy 69.16229 -280.394162)
			(xy 69.211145 -280.400094) (xy 69.258416 -280.413786) (xy 69.302878 -280.434884) (xy 69.343381 -280.46284)
			(xy 69.378874 -280.496932) (xy 69.408439 -280.536276) (xy 69.43131 -280.579853) (xy 69.446894 -280.626534)
			(xy 69.454789 -280.675111) (xy 69.455284 -280.699718) (xy 69.454789 -280.724325) (xy 69.45461 -280.725426)
			(xy 69.773288 -280.725426) (xy 69.773288 -280.67401) (xy 69.781331 -280.623228) (xy 69.797219 -280.574329)
			(xy 69.820562 -280.528517) (xy 69.850783 -280.486921) (xy 69.887139 -280.450565) (xy 69.928735 -280.420344)
			(xy 69.974547 -280.397001) (xy 70.023446 -280.381113) (xy 70.074228 -280.37307) (xy 70.125644 -280.37307)
			(xy 70.176426 -280.381113) (xy 70.225325 -280.397001) (xy 70.271137 -280.420344) (xy 70.312733 -280.450565)
			(xy 70.349089 -280.486921) (xy 70.37931 -280.528517) (xy 70.402653 -280.574329) (xy 70.418541 -280.623228)
			(xy 70.426584 -280.67401) (xy 70.427088 -280.699718) (xy 70.744092 -280.699718) (xy 70.748052 -280.650664)
			(xy 70.759829 -280.60288) (xy 70.77912 -280.557604) (xy 70.805423 -280.516008) (xy 70.838058 -280.479171)
			(xy 70.876179 -280.448046) (xy 70.9188 -280.423439) (xy 70.964816 -280.405987) (xy 71.013035 -280.396143)
			(xy 71.06221 -280.394162) (xy 71.111065 -280.400094) (xy 71.158336 -280.413786) (xy 71.202798 -280.434884)
			(xy 71.243301 -280.46284) (xy 71.278794 -280.496932) (xy 71.308359 -280.536276) (xy 71.33123 -280.579853)
			(xy 71.346814 -280.626534) (xy 71.354709 -280.675111) (xy 71.355204 -280.699718) (xy 71.354709 -280.724325)
			(xy 71.35453 -280.725426) (xy 71.673208 -280.725426) (xy 71.673208 -280.67401) (xy 71.681251 -280.623228)
			(xy 71.697139 -280.574329) (xy 71.720482 -280.528517) (xy 71.750703 -280.486921) (xy 71.787059 -280.450565)
			(xy 71.828655 -280.420344) (xy 71.874467 -280.397001) (xy 71.923366 -280.381113) (xy 71.974148 -280.37307)
			(xy 72.025564 -280.37307) (xy 72.076346 -280.381113) (xy 72.125245 -280.397001) (xy 72.171057 -280.420344)
			(xy 72.212653 -280.450565) (xy 72.249009 -280.486921) (xy 72.27923 -280.528517) (xy 72.302573 -280.574329)
			(xy 72.318461 -280.623228) (xy 72.326504 -280.67401) (xy 72.327008 -280.699718) (xy 72.644012 -280.699718)
			(xy 72.647972 -280.650664) (xy 72.659749 -280.60288) (xy 72.67904 -280.557604) (xy 72.705343 -280.516008)
			(xy 72.737978 -280.479171) (xy 72.776099 -280.448046) (xy 72.81872 -280.423439) (xy 72.864736 -280.405987)
			(xy 72.912955 -280.396143) (xy 72.96213 -280.394162) (xy 73.010985 -280.400094) (xy 73.058256 -280.413786)
			(xy 73.102718 -280.434884) (xy 73.143221 -280.46284) (xy 73.178714 -280.496932) (xy 73.208279 -280.536276)
			(xy 73.23115 -280.579853) (xy 73.246734 -280.626534) (xy 73.254629 -280.675111) (xy 73.255124 -280.699718)
			(xy 73.254629 -280.724325) (xy 73.25445 -280.725426) (xy 73.573128 -280.725426) (xy 73.573128 -280.67401)
			(xy 73.581171 -280.623228) (xy 73.597059 -280.574329) (xy 73.620402 -280.528517) (xy 73.650623 -280.486921)
			(xy 73.686979 -280.450565) (xy 73.728575 -280.420344) (xy 73.774387 -280.397001) (xy 73.823286 -280.381113)
			(xy 73.874068 -280.37307) (xy 73.925484 -280.37307) (xy 73.976266 -280.381113) (xy 74.025165 -280.397001)
			(xy 74.070977 -280.420344) (xy 74.112573 -280.450565) (xy 74.148929 -280.486921) (xy 74.17915 -280.528517)
			(xy 74.202493 -280.574329) (xy 74.218381 -280.623228) (xy 74.226424 -280.67401) (xy 74.226928 -280.699718)
			(xy 74.544186 -280.699718) (xy 74.548146 -280.650664) (xy 74.559923 -280.60288) (xy 74.579214 -280.557604)
			(xy 74.605517 -280.516008) (xy 74.638152 -280.479171) (xy 74.676273 -280.448046) (xy 74.718894 -280.423439)
			(xy 74.76491 -280.405987) (xy 74.813129 -280.396143) (xy 74.862304 -280.394162) (xy 74.911159 -280.400094)
			(xy 74.95843 -280.413786) (xy 75.002892 -280.434884) (xy 75.043395 -280.46284) (xy 75.078888 -280.496932)
			(xy 75.108453 -280.536276) (xy 75.131324 -280.579853) (xy 75.146908 -280.626534) (xy 75.154803 -280.675111)
			(xy 75.155298 -280.699718) (xy 75.154803 -280.724325) (xy 75.154624 -280.725426) (xy 75.473302 -280.725426)
			(xy 75.473302 -280.67401) (xy 75.481345 -280.623228) (xy 75.497233 -280.574329) (xy 75.520576 -280.528517)
			(xy 75.550797 -280.486921) (xy 75.587153 -280.450565) (xy 75.628749 -280.420344) (xy 75.674561 -280.397001)
			(xy 75.72346 -280.381113) (xy 75.774242 -280.37307) (xy 75.825658 -280.37307) (xy 75.87644 -280.381113)
			(xy 75.925339 -280.397001) (xy 75.971151 -280.420344) (xy 76.012747 -280.450565) (xy 76.049103 -280.486921)
			(xy 76.079324 -280.528517) (xy 76.102667 -280.574329) (xy 76.118555 -280.623228) (xy 76.126598 -280.67401)
			(xy 76.127102 -280.699718) (xy 76.444106 -280.699718) (xy 76.448066 -280.650664) (xy 76.459843 -280.60288)
			(xy 76.479134 -280.557604) (xy 76.505437 -280.516008) (xy 76.538072 -280.479171) (xy 76.576193 -280.448046)
			(xy 76.618814 -280.423439) (xy 76.66483 -280.405987) (xy 76.713049 -280.396143) (xy 76.762224 -280.394162)
			(xy 76.811079 -280.400094) (xy 76.85835 -280.413786) (xy 76.902812 -280.434884) (xy 76.943315 -280.46284)
			(xy 76.978808 -280.496932) (xy 77.008373 -280.536276) (xy 77.031244 -280.579853) (xy 77.046828 -280.626534)
			(xy 77.054723 -280.675111) (xy 77.055218 -280.699718) (xy 77.054723 -280.724325) (xy 77.054544 -280.725426)
			(xy 77.373222 -280.725426) (xy 77.373222 -280.67401) (xy 77.381265 -280.623228) (xy 77.397153 -280.574329)
			(xy 77.420496 -280.528517) (xy 77.450717 -280.486921) (xy 77.487073 -280.450565) (xy 77.528669 -280.420344)
			(xy 77.574481 -280.397001) (xy 77.62338 -280.381113) (xy 77.674162 -280.37307) (xy 77.725578 -280.37307)
			(xy 77.77636 -280.381113) (xy 77.825259 -280.397001) (xy 77.871071 -280.420344) (xy 77.912667 -280.450565)
			(xy 77.949023 -280.486921) (xy 77.979244 -280.528517) (xy 78.002587 -280.574329) (xy 78.018475 -280.623228)
			(xy 78.026518 -280.67401) (xy 78.027022 -280.699718) (xy 78.344026 -280.699718) (xy 78.347986 -280.650664)
			(xy 78.359763 -280.60288) (xy 78.379054 -280.557604) (xy 78.405357 -280.516008) (xy 78.437992 -280.479171)
			(xy 78.476113 -280.448046) (xy 78.518734 -280.423439) (xy 78.56475 -280.405987) (xy 78.612969 -280.396143)
			(xy 78.662144 -280.394162) (xy 78.710999 -280.400094) (xy 78.75827 -280.413786) (xy 78.802732 -280.434884)
			(xy 78.843235 -280.46284) (xy 78.878728 -280.496932) (xy 78.908293 -280.536276) (xy 78.931164 -280.579853)
			(xy 78.946748 -280.626534) (xy 78.954643 -280.675111) (xy 78.955138 -280.699718) (xy 78.954643 -280.724325)
			(xy 78.954464 -280.725426) (xy 79.273142 -280.725426) (xy 79.273142 -280.67401) (xy 79.281185 -280.623228)
			(xy 79.297073 -280.574329) (xy 79.320416 -280.528517) (xy 79.350637 -280.486921) (xy 79.386993 -280.450565)
			(xy 79.428589 -280.420344) (xy 79.474401 -280.397001) (xy 79.5233 -280.381113) (xy 79.574082 -280.37307)
			(xy 79.625498 -280.37307) (xy 79.67628 -280.381113) (xy 79.725179 -280.397001) (xy 79.770991 -280.420344)
			(xy 79.812587 -280.450565) (xy 79.848943 -280.486921) (xy 79.879164 -280.528517) (xy 79.902507 -280.574329)
			(xy 79.918395 -280.623228) (xy 79.926438 -280.67401) (xy 79.926942 -280.699718) (xy 80.2442 -280.699718)
			(xy 80.24816 -280.650664) (xy 80.259937 -280.60288) (xy 80.279228 -280.557604) (xy 80.305531 -280.516008)
			(xy 80.338166 -280.479171) (xy 80.376287 -280.448046) (xy 80.418908 -280.423439) (xy 80.464924 -280.405987)
			(xy 80.513143 -280.396143) (xy 80.562318 -280.394162) (xy 80.611173 -280.400094) (xy 80.658444 -280.413786)
			(xy 80.702906 -280.434884) (xy 80.743409 -280.46284) (xy 80.778902 -280.496932) (xy 80.808467 -280.536276)
			(xy 80.831338 -280.579853) (xy 80.846922 -280.626534) (xy 80.854817 -280.675111) (xy 80.855312 -280.699718)
			(xy 81.19416 -280.699718) (xy 81.19812 -280.650664) (xy 81.209897 -280.60288) (xy 81.229188 -280.557604)
			(xy 81.255491 -280.516008) (xy 81.288126 -280.479171) (xy 81.326247 -280.448046) (xy 81.368868 -280.423439)
			(xy 81.414884 -280.405987) (xy 81.463103 -280.396143) (xy 81.512278 -280.394162) (xy 81.561133 -280.400094)
			(xy 81.608404 -280.413786) (xy 81.652866 -280.434884) (xy 81.693369 -280.46284) (xy 81.728862 -280.496932)
			(xy 81.758427 -280.536276) (xy 81.781298 -280.579853) (xy 81.796882 -280.626534) (xy 81.804777 -280.675111)
			(xy 81.805272 -280.699718) (xy 82.14412 -280.699718) (xy 82.14808 -280.650664) (xy 82.159857 -280.60288)
			(xy 82.179148 -280.557604) (xy 82.205451 -280.516008) (xy 82.238086 -280.479171) (xy 82.276207 -280.448046)
			(xy 82.318828 -280.423439) (xy 82.364844 -280.405987) (xy 82.413063 -280.396143) (xy 82.462238 -280.394162)
			(xy 82.511093 -280.400094) (xy 82.558364 -280.413786) (xy 82.602826 -280.434884) (xy 82.643329 -280.46284)
			(xy 82.678822 -280.496932) (xy 82.708387 -280.536276) (xy 82.731258 -280.579853) (xy 82.746842 -280.626534)
			(xy 82.754737 -280.675111) (xy 82.755232 -280.699718) (xy 82.754737 -280.724325) (xy 82.746842 -280.772902)
			(xy 82.731258 -280.819583) (xy 82.708387 -280.86316) (xy 82.678822 -280.902504) (xy 82.643329 -280.936596)
			(xy 82.602826 -280.964552) (xy 82.558364 -280.98565) (xy 82.511093 -280.999342) (xy 82.462238 -281.005274)
			(xy 82.413063 -281.003293) (xy 82.364844 -280.993449) (xy 82.318828 -280.975997) (xy 82.276207 -280.95139)
			(xy 82.238086 -280.920265) (xy 82.205451 -280.883428) (xy 82.179148 -280.841832) (xy 82.159857 -280.796556)
			(xy 82.14808 -280.748772) (xy 82.14412 -280.699718) (xy 81.805272 -280.699718) (xy 81.804777 -280.724325)
			(xy 81.796882 -280.772902) (xy 81.781298 -280.819583) (xy 81.758427 -280.86316) (xy 81.728862 -280.902504)
			(xy 81.693369 -280.936596) (xy 81.652866 -280.964552) (xy 81.608404 -280.98565) (xy 81.561133 -280.999342)
			(xy 81.512278 -281.005274) (xy 81.463103 -281.003293) (xy 81.414884 -280.993449) (xy 81.368868 -280.975997)
			(xy 81.326247 -280.95139) (xy 81.288126 -280.920265) (xy 81.255491 -280.883428) (xy 81.229188 -280.841832)
			(xy 81.209897 -280.796556) (xy 81.19812 -280.748772) (xy 81.19416 -280.699718) (xy 80.855312 -280.699718)
			(xy 80.854817 -280.724325) (xy 80.846922 -280.772902) (xy 80.831338 -280.819583) (xy 80.808467 -280.86316)
			(xy 80.778902 -280.902504) (xy 80.743409 -280.936596) (xy 80.702906 -280.964552) (xy 80.658444 -280.98565)
			(xy 80.611173 -280.999342) (xy 80.562318 -281.005274) (xy 80.513143 -281.003293) (xy 80.464924 -280.993449)
			(xy 80.418908 -280.975997) (xy 80.376287 -280.95139) (xy 80.338166 -280.920265) (xy 80.305531 -280.883428)
			(xy 80.279228 -280.841832) (xy 80.259937 -280.796556) (xy 80.24816 -280.748772) (xy 80.2442 -280.699718)
			(xy 79.926942 -280.699718) (xy 79.926438 -280.725426) (xy 79.918395 -280.776208) (xy 79.902507 -280.825107)
			(xy 79.879164 -280.870919) (xy 79.848943 -280.912515) (xy 79.812587 -280.948871) (xy 79.770991 -280.979092)
			(xy 79.725179 -281.002435) (xy 79.67628 -281.018323) (xy 79.625498 -281.026366) (xy 79.574082 -281.026366)
			(xy 79.5233 -281.018323) (xy 79.474401 -281.002435) (xy 79.428589 -280.979092) (xy 79.386993 -280.948871)
			(xy 79.350637 -280.912515) (xy 79.320416 -280.870919) (xy 79.297073 -280.825107) (xy 79.281185 -280.776208)
			(xy 79.273142 -280.725426) (xy 78.954464 -280.725426) (xy 78.946748 -280.772902) (xy 78.931164 -280.819583)
			(xy 78.908293 -280.86316) (xy 78.878728 -280.902504) (xy 78.843235 -280.936596) (xy 78.802732 -280.964552)
			(xy 78.75827 -280.98565) (xy 78.710999 -280.999342) (xy 78.662144 -281.005274) (xy 78.612969 -281.003293)
			(xy 78.56475 -280.993449) (xy 78.518734 -280.975997) (xy 78.476113 -280.95139) (xy 78.437992 -280.920265)
			(xy 78.405357 -280.883428) (xy 78.379054 -280.841832) (xy 78.359763 -280.796556) (xy 78.347986 -280.748772)
			(xy 78.344026 -280.699718) (xy 78.027022 -280.699718) (xy 78.026518 -280.725426) (xy 78.018475 -280.776208)
			(xy 78.002587 -280.825107) (xy 77.979244 -280.870919) (xy 77.949023 -280.912515) (xy 77.912667 -280.948871)
			(xy 77.871071 -280.979092) (xy 77.825259 -281.002435) (xy 77.77636 -281.018323) (xy 77.725578 -281.026366)
			(xy 77.674162 -281.026366) (xy 77.62338 -281.018323) (xy 77.574481 -281.002435) (xy 77.528669 -280.979092)
			(xy 77.487073 -280.948871) (xy 77.450717 -280.912515) (xy 77.420496 -280.870919) (xy 77.397153 -280.825107)
			(xy 77.381265 -280.776208) (xy 77.373222 -280.725426) (xy 77.054544 -280.725426) (xy 77.046828 -280.772902)
			(xy 77.031244 -280.819583) (xy 77.008373 -280.86316) (xy 76.978808 -280.902504) (xy 76.943315 -280.936596)
			(xy 76.902812 -280.964552) (xy 76.85835 -280.98565) (xy 76.811079 -280.999342) (xy 76.762224 -281.005274)
			(xy 76.713049 -281.003293) (xy 76.66483 -280.993449) (xy 76.618814 -280.975997) (xy 76.576193 -280.95139)
			(xy 76.538072 -280.920265) (xy 76.505437 -280.883428) (xy 76.479134 -280.841832) (xy 76.459843 -280.796556)
			(xy 76.448066 -280.748772) (xy 76.444106 -280.699718) (xy 76.127102 -280.699718) (xy 76.126598 -280.725426)
			(xy 76.118555 -280.776208) (xy 76.102667 -280.825107) (xy 76.079324 -280.870919) (xy 76.049103 -280.912515)
			(xy 76.012747 -280.948871) (xy 75.971151 -280.979092) (xy 75.925339 -281.002435) (xy 75.87644 -281.018323)
			(xy 75.825658 -281.026366) (xy 75.774242 -281.026366) (xy 75.72346 -281.018323) (xy 75.674561 -281.002435)
			(xy 75.628749 -280.979092) (xy 75.587153 -280.948871) (xy 75.550797 -280.912515) (xy 75.520576 -280.870919)
			(xy 75.497233 -280.825107) (xy 75.481345 -280.776208) (xy 75.473302 -280.725426) (xy 75.154624 -280.725426)
			(xy 75.146908 -280.772902) (xy 75.131324 -280.819583) (xy 75.108453 -280.86316) (xy 75.078888 -280.902504)
			(xy 75.043395 -280.936596) (xy 75.002892 -280.964552) (xy 74.95843 -280.98565) (xy 74.911159 -280.999342)
			(xy 74.862304 -281.005274) (xy 74.813129 -281.003293) (xy 74.76491 -280.993449) (xy 74.718894 -280.975997)
			(xy 74.676273 -280.95139) (xy 74.638152 -280.920265) (xy 74.605517 -280.883428) (xy 74.579214 -280.841832)
			(xy 74.559923 -280.796556) (xy 74.548146 -280.748772) (xy 74.544186 -280.699718) (xy 74.226928 -280.699718)
			(xy 74.226424 -280.725426) (xy 74.218381 -280.776208) (xy 74.202493 -280.825107) (xy 74.17915 -280.870919)
			(xy 74.148929 -280.912515) (xy 74.112573 -280.948871) (xy 74.070977 -280.979092) (xy 74.025165 -281.002435)
			(xy 73.976266 -281.018323) (xy 73.925484 -281.026366) (xy 73.874068 -281.026366) (xy 73.823286 -281.018323)
			(xy 73.774387 -281.002435) (xy 73.728575 -280.979092) (xy 73.686979 -280.948871) (xy 73.650623 -280.912515)
			(xy 73.620402 -280.870919) (xy 73.597059 -280.825107) (xy 73.581171 -280.776208) (xy 73.573128 -280.725426)
			(xy 73.25445 -280.725426) (xy 73.246734 -280.772902) (xy 73.23115 -280.819583) (xy 73.208279 -280.86316)
			(xy 73.178714 -280.902504) (xy 73.143221 -280.936596) (xy 73.102718 -280.964552) (xy 73.058256 -280.98565)
			(xy 73.010985 -280.999342) (xy 72.96213 -281.005274) (xy 72.912955 -281.003293) (xy 72.864736 -280.993449)
			(xy 72.81872 -280.975997) (xy 72.776099 -280.95139) (xy 72.737978 -280.920265) (xy 72.705343 -280.883428)
			(xy 72.67904 -280.841832) (xy 72.659749 -280.796556) (xy 72.647972 -280.748772) (xy 72.644012 -280.699718)
			(xy 72.327008 -280.699718) (xy 72.326504 -280.725426) (xy 72.318461 -280.776208) (xy 72.302573 -280.825107)
			(xy 72.27923 -280.870919) (xy 72.249009 -280.912515) (xy 72.212653 -280.948871) (xy 72.171057 -280.979092)
			(xy 72.125245 -281.002435) (xy 72.076346 -281.018323) (xy 72.025564 -281.026366) (xy 71.974148 -281.026366)
			(xy 71.923366 -281.018323) (xy 71.874467 -281.002435) (xy 71.828655 -280.979092) (xy 71.787059 -280.948871)
			(xy 71.750703 -280.912515) (xy 71.720482 -280.870919) (xy 71.697139 -280.825107) (xy 71.681251 -280.776208)
			(xy 71.673208 -280.725426) (xy 71.35453 -280.725426) (xy 71.346814 -280.772902) (xy 71.33123 -280.819583)
			(xy 71.308359 -280.86316) (xy 71.278794 -280.902504) (xy 71.243301 -280.936596) (xy 71.202798 -280.964552)
			(xy 71.158336 -280.98565) (xy 71.111065 -280.999342) (xy 71.06221 -281.005274) (xy 71.013035 -281.003293)
			(xy 70.964816 -280.993449) (xy 70.9188 -280.975997) (xy 70.876179 -280.95139) (xy 70.838058 -280.920265)
			(xy 70.805423 -280.883428) (xy 70.77912 -280.841832) (xy 70.759829 -280.796556) (xy 70.748052 -280.748772)
			(xy 70.744092 -280.699718) (xy 70.427088 -280.699718) (xy 70.426584 -280.725426) (xy 70.418541 -280.776208)
			(xy 70.402653 -280.825107) (xy 70.37931 -280.870919) (xy 70.349089 -280.912515) (xy 70.312733 -280.948871)
			(xy 70.271137 -280.979092) (xy 70.225325 -281.002435) (xy 70.176426 -281.018323) (xy 70.125644 -281.026366)
			(xy 70.074228 -281.026366) (xy 70.023446 -281.018323) (xy 69.974547 -281.002435) (xy 69.928735 -280.979092)
			(xy 69.887139 -280.948871) (xy 69.850783 -280.912515) (xy 69.820562 -280.870919) (xy 69.797219 -280.825107)
			(xy 69.781331 -280.776208) (xy 69.773288 -280.725426) (xy 69.45461 -280.725426) (xy 69.446894 -280.772902)
			(xy 69.43131 -280.819583) (xy 69.408439 -280.86316) (xy 69.378874 -280.902504) (xy 69.343381 -280.936596)
			(xy 69.302878 -280.964552) (xy 69.258416 -280.98565) (xy 69.211145 -280.999342) (xy 69.16229 -281.005274)
			(xy 69.113115 -281.003293) (xy 69.064896 -280.993449) (xy 69.01888 -280.975997) (xy 68.976259 -280.95139)
			(xy 68.938138 -280.920265) (xy 68.905503 -280.883428) (xy 68.8792 -280.841832) (xy 68.859909 -280.796556)
			(xy 68.848132 -280.748772) (xy 68.844172 -280.699718) (xy 68.526914 -280.699718) (xy 68.52641 -280.725426)
			(xy 68.518367 -280.776208) (xy 68.502479 -280.825107) (xy 68.479136 -280.870919) (xy 68.448915 -280.912515)
			(xy 68.412559 -280.948871) (xy 68.370963 -280.979092) (xy 68.325151 -281.002435) (xy 68.276252 -281.018323)
			(xy 68.22547 -281.026366) (xy 68.174054 -281.026366) (xy 68.123272 -281.018323) (xy 68.074373 -281.002435)
			(xy 68.028561 -280.979092) (xy 67.986965 -280.948871) (xy 67.950609 -280.912515) (xy 67.920388 -280.870919)
			(xy 67.897045 -280.825107) (xy 67.881157 -280.776208) (xy 67.873114 -280.725426) (xy 67.554436 -280.725426)
			(xy 67.54672 -280.772902) (xy 67.531136 -280.819583) (xy 67.508265 -280.86316) (xy 67.4787 -280.902504)
			(xy 67.443207 -280.936596) (xy 67.402704 -280.964552) (xy 67.358242 -280.98565) (xy 67.310971 -280.999342)
			(xy 67.262116 -281.005274) (xy 67.212941 -281.003293) (xy 67.164722 -280.993449) (xy 67.118706 -280.975997)
			(xy 67.076085 -280.95139) (xy 67.037964 -280.920265) (xy 67.005329 -280.883428) (xy 66.979026 -280.841832)
			(xy 66.959735 -280.796556) (xy 66.947958 -280.748772) (xy 66.943998 -280.699718) (xy 66.626994 -280.699718)
			(xy 66.62649 -280.725426) (xy 66.618447 -280.776208) (xy 66.602559 -280.825107) (xy 66.579216 -280.870919)
			(xy 66.548995 -280.912515) (xy 66.512639 -280.948871) (xy 66.471043 -280.979092) (xy 66.425231 -281.002435)
			(xy 66.376332 -281.018323) (xy 66.32555 -281.026366) (xy 66.274134 -281.026366) (xy 66.223352 -281.018323)
			(xy 66.174453 -281.002435) (xy 66.128641 -280.979092) (xy 66.087045 -280.948871) (xy 66.050689 -280.912515)
			(xy 66.020468 -280.870919) (xy 65.997125 -280.825107) (xy 65.981237 -280.776208) (xy 65.973194 -280.725426)
			(xy 65.654516 -280.725426) (xy 65.6468 -280.772902) (xy 65.631216 -280.819583) (xy 65.608345 -280.86316)
			(xy 65.57878 -280.902504) (xy 65.543287 -280.936596) (xy 65.502784 -280.964552) (xy 65.458322 -280.98565)
			(xy 65.411051 -280.999342) (xy 65.362196 -281.005274) (xy 65.313021 -281.003293) (xy 65.264802 -280.993449)
			(xy 65.218786 -280.975997) (xy 65.176165 -280.95139) (xy 65.138044 -280.920265) (xy 65.105409 -280.883428)
			(xy 65.079106 -280.841832) (xy 65.059815 -280.796556) (xy 65.048038 -280.748772) (xy 65.044078 -280.699718)
			(xy 64.727074 -280.699718) (xy 64.72657 -280.725426) (xy 64.718527 -280.776208) (xy 64.702639 -280.825107)
			(xy 64.679296 -280.870919) (xy 64.649075 -280.912515) (xy 64.612719 -280.948871) (xy 64.571123 -280.979092)
			(xy 64.525311 -281.002435) (xy 64.476412 -281.018323) (xy 64.42563 -281.026366) (xy 64.374214 -281.026366)
			(xy 64.323432 -281.018323) (xy 64.274533 -281.002435) (xy 64.228721 -280.979092) (xy 64.187125 -280.948871)
			(xy 64.150769 -280.912515) (xy 64.120548 -280.870919) (xy 64.097205 -280.825107) (xy 64.081317 -280.776208)
			(xy 64.073274 -280.725426) (xy 63.754596 -280.725426) (xy 63.74688 -280.772902) (xy 63.731296 -280.819583)
			(xy 63.708425 -280.86316) (xy 63.67886 -280.902504) (xy 63.643367 -280.936596) (xy 63.602864 -280.964552)
			(xy 63.558402 -280.98565) (xy 63.511131 -280.999342) (xy 63.462276 -281.005274) (xy 63.413101 -281.003293)
			(xy 63.364882 -280.993449) (xy 63.318866 -280.975997) (xy 63.276245 -280.95139) (xy 63.238124 -280.920265)
			(xy 63.205489 -280.883428) (xy 63.179186 -280.841832) (xy 63.159895 -280.796556) (xy 63.148118 -280.748772)
			(xy 63.144158 -280.699718) (xy 62.8269 -280.699718) (xy 62.826396 -280.725426) (xy 62.818353 -280.776208)
			(xy 62.802465 -280.825107) (xy 62.779122 -280.870919) (xy 62.748901 -280.912515) (xy 62.712545 -280.948871)
			(xy 62.670949 -280.979092) (xy 62.625137 -281.002435) (xy 62.576238 -281.018323) (xy 62.525456 -281.026366)
			(xy 62.47404 -281.026366) (xy 62.423258 -281.018323) (xy 62.374359 -281.002435) (xy 62.328547 -280.979092)
			(xy 62.286951 -280.948871) (xy 62.250595 -280.912515) (xy 62.220374 -280.870919) (xy 62.197031 -280.825107)
			(xy 62.181143 -280.776208) (xy 62.1731 -280.725426) (xy 61.854422 -280.725426) (xy 61.846706 -280.772902)
			(xy 61.831122 -280.819583) (xy 61.808251 -280.86316) (xy 61.778686 -280.902504) (xy 61.743193 -280.936596)
			(xy 61.70269 -280.964552) (xy 61.658228 -280.98565) (xy 61.610957 -280.999342) (xy 61.562102 -281.005274)
			(xy 61.512927 -281.003293) (xy 61.464708 -280.993449) (xy 61.418692 -280.975997) (xy 61.376071 -280.95139)
			(xy 61.33795 -280.920265) (xy 61.305315 -280.883428) (xy 61.279012 -280.841832) (xy 61.259721 -280.796556)
			(xy 61.247944 -280.748772) (xy 61.243984 -280.699718) (xy 60.92698 -280.699718) (xy 60.926476 -280.725426)
			(xy 60.918433 -280.776208) (xy 60.902545 -280.825107) (xy 60.879202 -280.870919) (xy 60.848981 -280.912515)
			(xy 60.812625 -280.948871) (xy 60.771029 -280.979092) (xy 60.725217 -281.002435) (xy 60.676318 -281.018323)
			(xy 60.625536 -281.026366) (xy 60.57412 -281.026366) (xy 60.523338 -281.018323) (xy 60.474439 -281.002435)
			(xy 60.428627 -280.979092) (xy 60.387031 -280.948871) (xy 60.350675 -280.912515) (xy 60.320454 -280.870919)
			(xy 60.297111 -280.825107) (xy 60.281223 -280.776208) (xy 60.27318 -280.725426) (xy 59.954502 -280.725426)
			(xy 59.946786 -280.772902) (xy 59.931202 -280.819583) (xy 59.908331 -280.86316) (xy 59.878766 -280.902504)
			(xy 59.843273 -280.936596) (xy 59.80277 -280.964552) (xy 59.758308 -280.98565) (xy 59.711037 -280.999342)
			(xy 59.662182 -281.005274) (xy 59.613007 -281.003293) (xy 59.564788 -280.993449) (xy 59.518772 -280.975997)
			(xy 59.476151 -280.95139) (xy 59.43803 -280.920265) (xy 59.405395 -280.883428) (xy 59.379092 -280.841832)
			(xy 59.359801 -280.796556) (xy 59.348024 -280.748772) (xy 59.344064 -280.699718) (xy 59.02706 -280.699718)
			(xy 59.026556 -280.725426) (xy 59.018513 -280.776208) (xy 59.002625 -280.825107) (xy 58.979282 -280.870919)
			(xy 58.949061 -280.912515) (xy 58.912705 -280.948871) (xy 58.871109 -280.979092) (xy 58.825297 -281.002435)
			(xy 58.776398 -281.018323) (xy 58.725616 -281.026366) (xy 58.6742 -281.026366) (xy 58.623418 -281.018323)
			(xy 58.574519 -281.002435) (xy 58.528707 -280.979092) (xy 58.487111 -280.948871) (xy 58.450755 -280.912515)
			(xy 58.420534 -280.870919) (xy 58.397191 -280.825107) (xy 58.381303 -280.776208) (xy 58.37326 -280.725426)
			(xy 58.054582 -280.725426) (xy 58.046866 -280.772902) (xy 58.031282 -280.819583) (xy 58.008411 -280.86316)
			(xy 57.978846 -280.902504) (xy 57.943353 -280.936596) (xy 57.90285 -280.964552) (xy 57.858388 -280.98565)
			(xy 57.811117 -280.999342) (xy 57.762262 -281.005274) (xy 57.713087 -281.003293) (xy 57.664868 -280.993449)
			(xy 57.618852 -280.975997) (xy 57.576231 -280.95139) (xy 57.53811 -280.920265) (xy 57.505475 -280.883428)
			(xy 57.479172 -280.841832) (xy 57.459881 -280.796556) (xy 57.448104 -280.748772) (xy 57.444144 -280.699718)
			(xy 57.126886 -280.699718) (xy 57.126382 -280.725426) (xy 57.118339 -280.776208) (xy 57.102451 -280.825107)
			(xy 57.079108 -280.870919) (xy 57.048887 -280.912515) (xy 57.012531 -280.948871) (xy 56.970935 -280.979092)
			(xy 56.925123 -281.002435) (xy 56.876224 -281.018323) (xy 56.825442 -281.026366) (xy 56.774026 -281.026366)
			(xy 56.723244 -281.018323) (xy 56.674345 -281.002435) (xy 56.628533 -280.979092) (xy 56.586937 -280.948871)
			(xy 56.550581 -280.912515) (xy 56.52036 -280.870919) (xy 56.497017 -280.825107) (xy 56.481129 -280.776208)
			(xy 56.473086 -280.725426) (xy 56.154408 -280.725426) (xy 56.146692 -280.772902) (xy 56.131108 -280.819583)
			(xy 56.108237 -280.86316) (xy 56.078672 -280.902504) (xy 56.043179 -280.936596) (xy 56.002676 -280.964552)
			(xy 55.958214 -280.98565) (xy 55.910943 -280.999342) (xy 55.862088 -281.005274) (xy 55.812913 -281.003293)
			(xy 55.764694 -280.993449) (xy 55.718678 -280.975997) (xy 55.676057 -280.95139) (xy 55.637936 -280.920265)
			(xy 55.605301 -280.883428) (xy 55.578998 -280.841832) (xy 55.559707 -280.796556) (xy 55.54793 -280.748772)
			(xy 55.54397 -280.699718) (xy 55.226966 -280.699718) (xy 55.226462 -280.725426) (xy 55.218419 -280.776208)
			(xy 55.202531 -280.825107) (xy 55.179188 -280.870919) (xy 55.148967 -280.912515) (xy 55.112611 -280.948871)
			(xy 55.071015 -280.979092) (xy 55.025203 -281.002435) (xy 54.976304 -281.018323) (xy 54.925522 -281.026366)
			(xy 54.874106 -281.026366) (xy 54.823324 -281.018323) (xy 54.774425 -281.002435) (xy 54.728613 -280.979092)
			(xy 54.687017 -280.948871) (xy 54.650661 -280.912515) (xy 54.62044 -280.870919) (xy 54.597097 -280.825107)
			(xy 54.581209 -280.776208) (xy 54.573166 -280.725426) (xy 54.254488 -280.725426) (xy 54.246772 -280.772902)
			(xy 54.231188 -280.819583) (xy 54.208317 -280.86316) (xy 54.178752 -280.902504) (xy 54.143259 -280.936596)
			(xy 54.102756 -280.964552) (xy 54.058294 -280.98565) (xy 54.011023 -280.999342) (xy 53.962168 -281.005274)
			(xy 53.912993 -281.003293) (xy 53.864774 -280.993449) (xy 53.818758 -280.975997) (xy 53.776137 -280.95139)
			(xy 53.738016 -280.920265) (xy 53.705381 -280.883428) (xy 53.679078 -280.841832) (xy 53.659787 -280.796556)
			(xy 53.64801 -280.748772) (xy 53.64405 -280.699718) (xy 53.327046 -280.699718) (xy 53.326542 -280.725426)
			(xy 53.318499 -280.776208) (xy 53.302611 -280.825107) (xy 53.279268 -280.870919) (xy 53.249047 -280.912515)
			(xy 53.212691 -280.948871) (xy 53.171095 -280.979092) (xy 53.125283 -281.002435) (xy 53.076384 -281.018323)
			(xy 53.025602 -281.026366) (xy 52.974186 -281.026366) (xy 52.923404 -281.018323) (xy 52.874505 -281.002435)
			(xy 52.828693 -280.979092) (xy 52.787097 -280.948871) (xy 52.750741 -280.912515) (xy 52.72052 -280.870919)
			(xy 52.697177 -280.825107) (xy 52.681289 -280.776208) (xy 52.673246 -280.725426) (xy 52.354568 -280.725426)
			(xy 52.346852 -280.772902) (xy 52.331268 -280.819583) (xy 52.308397 -280.86316) (xy 52.278832 -280.902504)
			(xy 52.243339 -280.936596) (xy 52.202836 -280.964552) (xy 52.158374 -280.98565) (xy 52.111103 -280.999342)
			(xy 52.062248 -281.005274) (xy 52.013073 -281.003293) (xy 51.964854 -280.993449) (xy 51.918838 -280.975997)
			(xy 51.876217 -280.95139) (xy 51.838096 -280.920265) (xy 51.805461 -280.883428) (xy 51.779158 -280.841832)
			(xy 51.759867 -280.796556) (xy 51.74809 -280.748772) (xy 51.74413 -280.699718) (xy 51.427126 -280.699718)
			(xy 51.426622 -280.725426) (xy 51.418579 -280.776208) (xy 51.402691 -280.825107) (xy 51.379348 -280.870919)
			(xy 51.349127 -280.912515) (xy 51.312771 -280.948871) (xy 51.271175 -280.979092) (xy 51.225363 -281.002435)
			(xy 51.176464 -281.018323) (xy 51.125682 -281.026366) (xy 51.074266 -281.026366) (xy 51.023484 -281.018323)
			(xy 50.974585 -281.002435) (xy 50.928773 -280.979092) (xy 50.887177 -280.948871) (xy 50.850821 -280.912515)
			(xy 50.8206 -280.870919) (xy 50.797257 -280.825107) (xy 50.781369 -280.776208) (xy 50.773326 -280.725426)
			(xy 50.454394 -280.725426) (xy 50.446678 -280.772902) (xy 50.431094 -280.819583) (xy 50.408223 -280.86316)
			(xy 50.378658 -280.902504) (xy 50.343165 -280.936596) (xy 50.302662 -280.964552) (xy 50.2582 -280.98565)
			(xy 50.210929 -280.999342) (xy 50.162074 -281.005274) (xy 50.112899 -281.003293) (xy 50.06468 -280.993449)
			(xy 50.018664 -280.975997) (xy 49.976043 -280.95139) (xy 49.937922 -280.920265) (xy 49.905287 -280.883428)
			(xy 49.878984 -280.841832) (xy 49.859693 -280.796556) (xy 49.847916 -280.748772) (xy 49.843956 -280.699718)
			(xy 49.527541 -280.699718) (xy 49.523396 -280.751644) (xy 49.511062 -280.802272) (xy 49.490853 -280.850302)
			(xy 49.463281 -280.894519) (xy 49.429043 -280.933801) (xy 49.389008 -280.967155) (xy 49.344189 -280.993735)
			(xy 49.29572 -281.012869) (xy 49.24483 -281.024073) (xy 49.21885 -281.026108) (xy 49.209592 -281.027073)
			(xy 49.192661 -281.03477) (xy 49.18583 -281.041094) (xy 49.16424 -281.062684) (xy 49.157438 -281.070032)
			(xy 49.14973 -281.088495) (xy 49.149254 -281.098498) (xy 49.149254 -281.272742) (xy 49.149686 -281.282808)
			(xy 49.157417 -281.301396) (xy 49.16424 -281.30881) (xy 49.18583 -281.3304) (xy 49.192644 -281.336599)
			(xy 49.209437 -281.344137) (xy 49.218596 -281.345132) (xy 49.244137 -281.347224) (xy 49.294042 -281.358859)
			(xy 49.341303 -281.378664) (xy 49.384593 -281.406083) (xy 49.422697 -281.440346) (xy 49.454545 -281.480491)
			(xy 49.479241 -281.52539) (xy 49.496094 -281.573783) (xy 49.504629 -281.62431) (xy 49.505108 -281.649932)
			(xy 49.843956 -281.649932) (xy 49.847916 -281.600878) (xy 49.859693 -281.553094) (xy 49.878984 -281.507818)
			(xy 49.905287 -281.466222) (xy 49.937922 -281.429385) (xy 49.976043 -281.39826) (xy 50.018664 -281.373653)
			(xy 50.06468 -281.356201) (xy 50.112899 -281.346357) (xy 50.162074 -281.344376) (xy 50.210929 -281.350308)
			(xy 50.2582 -281.364) (xy 50.302662 -281.385098) (xy 50.343165 -281.413054) (xy 50.378658 -281.447146)
			(xy 50.408223 -281.48649) (xy 50.431094 -281.530067) (xy 50.446678 -281.576748) (xy 50.454573 -281.625325)
			(xy 50.455068 -281.649932) (xy 50.79417 -281.649932) (xy 50.79813 -281.600878) (xy 50.809907 -281.553094)
			(xy 50.829198 -281.507818) (xy 50.855501 -281.466222) (xy 50.888136 -281.429385) (xy 50.926257 -281.39826)
			(xy 50.968878 -281.373653) (xy 51.014894 -281.356201) (xy 51.063113 -281.346357) (xy 51.112288 -281.344376)
			(xy 51.161143 -281.350308) (xy 51.208414 -281.364) (xy 51.252876 -281.385098) (xy 51.293379 -281.413054)
			(xy 51.328872 -281.447146) (xy 51.358437 -281.48649) (xy 51.381308 -281.530067) (xy 51.396892 -281.576748)
			(xy 51.404787 -281.625325) (xy 51.405282 -281.649932) (xy 51.74413 -281.649932) (xy 51.74809 -281.600878)
			(xy 51.759867 -281.553094) (xy 51.779158 -281.507818) (xy 51.805461 -281.466222) (xy 51.838096 -281.429385)
			(xy 51.876217 -281.39826) (xy 51.918838 -281.373653) (xy 51.964854 -281.356201) (xy 52.013073 -281.346357)
			(xy 52.062248 -281.344376) (xy 52.111103 -281.350308) (xy 52.158374 -281.364) (xy 52.202836 -281.385098)
			(xy 52.243339 -281.413054) (xy 52.278832 -281.447146) (xy 52.308397 -281.48649) (xy 52.331268 -281.530067)
			(xy 52.346852 -281.576748) (xy 52.354747 -281.625325) (xy 52.355242 -281.649932) (xy 52.69409 -281.649932)
			(xy 52.69805 -281.600878) (xy 52.709827 -281.553094) (xy 52.729118 -281.507818) (xy 52.755421 -281.466222)
			(xy 52.788056 -281.429385) (xy 52.826177 -281.39826) (xy 52.868798 -281.373653) (xy 52.914814 -281.356201)
			(xy 52.963033 -281.346357) (xy 53.012208 -281.344376) (xy 53.061063 -281.350308) (xy 53.108334 -281.364)
			(xy 53.152796 -281.385098) (xy 53.193299 -281.413054) (xy 53.228792 -281.447146) (xy 53.258357 -281.48649)
			(xy 53.281228 -281.530067) (xy 53.296812 -281.576748) (xy 53.304707 -281.625325) (xy 53.305202 -281.649932)
			(xy 53.305037 -281.658139) (xy 53.644226 -281.658139) (xy 53.64692 -281.608578) (xy 53.657596 -281.560106)
			(xy 53.675973 -281.514) (xy 53.701568 -281.471475) (xy 53.733705 -281.43365) (xy 53.771538 -281.401522)
			(xy 53.81407 -281.375939) (xy 53.860181 -281.357573) (xy 53.908656 -281.346909) (xy 53.958217 -281.344228)
			(xy 54.007559 -281.3496) (xy 54.055382 -281.362884) (xy 54.100426 -281.38373) (xy 54.141504 -281.411589)
			(xy 54.177534 -281.445726) (xy 54.207567 -281.485242) (xy 54.230811 -281.529097) (xy 54.246654 -281.576134)
			(xy 54.254679 -281.625115) (xy 54.255162 -281.649932) (xy 54.254991 -281.664115) (xy 54.252315 -281.692355)
			(xy 54.249828 -281.70632) (xy 54.247542 -281.718766) (xy 54.254908 -281.742388) (xy 54.332378 -281.819858)
			(xy 54.356 -281.827224) (xy 54.368446 -281.824938) (xy 54.382412 -281.82246) (xy 54.410651 -281.819789)
			(xy 54.424834 -281.819604) (xy 54.439017 -281.819776) (xy 54.467257 -281.822451) (xy 54.481222 -281.824938)
			(xy 54.493668 -281.827224) (xy 54.51729 -281.819858) (xy 54.59476 -281.742388) (xy 54.602126 -281.718766)
			(xy 54.59984 -281.70632) (xy 54.597357 -281.692355) (xy 54.594689 -281.664115) (xy 54.594506 -281.649932)
			(xy 54.594943 -281.625108) (xy 54.60297 -281.576114) (xy 54.618818 -281.529064) (xy 54.642069 -281.485197)
			(xy 54.672111 -281.44567) (xy 54.708151 -281.411524) (xy 54.749242 -281.383659) (xy 54.794299 -281.362808)
			(xy 54.842135 -281.349522) (xy 54.891491 -281.34415) (xy 54.941066 -281.346834) (xy 54.989554 -281.357502)
			(xy 55.035677 -281.375875) (xy 55.07822 -281.401468) (xy 55.116062 -281.433606) (xy 55.148205 -281.471443)
			(xy 55.173804 -281.513982) (xy 55.192184 -281.560102) (xy 55.20286 -281.608588) (xy 55.205104 -281.649932)
			(xy 55.54397 -281.649932) (xy 55.54793 -281.600878) (xy 55.559707 -281.553094) (xy 55.578998 -281.507818)
			(xy 55.605301 -281.466222) (xy 55.637936 -281.429385) (xy 55.676057 -281.39826) (xy 55.718678 -281.373653)
			(xy 55.764694 -281.356201) (xy 55.812913 -281.346357) (xy 55.862088 -281.344376) (xy 55.910943 -281.350308)
			(xy 55.958214 -281.364) (xy 56.002676 -281.385098) (xy 56.043179 -281.413054) (xy 56.078672 -281.447146)
			(xy 56.108237 -281.48649) (xy 56.131108 -281.530067) (xy 56.146692 -281.576748) (xy 56.154587 -281.625325)
			(xy 56.155082 -281.649932) (xy 56.494184 -281.649932) (xy 56.498144 -281.600878) (xy 56.509921 -281.553094)
			(xy 56.529212 -281.507818) (xy 56.555515 -281.466222) (xy 56.58815 -281.429385) (xy 56.626271 -281.39826)
			(xy 56.668892 -281.373653) (xy 56.714908 -281.356201) (xy 56.763127 -281.346357) (xy 56.812302 -281.344376)
			(xy 56.861157 -281.350308) (xy 56.908428 -281.364) (xy 56.95289 -281.385098) (xy 56.993393 -281.413054)
			(xy 57.028886 -281.447146) (xy 57.058451 -281.48649) (xy 57.081322 -281.530067) (xy 57.096906 -281.576748)
			(xy 57.104801 -281.625325) (xy 57.105296 -281.649932) (xy 57.444144 -281.649932) (xy 57.448104 -281.600878)
			(xy 57.459881 -281.553094) (xy 57.479172 -281.507818) (xy 57.505475 -281.466222) (xy 57.53811 -281.429385)
			(xy 57.576231 -281.39826) (xy 57.618852 -281.373653) (xy 57.664868 -281.356201) (xy 57.713087 -281.346357)
			(xy 57.762262 -281.344376) (xy 57.811117 -281.350308) (xy 57.858388 -281.364) (xy 57.90285 -281.385098)
			(xy 57.943353 -281.413054) (xy 57.978846 -281.447146) (xy 58.008411 -281.48649) (xy 58.031282 -281.530067)
			(xy 58.046866 -281.576748) (xy 58.054761 -281.625325) (xy 58.055256 -281.649932) (xy 58.394104 -281.649932)
			(xy 58.398064 -281.600878) (xy 58.409841 -281.553094) (xy 58.429132 -281.507818) (xy 58.455435 -281.466222)
			(xy 58.48807 -281.429385) (xy 58.526191 -281.39826) (xy 58.568812 -281.373653) (xy 58.614828 -281.356201)
			(xy 58.663047 -281.346357) (xy 58.712222 -281.344376) (xy 58.761077 -281.350308) (xy 58.808348 -281.364)
			(xy 58.85281 -281.385098) (xy 58.893313 -281.413054) (xy 58.928806 -281.447146) (xy 58.958371 -281.48649)
			(xy 58.981242 -281.530067) (xy 58.996826 -281.576748) (xy 59.004721 -281.625325) (xy 59.005216 -281.649932)
			(xy 59.344064 -281.649932) (xy 59.348024 -281.600878) (xy 59.359801 -281.553094) (xy 59.379092 -281.507818)
			(xy 59.405395 -281.466222) (xy 59.43803 -281.429385) (xy 59.476151 -281.39826) (xy 59.518772 -281.373653)
			(xy 59.564788 -281.356201) (xy 59.613007 -281.346357) (xy 59.662182 -281.344376) (xy 59.711037 -281.350308)
			(xy 59.758308 -281.364) (xy 59.80277 -281.385098) (xy 59.843273 -281.413054) (xy 59.878766 -281.447146)
			(xy 59.908331 -281.48649) (xy 59.931202 -281.530067) (xy 59.946786 -281.576748) (xy 59.954681 -281.625325)
			(xy 59.955176 -281.649932) (xy 60.294024 -281.649932) (xy 60.297984 -281.600878) (xy 60.309761 -281.553094)
			(xy 60.329052 -281.507818) (xy 60.355355 -281.466222) (xy 60.38799 -281.429385) (xy 60.426111 -281.39826)
			(xy 60.468732 -281.373653) (xy 60.514748 -281.356201) (xy 60.562967 -281.346357) (xy 60.612142 -281.344376)
			(xy 60.660997 -281.350308) (xy 60.708268 -281.364) (xy 60.75273 -281.385098) (xy 60.793233 -281.413054)
			(xy 60.828726 -281.447146) (xy 60.858291 -281.48649) (xy 60.881162 -281.530067) (xy 60.896746 -281.576748)
			(xy 60.904641 -281.625325) (xy 60.905136 -281.649932) (xy 61.243984 -281.649932) (xy 61.247944 -281.600878)
			(xy 61.259721 -281.553094) (xy 61.279012 -281.507818) (xy 61.305315 -281.466222) (xy 61.33795 -281.429385)
			(xy 61.376071 -281.39826) (xy 61.418692 -281.373653) (xy 61.464708 -281.356201) (xy 61.512927 -281.346357)
			(xy 61.562102 -281.344376) (xy 61.610957 -281.350308) (xy 61.658228 -281.364) (xy 61.70269 -281.385098)
			(xy 61.743193 -281.413054) (xy 61.778686 -281.447146) (xy 61.808251 -281.48649) (xy 61.831122 -281.530067)
			(xy 61.846706 -281.576748) (xy 61.854601 -281.625325) (xy 61.855096 -281.649932) (xy 62.193944 -281.649932)
			(xy 62.197904 -281.600878) (xy 62.209681 -281.553094) (xy 62.228972 -281.507818) (xy 62.255275 -281.466222)
			(xy 62.28791 -281.429385) (xy 62.326031 -281.39826) (xy 62.368652 -281.373653) (xy 62.414668 -281.356201)
			(xy 62.462887 -281.346357) (xy 62.512062 -281.344376) (xy 62.560917 -281.350308) (xy 62.608188 -281.364)
			(xy 62.65265 -281.385098) (xy 62.693153 -281.413054) (xy 62.728646 -281.447146) (xy 62.758211 -281.48649)
			(xy 62.781082 -281.530067) (xy 62.796666 -281.576748) (xy 62.804561 -281.625325) (xy 62.805056 -281.649932)
			(xy 63.144158 -281.649932) (xy 63.148118 -281.600878) (xy 63.159895 -281.553094) (xy 63.179186 -281.507818)
			(xy 63.205489 -281.466222) (xy 63.238124 -281.429385) (xy 63.276245 -281.39826) (xy 63.318866 -281.373653)
			(xy 63.364882 -281.356201) (xy 63.413101 -281.346357) (xy 63.462276 -281.344376) (xy 63.511131 -281.350308)
			(xy 63.558402 -281.364) (xy 63.602864 -281.385098) (xy 63.643367 -281.413054) (xy 63.67886 -281.447146)
			(xy 63.708425 -281.48649) (xy 63.731296 -281.530067) (xy 63.74688 -281.576748) (xy 63.754775 -281.625325)
			(xy 63.75527 -281.649932) (xy 64.094118 -281.649932) (xy 64.098078 -281.600878) (xy 64.109855 -281.553094)
			(xy 64.129146 -281.507818) (xy 64.155449 -281.466222) (xy 64.188084 -281.429385) (xy 64.226205 -281.39826)
			(xy 64.268826 -281.373653) (xy 64.314842 -281.356201) (xy 64.363061 -281.346357) (xy 64.412236 -281.344376)
			(xy 64.461091 -281.350308) (xy 64.508362 -281.364) (xy 64.552824 -281.385098) (xy 64.593327 -281.413054)
			(xy 64.62882 -281.447146) (xy 64.658385 -281.48649) (xy 64.681256 -281.530067) (xy 64.69684 -281.576748)
			(xy 64.704735 -281.625325) (xy 64.70523 -281.649932) (xy 65.044078 -281.649932) (xy 65.048038 -281.600878)
			(xy 65.059815 -281.553094) (xy 65.079106 -281.507818) (xy 65.105409 -281.466222) (xy 65.138044 -281.429385)
			(xy 65.176165 -281.39826) (xy 65.218786 -281.373653) (xy 65.264802 -281.356201) (xy 65.313021 -281.346357)
			(xy 65.362196 -281.344376) (xy 65.411051 -281.350308) (xy 65.458322 -281.364) (xy 65.502784 -281.385098)
			(xy 65.543287 -281.413054) (xy 65.57878 -281.447146) (xy 65.608345 -281.48649) (xy 65.631216 -281.530067)
			(xy 65.6468 -281.576748) (xy 65.654695 -281.625325) (xy 65.65519 -281.649932) (xy 65.994038 -281.649932)
			(xy 65.997998 -281.600878) (xy 66.009775 -281.553094) (xy 66.029066 -281.507818) (xy 66.055369 -281.466222)
			(xy 66.088004 -281.429385) (xy 66.126125 -281.39826) (xy 66.168746 -281.373653) (xy 66.214762 -281.356201)
			(xy 66.262981 -281.346357) (xy 66.312156 -281.344376) (xy 66.361011 -281.350308) (xy 66.408282 -281.364)
			(xy 66.452744 -281.385098) (xy 66.493247 -281.413054) (xy 66.52874 -281.447146) (xy 66.558305 -281.48649)
			(xy 66.581176 -281.530067) (xy 66.59676 -281.576748) (xy 66.604655 -281.625325) (xy 66.60515 -281.649932)
			(xy 66.943998 -281.649932) (xy 66.947958 -281.600878) (xy 66.959735 -281.553094) (xy 66.979026 -281.507818)
			(xy 67.005329 -281.466222) (xy 67.037964 -281.429385) (xy 67.076085 -281.39826) (xy 67.118706 -281.373653)
			(xy 67.164722 -281.356201) (xy 67.212941 -281.346357) (xy 67.262116 -281.344376) (xy 67.310971 -281.350308)
			(xy 67.358242 -281.364) (xy 67.402704 -281.385098) (xy 67.443207 -281.413054) (xy 67.4787 -281.447146)
			(xy 67.508265 -281.48649) (xy 67.531136 -281.530067) (xy 67.54672 -281.576748) (xy 67.554615 -281.625325)
			(xy 67.55511 -281.649932) (xy 67.893958 -281.649932) (xy 67.897918 -281.600878) (xy 67.909695 -281.553094)
			(xy 67.928986 -281.507818) (xy 67.955289 -281.466222) (xy 67.987924 -281.429385) (xy 68.026045 -281.39826)
			(xy 68.068666 -281.373653) (xy 68.114682 -281.356201) (xy 68.162901 -281.346357) (xy 68.212076 -281.344376)
			(xy 68.260931 -281.350308) (xy 68.308202 -281.364) (xy 68.352664 -281.385098) (xy 68.393167 -281.413054)
			(xy 68.42866 -281.447146) (xy 68.458225 -281.48649) (xy 68.481096 -281.530067) (xy 68.49668 -281.576748)
			(xy 68.504575 -281.625325) (xy 68.50507 -281.649932) (xy 68.844172 -281.649932) (xy 68.848132 -281.600878)
			(xy 68.859909 -281.553094) (xy 68.8792 -281.507818) (xy 68.905503 -281.466222) (xy 68.938138 -281.429385)
			(xy 68.976259 -281.39826) (xy 69.01888 -281.373653) (xy 69.064896 -281.356201) (xy 69.113115 -281.346357)
			(xy 69.16229 -281.344376) (xy 69.211145 -281.350308) (xy 69.258416 -281.364) (xy 69.302878 -281.385098)
			(xy 69.343381 -281.413054) (xy 69.378874 -281.447146) (xy 69.408439 -281.48649) (xy 69.43131 -281.530067)
			(xy 69.446894 -281.576748) (xy 69.454789 -281.625325) (xy 69.455284 -281.649932) (xy 69.794132 -281.649932)
			(xy 69.798092 -281.600878) (xy 69.809869 -281.553094) (xy 69.82916 -281.507818) (xy 69.855463 -281.466222)
			(xy 69.888098 -281.429385) (xy 69.926219 -281.39826) (xy 69.96884 -281.373653) (xy 70.014856 -281.356201)
			(xy 70.063075 -281.346357) (xy 70.11225 -281.344376) (xy 70.161105 -281.350308) (xy 70.208376 -281.364)
			(xy 70.252838 -281.385098) (xy 70.293341 -281.413054) (xy 70.328834 -281.447146) (xy 70.358399 -281.48649)
			(xy 70.38127 -281.530067) (xy 70.396854 -281.576748) (xy 70.404749 -281.625325) (xy 70.405244 -281.649932)
			(xy 70.744092 -281.649932) (xy 70.748052 -281.600878) (xy 70.759829 -281.553094) (xy 70.77912 -281.507818)
			(xy 70.805423 -281.466222) (xy 70.838058 -281.429385) (xy 70.876179 -281.39826) (xy 70.9188 -281.373653)
			(xy 70.964816 -281.356201) (xy 71.013035 -281.346357) (xy 71.06221 -281.344376) (xy 71.111065 -281.350308)
			(xy 71.158336 -281.364) (xy 71.202798 -281.385098) (xy 71.243301 -281.413054) (xy 71.278794 -281.447146)
			(xy 71.308359 -281.48649) (xy 71.33123 -281.530067) (xy 71.346814 -281.576748) (xy 71.354709 -281.625325)
			(xy 71.355204 -281.649932) (xy 71.694052 -281.649932) (xy 71.698012 -281.600878) (xy 71.709789 -281.553094)
			(xy 71.72908 -281.507818) (xy 71.755383 -281.466222) (xy 71.788018 -281.429385) (xy 71.826139 -281.39826)
			(xy 71.86876 -281.373653) (xy 71.914776 -281.356201) (xy 71.962995 -281.346357) (xy 72.01217 -281.344376)
			(xy 72.061025 -281.350308) (xy 72.108296 -281.364) (xy 72.152758 -281.385098) (xy 72.193261 -281.413054)
			(xy 72.228754 -281.447146) (xy 72.258319 -281.48649) (xy 72.28119 -281.530067) (xy 72.296774 -281.576748)
			(xy 72.304669 -281.625325) (xy 72.305164 -281.649932) (xy 72.644012 -281.649932) (xy 72.647972 -281.600878)
			(xy 72.659749 -281.553094) (xy 72.67904 -281.507818) (xy 72.705343 -281.466222) (xy 72.737978 -281.429385)
			(xy 72.776099 -281.39826) (xy 72.81872 -281.373653) (xy 72.864736 -281.356201) (xy 72.912955 -281.346357)
			(xy 72.96213 -281.344376) (xy 73.010985 -281.350308) (xy 73.058256 -281.364) (xy 73.102718 -281.385098)
			(xy 73.143221 -281.413054) (xy 73.178714 -281.447146) (xy 73.208279 -281.48649) (xy 73.23115 -281.530067)
			(xy 73.246734 -281.576748) (xy 73.254629 -281.625325) (xy 73.255124 -281.649932) (xy 73.593972 -281.649932)
			(xy 73.597932 -281.600878) (xy 73.609709 -281.553094) (xy 73.629 -281.507818) (xy 73.655303 -281.466222)
			(xy 73.687938 -281.429385) (xy 73.726059 -281.39826) (xy 73.76868 -281.373653) (xy 73.814696 -281.356201)
			(xy 73.862915 -281.346357) (xy 73.91209 -281.344376) (xy 73.960945 -281.350308) (xy 74.008216 -281.364)
			(xy 74.052678 -281.385098) (xy 74.093181 -281.413054) (xy 74.128674 -281.447146) (xy 74.158239 -281.48649)
			(xy 74.18111 -281.530067) (xy 74.196694 -281.576748) (xy 74.204589 -281.625325) (xy 74.205084 -281.649932)
			(xy 74.544186 -281.649932) (xy 74.548146 -281.600878) (xy 74.559923 -281.553094) (xy 74.579214 -281.507818)
			(xy 74.605517 -281.466222) (xy 74.638152 -281.429385) (xy 74.676273 -281.39826) (xy 74.718894 -281.373653)
			(xy 74.76491 -281.356201) (xy 74.813129 -281.346357) (xy 74.862304 -281.344376) (xy 74.911159 -281.350308)
			(xy 74.95843 -281.364) (xy 75.002892 -281.385098) (xy 75.043395 -281.413054) (xy 75.078888 -281.447146)
			(xy 75.108453 -281.48649) (xy 75.131324 -281.530067) (xy 75.146908 -281.576748) (xy 75.154803 -281.625325)
			(xy 75.155298 -281.649932) (xy 75.494146 -281.649932) (xy 75.498106 -281.600878) (xy 75.509883 -281.553094)
			(xy 75.529174 -281.507818) (xy 75.555477 -281.466222) (xy 75.588112 -281.429385) (xy 75.626233 -281.39826)
			(xy 75.668854 -281.373653) (xy 75.71487 -281.356201) (xy 75.763089 -281.346357) (xy 75.812264 -281.344376)
			(xy 75.861119 -281.350308) (xy 75.90839 -281.364) (xy 75.952852 -281.385098) (xy 75.993355 -281.413054)
			(xy 76.028848 -281.447146) (xy 76.058413 -281.48649) (xy 76.081284 -281.530067) (xy 76.096868 -281.576748)
			(xy 76.104763 -281.625325) (xy 76.105258 -281.649932) (xy 76.444106 -281.649932) (xy 76.448066 -281.600878)
			(xy 76.459843 -281.553094) (xy 76.479134 -281.507818) (xy 76.505437 -281.466222) (xy 76.538072 -281.429385)
			(xy 76.576193 -281.39826) (xy 76.618814 -281.373653) (xy 76.66483 -281.356201) (xy 76.713049 -281.346357)
			(xy 76.762224 -281.344376) (xy 76.811079 -281.350308) (xy 76.85835 -281.364) (xy 76.902812 -281.385098)
			(xy 76.943315 -281.413054) (xy 76.978808 -281.447146) (xy 77.008373 -281.48649) (xy 77.031244 -281.530067)
			(xy 77.046828 -281.576748) (xy 77.054723 -281.625325) (xy 77.055213 -281.649678) (xy 77.393812 -281.649678)
			(xy 77.397772 -281.600624) (xy 77.409549 -281.55284) (xy 77.42884 -281.507564) (xy 77.455143 -281.465968)
			(xy 77.487778 -281.429131) (xy 77.525899 -281.398006) (xy 77.56852 -281.373399) (xy 77.614536 -281.355947)
			(xy 77.662755 -281.346103) (xy 77.71193 -281.344122) (xy 77.760785 -281.350054) (xy 77.808056 -281.363746)
			(xy 77.852518 -281.384844) (xy 77.893021 -281.4128) (xy 77.928514 -281.446892) (xy 77.958079 -281.486236)
			(xy 77.98095 -281.529813) (xy 77.996534 -281.576494) (xy 78.004429 -281.625071) (xy 78.004924 -281.649678)
			(xy 78.004919 -281.649932) (xy 78.343772 -281.649932) (xy 78.347732 -281.600878) (xy 78.359509 -281.553094)
			(xy 78.3788 -281.507818) (xy 78.405103 -281.466222) (xy 78.437738 -281.429385) (xy 78.475859 -281.39826)
			(xy 78.51848 -281.373653) (xy 78.564496 -281.356201) (xy 78.612715 -281.346357) (xy 78.66189 -281.344376)
			(xy 78.710745 -281.350308) (xy 78.758016 -281.364) (xy 78.802478 -281.385098) (xy 78.842981 -281.413054)
			(xy 78.878474 -281.447146) (xy 78.908039 -281.48649) (xy 78.93091 -281.530067) (xy 78.946494 -281.576748)
			(xy 78.954389 -281.625325) (xy 78.954884 -281.649932) (xy 79.293986 -281.649932) (xy 79.297946 -281.600878)
			(xy 79.309723 -281.553094) (xy 79.329014 -281.507818) (xy 79.355317 -281.466222) (xy 79.387952 -281.429385)
			(xy 79.426073 -281.39826) (xy 79.468694 -281.373653) (xy 79.51471 -281.356201) (xy 79.562929 -281.346357)
			(xy 79.612104 -281.344376) (xy 79.660959 -281.350308) (xy 79.70823 -281.364) (xy 79.752692 -281.385098)
			(xy 79.793195 -281.413054) (xy 79.828688 -281.447146) (xy 79.858253 -281.48649) (xy 79.881124 -281.530067)
			(xy 79.896708 -281.576748) (xy 79.904603 -281.625325) (xy 79.905098 -281.649932) (xy 80.243946 -281.649932)
			(xy 80.247906 -281.600878) (xy 80.259683 -281.553094) (xy 80.278974 -281.507818) (xy 80.305277 -281.466222)
			(xy 80.337912 -281.429385) (xy 80.376033 -281.39826) (xy 80.418654 -281.373653) (xy 80.46467 -281.356201)
			(xy 80.512889 -281.346357) (xy 80.562064 -281.344376) (xy 80.610919 -281.350308) (xy 80.65819 -281.364)
			(xy 80.702652 -281.385098) (xy 80.743155 -281.413054) (xy 80.778648 -281.447146) (xy 80.808213 -281.48649)
			(xy 80.831084 -281.530067) (xy 80.846668 -281.576748) (xy 80.854563 -281.625325) (xy 80.855058 -281.649932)
			(xy 80.854563 -281.674539) (xy 80.854384 -281.67564) (xy 81.173316 -281.67564) (xy 81.173316 -281.624224)
			(xy 81.181359 -281.573442) (xy 81.197247 -281.524543) (xy 81.22059 -281.478731) (xy 81.250811 -281.437135)
			(xy 81.287167 -281.400779) (xy 81.328763 -281.370558) (xy 81.374575 -281.347215) (xy 81.423474 -281.331327)
			(xy 81.474256 -281.323284) (xy 81.525672 -281.323284) (xy 81.576454 -281.331327) (xy 81.625353 -281.347215)
			(xy 81.671165 -281.370558) (xy 81.712761 -281.400779) (xy 81.749117 -281.437135) (xy 81.779338 -281.478731)
			(xy 81.802681 -281.524543) (xy 81.818569 -281.573442) (xy 81.826612 -281.624224) (xy 81.827116 -281.649932)
			(xy 81.826612 -281.67564) (xy 82.123276 -281.67564) (xy 82.123276 -281.624224) (xy 82.131319 -281.573442)
			(xy 82.147207 -281.524543) (xy 82.17055 -281.478731) (xy 82.200771 -281.437135) (xy 82.237127 -281.400779)
			(xy 82.278723 -281.370558) (xy 82.324535 -281.347215) (xy 82.373434 -281.331327) (xy 82.424216 -281.323284)
			(xy 82.475632 -281.323284) (xy 82.526414 -281.331327) (xy 82.575313 -281.347215) (xy 82.621125 -281.370558)
			(xy 82.662721 -281.400779) (xy 82.699077 -281.437135) (xy 82.729298 -281.478731) (xy 82.752641 -281.524543)
			(xy 82.768529 -281.573442) (xy 82.776572 -281.624224) (xy 82.777076 -281.649932) (xy 82.777071 -281.650186)
			(xy 83.094334 -281.650186) (xy 83.098294 -281.601132) (xy 83.110071 -281.553348) (xy 83.129362 -281.508072)
			(xy 83.155665 -281.466476) (xy 83.1883 -281.429639) (xy 83.226421 -281.398514) (xy 83.269042 -281.373907)
			(xy 83.315058 -281.356455) (xy 83.363277 -281.346611) (xy 83.412452 -281.34463) (xy 83.461307 -281.350562)
			(xy 83.508578 -281.364254) (xy 83.55304 -281.385352) (xy 83.593543 -281.413308) (xy 83.629036 -281.4474)
			(xy 83.658601 -281.486744) (xy 83.681472 -281.530321) (xy 83.697056 -281.577002) (xy 83.704951 -281.625579)
			(xy 83.705446 -281.650186) (xy 83.704951 -281.674793) (xy 83.697056 -281.72337) (xy 83.681472 -281.770051)
			(xy 83.658601 -281.813628) (xy 83.629036 -281.852972) (xy 83.593543 -281.887064) (xy 83.55304 -281.91502)
			(xy 83.508578 -281.936118) (xy 83.461307 -281.94981) (xy 83.412452 -281.955742) (xy 83.363277 -281.953761)
			(xy 83.315058 -281.943917) (xy 83.269042 -281.926465) (xy 83.226421 -281.901858) (xy 83.1883 -281.870733)
			(xy 83.155665 -281.833896) (xy 83.129362 -281.7923) (xy 83.110071 -281.747024) (xy 83.098294 -281.69924)
			(xy 83.094334 -281.650186) (xy 82.777071 -281.650186) (xy 82.776572 -281.67564) (xy 82.768529 -281.726422)
			(xy 82.752641 -281.775321) (xy 82.729298 -281.821133) (xy 82.699077 -281.862729) (xy 82.662721 -281.899085)
			(xy 82.621125 -281.929306) (xy 82.575313 -281.952649) (xy 82.526414 -281.968537) (xy 82.475632 -281.97658)
			(xy 82.424216 -281.97658) (xy 82.373434 -281.968537) (xy 82.324535 -281.952649) (xy 82.278723 -281.929306)
			(xy 82.237127 -281.899085) (xy 82.200771 -281.862729) (xy 82.17055 -281.821133) (xy 82.147207 -281.775321)
			(xy 82.131319 -281.726422) (xy 82.123276 -281.67564) (xy 81.826612 -281.67564) (xy 81.818569 -281.726422)
			(xy 81.802681 -281.775321) (xy 81.779338 -281.821133) (xy 81.749117 -281.862729) (xy 81.712761 -281.899085)
			(xy 81.671165 -281.929306) (xy 81.625353 -281.952649) (xy 81.576454 -281.968537) (xy 81.525672 -281.97658)
			(xy 81.474256 -281.97658) (xy 81.423474 -281.968537) (xy 81.374575 -281.952649) (xy 81.328763 -281.929306)
			(xy 81.287167 -281.899085) (xy 81.250811 -281.862729) (xy 81.22059 -281.821133) (xy 81.197247 -281.775321)
			(xy 81.181359 -281.726422) (xy 81.173316 -281.67564) (xy 80.854384 -281.67564) (xy 80.846668 -281.723116)
			(xy 80.831084 -281.769797) (xy 80.808213 -281.813374) (xy 80.778648 -281.852718) (xy 80.743155 -281.88681)
			(xy 80.702652 -281.914766) (xy 80.65819 -281.935864) (xy 80.610919 -281.949556) (xy 80.562064 -281.955488)
			(xy 80.512889 -281.953507) (xy 80.46467 -281.943663) (xy 80.418654 -281.926211) (xy 80.376033 -281.901604)
			(xy 80.337912 -281.870479) (xy 80.305277 -281.833642) (xy 80.278974 -281.792046) (xy 80.259683 -281.74677)
			(xy 80.247906 -281.698986) (xy 80.243946 -281.649932) (xy 79.905098 -281.649932) (xy 79.904603 -281.674539)
			(xy 79.896708 -281.723116) (xy 79.881124 -281.769797) (xy 79.858253 -281.813374) (xy 79.828688 -281.852718)
			(xy 79.793195 -281.88681) (xy 79.752692 -281.914766) (xy 79.70823 -281.935864) (xy 79.660959 -281.949556)
			(xy 79.612104 -281.955488) (xy 79.562929 -281.953507) (xy 79.51471 -281.943663) (xy 79.468694 -281.926211)
			(xy 79.426073 -281.901604) (xy 79.387952 -281.870479) (xy 79.355317 -281.833642) (xy 79.329014 -281.792046)
			(xy 79.309723 -281.74677) (xy 79.297946 -281.698986) (xy 79.293986 -281.649932) (xy 78.954884 -281.649932)
			(xy 78.954389 -281.674539) (xy 78.946494 -281.723116) (xy 78.93091 -281.769797) (xy 78.908039 -281.813374)
			(xy 78.878474 -281.852718) (xy 78.842981 -281.88681) (xy 78.802478 -281.914766) (xy 78.758016 -281.935864)
			(xy 78.710745 -281.949556) (xy 78.66189 -281.955488) (xy 78.612715 -281.953507) (xy 78.564496 -281.943663)
			(xy 78.51848 -281.926211) (xy 78.475859 -281.901604) (xy 78.437738 -281.870479) (xy 78.405103 -281.833642)
			(xy 78.3788 -281.792046) (xy 78.359509 -281.74677) (xy 78.347732 -281.698986) (xy 78.343772 -281.649932)
			(xy 78.004919 -281.649932) (xy 78.004429 -281.674285) (xy 77.996534 -281.722862) (xy 77.98095 -281.769543)
			(xy 77.958079 -281.81312) (xy 77.928514 -281.852464) (xy 77.893021 -281.886556) (xy 77.852518 -281.914512)
			(xy 77.808056 -281.93561) (xy 77.760785 -281.949302) (xy 77.71193 -281.955234) (xy 77.662755 -281.953253)
			(xy 77.614536 -281.943409) (xy 77.56852 -281.925957) (xy 77.525899 -281.90135) (xy 77.487778 -281.870225)
			(xy 77.455143 -281.833388) (xy 77.42884 -281.791792) (xy 77.409549 -281.746516) (xy 77.397772 -281.698732)
			(xy 77.393812 -281.649678) (xy 77.055213 -281.649678) (xy 77.055218 -281.649932) (xy 77.054723 -281.674539)
			(xy 77.046828 -281.723116) (xy 77.031244 -281.769797) (xy 77.008373 -281.813374) (xy 76.978808 -281.852718)
			(xy 76.943315 -281.88681) (xy 76.902812 -281.914766) (xy 76.85835 -281.935864) (xy 76.811079 -281.949556)
			(xy 76.762224 -281.955488) (xy 76.713049 -281.953507) (xy 76.66483 -281.943663) (xy 76.618814 -281.926211)
			(xy 76.576193 -281.901604) (xy 76.538072 -281.870479) (xy 76.505437 -281.833642) (xy 76.479134 -281.792046)
			(xy 76.459843 -281.74677) (xy 76.448066 -281.698986) (xy 76.444106 -281.649932) (xy 76.105258 -281.649932)
			(xy 76.104763 -281.674539) (xy 76.096868 -281.723116) (xy 76.081284 -281.769797) (xy 76.058413 -281.813374)
			(xy 76.028848 -281.852718) (xy 75.993355 -281.88681) (xy 75.952852 -281.914766) (xy 75.90839 -281.935864)
			(xy 75.861119 -281.949556) (xy 75.812264 -281.955488) (xy 75.763089 -281.953507) (xy 75.71487 -281.943663)
			(xy 75.668854 -281.926211) (xy 75.626233 -281.901604) (xy 75.588112 -281.870479) (xy 75.555477 -281.833642)
			(xy 75.529174 -281.792046) (xy 75.509883 -281.74677) (xy 75.498106 -281.698986) (xy 75.494146 -281.649932)
			(xy 75.155298 -281.649932) (xy 75.154803 -281.674539) (xy 75.146908 -281.723116) (xy 75.131324 -281.769797)
			(xy 75.108453 -281.813374) (xy 75.078888 -281.852718) (xy 75.043395 -281.88681) (xy 75.002892 -281.914766)
			(xy 74.95843 -281.935864) (xy 74.911159 -281.949556) (xy 74.862304 -281.955488) (xy 74.813129 -281.953507)
			(xy 74.76491 -281.943663) (xy 74.718894 -281.926211) (xy 74.676273 -281.901604) (xy 74.638152 -281.870479)
			(xy 74.605517 -281.833642) (xy 74.579214 -281.792046) (xy 74.559923 -281.74677) (xy 74.548146 -281.698986)
			(xy 74.544186 -281.649932) (xy 74.205084 -281.649932) (xy 74.204589 -281.674539) (xy 74.196694 -281.723116)
			(xy 74.18111 -281.769797) (xy 74.158239 -281.813374) (xy 74.128674 -281.852718) (xy 74.093181 -281.88681)
			(xy 74.052678 -281.914766) (xy 74.008216 -281.935864) (xy 73.960945 -281.949556) (xy 73.91209 -281.955488)
			(xy 73.862915 -281.953507) (xy 73.814696 -281.943663) (xy 73.76868 -281.926211) (xy 73.726059 -281.901604)
			(xy 73.687938 -281.870479) (xy 73.655303 -281.833642) (xy 73.629 -281.792046) (xy 73.609709 -281.74677)
			(xy 73.597932 -281.698986) (xy 73.593972 -281.649932) (xy 73.255124 -281.649932) (xy 73.254629 -281.674539)
			(xy 73.246734 -281.723116) (xy 73.23115 -281.769797) (xy 73.208279 -281.813374) (xy 73.178714 -281.852718)
			(xy 73.143221 -281.88681) (xy 73.102718 -281.914766) (xy 73.058256 -281.935864) (xy 73.010985 -281.949556)
			(xy 72.96213 -281.955488) (xy 72.912955 -281.953507) (xy 72.864736 -281.943663) (xy 72.81872 -281.926211)
			(xy 72.776099 -281.901604) (xy 72.737978 -281.870479) (xy 72.705343 -281.833642) (xy 72.67904 -281.792046)
			(xy 72.659749 -281.74677) (xy 72.647972 -281.698986) (xy 72.644012 -281.649932) (xy 72.305164 -281.649932)
			(xy 72.304669 -281.674539) (xy 72.296774 -281.723116) (xy 72.28119 -281.769797) (xy 72.258319 -281.813374)
			(xy 72.228754 -281.852718) (xy 72.193261 -281.88681) (xy 72.152758 -281.914766) (xy 72.108296 -281.935864)
			(xy 72.061025 -281.949556) (xy 72.01217 -281.955488) (xy 71.962995 -281.953507) (xy 71.914776 -281.943663)
			(xy 71.86876 -281.926211) (xy 71.826139 -281.901604) (xy 71.788018 -281.870479) (xy 71.755383 -281.833642)
			(xy 71.72908 -281.792046) (xy 71.709789 -281.74677) (xy 71.698012 -281.698986) (xy 71.694052 -281.649932)
			(xy 71.355204 -281.649932) (xy 71.354709 -281.674539) (xy 71.346814 -281.723116) (xy 71.33123 -281.769797)
			(xy 71.308359 -281.813374) (xy 71.278794 -281.852718) (xy 71.243301 -281.88681) (xy 71.202798 -281.914766)
			(xy 71.158336 -281.935864) (xy 71.111065 -281.949556) (xy 71.06221 -281.955488) (xy 71.013035 -281.953507)
			(xy 70.964816 -281.943663) (xy 70.9188 -281.926211) (xy 70.876179 -281.901604) (xy 70.838058 -281.870479)
			(xy 70.805423 -281.833642) (xy 70.77912 -281.792046) (xy 70.759829 -281.74677) (xy 70.748052 -281.698986)
			(xy 70.744092 -281.649932) (xy 70.405244 -281.649932) (xy 70.404749 -281.674539) (xy 70.396854 -281.723116)
			(xy 70.38127 -281.769797) (xy 70.358399 -281.813374) (xy 70.328834 -281.852718) (xy 70.293341 -281.88681)
			(xy 70.252838 -281.914766) (xy 70.208376 -281.935864) (xy 70.161105 -281.949556) (xy 70.11225 -281.955488)
			(xy 70.063075 -281.953507) (xy 70.014856 -281.943663) (xy 69.96884 -281.926211) (xy 69.926219 -281.901604)
			(xy 69.888098 -281.870479) (xy 69.855463 -281.833642) (xy 69.82916 -281.792046) (xy 69.809869 -281.74677)
			(xy 69.798092 -281.698986) (xy 69.794132 -281.649932) (xy 69.455284 -281.649932) (xy 69.454789 -281.674539)
			(xy 69.446894 -281.723116) (xy 69.43131 -281.769797) (xy 69.408439 -281.813374) (xy 69.378874 -281.852718)
			(xy 69.343381 -281.88681) (xy 69.302878 -281.914766) (xy 69.258416 -281.935864) (xy 69.211145 -281.949556)
			(xy 69.16229 -281.955488) (xy 69.113115 -281.953507) (xy 69.064896 -281.943663) (xy 69.01888 -281.926211)
			(xy 68.976259 -281.901604) (xy 68.938138 -281.870479) (xy 68.905503 -281.833642) (xy 68.8792 -281.792046)
			(xy 68.859909 -281.74677) (xy 68.848132 -281.698986) (xy 68.844172 -281.649932) (xy 68.50507 -281.649932)
			(xy 68.504575 -281.674539) (xy 68.49668 -281.723116) (xy 68.481096 -281.769797) (xy 68.458225 -281.813374)
			(xy 68.42866 -281.852718) (xy 68.393167 -281.88681) (xy 68.352664 -281.914766) (xy 68.308202 -281.935864)
			(xy 68.260931 -281.949556) (xy 68.212076 -281.955488) (xy 68.162901 -281.953507) (xy 68.114682 -281.943663)
			(xy 68.068666 -281.926211) (xy 68.026045 -281.901604) (xy 67.987924 -281.870479) (xy 67.955289 -281.833642)
			(xy 67.928986 -281.792046) (xy 67.909695 -281.74677) (xy 67.897918 -281.698986) (xy 67.893958 -281.649932)
			(xy 67.55511 -281.649932) (xy 67.554615 -281.674539) (xy 67.54672 -281.723116) (xy 67.531136 -281.769797)
			(xy 67.508265 -281.813374) (xy 67.4787 -281.852718) (xy 67.443207 -281.88681) (xy 67.402704 -281.914766)
			(xy 67.358242 -281.935864) (xy 67.310971 -281.949556) (xy 67.262116 -281.955488) (xy 67.212941 -281.953507)
			(xy 67.164722 -281.943663) (xy 67.118706 -281.926211) (xy 67.076085 -281.901604) (xy 67.037964 -281.870479)
			(xy 67.005329 -281.833642) (xy 66.979026 -281.792046) (xy 66.959735 -281.74677) (xy 66.947958 -281.698986)
			(xy 66.943998 -281.649932) (xy 66.60515 -281.649932) (xy 66.604655 -281.674539) (xy 66.59676 -281.723116)
			(xy 66.581176 -281.769797) (xy 66.558305 -281.813374) (xy 66.52874 -281.852718) (xy 66.493247 -281.88681)
			(xy 66.452744 -281.914766) (xy 66.408282 -281.935864) (xy 66.361011 -281.949556) (xy 66.312156 -281.955488)
			(xy 66.262981 -281.953507) (xy 66.214762 -281.943663) (xy 66.168746 -281.926211) (xy 66.126125 -281.901604)
			(xy 66.088004 -281.870479) (xy 66.055369 -281.833642) (xy 66.029066 -281.792046) (xy 66.009775 -281.74677)
			(xy 65.997998 -281.698986) (xy 65.994038 -281.649932) (xy 65.65519 -281.649932) (xy 65.654695 -281.674539)
			(xy 65.6468 -281.723116) (xy 65.631216 -281.769797) (xy 65.608345 -281.813374) (xy 65.57878 -281.852718)
			(xy 65.543287 -281.88681) (xy 65.502784 -281.914766) (xy 65.458322 -281.935864) (xy 65.411051 -281.949556)
			(xy 65.362196 -281.955488) (xy 65.313021 -281.953507) (xy 65.264802 -281.943663) (xy 65.218786 -281.926211)
			(xy 65.176165 -281.901604) (xy 65.138044 -281.870479) (xy 65.105409 -281.833642) (xy 65.079106 -281.792046)
			(xy 65.059815 -281.74677) (xy 65.048038 -281.698986) (xy 65.044078 -281.649932) (xy 64.70523 -281.649932)
			(xy 64.704735 -281.674539) (xy 64.69684 -281.723116) (xy 64.681256 -281.769797) (xy 64.658385 -281.813374)
			(xy 64.62882 -281.852718) (xy 64.593327 -281.88681) (xy 64.552824 -281.914766) (xy 64.508362 -281.935864)
			(xy 64.461091 -281.949556) (xy 64.412236 -281.955488) (xy 64.363061 -281.953507) (xy 64.314842 -281.943663)
			(xy 64.268826 -281.926211) (xy 64.226205 -281.901604) (xy 64.188084 -281.870479) (xy 64.155449 -281.833642)
			(xy 64.129146 -281.792046) (xy 64.109855 -281.74677) (xy 64.098078 -281.698986) (xy 64.094118 -281.649932)
			(xy 63.75527 -281.649932) (xy 63.754775 -281.674539) (xy 63.74688 -281.723116) (xy 63.731296 -281.769797)
			(xy 63.708425 -281.813374) (xy 63.67886 -281.852718) (xy 63.643367 -281.88681) (xy 63.602864 -281.914766)
			(xy 63.558402 -281.935864) (xy 63.511131 -281.949556) (xy 63.462276 -281.955488) (xy 63.413101 -281.953507)
			(xy 63.364882 -281.943663) (xy 63.318866 -281.926211) (xy 63.276245 -281.901604) (xy 63.238124 -281.870479)
			(xy 63.205489 -281.833642) (xy 63.179186 -281.792046) (xy 63.159895 -281.74677) (xy 63.148118 -281.698986)
			(xy 63.144158 -281.649932) (xy 62.805056 -281.649932) (xy 62.804561 -281.674539) (xy 62.796666 -281.723116)
			(xy 62.781082 -281.769797) (xy 62.758211 -281.813374) (xy 62.728646 -281.852718) (xy 62.693153 -281.88681)
			(xy 62.65265 -281.914766) (xy 62.608188 -281.935864) (xy 62.560917 -281.949556) (xy 62.512062 -281.955488)
			(xy 62.462887 -281.953507) (xy 62.414668 -281.943663) (xy 62.368652 -281.926211) (xy 62.326031 -281.901604)
			(xy 62.28791 -281.870479) (xy 62.255275 -281.833642) (xy 62.228972 -281.792046) (xy 62.209681 -281.74677)
			(xy 62.197904 -281.698986) (xy 62.193944 -281.649932) (xy 61.855096 -281.649932) (xy 61.854601 -281.674539)
			(xy 61.846706 -281.723116) (xy 61.831122 -281.769797) (xy 61.808251 -281.813374) (xy 61.778686 -281.852718)
			(xy 61.743193 -281.88681) (xy 61.70269 -281.914766) (xy 61.658228 -281.935864) (xy 61.610957 -281.949556)
			(xy 61.562102 -281.955488) (xy 61.512927 -281.953507) (xy 61.464708 -281.943663) (xy 61.418692 -281.926211)
			(xy 61.376071 -281.901604) (xy 61.33795 -281.870479) (xy 61.305315 -281.833642) (xy 61.279012 -281.792046)
			(xy 61.259721 -281.74677) (xy 61.247944 -281.698986) (xy 61.243984 -281.649932) (xy 60.905136 -281.649932)
			(xy 60.904641 -281.674539) (xy 60.896746 -281.723116) (xy 60.881162 -281.769797) (xy 60.858291 -281.813374)
			(xy 60.828726 -281.852718) (xy 60.793233 -281.88681) (xy 60.75273 -281.914766) (xy 60.708268 -281.935864)
			(xy 60.660997 -281.949556) (xy 60.612142 -281.955488) (xy 60.562967 -281.953507) (xy 60.514748 -281.943663)
			(xy 60.468732 -281.926211) (xy 60.426111 -281.901604) (xy 60.38799 -281.870479) (xy 60.355355 -281.833642)
			(xy 60.329052 -281.792046) (xy 60.309761 -281.74677) (xy 60.297984 -281.698986) (xy 60.294024 -281.649932)
			(xy 59.955176 -281.649932) (xy 59.954681 -281.674539) (xy 59.946786 -281.723116) (xy 59.931202 -281.769797)
			(xy 59.908331 -281.813374) (xy 59.878766 -281.852718) (xy 59.843273 -281.88681) (xy 59.80277 -281.914766)
			(xy 59.758308 -281.935864) (xy 59.711037 -281.949556) (xy 59.662182 -281.955488) (xy 59.613007 -281.953507)
			(xy 59.564788 -281.943663) (xy 59.518772 -281.926211) (xy 59.476151 -281.901604) (xy 59.43803 -281.870479)
			(xy 59.405395 -281.833642) (xy 59.379092 -281.792046) (xy 59.359801 -281.74677) (xy 59.348024 -281.698986)
			(xy 59.344064 -281.649932) (xy 59.005216 -281.649932) (xy 59.004721 -281.674539) (xy 58.996826 -281.723116)
			(xy 58.981242 -281.769797) (xy 58.958371 -281.813374) (xy 58.928806 -281.852718) (xy 58.893313 -281.88681)
			(xy 58.85281 -281.914766) (xy 58.808348 -281.935864) (xy 58.761077 -281.949556) (xy 58.712222 -281.955488)
			(xy 58.663047 -281.953507) (xy 58.614828 -281.943663) (xy 58.568812 -281.926211) (xy 58.526191 -281.901604)
			(xy 58.48807 -281.870479) (xy 58.455435 -281.833642) (xy 58.429132 -281.792046) (xy 58.409841 -281.74677)
			(xy 58.398064 -281.698986) (xy 58.394104 -281.649932) (xy 58.055256 -281.649932) (xy 58.054761 -281.674539)
			(xy 58.046866 -281.723116) (xy 58.031282 -281.769797) (xy 58.008411 -281.813374) (xy 57.978846 -281.852718)
			(xy 57.943353 -281.88681) (xy 57.90285 -281.914766) (xy 57.858388 -281.935864) (xy 57.811117 -281.949556)
			(xy 57.762262 -281.955488) (xy 57.713087 -281.953507) (xy 57.664868 -281.943663) (xy 57.618852 -281.926211)
			(xy 57.576231 -281.901604) (xy 57.53811 -281.870479) (xy 57.505475 -281.833642) (xy 57.479172 -281.792046)
			(xy 57.459881 -281.74677) (xy 57.448104 -281.698986) (xy 57.444144 -281.649932) (xy 57.105296 -281.649932)
			(xy 57.104801 -281.674539) (xy 57.096906 -281.723116) (xy 57.081322 -281.769797) (xy 57.058451 -281.813374)
			(xy 57.028886 -281.852718) (xy 56.993393 -281.88681) (xy 56.95289 -281.914766) (xy 56.908428 -281.935864)
			(xy 56.861157 -281.949556) (xy 56.812302 -281.955488) (xy 56.763127 -281.953507) (xy 56.714908 -281.943663)
			(xy 56.668892 -281.926211) (xy 56.626271 -281.901604) (xy 56.58815 -281.870479) (xy 56.555515 -281.833642)
			(xy 56.529212 -281.792046) (xy 56.509921 -281.74677) (xy 56.498144 -281.698986) (xy 56.494184 -281.649932)
			(xy 56.155082 -281.649932) (xy 56.154587 -281.674539) (xy 56.146692 -281.723116) (xy 56.131108 -281.769797)
			(xy 56.108237 -281.813374) (xy 56.078672 -281.852718) (xy 56.043179 -281.88681) (xy 56.002676 -281.914766)
			(xy 55.958214 -281.935864) (xy 55.910943 -281.949556) (xy 55.862088 -281.955488) (xy 55.812913 -281.953507)
			(xy 55.764694 -281.943663) (xy 55.718678 -281.926211) (xy 55.676057 -281.901604) (xy 55.637936 -281.870479)
			(xy 55.605301 -281.833642) (xy 55.578998 -281.792046) (xy 55.559707 -281.74677) (xy 55.54793 -281.698986)
			(xy 55.54397 -281.649932) (xy 55.205104 -281.649932) (xy 55.205551 -281.658163) (xy 55.200187 -281.707519)
			(xy 55.186908 -281.755358) (xy 55.166064 -281.800418) (xy 55.138205 -281.841513) (xy 55.104064 -281.877558)
			(xy 55.064542 -281.907606) (xy 55.020679 -281.930864) (xy 54.973631 -281.946718) (xy 54.924638 -281.954753)
			(xy 54.899814 -281.95524) (xy 54.885631 -281.955061) (xy 54.857391 -281.95239) (xy 54.843426 -281.949906)
			(xy 54.83098 -281.94762) (xy 54.807358 -281.954986) (xy 54.729888 -282.032456) (xy 54.722522 -282.056078)
			(xy 54.724808 -282.068524) (xy 54.727284 -282.08249) (xy 54.729956 -282.110729) (xy 54.730142 -282.124912)
			(xy 54.72962 -282.150167) (xy 54.721307 -282.199989) (xy 54.704906 -282.247763) (xy 54.680865 -282.292186)
			(xy 54.649841 -282.332046) (xy 54.612679 -282.366256) (xy 54.570393 -282.393882) (xy 54.524137 -282.414172)
			(xy 54.475172 -282.426572) (xy 54.424834 -282.430743) (xy 54.374496 -282.426572) (xy 54.325531 -282.414172)
			(xy 54.279275 -282.393882) (xy 54.236989 -282.366256) (xy 54.199827 -282.332046) (xy 54.168803 -282.292186)
			(xy 54.144762 -282.247763) (xy 54.128361 -282.199989) (xy 54.120048 -282.150167) (xy 54.119526 -282.124912)
			(xy 54.119704 -282.110729) (xy 54.122375 -282.082489) (xy 54.12486 -282.068524) (xy 54.127146 -282.056078)
			(xy 54.11978 -282.032456) (xy 54.04231 -281.954986) (xy 54.018688 -281.94762) (xy 54.006242 -281.949906)
			(xy 53.992277 -281.952387) (xy 53.964037 -281.955056) (xy 53.949854 -281.95524) (xy 53.925037 -281.954673)
			(xy 53.876058 -281.946635) (xy 53.829025 -281.93078) (xy 53.785177 -281.907525) (xy 53.745668 -281.877482)
			(xy 53.71154 -281.841444) (xy 53.683692 -281.800358) (xy 53.662857 -281.755309) (xy 53.649586 -281.707483)
			(xy 53.644226 -281.658139) (xy 53.305037 -281.658139) (xy 53.304707 -281.674539) (xy 53.296812 -281.723116)
			(xy 53.281228 -281.769797) (xy 53.258357 -281.813374) (xy 53.228792 -281.852718) (xy 53.193299 -281.88681)
			(xy 53.152796 -281.914766) (xy 53.108334 -281.935864) (xy 53.061063 -281.949556) (xy 53.012208 -281.955488)
			(xy 52.963033 -281.953507) (xy 52.914814 -281.943663) (xy 52.868798 -281.926211) (xy 52.826177 -281.901604)
			(xy 52.788056 -281.870479) (xy 52.755421 -281.833642) (xy 52.729118 -281.792046) (xy 52.709827 -281.74677)
			(xy 52.69805 -281.698986) (xy 52.69409 -281.649932) (xy 52.355242 -281.649932) (xy 52.354747 -281.674539)
			(xy 52.346852 -281.723116) (xy 52.331268 -281.769797) (xy 52.308397 -281.813374) (xy 52.278832 -281.852718)
			(xy 52.243339 -281.88681) (xy 52.202836 -281.914766) (xy 52.158374 -281.935864) (xy 52.111103 -281.949556)
			(xy 52.062248 -281.955488) (xy 52.013073 -281.953507) (xy 51.964854 -281.943663) (xy 51.918838 -281.926211)
			(xy 51.876217 -281.901604) (xy 51.838096 -281.870479) (xy 51.805461 -281.833642) (xy 51.779158 -281.792046)
			(xy 51.759867 -281.74677) (xy 51.74809 -281.698986) (xy 51.74413 -281.649932) (xy 51.405282 -281.649932)
			(xy 51.404787 -281.674539) (xy 51.396892 -281.723116) (xy 51.381308 -281.769797) (xy 51.358437 -281.813374)
			(xy 51.328872 -281.852718) (xy 51.293379 -281.88681) (xy 51.252876 -281.914766) (xy 51.208414 -281.935864)
			(xy 51.161143 -281.949556) (xy 51.112288 -281.955488) (xy 51.063113 -281.953507) (xy 51.014894 -281.943663)
			(xy 50.968878 -281.926211) (xy 50.926257 -281.901604) (xy 50.888136 -281.870479) (xy 50.855501 -281.833642)
			(xy 50.829198 -281.792046) (xy 50.809907 -281.74677) (xy 50.79813 -281.698986) (xy 50.79417 -281.649932)
			(xy 50.455068 -281.649932) (xy 50.454573 -281.674539) (xy 50.446678 -281.723116) (xy 50.431094 -281.769797)
			(xy 50.408223 -281.813374) (xy 50.378658 -281.852718) (xy 50.343165 -281.88681) (xy 50.302662 -281.914766)
			(xy 50.2582 -281.935864) (xy 50.210929 -281.949556) (xy 50.162074 -281.955488) (xy 50.112899 -281.953507)
			(xy 50.06468 -281.943663) (xy 50.018664 -281.926211) (xy 49.976043 -281.901604) (xy 49.937922 -281.870479)
			(xy 49.905287 -281.833642) (xy 49.878984 -281.792046) (xy 49.859693 -281.74677) (xy 49.847916 -281.698986)
			(xy 49.843956 -281.649932) (xy 49.505108 -281.649932) (xy 49.504646 -281.674095) (xy 49.497028 -281.721817)
			(xy 49.481987 -281.767743) (xy 49.459899 -281.810726) (xy 49.431315 -281.849692) (xy 49.39695 -281.88367)
			(xy 49.357661 -281.911809) (xy 49.31443 -281.933407) (xy 49.268336 -281.947925) (xy 49.244504 -281.951938)
			(xy 49.235972 -281.953588) (xy 49.220653 -281.961771) (xy 49.214532 -281.96794) (xy 49.194212 -281.990038)
			(xy 49.188126 -281.997265) (xy 49.181344 -282.014885) (xy 49.181004 -282.024328) (xy 49.181004 -282.599892)
			(xy 73.593972 -282.599892) (xy 73.597932 -282.550838) (xy 73.609709 -282.503054) (xy 73.629 -282.457778)
			(xy 73.655303 -282.416182) (xy 73.687938 -282.379345) (xy 73.726059 -282.34822) (xy 73.76868 -282.323613)
			(xy 73.814696 -282.306161) (xy 73.862915 -282.296317) (xy 73.91209 -282.294336) (xy 73.960945 -282.300268)
			(xy 74.008216 -282.31396) (xy 74.052678 -282.335058) (xy 74.093181 -282.363014) (xy 74.128674 -282.397106)
			(xy 74.158239 -282.43645) (xy 74.18111 -282.480027) (xy 74.196694 -282.526708) (xy 74.204589 -282.575285)
			(xy 74.205084 -282.599892) (xy 74.543932 -282.599892) (xy 74.547892 -282.550838) (xy 74.559669 -282.503054)
			(xy 74.57896 -282.457778) (xy 74.605263 -282.416182) (xy 74.637898 -282.379345) (xy 74.676019 -282.34822)
			(xy 74.71864 -282.323613) (xy 74.764656 -282.306161) (xy 74.812875 -282.296317) (xy 74.86205 -282.294336)
			(xy 74.910905 -282.300268) (xy 74.958176 -282.31396) (xy 75.002638 -282.335058) (xy 75.043141 -282.363014)
			(xy 75.078634 -282.397106) (xy 75.108199 -282.43645) (xy 75.13107 -282.480027) (xy 75.146654 -282.526708)
			(xy 75.154549 -282.575285) (xy 75.155044 -282.599892) (xy 75.494146 -282.599892) (xy 75.498106 -282.550838)
			(xy 75.509883 -282.503054) (xy 75.529174 -282.457778) (xy 75.555477 -282.416182) (xy 75.588112 -282.379345)
			(xy 75.626233 -282.34822) (xy 75.668854 -282.323613) (xy 75.71487 -282.306161) (xy 75.763089 -282.296317)
			(xy 75.812264 -282.294336) (xy 75.861119 -282.300268) (xy 75.90839 -282.31396) (xy 75.952852 -282.335058)
			(xy 75.993355 -282.363014) (xy 76.028848 -282.397106) (xy 76.058413 -282.43645) (xy 76.081284 -282.480027)
			(xy 76.096868 -282.526708) (xy 76.104763 -282.575285) (xy 76.105258 -282.599892) (xy 76.104763 -282.624499)
			(xy 76.104584 -282.6256) (xy 76.423262 -282.6256) (xy 76.423262 -282.574184) (xy 76.431305 -282.523402)
			(xy 76.447193 -282.474503) (xy 76.470536 -282.428691) (xy 76.500757 -282.387095) (xy 76.537113 -282.350739)
			(xy 76.578709 -282.320518) (xy 76.624521 -282.297175) (xy 76.67342 -282.281287) (xy 76.724202 -282.273244)
			(xy 76.775618 -282.273244) (xy 76.8264 -282.281287) (xy 76.875299 -282.297175) (xy 76.921111 -282.320518)
			(xy 76.962707 -282.350739) (xy 76.999063 -282.387095) (xy 77.029284 -282.428691) (xy 77.052627 -282.474503)
			(xy 77.068515 -282.523402) (xy 77.076558 -282.574184) (xy 77.077062 -282.599892) (xy 77.076558 -282.6256)
			(xy 77.373222 -282.6256) (xy 77.373222 -282.574184) (xy 77.381265 -282.523402) (xy 77.397153 -282.474503)
			(xy 77.420496 -282.428691) (xy 77.450717 -282.387095) (xy 77.487073 -282.350739) (xy 77.528669 -282.320518)
			(xy 77.574481 -282.297175) (xy 77.62338 -282.281287) (xy 77.674162 -282.273244) (xy 77.725578 -282.273244)
			(xy 77.77636 -282.281287) (xy 77.825259 -282.297175) (xy 77.871071 -282.320518) (xy 77.912667 -282.350739)
			(xy 77.949023 -282.387095) (xy 77.979244 -282.428691) (xy 78.002587 -282.474503) (xy 78.018475 -282.523402)
			(xy 78.026518 -282.574184) (xy 78.027022 -282.599892) (xy 78.344026 -282.599892) (xy 78.347986 -282.550838)
			(xy 78.359763 -282.503054) (xy 78.379054 -282.457778) (xy 78.405357 -282.416182) (xy 78.437992 -282.379345)
			(xy 78.476113 -282.34822) (xy 78.518734 -282.323613) (xy 78.56475 -282.306161) (xy 78.612969 -282.296317)
			(xy 78.662144 -282.294336) (xy 78.710999 -282.300268) (xy 78.75827 -282.31396) (xy 78.802732 -282.335058)
			(xy 78.843235 -282.363014) (xy 78.878728 -282.397106) (xy 78.908293 -282.43645) (xy 78.931164 -282.480027)
			(xy 78.946748 -282.526708) (xy 78.954643 -282.575285) (xy 78.955138 -282.599892) (xy 78.954643 -282.624499)
			(xy 78.954464 -282.6256) (xy 79.273142 -282.6256) (xy 79.273142 -282.574184) (xy 79.281185 -282.523402)
			(xy 79.297073 -282.474503) (xy 79.320416 -282.428691) (xy 79.350637 -282.387095) (xy 79.386993 -282.350739)
			(xy 79.428589 -282.320518) (xy 79.474401 -282.297175) (xy 79.5233 -282.281287) (xy 79.574082 -282.273244)
			(xy 79.625498 -282.273244) (xy 79.67628 -282.281287) (xy 79.725179 -282.297175) (xy 79.770991 -282.320518)
			(xy 79.812587 -282.350739) (xy 79.848943 -282.387095) (xy 79.879164 -282.428691) (xy 79.902507 -282.474503)
			(xy 79.918395 -282.523402) (xy 79.926438 -282.574184) (xy 79.926942 -282.599892) (xy 79.926438 -282.6256)
			(xy 80.223102 -282.6256) (xy 80.223102 -282.574184) (xy 80.231145 -282.523402) (xy 80.247033 -282.474503)
			(xy 80.270376 -282.428691) (xy 80.300597 -282.387095) (xy 80.336953 -282.350739) (xy 80.378549 -282.320518)
			(xy 80.424361 -282.297175) (xy 80.47326 -282.281287) (xy 80.524042 -282.273244) (xy 80.575458 -282.273244)
			(xy 80.62624 -282.281287) (xy 80.675139 -282.297175) (xy 80.720951 -282.320518) (xy 80.762547 -282.350739)
			(xy 80.798903 -282.387095) (xy 80.829124 -282.428691) (xy 80.852467 -282.474503) (xy 80.868355 -282.523402)
			(xy 80.876398 -282.574184) (xy 80.876902 -282.599892) (xy 81.19416 -282.599892) (xy 81.19812 -282.550838)
			(xy 81.209897 -282.503054) (xy 81.229188 -282.457778) (xy 81.255491 -282.416182) (xy 81.288126 -282.379345)
			(xy 81.326247 -282.34822) (xy 81.368868 -282.323613) (xy 81.414884 -282.306161) (xy 81.463103 -282.296317)
			(xy 81.512278 -282.294336) (xy 81.561133 -282.300268) (xy 81.608404 -282.31396) (xy 81.652866 -282.335058)
			(xy 81.693369 -282.363014) (xy 81.728862 -282.397106) (xy 81.758427 -282.43645) (xy 81.781298 -282.480027)
			(xy 81.796882 -282.526708) (xy 81.804777 -282.575285) (xy 81.805272 -282.599892) (xy 82.14412 -282.599892)
			(xy 82.14808 -282.550838) (xy 82.159857 -282.503054) (xy 82.179148 -282.457778) (xy 82.205451 -282.416182)
			(xy 82.238086 -282.379345) (xy 82.276207 -282.34822) (xy 82.318828 -282.323613) (xy 82.364844 -282.306161)
			(xy 82.413063 -282.296317) (xy 82.462238 -282.294336) (xy 82.511093 -282.300268) (xy 82.558364 -282.31396)
			(xy 82.602826 -282.335058) (xy 82.643329 -282.363014) (xy 82.678822 -282.397106) (xy 82.708387 -282.43645)
			(xy 82.731258 -282.480027) (xy 82.746842 -282.526708) (xy 82.754737 -282.575285) (xy 82.755232 -282.599892)
			(xy 82.754737 -282.624499) (xy 82.746842 -282.673076) (xy 82.731258 -282.719757) (xy 82.708387 -282.763334)
			(xy 82.678822 -282.802678) (xy 82.643329 -282.83677) (xy 82.602826 -282.864726) (xy 82.558364 -282.885824)
			(xy 82.511093 -282.899516) (xy 82.462238 -282.905448) (xy 82.413063 -282.903467) (xy 82.364844 -282.893623)
			(xy 82.318828 -282.876171) (xy 82.276207 -282.851564) (xy 82.238086 -282.820439) (xy 82.205451 -282.783602)
			(xy 82.179148 -282.742006) (xy 82.159857 -282.69673) (xy 82.14808 -282.648946) (xy 82.14412 -282.599892)
			(xy 81.805272 -282.599892) (xy 81.804777 -282.624499) (xy 81.796882 -282.673076) (xy 81.781298 -282.719757)
			(xy 81.758427 -282.763334) (xy 81.728862 -282.802678) (xy 81.693369 -282.83677) (xy 81.652866 -282.864726)
			(xy 81.608404 -282.885824) (xy 81.561133 -282.899516) (xy 81.512278 -282.905448) (xy 81.463103 -282.903467)
			(xy 81.414884 -282.893623) (xy 81.368868 -282.876171) (xy 81.326247 -282.851564) (xy 81.288126 -282.820439)
			(xy 81.255491 -282.783602) (xy 81.229188 -282.742006) (xy 81.209897 -282.69673) (xy 81.19812 -282.648946)
			(xy 81.19416 -282.599892) (xy 80.876902 -282.599892) (xy 80.876398 -282.6256) (xy 80.868355 -282.676382)
			(xy 80.852467 -282.725281) (xy 80.829124 -282.771093) (xy 80.798903 -282.812689) (xy 80.762547 -282.849045)
			(xy 80.720951 -282.879266) (xy 80.675139 -282.902609) (xy 80.62624 -282.918497) (xy 80.575458 -282.92654)
			(xy 80.524042 -282.92654) (xy 80.47326 -282.918497) (xy 80.424361 -282.902609) (xy 80.378549 -282.879266)
			(xy 80.336953 -282.849045) (xy 80.300597 -282.812689) (xy 80.270376 -282.771093) (xy 80.247033 -282.725281)
			(xy 80.231145 -282.676382) (xy 80.223102 -282.6256) (xy 79.926438 -282.6256) (xy 79.918395 -282.676382)
			(xy 79.902507 -282.725281) (xy 79.879164 -282.771093) (xy 79.848943 -282.812689) (xy 79.812587 -282.849045)
			(xy 79.770991 -282.879266) (xy 79.725179 -282.902609) (xy 79.67628 -282.918497) (xy 79.625498 -282.92654)
			(xy 79.574082 -282.92654) (xy 79.5233 -282.918497) (xy 79.474401 -282.902609) (xy 79.428589 -282.879266)
			(xy 79.386993 -282.849045) (xy 79.350637 -282.812689) (xy 79.320416 -282.771093) (xy 79.297073 -282.725281)
			(xy 79.281185 -282.676382) (xy 79.273142 -282.6256) (xy 78.954464 -282.6256) (xy 78.946748 -282.673076)
			(xy 78.931164 -282.719757) (xy 78.908293 -282.763334) (xy 78.878728 -282.802678) (xy 78.843235 -282.83677)
			(xy 78.802732 -282.864726) (xy 78.75827 -282.885824) (xy 78.710999 -282.899516) (xy 78.662144 -282.905448)
			(xy 78.612969 -282.903467) (xy 78.56475 -282.893623) (xy 78.518734 -282.876171) (xy 78.476113 -282.851564)
			(xy 78.437992 -282.820439) (xy 78.405357 -282.783602) (xy 78.379054 -282.742006) (xy 78.359763 -282.69673)
			(xy 78.347986 -282.648946) (xy 78.344026 -282.599892) (xy 78.027022 -282.599892) (xy 78.026518 -282.6256)
			(xy 78.018475 -282.676382) (xy 78.002587 -282.725281) (xy 77.979244 -282.771093) (xy 77.949023 -282.812689)
			(xy 77.912667 -282.849045) (xy 77.871071 -282.879266) (xy 77.825259 -282.902609) (xy 77.77636 -282.918497)
			(xy 77.725578 -282.92654) (xy 77.674162 -282.92654) (xy 77.62338 -282.918497) (xy 77.574481 -282.902609)
			(xy 77.528669 -282.879266) (xy 77.487073 -282.849045) (xy 77.450717 -282.812689) (xy 77.420496 -282.771093)
			(xy 77.397153 -282.725281) (xy 77.381265 -282.676382) (xy 77.373222 -282.6256) (xy 77.076558 -282.6256)
			(xy 77.068515 -282.676382) (xy 77.052627 -282.725281) (xy 77.029284 -282.771093) (xy 76.999063 -282.812689)
			(xy 76.962707 -282.849045) (xy 76.921111 -282.879266) (xy 76.875299 -282.902609) (xy 76.8264 -282.918497)
			(xy 76.775618 -282.92654) (xy 76.724202 -282.92654) (xy 76.67342 -282.918497) (xy 76.624521 -282.902609)
			(xy 76.578709 -282.879266) (xy 76.537113 -282.849045) (xy 76.500757 -282.812689) (xy 76.470536 -282.771093)
			(xy 76.447193 -282.725281) (xy 76.431305 -282.676382) (xy 76.423262 -282.6256) (xy 76.104584 -282.6256)
			(xy 76.096868 -282.673076) (xy 76.081284 -282.719757) (xy 76.058413 -282.763334) (xy 76.028848 -282.802678)
			(xy 75.993355 -282.83677) (xy 75.952852 -282.864726) (xy 75.90839 -282.885824) (xy 75.861119 -282.899516)
			(xy 75.812264 -282.905448) (xy 75.763089 -282.903467) (xy 75.71487 -282.893623) (xy 75.668854 -282.876171)
			(xy 75.626233 -282.851564) (xy 75.588112 -282.820439) (xy 75.555477 -282.783602) (xy 75.529174 -282.742006)
			(xy 75.509883 -282.69673) (xy 75.498106 -282.648946) (xy 75.494146 -282.599892) (xy 75.155044 -282.599892)
			(xy 75.154549 -282.624499) (xy 75.146654 -282.673076) (xy 75.13107 -282.719757) (xy 75.108199 -282.763334)
			(xy 75.078634 -282.802678) (xy 75.043141 -282.83677) (xy 75.002638 -282.864726) (xy 74.958176 -282.885824)
			(xy 74.910905 -282.899516) (xy 74.86205 -282.905448) (xy 74.812875 -282.903467) (xy 74.764656 -282.893623)
			(xy 74.71864 -282.876171) (xy 74.676019 -282.851564) (xy 74.637898 -282.820439) (xy 74.605263 -282.783602)
			(xy 74.57896 -282.742006) (xy 74.559669 -282.69673) (xy 74.547892 -282.648946) (xy 74.543932 -282.599892)
			(xy 74.205084 -282.599892) (xy 74.204589 -282.624499) (xy 74.196694 -282.673076) (xy 74.18111 -282.719757)
			(xy 74.158239 -282.763334) (xy 74.128674 -282.802678) (xy 74.093181 -282.83677) (xy 74.052678 -282.864726)
			(xy 74.008216 -282.885824) (xy 73.960945 -282.899516) (xy 73.91209 -282.905448) (xy 73.862915 -282.903467)
			(xy 73.814696 -282.893623) (xy 73.76868 -282.876171) (xy 73.726059 -282.851564) (xy 73.687938 -282.820439)
			(xy 73.655303 -282.783602) (xy 73.629 -282.742006) (xy 73.609709 -282.69673) (xy 73.597932 -282.648946)
			(xy 73.593972 -282.599892) (xy 49.181004 -282.599892) (xy 49.181004 -283.074872) (xy 49.368976 -283.074872)
			(xy 49.372936 -283.025818) (xy 49.384713 -282.978034) (xy 49.404004 -282.932758) (xy 49.430307 -282.891162)
			(xy 49.462942 -282.854325) (xy 49.501063 -282.8232) (xy 49.543684 -282.798593) (xy 49.5897 -282.781141)
			(xy 49.637919 -282.771297) (xy 49.687094 -282.769316) (xy 49.735949 -282.775248) (xy 49.78322 -282.78894)
			(xy 49.827682 -282.810038) (xy 49.868185 -282.837994) (xy 49.903678 -282.872086) (xy 49.933243 -282.91143)
			(xy 49.956114 -282.955007) (xy 49.971698 -283.001688) (xy 49.979593 -283.050265) (xy 49.980088 -283.074872)
			(xy 50.31919 -283.074872) (xy 50.32315 -283.025818) (xy 50.334927 -282.978034) (xy 50.354218 -282.932758)
			(xy 50.380521 -282.891162) (xy 50.413156 -282.854325) (xy 50.451277 -282.8232) (xy 50.493898 -282.798593)
			(xy 50.539914 -282.781141) (xy 50.588133 -282.771297) (xy 50.637308 -282.769316) (xy 50.686163 -282.775248)
			(xy 50.733434 -282.78894) (xy 50.777896 -282.810038) (xy 50.818399 -282.837994) (xy 50.853892 -282.872086)
			(xy 50.883457 -282.91143) (xy 50.906328 -282.955007) (xy 50.921912 -283.001688) (xy 50.929807 -283.050265)
			(xy 50.930302 -283.074872) (xy 51.26915 -283.074872) (xy 51.27311 -283.025818) (xy 51.284887 -282.978034)
			(xy 51.304178 -282.932758) (xy 51.330481 -282.891162) (xy 51.363116 -282.854325) (xy 51.401237 -282.8232)
			(xy 51.443858 -282.798593) (xy 51.489874 -282.781141) (xy 51.538093 -282.771297) (xy 51.587268 -282.769316)
			(xy 51.636123 -282.775248) (xy 51.683394 -282.78894) (xy 51.727856 -282.810038) (xy 51.768359 -282.837994)
			(xy 51.803852 -282.872086) (xy 51.833417 -282.91143) (xy 51.856288 -282.955007) (xy 51.871872 -283.001688)
			(xy 51.879767 -283.050265) (xy 51.880262 -283.074872) (xy 52.21911 -283.074872) (xy 52.22307 -283.025818)
			(xy 52.234847 -282.978034) (xy 52.254138 -282.932758) (xy 52.280441 -282.891162) (xy 52.313076 -282.854325)
			(xy 52.351197 -282.8232) (xy 52.393818 -282.798593) (xy 52.439834 -282.781141) (xy 52.488053 -282.771297)
			(xy 52.537228 -282.769316) (xy 52.586083 -282.775248) (xy 52.633354 -282.78894) (xy 52.677816 -282.810038)
			(xy 52.718319 -282.837994) (xy 52.753812 -282.872086) (xy 52.783377 -282.91143) (xy 52.806248 -282.955007)
			(xy 52.821832 -283.001688) (xy 52.829727 -283.050265) (xy 52.830222 -283.074872) (xy 53.16907 -283.074872)
			(xy 53.17303 -283.025818) (xy 53.184807 -282.978034) (xy 53.204098 -282.932758) (xy 53.230401 -282.891162)
			(xy 53.263036 -282.854325) (xy 53.301157 -282.8232) (xy 53.343778 -282.798593) (xy 53.389794 -282.781141)
			(xy 53.438013 -282.771297) (xy 53.487188 -282.769316) (xy 53.536043 -282.775248) (xy 53.583314 -282.78894)
			(xy 53.627776 -282.810038) (xy 53.668279 -282.837994) (xy 53.703772 -282.872086) (xy 53.733337 -282.91143)
			(xy 53.756208 -282.955007) (xy 53.771792 -283.001688) (xy 53.779687 -283.050265) (xy 53.780182 -283.074872)
			(xy 54.11903 -283.074872) (xy 54.12299 -283.025818) (xy 54.134767 -282.978034) (xy 54.154058 -282.932758)
			(xy 54.180361 -282.891162) (xy 54.212996 -282.854325) (xy 54.251117 -282.8232) (xy 54.293738 -282.798593)
			(xy 54.339754 -282.781141) (xy 54.387973 -282.771297) (xy 54.437148 -282.769316) (xy 54.486003 -282.775248)
			(xy 54.533274 -282.78894) (xy 54.577736 -282.810038) (xy 54.618239 -282.837994) (xy 54.653732 -282.872086)
			(xy 54.683297 -282.91143) (xy 54.706168 -282.955007) (xy 54.721752 -283.001688) (xy 54.729647 -283.050265)
			(xy 54.730142 -283.074872) (xy 55.06899 -283.074872) (xy 55.07295 -283.025818) (xy 55.084727 -282.978034)
			(xy 55.104018 -282.932758) (xy 55.130321 -282.891162) (xy 55.162956 -282.854325) (xy 55.201077 -282.8232)
			(xy 55.243698 -282.798593) (xy 55.289714 -282.781141) (xy 55.337933 -282.771297) (xy 55.387108 -282.769316)
			(xy 55.435963 -282.775248) (xy 55.483234 -282.78894) (xy 55.527696 -282.810038) (xy 55.568199 -282.837994)
			(xy 55.603692 -282.872086) (xy 55.633257 -282.91143) (xy 55.656128 -282.955007) (xy 55.671712 -283.001688)
			(xy 55.679607 -283.050265) (xy 55.680102 -283.074872) (xy 56.019204 -283.074872) (xy 56.023164 -283.025818)
			(xy 56.034941 -282.978034) (xy 56.054232 -282.932758) (xy 56.080535 -282.891162) (xy 56.11317 -282.854325)
			(xy 56.151291 -282.8232) (xy 56.193912 -282.798593) (xy 56.239928 -282.781141) (xy 56.288147 -282.771297)
			(xy 56.337322 -282.769316) (xy 56.386177 -282.775248) (xy 56.433448 -282.78894) (xy 56.47791 -282.810038)
			(xy 56.518413 -282.837994) (xy 56.553906 -282.872086) (xy 56.583471 -282.91143) (xy 56.606342 -282.955007)
			(xy 56.621926 -283.001688) (xy 56.629821 -283.050265) (xy 56.630316 -283.074872) (xy 56.969164 -283.074872)
			(xy 56.973124 -283.025818) (xy 56.984901 -282.978034) (xy 57.004192 -282.932758) (xy 57.030495 -282.891162)
			(xy 57.06313 -282.854325) (xy 57.101251 -282.8232) (xy 57.143872 -282.798593) (xy 57.189888 -282.781141)
			(xy 57.238107 -282.771297) (xy 57.287282 -282.769316) (xy 57.336137 -282.775248) (xy 57.383408 -282.78894)
			(xy 57.42787 -282.810038) (xy 57.468373 -282.837994) (xy 57.503866 -282.872086) (xy 57.533431 -282.91143)
			(xy 57.556302 -282.955007) (xy 57.571886 -283.001688) (xy 57.579781 -283.050265) (xy 57.580276 -283.074872)
			(xy 57.919124 -283.074872) (xy 57.923084 -283.025818) (xy 57.934861 -282.978034) (xy 57.954152 -282.932758)
			(xy 57.980455 -282.891162) (xy 58.01309 -282.854325) (xy 58.051211 -282.8232) (xy 58.093832 -282.798593)
			(xy 58.139848 -282.781141) (xy 58.188067 -282.771297) (xy 58.237242 -282.769316) (xy 58.286097 -282.775248)
			(xy 58.333368 -282.78894) (xy 58.37783 -282.810038) (xy 58.418333 -282.837994) (xy 58.453826 -282.872086)
			(xy 58.483391 -282.91143) (xy 58.506262 -282.955007) (xy 58.521846 -283.001688) (xy 58.529741 -283.050265)
			(xy 58.530236 -283.074872) (xy 59.819044 -283.074872) (xy 59.823004 -283.025818) (xy 59.834781 -282.978034)
			(xy 59.854072 -282.932758) (xy 59.880375 -282.891162) (xy 59.91301 -282.854325) (xy 59.951131 -282.8232)
			(xy 59.993752 -282.798593) (xy 60.039768 -282.781141) (xy 60.087987 -282.771297) (xy 60.137162 -282.769316)
			(xy 60.186017 -282.775248) (xy 60.233288 -282.78894) (xy 60.27775 -282.810038) (xy 60.318253 -282.837994)
			(xy 60.353746 -282.872086) (xy 60.383311 -282.91143) (xy 60.406182 -282.955007) (xy 60.421766 -283.001688)
			(xy 60.429661 -283.050265) (xy 60.430156 -283.074872) (xy 60.769004 -283.074872) (xy 60.772964 -283.025818)
			(xy 60.784741 -282.978034) (xy 60.804032 -282.932758) (xy 60.830335 -282.891162) (xy 60.86297 -282.854325)
			(xy 60.901091 -282.8232) (xy 60.943712 -282.798593) (xy 60.989728 -282.781141) (xy 61.037947 -282.771297)
			(xy 61.087122 -282.769316) (xy 61.135977 -282.775248) (xy 61.183248 -282.78894) (xy 61.22771 -282.810038)
			(xy 61.268213 -282.837994) (xy 61.303706 -282.872086) (xy 61.333271 -282.91143) (xy 61.356142 -282.955007)
			(xy 61.371726 -283.001688) (xy 61.379621 -283.050265) (xy 61.380116 -283.074872) (xy 61.718964 -283.074872)
			(xy 61.722924 -283.025818) (xy 61.734701 -282.978034) (xy 61.753992 -282.932758) (xy 61.780295 -282.891162)
			(xy 61.81293 -282.854325) (xy 61.851051 -282.8232) (xy 61.893672 -282.798593) (xy 61.939688 -282.781141)
			(xy 61.987907 -282.771297) (xy 62.037082 -282.769316) (xy 62.085937 -282.775248) (xy 62.133208 -282.78894)
			(xy 62.17767 -282.810038) (xy 62.218173 -282.837994) (xy 62.253666 -282.872086) (xy 62.283231 -282.91143)
			(xy 62.306102 -282.955007) (xy 62.321686 -283.001688) (xy 62.329581 -283.050265) (xy 62.330076 -283.074872)
			(xy 62.669178 -283.074872) (xy 62.673138 -283.025818) (xy 62.684915 -282.978034) (xy 62.704206 -282.932758)
			(xy 62.730509 -282.891162) (xy 62.763144 -282.854325) (xy 62.801265 -282.8232) (xy 62.843886 -282.798593)
			(xy 62.889902 -282.781141) (xy 62.938121 -282.771297) (xy 62.987296 -282.769316) (xy 63.036151 -282.775248)
			(xy 63.083422 -282.78894) (xy 63.127884 -282.810038) (xy 63.168387 -282.837994) (xy 63.20388 -282.872086)
			(xy 63.233445 -282.91143) (xy 63.256316 -282.955007) (xy 63.2719 -283.001688) (xy 63.279795 -283.050265)
			(xy 63.28029 -283.074872) (xy 63.619138 -283.074872) (xy 63.623098 -283.025818) (xy 63.634875 -282.978034)
			(xy 63.654166 -282.932758) (xy 63.680469 -282.891162) (xy 63.713104 -282.854325) (xy 63.751225 -282.8232)
			(xy 63.793846 -282.798593) (xy 63.839862 -282.781141) (xy 63.888081 -282.771297) (xy 63.937256 -282.769316)
			(xy 63.986111 -282.775248) (xy 64.033382 -282.78894) (xy 64.077844 -282.810038) (xy 64.118347 -282.837994)
			(xy 64.15384 -282.872086) (xy 64.183405 -282.91143) (xy 64.206276 -282.955007) (xy 64.22186 -283.001688)
			(xy 64.229755 -283.050265) (xy 64.23025 -283.074872) (xy 64.569098 -283.074872) (xy 64.573058 -283.025818)
			(xy 64.584835 -282.978034) (xy 64.604126 -282.932758) (xy 64.630429 -282.891162) (xy 64.663064 -282.854325)
			(xy 64.701185 -282.8232) (xy 64.743806 -282.798593) (xy 64.789822 -282.781141) (xy 64.838041 -282.771297)
			(xy 64.887216 -282.769316) (xy 64.936071 -282.775248) (xy 64.983342 -282.78894) (xy 65.027804 -282.810038)
			(xy 65.068307 -282.837994) (xy 65.1038 -282.872086) (xy 65.133365 -282.91143) (xy 65.156236 -282.955007)
			(xy 65.17182 -283.001688) (xy 65.179715 -283.050265) (xy 65.18021 -283.074872) (xy 65.519058 -283.074872)
			(xy 65.523018 -283.025818) (xy 65.534795 -282.978034) (xy 65.554086 -282.932758) (xy 65.580389 -282.891162)
			(xy 65.613024 -282.854325) (xy 65.651145 -282.8232) (xy 65.693766 -282.798593) (xy 65.739782 -282.781141)
			(xy 65.788001 -282.771297) (xy 65.837176 -282.769316) (xy 65.886031 -282.775248) (xy 65.933302 -282.78894)
			(xy 65.977764 -282.810038) (xy 66.018267 -282.837994) (xy 66.05376 -282.872086) (xy 66.083325 -282.91143)
			(xy 66.106196 -282.955007) (xy 66.12178 -283.001688) (xy 66.129675 -283.050265) (xy 66.13017 -283.074872)
			(xy 66.469018 -283.074872) (xy 66.472978 -283.025818) (xy 66.484755 -282.978034) (xy 66.504046 -282.932758)
			(xy 66.530349 -282.891162) (xy 66.562984 -282.854325) (xy 66.601105 -282.8232) (xy 66.643726 -282.798593)
			(xy 66.689742 -282.781141) (xy 66.737961 -282.771297) (xy 66.787136 -282.769316) (xy 66.835991 -282.775248)
			(xy 66.883262 -282.78894) (xy 66.927724 -282.810038) (xy 66.968227 -282.837994) (xy 67.00372 -282.872086)
			(xy 67.033285 -282.91143) (xy 67.056156 -282.955007) (xy 67.07174 -283.001688) (xy 67.079635 -283.050265)
			(xy 67.08013 -283.074872) (xy 68.368938 -283.074872) (xy 68.372898 -283.025818) (xy 68.384675 -282.978034)
			(xy 68.403966 -282.932758) (xy 68.430269 -282.891162) (xy 68.462904 -282.854325) (xy 68.501025 -282.8232)
			(xy 68.543646 -282.798593) (xy 68.589662 -282.781141) (xy 68.637881 -282.771297) (xy 68.687056 -282.769316)
			(xy 68.735911 -282.775248) (xy 68.783182 -282.78894) (xy 68.827644 -282.810038) (xy 68.868147 -282.837994)
			(xy 68.90364 -282.872086) (xy 68.933205 -282.91143) (xy 68.956076 -282.955007) (xy 68.97166 -283.001688)
			(xy 68.979555 -283.050265) (xy 68.98005 -283.074872) (xy 69.319152 -283.074872) (xy 69.323112 -283.025818)
			(xy 69.334889 -282.978034) (xy 69.35418 -282.932758) (xy 69.380483 -282.891162) (xy 69.413118 -282.854325)
			(xy 69.451239 -282.8232) (xy 69.49386 -282.798593) (xy 69.539876 -282.781141) (xy 69.588095 -282.771297)
			(xy 69.63727 -282.769316) (xy 69.686125 -282.775248) (xy 69.733396 -282.78894) (xy 69.777858 -282.810038)
			(xy 69.818361 -282.837994) (xy 69.853854 -282.872086) (xy 69.883419 -282.91143) (xy 69.90629 -282.955007)
			(xy 69.921874 -283.001688) (xy 69.929769 -283.050265) (xy 69.930264 -283.074872) (xy 70.269112 -283.074872)
			(xy 70.273072 -283.025818) (xy 70.284849 -282.978034) (xy 70.30414 -282.932758) (xy 70.330443 -282.891162)
			(xy 70.363078 -282.854325) (xy 70.401199 -282.8232) (xy 70.44382 -282.798593) (xy 70.489836 -282.781141)
			(xy 70.538055 -282.771297) (xy 70.58723 -282.769316) (xy 70.636085 -282.775248) (xy 70.683356 -282.78894)
			(xy 70.727818 -282.810038) (xy 70.768321 -282.837994) (xy 70.803814 -282.872086) (xy 70.833379 -282.91143)
			(xy 70.85625 -282.955007) (xy 70.871834 -283.001688) (xy 70.879729 -283.050265) (xy 70.880224 -283.074872)
			(xy 71.219072 -283.074872) (xy 71.223032 -283.025818) (xy 71.234809 -282.978034) (xy 71.2541 -282.932758)
			(xy 71.280403 -282.891162) (xy 71.313038 -282.854325) (xy 71.351159 -282.8232) (xy 71.39378 -282.798593)
			(xy 71.439796 -282.781141) (xy 71.488015 -282.771297) (xy 71.53719 -282.769316) (xy 71.586045 -282.775248)
			(xy 71.633316 -282.78894) (xy 71.677778 -282.810038) (xy 71.718281 -282.837994) (xy 71.753774 -282.872086)
			(xy 71.783339 -282.91143) (xy 71.80621 -282.955007) (xy 71.821794 -283.001688) (xy 71.829689 -283.050265)
			(xy 71.830184 -283.074872) (xy 72.169032 -283.074872) (xy 72.172992 -283.025818) (xy 72.184769 -282.978034)
			(xy 72.20406 -282.932758) (xy 72.230363 -282.891162) (xy 72.262998 -282.854325) (xy 72.301119 -282.8232)
			(xy 72.34374 -282.798593) (xy 72.389756 -282.781141) (xy 72.437975 -282.771297) (xy 72.48715 -282.769316)
			(xy 72.536005 -282.775248) (xy 72.583276 -282.78894) (xy 72.627738 -282.810038) (xy 72.668241 -282.837994)
			(xy 72.703734 -282.872086) (xy 72.733299 -282.91143) (xy 72.75617 -282.955007) (xy 72.771754 -283.001688)
			(xy 72.779649 -283.050265) (xy 72.780144 -283.074872) (xy 72.779649 -283.099479) (xy 72.771754 -283.148056)
			(xy 72.75617 -283.194737) (xy 72.733299 -283.238314) (xy 72.703734 -283.277658) (xy 72.668241 -283.31175)
			(xy 72.627738 -283.339706) (xy 72.583276 -283.360804) (xy 72.536005 -283.374496) (xy 72.48715 -283.380428)
			(xy 72.437975 -283.378447) (xy 72.389756 -283.368603) (xy 72.34374 -283.351151) (xy 72.301119 -283.326544)
			(xy 72.262998 -283.295419) (xy 72.230363 -283.258582) (xy 72.20406 -283.216986) (xy 72.184769 -283.17171)
			(xy 72.172992 -283.123926) (xy 72.169032 -283.074872) (xy 71.830184 -283.074872) (xy 71.829689 -283.099479)
			(xy 71.821794 -283.148056) (xy 71.80621 -283.194737) (xy 71.783339 -283.238314) (xy 71.753774 -283.277658)
			(xy 71.718281 -283.31175) (xy 71.677778 -283.339706) (xy 71.633316 -283.360804) (xy 71.586045 -283.374496)
			(xy 71.53719 -283.380428) (xy 71.488015 -283.378447) (xy 71.439796 -283.368603) (xy 71.39378 -283.351151)
			(xy 71.351159 -283.326544) (xy 71.313038 -283.295419) (xy 71.280403 -283.258582) (xy 71.2541 -283.216986)
			(xy 71.234809 -283.17171) (xy 71.223032 -283.123926) (xy 71.219072 -283.074872) (xy 70.880224 -283.074872)
			(xy 70.879729 -283.099479) (xy 70.871834 -283.148056) (xy 70.85625 -283.194737) (xy 70.833379 -283.238314)
			(xy 70.803814 -283.277658) (xy 70.768321 -283.31175) (xy 70.727818 -283.339706) (xy 70.683356 -283.360804)
			(xy 70.636085 -283.374496) (xy 70.58723 -283.380428) (xy 70.538055 -283.378447) (xy 70.489836 -283.368603)
			(xy 70.44382 -283.351151) (xy 70.401199 -283.326544) (xy 70.363078 -283.295419) (xy 70.330443 -283.258582)
			(xy 70.30414 -283.216986) (xy 70.284849 -283.17171) (xy 70.273072 -283.123926) (xy 70.269112 -283.074872)
			(xy 69.930264 -283.074872) (xy 69.929769 -283.099479) (xy 69.921874 -283.148056) (xy 69.90629 -283.194737)
			(xy 69.883419 -283.238314) (xy 69.853854 -283.277658) (xy 69.818361 -283.31175) (xy 69.777858 -283.339706)
			(xy 69.733396 -283.360804) (xy 69.686125 -283.374496) (xy 69.63727 -283.380428) (xy 69.588095 -283.378447)
			(xy 69.539876 -283.368603) (xy 69.49386 -283.351151) (xy 69.451239 -283.326544) (xy 69.413118 -283.295419)
			(xy 69.380483 -283.258582) (xy 69.35418 -283.216986) (xy 69.334889 -283.17171) (xy 69.323112 -283.123926)
			(xy 69.319152 -283.074872) (xy 68.98005 -283.074872) (xy 68.979555 -283.099479) (xy 68.97166 -283.148056)
			(xy 68.956076 -283.194737) (xy 68.933205 -283.238314) (xy 68.90364 -283.277658) (xy 68.868147 -283.31175)
			(xy 68.827644 -283.339706) (xy 68.783182 -283.360804) (xy 68.735911 -283.374496) (xy 68.687056 -283.380428)
			(xy 68.637881 -283.378447) (xy 68.589662 -283.368603) (xy 68.543646 -283.351151) (xy 68.501025 -283.326544)
			(xy 68.462904 -283.295419) (xy 68.430269 -283.258582) (xy 68.403966 -283.216986) (xy 68.384675 -283.17171)
			(xy 68.372898 -283.123926) (xy 68.368938 -283.074872) (xy 67.08013 -283.074872) (xy 67.079635 -283.099479)
			(xy 67.07174 -283.148056) (xy 67.056156 -283.194737) (xy 67.033285 -283.238314) (xy 67.00372 -283.277658)
			(xy 66.968227 -283.31175) (xy 66.927724 -283.339706) (xy 66.883262 -283.360804) (xy 66.835991 -283.374496)
			(xy 66.787136 -283.380428) (xy 66.737961 -283.378447) (xy 66.689742 -283.368603) (xy 66.643726 -283.351151)
			(xy 66.601105 -283.326544) (xy 66.562984 -283.295419) (xy 66.530349 -283.258582) (xy 66.504046 -283.216986)
			(xy 66.484755 -283.17171) (xy 66.472978 -283.123926) (xy 66.469018 -283.074872) (xy 66.13017 -283.074872)
			(xy 66.129675 -283.099479) (xy 66.12178 -283.148056) (xy 66.106196 -283.194737) (xy 66.083325 -283.238314)
			(xy 66.05376 -283.277658) (xy 66.018267 -283.31175) (xy 65.977764 -283.339706) (xy 65.933302 -283.360804)
			(xy 65.886031 -283.374496) (xy 65.837176 -283.380428) (xy 65.788001 -283.378447) (xy 65.739782 -283.368603)
			(xy 65.693766 -283.351151) (xy 65.651145 -283.326544) (xy 65.613024 -283.295419) (xy 65.580389 -283.258582)
			(xy 65.554086 -283.216986) (xy 65.534795 -283.17171) (xy 65.523018 -283.123926) (xy 65.519058 -283.074872)
			(xy 65.18021 -283.074872) (xy 65.179715 -283.099479) (xy 65.17182 -283.148056) (xy 65.156236 -283.194737)
			(xy 65.133365 -283.238314) (xy 65.1038 -283.277658) (xy 65.068307 -283.31175) (xy 65.027804 -283.339706)
			(xy 64.983342 -283.360804) (xy 64.936071 -283.374496) (xy 64.887216 -283.380428) (xy 64.838041 -283.378447)
			(xy 64.789822 -283.368603) (xy 64.743806 -283.351151) (xy 64.701185 -283.326544) (xy 64.663064 -283.295419)
			(xy 64.630429 -283.258582) (xy 64.604126 -283.216986) (xy 64.584835 -283.17171) (xy 64.573058 -283.123926)
			(xy 64.569098 -283.074872) (xy 64.23025 -283.074872) (xy 64.229755 -283.099479) (xy 64.22186 -283.148056)
			(xy 64.206276 -283.194737) (xy 64.183405 -283.238314) (xy 64.15384 -283.277658) (xy 64.118347 -283.31175)
			(xy 64.077844 -283.339706) (xy 64.033382 -283.360804) (xy 63.986111 -283.374496) (xy 63.937256 -283.380428)
			(xy 63.888081 -283.378447) (xy 63.839862 -283.368603) (xy 63.793846 -283.351151) (xy 63.751225 -283.326544)
			(xy 63.713104 -283.295419) (xy 63.680469 -283.258582) (xy 63.654166 -283.216986) (xy 63.634875 -283.17171)
			(xy 63.623098 -283.123926) (xy 63.619138 -283.074872) (xy 63.28029 -283.074872) (xy 63.279795 -283.099479)
			(xy 63.2719 -283.148056) (xy 63.256316 -283.194737) (xy 63.233445 -283.238314) (xy 63.20388 -283.277658)
			(xy 63.168387 -283.31175) (xy 63.127884 -283.339706) (xy 63.083422 -283.360804) (xy 63.036151 -283.374496)
			(xy 62.987296 -283.380428) (xy 62.938121 -283.378447) (xy 62.889902 -283.368603) (xy 62.843886 -283.351151)
			(xy 62.801265 -283.326544) (xy 62.763144 -283.295419) (xy 62.730509 -283.258582) (xy 62.704206 -283.216986)
			(xy 62.684915 -283.17171) (xy 62.673138 -283.123926) (xy 62.669178 -283.074872) (xy 62.330076 -283.074872)
			(xy 62.329581 -283.099479) (xy 62.321686 -283.148056) (xy 62.306102 -283.194737) (xy 62.283231 -283.238314)
			(xy 62.253666 -283.277658) (xy 62.218173 -283.31175) (xy 62.17767 -283.339706) (xy 62.133208 -283.360804)
			(xy 62.085937 -283.374496) (xy 62.037082 -283.380428) (xy 61.987907 -283.378447) (xy 61.939688 -283.368603)
			(xy 61.893672 -283.351151) (xy 61.851051 -283.326544) (xy 61.81293 -283.295419) (xy 61.780295 -283.258582)
			(xy 61.753992 -283.216986) (xy 61.734701 -283.17171) (xy 61.722924 -283.123926) (xy 61.718964 -283.074872)
			(xy 61.380116 -283.074872) (xy 61.379621 -283.099479) (xy 61.371726 -283.148056) (xy 61.356142 -283.194737)
			(xy 61.333271 -283.238314) (xy 61.303706 -283.277658) (xy 61.268213 -283.31175) (xy 61.22771 -283.339706)
			(xy 61.183248 -283.360804) (xy 61.135977 -283.374496) (xy 61.087122 -283.380428) (xy 61.037947 -283.378447)
			(xy 60.989728 -283.368603) (xy 60.943712 -283.351151) (xy 60.901091 -283.326544) (xy 60.86297 -283.295419)
			(xy 60.830335 -283.258582) (xy 60.804032 -283.216986) (xy 60.784741 -283.17171) (xy 60.772964 -283.123926)
			(xy 60.769004 -283.074872) (xy 60.430156 -283.074872) (xy 60.429661 -283.099479) (xy 60.421766 -283.148056)
			(xy 60.406182 -283.194737) (xy 60.383311 -283.238314) (xy 60.353746 -283.277658) (xy 60.318253 -283.31175)
			(xy 60.27775 -283.339706) (xy 60.233288 -283.360804) (xy 60.186017 -283.374496) (xy 60.137162 -283.380428)
			(xy 60.087987 -283.378447) (xy 60.039768 -283.368603) (xy 59.993752 -283.351151) (xy 59.951131 -283.326544)
			(xy 59.91301 -283.295419) (xy 59.880375 -283.258582) (xy 59.854072 -283.216986) (xy 59.834781 -283.17171)
			(xy 59.823004 -283.123926) (xy 59.819044 -283.074872) (xy 58.530236 -283.074872) (xy 58.529741 -283.099479)
			(xy 58.521846 -283.148056) (xy 58.506262 -283.194737) (xy 58.483391 -283.238314) (xy 58.453826 -283.277658)
			(xy 58.418333 -283.31175) (xy 58.37783 -283.339706) (xy 58.333368 -283.360804) (xy 58.286097 -283.374496)
			(xy 58.237242 -283.380428) (xy 58.188067 -283.378447) (xy 58.139848 -283.368603) (xy 58.093832 -283.351151)
			(xy 58.051211 -283.326544) (xy 58.01309 -283.295419) (xy 57.980455 -283.258582) (xy 57.954152 -283.216986)
			(xy 57.934861 -283.17171) (xy 57.923084 -283.123926) (xy 57.919124 -283.074872) (xy 57.580276 -283.074872)
			(xy 57.579781 -283.099479) (xy 57.571886 -283.148056) (xy 57.556302 -283.194737) (xy 57.533431 -283.238314)
			(xy 57.503866 -283.277658) (xy 57.468373 -283.31175) (xy 57.42787 -283.339706) (xy 57.383408 -283.360804)
			(xy 57.336137 -283.374496) (xy 57.287282 -283.380428) (xy 57.238107 -283.378447) (xy 57.189888 -283.368603)
			(xy 57.143872 -283.351151) (xy 57.101251 -283.326544) (xy 57.06313 -283.295419) (xy 57.030495 -283.258582)
			(xy 57.004192 -283.216986) (xy 56.984901 -283.17171) (xy 56.973124 -283.123926) (xy 56.969164 -283.074872)
			(xy 56.630316 -283.074872) (xy 56.629821 -283.099479) (xy 56.621926 -283.148056) (xy 56.606342 -283.194737)
			(xy 56.583471 -283.238314) (xy 56.553906 -283.277658) (xy 56.518413 -283.31175) (xy 56.47791 -283.339706)
			(xy 56.433448 -283.360804) (xy 56.386177 -283.374496) (xy 56.337322 -283.380428) (xy 56.288147 -283.378447)
			(xy 56.239928 -283.368603) (xy 56.193912 -283.351151) (xy 56.151291 -283.326544) (xy 56.11317 -283.295419)
			(xy 56.080535 -283.258582) (xy 56.054232 -283.216986) (xy 56.034941 -283.17171) (xy 56.023164 -283.123926)
			(xy 56.019204 -283.074872) (xy 55.680102 -283.074872) (xy 55.679607 -283.099479) (xy 55.671712 -283.148056)
			(xy 55.656128 -283.194737) (xy 55.633257 -283.238314) (xy 55.603692 -283.277658) (xy 55.568199 -283.31175)
			(xy 55.527696 -283.339706) (xy 55.483234 -283.360804) (xy 55.435963 -283.374496) (xy 55.387108 -283.380428)
			(xy 55.337933 -283.378447) (xy 55.289714 -283.368603) (xy 55.243698 -283.351151) (xy 55.201077 -283.326544)
			(xy 55.162956 -283.295419) (xy 55.130321 -283.258582) (xy 55.104018 -283.216986) (xy 55.084727 -283.17171)
			(xy 55.07295 -283.123926) (xy 55.06899 -283.074872) (xy 54.730142 -283.074872) (xy 54.729647 -283.099479)
			(xy 54.721752 -283.148056) (xy 54.706168 -283.194737) (xy 54.683297 -283.238314) (xy 54.653732 -283.277658)
			(xy 54.618239 -283.31175) (xy 54.577736 -283.339706) (xy 54.533274 -283.360804) (xy 54.486003 -283.374496)
			(xy 54.437148 -283.380428) (xy 54.387973 -283.378447) (xy 54.339754 -283.368603) (xy 54.293738 -283.351151)
			(xy 54.251117 -283.326544) (xy 54.212996 -283.295419) (xy 54.180361 -283.258582) (xy 54.154058 -283.216986)
			(xy 54.134767 -283.17171) (xy 54.12299 -283.123926) (xy 54.11903 -283.074872) (xy 53.780182 -283.074872)
			(xy 53.779687 -283.099479) (xy 53.771792 -283.148056) (xy 53.756208 -283.194737) (xy 53.733337 -283.238314)
			(xy 53.703772 -283.277658) (xy 53.668279 -283.31175) (xy 53.627776 -283.339706) (xy 53.583314 -283.360804)
			(xy 53.536043 -283.374496) (xy 53.487188 -283.380428) (xy 53.438013 -283.378447) (xy 53.389794 -283.368603)
			(xy 53.343778 -283.351151) (xy 53.301157 -283.326544) (xy 53.263036 -283.295419) (xy 53.230401 -283.258582)
			(xy 53.204098 -283.216986) (xy 53.184807 -283.17171) (xy 53.17303 -283.123926) (xy 53.16907 -283.074872)
			(xy 52.830222 -283.074872) (xy 52.829727 -283.099479) (xy 52.821832 -283.148056) (xy 52.806248 -283.194737)
			(xy 52.783377 -283.238314) (xy 52.753812 -283.277658) (xy 52.718319 -283.31175) (xy 52.677816 -283.339706)
			(xy 52.633354 -283.360804) (xy 52.586083 -283.374496) (xy 52.537228 -283.380428) (xy 52.488053 -283.378447)
			(xy 52.439834 -283.368603) (xy 52.393818 -283.351151) (xy 52.351197 -283.326544) (xy 52.313076 -283.295419)
			(xy 52.280441 -283.258582) (xy 52.254138 -283.216986) (xy 52.234847 -283.17171) (xy 52.22307 -283.123926)
			(xy 52.21911 -283.074872) (xy 51.880262 -283.074872) (xy 51.879767 -283.099479) (xy 51.871872 -283.148056)
			(xy 51.856288 -283.194737) (xy 51.833417 -283.238314) (xy 51.803852 -283.277658) (xy 51.768359 -283.31175)
			(xy 51.727856 -283.339706) (xy 51.683394 -283.360804) (xy 51.636123 -283.374496) (xy 51.587268 -283.380428)
			(xy 51.538093 -283.378447) (xy 51.489874 -283.368603) (xy 51.443858 -283.351151) (xy 51.401237 -283.326544)
			(xy 51.363116 -283.295419) (xy 51.330481 -283.258582) (xy 51.304178 -283.216986) (xy 51.284887 -283.17171)
			(xy 51.27311 -283.123926) (xy 51.26915 -283.074872) (xy 50.930302 -283.074872) (xy 50.929807 -283.099479)
			(xy 50.921912 -283.148056) (xy 50.906328 -283.194737) (xy 50.883457 -283.238314) (xy 50.853892 -283.277658)
			(xy 50.818399 -283.31175) (xy 50.777896 -283.339706) (xy 50.733434 -283.360804) (xy 50.686163 -283.374496)
			(xy 50.637308 -283.380428) (xy 50.588133 -283.378447) (xy 50.539914 -283.368603) (xy 50.493898 -283.351151)
			(xy 50.451277 -283.326544) (xy 50.413156 -283.295419) (xy 50.380521 -283.258582) (xy 50.354218 -283.216986)
			(xy 50.334927 -283.17171) (xy 50.32315 -283.123926) (xy 50.31919 -283.074872) (xy 49.980088 -283.074872)
			(xy 49.979593 -283.099479) (xy 49.971698 -283.148056) (xy 49.956114 -283.194737) (xy 49.933243 -283.238314)
			(xy 49.903678 -283.277658) (xy 49.868185 -283.31175) (xy 49.827682 -283.339706) (xy 49.78322 -283.360804)
			(xy 49.735949 -283.374496) (xy 49.687094 -283.380428) (xy 49.637919 -283.378447) (xy 49.5897 -283.368603)
			(xy 49.543684 -283.351151) (xy 49.501063 -283.326544) (xy 49.462942 -283.295419) (xy 49.430307 -283.258582)
			(xy 49.404004 -283.216986) (xy 49.384713 -283.17171) (xy 49.372936 -283.123926) (xy 49.368976 -283.074872)
			(xy 49.181004 -283.074872) (xy 49.181004 -283.549852) (xy 73.593972 -283.549852) (xy 73.597932 -283.500798)
			(xy 73.609709 -283.453014) (xy 73.629 -283.407738) (xy 73.655303 -283.366142) (xy 73.687938 -283.329305)
			(xy 73.726059 -283.29818) (xy 73.76868 -283.273573) (xy 73.814696 -283.256121) (xy 73.862915 -283.246277)
			(xy 73.91209 -283.244296) (xy 73.960945 -283.250228) (xy 74.008216 -283.26392) (xy 74.052678 -283.285018)
			(xy 74.093181 -283.312974) (xy 74.128674 -283.347066) (xy 74.158239 -283.38641) (xy 74.18111 -283.429987)
			(xy 74.196694 -283.476668) (xy 74.204589 -283.525245) (xy 74.205084 -283.549852) (xy 74.204589 -283.574459)
			(xy 74.20441 -283.57556) (xy 74.523088 -283.57556) (xy 74.523088 -283.524144) (xy 74.531131 -283.473362)
			(xy 74.547019 -283.424463) (xy 74.570362 -283.378651) (xy 74.600583 -283.337055) (xy 74.636939 -283.300699)
			(xy 74.678535 -283.270478) (xy 74.724347 -283.247135) (xy 74.773246 -283.231247) (xy 74.824028 -283.223204)
			(xy 74.875444 -283.223204) (xy 74.926226 -283.231247) (xy 74.975125 -283.247135) (xy 75.020937 -283.270478)
			(xy 75.062533 -283.300699) (xy 75.098889 -283.337055) (xy 75.12911 -283.378651) (xy 75.152453 -283.424463)
			(xy 75.168341 -283.473362) (xy 75.176384 -283.524144) (xy 75.176888 -283.549852) (xy 75.176384 -283.57556)
			(xy 75.473302 -283.57556) (xy 75.473302 -283.524144) (xy 75.481345 -283.473362) (xy 75.497233 -283.424463)
			(xy 75.520576 -283.378651) (xy 75.550797 -283.337055) (xy 75.587153 -283.300699) (xy 75.628749 -283.270478)
			(xy 75.674561 -283.247135) (xy 75.72346 -283.231247) (xy 75.774242 -283.223204) (xy 75.825658 -283.223204)
			(xy 75.87644 -283.231247) (xy 75.925339 -283.247135) (xy 75.971151 -283.270478) (xy 76.012747 -283.300699)
			(xy 76.049103 -283.337055) (xy 76.079324 -283.378651) (xy 76.102667 -283.424463) (xy 76.118555 -283.473362)
			(xy 76.126598 -283.524144) (xy 76.127102 -283.549852) (xy 76.444106 -283.549852) (xy 76.448066 -283.500798)
			(xy 76.459843 -283.453014) (xy 76.479134 -283.407738) (xy 76.505437 -283.366142) (xy 76.538072 -283.329305)
			(xy 76.576193 -283.29818) (xy 76.618814 -283.273573) (xy 76.66483 -283.256121) (xy 76.713049 -283.246277)
			(xy 76.762224 -283.244296) (xy 76.811079 -283.250228) (xy 76.85835 -283.26392) (xy 76.902812 -283.285018)
			(xy 76.943315 -283.312974) (xy 76.978808 -283.347066) (xy 77.008373 -283.38641) (xy 77.031244 -283.429987)
			(xy 77.046828 -283.476668) (xy 77.054723 -283.525245) (xy 77.055218 -283.549852) (xy 77.394066 -283.549852)
			(xy 77.398026 -283.500798) (xy 77.409803 -283.453014) (xy 77.429094 -283.407738) (xy 77.455397 -283.366142)
			(xy 77.488032 -283.329305) (xy 77.526153 -283.29818) (xy 77.568774 -283.273573) (xy 77.61479 -283.256121)
			(xy 77.663009 -283.246277) (xy 77.712184 -283.244296) (xy 77.761039 -283.250228) (xy 77.80831 -283.26392)
			(xy 77.852772 -283.285018) (xy 77.893275 -283.312974) (xy 77.928768 -283.347066) (xy 77.958333 -283.38641)
			(xy 77.981204 -283.429987) (xy 77.996788 -283.476668) (xy 78.004683 -283.525245) (xy 78.005178 -283.549852)
			(xy 78.344026 -283.549852) (xy 78.347986 -283.500798) (xy 78.359763 -283.453014) (xy 78.379054 -283.407738)
			(xy 78.405357 -283.366142) (xy 78.437992 -283.329305) (xy 78.476113 -283.29818) (xy 78.518734 -283.273573)
			(xy 78.56475 -283.256121) (xy 78.612969 -283.246277) (xy 78.662144 -283.244296) (xy 78.710999 -283.250228)
			(xy 78.75827 -283.26392) (xy 78.802732 -283.285018) (xy 78.843235 -283.312974) (xy 78.878728 -283.347066)
			(xy 78.908293 -283.38641) (xy 78.931164 -283.429987) (xy 78.946748 -283.476668) (xy 78.954643 -283.525245)
			(xy 78.955138 -283.549852) (xy 79.293986 -283.549852) (xy 79.297946 -283.500798) (xy 79.309723 -283.453014)
			(xy 79.329014 -283.407738) (xy 79.355317 -283.366142) (xy 79.387952 -283.329305) (xy 79.426073 -283.29818)
			(xy 79.468694 -283.273573) (xy 79.51471 -283.256121) (xy 79.562929 -283.246277) (xy 79.612104 -283.244296)
			(xy 79.660959 -283.250228) (xy 79.70823 -283.26392) (xy 79.752692 -283.285018) (xy 79.793195 -283.312974)
			(xy 79.828688 -283.347066) (xy 79.858253 -283.38641) (xy 79.881124 -283.429987) (xy 79.896708 -283.476668)
			(xy 79.904603 -283.525245) (xy 79.905098 -283.549852) (xy 80.243946 -283.549852) (xy 80.247906 -283.500798)
			(xy 80.259683 -283.453014) (xy 80.278974 -283.407738) (xy 80.305277 -283.366142) (xy 80.337912 -283.329305)
			(xy 80.376033 -283.29818) (xy 80.418654 -283.273573) (xy 80.46467 -283.256121) (xy 80.512889 -283.246277)
			(xy 80.562064 -283.244296) (xy 80.610919 -283.250228) (xy 80.65819 -283.26392) (xy 80.702652 -283.285018)
			(xy 80.743155 -283.312974) (xy 80.778648 -283.347066) (xy 80.808213 -283.38641) (xy 80.831084 -283.429987)
			(xy 80.846668 -283.476668) (xy 80.854563 -283.525245) (xy 80.855058 -283.549852) (xy 80.854563 -283.574459)
			(xy 80.854384 -283.57556) (xy 81.173316 -283.57556) (xy 81.173316 -283.524144) (xy 81.181359 -283.473362)
			(xy 81.197247 -283.424463) (xy 81.22059 -283.378651) (xy 81.250811 -283.337055) (xy 81.287167 -283.300699)
			(xy 81.328763 -283.270478) (xy 81.374575 -283.247135) (xy 81.423474 -283.231247) (xy 81.474256 -283.223204)
			(xy 81.525672 -283.223204) (xy 81.576454 -283.231247) (xy 81.625353 -283.247135) (xy 81.671165 -283.270478)
			(xy 81.712761 -283.300699) (xy 81.749117 -283.337055) (xy 81.779338 -283.378651) (xy 81.802681 -283.424463)
			(xy 81.818569 -283.473362) (xy 81.826612 -283.524144) (xy 81.827116 -283.549852) (xy 81.826612 -283.57556)
			(xy 82.123276 -283.57556) (xy 82.123276 -283.524144) (xy 82.131319 -283.473362) (xy 82.147207 -283.424463)
			(xy 82.17055 -283.378651) (xy 82.200771 -283.337055) (xy 82.237127 -283.300699) (xy 82.278723 -283.270478)
			(xy 82.324535 -283.247135) (xy 82.373434 -283.231247) (xy 82.424216 -283.223204) (xy 82.475632 -283.223204)
			(xy 82.526414 -283.231247) (xy 82.575313 -283.247135) (xy 82.621125 -283.270478) (xy 82.662721 -283.300699)
			(xy 82.699077 -283.337055) (xy 82.729298 -283.378651) (xy 82.752641 -283.424463) (xy 82.768529 -283.473362)
			(xy 82.776572 -283.524144) (xy 82.777076 -283.549852) (xy 82.777071 -283.550106) (xy 83.094334 -283.550106)
			(xy 83.098294 -283.501052) (xy 83.110071 -283.453268) (xy 83.129362 -283.407992) (xy 83.155665 -283.366396)
			(xy 83.1883 -283.329559) (xy 83.226421 -283.298434) (xy 83.269042 -283.273827) (xy 83.315058 -283.256375)
			(xy 83.363277 -283.246531) (xy 83.412452 -283.24455) (xy 83.461307 -283.250482) (xy 83.508578 -283.264174)
			(xy 83.55304 -283.285272) (xy 83.593543 -283.313228) (xy 83.629036 -283.34732) (xy 83.658601 -283.386664)
			(xy 83.681472 -283.430241) (xy 83.697056 -283.476922) (xy 83.704951 -283.525499) (xy 83.705446 -283.550106)
			(xy 83.704951 -283.574713) (xy 83.697056 -283.62329) (xy 83.681472 -283.669971) (xy 83.658601 -283.713548)
			(xy 83.629036 -283.752892) (xy 83.593543 -283.786984) (xy 83.55304 -283.81494) (xy 83.508578 -283.836038)
			(xy 83.461307 -283.84973) (xy 83.412452 -283.855662) (xy 83.363277 -283.853681) (xy 83.315058 -283.843837)
			(xy 83.269042 -283.826385) (xy 83.226421 -283.801778) (xy 83.1883 -283.770653) (xy 83.155665 -283.733816)
			(xy 83.129362 -283.69222) (xy 83.110071 -283.646944) (xy 83.098294 -283.59916) (xy 83.094334 -283.550106)
			(xy 82.777071 -283.550106) (xy 82.776572 -283.57556) (xy 82.768529 -283.626342) (xy 82.752641 -283.675241)
			(xy 82.729298 -283.721053) (xy 82.699077 -283.762649) (xy 82.662721 -283.799005) (xy 82.621125 -283.829226)
			(xy 82.575313 -283.852569) (xy 82.526414 -283.868457) (xy 82.475632 -283.8765) (xy 82.424216 -283.8765)
			(xy 82.373434 -283.868457) (xy 82.324535 -283.852569) (xy 82.278723 -283.829226) (xy 82.237127 -283.799005)
			(xy 82.200771 -283.762649) (xy 82.17055 -283.721053) (xy 82.147207 -283.675241) (xy 82.131319 -283.626342)
			(xy 82.123276 -283.57556) (xy 81.826612 -283.57556) (xy 81.818569 -283.626342) (xy 81.802681 -283.675241)
			(xy 81.779338 -283.721053) (xy 81.749117 -283.762649) (xy 81.712761 -283.799005) (xy 81.671165 -283.829226)
			(xy 81.625353 -283.852569) (xy 81.576454 -283.868457) (xy 81.525672 -283.8765) (xy 81.474256 -283.8765)
			(xy 81.423474 -283.868457) (xy 81.374575 -283.852569) (xy 81.328763 -283.829226) (xy 81.287167 -283.799005)
			(xy 81.250811 -283.762649) (xy 81.22059 -283.721053) (xy 81.197247 -283.675241) (xy 81.181359 -283.626342)
			(xy 81.173316 -283.57556) (xy 80.854384 -283.57556) (xy 80.846668 -283.623036) (xy 80.831084 -283.669717)
			(xy 80.808213 -283.713294) (xy 80.778648 -283.752638) (xy 80.743155 -283.78673) (xy 80.702652 -283.814686)
			(xy 80.65819 -283.835784) (xy 80.610919 -283.849476) (xy 80.562064 -283.855408) (xy 80.512889 -283.853427)
			(xy 80.46467 -283.843583) (xy 80.418654 -283.826131) (xy 80.376033 -283.801524) (xy 80.337912 -283.770399)
			(xy 80.305277 -283.733562) (xy 80.278974 -283.691966) (xy 80.259683 -283.64669) (xy 80.247906 -283.598906)
			(xy 80.243946 -283.549852) (xy 79.905098 -283.549852) (xy 79.904603 -283.574459) (xy 79.896708 -283.623036)
			(xy 79.881124 -283.669717) (xy 79.858253 -283.713294) (xy 79.828688 -283.752638) (xy 79.793195 -283.78673)
			(xy 79.752692 -283.814686) (xy 79.70823 -283.835784) (xy 79.660959 -283.849476) (xy 79.612104 -283.855408)
			(xy 79.562929 -283.853427) (xy 79.51471 -283.843583) (xy 79.468694 -283.826131) (xy 79.426073 -283.801524)
			(xy 79.387952 -283.770399) (xy 79.355317 -283.733562) (xy 79.329014 -283.691966) (xy 79.309723 -283.64669)
			(xy 79.297946 -283.598906) (xy 79.293986 -283.549852) (xy 78.955138 -283.549852) (xy 78.954643 -283.574459)
			(xy 78.946748 -283.623036) (xy 78.931164 -283.669717) (xy 78.908293 -283.713294) (xy 78.878728 -283.752638)
			(xy 78.843235 -283.78673) (xy 78.802732 -283.814686) (xy 78.75827 -283.835784) (xy 78.710999 -283.849476)
			(xy 78.662144 -283.855408) (xy 78.612969 -283.853427) (xy 78.56475 -283.843583) (xy 78.518734 -283.826131)
			(xy 78.476113 -283.801524) (xy 78.437992 -283.770399) (xy 78.405357 -283.733562) (xy 78.379054 -283.691966)
			(xy 78.359763 -283.64669) (xy 78.347986 -283.598906) (xy 78.344026 -283.549852) (xy 78.005178 -283.549852)
			(xy 78.004683 -283.574459) (xy 77.996788 -283.623036) (xy 77.981204 -283.669717) (xy 77.958333 -283.713294)
			(xy 77.928768 -283.752638) (xy 77.893275 -283.78673) (xy 77.852772 -283.814686) (xy 77.80831 -283.835784)
			(xy 77.761039 -283.849476) (xy 77.712184 -283.855408) (xy 77.663009 -283.853427) (xy 77.61479 -283.843583)
			(xy 77.568774 -283.826131) (xy 77.526153 -283.801524) (xy 77.488032 -283.770399) (xy 77.455397 -283.733562)
			(xy 77.429094 -283.691966) (xy 77.409803 -283.64669) (xy 77.398026 -283.598906) (xy 77.394066 -283.549852)
			(xy 77.055218 -283.549852) (xy 77.054723 -283.574459) (xy 77.046828 -283.623036) (xy 77.031244 -283.669717)
			(xy 77.008373 -283.713294) (xy 76.978808 -283.752638) (xy 76.943315 -283.78673) (xy 76.902812 -283.814686)
			(xy 76.85835 -283.835784) (xy 76.811079 -283.849476) (xy 76.762224 -283.855408) (xy 76.713049 -283.853427)
			(xy 76.66483 -283.843583) (xy 76.618814 -283.826131) (xy 76.576193 -283.801524) (xy 76.538072 -283.770399)
			(xy 76.505437 -283.733562) (xy 76.479134 -283.691966) (xy 76.459843 -283.64669) (xy 76.448066 -283.598906)
			(xy 76.444106 -283.549852) (xy 76.127102 -283.549852) (xy 76.126598 -283.57556) (xy 76.118555 -283.626342)
			(xy 76.102667 -283.675241) (xy 76.079324 -283.721053) (xy 76.049103 -283.762649) (xy 76.012747 -283.799005)
			(xy 75.971151 -283.829226) (xy 75.925339 -283.852569) (xy 75.87644 -283.868457) (xy 75.825658 -283.8765)
			(xy 75.774242 -283.8765) (xy 75.72346 -283.868457) (xy 75.674561 -283.852569) (xy 75.628749 -283.829226)
			(xy 75.587153 -283.799005) (xy 75.550797 -283.762649) (xy 75.520576 -283.721053) (xy 75.497233 -283.675241)
			(xy 75.481345 -283.626342) (xy 75.473302 -283.57556) (xy 75.176384 -283.57556) (xy 75.168341 -283.626342)
			(xy 75.152453 -283.675241) (xy 75.12911 -283.721053) (xy 75.098889 -283.762649) (xy 75.062533 -283.799005)
			(xy 75.020937 -283.829226) (xy 74.975125 -283.852569) (xy 74.926226 -283.868457) (xy 74.875444 -283.8765)
			(xy 74.824028 -283.8765) (xy 74.773246 -283.868457) (xy 74.724347 -283.852569) (xy 74.678535 -283.829226)
			(xy 74.636939 -283.799005) (xy 74.600583 -283.762649) (xy 74.570362 -283.721053) (xy 74.547019 -283.675241)
			(xy 74.531131 -283.626342) (xy 74.523088 -283.57556) (xy 74.20441 -283.57556) (xy 74.196694 -283.623036)
			(xy 74.18111 -283.669717) (xy 74.158239 -283.713294) (xy 74.128674 -283.752638) (xy 74.093181 -283.78673)
			(xy 74.052678 -283.814686) (xy 74.008216 -283.835784) (xy 73.960945 -283.849476) (xy 73.91209 -283.855408)
			(xy 73.862915 -283.853427) (xy 73.814696 -283.843583) (xy 73.76868 -283.826131) (xy 73.726059 -283.801524)
			(xy 73.687938 -283.770399) (xy 73.655303 -283.733562) (xy 73.629 -283.691966) (xy 73.609709 -283.64669)
			(xy 73.597932 -283.598906) (xy 73.593972 -283.549852) (xy 49.181004 -283.549852) (xy 49.181004 -284.024832)
			(xy 49.368976 -284.024832) (xy 49.372936 -283.975778) (xy 49.384713 -283.927994) (xy 49.404004 -283.882718)
			(xy 49.430307 -283.841122) (xy 49.462942 -283.804285) (xy 49.501063 -283.77316) (xy 49.543684 -283.748553)
			(xy 49.5897 -283.731101) (xy 49.637919 -283.721257) (xy 49.687094 -283.719276) (xy 49.735949 -283.725208)
			(xy 49.78322 -283.7389) (xy 49.827682 -283.759998) (xy 49.868185 -283.787954) (xy 49.903678 -283.822046)
			(xy 49.933243 -283.86139) (xy 49.956114 -283.904967) (xy 49.971698 -283.951648) (xy 49.979593 -284.000225)
			(xy 49.980088 -284.024832) (xy 50.31919 -284.024832) (xy 50.32315 -283.975778) (xy 50.334927 -283.927994)
			(xy 50.354218 -283.882718) (xy 50.380521 -283.841122) (xy 50.413156 -283.804285) (xy 50.451277 -283.77316)
			(xy 50.493898 -283.748553) (xy 50.539914 -283.731101) (xy 50.588133 -283.721257) (xy 50.637308 -283.719276)
			(xy 50.686163 -283.725208) (xy 50.733434 -283.7389) (xy 50.777896 -283.759998) (xy 50.818399 -283.787954)
			(xy 50.853892 -283.822046) (xy 50.883457 -283.86139) (xy 50.906328 -283.904967) (xy 50.921912 -283.951648)
			(xy 50.929807 -284.000225) (xy 50.930302 -284.024832) (xy 51.26915 -284.024832) (xy 51.27311 -283.975778)
			(xy 51.284887 -283.927994) (xy 51.304178 -283.882718) (xy 51.330481 -283.841122) (xy 51.363116 -283.804285)
			(xy 51.401237 -283.77316) (xy 51.443858 -283.748553) (xy 51.489874 -283.731101) (xy 51.538093 -283.721257)
			(xy 51.587268 -283.719276) (xy 51.636123 -283.725208) (xy 51.683394 -283.7389) (xy 51.727856 -283.759998)
			(xy 51.768359 -283.787954) (xy 51.803852 -283.822046) (xy 51.833417 -283.86139) (xy 51.856288 -283.904967)
			(xy 51.871872 -283.951648) (xy 51.879767 -284.000225) (xy 51.880262 -284.024832) (xy 52.21911 -284.024832)
			(xy 52.22307 -283.975778) (xy 52.234847 -283.927994) (xy 52.254138 -283.882718) (xy 52.280441 -283.841122)
			(xy 52.313076 -283.804285) (xy 52.351197 -283.77316) (xy 52.393818 -283.748553) (xy 52.439834 -283.731101)
			(xy 52.488053 -283.721257) (xy 52.537228 -283.719276) (xy 52.586083 -283.725208) (xy 52.633354 -283.7389)
			(xy 52.677816 -283.759998) (xy 52.718319 -283.787954) (xy 52.753812 -283.822046) (xy 52.783377 -283.86139)
			(xy 52.806248 -283.904967) (xy 52.821832 -283.951648) (xy 52.829727 -284.000225) (xy 52.830222 -284.024832)
			(xy 53.16907 -284.024832) (xy 53.17303 -283.975778) (xy 53.184807 -283.927994) (xy 53.204098 -283.882718)
			(xy 53.230401 -283.841122) (xy 53.263036 -283.804285) (xy 53.301157 -283.77316) (xy 53.343778 -283.748553)
			(xy 53.389794 -283.731101) (xy 53.438013 -283.721257) (xy 53.487188 -283.719276) (xy 53.536043 -283.725208)
			(xy 53.583314 -283.7389) (xy 53.627776 -283.759998) (xy 53.668279 -283.787954) (xy 53.703772 -283.822046)
			(xy 53.733337 -283.86139) (xy 53.756208 -283.904967) (xy 53.771792 -283.951648) (xy 53.779687 -284.000225)
			(xy 53.780182 -284.024832) (xy 54.11903 -284.024832) (xy 54.12299 -283.975778) (xy 54.134767 -283.927994)
			(xy 54.154058 -283.882718) (xy 54.180361 -283.841122) (xy 54.212996 -283.804285) (xy 54.251117 -283.77316)
			(xy 54.293738 -283.748553) (xy 54.339754 -283.731101) (xy 54.387973 -283.721257) (xy 54.437148 -283.719276)
			(xy 54.486003 -283.725208) (xy 54.533274 -283.7389) (xy 54.577736 -283.759998) (xy 54.618239 -283.787954)
			(xy 54.653732 -283.822046) (xy 54.683297 -283.86139) (xy 54.706168 -283.904967) (xy 54.721752 -283.951648)
			(xy 54.729647 -284.000225) (xy 54.730142 -284.024832) (xy 55.06899 -284.024832) (xy 55.07295 -283.975778)
			(xy 55.084727 -283.927994) (xy 55.104018 -283.882718) (xy 55.130321 -283.841122) (xy 55.162956 -283.804285)
			(xy 55.201077 -283.77316) (xy 55.243698 -283.748553) (xy 55.289714 -283.731101) (xy 55.337933 -283.721257)
			(xy 55.387108 -283.719276) (xy 55.435963 -283.725208) (xy 55.483234 -283.7389) (xy 55.527696 -283.759998)
			(xy 55.568199 -283.787954) (xy 55.603692 -283.822046) (xy 55.633257 -283.86139) (xy 55.656128 -283.904967)
			(xy 55.671712 -283.951648) (xy 55.679607 -284.000225) (xy 55.680102 -284.024832) (xy 56.01895 -284.024832)
			(xy 56.02291 -283.975778) (xy 56.034687 -283.927994) (xy 56.053978 -283.882718) (xy 56.080281 -283.841122)
			(xy 56.112916 -283.804285) (xy 56.151037 -283.77316) (xy 56.193658 -283.748553) (xy 56.239674 -283.731101)
			(xy 56.287893 -283.721257) (xy 56.337068 -283.719276) (xy 56.385923 -283.725208) (xy 56.433194 -283.7389)
			(xy 56.477656 -283.759998) (xy 56.518159 -283.787954) (xy 56.553652 -283.822046) (xy 56.583217 -283.86139)
			(xy 56.606088 -283.904967) (xy 56.621672 -283.951648) (xy 56.629567 -284.000225) (xy 56.630062 -284.024832)
			(xy 56.969164 -284.024832) (xy 56.973124 -283.975778) (xy 56.984901 -283.927994) (xy 57.004192 -283.882718)
			(xy 57.030495 -283.841122) (xy 57.06313 -283.804285) (xy 57.101251 -283.77316) (xy 57.143872 -283.748553)
			(xy 57.189888 -283.731101) (xy 57.238107 -283.721257) (xy 57.287282 -283.719276) (xy 57.336137 -283.725208)
			(xy 57.383408 -283.7389) (xy 57.42787 -283.759998) (xy 57.468373 -283.787954) (xy 57.503866 -283.822046)
			(xy 57.533431 -283.86139) (xy 57.556302 -283.904967) (xy 57.571886 -283.951648) (xy 57.579781 -284.000225)
			(xy 57.580276 -284.024832) (xy 57.919124 -284.024832) (xy 57.923084 -283.975778) (xy 57.934861 -283.927994)
			(xy 57.954152 -283.882718) (xy 57.980455 -283.841122) (xy 58.01309 -283.804285) (xy 58.051211 -283.77316)
			(xy 58.093832 -283.748553) (xy 58.139848 -283.731101) (xy 58.188067 -283.721257) (xy 58.237242 -283.719276)
			(xy 58.286097 -283.725208) (xy 58.333368 -283.7389) (xy 58.37783 -283.759998) (xy 58.418333 -283.787954)
			(xy 58.453826 -283.822046) (xy 58.483391 -283.86139) (xy 58.506262 -283.904967) (xy 58.521846 -283.951648)
			(xy 58.529741 -284.000225) (xy 58.530236 -284.024832) (xy 59.819044 -284.024832) (xy 59.823004 -283.975778)
			(xy 59.834781 -283.927994) (xy 59.854072 -283.882718) (xy 59.880375 -283.841122) (xy 59.91301 -283.804285)
			(xy 59.951131 -283.77316) (xy 59.993752 -283.748553) (xy 60.039768 -283.731101) (xy 60.087987 -283.721257)
			(xy 60.137162 -283.719276) (xy 60.186017 -283.725208) (xy 60.233288 -283.7389) (xy 60.27775 -283.759998)
			(xy 60.318253 -283.787954) (xy 60.353746 -283.822046) (xy 60.383311 -283.86139) (xy 60.406182 -283.904967)
			(xy 60.421766 -283.951648) (xy 60.429661 -284.000225) (xy 60.430156 -284.024832) (xy 60.769004 -284.024832)
			(xy 60.772964 -283.975778) (xy 60.784741 -283.927994) (xy 60.804032 -283.882718) (xy 60.830335 -283.841122)
			(xy 60.86297 -283.804285) (xy 60.901091 -283.77316) (xy 60.943712 -283.748553) (xy 60.989728 -283.731101)
			(xy 61.037947 -283.721257) (xy 61.087122 -283.719276) (xy 61.135977 -283.725208) (xy 61.183248 -283.7389)
			(xy 61.22771 -283.759998) (xy 61.268213 -283.787954) (xy 61.303706 -283.822046) (xy 61.333271 -283.86139)
			(xy 61.356142 -283.904967) (xy 61.371726 -283.951648) (xy 61.379621 -284.000225) (xy 61.380116 -284.024832)
			(xy 61.718964 -284.024832) (xy 61.722924 -283.975778) (xy 61.734701 -283.927994) (xy 61.753992 -283.882718)
			(xy 61.780295 -283.841122) (xy 61.81293 -283.804285) (xy 61.851051 -283.77316) (xy 61.893672 -283.748553)
			(xy 61.939688 -283.731101) (xy 61.987907 -283.721257) (xy 62.037082 -283.719276) (xy 62.085937 -283.725208)
			(xy 62.133208 -283.7389) (xy 62.17767 -283.759998) (xy 62.218173 -283.787954) (xy 62.253666 -283.822046)
			(xy 62.283231 -283.86139) (xy 62.306102 -283.904967) (xy 62.321686 -283.951648) (xy 62.329581 -284.000225)
			(xy 62.330076 -284.024832) (xy 62.669178 -284.024832) (xy 62.673138 -283.975778) (xy 62.684915 -283.927994)
			(xy 62.704206 -283.882718) (xy 62.730509 -283.841122) (xy 62.763144 -283.804285) (xy 62.801265 -283.77316)
			(xy 62.843886 -283.748553) (xy 62.889902 -283.731101) (xy 62.938121 -283.721257) (xy 62.987296 -283.719276)
			(xy 63.036151 -283.725208) (xy 63.083422 -283.7389) (xy 63.127884 -283.759998) (xy 63.168387 -283.787954)
			(xy 63.20388 -283.822046) (xy 63.233445 -283.86139) (xy 63.256316 -283.904967) (xy 63.2719 -283.951648)
			(xy 63.279795 -284.000225) (xy 63.28029 -284.024832) (xy 63.619138 -284.024832) (xy 63.623098 -283.975778)
			(xy 63.634875 -283.927994) (xy 63.654166 -283.882718) (xy 63.680469 -283.841122) (xy 63.713104 -283.804285)
			(xy 63.751225 -283.77316) (xy 63.793846 -283.748553) (xy 63.839862 -283.731101) (xy 63.888081 -283.721257)
			(xy 63.937256 -283.719276) (xy 63.986111 -283.725208) (xy 64.033382 -283.7389) (xy 64.077844 -283.759998)
			(xy 64.118347 -283.787954) (xy 64.15384 -283.822046) (xy 64.183405 -283.86139) (xy 64.206276 -283.904967)
			(xy 64.22186 -283.951648) (xy 64.229755 -284.000225) (xy 64.23025 -284.024832) (xy 64.569098 -284.024832)
			(xy 64.573058 -283.975778) (xy 64.584835 -283.927994) (xy 64.604126 -283.882718) (xy 64.630429 -283.841122)
			(xy 64.663064 -283.804285) (xy 64.701185 -283.77316) (xy 64.743806 -283.748553) (xy 64.789822 -283.731101)
			(xy 64.838041 -283.721257) (xy 64.887216 -283.719276) (xy 64.936071 -283.725208) (xy 64.983342 -283.7389)
			(xy 65.027804 -283.759998) (xy 65.068307 -283.787954) (xy 65.1038 -283.822046) (xy 65.133365 -283.86139)
			(xy 65.156236 -283.904967) (xy 65.17182 -283.951648) (xy 65.179715 -284.000225) (xy 65.18021 -284.024832)
			(xy 65.519058 -284.024832) (xy 65.523018 -283.975778) (xy 65.534795 -283.927994) (xy 65.554086 -283.882718)
			(xy 65.580389 -283.841122) (xy 65.613024 -283.804285) (xy 65.651145 -283.77316) (xy 65.693766 -283.748553)
			(xy 65.739782 -283.731101) (xy 65.788001 -283.721257) (xy 65.837176 -283.719276) (xy 65.886031 -283.725208)
			(xy 65.933302 -283.7389) (xy 65.977764 -283.759998) (xy 66.018267 -283.787954) (xy 66.05376 -283.822046)
			(xy 66.083325 -283.86139) (xy 66.106196 -283.904967) (xy 66.12178 -283.951648) (xy 66.129675 -284.000225)
			(xy 66.13017 -284.024832) (xy 66.469018 -284.024832) (xy 66.472978 -283.975778) (xy 66.484755 -283.927994)
			(xy 66.504046 -283.882718) (xy 66.530349 -283.841122) (xy 66.562984 -283.804285) (xy 66.601105 -283.77316)
			(xy 66.643726 -283.748553) (xy 66.689742 -283.731101) (xy 66.737961 -283.721257) (xy 66.787136 -283.719276)
			(xy 66.835991 -283.725208) (xy 66.883262 -283.7389) (xy 66.927724 -283.759998) (xy 66.968227 -283.787954)
			(xy 67.00372 -283.822046) (xy 67.033285 -283.86139) (xy 67.056156 -283.904967) (xy 67.07174 -283.951648)
			(xy 67.079635 -284.000225) (xy 67.08013 -284.024832) (xy 68.368938 -284.024832) (xy 68.372898 -283.975778)
			(xy 68.384675 -283.927994) (xy 68.403966 -283.882718) (xy 68.430269 -283.841122) (xy 68.462904 -283.804285)
			(xy 68.501025 -283.77316) (xy 68.543646 -283.748553) (xy 68.589662 -283.731101) (xy 68.637881 -283.721257)
			(xy 68.687056 -283.719276) (xy 68.735911 -283.725208) (xy 68.783182 -283.7389) (xy 68.827644 -283.759998)
			(xy 68.868147 -283.787954) (xy 68.90364 -283.822046) (xy 68.933205 -283.86139) (xy 68.956076 -283.904967)
			(xy 68.97166 -283.951648) (xy 68.979555 -284.000225) (xy 68.98005 -284.024832) (xy 69.319152 -284.024832)
			(xy 69.323112 -283.975778) (xy 69.334889 -283.927994) (xy 69.35418 -283.882718) (xy 69.380483 -283.841122)
			(xy 69.413118 -283.804285) (xy 69.451239 -283.77316) (xy 69.49386 -283.748553) (xy 69.539876 -283.731101)
			(xy 69.588095 -283.721257) (xy 69.63727 -283.719276) (xy 69.686125 -283.725208) (xy 69.733396 -283.7389)
			(xy 69.777858 -283.759998) (xy 69.818361 -283.787954) (xy 69.853854 -283.822046) (xy 69.883419 -283.86139)
			(xy 69.90629 -283.904967) (xy 69.921874 -283.951648) (xy 69.929769 -284.000225) (xy 69.930264 -284.024832)
			(xy 70.269112 -284.024832) (xy 70.273072 -283.975778) (xy 70.284849 -283.927994) (xy 70.30414 -283.882718)
			(xy 70.330443 -283.841122) (xy 70.363078 -283.804285) (xy 70.401199 -283.77316) (xy 70.44382 -283.748553)
			(xy 70.489836 -283.731101) (xy 70.538055 -283.721257) (xy 70.58723 -283.719276) (xy 70.636085 -283.725208)
			(xy 70.683356 -283.7389) (xy 70.727818 -283.759998) (xy 70.768321 -283.787954) (xy 70.803814 -283.822046)
			(xy 70.833379 -283.86139) (xy 70.85625 -283.904967) (xy 70.871834 -283.951648) (xy 70.879729 -284.000225)
			(xy 70.880224 -284.024832) (xy 71.219072 -284.024832) (xy 71.223032 -283.975778) (xy 71.234809 -283.927994)
			(xy 71.2541 -283.882718) (xy 71.280403 -283.841122) (xy 71.313038 -283.804285) (xy 71.351159 -283.77316)
			(xy 71.39378 -283.748553) (xy 71.439796 -283.731101) (xy 71.488015 -283.721257) (xy 71.53719 -283.719276)
			(xy 71.586045 -283.725208) (xy 71.633316 -283.7389) (xy 71.677778 -283.759998) (xy 71.718281 -283.787954)
			(xy 71.753774 -283.822046) (xy 71.783339 -283.86139) (xy 71.80621 -283.904967) (xy 71.821794 -283.951648)
			(xy 71.829689 -284.000225) (xy 71.830184 -284.024832) (xy 72.169032 -284.024832) (xy 72.172992 -283.975778)
			(xy 72.184769 -283.927994) (xy 72.20406 -283.882718) (xy 72.230363 -283.841122) (xy 72.262998 -283.804285)
			(xy 72.301119 -283.77316) (xy 72.34374 -283.748553) (xy 72.389756 -283.731101) (xy 72.437975 -283.721257)
			(xy 72.48715 -283.719276) (xy 72.536005 -283.725208) (xy 72.583276 -283.7389) (xy 72.627738 -283.759998)
			(xy 72.668241 -283.787954) (xy 72.703734 -283.822046) (xy 72.733299 -283.86139) (xy 72.75617 -283.904967)
			(xy 72.771754 -283.951648) (xy 72.779649 -284.000225) (xy 72.780144 -284.024832) (xy 72.779649 -284.049439)
			(xy 72.771754 -284.098016) (xy 72.75617 -284.144697) (xy 72.733299 -284.188274) (xy 72.703734 -284.227618)
			(xy 72.668241 -284.26171) (xy 72.627738 -284.289666) (xy 72.583276 -284.310764) (xy 72.536005 -284.324456)
			(xy 72.48715 -284.330388) (xy 72.437975 -284.328407) (xy 72.389756 -284.318563) (xy 72.34374 -284.301111)
			(xy 72.301119 -284.276504) (xy 72.262998 -284.245379) (xy 72.230363 -284.208542) (xy 72.20406 -284.166946)
			(xy 72.184769 -284.12167) (xy 72.172992 -284.073886) (xy 72.169032 -284.024832) (xy 71.830184 -284.024832)
			(xy 71.829689 -284.049439) (xy 71.821794 -284.098016) (xy 71.80621 -284.144697) (xy 71.783339 -284.188274)
			(xy 71.753774 -284.227618) (xy 71.718281 -284.26171) (xy 71.677778 -284.289666) (xy 71.633316 -284.310764)
			(xy 71.586045 -284.324456) (xy 71.53719 -284.330388) (xy 71.488015 -284.328407) (xy 71.439796 -284.318563)
			(xy 71.39378 -284.301111) (xy 71.351159 -284.276504) (xy 71.313038 -284.245379) (xy 71.280403 -284.208542)
			(xy 71.2541 -284.166946) (xy 71.234809 -284.12167) (xy 71.223032 -284.073886) (xy 71.219072 -284.024832)
			(xy 70.880224 -284.024832) (xy 70.879729 -284.049439) (xy 70.871834 -284.098016) (xy 70.85625 -284.144697)
			(xy 70.833379 -284.188274) (xy 70.803814 -284.227618) (xy 70.768321 -284.26171) (xy 70.727818 -284.289666)
			(xy 70.683356 -284.310764) (xy 70.636085 -284.324456) (xy 70.58723 -284.330388) (xy 70.538055 -284.328407)
			(xy 70.489836 -284.318563) (xy 70.44382 -284.301111) (xy 70.401199 -284.276504) (xy 70.363078 -284.245379)
			(xy 70.330443 -284.208542) (xy 70.30414 -284.166946) (xy 70.284849 -284.12167) (xy 70.273072 -284.073886)
			(xy 70.269112 -284.024832) (xy 69.930264 -284.024832) (xy 69.929769 -284.049439) (xy 69.921874 -284.098016)
			(xy 69.90629 -284.144697) (xy 69.883419 -284.188274) (xy 69.853854 -284.227618) (xy 69.818361 -284.26171)
			(xy 69.777858 -284.289666) (xy 69.733396 -284.310764) (xy 69.686125 -284.324456) (xy 69.63727 -284.330388)
			(xy 69.588095 -284.328407) (xy 69.539876 -284.318563) (xy 69.49386 -284.301111) (xy 69.451239 -284.276504)
			(xy 69.413118 -284.245379) (xy 69.380483 -284.208542) (xy 69.35418 -284.166946) (xy 69.334889 -284.12167)
			(xy 69.323112 -284.073886) (xy 69.319152 -284.024832) (xy 68.98005 -284.024832) (xy 68.979555 -284.049439)
			(xy 68.97166 -284.098016) (xy 68.956076 -284.144697) (xy 68.933205 -284.188274) (xy 68.90364 -284.227618)
			(xy 68.868147 -284.26171) (xy 68.827644 -284.289666) (xy 68.783182 -284.310764) (xy 68.735911 -284.324456)
			(xy 68.687056 -284.330388) (xy 68.637881 -284.328407) (xy 68.589662 -284.318563) (xy 68.543646 -284.301111)
			(xy 68.501025 -284.276504) (xy 68.462904 -284.245379) (xy 68.430269 -284.208542) (xy 68.403966 -284.166946)
			(xy 68.384675 -284.12167) (xy 68.372898 -284.073886) (xy 68.368938 -284.024832) (xy 67.08013 -284.024832)
			(xy 67.079635 -284.049439) (xy 67.07174 -284.098016) (xy 67.056156 -284.144697) (xy 67.033285 -284.188274)
			(xy 67.00372 -284.227618) (xy 66.968227 -284.26171) (xy 66.927724 -284.289666) (xy 66.883262 -284.310764)
			(xy 66.835991 -284.324456) (xy 66.787136 -284.330388) (xy 66.737961 -284.328407) (xy 66.689742 -284.318563)
			(xy 66.643726 -284.301111) (xy 66.601105 -284.276504) (xy 66.562984 -284.245379) (xy 66.530349 -284.208542)
			(xy 66.504046 -284.166946) (xy 66.484755 -284.12167) (xy 66.472978 -284.073886) (xy 66.469018 -284.024832)
			(xy 66.13017 -284.024832) (xy 66.129675 -284.049439) (xy 66.12178 -284.098016) (xy 66.106196 -284.144697)
			(xy 66.083325 -284.188274) (xy 66.05376 -284.227618) (xy 66.018267 -284.26171) (xy 65.977764 -284.289666)
			(xy 65.933302 -284.310764) (xy 65.886031 -284.324456) (xy 65.837176 -284.330388) (xy 65.788001 -284.328407)
			(xy 65.739782 -284.318563) (xy 65.693766 -284.301111) (xy 65.651145 -284.276504) (xy 65.613024 -284.245379)
			(xy 65.580389 -284.208542) (xy 65.554086 -284.166946) (xy 65.534795 -284.12167) (xy 65.523018 -284.073886)
			(xy 65.519058 -284.024832) (xy 65.18021 -284.024832) (xy 65.179715 -284.049439) (xy 65.17182 -284.098016)
			(xy 65.156236 -284.144697) (xy 65.133365 -284.188274) (xy 65.1038 -284.227618) (xy 65.068307 -284.26171)
			(xy 65.027804 -284.289666) (xy 64.983342 -284.310764) (xy 64.936071 -284.324456) (xy 64.887216 -284.330388)
			(xy 64.838041 -284.328407) (xy 64.789822 -284.318563) (xy 64.743806 -284.301111) (xy 64.701185 -284.276504)
			(xy 64.663064 -284.245379) (xy 64.630429 -284.208542) (xy 64.604126 -284.166946) (xy 64.584835 -284.12167)
			(xy 64.573058 -284.073886) (xy 64.569098 -284.024832) (xy 64.23025 -284.024832) (xy 64.229755 -284.049439)
			(xy 64.22186 -284.098016) (xy 64.206276 -284.144697) (xy 64.183405 -284.188274) (xy 64.15384 -284.227618)
			(xy 64.118347 -284.26171) (xy 64.077844 -284.289666) (xy 64.033382 -284.310764) (xy 63.986111 -284.324456)
			(xy 63.937256 -284.330388) (xy 63.888081 -284.328407) (xy 63.839862 -284.318563) (xy 63.793846 -284.301111)
			(xy 63.751225 -284.276504) (xy 63.713104 -284.245379) (xy 63.680469 -284.208542) (xy 63.654166 -284.166946)
			(xy 63.634875 -284.12167) (xy 63.623098 -284.073886) (xy 63.619138 -284.024832) (xy 63.28029 -284.024832)
			(xy 63.279795 -284.049439) (xy 63.2719 -284.098016) (xy 63.256316 -284.144697) (xy 63.233445 -284.188274)
			(xy 63.20388 -284.227618) (xy 63.168387 -284.26171) (xy 63.127884 -284.289666) (xy 63.083422 -284.310764)
			(xy 63.036151 -284.324456) (xy 62.987296 -284.330388) (xy 62.938121 -284.328407) (xy 62.889902 -284.318563)
			(xy 62.843886 -284.301111) (xy 62.801265 -284.276504) (xy 62.763144 -284.245379) (xy 62.730509 -284.208542)
			(xy 62.704206 -284.166946) (xy 62.684915 -284.12167) (xy 62.673138 -284.073886) (xy 62.669178 -284.024832)
			(xy 62.330076 -284.024832) (xy 62.329581 -284.049439) (xy 62.321686 -284.098016) (xy 62.306102 -284.144697)
			(xy 62.283231 -284.188274) (xy 62.253666 -284.227618) (xy 62.218173 -284.26171) (xy 62.17767 -284.289666)
			(xy 62.133208 -284.310764) (xy 62.085937 -284.324456) (xy 62.037082 -284.330388) (xy 61.987907 -284.328407)
			(xy 61.939688 -284.318563) (xy 61.893672 -284.301111) (xy 61.851051 -284.276504) (xy 61.81293 -284.245379)
			(xy 61.780295 -284.208542) (xy 61.753992 -284.166946) (xy 61.734701 -284.12167) (xy 61.722924 -284.073886)
			(xy 61.718964 -284.024832) (xy 61.380116 -284.024832) (xy 61.379621 -284.049439) (xy 61.371726 -284.098016)
			(xy 61.356142 -284.144697) (xy 61.333271 -284.188274) (xy 61.303706 -284.227618) (xy 61.268213 -284.26171)
			(xy 61.22771 -284.289666) (xy 61.183248 -284.310764) (xy 61.135977 -284.324456) (xy 61.087122 -284.330388)
			(xy 61.037947 -284.328407) (xy 60.989728 -284.318563) (xy 60.943712 -284.301111) (xy 60.901091 -284.276504)
			(xy 60.86297 -284.245379) (xy 60.830335 -284.208542) (xy 60.804032 -284.166946) (xy 60.784741 -284.12167)
			(xy 60.772964 -284.073886) (xy 60.769004 -284.024832) (xy 60.430156 -284.024832) (xy 60.429661 -284.049439)
			(xy 60.421766 -284.098016) (xy 60.406182 -284.144697) (xy 60.383311 -284.188274) (xy 60.353746 -284.227618)
			(xy 60.318253 -284.26171) (xy 60.27775 -284.289666) (xy 60.233288 -284.310764) (xy 60.186017 -284.324456)
			(xy 60.137162 -284.330388) (xy 60.087987 -284.328407) (xy 60.039768 -284.318563) (xy 59.993752 -284.301111)
			(xy 59.951131 -284.276504) (xy 59.91301 -284.245379) (xy 59.880375 -284.208542) (xy 59.854072 -284.166946)
			(xy 59.834781 -284.12167) (xy 59.823004 -284.073886) (xy 59.819044 -284.024832) (xy 58.530236 -284.024832)
			(xy 58.529741 -284.049439) (xy 58.521846 -284.098016) (xy 58.506262 -284.144697) (xy 58.483391 -284.188274)
			(xy 58.453826 -284.227618) (xy 58.418333 -284.26171) (xy 58.37783 -284.289666) (xy 58.333368 -284.310764)
			(xy 58.286097 -284.324456) (xy 58.237242 -284.330388) (xy 58.188067 -284.328407) (xy 58.139848 -284.318563)
			(xy 58.093832 -284.301111) (xy 58.051211 -284.276504) (xy 58.01309 -284.245379) (xy 57.980455 -284.208542)
			(xy 57.954152 -284.166946) (xy 57.934861 -284.12167) (xy 57.923084 -284.073886) (xy 57.919124 -284.024832)
			(xy 57.580276 -284.024832) (xy 57.579781 -284.049439) (xy 57.571886 -284.098016) (xy 57.556302 -284.144697)
			(xy 57.533431 -284.188274) (xy 57.503866 -284.227618) (xy 57.468373 -284.26171) (xy 57.42787 -284.289666)
			(xy 57.383408 -284.310764) (xy 57.336137 -284.324456) (xy 57.287282 -284.330388) (xy 57.238107 -284.328407)
			(xy 57.189888 -284.318563) (xy 57.143872 -284.301111) (xy 57.101251 -284.276504) (xy 57.06313 -284.245379)
			(xy 57.030495 -284.208542) (xy 57.004192 -284.166946) (xy 56.984901 -284.12167) (xy 56.973124 -284.073886)
			(xy 56.969164 -284.024832) (xy 56.630062 -284.024832) (xy 56.629567 -284.049439) (xy 56.621672 -284.098016)
			(xy 56.606088 -284.144697) (xy 56.583217 -284.188274) (xy 56.553652 -284.227618) (xy 56.518159 -284.26171)
			(xy 56.477656 -284.289666) (xy 56.433194 -284.310764) (xy 56.385923 -284.324456) (xy 56.337068 -284.330388)
			(xy 56.287893 -284.328407) (xy 56.239674 -284.318563) (xy 56.193658 -284.301111) (xy 56.151037 -284.276504)
			(xy 56.112916 -284.245379) (xy 56.080281 -284.208542) (xy 56.053978 -284.166946) (xy 56.034687 -284.12167)
			(xy 56.02291 -284.073886) (xy 56.01895 -284.024832) (xy 55.680102 -284.024832) (xy 55.679607 -284.049439)
			(xy 55.671712 -284.098016) (xy 55.656128 -284.144697) (xy 55.633257 -284.188274) (xy 55.603692 -284.227618)
			(xy 55.568199 -284.26171) (xy 55.527696 -284.289666) (xy 55.483234 -284.310764) (xy 55.435963 -284.324456)
			(xy 55.387108 -284.330388) (xy 55.337933 -284.328407) (xy 55.289714 -284.318563) (xy 55.243698 -284.301111)
			(xy 55.201077 -284.276504) (xy 55.162956 -284.245379) (xy 55.130321 -284.208542) (xy 55.104018 -284.166946)
			(xy 55.084727 -284.12167) (xy 55.07295 -284.073886) (xy 55.06899 -284.024832) (xy 54.730142 -284.024832)
			(xy 54.729647 -284.049439) (xy 54.721752 -284.098016) (xy 54.706168 -284.144697) (xy 54.683297 -284.188274)
			(xy 54.653732 -284.227618) (xy 54.618239 -284.26171) (xy 54.577736 -284.289666) (xy 54.533274 -284.310764)
			(xy 54.486003 -284.324456) (xy 54.437148 -284.330388) (xy 54.387973 -284.328407) (xy 54.339754 -284.318563)
			(xy 54.293738 -284.301111) (xy 54.251117 -284.276504) (xy 54.212996 -284.245379) (xy 54.180361 -284.208542)
			(xy 54.154058 -284.166946) (xy 54.134767 -284.12167) (xy 54.12299 -284.073886) (xy 54.11903 -284.024832)
			(xy 53.780182 -284.024832) (xy 53.779687 -284.049439) (xy 53.771792 -284.098016) (xy 53.756208 -284.144697)
			(xy 53.733337 -284.188274) (xy 53.703772 -284.227618) (xy 53.668279 -284.26171) (xy 53.627776 -284.289666)
			(xy 53.583314 -284.310764) (xy 53.536043 -284.324456) (xy 53.487188 -284.330388) (xy 53.438013 -284.328407)
			(xy 53.389794 -284.318563) (xy 53.343778 -284.301111) (xy 53.301157 -284.276504) (xy 53.263036 -284.245379)
			(xy 53.230401 -284.208542) (xy 53.204098 -284.166946) (xy 53.184807 -284.12167) (xy 53.17303 -284.073886)
			(xy 53.16907 -284.024832) (xy 52.830222 -284.024832) (xy 52.829727 -284.049439) (xy 52.821832 -284.098016)
			(xy 52.806248 -284.144697) (xy 52.783377 -284.188274) (xy 52.753812 -284.227618) (xy 52.718319 -284.26171)
			(xy 52.677816 -284.289666) (xy 52.633354 -284.310764) (xy 52.586083 -284.324456) (xy 52.537228 -284.330388)
			(xy 52.488053 -284.328407) (xy 52.439834 -284.318563) (xy 52.393818 -284.301111) (xy 52.351197 -284.276504)
			(xy 52.313076 -284.245379) (xy 52.280441 -284.208542) (xy 52.254138 -284.166946) (xy 52.234847 -284.12167)
			(xy 52.22307 -284.073886) (xy 52.21911 -284.024832) (xy 51.880262 -284.024832) (xy 51.879767 -284.049439)
			(xy 51.871872 -284.098016) (xy 51.856288 -284.144697) (xy 51.833417 -284.188274) (xy 51.803852 -284.227618)
			(xy 51.768359 -284.26171) (xy 51.727856 -284.289666) (xy 51.683394 -284.310764) (xy 51.636123 -284.324456)
			(xy 51.587268 -284.330388) (xy 51.538093 -284.328407) (xy 51.489874 -284.318563) (xy 51.443858 -284.301111)
			(xy 51.401237 -284.276504) (xy 51.363116 -284.245379) (xy 51.330481 -284.208542) (xy 51.304178 -284.166946)
			(xy 51.284887 -284.12167) (xy 51.27311 -284.073886) (xy 51.26915 -284.024832) (xy 50.930302 -284.024832)
			(xy 50.929807 -284.049439) (xy 50.921912 -284.098016) (xy 50.906328 -284.144697) (xy 50.883457 -284.188274)
			(xy 50.853892 -284.227618) (xy 50.818399 -284.26171) (xy 50.777896 -284.289666) (xy 50.733434 -284.310764)
			(xy 50.686163 -284.324456) (xy 50.637308 -284.330388) (xy 50.588133 -284.328407) (xy 50.539914 -284.318563)
			(xy 50.493898 -284.301111) (xy 50.451277 -284.276504) (xy 50.413156 -284.245379) (xy 50.380521 -284.208542)
			(xy 50.354218 -284.166946) (xy 50.334927 -284.12167) (xy 50.32315 -284.073886) (xy 50.31919 -284.024832)
			(xy 49.980088 -284.024832) (xy 49.979593 -284.049439) (xy 49.971698 -284.098016) (xy 49.956114 -284.144697)
			(xy 49.933243 -284.188274) (xy 49.903678 -284.227618) (xy 49.868185 -284.26171) (xy 49.827682 -284.289666)
			(xy 49.78322 -284.310764) (xy 49.735949 -284.324456) (xy 49.687094 -284.330388) (xy 49.637919 -284.328407)
			(xy 49.5897 -284.318563) (xy 49.543684 -284.301111) (xy 49.501063 -284.276504) (xy 49.462942 -284.245379)
			(xy 49.430307 -284.208542) (xy 49.404004 -284.166946) (xy 49.384713 -284.12167) (xy 49.372936 -284.073886)
			(xy 49.368976 -284.024832) (xy 49.181004 -284.024832) (xy 49.181004 -284.499812) (xy 73.593972 -284.499812)
			(xy 73.597932 -284.450758) (xy 73.609709 -284.402974) (xy 73.629 -284.357698) (xy 73.655303 -284.316102)
			(xy 73.687938 -284.279265) (xy 73.726059 -284.24814) (xy 73.76868 -284.223533) (xy 73.814696 -284.206081)
			(xy 73.862915 -284.196237) (xy 73.91209 -284.194256) (xy 73.960945 -284.200188) (xy 74.008216 -284.21388)
			(xy 74.052678 -284.234978) (xy 74.093181 -284.262934) (xy 74.128674 -284.297026) (xy 74.158239 -284.33637)
			(xy 74.18111 -284.379947) (xy 74.196694 -284.426628) (xy 74.204589 -284.475205) (xy 74.205084 -284.499812)
			(xy 74.543932 -284.499812) (xy 74.547892 -284.450758) (xy 74.559669 -284.402974) (xy 74.57896 -284.357698)
			(xy 74.605263 -284.316102) (xy 74.637898 -284.279265) (xy 74.676019 -284.24814) (xy 74.71864 -284.223533)
			(xy 74.764656 -284.206081) (xy 74.812875 -284.196237) (xy 74.86205 -284.194256) (xy 74.910905 -284.200188)
			(xy 74.958176 -284.21388) (xy 75.002638 -284.234978) (xy 75.043141 -284.262934) (xy 75.078634 -284.297026)
			(xy 75.108199 -284.33637) (xy 75.13107 -284.379947) (xy 75.146654 -284.426628) (xy 75.154549 -284.475205)
			(xy 75.155044 -284.499812) (xy 75.494146 -284.499812) (xy 75.498106 -284.450758) (xy 75.509883 -284.402974)
			(xy 75.529174 -284.357698) (xy 75.555477 -284.316102) (xy 75.588112 -284.279265) (xy 75.626233 -284.24814)
			(xy 75.668854 -284.223533) (xy 75.71487 -284.206081) (xy 75.763089 -284.196237) (xy 75.812264 -284.194256)
			(xy 75.861119 -284.200188) (xy 75.90839 -284.21388) (xy 75.952852 -284.234978) (xy 75.993355 -284.262934)
			(xy 76.028848 -284.297026) (xy 76.058413 -284.33637) (xy 76.081284 -284.379947) (xy 76.096868 -284.426628)
			(xy 76.104763 -284.475205) (xy 76.105258 -284.499812) (xy 76.104763 -284.524419) (xy 76.104584 -284.52552)
			(xy 76.423262 -284.52552) (xy 76.423262 -284.474104) (xy 76.431305 -284.423322) (xy 76.447193 -284.374423)
			(xy 76.470536 -284.328611) (xy 76.500757 -284.287015) (xy 76.537113 -284.250659) (xy 76.578709 -284.220438)
			(xy 76.624521 -284.197095) (xy 76.67342 -284.181207) (xy 76.724202 -284.173164) (xy 76.775618 -284.173164)
			(xy 76.8264 -284.181207) (xy 76.875299 -284.197095) (xy 76.921111 -284.220438) (xy 76.962707 -284.250659)
			(xy 76.999063 -284.287015) (xy 77.029284 -284.328611) (xy 77.052627 -284.374423) (xy 77.068515 -284.423322)
			(xy 77.076558 -284.474104) (xy 77.077062 -284.499812) (xy 77.076558 -284.52552) (xy 77.373222 -284.52552)
			(xy 77.373222 -284.474104) (xy 77.381265 -284.423322) (xy 77.397153 -284.374423) (xy 77.420496 -284.328611)
			(xy 77.450717 -284.287015) (xy 77.487073 -284.250659) (xy 77.528669 -284.220438) (xy 77.574481 -284.197095)
			(xy 77.62338 -284.181207) (xy 77.674162 -284.173164) (xy 77.725578 -284.173164) (xy 77.77636 -284.181207)
			(xy 77.825259 -284.197095) (xy 77.871071 -284.220438) (xy 77.912667 -284.250659) (xy 77.949023 -284.287015)
			(xy 77.979244 -284.328611) (xy 78.002587 -284.374423) (xy 78.018475 -284.423322) (xy 78.026518 -284.474104)
			(xy 78.027022 -284.499812) (xy 78.344026 -284.499812) (xy 78.347986 -284.450758) (xy 78.359763 -284.402974)
			(xy 78.379054 -284.357698) (xy 78.405357 -284.316102) (xy 78.437992 -284.279265) (xy 78.476113 -284.24814)
			(xy 78.518734 -284.223533) (xy 78.56475 -284.206081) (xy 78.612969 -284.196237) (xy 78.662144 -284.194256)
			(xy 78.710999 -284.200188) (xy 78.75827 -284.21388) (xy 78.802732 -284.234978) (xy 78.843235 -284.262934)
			(xy 78.878728 -284.297026) (xy 78.908293 -284.33637) (xy 78.931164 -284.379947) (xy 78.946748 -284.426628)
			(xy 78.954643 -284.475205) (xy 78.955138 -284.499812) (xy 78.954643 -284.524419) (xy 78.954464 -284.52552)
			(xy 79.273142 -284.52552) (xy 79.273142 -284.474104) (xy 79.281185 -284.423322) (xy 79.297073 -284.374423)
			(xy 79.320416 -284.328611) (xy 79.350637 -284.287015) (xy 79.386993 -284.250659) (xy 79.428589 -284.220438)
			(xy 79.474401 -284.197095) (xy 79.5233 -284.181207) (xy 79.574082 -284.173164) (xy 79.625498 -284.173164)
			(xy 79.67628 -284.181207) (xy 79.725179 -284.197095) (xy 79.770991 -284.220438) (xy 79.812587 -284.250659)
			(xy 79.848943 -284.287015) (xy 79.879164 -284.328611) (xy 79.902507 -284.374423) (xy 79.918395 -284.423322)
			(xy 79.926438 -284.474104) (xy 79.926942 -284.499812) (xy 79.926438 -284.52552) (xy 80.223102 -284.52552)
			(xy 80.223102 -284.474104) (xy 80.231145 -284.423322) (xy 80.247033 -284.374423) (xy 80.270376 -284.328611)
			(xy 80.300597 -284.287015) (xy 80.336953 -284.250659) (xy 80.378549 -284.220438) (xy 80.424361 -284.197095)
			(xy 80.47326 -284.181207) (xy 80.524042 -284.173164) (xy 80.575458 -284.173164) (xy 80.62624 -284.181207)
			(xy 80.675139 -284.197095) (xy 80.720951 -284.220438) (xy 80.762547 -284.250659) (xy 80.798903 -284.287015)
			(xy 80.829124 -284.328611) (xy 80.852467 -284.374423) (xy 80.868355 -284.423322) (xy 80.876398 -284.474104)
			(xy 80.876902 -284.499812) (xy 81.19416 -284.499812) (xy 81.19812 -284.450758) (xy 81.209897 -284.402974)
			(xy 81.229188 -284.357698) (xy 81.255491 -284.316102) (xy 81.288126 -284.279265) (xy 81.326247 -284.24814)
			(xy 81.368868 -284.223533) (xy 81.414884 -284.206081) (xy 81.463103 -284.196237) (xy 81.512278 -284.194256)
			(xy 81.561133 -284.200188) (xy 81.608404 -284.21388) (xy 81.652866 -284.234978) (xy 81.693369 -284.262934)
			(xy 81.728862 -284.297026) (xy 81.758427 -284.33637) (xy 81.781298 -284.379947) (xy 81.796882 -284.426628)
			(xy 81.804777 -284.475205) (xy 81.805272 -284.499812) (xy 82.14412 -284.499812) (xy 82.14808 -284.450758)
			(xy 82.159857 -284.402974) (xy 82.179148 -284.357698) (xy 82.205451 -284.316102) (xy 82.238086 -284.279265)
			(xy 82.276207 -284.24814) (xy 82.318828 -284.223533) (xy 82.364844 -284.206081) (xy 82.413063 -284.196237)
			(xy 82.462238 -284.194256) (xy 82.511093 -284.200188) (xy 82.558364 -284.21388) (xy 82.602826 -284.234978)
			(xy 82.643329 -284.262934) (xy 82.678822 -284.297026) (xy 82.708387 -284.33637) (xy 82.731258 -284.379947)
			(xy 82.746842 -284.426628) (xy 82.754737 -284.475205) (xy 82.755232 -284.499812) (xy 82.754737 -284.524419)
			(xy 82.746842 -284.572996) (xy 82.731258 -284.619677) (xy 82.708387 -284.663254) (xy 82.678822 -284.702598)
			(xy 82.643329 -284.73669) (xy 82.602826 -284.764646) (xy 82.558364 -284.785744) (xy 82.511093 -284.799436)
			(xy 82.462238 -284.805368) (xy 82.413063 -284.803387) (xy 82.364844 -284.793543) (xy 82.318828 -284.776091)
			(xy 82.276207 -284.751484) (xy 82.238086 -284.720359) (xy 82.205451 -284.683522) (xy 82.179148 -284.641926)
			(xy 82.159857 -284.59665) (xy 82.14808 -284.548866) (xy 82.14412 -284.499812) (xy 81.805272 -284.499812)
			(xy 81.804777 -284.524419) (xy 81.796882 -284.572996) (xy 81.781298 -284.619677) (xy 81.758427 -284.663254)
			(xy 81.728862 -284.702598) (xy 81.693369 -284.73669) (xy 81.652866 -284.764646) (xy 81.608404 -284.785744)
			(xy 81.561133 -284.799436) (xy 81.512278 -284.805368) (xy 81.463103 -284.803387) (xy 81.414884 -284.793543)
			(xy 81.368868 -284.776091) (xy 81.326247 -284.751484) (xy 81.288126 -284.720359) (xy 81.255491 -284.683522)
			(xy 81.229188 -284.641926) (xy 81.209897 -284.59665) (xy 81.19812 -284.548866) (xy 81.19416 -284.499812)
			(xy 80.876902 -284.499812) (xy 80.876398 -284.52552) (xy 80.868355 -284.576302) (xy 80.852467 -284.625201)
			(xy 80.829124 -284.671013) (xy 80.798903 -284.712609) (xy 80.762547 -284.748965) (xy 80.720951 -284.779186)
			(xy 80.675139 -284.802529) (xy 80.62624 -284.818417) (xy 80.575458 -284.82646) (xy 80.524042 -284.82646)
			(xy 80.47326 -284.818417) (xy 80.424361 -284.802529) (xy 80.378549 -284.779186) (xy 80.336953 -284.748965)
			(xy 80.300597 -284.712609) (xy 80.270376 -284.671013) (xy 80.247033 -284.625201) (xy 80.231145 -284.576302)
			(xy 80.223102 -284.52552) (xy 79.926438 -284.52552) (xy 79.918395 -284.576302) (xy 79.902507 -284.625201)
			(xy 79.879164 -284.671013) (xy 79.848943 -284.712609) (xy 79.812587 -284.748965) (xy 79.770991 -284.779186)
			(xy 79.725179 -284.802529) (xy 79.67628 -284.818417) (xy 79.625498 -284.82646) (xy 79.574082 -284.82646)
			(xy 79.5233 -284.818417) (xy 79.474401 -284.802529) (xy 79.428589 -284.779186) (xy 79.386993 -284.748965)
			(xy 79.350637 -284.712609) (xy 79.320416 -284.671013) (xy 79.297073 -284.625201) (xy 79.281185 -284.576302)
			(xy 79.273142 -284.52552) (xy 78.954464 -284.52552) (xy 78.946748 -284.572996) (xy 78.931164 -284.619677)
			(xy 78.908293 -284.663254) (xy 78.878728 -284.702598) (xy 78.843235 -284.73669) (xy 78.802732 -284.764646)
			(xy 78.75827 -284.785744) (xy 78.710999 -284.799436) (xy 78.662144 -284.805368) (xy 78.612969 -284.803387)
			(xy 78.56475 -284.793543) (xy 78.518734 -284.776091) (xy 78.476113 -284.751484) (xy 78.437992 -284.720359)
			(xy 78.405357 -284.683522) (xy 78.379054 -284.641926) (xy 78.359763 -284.59665) (xy 78.347986 -284.548866)
			(xy 78.344026 -284.499812) (xy 78.027022 -284.499812) (xy 78.026518 -284.52552) (xy 78.018475 -284.576302)
			(xy 78.002587 -284.625201) (xy 77.979244 -284.671013) (xy 77.949023 -284.712609) (xy 77.912667 -284.748965)
			(xy 77.871071 -284.779186) (xy 77.825259 -284.802529) (xy 77.77636 -284.818417) (xy 77.725578 -284.82646)
			(xy 77.674162 -284.82646) (xy 77.62338 -284.818417) (xy 77.574481 -284.802529) (xy 77.528669 -284.779186)
			(xy 77.487073 -284.748965) (xy 77.450717 -284.712609) (xy 77.420496 -284.671013) (xy 77.397153 -284.625201)
			(xy 77.381265 -284.576302) (xy 77.373222 -284.52552) (xy 77.076558 -284.52552) (xy 77.068515 -284.576302)
			(xy 77.052627 -284.625201) (xy 77.029284 -284.671013) (xy 76.999063 -284.712609) (xy 76.962707 -284.748965)
			(xy 76.921111 -284.779186) (xy 76.875299 -284.802529) (xy 76.8264 -284.818417) (xy 76.775618 -284.82646)
			(xy 76.724202 -284.82646) (xy 76.67342 -284.818417) (xy 76.624521 -284.802529) (xy 76.578709 -284.779186)
			(xy 76.537113 -284.748965) (xy 76.500757 -284.712609) (xy 76.470536 -284.671013) (xy 76.447193 -284.625201)
			(xy 76.431305 -284.576302) (xy 76.423262 -284.52552) (xy 76.104584 -284.52552) (xy 76.096868 -284.572996)
			(xy 76.081284 -284.619677) (xy 76.058413 -284.663254) (xy 76.028848 -284.702598) (xy 75.993355 -284.73669)
			(xy 75.952852 -284.764646) (xy 75.90839 -284.785744) (xy 75.861119 -284.799436) (xy 75.812264 -284.805368)
			(xy 75.763089 -284.803387) (xy 75.71487 -284.793543) (xy 75.668854 -284.776091) (xy 75.626233 -284.751484)
			(xy 75.588112 -284.720359) (xy 75.555477 -284.683522) (xy 75.529174 -284.641926) (xy 75.509883 -284.59665)
			(xy 75.498106 -284.548866) (xy 75.494146 -284.499812) (xy 75.155044 -284.499812) (xy 75.154549 -284.524419)
			(xy 75.146654 -284.572996) (xy 75.13107 -284.619677) (xy 75.108199 -284.663254) (xy 75.078634 -284.702598)
			(xy 75.043141 -284.73669) (xy 75.002638 -284.764646) (xy 74.958176 -284.785744) (xy 74.910905 -284.799436)
			(xy 74.86205 -284.805368) (xy 74.812875 -284.803387) (xy 74.764656 -284.793543) (xy 74.71864 -284.776091)
			(xy 74.676019 -284.751484) (xy 74.637898 -284.720359) (xy 74.605263 -284.683522) (xy 74.57896 -284.641926)
			(xy 74.559669 -284.59665) (xy 74.547892 -284.548866) (xy 74.543932 -284.499812) (xy 74.205084 -284.499812)
			(xy 74.204589 -284.524419) (xy 74.196694 -284.572996) (xy 74.18111 -284.619677) (xy 74.158239 -284.663254)
			(xy 74.128674 -284.702598) (xy 74.093181 -284.73669) (xy 74.052678 -284.764646) (xy 74.008216 -284.785744)
			(xy 73.960945 -284.799436) (xy 73.91209 -284.805368) (xy 73.862915 -284.803387) (xy 73.814696 -284.793543)
			(xy 73.76868 -284.776091) (xy 73.726059 -284.751484) (xy 73.687938 -284.720359) (xy 73.655303 -284.683522)
			(xy 73.629 -284.641926) (xy 73.609709 -284.59665) (xy 73.597932 -284.548866) (xy 73.593972 -284.499812)
			(xy 49.181004 -284.499812) (xy 49.181004 -284.974792) (xy 49.368976 -284.974792) (xy 49.372936 -284.925738)
			(xy 49.384713 -284.877954) (xy 49.404004 -284.832678) (xy 49.430307 -284.791082) (xy 49.462942 -284.754245)
			(xy 49.501063 -284.72312) (xy 49.543684 -284.698513) (xy 49.5897 -284.681061) (xy 49.637919 -284.671217)
			(xy 49.687094 -284.669236) (xy 49.735949 -284.675168) (xy 49.78322 -284.68886) (xy 49.827682 -284.709958)
			(xy 49.868185 -284.737914) (xy 49.903678 -284.772006) (xy 49.933243 -284.81135) (xy 49.956114 -284.854927)
			(xy 49.971698 -284.901608) (xy 49.979593 -284.950185) (xy 49.980088 -284.974792) (xy 50.31919 -284.974792)
			(xy 50.32315 -284.925738) (xy 50.334927 -284.877954) (xy 50.354218 -284.832678) (xy 50.380521 -284.791082)
			(xy 50.413156 -284.754245) (xy 50.451277 -284.72312) (xy 50.493898 -284.698513) (xy 50.539914 -284.681061)
			(xy 50.588133 -284.671217) (xy 50.637308 -284.669236) (xy 50.686163 -284.675168) (xy 50.733434 -284.68886)
			(xy 50.777896 -284.709958) (xy 50.818399 -284.737914) (xy 50.853892 -284.772006) (xy 50.883457 -284.81135)
			(xy 50.906328 -284.854927) (xy 50.921912 -284.901608) (xy 50.929807 -284.950185) (xy 50.930302 -284.974792)
			(xy 51.26915 -284.974792) (xy 51.27311 -284.925738) (xy 51.284887 -284.877954) (xy 51.304178 -284.832678)
			(xy 51.330481 -284.791082) (xy 51.363116 -284.754245) (xy 51.401237 -284.72312) (xy 51.443858 -284.698513)
			(xy 51.489874 -284.681061) (xy 51.538093 -284.671217) (xy 51.587268 -284.669236) (xy 51.636123 -284.675168)
			(xy 51.683394 -284.68886) (xy 51.727856 -284.709958) (xy 51.768359 -284.737914) (xy 51.803852 -284.772006)
			(xy 51.833417 -284.81135) (xy 51.856288 -284.854927) (xy 51.871872 -284.901608) (xy 51.879767 -284.950185)
			(xy 51.880262 -284.974792) (xy 52.21911 -284.974792) (xy 52.22307 -284.925738) (xy 52.234847 -284.877954)
			(xy 52.254138 -284.832678) (xy 52.280441 -284.791082) (xy 52.313076 -284.754245) (xy 52.351197 -284.72312)
			(xy 52.393818 -284.698513) (xy 52.439834 -284.681061) (xy 52.488053 -284.671217) (xy 52.537228 -284.669236)
			(xy 52.586083 -284.675168) (xy 52.633354 -284.68886) (xy 52.677816 -284.709958) (xy 52.718319 -284.737914)
			(xy 52.753812 -284.772006) (xy 52.783377 -284.81135) (xy 52.806248 -284.854927) (xy 52.821832 -284.901608)
			(xy 52.829727 -284.950185) (xy 52.830222 -284.974792) (xy 53.16907 -284.974792) (xy 53.17303 -284.925738)
			(xy 53.184807 -284.877954) (xy 53.204098 -284.832678) (xy 53.230401 -284.791082) (xy 53.263036 -284.754245)
			(xy 53.301157 -284.72312) (xy 53.343778 -284.698513) (xy 53.389794 -284.681061) (xy 53.438013 -284.671217)
			(xy 53.487188 -284.669236) (xy 53.536043 -284.675168) (xy 53.583314 -284.68886) (xy 53.627776 -284.709958)
			(xy 53.668279 -284.737914) (xy 53.703772 -284.772006) (xy 53.733337 -284.81135) (xy 53.756208 -284.854927)
			(xy 53.771792 -284.901608) (xy 53.779687 -284.950185) (xy 53.780182 -284.974792) (xy 54.11903 -284.974792)
			(xy 54.12299 -284.925738) (xy 54.134767 -284.877954) (xy 54.154058 -284.832678) (xy 54.180361 -284.791082)
			(xy 54.212996 -284.754245) (xy 54.251117 -284.72312) (xy 54.293738 -284.698513) (xy 54.339754 -284.681061)
			(xy 54.387973 -284.671217) (xy 54.437148 -284.669236) (xy 54.486003 -284.675168) (xy 54.533274 -284.68886)
			(xy 54.577736 -284.709958) (xy 54.618239 -284.737914) (xy 54.653732 -284.772006) (xy 54.683297 -284.81135)
			(xy 54.706168 -284.854927) (xy 54.721752 -284.901608) (xy 54.729647 -284.950185) (xy 54.730142 -284.974792)
			(xy 55.06899 -284.974792) (xy 55.07295 -284.925738) (xy 55.084727 -284.877954) (xy 55.104018 -284.832678)
			(xy 55.130321 -284.791082) (xy 55.162956 -284.754245) (xy 55.201077 -284.72312) (xy 55.243698 -284.698513)
			(xy 55.289714 -284.681061) (xy 55.337933 -284.671217) (xy 55.387108 -284.669236) (xy 55.435963 -284.675168)
			(xy 55.483234 -284.68886) (xy 55.527696 -284.709958) (xy 55.568199 -284.737914) (xy 55.603692 -284.772006)
			(xy 55.633257 -284.81135) (xy 55.656128 -284.854927) (xy 55.671712 -284.901608) (xy 55.679607 -284.950185)
			(xy 55.680102 -284.974792) (xy 56.01895 -284.974792) (xy 56.02291 -284.925738) (xy 56.034687 -284.877954)
			(xy 56.053978 -284.832678) (xy 56.080281 -284.791082) (xy 56.112916 -284.754245) (xy 56.151037 -284.72312)
			(xy 56.193658 -284.698513) (xy 56.239674 -284.681061) (xy 56.287893 -284.671217) (xy 56.337068 -284.669236)
			(xy 56.385923 -284.675168) (xy 56.433194 -284.68886) (xy 56.477656 -284.709958) (xy 56.518159 -284.737914)
			(xy 56.553652 -284.772006) (xy 56.583217 -284.81135) (xy 56.606088 -284.854927) (xy 56.621672 -284.901608)
			(xy 56.629567 -284.950185) (xy 56.630062 -284.974792) (xy 56.969164 -284.974792) (xy 56.973124 -284.925738)
			(xy 56.984901 -284.877954) (xy 57.004192 -284.832678) (xy 57.030495 -284.791082) (xy 57.06313 -284.754245)
			(xy 57.101251 -284.72312) (xy 57.143872 -284.698513) (xy 57.189888 -284.681061) (xy 57.238107 -284.671217)
			(xy 57.287282 -284.669236) (xy 57.336137 -284.675168) (xy 57.383408 -284.68886) (xy 57.42787 -284.709958)
			(xy 57.468373 -284.737914) (xy 57.503866 -284.772006) (xy 57.533431 -284.81135) (xy 57.556302 -284.854927)
			(xy 57.571886 -284.901608) (xy 57.579781 -284.950185) (xy 57.580276 -284.974792) (xy 57.919124 -284.974792)
			(xy 57.923084 -284.925738) (xy 57.934861 -284.877954) (xy 57.954152 -284.832678) (xy 57.980455 -284.791082)
			(xy 58.01309 -284.754245) (xy 58.051211 -284.72312) (xy 58.093832 -284.698513) (xy 58.139848 -284.681061)
			(xy 58.188067 -284.671217) (xy 58.237242 -284.669236) (xy 58.286097 -284.675168) (xy 58.333368 -284.68886)
			(xy 58.37783 -284.709958) (xy 58.418333 -284.737914) (xy 58.453826 -284.772006) (xy 58.483391 -284.81135)
			(xy 58.506262 -284.854927) (xy 58.521846 -284.901608) (xy 58.529741 -284.950185) (xy 58.530236 -284.974792)
			(xy 59.819044 -284.974792) (xy 59.823004 -284.925738) (xy 59.834781 -284.877954) (xy 59.854072 -284.832678)
			(xy 59.880375 -284.791082) (xy 59.91301 -284.754245) (xy 59.951131 -284.72312) (xy 59.993752 -284.698513)
			(xy 60.039768 -284.681061) (xy 60.087987 -284.671217) (xy 60.137162 -284.669236) (xy 60.186017 -284.675168)
			(xy 60.233288 -284.68886) (xy 60.27775 -284.709958) (xy 60.318253 -284.737914) (xy 60.353746 -284.772006)
			(xy 60.383311 -284.81135) (xy 60.406182 -284.854927) (xy 60.421766 -284.901608) (xy 60.429661 -284.950185)
			(xy 60.430156 -284.974792) (xy 60.769004 -284.974792) (xy 60.772964 -284.925738) (xy 60.784741 -284.877954)
			(xy 60.804032 -284.832678) (xy 60.830335 -284.791082) (xy 60.86297 -284.754245) (xy 60.901091 -284.72312)
			(xy 60.943712 -284.698513) (xy 60.989728 -284.681061) (xy 61.037947 -284.671217) (xy 61.087122 -284.669236)
			(xy 61.135977 -284.675168) (xy 61.183248 -284.68886) (xy 61.22771 -284.709958) (xy 61.268213 -284.737914)
			(xy 61.303706 -284.772006) (xy 61.333271 -284.81135) (xy 61.356142 -284.854927) (xy 61.371726 -284.901608)
			(xy 61.379621 -284.950185) (xy 61.380116 -284.974792) (xy 61.718964 -284.974792) (xy 61.722924 -284.925738)
			(xy 61.734701 -284.877954) (xy 61.753992 -284.832678) (xy 61.780295 -284.791082) (xy 61.81293 -284.754245)
			(xy 61.851051 -284.72312) (xy 61.893672 -284.698513) (xy 61.939688 -284.681061) (xy 61.987907 -284.671217)
			(xy 62.037082 -284.669236) (xy 62.085937 -284.675168) (xy 62.133208 -284.68886) (xy 62.17767 -284.709958)
			(xy 62.218173 -284.737914) (xy 62.253666 -284.772006) (xy 62.283231 -284.81135) (xy 62.306102 -284.854927)
			(xy 62.321686 -284.901608) (xy 62.329581 -284.950185) (xy 62.330076 -284.974792) (xy 62.669178 -284.974792)
			(xy 62.673138 -284.925738) (xy 62.684915 -284.877954) (xy 62.704206 -284.832678) (xy 62.730509 -284.791082)
			(xy 62.763144 -284.754245) (xy 62.801265 -284.72312) (xy 62.843886 -284.698513) (xy 62.889902 -284.681061)
			(xy 62.938121 -284.671217) (xy 62.987296 -284.669236) (xy 63.036151 -284.675168) (xy 63.083422 -284.68886)
			(xy 63.127884 -284.709958) (xy 63.168387 -284.737914) (xy 63.20388 -284.772006) (xy 63.233445 -284.81135)
			(xy 63.256316 -284.854927) (xy 63.2719 -284.901608) (xy 63.279795 -284.950185) (xy 63.28029 -284.974792)
			(xy 63.619138 -284.974792) (xy 63.623098 -284.925738) (xy 63.634875 -284.877954) (xy 63.654166 -284.832678)
			(xy 63.680469 -284.791082) (xy 63.713104 -284.754245) (xy 63.751225 -284.72312) (xy 63.793846 -284.698513)
			(xy 63.839862 -284.681061) (xy 63.888081 -284.671217) (xy 63.937256 -284.669236) (xy 63.986111 -284.675168)
			(xy 64.033382 -284.68886) (xy 64.077844 -284.709958) (xy 64.118347 -284.737914) (xy 64.15384 -284.772006)
			(xy 64.183405 -284.81135) (xy 64.206276 -284.854927) (xy 64.22186 -284.901608) (xy 64.229755 -284.950185)
			(xy 64.23025 -284.974792) (xy 64.569098 -284.974792) (xy 64.573058 -284.925738) (xy 64.584835 -284.877954)
			(xy 64.604126 -284.832678) (xy 64.630429 -284.791082) (xy 64.663064 -284.754245) (xy 64.701185 -284.72312)
			(xy 64.743806 -284.698513) (xy 64.789822 -284.681061) (xy 64.838041 -284.671217) (xy 64.887216 -284.669236)
			(xy 64.936071 -284.675168) (xy 64.983342 -284.68886) (xy 65.027804 -284.709958) (xy 65.068307 -284.737914)
			(xy 65.1038 -284.772006) (xy 65.133365 -284.81135) (xy 65.156236 -284.854927) (xy 65.17182 -284.901608)
			(xy 65.179715 -284.950185) (xy 65.18021 -284.974792) (xy 65.519058 -284.974792) (xy 65.523018 -284.925738)
			(xy 65.534795 -284.877954) (xy 65.554086 -284.832678) (xy 65.580389 -284.791082) (xy 65.613024 -284.754245)
			(xy 65.651145 -284.72312) (xy 65.693766 -284.698513) (xy 65.739782 -284.681061) (xy 65.788001 -284.671217)
			(xy 65.837176 -284.669236) (xy 65.886031 -284.675168) (xy 65.933302 -284.68886) (xy 65.977764 -284.709958)
			(xy 66.018267 -284.737914) (xy 66.05376 -284.772006) (xy 66.083325 -284.81135) (xy 66.106196 -284.854927)
			(xy 66.12178 -284.901608) (xy 66.129675 -284.950185) (xy 66.13017 -284.974792) (xy 66.469018 -284.974792)
			(xy 66.472978 -284.925738) (xy 66.484755 -284.877954) (xy 66.504046 -284.832678) (xy 66.530349 -284.791082)
			(xy 66.562984 -284.754245) (xy 66.601105 -284.72312) (xy 66.643726 -284.698513) (xy 66.689742 -284.681061)
			(xy 66.737961 -284.671217) (xy 66.787136 -284.669236) (xy 66.835991 -284.675168) (xy 66.883262 -284.68886)
			(xy 66.927724 -284.709958) (xy 66.968227 -284.737914) (xy 67.00372 -284.772006) (xy 67.033285 -284.81135)
			(xy 67.056156 -284.854927) (xy 67.07174 -284.901608) (xy 67.079635 -284.950185) (xy 67.08013 -284.974792)
			(xy 67.418978 -284.974792) (xy 67.422938 -284.925738) (xy 67.434715 -284.877954) (xy 67.454006 -284.832678)
			(xy 67.480309 -284.791082) (xy 67.512944 -284.754245) (xy 67.551065 -284.72312) (xy 67.593686 -284.698513)
			(xy 67.639702 -284.681061) (xy 67.687921 -284.671217) (xy 67.737096 -284.669236) (xy 67.785951 -284.675168)
			(xy 67.833222 -284.68886) (xy 67.877684 -284.709958) (xy 67.918187 -284.737914) (xy 67.95368 -284.772006)
			(xy 67.983245 -284.81135) (xy 68.006116 -284.854927) (xy 68.0217 -284.901608) (xy 68.029595 -284.950185)
			(xy 68.03009 -284.974792) (xy 68.368938 -284.974792) (xy 68.372898 -284.925738) (xy 68.384675 -284.877954)
			(xy 68.403966 -284.832678) (xy 68.430269 -284.791082) (xy 68.462904 -284.754245) (xy 68.501025 -284.72312)
			(xy 68.543646 -284.698513) (xy 68.589662 -284.681061) (xy 68.637881 -284.671217) (xy 68.687056 -284.669236)
			(xy 68.735911 -284.675168) (xy 68.783182 -284.68886) (xy 68.827644 -284.709958) (xy 68.868147 -284.737914)
			(xy 68.90364 -284.772006) (xy 68.933205 -284.81135) (xy 68.956076 -284.854927) (xy 68.97166 -284.901608)
			(xy 68.979555 -284.950185) (xy 68.98005 -284.974792) (xy 69.319152 -284.974792) (xy 69.323112 -284.925738)
			(xy 69.334889 -284.877954) (xy 69.35418 -284.832678) (xy 69.380483 -284.791082) (xy 69.413118 -284.754245)
			(xy 69.451239 -284.72312) (xy 69.49386 -284.698513) (xy 69.539876 -284.681061) (xy 69.588095 -284.671217)
			(xy 69.63727 -284.669236) (xy 69.686125 -284.675168) (xy 69.733396 -284.68886) (xy 69.777858 -284.709958)
			(xy 69.818361 -284.737914) (xy 69.853854 -284.772006) (xy 69.883419 -284.81135) (xy 69.90629 -284.854927)
			(xy 69.921874 -284.901608) (xy 69.929769 -284.950185) (xy 69.930264 -284.974792) (xy 70.269112 -284.974792)
			(xy 70.273072 -284.925738) (xy 70.284849 -284.877954) (xy 70.30414 -284.832678) (xy 70.330443 -284.791082)
			(xy 70.363078 -284.754245) (xy 70.401199 -284.72312) (xy 70.44382 -284.698513) (xy 70.489836 -284.681061)
			(xy 70.538055 -284.671217) (xy 70.58723 -284.669236) (xy 70.636085 -284.675168) (xy 70.683356 -284.68886)
			(xy 70.727818 -284.709958) (xy 70.768321 -284.737914) (xy 70.803814 -284.772006) (xy 70.833379 -284.81135)
			(xy 70.85625 -284.854927) (xy 70.871834 -284.901608) (xy 70.879729 -284.950185) (xy 70.880224 -284.974792)
			(xy 70.879729 -284.999399) (xy 70.871834 -285.047976) (xy 70.85625 -285.094657) (xy 70.833379 -285.138234)
			(xy 70.803814 -285.177578) (xy 70.768321 -285.21167) (xy 70.727818 -285.239626) (xy 70.683356 -285.260724)
			(xy 70.636085 -285.274416) (xy 70.58723 -285.280348) (xy 70.538055 -285.278367) (xy 70.489836 -285.268523)
			(xy 70.44382 -285.251071) (xy 70.401199 -285.226464) (xy 70.363078 -285.195339) (xy 70.330443 -285.158502)
			(xy 70.30414 -285.116906) (xy 70.284849 -285.07163) (xy 70.273072 -285.023846) (xy 70.269112 -284.974792)
			(xy 69.930264 -284.974792) (xy 69.929769 -284.999399) (xy 69.921874 -285.047976) (xy 69.90629 -285.094657)
			(xy 69.883419 -285.138234) (xy 69.853854 -285.177578) (xy 69.818361 -285.21167) (xy 69.777858 -285.239626)
			(xy 69.733396 -285.260724) (xy 69.686125 -285.274416) (xy 69.63727 -285.280348) (xy 69.588095 -285.278367)
			(xy 69.539876 -285.268523) (xy 69.49386 -285.251071) (xy 69.451239 -285.226464) (xy 69.413118 -285.195339)
			(xy 69.380483 -285.158502) (xy 69.35418 -285.116906) (xy 69.334889 -285.07163) (xy 69.323112 -285.023846)
			(xy 69.319152 -284.974792) (xy 68.98005 -284.974792) (xy 68.979555 -284.999399) (xy 68.97166 -285.047976)
			(xy 68.956076 -285.094657) (xy 68.933205 -285.138234) (xy 68.90364 -285.177578) (xy 68.868147 -285.21167)
			(xy 68.827644 -285.239626) (xy 68.783182 -285.260724) (xy 68.735911 -285.274416) (xy 68.687056 -285.280348)
			(xy 68.637881 -285.278367) (xy 68.589662 -285.268523) (xy 68.543646 -285.251071) (xy 68.501025 -285.226464)
			(xy 68.462904 -285.195339) (xy 68.430269 -285.158502) (xy 68.403966 -285.116906) (xy 68.384675 -285.07163)
			(xy 68.372898 -285.023846) (xy 68.368938 -284.974792) (xy 68.03009 -284.974792) (xy 68.029595 -284.999399)
			(xy 68.0217 -285.047976) (xy 68.006116 -285.094657) (xy 67.983245 -285.138234) (xy 67.95368 -285.177578)
			(xy 67.918187 -285.21167) (xy 67.877684 -285.239626) (xy 67.833222 -285.260724) (xy 67.785951 -285.274416)
			(xy 67.737096 -285.280348) (xy 67.687921 -285.278367) (xy 67.639702 -285.268523) (xy 67.593686 -285.251071)
			(xy 67.551065 -285.226464) (xy 67.512944 -285.195339) (xy 67.480309 -285.158502) (xy 67.454006 -285.116906)
			(xy 67.434715 -285.07163) (xy 67.422938 -285.023846) (xy 67.418978 -284.974792) (xy 67.08013 -284.974792)
			(xy 67.079635 -284.999399) (xy 67.07174 -285.047976) (xy 67.056156 -285.094657) (xy 67.033285 -285.138234)
			(xy 67.00372 -285.177578) (xy 66.968227 -285.21167) (xy 66.927724 -285.239626) (xy 66.883262 -285.260724)
			(xy 66.835991 -285.274416) (xy 66.787136 -285.280348) (xy 66.737961 -285.278367) (xy 66.689742 -285.268523)
			(xy 66.643726 -285.251071) (xy 66.601105 -285.226464) (xy 66.562984 -285.195339) (xy 66.530349 -285.158502)
			(xy 66.504046 -285.116906) (xy 66.484755 -285.07163) (xy 66.472978 -285.023846) (xy 66.469018 -284.974792)
			(xy 66.13017 -284.974792) (xy 66.129675 -284.999399) (xy 66.12178 -285.047976) (xy 66.106196 -285.094657)
			(xy 66.083325 -285.138234) (xy 66.05376 -285.177578) (xy 66.018267 -285.21167) (xy 65.977764 -285.239626)
			(xy 65.933302 -285.260724) (xy 65.886031 -285.274416) (xy 65.837176 -285.280348) (xy 65.788001 -285.278367)
			(xy 65.739782 -285.268523) (xy 65.693766 -285.251071) (xy 65.651145 -285.226464) (xy 65.613024 -285.195339)
			(xy 65.580389 -285.158502) (xy 65.554086 -285.116906) (xy 65.534795 -285.07163) (xy 65.523018 -285.023846)
			(xy 65.519058 -284.974792) (xy 65.18021 -284.974792) (xy 65.179715 -284.999399) (xy 65.17182 -285.047976)
			(xy 65.156236 -285.094657) (xy 65.133365 -285.138234) (xy 65.1038 -285.177578) (xy 65.068307 -285.21167)
			(xy 65.027804 -285.239626) (xy 64.983342 -285.260724) (xy 64.936071 -285.274416) (xy 64.887216 -285.280348)
			(xy 64.838041 -285.278367) (xy 64.789822 -285.268523) (xy 64.743806 -285.251071) (xy 64.701185 -285.226464)
			(xy 64.663064 -285.195339) (xy 64.630429 -285.158502) (xy 64.604126 -285.116906) (xy 64.584835 -285.07163)
			(xy 64.573058 -285.023846) (xy 64.569098 -284.974792) (xy 64.23025 -284.974792) (xy 64.229755 -284.999399)
			(xy 64.22186 -285.047976) (xy 64.206276 -285.094657) (xy 64.183405 -285.138234) (xy 64.15384 -285.177578)
			(xy 64.118347 -285.21167) (xy 64.077844 -285.239626) (xy 64.033382 -285.260724) (xy 63.986111 -285.274416)
			(xy 63.937256 -285.280348) (xy 63.888081 -285.278367) (xy 63.839862 -285.268523) (xy 63.793846 -285.251071)
			(xy 63.751225 -285.226464) (xy 63.713104 -285.195339) (xy 63.680469 -285.158502) (xy 63.654166 -285.116906)
			(xy 63.634875 -285.07163) (xy 63.623098 -285.023846) (xy 63.619138 -284.974792) (xy 63.28029 -284.974792)
			(xy 63.279795 -284.999399) (xy 63.2719 -285.047976) (xy 63.256316 -285.094657) (xy 63.233445 -285.138234)
			(xy 63.20388 -285.177578) (xy 63.168387 -285.21167) (xy 63.127884 -285.239626) (xy 63.083422 -285.260724)
			(xy 63.036151 -285.274416) (xy 62.987296 -285.280348) (xy 62.938121 -285.278367) (xy 62.889902 -285.268523)
			(xy 62.843886 -285.251071) (xy 62.801265 -285.226464) (xy 62.763144 -285.195339) (xy 62.730509 -285.158502)
			(xy 62.704206 -285.116906) (xy 62.684915 -285.07163) (xy 62.673138 -285.023846) (xy 62.669178 -284.974792)
			(xy 62.330076 -284.974792) (xy 62.329581 -284.999399) (xy 62.321686 -285.047976) (xy 62.306102 -285.094657)
			(xy 62.283231 -285.138234) (xy 62.253666 -285.177578) (xy 62.218173 -285.21167) (xy 62.17767 -285.239626)
			(xy 62.133208 -285.260724) (xy 62.085937 -285.274416) (xy 62.037082 -285.280348) (xy 61.987907 -285.278367)
			(xy 61.939688 -285.268523) (xy 61.893672 -285.251071) (xy 61.851051 -285.226464) (xy 61.81293 -285.195339)
			(xy 61.780295 -285.158502) (xy 61.753992 -285.116906) (xy 61.734701 -285.07163) (xy 61.722924 -285.023846)
			(xy 61.718964 -284.974792) (xy 61.380116 -284.974792) (xy 61.379621 -284.999399) (xy 61.371726 -285.047976)
			(xy 61.356142 -285.094657) (xy 61.333271 -285.138234) (xy 61.303706 -285.177578) (xy 61.268213 -285.21167)
			(xy 61.22771 -285.239626) (xy 61.183248 -285.260724) (xy 61.135977 -285.274416) (xy 61.087122 -285.280348)
			(xy 61.037947 -285.278367) (xy 60.989728 -285.268523) (xy 60.943712 -285.251071) (xy 60.901091 -285.226464)
			(xy 60.86297 -285.195339) (xy 60.830335 -285.158502) (xy 60.804032 -285.116906) (xy 60.784741 -285.07163)
			(xy 60.772964 -285.023846) (xy 60.769004 -284.974792) (xy 60.430156 -284.974792) (xy 60.429661 -284.999399)
			(xy 60.421766 -285.047976) (xy 60.406182 -285.094657) (xy 60.383311 -285.138234) (xy 60.353746 -285.177578)
			(xy 60.318253 -285.21167) (xy 60.27775 -285.239626) (xy 60.233288 -285.260724) (xy 60.186017 -285.274416)
			(xy 60.137162 -285.280348) (xy 60.087987 -285.278367) (xy 60.039768 -285.268523) (xy 59.993752 -285.251071)
			(xy 59.951131 -285.226464) (xy 59.91301 -285.195339) (xy 59.880375 -285.158502) (xy 59.854072 -285.116906)
			(xy 59.834781 -285.07163) (xy 59.823004 -285.023846) (xy 59.819044 -284.974792) (xy 58.530236 -284.974792)
			(xy 58.529741 -284.999399) (xy 58.521846 -285.047976) (xy 58.506262 -285.094657) (xy 58.483391 -285.138234)
			(xy 58.453826 -285.177578) (xy 58.418333 -285.21167) (xy 58.37783 -285.239626) (xy 58.333368 -285.260724)
			(xy 58.286097 -285.274416) (xy 58.237242 -285.280348) (xy 58.188067 -285.278367) (xy 58.139848 -285.268523)
			(xy 58.093832 -285.251071) (xy 58.051211 -285.226464) (xy 58.01309 -285.195339) (xy 57.980455 -285.158502)
			(xy 57.954152 -285.116906) (xy 57.934861 -285.07163) (xy 57.923084 -285.023846) (xy 57.919124 -284.974792)
			(xy 57.580276 -284.974792) (xy 57.579781 -284.999399) (xy 57.571886 -285.047976) (xy 57.556302 -285.094657)
			(xy 57.533431 -285.138234) (xy 57.503866 -285.177578) (xy 57.468373 -285.21167) (xy 57.42787 -285.239626)
			(xy 57.383408 -285.260724) (xy 57.336137 -285.274416) (xy 57.287282 -285.280348) (xy 57.238107 -285.278367)
			(xy 57.189888 -285.268523) (xy 57.143872 -285.251071) (xy 57.101251 -285.226464) (xy 57.06313 -285.195339)
			(xy 57.030495 -285.158502) (xy 57.004192 -285.116906) (xy 56.984901 -285.07163) (xy 56.973124 -285.023846)
			(xy 56.969164 -284.974792) (xy 56.630062 -284.974792) (xy 56.629567 -284.999399) (xy 56.621672 -285.047976)
			(xy 56.606088 -285.094657) (xy 56.583217 -285.138234) (xy 56.553652 -285.177578) (xy 56.518159 -285.21167)
			(xy 56.477656 -285.239626) (xy 56.433194 -285.260724) (xy 56.385923 -285.274416) (xy 56.337068 -285.280348)
			(xy 56.287893 -285.278367) (xy 56.239674 -285.268523) (xy 56.193658 -285.251071) (xy 56.151037 -285.226464)
			(xy 56.112916 -285.195339) (xy 56.080281 -285.158502) (xy 56.053978 -285.116906) (xy 56.034687 -285.07163)
			(xy 56.02291 -285.023846) (xy 56.01895 -284.974792) (xy 55.680102 -284.974792) (xy 55.679607 -284.999399)
			(xy 55.671712 -285.047976) (xy 55.656128 -285.094657) (xy 55.633257 -285.138234) (xy 55.603692 -285.177578)
			(xy 55.568199 -285.21167) (xy 55.527696 -285.239626) (xy 55.483234 -285.260724) (xy 55.435963 -285.274416)
			(xy 55.387108 -285.280348) (xy 55.337933 -285.278367) (xy 55.289714 -285.268523) (xy 55.243698 -285.251071)
			(xy 55.201077 -285.226464) (xy 55.162956 -285.195339) (xy 55.130321 -285.158502) (xy 55.104018 -285.116906)
			(xy 55.084727 -285.07163) (xy 55.07295 -285.023846) (xy 55.06899 -284.974792) (xy 54.730142 -284.974792)
			(xy 54.729647 -284.999399) (xy 54.721752 -285.047976) (xy 54.706168 -285.094657) (xy 54.683297 -285.138234)
			(xy 54.653732 -285.177578) (xy 54.618239 -285.21167) (xy 54.577736 -285.239626) (xy 54.533274 -285.260724)
			(xy 54.486003 -285.274416) (xy 54.437148 -285.280348) (xy 54.387973 -285.278367) (xy 54.339754 -285.268523)
			(xy 54.293738 -285.251071) (xy 54.251117 -285.226464) (xy 54.212996 -285.195339) (xy 54.180361 -285.158502)
			(xy 54.154058 -285.116906) (xy 54.134767 -285.07163) (xy 54.12299 -285.023846) (xy 54.11903 -284.974792)
			(xy 53.780182 -284.974792) (xy 53.779687 -284.999399) (xy 53.771792 -285.047976) (xy 53.756208 -285.094657)
			(xy 53.733337 -285.138234) (xy 53.703772 -285.177578) (xy 53.668279 -285.21167) (xy 53.627776 -285.239626)
			(xy 53.583314 -285.260724) (xy 53.536043 -285.274416) (xy 53.487188 -285.280348) (xy 53.438013 -285.278367)
			(xy 53.389794 -285.268523) (xy 53.343778 -285.251071) (xy 53.301157 -285.226464) (xy 53.263036 -285.195339)
			(xy 53.230401 -285.158502) (xy 53.204098 -285.116906) (xy 53.184807 -285.07163) (xy 53.17303 -285.023846)
			(xy 53.16907 -284.974792) (xy 52.830222 -284.974792) (xy 52.829727 -284.999399) (xy 52.821832 -285.047976)
			(xy 52.806248 -285.094657) (xy 52.783377 -285.138234) (xy 52.753812 -285.177578) (xy 52.718319 -285.21167)
			(xy 52.677816 -285.239626) (xy 52.633354 -285.260724) (xy 52.586083 -285.274416) (xy 52.537228 -285.280348)
			(xy 52.488053 -285.278367) (xy 52.439834 -285.268523) (xy 52.393818 -285.251071) (xy 52.351197 -285.226464)
			(xy 52.313076 -285.195339) (xy 52.280441 -285.158502) (xy 52.254138 -285.116906) (xy 52.234847 -285.07163)
			(xy 52.22307 -285.023846) (xy 52.21911 -284.974792) (xy 51.880262 -284.974792) (xy 51.879767 -284.999399)
			(xy 51.871872 -285.047976) (xy 51.856288 -285.094657) (xy 51.833417 -285.138234) (xy 51.803852 -285.177578)
			(xy 51.768359 -285.21167) (xy 51.727856 -285.239626) (xy 51.683394 -285.260724) (xy 51.636123 -285.274416)
			(xy 51.587268 -285.280348) (xy 51.538093 -285.278367) (xy 51.489874 -285.268523) (xy 51.443858 -285.251071)
			(xy 51.401237 -285.226464) (xy 51.363116 -285.195339) (xy 51.330481 -285.158502) (xy 51.304178 -285.116906)
			(xy 51.284887 -285.07163) (xy 51.27311 -285.023846) (xy 51.26915 -284.974792) (xy 50.930302 -284.974792)
			(xy 50.929807 -284.999399) (xy 50.921912 -285.047976) (xy 50.906328 -285.094657) (xy 50.883457 -285.138234)
			(xy 50.853892 -285.177578) (xy 50.818399 -285.21167) (xy 50.777896 -285.239626) (xy 50.733434 -285.260724)
			(xy 50.686163 -285.274416) (xy 50.637308 -285.280348) (xy 50.588133 -285.278367) (xy 50.539914 -285.268523)
			(xy 50.493898 -285.251071) (xy 50.451277 -285.226464) (xy 50.413156 -285.195339) (xy 50.380521 -285.158502)
			(xy 50.354218 -285.116906) (xy 50.334927 -285.07163) (xy 50.32315 -285.023846) (xy 50.31919 -284.974792)
			(xy 49.980088 -284.974792) (xy 49.979593 -284.999399) (xy 49.971698 -285.047976) (xy 49.956114 -285.094657)
			(xy 49.933243 -285.138234) (xy 49.903678 -285.177578) (xy 49.868185 -285.21167) (xy 49.827682 -285.239626)
			(xy 49.78322 -285.260724) (xy 49.735949 -285.274416) (xy 49.687094 -285.280348) (xy 49.637919 -285.278367)
			(xy 49.5897 -285.268523) (xy 49.543684 -285.251071) (xy 49.501063 -285.226464) (xy 49.462942 -285.195339)
			(xy 49.430307 -285.158502) (xy 49.404004 -285.116906) (xy 49.384713 -285.07163) (xy 49.372936 -285.023846)
			(xy 49.368976 -284.974792) (xy 49.181004 -284.974792) (xy 49.181004 -285.449772) (xy 73.593972 -285.449772)
			(xy 73.597932 -285.400718) (xy 73.609709 -285.352934) (xy 73.629 -285.307658) (xy 73.655303 -285.266062)
			(xy 73.687938 -285.229225) (xy 73.726059 -285.1981) (xy 73.76868 -285.173493) (xy 73.814696 -285.156041)
			(xy 73.862915 -285.146197) (xy 73.91209 -285.144216) (xy 73.960945 -285.150148) (xy 74.008216 -285.16384)
			(xy 74.052678 -285.184938) (xy 74.093181 -285.212894) (xy 74.128674 -285.246986) (xy 74.158239 -285.28633)
			(xy 74.18111 -285.329907) (xy 74.196694 -285.376588) (xy 74.204589 -285.425165) (xy 74.205084 -285.449772)
			(xy 74.204589 -285.474379) (xy 74.20441 -285.47548) (xy 74.523088 -285.47548) (xy 74.523088 -285.424064)
			(xy 74.531131 -285.373282) (xy 74.547019 -285.324383) (xy 74.570362 -285.278571) (xy 74.600583 -285.236975)
			(xy 74.636939 -285.200619) (xy 74.678535 -285.170398) (xy 74.724347 -285.147055) (xy 74.773246 -285.131167)
			(xy 74.824028 -285.123124) (xy 74.875444 -285.123124) (xy 74.926226 -285.131167) (xy 74.975125 -285.147055)
			(xy 75.020937 -285.170398) (xy 75.062533 -285.200619) (xy 75.098889 -285.236975) (xy 75.12911 -285.278571)
			(xy 75.152453 -285.324383) (xy 75.168341 -285.373282) (xy 75.176384 -285.424064) (xy 75.176888 -285.449772)
			(xy 75.176384 -285.47548) (xy 75.473302 -285.47548) (xy 75.473302 -285.424064) (xy 75.481345 -285.373282)
			(xy 75.497233 -285.324383) (xy 75.520576 -285.278571) (xy 75.550797 -285.236975) (xy 75.587153 -285.200619)
			(xy 75.628749 -285.170398) (xy 75.674561 -285.147055) (xy 75.72346 -285.131167) (xy 75.774242 -285.123124)
			(xy 75.825658 -285.123124) (xy 75.87644 -285.131167) (xy 75.925339 -285.147055) (xy 75.971151 -285.170398)
			(xy 76.012747 -285.200619) (xy 76.049103 -285.236975) (xy 76.079324 -285.278571) (xy 76.102667 -285.324383)
			(xy 76.118555 -285.373282) (xy 76.126598 -285.424064) (xy 76.127102 -285.449772) (xy 76.444106 -285.449772)
			(xy 76.448066 -285.400718) (xy 76.459843 -285.352934) (xy 76.479134 -285.307658) (xy 76.505437 -285.266062)
			(xy 76.538072 -285.229225) (xy 76.576193 -285.1981) (xy 76.618814 -285.173493) (xy 76.66483 -285.156041)
			(xy 76.713049 -285.146197) (xy 76.762224 -285.144216) (xy 76.811079 -285.150148) (xy 76.85835 -285.16384)
			(xy 76.902812 -285.184938) (xy 76.943315 -285.212894) (xy 76.978808 -285.246986) (xy 77.008373 -285.28633)
			(xy 77.031244 -285.329907) (xy 77.046828 -285.376588) (xy 77.054723 -285.425165) (xy 77.055218 -285.449772)
			(xy 77.394066 -285.449772) (xy 77.398026 -285.400718) (xy 77.409803 -285.352934) (xy 77.429094 -285.307658)
			(xy 77.455397 -285.266062) (xy 77.488032 -285.229225) (xy 77.526153 -285.1981) (xy 77.568774 -285.173493)
			(xy 77.61479 -285.156041) (xy 77.663009 -285.146197) (xy 77.712184 -285.144216) (xy 77.761039 -285.150148)
			(xy 77.80831 -285.16384) (xy 77.852772 -285.184938) (xy 77.893275 -285.212894) (xy 77.928768 -285.246986)
			(xy 77.958333 -285.28633) (xy 77.981204 -285.329907) (xy 77.996788 -285.376588) (xy 78.004683 -285.425165)
			(xy 78.005178 -285.449772) (xy 78.344026 -285.449772) (xy 78.347986 -285.400718) (xy 78.359763 -285.352934)
			(xy 78.379054 -285.307658) (xy 78.405357 -285.266062) (xy 78.437992 -285.229225) (xy 78.476113 -285.1981)
			(xy 78.518734 -285.173493) (xy 78.56475 -285.156041) (xy 78.612969 -285.146197) (xy 78.662144 -285.144216)
			(xy 78.710999 -285.150148) (xy 78.75827 -285.16384) (xy 78.802732 -285.184938) (xy 78.843235 -285.212894)
			(xy 78.878728 -285.246986) (xy 78.908293 -285.28633) (xy 78.931164 -285.329907) (xy 78.946748 -285.376588)
			(xy 78.954643 -285.425165) (xy 78.955138 -285.449772) (xy 79.293986 -285.449772) (xy 79.297946 -285.400718)
			(xy 79.309723 -285.352934) (xy 79.329014 -285.307658) (xy 79.355317 -285.266062) (xy 79.387952 -285.229225)
			(xy 79.426073 -285.1981) (xy 79.468694 -285.173493) (xy 79.51471 -285.156041) (xy 79.562929 -285.146197)
			(xy 79.612104 -285.144216) (xy 79.660959 -285.150148) (xy 79.70823 -285.16384) (xy 79.752692 -285.184938)
			(xy 79.793195 -285.212894) (xy 79.828688 -285.246986) (xy 79.858253 -285.28633) (xy 79.881124 -285.329907)
			(xy 79.896708 -285.376588) (xy 79.904603 -285.425165) (xy 79.905098 -285.449772) (xy 80.243946 -285.449772)
			(xy 80.247906 -285.400718) (xy 80.259683 -285.352934) (xy 80.278974 -285.307658) (xy 80.305277 -285.266062)
			(xy 80.337912 -285.229225) (xy 80.376033 -285.1981) (xy 80.418654 -285.173493) (xy 80.46467 -285.156041)
			(xy 80.512889 -285.146197) (xy 80.562064 -285.144216) (xy 80.610919 -285.150148) (xy 80.65819 -285.16384)
			(xy 80.702652 -285.184938) (xy 80.743155 -285.212894) (xy 80.778648 -285.246986) (xy 80.808213 -285.28633)
			(xy 80.831084 -285.329907) (xy 80.846668 -285.376588) (xy 80.854563 -285.425165) (xy 80.855058 -285.449772)
			(xy 80.854563 -285.474379) (xy 80.854384 -285.47548) (xy 81.173316 -285.47548) (xy 81.173316 -285.424064)
			(xy 81.181359 -285.373282) (xy 81.197247 -285.324383) (xy 81.22059 -285.278571) (xy 81.250811 -285.236975)
			(xy 81.287167 -285.200619) (xy 81.328763 -285.170398) (xy 81.374575 -285.147055) (xy 81.423474 -285.131167)
			(xy 81.474256 -285.123124) (xy 81.525672 -285.123124) (xy 81.576454 -285.131167) (xy 81.625353 -285.147055)
			(xy 81.671165 -285.170398) (xy 81.712761 -285.200619) (xy 81.749117 -285.236975) (xy 81.779338 -285.278571)
			(xy 81.802681 -285.324383) (xy 81.818569 -285.373282) (xy 81.826612 -285.424064) (xy 81.827116 -285.449772)
			(xy 81.826612 -285.47548) (xy 82.123276 -285.47548) (xy 82.123276 -285.424064) (xy 82.131319 -285.373282)
			(xy 82.147207 -285.324383) (xy 82.17055 -285.278571) (xy 82.200771 -285.236975) (xy 82.237127 -285.200619)
			(xy 82.278723 -285.170398) (xy 82.324535 -285.147055) (xy 82.373434 -285.131167) (xy 82.424216 -285.123124)
			(xy 82.475632 -285.123124) (xy 82.526414 -285.131167) (xy 82.575313 -285.147055) (xy 82.621125 -285.170398)
			(xy 82.662721 -285.200619) (xy 82.699077 -285.236975) (xy 82.729298 -285.278571) (xy 82.752641 -285.324383)
			(xy 82.768529 -285.373282) (xy 82.776572 -285.424064) (xy 82.777076 -285.449772) (xy 82.777071 -285.450026)
			(xy 83.094334 -285.450026) (xy 83.098294 -285.400972) (xy 83.110071 -285.353188) (xy 83.129362 -285.307912)
			(xy 83.155665 -285.266316) (xy 83.1883 -285.229479) (xy 83.226421 -285.198354) (xy 83.269042 -285.173747)
			(xy 83.315058 -285.156295) (xy 83.363277 -285.146451) (xy 83.412452 -285.14447) (xy 83.461307 -285.150402)
			(xy 83.508578 -285.164094) (xy 83.55304 -285.185192) (xy 83.593543 -285.213148) (xy 83.629036 -285.24724)
			(xy 83.658601 -285.286584) (xy 83.681472 -285.330161) (xy 83.697056 -285.376842) (xy 83.703831 -285.41853)
			(xy 94.233236 -285.41853) (xy 94.237307 -285.362908) (xy 94.249433 -285.308471) (xy 94.269356 -285.25638)
			(xy 94.296652 -285.207745) (xy 94.330738 -285.163602) (xy 94.370887 -285.124893) (xy 94.416245 -285.092442)
			(xy 94.465845 -285.066941) (xy 94.518629 -285.048934) (xy 94.573472 -285.038804) (xy 94.629206 -285.036767)
			(xy 94.684643 -285.042867) (xy 94.7386 -285.056973) (xy 94.789929 -285.078785) (xy 94.837535 -285.107839)
			(xy 94.880403 -285.143514) (xy 94.91762 -285.185051) (xy 94.948393 -285.231564) (xy 94.972065 -285.282061)
			(xy 94.988133 -285.335468) (xy 94.996253 -285.390644) (xy 94.996762 -285.41853) (xy 94.996253 -285.446416)
			(xy 94.988133 -285.501592) (xy 94.972065 -285.554999) (xy 94.948393 -285.605496) (xy 94.91762 -285.652009)
			(xy 94.880403 -285.693546) (xy 94.837535 -285.729221) (xy 94.789929 -285.758275) (xy 94.7386 -285.780087)
			(xy 94.684643 -285.794193) (xy 94.629206 -285.800293) (xy 94.573472 -285.798256) (xy 94.518629 -285.788126)
			(xy 94.465845 -285.770119) (xy 94.416245 -285.744618) (xy 94.370887 -285.712167) (xy 94.330738 -285.673458)
			(xy 94.296652 -285.629315) (xy 94.269356 -285.58068) (xy 94.249433 -285.528589) (xy 94.237307 -285.474152)
			(xy 94.233236 -285.41853) (xy 83.703831 -285.41853) (xy 83.704951 -285.425419) (xy 83.705446 -285.450026)
			(xy 83.704951 -285.474633) (xy 83.697056 -285.52321) (xy 83.681472 -285.569891) (xy 83.658601 -285.613468)
			(xy 83.629036 -285.652812) (xy 83.593543 -285.686904) (xy 83.55304 -285.71486) (xy 83.508578 -285.735958)
			(xy 83.461307 -285.74965) (xy 83.412452 -285.755582) (xy 83.363277 -285.753601) (xy 83.315058 -285.743757)
			(xy 83.269042 -285.726305) (xy 83.226421 -285.701698) (xy 83.1883 -285.670573) (xy 83.155665 -285.633736)
			(xy 83.129362 -285.59214) (xy 83.110071 -285.546864) (xy 83.098294 -285.49908) (xy 83.094334 -285.450026)
			(xy 82.777071 -285.450026) (xy 82.776572 -285.47548) (xy 82.768529 -285.526262) (xy 82.752641 -285.575161)
			(xy 82.729298 -285.620973) (xy 82.699077 -285.662569) (xy 82.662721 -285.698925) (xy 82.621125 -285.729146)
			(xy 82.575313 -285.752489) (xy 82.526414 -285.768377) (xy 82.475632 -285.77642) (xy 82.424216 -285.77642)
			(xy 82.373434 -285.768377) (xy 82.324535 -285.752489) (xy 82.278723 -285.729146) (xy 82.237127 -285.698925)
			(xy 82.200771 -285.662569) (xy 82.17055 -285.620973) (xy 82.147207 -285.575161) (xy 82.131319 -285.526262)
			(xy 82.123276 -285.47548) (xy 81.826612 -285.47548) (xy 81.818569 -285.526262) (xy 81.802681 -285.575161)
			(xy 81.779338 -285.620973) (xy 81.749117 -285.662569) (xy 81.712761 -285.698925) (xy 81.671165 -285.729146)
			(xy 81.625353 -285.752489) (xy 81.576454 -285.768377) (xy 81.525672 -285.77642) (xy 81.474256 -285.77642)
			(xy 81.423474 -285.768377) (xy 81.374575 -285.752489) (xy 81.328763 -285.729146) (xy 81.287167 -285.698925)
			(xy 81.250811 -285.662569) (xy 81.22059 -285.620973) (xy 81.197247 -285.575161) (xy 81.181359 -285.526262)
			(xy 81.173316 -285.47548) (xy 80.854384 -285.47548) (xy 80.846668 -285.522956) (xy 80.831084 -285.569637)
			(xy 80.808213 -285.613214) (xy 80.778648 -285.652558) (xy 80.743155 -285.68665) (xy 80.702652 -285.714606)
			(xy 80.65819 -285.735704) (xy 80.610919 -285.749396) (xy 80.562064 -285.755328) (xy 80.512889 -285.753347)
			(xy 80.46467 -285.743503) (xy 80.418654 -285.726051) (xy 80.376033 -285.701444) (xy 80.337912 -285.670319)
			(xy 80.305277 -285.633482) (xy 80.278974 -285.591886) (xy 80.259683 -285.54661) (xy 80.247906 -285.498826)
			(xy 80.243946 -285.449772) (xy 79.905098 -285.449772) (xy 79.904603 -285.474379) (xy 79.896708 -285.522956)
			(xy 79.881124 -285.569637) (xy 79.858253 -285.613214) (xy 79.828688 -285.652558) (xy 79.793195 -285.68665)
			(xy 79.752692 -285.714606) (xy 79.70823 -285.735704) (xy 79.660959 -285.749396) (xy 79.612104 -285.755328)
			(xy 79.562929 -285.753347) (xy 79.51471 -285.743503) (xy 79.468694 -285.726051) (xy 79.426073 -285.701444)
			(xy 79.387952 -285.670319) (xy 79.355317 -285.633482) (xy 79.329014 -285.591886) (xy 79.309723 -285.54661)
			(xy 79.297946 -285.498826) (xy 79.293986 -285.449772) (xy 78.955138 -285.449772) (xy 78.954643 -285.474379)
			(xy 78.946748 -285.522956) (xy 78.931164 -285.569637) (xy 78.908293 -285.613214) (xy 78.878728 -285.652558)
			(xy 78.843235 -285.68665) (xy 78.802732 -285.714606) (xy 78.75827 -285.735704) (xy 78.710999 -285.749396)
			(xy 78.662144 -285.755328) (xy 78.612969 -285.753347) (xy 78.56475 -285.743503) (xy 78.518734 -285.726051)
			(xy 78.476113 -285.701444) (xy 78.437992 -285.670319) (xy 78.405357 -285.633482) (xy 78.379054 -285.591886)
			(xy 78.359763 -285.54661) (xy 78.347986 -285.498826) (xy 78.344026 -285.449772) (xy 78.005178 -285.449772)
			(xy 78.004683 -285.474379) (xy 77.996788 -285.522956) (xy 77.981204 -285.569637) (xy 77.958333 -285.613214)
			(xy 77.928768 -285.652558) (xy 77.893275 -285.68665) (xy 77.852772 -285.714606) (xy 77.80831 -285.735704)
			(xy 77.761039 -285.749396) (xy 77.712184 -285.755328) (xy 77.663009 -285.753347) (xy 77.61479 -285.743503)
			(xy 77.568774 -285.726051) (xy 77.526153 -285.701444) (xy 77.488032 -285.670319) (xy 77.455397 -285.633482)
			(xy 77.429094 -285.591886) (xy 77.409803 -285.54661) (xy 77.398026 -285.498826) (xy 77.394066 -285.449772)
			(xy 77.055218 -285.449772) (xy 77.054723 -285.474379) (xy 77.046828 -285.522956) (xy 77.031244 -285.569637)
			(xy 77.008373 -285.613214) (xy 76.978808 -285.652558) (xy 76.943315 -285.68665) (xy 76.902812 -285.714606)
			(xy 76.85835 -285.735704) (xy 76.811079 -285.749396) (xy 76.762224 -285.755328) (xy 76.713049 -285.753347)
			(xy 76.66483 -285.743503) (xy 76.618814 -285.726051) (xy 76.576193 -285.701444) (xy 76.538072 -285.670319)
			(xy 76.505437 -285.633482) (xy 76.479134 -285.591886) (xy 76.459843 -285.54661) (xy 76.448066 -285.498826)
			(xy 76.444106 -285.449772) (xy 76.127102 -285.449772) (xy 76.126598 -285.47548) (xy 76.118555 -285.526262)
			(xy 76.102667 -285.575161) (xy 76.079324 -285.620973) (xy 76.049103 -285.662569) (xy 76.012747 -285.698925)
			(xy 75.971151 -285.729146) (xy 75.925339 -285.752489) (xy 75.87644 -285.768377) (xy 75.825658 -285.77642)
			(xy 75.774242 -285.77642) (xy 75.72346 -285.768377) (xy 75.674561 -285.752489) (xy 75.628749 -285.729146)
			(xy 75.587153 -285.698925) (xy 75.550797 -285.662569) (xy 75.520576 -285.620973) (xy 75.497233 -285.575161)
			(xy 75.481345 -285.526262) (xy 75.473302 -285.47548) (xy 75.176384 -285.47548) (xy 75.168341 -285.526262)
			(xy 75.152453 -285.575161) (xy 75.12911 -285.620973) (xy 75.098889 -285.662569) (xy 75.062533 -285.698925)
			(xy 75.020937 -285.729146) (xy 74.975125 -285.752489) (xy 74.926226 -285.768377) (xy 74.875444 -285.77642)
			(xy 74.824028 -285.77642) (xy 74.773246 -285.768377) (xy 74.724347 -285.752489) (xy 74.678535 -285.729146)
			(xy 74.636939 -285.698925) (xy 74.600583 -285.662569) (xy 74.570362 -285.620973) (xy 74.547019 -285.575161)
			(xy 74.531131 -285.526262) (xy 74.523088 -285.47548) (xy 74.20441 -285.47548) (xy 74.196694 -285.522956)
			(xy 74.18111 -285.569637) (xy 74.158239 -285.613214) (xy 74.128674 -285.652558) (xy 74.093181 -285.68665)
			(xy 74.052678 -285.714606) (xy 74.008216 -285.735704) (xy 73.960945 -285.749396) (xy 73.91209 -285.755328)
			(xy 73.862915 -285.753347) (xy 73.814696 -285.743503) (xy 73.76868 -285.726051) (xy 73.726059 -285.701444)
			(xy 73.687938 -285.670319) (xy 73.655303 -285.633482) (xy 73.629 -285.591886) (xy 73.609709 -285.54661)
			(xy 73.597932 -285.498826) (xy 73.593972 -285.449772) (xy 49.181004 -285.449772) (xy 49.181004 -285.924752)
			(xy 49.368976 -285.924752) (xy 49.372936 -285.875698) (xy 49.384713 -285.827914) (xy 49.404004 -285.782638)
			(xy 49.430307 -285.741042) (xy 49.462942 -285.704205) (xy 49.501063 -285.67308) (xy 49.543684 -285.648473)
			(xy 49.5897 -285.631021) (xy 49.637919 -285.621177) (xy 49.687094 -285.619196) (xy 49.735949 -285.625128)
			(xy 49.78322 -285.63882) (xy 49.827682 -285.659918) (xy 49.868185 -285.687874) (xy 49.903678 -285.721966)
			(xy 49.933243 -285.76131) (xy 49.956114 -285.804887) (xy 49.971698 -285.851568) (xy 49.979593 -285.900145)
			(xy 49.980088 -285.924752) (xy 50.31919 -285.924752) (xy 50.32315 -285.875698) (xy 50.334927 -285.827914)
			(xy 50.354218 -285.782638) (xy 50.380521 -285.741042) (xy 50.413156 -285.704205) (xy 50.451277 -285.67308)
			(xy 50.493898 -285.648473) (xy 50.539914 -285.631021) (xy 50.588133 -285.621177) (xy 50.637308 -285.619196)
			(xy 50.686163 -285.625128) (xy 50.733434 -285.63882) (xy 50.777896 -285.659918) (xy 50.818399 -285.687874)
			(xy 50.853892 -285.721966) (xy 50.883457 -285.76131) (xy 50.906328 -285.804887) (xy 50.921912 -285.851568)
			(xy 50.929807 -285.900145) (xy 50.930302 -285.924752) (xy 51.26915 -285.924752) (xy 51.27311 -285.875698)
			(xy 51.284887 -285.827914) (xy 51.304178 -285.782638) (xy 51.330481 -285.741042) (xy 51.363116 -285.704205)
			(xy 51.401237 -285.67308) (xy 51.443858 -285.648473) (xy 51.489874 -285.631021) (xy 51.538093 -285.621177)
			(xy 51.587268 -285.619196) (xy 51.636123 -285.625128) (xy 51.683394 -285.63882) (xy 51.727856 -285.659918)
			(xy 51.768359 -285.687874) (xy 51.803852 -285.721966) (xy 51.833417 -285.76131) (xy 51.856288 -285.804887)
			(xy 51.871872 -285.851568) (xy 51.879767 -285.900145) (xy 51.880262 -285.924752) (xy 52.21911 -285.924752)
			(xy 52.22307 -285.875698) (xy 52.234847 -285.827914) (xy 52.254138 -285.782638) (xy 52.280441 -285.741042)
			(xy 52.313076 -285.704205) (xy 52.351197 -285.67308) (xy 52.393818 -285.648473) (xy 52.439834 -285.631021)
			(xy 52.488053 -285.621177) (xy 52.537228 -285.619196) (xy 52.586083 -285.625128) (xy 52.633354 -285.63882)
			(xy 52.677816 -285.659918) (xy 52.718319 -285.687874) (xy 52.753812 -285.721966) (xy 52.783377 -285.76131)
			(xy 52.806248 -285.804887) (xy 52.821832 -285.851568) (xy 52.829727 -285.900145) (xy 52.830222 -285.924752)
			(xy 53.16907 -285.924752) (xy 53.17303 -285.875698) (xy 53.184807 -285.827914) (xy 53.204098 -285.782638)
			(xy 53.230401 -285.741042) (xy 53.263036 -285.704205) (xy 53.301157 -285.67308) (xy 53.343778 -285.648473)
			(xy 53.389794 -285.631021) (xy 53.438013 -285.621177) (xy 53.487188 -285.619196) (xy 53.536043 -285.625128)
			(xy 53.583314 -285.63882) (xy 53.627776 -285.659918) (xy 53.668279 -285.687874) (xy 53.703772 -285.721966)
			(xy 53.733337 -285.76131) (xy 53.756208 -285.804887) (xy 53.771792 -285.851568) (xy 53.779687 -285.900145)
			(xy 53.780182 -285.924752) (xy 54.11903 -285.924752) (xy 54.12299 -285.875698) (xy 54.134767 -285.827914)
			(xy 54.154058 -285.782638) (xy 54.180361 -285.741042) (xy 54.212996 -285.704205) (xy 54.251117 -285.67308)
			(xy 54.293738 -285.648473) (xy 54.339754 -285.631021) (xy 54.387973 -285.621177) (xy 54.437148 -285.619196)
			(xy 54.486003 -285.625128) (xy 54.533274 -285.63882) (xy 54.577736 -285.659918) (xy 54.618239 -285.687874)
			(xy 54.653732 -285.721966) (xy 54.683297 -285.76131) (xy 54.706168 -285.804887) (xy 54.721752 -285.851568)
			(xy 54.729647 -285.900145) (xy 54.730142 -285.924752) (xy 55.06899 -285.924752) (xy 55.07295 -285.875698)
			(xy 55.084727 -285.827914) (xy 55.104018 -285.782638) (xy 55.130321 -285.741042) (xy 55.162956 -285.704205)
			(xy 55.201077 -285.67308) (xy 55.243698 -285.648473) (xy 55.289714 -285.631021) (xy 55.337933 -285.621177)
			(xy 55.387108 -285.619196) (xy 55.435963 -285.625128) (xy 55.483234 -285.63882) (xy 55.527696 -285.659918)
			(xy 55.568199 -285.687874) (xy 55.603692 -285.721966) (xy 55.633257 -285.76131) (xy 55.656128 -285.804887)
			(xy 55.671712 -285.851568) (xy 55.679607 -285.900145) (xy 55.680102 -285.924752) (xy 56.01895 -285.924752)
			(xy 56.02291 -285.875698) (xy 56.034687 -285.827914) (xy 56.053978 -285.782638) (xy 56.080281 -285.741042)
			(xy 56.112916 -285.704205) (xy 56.151037 -285.67308) (xy 56.193658 -285.648473) (xy 56.239674 -285.631021)
			(xy 56.287893 -285.621177) (xy 56.337068 -285.619196) (xy 56.385923 -285.625128) (xy 56.433194 -285.63882)
			(xy 56.477656 -285.659918) (xy 56.518159 -285.687874) (xy 56.553652 -285.721966) (xy 56.583217 -285.76131)
			(xy 56.606088 -285.804887) (xy 56.621672 -285.851568) (xy 56.629567 -285.900145) (xy 56.630062 -285.924752)
			(xy 56.969164 -285.924752) (xy 56.973124 -285.875698) (xy 56.984901 -285.827914) (xy 57.004192 -285.782638)
			(xy 57.030495 -285.741042) (xy 57.06313 -285.704205) (xy 57.101251 -285.67308) (xy 57.143872 -285.648473)
			(xy 57.189888 -285.631021) (xy 57.238107 -285.621177) (xy 57.287282 -285.619196) (xy 57.336137 -285.625128)
			(xy 57.383408 -285.63882) (xy 57.42787 -285.659918) (xy 57.468373 -285.687874) (xy 57.503866 -285.721966)
			(xy 57.533431 -285.76131) (xy 57.556302 -285.804887) (xy 57.571886 -285.851568) (xy 57.579781 -285.900145)
			(xy 57.580276 -285.924752) (xy 57.919124 -285.924752) (xy 57.923084 -285.875698) (xy 57.934861 -285.827914)
			(xy 57.954152 -285.782638) (xy 57.980455 -285.741042) (xy 58.01309 -285.704205) (xy 58.051211 -285.67308)
			(xy 58.093832 -285.648473) (xy 58.139848 -285.631021) (xy 58.188067 -285.621177) (xy 58.237242 -285.619196)
			(xy 58.286097 -285.625128) (xy 58.333368 -285.63882) (xy 58.37783 -285.659918) (xy 58.418333 -285.687874)
			(xy 58.453826 -285.721966) (xy 58.483391 -285.76131) (xy 58.506262 -285.804887) (xy 58.521846 -285.851568)
			(xy 58.529741 -285.900145) (xy 58.530236 -285.924752) (xy 59.819044 -285.924752) (xy 59.823004 -285.875698)
			(xy 59.834781 -285.827914) (xy 59.854072 -285.782638) (xy 59.880375 -285.741042) (xy 59.91301 -285.704205)
			(xy 59.951131 -285.67308) (xy 59.993752 -285.648473) (xy 60.039768 -285.631021) (xy 60.087987 -285.621177)
			(xy 60.137162 -285.619196) (xy 60.186017 -285.625128) (xy 60.233288 -285.63882) (xy 60.27775 -285.659918)
			(xy 60.318253 -285.687874) (xy 60.353746 -285.721966) (xy 60.383311 -285.76131) (xy 60.406182 -285.804887)
			(xy 60.421766 -285.851568) (xy 60.429661 -285.900145) (xy 60.430156 -285.924752) (xy 60.769004 -285.924752)
			(xy 60.772964 -285.875698) (xy 60.784741 -285.827914) (xy 60.804032 -285.782638) (xy 60.830335 -285.741042)
			(xy 60.86297 -285.704205) (xy 60.901091 -285.67308) (xy 60.943712 -285.648473) (xy 60.989728 -285.631021)
			(xy 61.037947 -285.621177) (xy 61.087122 -285.619196) (xy 61.135977 -285.625128) (xy 61.183248 -285.63882)
			(xy 61.22771 -285.659918) (xy 61.268213 -285.687874) (xy 61.303706 -285.721966) (xy 61.333271 -285.76131)
			(xy 61.356142 -285.804887) (xy 61.371726 -285.851568) (xy 61.379621 -285.900145) (xy 61.380116 -285.924752)
			(xy 61.718964 -285.924752) (xy 61.722924 -285.875698) (xy 61.734701 -285.827914) (xy 61.753992 -285.782638)
			(xy 61.780295 -285.741042) (xy 61.81293 -285.704205) (xy 61.851051 -285.67308) (xy 61.893672 -285.648473)
			(xy 61.939688 -285.631021) (xy 61.987907 -285.621177) (xy 62.037082 -285.619196) (xy 62.085937 -285.625128)
			(xy 62.133208 -285.63882) (xy 62.17767 -285.659918) (xy 62.218173 -285.687874) (xy 62.253666 -285.721966)
			(xy 62.283231 -285.76131) (xy 62.306102 -285.804887) (xy 62.321686 -285.851568) (xy 62.329581 -285.900145)
			(xy 62.330076 -285.924752) (xy 62.669178 -285.924752) (xy 62.673138 -285.875698) (xy 62.684915 -285.827914)
			(xy 62.704206 -285.782638) (xy 62.730509 -285.741042) (xy 62.763144 -285.704205) (xy 62.801265 -285.67308)
			(xy 62.843886 -285.648473) (xy 62.889902 -285.631021) (xy 62.938121 -285.621177) (xy 62.987296 -285.619196)
			(xy 63.036151 -285.625128) (xy 63.083422 -285.63882) (xy 63.127884 -285.659918) (xy 63.168387 -285.687874)
			(xy 63.20388 -285.721966) (xy 63.233445 -285.76131) (xy 63.256316 -285.804887) (xy 63.2719 -285.851568)
			(xy 63.279795 -285.900145) (xy 63.28029 -285.924752) (xy 63.619138 -285.924752) (xy 63.623098 -285.875698)
			(xy 63.634875 -285.827914) (xy 63.654166 -285.782638) (xy 63.680469 -285.741042) (xy 63.713104 -285.704205)
			(xy 63.751225 -285.67308) (xy 63.793846 -285.648473) (xy 63.839862 -285.631021) (xy 63.888081 -285.621177)
			(xy 63.937256 -285.619196) (xy 63.986111 -285.625128) (xy 64.033382 -285.63882) (xy 64.077844 -285.659918)
			(xy 64.118347 -285.687874) (xy 64.15384 -285.721966) (xy 64.183405 -285.76131) (xy 64.206276 -285.804887)
			(xy 64.22186 -285.851568) (xy 64.229755 -285.900145) (xy 64.23025 -285.924752) (xy 64.569098 -285.924752)
			(xy 64.573058 -285.875698) (xy 64.584835 -285.827914) (xy 64.604126 -285.782638) (xy 64.630429 -285.741042)
			(xy 64.663064 -285.704205) (xy 64.701185 -285.67308) (xy 64.743806 -285.648473) (xy 64.789822 -285.631021)
			(xy 64.838041 -285.621177) (xy 64.887216 -285.619196) (xy 64.936071 -285.625128) (xy 64.983342 -285.63882)
			(xy 65.027804 -285.659918) (xy 65.068307 -285.687874) (xy 65.1038 -285.721966) (xy 65.133365 -285.76131)
			(xy 65.156236 -285.804887) (xy 65.17182 -285.851568) (xy 65.179715 -285.900145) (xy 65.18021 -285.924752)
			(xy 65.519058 -285.924752) (xy 65.523018 -285.875698) (xy 65.534795 -285.827914) (xy 65.554086 -285.782638)
			(xy 65.580389 -285.741042) (xy 65.613024 -285.704205) (xy 65.651145 -285.67308) (xy 65.693766 -285.648473)
			(xy 65.739782 -285.631021) (xy 65.788001 -285.621177) (xy 65.837176 -285.619196) (xy 65.886031 -285.625128)
			(xy 65.933302 -285.63882) (xy 65.977764 -285.659918) (xy 66.018267 -285.687874) (xy 66.05376 -285.721966)
			(xy 66.083325 -285.76131) (xy 66.106196 -285.804887) (xy 66.12178 -285.851568) (xy 66.129675 -285.900145)
			(xy 66.13017 -285.924752) (xy 66.469018 -285.924752) (xy 66.472978 -285.875698) (xy 66.484755 -285.827914)
			(xy 66.504046 -285.782638) (xy 66.530349 -285.741042) (xy 66.562984 -285.704205) (xy 66.601105 -285.67308)
			(xy 66.643726 -285.648473) (xy 66.689742 -285.631021) (xy 66.737961 -285.621177) (xy 66.787136 -285.619196)
			(xy 66.835991 -285.625128) (xy 66.883262 -285.63882) (xy 66.927724 -285.659918) (xy 66.968227 -285.687874)
			(xy 67.00372 -285.721966) (xy 67.033285 -285.76131) (xy 67.056156 -285.804887) (xy 67.07174 -285.851568)
			(xy 67.079635 -285.900145) (xy 67.08013 -285.924752) (xy 67.418978 -285.924752) (xy 67.422938 -285.875698)
			(xy 67.434715 -285.827914) (xy 67.454006 -285.782638) (xy 67.480309 -285.741042) (xy 67.512944 -285.704205)
			(xy 67.551065 -285.67308) (xy 67.593686 -285.648473) (xy 67.639702 -285.631021) (xy 67.687921 -285.621177)
			(xy 67.737096 -285.619196) (xy 67.785951 -285.625128) (xy 67.833222 -285.63882) (xy 67.877684 -285.659918)
			(xy 67.918187 -285.687874) (xy 67.95368 -285.721966) (xy 67.983245 -285.76131) (xy 68.006116 -285.804887)
			(xy 68.0217 -285.851568) (xy 68.029595 -285.900145) (xy 68.03009 -285.924752) (xy 68.368938 -285.924752)
			(xy 68.372898 -285.875698) (xy 68.384675 -285.827914) (xy 68.403966 -285.782638) (xy 68.430269 -285.741042)
			(xy 68.462904 -285.704205) (xy 68.501025 -285.67308) (xy 68.543646 -285.648473) (xy 68.589662 -285.631021)
			(xy 68.637881 -285.621177) (xy 68.687056 -285.619196) (xy 68.735911 -285.625128) (xy 68.783182 -285.63882)
			(xy 68.827644 -285.659918) (xy 68.868147 -285.687874) (xy 68.90364 -285.721966) (xy 68.933205 -285.76131)
			(xy 68.956076 -285.804887) (xy 68.97166 -285.851568) (xy 68.979555 -285.900145) (xy 68.98005 -285.924752)
			(xy 69.319152 -285.924752) (xy 69.323112 -285.875698) (xy 69.334889 -285.827914) (xy 69.35418 -285.782638)
			(xy 69.380483 -285.741042) (xy 69.413118 -285.704205) (xy 69.451239 -285.67308) (xy 69.49386 -285.648473)
			(xy 69.539876 -285.631021) (xy 69.588095 -285.621177) (xy 69.63727 -285.619196) (xy 69.686125 -285.625128)
			(xy 69.733396 -285.63882) (xy 69.777858 -285.659918) (xy 69.818361 -285.687874) (xy 69.853854 -285.721966)
			(xy 69.883419 -285.76131) (xy 69.90629 -285.804887) (xy 69.921874 -285.851568) (xy 69.929769 -285.900145)
			(xy 69.930264 -285.924752) (xy 70.269112 -285.924752) (xy 70.273072 -285.875698) (xy 70.284849 -285.827914)
			(xy 70.30414 -285.782638) (xy 70.330443 -285.741042) (xy 70.363078 -285.704205) (xy 70.401199 -285.67308)
			(xy 70.44382 -285.648473) (xy 70.489836 -285.631021) (xy 70.538055 -285.621177) (xy 70.58723 -285.619196)
			(xy 70.636085 -285.625128) (xy 70.683356 -285.63882) (xy 70.727818 -285.659918) (xy 70.768321 -285.687874)
			(xy 70.803814 -285.721966) (xy 70.833379 -285.76131) (xy 70.85625 -285.804887) (xy 70.871834 -285.851568)
			(xy 70.879729 -285.900145) (xy 70.880224 -285.924752) (xy 70.879729 -285.949359) (xy 70.871834 -285.997936)
			(xy 70.85625 -286.044617) (xy 70.833379 -286.088194) (xy 70.803814 -286.127538) (xy 70.768321 -286.16163)
			(xy 70.727818 -286.189586) (xy 70.683356 -286.210684) (xy 70.636085 -286.224376) (xy 70.58723 -286.230308)
			(xy 70.538055 -286.228327) (xy 70.489836 -286.218483) (xy 70.44382 -286.201031) (xy 70.401199 -286.176424)
			(xy 70.363078 -286.145299) (xy 70.330443 -286.108462) (xy 70.30414 -286.066866) (xy 70.284849 -286.02159)
			(xy 70.273072 -285.973806) (xy 70.269112 -285.924752) (xy 69.930264 -285.924752) (xy 69.929769 -285.949359)
			(xy 69.921874 -285.997936) (xy 69.90629 -286.044617) (xy 69.883419 -286.088194) (xy 69.853854 -286.127538)
			(xy 69.818361 -286.16163) (xy 69.777858 -286.189586) (xy 69.733396 -286.210684) (xy 69.686125 -286.224376)
			(xy 69.63727 -286.230308) (xy 69.588095 -286.228327) (xy 69.539876 -286.218483) (xy 69.49386 -286.201031)
			(xy 69.451239 -286.176424) (xy 69.413118 -286.145299) (xy 69.380483 -286.108462) (xy 69.35418 -286.066866)
			(xy 69.334889 -286.02159) (xy 69.323112 -285.973806) (xy 69.319152 -285.924752) (xy 68.98005 -285.924752)
			(xy 68.979555 -285.949359) (xy 68.97166 -285.997936) (xy 68.956076 -286.044617) (xy 68.933205 -286.088194)
			(xy 68.90364 -286.127538) (xy 68.868147 -286.16163) (xy 68.827644 -286.189586) (xy 68.783182 -286.210684)
			(xy 68.735911 -286.224376) (xy 68.687056 -286.230308) (xy 68.637881 -286.228327) (xy 68.589662 -286.218483)
			(xy 68.543646 -286.201031) (xy 68.501025 -286.176424) (xy 68.462904 -286.145299) (xy 68.430269 -286.108462)
			(xy 68.403966 -286.066866) (xy 68.384675 -286.02159) (xy 68.372898 -285.973806) (xy 68.368938 -285.924752)
			(xy 68.03009 -285.924752) (xy 68.029595 -285.949359) (xy 68.0217 -285.997936) (xy 68.006116 -286.044617)
			(xy 67.983245 -286.088194) (xy 67.95368 -286.127538) (xy 67.918187 -286.16163) (xy 67.877684 -286.189586)
			(xy 67.833222 -286.210684) (xy 67.785951 -286.224376) (xy 67.737096 -286.230308) (xy 67.687921 -286.228327)
			(xy 67.639702 -286.218483) (xy 67.593686 -286.201031) (xy 67.551065 -286.176424) (xy 67.512944 -286.145299)
			(xy 67.480309 -286.108462) (xy 67.454006 -286.066866) (xy 67.434715 -286.02159) (xy 67.422938 -285.973806)
			(xy 67.418978 -285.924752) (xy 67.08013 -285.924752) (xy 67.079635 -285.949359) (xy 67.07174 -285.997936)
			(xy 67.056156 -286.044617) (xy 67.033285 -286.088194) (xy 67.00372 -286.127538) (xy 66.968227 -286.16163)
			(xy 66.927724 -286.189586) (xy 66.883262 -286.210684) (xy 66.835991 -286.224376) (xy 66.787136 -286.230308)
			(xy 66.737961 -286.228327) (xy 66.689742 -286.218483) (xy 66.643726 -286.201031) (xy 66.601105 -286.176424)
			(xy 66.562984 -286.145299) (xy 66.530349 -286.108462) (xy 66.504046 -286.066866) (xy 66.484755 -286.02159)
			(xy 66.472978 -285.973806) (xy 66.469018 -285.924752) (xy 66.13017 -285.924752) (xy 66.129675 -285.949359)
			(xy 66.12178 -285.997936) (xy 66.106196 -286.044617) (xy 66.083325 -286.088194) (xy 66.05376 -286.127538)
			(xy 66.018267 -286.16163) (xy 65.977764 -286.189586) (xy 65.933302 -286.210684) (xy 65.886031 -286.224376)
			(xy 65.837176 -286.230308) (xy 65.788001 -286.228327) (xy 65.739782 -286.218483) (xy 65.693766 -286.201031)
			(xy 65.651145 -286.176424) (xy 65.613024 -286.145299) (xy 65.580389 -286.108462) (xy 65.554086 -286.066866)
			(xy 65.534795 -286.02159) (xy 65.523018 -285.973806) (xy 65.519058 -285.924752) (xy 65.18021 -285.924752)
			(xy 65.179715 -285.949359) (xy 65.17182 -285.997936) (xy 65.156236 -286.044617) (xy 65.133365 -286.088194)
			(xy 65.1038 -286.127538) (xy 65.068307 -286.16163) (xy 65.027804 -286.189586) (xy 64.983342 -286.210684)
			(xy 64.936071 -286.224376) (xy 64.887216 -286.230308) (xy 64.838041 -286.228327) (xy 64.789822 -286.218483)
			(xy 64.743806 -286.201031) (xy 64.701185 -286.176424) (xy 64.663064 -286.145299) (xy 64.630429 -286.108462)
			(xy 64.604126 -286.066866) (xy 64.584835 -286.02159) (xy 64.573058 -285.973806) (xy 64.569098 -285.924752)
			(xy 64.23025 -285.924752) (xy 64.229755 -285.949359) (xy 64.22186 -285.997936) (xy 64.206276 -286.044617)
			(xy 64.183405 -286.088194) (xy 64.15384 -286.127538) (xy 64.118347 -286.16163) (xy 64.077844 -286.189586)
			(xy 64.033382 -286.210684) (xy 63.986111 -286.224376) (xy 63.937256 -286.230308) (xy 63.888081 -286.228327)
			(xy 63.839862 -286.218483) (xy 63.793846 -286.201031) (xy 63.751225 -286.176424) (xy 63.713104 -286.145299)
			(xy 63.680469 -286.108462) (xy 63.654166 -286.066866) (xy 63.634875 -286.02159) (xy 63.623098 -285.973806)
			(xy 63.619138 -285.924752) (xy 63.28029 -285.924752) (xy 63.279795 -285.949359) (xy 63.2719 -285.997936)
			(xy 63.256316 -286.044617) (xy 63.233445 -286.088194) (xy 63.20388 -286.127538) (xy 63.168387 -286.16163)
			(xy 63.127884 -286.189586) (xy 63.083422 -286.210684) (xy 63.036151 -286.224376) (xy 62.987296 -286.230308)
			(xy 62.938121 -286.228327) (xy 62.889902 -286.218483) (xy 62.843886 -286.201031) (xy 62.801265 -286.176424)
			(xy 62.763144 -286.145299) (xy 62.730509 -286.108462) (xy 62.704206 -286.066866) (xy 62.684915 -286.02159)
			(xy 62.673138 -285.973806) (xy 62.669178 -285.924752) (xy 62.330076 -285.924752) (xy 62.329581 -285.949359)
			(xy 62.321686 -285.997936) (xy 62.306102 -286.044617) (xy 62.283231 -286.088194) (xy 62.253666 -286.127538)
			(xy 62.218173 -286.16163) (xy 62.17767 -286.189586) (xy 62.133208 -286.210684) (xy 62.085937 -286.224376)
			(xy 62.037082 -286.230308) (xy 61.987907 -286.228327) (xy 61.939688 -286.218483) (xy 61.893672 -286.201031)
			(xy 61.851051 -286.176424) (xy 61.81293 -286.145299) (xy 61.780295 -286.108462) (xy 61.753992 -286.066866)
			(xy 61.734701 -286.02159) (xy 61.722924 -285.973806) (xy 61.718964 -285.924752) (xy 61.380116 -285.924752)
			(xy 61.379621 -285.949359) (xy 61.371726 -285.997936) (xy 61.356142 -286.044617) (xy 61.333271 -286.088194)
			(xy 61.303706 -286.127538) (xy 61.268213 -286.16163) (xy 61.22771 -286.189586) (xy 61.183248 -286.210684)
			(xy 61.135977 -286.224376) (xy 61.087122 -286.230308) (xy 61.037947 -286.228327) (xy 60.989728 -286.218483)
			(xy 60.943712 -286.201031) (xy 60.901091 -286.176424) (xy 60.86297 -286.145299) (xy 60.830335 -286.108462)
			(xy 60.804032 -286.066866) (xy 60.784741 -286.02159) (xy 60.772964 -285.973806) (xy 60.769004 -285.924752)
			(xy 60.430156 -285.924752) (xy 60.429661 -285.949359) (xy 60.421766 -285.997936) (xy 60.406182 -286.044617)
			(xy 60.383311 -286.088194) (xy 60.353746 -286.127538) (xy 60.318253 -286.16163) (xy 60.27775 -286.189586)
			(xy 60.233288 -286.210684) (xy 60.186017 -286.224376) (xy 60.137162 -286.230308) (xy 60.087987 -286.228327)
			(xy 60.039768 -286.218483) (xy 59.993752 -286.201031) (xy 59.951131 -286.176424) (xy 59.91301 -286.145299)
			(xy 59.880375 -286.108462) (xy 59.854072 -286.066866) (xy 59.834781 -286.02159) (xy 59.823004 -285.973806)
			(xy 59.819044 -285.924752) (xy 58.530236 -285.924752) (xy 58.529741 -285.949359) (xy 58.521846 -285.997936)
			(xy 58.506262 -286.044617) (xy 58.483391 -286.088194) (xy 58.453826 -286.127538) (xy 58.418333 -286.16163)
			(xy 58.37783 -286.189586) (xy 58.333368 -286.210684) (xy 58.286097 -286.224376) (xy 58.237242 -286.230308)
			(xy 58.188067 -286.228327) (xy 58.139848 -286.218483) (xy 58.093832 -286.201031) (xy 58.051211 -286.176424)
			(xy 58.01309 -286.145299) (xy 57.980455 -286.108462) (xy 57.954152 -286.066866) (xy 57.934861 -286.02159)
			(xy 57.923084 -285.973806) (xy 57.919124 -285.924752) (xy 57.580276 -285.924752) (xy 57.579781 -285.949359)
			(xy 57.571886 -285.997936) (xy 57.556302 -286.044617) (xy 57.533431 -286.088194) (xy 57.503866 -286.127538)
			(xy 57.468373 -286.16163) (xy 57.42787 -286.189586) (xy 57.383408 -286.210684) (xy 57.336137 -286.224376)
			(xy 57.287282 -286.230308) (xy 57.238107 -286.228327) (xy 57.189888 -286.218483) (xy 57.143872 -286.201031)
			(xy 57.101251 -286.176424) (xy 57.06313 -286.145299) (xy 57.030495 -286.108462) (xy 57.004192 -286.066866)
			(xy 56.984901 -286.02159) (xy 56.973124 -285.973806) (xy 56.969164 -285.924752) (xy 56.630062 -285.924752)
			(xy 56.629567 -285.949359) (xy 56.621672 -285.997936) (xy 56.606088 -286.044617) (xy 56.583217 -286.088194)
			(xy 56.553652 -286.127538) (xy 56.518159 -286.16163) (xy 56.477656 -286.189586) (xy 56.433194 -286.210684)
			(xy 56.385923 -286.224376) (xy 56.337068 -286.230308) (xy 56.287893 -286.228327) (xy 56.239674 -286.218483)
			(xy 56.193658 -286.201031) (xy 56.151037 -286.176424) (xy 56.112916 -286.145299) (xy 56.080281 -286.108462)
			(xy 56.053978 -286.066866) (xy 56.034687 -286.02159) (xy 56.02291 -285.973806) (xy 56.01895 -285.924752)
			(xy 55.680102 -285.924752) (xy 55.679607 -285.949359) (xy 55.671712 -285.997936) (xy 55.656128 -286.044617)
			(xy 55.633257 -286.088194) (xy 55.603692 -286.127538) (xy 55.568199 -286.16163) (xy 55.527696 -286.189586)
			(xy 55.483234 -286.210684) (xy 55.435963 -286.224376) (xy 55.387108 -286.230308) (xy 55.337933 -286.228327)
			(xy 55.289714 -286.218483) (xy 55.243698 -286.201031) (xy 55.201077 -286.176424) (xy 55.162956 -286.145299)
			(xy 55.130321 -286.108462) (xy 55.104018 -286.066866) (xy 55.084727 -286.02159) (xy 55.07295 -285.973806)
			(xy 55.06899 -285.924752) (xy 54.730142 -285.924752) (xy 54.729647 -285.949359) (xy 54.721752 -285.997936)
			(xy 54.706168 -286.044617) (xy 54.683297 -286.088194) (xy 54.653732 -286.127538) (xy 54.618239 -286.16163)
			(xy 54.577736 -286.189586) (xy 54.533274 -286.210684) (xy 54.486003 -286.224376) (xy 54.437148 -286.230308)
			(xy 54.387973 -286.228327) (xy 54.339754 -286.218483) (xy 54.293738 -286.201031) (xy 54.251117 -286.176424)
			(xy 54.212996 -286.145299) (xy 54.180361 -286.108462) (xy 54.154058 -286.066866) (xy 54.134767 -286.02159)
			(xy 54.12299 -285.973806) (xy 54.11903 -285.924752) (xy 53.780182 -285.924752) (xy 53.779687 -285.949359)
			(xy 53.771792 -285.997936) (xy 53.756208 -286.044617) (xy 53.733337 -286.088194) (xy 53.703772 -286.127538)
			(xy 53.668279 -286.16163) (xy 53.627776 -286.189586) (xy 53.583314 -286.210684) (xy 53.536043 -286.224376)
			(xy 53.487188 -286.230308) (xy 53.438013 -286.228327) (xy 53.389794 -286.218483) (xy 53.343778 -286.201031)
			(xy 53.301157 -286.176424) (xy 53.263036 -286.145299) (xy 53.230401 -286.108462) (xy 53.204098 -286.066866)
			(xy 53.184807 -286.02159) (xy 53.17303 -285.973806) (xy 53.16907 -285.924752) (xy 52.830222 -285.924752)
			(xy 52.829727 -285.949359) (xy 52.821832 -285.997936) (xy 52.806248 -286.044617) (xy 52.783377 -286.088194)
			(xy 52.753812 -286.127538) (xy 52.718319 -286.16163) (xy 52.677816 -286.189586) (xy 52.633354 -286.210684)
			(xy 52.586083 -286.224376) (xy 52.537228 -286.230308) (xy 52.488053 -286.228327) (xy 52.439834 -286.218483)
			(xy 52.393818 -286.201031) (xy 52.351197 -286.176424) (xy 52.313076 -286.145299) (xy 52.280441 -286.108462)
			(xy 52.254138 -286.066866) (xy 52.234847 -286.02159) (xy 52.22307 -285.973806) (xy 52.21911 -285.924752)
			(xy 51.880262 -285.924752) (xy 51.879767 -285.949359) (xy 51.871872 -285.997936) (xy 51.856288 -286.044617)
			(xy 51.833417 -286.088194) (xy 51.803852 -286.127538) (xy 51.768359 -286.16163) (xy 51.727856 -286.189586)
			(xy 51.683394 -286.210684) (xy 51.636123 -286.224376) (xy 51.587268 -286.230308) (xy 51.538093 -286.228327)
			(xy 51.489874 -286.218483) (xy 51.443858 -286.201031) (xy 51.401237 -286.176424) (xy 51.363116 -286.145299)
			(xy 51.330481 -286.108462) (xy 51.304178 -286.066866) (xy 51.284887 -286.02159) (xy 51.27311 -285.973806)
			(xy 51.26915 -285.924752) (xy 50.930302 -285.924752) (xy 50.929807 -285.949359) (xy 50.921912 -285.997936)
			(xy 50.906328 -286.044617) (xy 50.883457 -286.088194) (xy 50.853892 -286.127538) (xy 50.818399 -286.16163)
			(xy 50.777896 -286.189586) (xy 50.733434 -286.210684) (xy 50.686163 -286.224376) (xy 50.637308 -286.230308)
			(xy 50.588133 -286.228327) (xy 50.539914 -286.218483) (xy 50.493898 -286.201031) (xy 50.451277 -286.176424)
			(xy 50.413156 -286.145299) (xy 50.380521 -286.108462) (xy 50.354218 -286.066866) (xy 50.334927 -286.02159)
			(xy 50.32315 -285.973806) (xy 50.31919 -285.924752) (xy 49.980088 -285.924752) (xy 49.979593 -285.949359)
			(xy 49.971698 -285.997936) (xy 49.956114 -286.044617) (xy 49.933243 -286.088194) (xy 49.903678 -286.127538)
			(xy 49.868185 -286.16163) (xy 49.827682 -286.189586) (xy 49.78322 -286.210684) (xy 49.735949 -286.224376)
			(xy 49.687094 -286.230308) (xy 49.637919 -286.228327) (xy 49.5897 -286.218483) (xy 49.543684 -286.201031)
			(xy 49.501063 -286.176424) (xy 49.462942 -286.145299) (xy 49.430307 -286.108462) (xy 49.404004 -286.066866)
			(xy 49.384713 -286.02159) (xy 49.372936 -285.973806) (xy 49.368976 -285.924752) (xy 49.181004 -285.924752)
			(xy 49.181004 -286.399732) (xy 73.593972 -286.399732) (xy 73.597932 -286.350678) (xy 73.609709 -286.302894)
			(xy 73.629 -286.257618) (xy 73.655303 -286.216022) (xy 73.687938 -286.179185) (xy 73.726059 -286.14806)
			(xy 73.76868 -286.123453) (xy 73.814696 -286.106001) (xy 73.862915 -286.096157) (xy 73.91209 -286.094176)
			(xy 73.960945 -286.100108) (xy 74.008216 -286.1138) (xy 74.052678 -286.134898) (xy 74.093181 -286.162854)
			(xy 74.128674 -286.196946) (xy 74.158239 -286.23629) (xy 74.18111 -286.279867) (xy 74.196694 -286.326548)
			(xy 74.204589 -286.375125) (xy 74.205084 -286.399732) (xy 74.544186 -286.399732) (xy 74.548146 -286.350678)
			(xy 74.559923 -286.302894) (xy 74.579214 -286.257618) (xy 74.605517 -286.216022) (xy 74.638152 -286.179185)
			(xy 74.676273 -286.14806) (xy 74.718894 -286.123453) (xy 74.76491 -286.106001) (xy 74.813129 -286.096157)
			(xy 74.862304 -286.094176) (xy 74.911159 -286.100108) (xy 74.95843 -286.1138) (xy 75.002892 -286.134898)
			(xy 75.043395 -286.162854) (xy 75.078888 -286.196946) (xy 75.108453 -286.23629) (xy 75.131324 -286.279867)
			(xy 75.146908 -286.326548) (xy 75.154803 -286.375125) (xy 75.155298 -286.399732) (xy 75.494146 -286.399732)
			(xy 75.498106 -286.350678) (xy 75.509883 -286.302894) (xy 75.529174 -286.257618) (xy 75.555477 -286.216022)
			(xy 75.588112 -286.179185) (xy 75.626233 -286.14806) (xy 75.668854 -286.123453) (xy 75.71487 -286.106001)
			(xy 75.763089 -286.096157) (xy 75.812264 -286.094176) (xy 75.861119 -286.100108) (xy 75.90839 -286.1138)
			(xy 75.952852 -286.134898) (xy 75.993355 -286.162854) (xy 76.028848 -286.196946) (xy 76.058413 -286.23629)
			(xy 76.081284 -286.279867) (xy 76.096868 -286.326548) (xy 76.104763 -286.375125) (xy 76.105258 -286.399732)
			(xy 76.104763 -286.424339) (xy 76.104543 -286.425694) (xy 76.423262 -286.425694) (xy 76.423262 -286.374278)
			(xy 76.431305 -286.323496) (xy 76.447193 -286.274597) (xy 76.470536 -286.228785) (xy 76.500757 -286.187189)
			(xy 76.537113 -286.150833) (xy 76.578709 -286.120612) (xy 76.624521 -286.097269) (xy 76.67342 -286.081381)
			(xy 76.724202 -286.073338) (xy 76.775618 -286.073338) (xy 76.8264 -286.081381) (xy 76.875299 -286.097269)
			(xy 76.921111 -286.120612) (xy 76.962707 -286.150833) (xy 76.999063 -286.187189) (xy 77.029284 -286.228785)
			(xy 77.052627 -286.274597) (xy 77.068515 -286.323496) (xy 77.076558 -286.374278) (xy 77.077062 -286.399986)
			(xy 77.076558 -286.425694) (xy 77.373222 -286.425694) (xy 77.373222 -286.374278) (xy 77.381265 -286.323496)
			(xy 77.397153 -286.274597) (xy 77.420496 -286.228785) (xy 77.450717 -286.187189) (xy 77.487073 -286.150833)
			(xy 77.528669 -286.120612) (xy 77.574481 -286.097269) (xy 77.62338 -286.081381) (xy 77.674162 -286.073338)
			(xy 77.725578 -286.073338) (xy 77.77636 -286.081381) (xy 77.825259 -286.097269) (xy 77.871071 -286.120612)
			(xy 77.912667 -286.150833) (xy 77.949023 -286.187189) (xy 77.979244 -286.228785) (xy 78.002587 -286.274597)
			(xy 78.018475 -286.323496) (xy 78.026518 -286.374278) (xy 78.027017 -286.399732) (xy 78.344026 -286.399732)
			(xy 78.347986 -286.350678) (xy 78.359763 -286.302894) (xy 78.379054 -286.257618) (xy 78.405357 -286.216022)
			(xy 78.437992 -286.179185) (xy 78.476113 -286.14806) (xy 78.518734 -286.123453) (xy 78.56475 -286.106001)
			(xy 78.612969 -286.096157) (xy 78.662144 -286.094176) (xy 78.710999 -286.100108) (xy 78.75827 -286.1138)
			(xy 78.802732 -286.134898) (xy 78.843235 -286.162854) (xy 78.878728 -286.196946) (xy 78.908293 -286.23629)
			(xy 78.931164 -286.279867) (xy 78.946748 -286.326548) (xy 78.954643 -286.375125) (xy 78.955138 -286.399732)
			(xy 78.954643 -286.424339) (xy 78.954464 -286.42544) (xy 79.273142 -286.42544) (xy 79.273142 -286.374024)
			(xy 79.281185 -286.323242) (xy 79.297073 -286.274343) (xy 79.320416 -286.228531) (xy 79.350637 -286.186935)
			(xy 79.386993 -286.150579) (xy 79.428589 -286.120358) (xy 79.474401 -286.097015) (xy 79.5233 -286.081127)
			(xy 79.574082 -286.073084) (xy 79.625498 -286.073084) (xy 79.67628 -286.081127) (xy 79.725179 -286.097015)
			(xy 79.770991 -286.120358) (xy 79.812587 -286.150579) (xy 79.848943 -286.186935) (xy 79.879164 -286.228531)
			(xy 79.902507 -286.274343) (xy 79.918395 -286.323242) (xy 79.926438 -286.374024) (xy 79.926942 -286.399732)
			(xy 79.926438 -286.42544) (xy 80.223102 -286.42544) (xy 80.223102 -286.374024) (xy 80.231145 -286.323242)
			(xy 80.247033 -286.274343) (xy 80.270376 -286.228531) (xy 80.300597 -286.186935) (xy 80.336953 -286.150579)
			(xy 80.378549 -286.120358) (xy 80.424361 -286.097015) (xy 80.47326 -286.081127) (xy 80.524042 -286.073084)
			(xy 80.575458 -286.073084) (xy 80.62624 -286.081127) (xy 80.675139 -286.097015) (xy 80.720951 -286.120358)
			(xy 80.762547 -286.150579) (xy 80.798903 -286.186935) (xy 80.829124 -286.228531) (xy 80.852467 -286.274343)
			(xy 80.868355 -286.323242) (xy 80.876398 -286.374024) (xy 80.876902 -286.399732) (xy 81.19416 -286.399732)
			(xy 81.19812 -286.350678) (xy 81.209897 -286.302894) (xy 81.229188 -286.257618) (xy 81.255491 -286.216022)
			(xy 81.288126 -286.179185) (xy 81.326247 -286.14806) (xy 81.368868 -286.123453) (xy 81.414884 -286.106001)
			(xy 81.463103 -286.096157) (xy 81.512278 -286.094176) (xy 81.561133 -286.100108) (xy 81.608404 -286.1138)
			(xy 81.652866 -286.134898) (xy 81.693369 -286.162854) (xy 81.728862 -286.196946) (xy 81.758427 -286.23629)
			(xy 81.781298 -286.279867) (xy 81.796882 -286.326548) (xy 81.804777 -286.375125) (xy 81.805272 -286.399732)
			(xy 82.14412 -286.399732) (xy 82.14808 -286.350678) (xy 82.159857 -286.302894) (xy 82.179148 -286.257618)
			(xy 82.205451 -286.216022) (xy 82.238086 -286.179185) (xy 82.276207 -286.14806) (xy 82.318828 -286.123453)
			(xy 82.364844 -286.106001) (xy 82.413063 -286.096157) (xy 82.462238 -286.094176) (xy 82.511093 -286.100108)
			(xy 82.558364 -286.1138) (xy 82.602826 -286.134898) (xy 82.643329 -286.162854) (xy 82.678822 -286.196946)
			(xy 82.708387 -286.23629) (xy 82.731258 -286.279867) (xy 82.746842 -286.326548) (xy 82.754737 -286.375125)
			(xy 82.755232 -286.399732) (xy 82.754737 -286.424339) (xy 82.746842 -286.472916) (xy 82.731258 -286.519597)
			(xy 82.708387 -286.563174) (xy 82.678822 -286.602518) (xy 82.643329 -286.63661) (xy 82.602826 -286.664566)
			(xy 82.558364 -286.685664) (xy 82.511093 -286.699356) (xy 82.462238 -286.705288) (xy 82.413063 -286.703307)
			(xy 82.364844 -286.693463) (xy 82.318828 -286.676011) (xy 82.276207 -286.651404) (xy 82.238086 -286.620279)
			(xy 82.205451 -286.583442) (xy 82.179148 -286.541846) (xy 82.159857 -286.49657) (xy 82.14808 -286.448786)
			(xy 82.14412 -286.399732) (xy 81.805272 -286.399732) (xy 81.804777 -286.424339) (xy 81.796882 -286.472916)
			(xy 81.781298 -286.519597) (xy 81.758427 -286.563174) (xy 81.728862 -286.602518) (xy 81.693369 -286.63661)
			(xy 81.652866 -286.664566) (xy 81.608404 -286.685664) (xy 81.561133 -286.699356) (xy 81.512278 -286.705288)
			(xy 81.463103 -286.703307) (xy 81.414884 -286.693463) (xy 81.368868 -286.676011) (xy 81.326247 -286.651404)
			(xy 81.288126 -286.620279) (xy 81.255491 -286.583442) (xy 81.229188 -286.541846) (xy 81.209897 -286.49657)
			(xy 81.19812 -286.448786) (xy 81.19416 -286.399732) (xy 80.876902 -286.399732) (xy 80.876398 -286.42544)
			(xy 80.868355 -286.476222) (xy 80.852467 -286.525121) (xy 80.829124 -286.570933) (xy 80.798903 -286.612529)
			(xy 80.762547 -286.648885) (xy 80.720951 -286.679106) (xy 80.675139 -286.702449) (xy 80.62624 -286.718337)
			(xy 80.575458 -286.72638) (xy 80.524042 -286.72638) (xy 80.47326 -286.718337) (xy 80.424361 -286.702449)
			(xy 80.378549 -286.679106) (xy 80.336953 -286.648885) (xy 80.300597 -286.612529) (xy 80.270376 -286.570933)
			(xy 80.247033 -286.525121) (xy 80.231145 -286.476222) (xy 80.223102 -286.42544) (xy 79.926438 -286.42544)
			(xy 79.918395 -286.476222) (xy 79.902507 -286.525121) (xy 79.879164 -286.570933) (xy 79.848943 -286.612529)
			(xy 79.812587 -286.648885) (xy 79.770991 -286.679106) (xy 79.725179 -286.702449) (xy 79.67628 -286.718337)
			(xy 79.625498 -286.72638) (xy 79.574082 -286.72638) (xy 79.5233 -286.718337) (xy 79.474401 -286.702449)
			(xy 79.428589 -286.679106) (xy 79.386993 -286.648885) (xy 79.350637 -286.612529) (xy 79.320416 -286.570933)
			(xy 79.297073 -286.525121) (xy 79.281185 -286.476222) (xy 79.273142 -286.42544) (xy 78.954464 -286.42544)
			(xy 78.946748 -286.472916) (xy 78.931164 -286.519597) (xy 78.908293 -286.563174) (xy 78.878728 -286.602518)
			(xy 78.843235 -286.63661) (xy 78.802732 -286.664566) (xy 78.75827 -286.685664) (xy 78.710999 -286.699356)
			(xy 78.662144 -286.705288) (xy 78.612969 -286.703307) (xy 78.56475 -286.693463) (xy 78.518734 -286.676011)
			(xy 78.476113 -286.651404) (xy 78.437992 -286.620279) (xy 78.405357 -286.583442) (xy 78.379054 -286.541846)
			(xy 78.359763 -286.49657) (xy 78.347986 -286.448786) (xy 78.344026 -286.399732) (xy 78.027017 -286.399732)
			(xy 78.027022 -286.399986) (xy 78.026518 -286.425694) (xy 78.018475 -286.476476) (xy 78.002587 -286.525375)
			(xy 77.979244 -286.571187) (xy 77.949023 -286.612783) (xy 77.912667 -286.649139) (xy 77.871071 -286.67936)
			(xy 77.825259 -286.702703) (xy 77.77636 -286.718591) (xy 77.725578 -286.726634) (xy 77.674162 -286.726634)
			(xy 77.62338 -286.718591) (xy 77.574481 -286.702703) (xy 77.528669 -286.67936) (xy 77.487073 -286.649139)
			(xy 77.450717 -286.612783) (xy 77.420496 -286.571187) (xy 77.397153 -286.525375) (xy 77.381265 -286.476476)
			(xy 77.373222 -286.425694) (xy 77.076558 -286.425694) (xy 77.068515 -286.476476) (xy 77.052627 -286.525375)
			(xy 77.029284 -286.571187) (xy 76.999063 -286.612783) (xy 76.962707 -286.649139) (xy 76.921111 -286.67936)
			(xy 76.875299 -286.702703) (xy 76.8264 -286.718591) (xy 76.775618 -286.726634) (xy 76.724202 -286.726634)
			(xy 76.67342 -286.718591) (xy 76.624521 -286.702703) (xy 76.578709 -286.67936) (xy 76.537113 -286.649139)
			(xy 76.500757 -286.612783) (xy 76.470536 -286.571187) (xy 76.447193 -286.525375) (xy 76.431305 -286.476476)
			(xy 76.423262 -286.425694) (xy 76.104543 -286.425694) (xy 76.096868 -286.472916) (xy 76.081284 -286.519597)
			(xy 76.058413 -286.563174) (xy 76.028848 -286.602518) (xy 75.993355 -286.63661) (xy 75.952852 -286.664566)
			(xy 75.90839 -286.685664) (xy 75.861119 -286.699356) (xy 75.812264 -286.705288) (xy 75.763089 -286.703307)
			(xy 75.71487 -286.693463) (xy 75.668854 -286.676011) (xy 75.626233 -286.651404) (xy 75.588112 -286.620279)
			(xy 75.555477 -286.583442) (xy 75.529174 -286.541846) (xy 75.509883 -286.49657) (xy 75.498106 -286.448786)
			(xy 75.494146 -286.399732) (xy 75.155298 -286.399732) (xy 75.154803 -286.424339) (xy 75.146908 -286.472916)
			(xy 75.131324 -286.519597) (xy 75.108453 -286.563174) (xy 75.078888 -286.602518) (xy 75.043395 -286.63661)
			(xy 75.002892 -286.664566) (xy 74.95843 -286.685664) (xy 74.911159 -286.699356) (xy 74.862304 -286.705288)
			(xy 74.813129 -286.703307) (xy 74.76491 -286.693463) (xy 74.718894 -286.676011) (xy 74.676273 -286.651404)
			(xy 74.638152 -286.620279) (xy 74.605517 -286.583442) (xy 74.579214 -286.541846) (xy 74.559923 -286.49657)
			(xy 74.548146 -286.448786) (xy 74.544186 -286.399732) (xy 74.205084 -286.399732) (xy 74.204589 -286.424339)
			(xy 74.196694 -286.472916) (xy 74.18111 -286.519597) (xy 74.158239 -286.563174) (xy 74.128674 -286.602518)
			(xy 74.093181 -286.63661) (xy 74.052678 -286.664566) (xy 74.008216 -286.685664) (xy 73.960945 -286.699356)
			(xy 73.91209 -286.705288) (xy 73.862915 -286.703307) (xy 73.814696 -286.693463) (xy 73.76868 -286.676011)
			(xy 73.726059 -286.651404) (xy 73.687938 -286.620279) (xy 73.655303 -286.583442) (xy 73.629 -286.541846)
			(xy 73.609709 -286.49657) (xy 73.597932 -286.448786) (xy 73.593972 -286.399732) (xy 49.181004 -286.399732)
			(xy 49.181004 -286.874966) (xy 49.368976 -286.874966) (xy 49.372936 -286.825912) (xy 49.384713 -286.778128)
			(xy 49.404004 -286.732852) (xy 49.430307 -286.691256) (xy 49.462942 -286.654419) (xy 49.501063 -286.623294)
			(xy 49.543684 -286.598687) (xy 49.5897 -286.581235) (xy 49.637919 -286.571391) (xy 49.687094 -286.56941)
			(xy 49.735949 -286.575342) (xy 49.78322 -286.589034) (xy 49.827682 -286.610132) (xy 49.868185 -286.638088)
			(xy 49.903678 -286.67218) (xy 49.933243 -286.711524) (xy 49.956114 -286.755101) (xy 49.971698 -286.801782)
			(xy 49.979593 -286.850359) (xy 49.980088 -286.874966) (xy 50.31919 -286.874966) (xy 50.32315 -286.825912)
			(xy 50.334927 -286.778128) (xy 50.354218 -286.732852) (xy 50.380521 -286.691256) (xy 50.413156 -286.654419)
			(xy 50.451277 -286.623294) (xy 50.493898 -286.598687) (xy 50.539914 -286.581235) (xy 50.588133 -286.571391)
			(xy 50.637308 -286.56941) (xy 50.686163 -286.575342) (xy 50.733434 -286.589034) (xy 50.777896 -286.610132)
			(xy 50.818399 -286.638088) (xy 50.853892 -286.67218) (xy 50.883457 -286.711524) (xy 50.906328 -286.755101)
			(xy 50.921912 -286.801782) (xy 50.929807 -286.850359) (xy 50.930302 -286.874966) (xy 51.26915 -286.874966)
			(xy 51.27311 -286.825912) (xy 51.284887 -286.778128) (xy 51.304178 -286.732852) (xy 51.330481 -286.691256)
			(xy 51.363116 -286.654419) (xy 51.401237 -286.623294) (xy 51.443858 -286.598687) (xy 51.489874 -286.581235)
			(xy 51.538093 -286.571391) (xy 51.587268 -286.56941) (xy 51.636123 -286.575342) (xy 51.683394 -286.589034)
			(xy 51.727856 -286.610132) (xy 51.768359 -286.638088) (xy 51.803852 -286.67218) (xy 51.833417 -286.711524)
			(xy 51.856288 -286.755101) (xy 51.871872 -286.801782) (xy 51.879767 -286.850359) (xy 51.880262 -286.874966)
			(xy 52.21911 -286.874966) (xy 52.22307 -286.825912) (xy 52.234847 -286.778128) (xy 52.254138 -286.732852)
			(xy 52.280441 -286.691256) (xy 52.313076 -286.654419) (xy 52.351197 -286.623294) (xy 52.393818 -286.598687)
			(xy 52.439834 -286.581235) (xy 52.488053 -286.571391) (xy 52.537228 -286.56941) (xy 52.586083 -286.575342)
			(xy 52.633354 -286.589034) (xy 52.677816 -286.610132) (xy 52.718319 -286.638088) (xy 52.753812 -286.67218)
			(xy 52.783377 -286.711524) (xy 52.806248 -286.755101) (xy 52.821832 -286.801782) (xy 52.829727 -286.850359)
			(xy 52.830222 -286.874966) (xy 53.16907 -286.874966) (xy 53.17303 -286.825912) (xy 53.184807 -286.778128)
			(xy 53.204098 -286.732852) (xy 53.230401 -286.691256) (xy 53.263036 -286.654419) (xy 53.301157 -286.623294)
			(xy 53.343778 -286.598687) (xy 53.389794 -286.581235) (xy 53.438013 -286.571391) (xy 53.487188 -286.56941)
			(xy 53.536043 -286.575342) (xy 53.583314 -286.589034) (xy 53.627776 -286.610132) (xy 53.668279 -286.638088)
			(xy 53.703772 -286.67218) (xy 53.733337 -286.711524) (xy 53.756208 -286.755101) (xy 53.771792 -286.801782)
			(xy 53.779687 -286.850359) (xy 53.780182 -286.874966) (xy 54.11903 -286.874966) (xy 54.12299 -286.825912)
			(xy 54.134767 -286.778128) (xy 54.154058 -286.732852) (xy 54.180361 -286.691256) (xy 54.212996 -286.654419)
			(xy 54.251117 -286.623294) (xy 54.293738 -286.598687) (xy 54.339754 -286.581235) (xy 54.387973 -286.571391)
			(xy 54.437148 -286.56941) (xy 54.486003 -286.575342) (xy 54.533274 -286.589034) (xy 54.577736 -286.610132)
			(xy 54.618239 -286.638088) (xy 54.653732 -286.67218) (xy 54.683297 -286.711524) (xy 54.706168 -286.755101)
			(xy 54.721752 -286.801782) (xy 54.729647 -286.850359) (xy 54.730142 -286.874966) (xy 55.06899 -286.874966)
			(xy 55.07295 -286.825912) (xy 55.084727 -286.778128) (xy 55.104018 -286.732852) (xy 55.130321 -286.691256)
			(xy 55.162956 -286.654419) (xy 55.201077 -286.623294) (xy 55.243698 -286.598687) (xy 55.289714 -286.581235)
			(xy 55.337933 -286.571391) (xy 55.387108 -286.56941) (xy 55.435963 -286.575342) (xy 55.483234 -286.589034)
			(xy 55.527696 -286.610132) (xy 55.568199 -286.638088) (xy 55.603692 -286.67218) (xy 55.633257 -286.711524)
			(xy 55.656128 -286.755101) (xy 55.671712 -286.801782) (xy 55.679607 -286.850359) (xy 55.680102 -286.874966)
			(xy 56.01895 -286.874966) (xy 56.02291 -286.825912) (xy 56.034687 -286.778128) (xy 56.053978 -286.732852)
			(xy 56.080281 -286.691256) (xy 56.112916 -286.654419) (xy 56.151037 -286.623294) (xy 56.193658 -286.598687)
			(xy 56.239674 -286.581235) (xy 56.287893 -286.571391) (xy 56.337068 -286.56941) (xy 56.385923 -286.575342)
			(xy 56.433194 -286.589034) (xy 56.477656 -286.610132) (xy 56.518159 -286.638088) (xy 56.553652 -286.67218)
			(xy 56.583217 -286.711524) (xy 56.606088 -286.755101) (xy 56.621672 -286.801782) (xy 56.629567 -286.850359)
			(xy 56.630062 -286.874966) (xy 56.969164 -286.874966) (xy 56.973124 -286.825912) (xy 56.984901 -286.778128)
			(xy 57.004192 -286.732852) (xy 57.030495 -286.691256) (xy 57.06313 -286.654419) (xy 57.101251 -286.623294)
			(xy 57.143872 -286.598687) (xy 57.189888 -286.581235) (xy 57.238107 -286.571391) (xy 57.287282 -286.56941)
			(xy 57.336137 -286.575342) (xy 57.383408 -286.589034) (xy 57.42787 -286.610132) (xy 57.468373 -286.638088)
			(xy 57.503866 -286.67218) (xy 57.533431 -286.711524) (xy 57.556302 -286.755101) (xy 57.571886 -286.801782)
			(xy 57.579781 -286.850359) (xy 57.580276 -286.874966) (xy 57.919124 -286.874966) (xy 57.923084 -286.825912)
			(xy 57.934861 -286.778128) (xy 57.954152 -286.732852) (xy 57.980455 -286.691256) (xy 58.01309 -286.654419)
			(xy 58.051211 -286.623294) (xy 58.093832 -286.598687) (xy 58.139848 -286.581235) (xy 58.188067 -286.571391)
			(xy 58.237242 -286.56941) (xy 58.286097 -286.575342) (xy 58.333368 -286.589034) (xy 58.37783 -286.610132)
			(xy 58.418333 -286.638088) (xy 58.453826 -286.67218) (xy 58.483391 -286.711524) (xy 58.506262 -286.755101)
			(xy 58.521846 -286.801782) (xy 58.529741 -286.850359) (xy 58.530236 -286.874966) (xy 59.819044 -286.874966)
			(xy 59.823004 -286.825912) (xy 59.834781 -286.778128) (xy 59.854072 -286.732852) (xy 59.880375 -286.691256)
			(xy 59.91301 -286.654419) (xy 59.951131 -286.623294) (xy 59.993752 -286.598687) (xy 60.039768 -286.581235)
			(xy 60.087987 -286.571391) (xy 60.137162 -286.56941) (xy 60.186017 -286.575342) (xy 60.233288 -286.589034)
			(xy 60.27775 -286.610132) (xy 60.318253 -286.638088) (xy 60.353746 -286.67218) (xy 60.383311 -286.711524)
			(xy 60.406182 -286.755101) (xy 60.421766 -286.801782) (xy 60.429661 -286.850359) (xy 60.430156 -286.874966)
			(xy 60.769004 -286.874966) (xy 60.772964 -286.825912) (xy 60.784741 -286.778128) (xy 60.804032 -286.732852)
			(xy 60.830335 -286.691256) (xy 60.86297 -286.654419) (xy 60.901091 -286.623294) (xy 60.943712 -286.598687)
			(xy 60.989728 -286.581235) (xy 61.037947 -286.571391) (xy 61.087122 -286.56941) (xy 61.135977 -286.575342)
			(xy 61.183248 -286.589034) (xy 61.22771 -286.610132) (xy 61.268213 -286.638088) (xy 61.303706 -286.67218)
			(xy 61.333271 -286.711524) (xy 61.356142 -286.755101) (xy 61.371726 -286.801782) (xy 61.379621 -286.850359)
			(xy 61.380116 -286.874966) (xy 61.718964 -286.874966) (xy 61.722924 -286.825912) (xy 61.734701 -286.778128)
			(xy 61.753992 -286.732852) (xy 61.780295 -286.691256) (xy 61.81293 -286.654419) (xy 61.851051 -286.623294)
			(xy 61.893672 -286.598687) (xy 61.939688 -286.581235) (xy 61.987907 -286.571391) (xy 62.037082 -286.56941)
			(xy 62.085937 -286.575342) (xy 62.133208 -286.589034) (xy 62.17767 -286.610132) (xy 62.218173 -286.638088)
			(xy 62.253666 -286.67218) (xy 62.283231 -286.711524) (xy 62.306102 -286.755101) (xy 62.321686 -286.801782)
			(xy 62.329581 -286.850359) (xy 62.330076 -286.874966) (xy 62.669178 -286.874966) (xy 62.673138 -286.825912)
			(xy 62.684915 -286.778128) (xy 62.704206 -286.732852) (xy 62.730509 -286.691256) (xy 62.763144 -286.654419)
			(xy 62.801265 -286.623294) (xy 62.843886 -286.598687) (xy 62.889902 -286.581235) (xy 62.938121 -286.571391)
			(xy 62.987296 -286.56941) (xy 63.036151 -286.575342) (xy 63.083422 -286.589034) (xy 63.127884 -286.610132)
			(xy 63.168387 -286.638088) (xy 63.20388 -286.67218) (xy 63.233445 -286.711524) (xy 63.256316 -286.755101)
			(xy 63.2719 -286.801782) (xy 63.279795 -286.850359) (xy 63.28029 -286.874966) (xy 63.619138 -286.874966)
			(xy 63.623098 -286.825912) (xy 63.634875 -286.778128) (xy 63.654166 -286.732852) (xy 63.680469 -286.691256)
			(xy 63.713104 -286.654419) (xy 63.751225 -286.623294) (xy 63.793846 -286.598687) (xy 63.839862 -286.581235)
			(xy 63.888081 -286.571391) (xy 63.937256 -286.56941) (xy 63.986111 -286.575342) (xy 64.033382 -286.589034)
			(xy 64.077844 -286.610132) (xy 64.118347 -286.638088) (xy 64.15384 -286.67218) (xy 64.183405 -286.711524)
			(xy 64.206276 -286.755101) (xy 64.22186 -286.801782) (xy 64.229755 -286.850359) (xy 64.23025 -286.874966)
			(xy 64.569098 -286.874966) (xy 64.573058 -286.825912) (xy 64.584835 -286.778128) (xy 64.604126 -286.732852)
			(xy 64.630429 -286.691256) (xy 64.663064 -286.654419) (xy 64.701185 -286.623294) (xy 64.743806 -286.598687)
			(xy 64.789822 -286.581235) (xy 64.838041 -286.571391) (xy 64.887216 -286.56941) (xy 64.936071 -286.575342)
			(xy 64.983342 -286.589034) (xy 65.027804 -286.610132) (xy 65.068307 -286.638088) (xy 65.1038 -286.67218)
			(xy 65.133365 -286.711524) (xy 65.156236 -286.755101) (xy 65.17182 -286.801782) (xy 65.179715 -286.850359)
			(xy 65.18021 -286.874966) (xy 65.519058 -286.874966) (xy 65.523018 -286.825912) (xy 65.534795 -286.778128)
			(xy 65.554086 -286.732852) (xy 65.580389 -286.691256) (xy 65.613024 -286.654419) (xy 65.651145 -286.623294)
			(xy 65.693766 -286.598687) (xy 65.739782 -286.581235) (xy 65.788001 -286.571391) (xy 65.837176 -286.56941)
			(xy 65.886031 -286.575342) (xy 65.933302 -286.589034) (xy 65.977764 -286.610132) (xy 66.018267 -286.638088)
			(xy 66.05376 -286.67218) (xy 66.083325 -286.711524) (xy 66.106196 -286.755101) (xy 66.12178 -286.801782)
			(xy 66.129675 -286.850359) (xy 66.13017 -286.874966) (xy 66.469018 -286.874966) (xy 66.472978 -286.825912)
			(xy 66.484755 -286.778128) (xy 66.504046 -286.732852) (xy 66.530349 -286.691256) (xy 66.562984 -286.654419)
			(xy 66.601105 -286.623294) (xy 66.643726 -286.598687) (xy 66.689742 -286.581235) (xy 66.737961 -286.571391)
			(xy 66.787136 -286.56941) (xy 66.835991 -286.575342) (xy 66.883262 -286.589034) (xy 66.927724 -286.610132)
			(xy 66.968227 -286.638088) (xy 67.00372 -286.67218) (xy 67.033285 -286.711524) (xy 67.056156 -286.755101)
			(xy 67.07174 -286.801782) (xy 67.079635 -286.850359) (xy 67.08013 -286.874966) (xy 67.418978 -286.874966)
			(xy 67.422938 -286.825912) (xy 67.434715 -286.778128) (xy 67.454006 -286.732852) (xy 67.480309 -286.691256)
			(xy 67.512944 -286.654419) (xy 67.551065 -286.623294) (xy 67.593686 -286.598687) (xy 67.639702 -286.581235)
			(xy 67.687921 -286.571391) (xy 67.737096 -286.56941) (xy 67.785951 -286.575342) (xy 67.833222 -286.589034)
			(xy 67.877684 -286.610132) (xy 67.918187 -286.638088) (xy 67.95368 -286.67218) (xy 67.983245 -286.711524)
			(xy 68.006116 -286.755101) (xy 68.0217 -286.801782) (xy 68.029595 -286.850359) (xy 68.03009 -286.874966)
			(xy 68.368938 -286.874966) (xy 68.372898 -286.825912) (xy 68.384675 -286.778128) (xy 68.403966 -286.732852)
			(xy 68.430269 -286.691256) (xy 68.462904 -286.654419) (xy 68.501025 -286.623294) (xy 68.543646 -286.598687)
			(xy 68.589662 -286.581235) (xy 68.637881 -286.571391) (xy 68.687056 -286.56941) (xy 68.735911 -286.575342)
			(xy 68.783182 -286.589034) (xy 68.827644 -286.610132) (xy 68.868147 -286.638088) (xy 68.90364 -286.67218)
			(xy 68.933205 -286.711524) (xy 68.956076 -286.755101) (xy 68.97166 -286.801782) (xy 68.979555 -286.850359)
			(xy 68.98005 -286.874966) (xy 69.319152 -286.874966) (xy 69.323112 -286.825912) (xy 69.334889 -286.778128)
			(xy 69.35418 -286.732852) (xy 69.380483 -286.691256) (xy 69.413118 -286.654419) (xy 69.451239 -286.623294)
			(xy 69.49386 -286.598687) (xy 69.539876 -286.581235) (xy 69.588095 -286.571391) (xy 69.63727 -286.56941)
			(xy 69.686125 -286.575342) (xy 69.733396 -286.589034) (xy 69.777858 -286.610132) (xy 69.818361 -286.638088)
			(xy 69.853854 -286.67218) (xy 69.883419 -286.711524) (xy 69.90629 -286.755101) (xy 69.921874 -286.801782)
			(xy 69.929769 -286.850359) (xy 69.930264 -286.874966) (xy 70.269112 -286.874966) (xy 70.273072 -286.825912)
			(xy 70.284849 -286.778128) (xy 70.30414 -286.732852) (xy 70.330443 -286.691256) (xy 70.363078 -286.654419)
			(xy 70.401199 -286.623294) (xy 70.44382 -286.598687) (xy 70.489836 -286.581235) (xy 70.538055 -286.571391)
			(xy 70.58723 -286.56941) (xy 70.636085 -286.575342) (xy 70.683356 -286.589034) (xy 70.727818 -286.610132)
			(xy 70.768321 -286.638088) (xy 70.803814 -286.67218) (xy 70.833379 -286.711524) (xy 70.85625 -286.755101)
			(xy 70.871834 -286.801782) (xy 70.879729 -286.850359) (xy 70.880224 -286.874966) (xy 70.879729 -286.899573)
			(xy 70.871834 -286.94815) (xy 70.85625 -286.994831) (xy 70.833379 -287.038408) (xy 70.803814 -287.077752)
			(xy 70.768321 -287.111844) (xy 70.727818 -287.1398) (xy 70.683356 -287.160898) (xy 70.636085 -287.17459)
			(xy 70.58723 -287.180522) (xy 70.538055 -287.178541) (xy 70.489836 -287.168697) (xy 70.44382 -287.151245)
			(xy 70.401199 -287.126638) (xy 70.363078 -287.095513) (xy 70.330443 -287.058676) (xy 70.30414 -287.01708)
			(xy 70.284849 -286.971804) (xy 70.273072 -286.92402) (xy 70.269112 -286.874966) (xy 69.930264 -286.874966)
			(xy 69.929769 -286.899573) (xy 69.921874 -286.94815) (xy 69.90629 -286.994831) (xy 69.883419 -287.038408)
			(xy 69.853854 -287.077752) (xy 69.818361 -287.111844) (xy 69.777858 -287.1398) (xy 69.733396 -287.160898)
			(xy 69.686125 -287.17459) (xy 69.63727 -287.180522) (xy 69.588095 -287.178541) (xy 69.539876 -287.168697)
			(xy 69.49386 -287.151245) (xy 69.451239 -287.126638) (xy 69.413118 -287.095513) (xy 69.380483 -287.058676)
			(xy 69.35418 -287.01708) (xy 69.334889 -286.971804) (xy 69.323112 -286.92402) (xy 69.319152 -286.874966)
			(xy 68.98005 -286.874966) (xy 68.979555 -286.899573) (xy 68.97166 -286.94815) (xy 68.956076 -286.994831)
			(xy 68.933205 -287.038408) (xy 68.90364 -287.077752) (xy 68.868147 -287.111844) (xy 68.827644 -287.1398)
			(xy 68.783182 -287.160898) (xy 68.735911 -287.17459) (xy 68.687056 -287.180522) (xy 68.637881 -287.178541)
			(xy 68.589662 -287.168697) (xy 68.543646 -287.151245) (xy 68.501025 -287.126638) (xy 68.462904 -287.095513)
			(xy 68.430269 -287.058676) (xy 68.403966 -287.01708) (xy 68.384675 -286.971804) (xy 68.372898 -286.92402)
			(xy 68.368938 -286.874966) (xy 68.03009 -286.874966) (xy 68.029595 -286.899573) (xy 68.0217 -286.94815)
			(xy 68.006116 -286.994831) (xy 67.983245 -287.038408) (xy 67.95368 -287.077752) (xy 67.918187 -287.111844)
			(xy 67.877684 -287.1398) (xy 67.833222 -287.160898) (xy 67.785951 -287.17459) (xy 67.737096 -287.180522)
			(xy 67.687921 -287.178541) (xy 67.639702 -287.168697) (xy 67.593686 -287.151245) (xy 67.551065 -287.126638)
			(xy 67.512944 -287.095513) (xy 67.480309 -287.058676) (xy 67.454006 -287.01708) (xy 67.434715 -286.971804)
			(xy 67.422938 -286.92402) (xy 67.418978 -286.874966) (xy 67.08013 -286.874966) (xy 67.079635 -286.899573)
			(xy 67.07174 -286.94815) (xy 67.056156 -286.994831) (xy 67.033285 -287.038408) (xy 67.00372 -287.077752)
			(xy 66.968227 -287.111844) (xy 66.927724 -287.1398) (xy 66.883262 -287.160898) (xy 66.835991 -287.17459)
			(xy 66.787136 -287.180522) (xy 66.737961 -287.178541) (xy 66.689742 -287.168697) (xy 66.643726 -287.151245)
			(xy 66.601105 -287.126638) (xy 66.562984 -287.095513) (xy 66.530349 -287.058676) (xy 66.504046 -287.01708)
			(xy 66.484755 -286.971804) (xy 66.472978 -286.92402) (xy 66.469018 -286.874966) (xy 66.13017 -286.874966)
			(xy 66.129675 -286.899573) (xy 66.12178 -286.94815) (xy 66.106196 -286.994831) (xy 66.083325 -287.038408)
			(xy 66.05376 -287.077752) (xy 66.018267 -287.111844) (xy 65.977764 -287.1398) (xy 65.933302 -287.160898)
			(xy 65.886031 -287.17459) (xy 65.837176 -287.180522) (xy 65.788001 -287.178541) (xy 65.739782 -287.168697)
			(xy 65.693766 -287.151245) (xy 65.651145 -287.126638) (xy 65.613024 -287.095513) (xy 65.580389 -287.058676)
			(xy 65.554086 -287.01708) (xy 65.534795 -286.971804) (xy 65.523018 -286.92402) (xy 65.519058 -286.874966)
			(xy 65.18021 -286.874966) (xy 65.179715 -286.899573) (xy 65.17182 -286.94815) (xy 65.156236 -286.994831)
			(xy 65.133365 -287.038408) (xy 65.1038 -287.077752) (xy 65.068307 -287.111844) (xy 65.027804 -287.1398)
			(xy 64.983342 -287.160898) (xy 64.936071 -287.17459) (xy 64.887216 -287.180522) (xy 64.838041 -287.178541)
			(xy 64.789822 -287.168697) (xy 64.743806 -287.151245) (xy 64.701185 -287.126638) (xy 64.663064 -287.095513)
			(xy 64.630429 -287.058676) (xy 64.604126 -287.01708) (xy 64.584835 -286.971804) (xy 64.573058 -286.92402)
			(xy 64.569098 -286.874966) (xy 64.23025 -286.874966) (xy 64.229755 -286.899573) (xy 64.22186 -286.94815)
			(xy 64.206276 -286.994831) (xy 64.183405 -287.038408) (xy 64.15384 -287.077752) (xy 64.118347 -287.111844)
			(xy 64.077844 -287.1398) (xy 64.033382 -287.160898) (xy 63.986111 -287.17459) (xy 63.937256 -287.180522)
			(xy 63.888081 -287.178541) (xy 63.839862 -287.168697) (xy 63.793846 -287.151245) (xy 63.751225 -287.126638)
			(xy 63.713104 -287.095513) (xy 63.680469 -287.058676) (xy 63.654166 -287.01708) (xy 63.634875 -286.971804)
			(xy 63.623098 -286.92402) (xy 63.619138 -286.874966) (xy 63.28029 -286.874966) (xy 63.279795 -286.899573)
			(xy 63.2719 -286.94815) (xy 63.256316 -286.994831) (xy 63.233445 -287.038408) (xy 63.20388 -287.077752)
			(xy 63.168387 -287.111844) (xy 63.127884 -287.1398) (xy 63.083422 -287.160898) (xy 63.036151 -287.17459)
			(xy 62.987296 -287.180522) (xy 62.938121 -287.178541) (xy 62.889902 -287.168697) (xy 62.843886 -287.151245)
			(xy 62.801265 -287.126638) (xy 62.763144 -287.095513) (xy 62.730509 -287.058676) (xy 62.704206 -287.01708)
			(xy 62.684915 -286.971804) (xy 62.673138 -286.92402) (xy 62.669178 -286.874966) (xy 62.330076 -286.874966)
			(xy 62.329581 -286.899573) (xy 62.321686 -286.94815) (xy 62.306102 -286.994831) (xy 62.283231 -287.038408)
			(xy 62.253666 -287.077752) (xy 62.218173 -287.111844) (xy 62.17767 -287.1398) (xy 62.133208 -287.160898)
			(xy 62.085937 -287.17459) (xy 62.037082 -287.180522) (xy 61.987907 -287.178541) (xy 61.939688 -287.168697)
			(xy 61.893672 -287.151245) (xy 61.851051 -287.126638) (xy 61.81293 -287.095513) (xy 61.780295 -287.058676)
			(xy 61.753992 -287.01708) (xy 61.734701 -286.971804) (xy 61.722924 -286.92402) (xy 61.718964 -286.874966)
			(xy 61.380116 -286.874966) (xy 61.379621 -286.899573) (xy 61.371726 -286.94815) (xy 61.356142 -286.994831)
			(xy 61.333271 -287.038408) (xy 61.303706 -287.077752) (xy 61.268213 -287.111844) (xy 61.22771 -287.1398)
			(xy 61.183248 -287.160898) (xy 61.135977 -287.17459) (xy 61.087122 -287.180522) (xy 61.037947 -287.178541)
			(xy 60.989728 -287.168697) (xy 60.943712 -287.151245) (xy 60.901091 -287.126638) (xy 60.86297 -287.095513)
			(xy 60.830335 -287.058676) (xy 60.804032 -287.01708) (xy 60.784741 -286.971804) (xy 60.772964 -286.92402)
			(xy 60.769004 -286.874966) (xy 60.430156 -286.874966) (xy 60.429661 -286.899573) (xy 60.421766 -286.94815)
			(xy 60.406182 -286.994831) (xy 60.383311 -287.038408) (xy 60.353746 -287.077752) (xy 60.318253 -287.111844)
			(xy 60.27775 -287.1398) (xy 60.233288 -287.160898) (xy 60.186017 -287.17459) (xy 60.137162 -287.180522)
			(xy 60.087987 -287.178541) (xy 60.039768 -287.168697) (xy 59.993752 -287.151245) (xy 59.951131 -287.126638)
			(xy 59.91301 -287.095513) (xy 59.880375 -287.058676) (xy 59.854072 -287.01708) (xy 59.834781 -286.971804)
			(xy 59.823004 -286.92402) (xy 59.819044 -286.874966) (xy 58.530236 -286.874966) (xy 58.529741 -286.899573)
			(xy 58.521846 -286.94815) (xy 58.506262 -286.994831) (xy 58.483391 -287.038408) (xy 58.453826 -287.077752)
			(xy 58.418333 -287.111844) (xy 58.37783 -287.1398) (xy 58.333368 -287.160898) (xy 58.286097 -287.17459)
			(xy 58.237242 -287.180522) (xy 58.188067 -287.178541) (xy 58.139848 -287.168697) (xy 58.093832 -287.151245)
			(xy 58.051211 -287.126638) (xy 58.01309 -287.095513) (xy 57.980455 -287.058676) (xy 57.954152 -287.01708)
			(xy 57.934861 -286.971804) (xy 57.923084 -286.92402) (xy 57.919124 -286.874966) (xy 57.580276 -286.874966)
			(xy 57.579781 -286.899573) (xy 57.571886 -286.94815) (xy 57.556302 -286.994831) (xy 57.533431 -287.038408)
			(xy 57.503866 -287.077752) (xy 57.468373 -287.111844) (xy 57.42787 -287.1398) (xy 57.383408 -287.160898)
			(xy 57.336137 -287.17459) (xy 57.287282 -287.180522) (xy 57.238107 -287.178541) (xy 57.189888 -287.168697)
			(xy 57.143872 -287.151245) (xy 57.101251 -287.126638) (xy 57.06313 -287.095513) (xy 57.030495 -287.058676)
			(xy 57.004192 -287.01708) (xy 56.984901 -286.971804) (xy 56.973124 -286.92402) (xy 56.969164 -286.874966)
			(xy 56.630062 -286.874966) (xy 56.629567 -286.899573) (xy 56.621672 -286.94815) (xy 56.606088 -286.994831)
			(xy 56.583217 -287.038408) (xy 56.553652 -287.077752) (xy 56.518159 -287.111844) (xy 56.477656 -287.1398)
			(xy 56.433194 -287.160898) (xy 56.385923 -287.17459) (xy 56.337068 -287.180522) (xy 56.287893 -287.178541)
			(xy 56.239674 -287.168697) (xy 56.193658 -287.151245) (xy 56.151037 -287.126638) (xy 56.112916 -287.095513)
			(xy 56.080281 -287.058676) (xy 56.053978 -287.01708) (xy 56.034687 -286.971804) (xy 56.02291 -286.92402)
			(xy 56.01895 -286.874966) (xy 55.680102 -286.874966) (xy 55.679607 -286.899573) (xy 55.671712 -286.94815)
			(xy 55.656128 -286.994831) (xy 55.633257 -287.038408) (xy 55.603692 -287.077752) (xy 55.568199 -287.111844)
			(xy 55.527696 -287.1398) (xy 55.483234 -287.160898) (xy 55.435963 -287.17459) (xy 55.387108 -287.180522)
			(xy 55.337933 -287.178541) (xy 55.289714 -287.168697) (xy 55.243698 -287.151245) (xy 55.201077 -287.126638)
			(xy 55.162956 -287.095513) (xy 55.130321 -287.058676) (xy 55.104018 -287.01708) (xy 55.084727 -286.971804)
			(xy 55.07295 -286.92402) (xy 55.06899 -286.874966) (xy 54.730142 -286.874966) (xy 54.729647 -286.899573)
			(xy 54.721752 -286.94815) (xy 54.706168 -286.994831) (xy 54.683297 -287.038408) (xy 54.653732 -287.077752)
			(xy 54.618239 -287.111844) (xy 54.577736 -287.1398) (xy 54.533274 -287.160898) (xy 54.486003 -287.17459)
			(xy 54.437148 -287.180522) (xy 54.387973 -287.178541) (xy 54.339754 -287.168697) (xy 54.293738 -287.151245)
			(xy 54.251117 -287.126638) (xy 54.212996 -287.095513) (xy 54.180361 -287.058676) (xy 54.154058 -287.01708)
			(xy 54.134767 -286.971804) (xy 54.12299 -286.92402) (xy 54.11903 -286.874966) (xy 53.780182 -286.874966)
			(xy 53.779687 -286.899573) (xy 53.771792 -286.94815) (xy 53.756208 -286.994831) (xy 53.733337 -287.038408)
			(xy 53.703772 -287.077752) (xy 53.668279 -287.111844) (xy 53.627776 -287.1398) (xy 53.583314 -287.160898)
			(xy 53.536043 -287.17459) (xy 53.487188 -287.180522) (xy 53.438013 -287.178541) (xy 53.389794 -287.168697)
			(xy 53.343778 -287.151245) (xy 53.301157 -287.126638) (xy 53.263036 -287.095513) (xy 53.230401 -287.058676)
			(xy 53.204098 -287.01708) (xy 53.184807 -286.971804) (xy 53.17303 -286.92402) (xy 53.16907 -286.874966)
			(xy 52.830222 -286.874966) (xy 52.829727 -286.899573) (xy 52.821832 -286.94815) (xy 52.806248 -286.994831)
			(xy 52.783377 -287.038408) (xy 52.753812 -287.077752) (xy 52.718319 -287.111844) (xy 52.677816 -287.1398)
			(xy 52.633354 -287.160898) (xy 52.586083 -287.17459) (xy 52.537228 -287.180522) (xy 52.488053 -287.178541)
			(xy 52.439834 -287.168697) (xy 52.393818 -287.151245) (xy 52.351197 -287.126638) (xy 52.313076 -287.095513)
			(xy 52.280441 -287.058676) (xy 52.254138 -287.01708) (xy 52.234847 -286.971804) (xy 52.22307 -286.92402)
			(xy 52.21911 -286.874966) (xy 51.880262 -286.874966) (xy 51.879767 -286.899573) (xy 51.871872 -286.94815)
			(xy 51.856288 -286.994831) (xy 51.833417 -287.038408) (xy 51.803852 -287.077752) (xy 51.768359 -287.111844)
			(xy 51.727856 -287.1398) (xy 51.683394 -287.160898) (xy 51.636123 -287.17459) (xy 51.587268 -287.180522)
			(xy 51.538093 -287.178541) (xy 51.489874 -287.168697) (xy 51.443858 -287.151245) (xy 51.401237 -287.126638)
			(xy 51.363116 -287.095513) (xy 51.330481 -287.058676) (xy 51.304178 -287.01708) (xy 51.284887 -286.971804)
			(xy 51.27311 -286.92402) (xy 51.26915 -286.874966) (xy 50.930302 -286.874966) (xy 50.929807 -286.899573)
			(xy 50.921912 -286.94815) (xy 50.906328 -286.994831) (xy 50.883457 -287.038408) (xy 50.853892 -287.077752)
			(xy 50.818399 -287.111844) (xy 50.777896 -287.1398) (xy 50.733434 -287.160898) (xy 50.686163 -287.17459)
			(xy 50.637308 -287.180522) (xy 50.588133 -287.178541) (xy 50.539914 -287.168697) (xy 50.493898 -287.151245)
			(xy 50.451277 -287.126638) (xy 50.413156 -287.095513) (xy 50.380521 -287.058676) (xy 50.354218 -287.01708)
			(xy 50.334927 -286.971804) (xy 50.32315 -286.92402) (xy 50.31919 -286.874966) (xy 49.980088 -286.874966)
			(xy 49.979593 -286.899573) (xy 49.971698 -286.94815) (xy 49.956114 -286.994831) (xy 49.933243 -287.038408)
			(xy 49.903678 -287.077752) (xy 49.868185 -287.111844) (xy 49.827682 -287.1398) (xy 49.78322 -287.160898)
			(xy 49.735949 -287.17459) (xy 49.687094 -287.180522) (xy 49.637919 -287.178541) (xy 49.5897 -287.168697)
			(xy 49.543684 -287.151245) (xy 49.501063 -287.126638) (xy 49.462942 -287.095513) (xy 49.430307 -287.058676)
			(xy 49.404004 -287.01708) (xy 49.384713 -286.971804) (xy 49.372936 -286.92402) (xy 49.368976 -286.874966)
			(xy 49.181004 -286.874966) (xy 49.181004 -287.349946) (xy 73.593972 -287.349946) (xy 73.597932 -287.300892)
			(xy 73.609709 -287.253108) (xy 73.629 -287.207832) (xy 73.655303 -287.166236) (xy 73.687938 -287.129399)
			(xy 73.726059 -287.098274) (xy 73.76868 -287.073667) (xy 73.814696 -287.056215) (xy 73.862915 -287.046371)
			(xy 73.91209 -287.04439) (xy 73.960945 -287.050322) (xy 74.008216 -287.064014) (xy 74.052678 -287.085112)
			(xy 74.093181 -287.113068) (xy 74.128674 -287.14716) (xy 74.158239 -287.186504) (xy 74.18111 -287.230081)
			(xy 74.196694 -287.276762) (xy 74.204589 -287.325339) (xy 74.205084 -287.349946) (xy 74.204589 -287.374553)
			(xy 74.20441 -287.375654) (xy 74.523088 -287.375654) (xy 74.523088 -287.324238) (xy 74.531131 -287.273456)
			(xy 74.547019 -287.224557) (xy 74.570362 -287.178745) (xy 74.600583 -287.137149) (xy 74.636939 -287.100793)
			(xy 74.678535 -287.070572) (xy 74.724347 -287.047229) (xy 74.773246 -287.031341) (xy 74.824028 -287.023298)
			(xy 74.875444 -287.023298) (xy 74.926226 -287.031341) (xy 74.975125 -287.047229) (xy 75.020937 -287.070572)
			(xy 75.062533 -287.100793) (xy 75.098889 -287.137149) (xy 75.12911 -287.178745) (xy 75.152453 -287.224557)
			(xy 75.168341 -287.273456) (xy 75.176384 -287.324238) (xy 75.176888 -287.349946) (xy 75.176384 -287.375654)
			(xy 75.473302 -287.375654) (xy 75.473302 -287.324238) (xy 75.481345 -287.273456) (xy 75.497233 -287.224557)
			(xy 75.520576 -287.178745) (xy 75.550797 -287.137149) (xy 75.587153 -287.100793) (xy 75.628749 -287.070572)
			(xy 75.674561 -287.047229) (xy 75.72346 -287.031341) (xy 75.774242 -287.023298) (xy 75.825658 -287.023298)
			(xy 75.87644 -287.031341) (xy 75.925339 -287.047229) (xy 75.971151 -287.070572) (xy 76.012747 -287.100793)
			(xy 76.049103 -287.137149) (xy 76.079324 -287.178745) (xy 76.102667 -287.224557) (xy 76.118555 -287.273456)
			(xy 76.126598 -287.324238) (xy 76.127102 -287.349946) (xy 76.444106 -287.349946) (xy 76.448066 -287.300892)
			(xy 76.459843 -287.253108) (xy 76.479134 -287.207832) (xy 76.505437 -287.166236) (xy 76.538072 -287.129399)
			(xy 76.576193 -287.098274) (xy 76.618814 -287.073667) (xy 76.66483 -287.056215) (xy 76.713049 -287.046371)
			(xy 76.762224 -287.04439) (xy 76.811079 -287.050322) (xy 76.85835 -287.064014) (xy 76.902812 -287.085112)
			(xy 76.943315 -287.113068) (xy 76.978808 -287.14716) (xy 77.008373 -287.186504) (xy 77.031244 -287.230081)
			(xy 77.046828 -287.276762) (xy 77.054723 -287.325339) (xy 77.055218 -287.349946) (xy 77.394066 -287.349946)
			(xy 77.398026 -287.300892) (xy 77.409803 -287.253108) (xy 77.429094 -287.207832) (xy 77.455397 -287.166236)
			(xy 77.488032 -287.129399) (xy 77.526153 -287.098274) (xy 77.568774 -287.073667) (xy 77.61479 -287.056215)
			(xy 77.663009 -287.046371) (xy 77.712184 -287.04439) (xy 77.761039 -287.050322) (xy 77.80831 -287.064014)
			(xy 77.852772 -287.085112) (xy 77.893275 -287.113068) (xy 77.928768 -287.14716) (xy 77.958333 -287.186504)
			(xy 77.981204 -287.230081) (xy 77.996788 -287.276762) (xy 78.004683 -287.325339) (xy 78.005178 -287.349946)
			(xy 78.344026 -287.349946) (xy 78.347986 -287.300892) (xy 78.359763 -287.253108) (xy 78.379054 -287.207832)
			(xy 78.405357 -287.166236) (xy 78.437992 -287.129399) (xy 78.476113 -287.098274) (xy 78.518734 -287.073667)
			(xy 78.56475 -287.056215) (xy 78.612969 -287.046371) (xy 78.662144 -287.04439) (xy 78.710999 -287.050322)
			(xy 78.75827 -287.064014) (xy 78.802732 -287.085112) (xy 78.843235 -287.113068) (xy 78.878728 -287.14716)
			(xy 78.908293 -287.186504) (xy 78.931164 -287.230081) (xy 78.946748 -287.276762) (xy 78.954643 -287.325339)
			(xy 78.955138 -287.349946) (xy 79.293732 -287.349946) (xy 79.297692 -287.300892) (xy 79.309469 -287.253108)
			(xy 79.32876 -287.207832) (xy 79.355063 -287.166236) (xy 79.387698 -287.129399) (xy 79.425819 -287.098274)
			(xy 79.46844 -287.073667) (xy 79.514456 -287.056215) (xy 79.562675 -287.046371) (xy 79.61185 -287.04439)
			(xy 79.660705 -287.050322) (xy 79.707976 -287.064014) (xy 79.752438 -287.085112) (xy 79.792941 -287.113068)
			(xy 79.828434 -287.14716) (xy 79.857999 -287.186504) (xy 79.88087 -287.230081) (xy 79.896454 -287.276762)
			(xy 79.904349 -287.325339) (xy 79.904844 -287.349946) (xy 80.243946 -287.349946) (xy 80.247906 -287.300892)
			(xy 80.259683 -287.253108) (xy 80.278974 -287.207832) (xy 80.305277 -287.166236) (xy 80.337912 -287.129399)
			(xy 80.376033 -287.098274) (xy 80.418654 -287.073667) (xy 80.46467 -287.056215) (xy 80.512889 -287.046371)
			(xy 80.562064 -287.04439) (xy 80.610919 -287.050322) (xy 80.65819 -287.064014) (xy 80.702652 -287.085112)
			(xy 80.743155 -287.113068) (xy 80.778648 -287.14716) (xy 80.808213 -287.186504) (xy 80.831084 -287.230081)
			(xy 80.846668 -287.276762) (xy 80.854563 -287.325339) (xy 80.855058 -287.349946) (xy 80.854563 -287.374553)
			(xy 80.854384 -287.375654) (xy 81.173316 -287.375654) (xy 81.173316 -287.324238) (xy 81.181359 -287.273456)
			(xy 81.197247 -287.224557) (xy 81.22059 -287.178745) (xy 81.250811 -287.137149) (xy 81.287167 -287.100793)
			(xy 81.328763 -287.070572) (xy 81.374575 -287.047229) (xy 81.423474 -287.031341) (xy 81.474256 -287.023298)
			(xy 81.525672 -287.023298) (xy 81.576454 -287.031341) (xy 81.625353 -287.047229) (xy 81.671165 -287.070572)
			(xy 81.712761 -287.100793) (xy 81.749117 -287.137149) (xy 81.779338 -287.178745) (xy 81.802681 -287.224557)
			(xy 81.818569 -287.273456) (xy 81.826612 -287.324238) (xy 81.827116 -287.349946) (xy 81.826612 -287.375654)
			(xy 82.123276 -287.375654) (xy 82.123276 -287.324238) (xy 82.131319 -287.273456) (xy 82.147207 -287.224557)
			(xy 82.17055 -287.178745) (xy 82.200771 -287.137149) (xy 82.237127 -287.100793) (xy 82.278723 -287.070572)
			(xy 82.324535 -287.047229) (xy 82.373434 -287.031341) (xy 82.424216 -287.023298) (xy 82.475632 -287.023298)
			(xy 82.526414 -287.031341) (xy 82.575313 -287.047229) (xy 82.621125 -287.070572) (xy 82.662721 -287.100793)
			(xy 82.699077 -287.137149) (xy 82.729298 -287.178745) (xy 82.752641 -287.224557) (xy 82.768529 -287.273456)
			(xy 82.776572 -287.324238) (xy 82.777076 -287.349946) (xy 82.777071 -287.3502) (xy 83.094334 -287.3502)
			(xy 83.098294 -287.301146) (xy 83.110071 -287.253362) (xy 83.129362 -287.208086) (xy 83.155665 -287.16649)
			(xy 83.1883 -287.129653) (xy 83.226421 -287.098528) (xy 83.269042 -287.073921) (xy 83.315058 -287.056469)
			(xy 83.363277 -287.046625) (xy 83.412452 -287.044644) (xy 83.461307 -287.050576) (xy 83.508578 -287.064268)
			(xy 83.55304 -287.085366) (xy 83.593543 -287.113322) (xy 83.629036 -287.147414) (xy 83.658601 -287.186758)
			(xy 83.681472 -287.230335) (xy 83.697056 -287.277016) (xy 83.704951 -287.325593) (xy 83.705446 -287.3502)
			(xy 83.704951 -287.374807) (xy 83.697056 -287.423384) (xy 83.681472 -287.470065) (xy 83.658601 -287.513642)
			(xy 83.629036 -287.552986) (xy 83.593543 -287.587078) (xy 83.55304 -287.615034) (xy 83.508578 -287.636132)
			(xy 83.461307 -287.649824) (xy 83.412452 -287.655756) (xy 83.363277 -287.653775) (xy 83.315058 -287.643931)
			(xy 83.269042 -287.626479) (xy 83.226421 -287.601872) (xy 83.1883 -287.570747) (xy 83.155665 -287.53391)
			(xy 83.129362 -287.492314) (xy 83.110071 -287.447038) (xy 83.098294 -287.399254) (xy 83.094334 -287.3502)
			(xy 82.777071 -287.3502) (xy 82.776572 -287.375654) (xy 82.768529 -287.426436) (xy 82.752641 -287.475335)
			(xy 82.729298 -287.521147) (xy 82.699077 -287.562743) (xy 82.662721 -287.599099) (xy 82.621125 -287.62932)
			(xy 82.575313 -287.652663) (xy 82.526414 -287.668551) (xy 82.475632 -287.676594) (xy 82.424216 -287.676594)
			(xy 82.373434 -287.668551) (xy 82.324535 -287.652663) (xy 82.278723 -287.62932) (xy 82.237127 -287.599099)
			(xy 82.200771 -287.562743) (xy 82.17055 -287.521147) (xy 82.147207 -287.475335) (xy 82.131319 -287.426436)
			(xy 82.123276 -287.375654) (xy 81.826612 -287.375654) (xy 81.818569 -287.426436) (xy 81.802681 -287.475335)
			(xy 81.779338 -287.521147) (xy 81.749117 -287.562743) (xy 81.712761 -287.599099) (xy 81.671165 -287.62932)
			(xy 81.625353 -287.652663) (xy 81.576454 -287.668551) (xy 81.525672 -287.676594) (xy 81.474256 -287.676594)
			(xy 81.423474 -287.668551) (xy 81.374575 -287.652663) (xy 81.328763 -287.62932) (xy 81.287167 -287.599099)
			(xy 81.250811 -287.562743) (xy 81.22059 -287.521147) (xy 81.197247 -287.475335) (xy 81.181359 -287.426436)
			(xy 81.173316 -287.375654) (xy 80.854384 -287.375654) (xy 80.846668 -287.42313) (xy 80.831084 -287.469811)
			(xy 80.808213 -287.513388) (xy 80.778648 -287.552732) (xy 80.743155 -287.586824) (xy 80.702652 -287.61478)
			(xy 80.65819 -287.635878) (xy 80.610919 -287.64957) (xy 80.562064 -287.655502) (xy 80.512889 -287.653521)
			(xy 80.46467 -287.643677) (xy 80.418654 -287.626225) (xy 80.376033 -287.601618) (xy 80.337912 -287.570493)
			(xy 80.305277 -287.533656) (xy 80.278974 -287.49206) (xy 80.259683 -287.446784) (xy 80.247906 -287.399)
			(xy 80.243946 -287.349946) (xy 79.904844 -287.349946) (xy 79.904349 -287.374553) (xy 79.896454 -287.42313)
			(xy 79.88087 -287.469811) (xy 79.857999 -287.513388) (xy 79.828434 -287.552732) (xy 79.792941 -287.586824)
			(xy 79.752438 -287.61478) (xy 79.707976 -287.635878) (xy 79.660705 -287.64957) (xy 79.61185 -287.655502)
			(xy 79.562675 -287.653521) (xy 79.514456 -287.643677) (xy 79.46844 -287.626225) (xy 79.425819 -287.601618)
			(xy 79.387698 -287.570493) (xy 79.355063 -287.533656) (xy 79.32876 -287.49206) (xy 79.309469 -287.446784)
			(xy 79.297692 -287.399) (xy 79.293732 -287.349946) (xy 78.955138 -287.349946) (xy 78.954643 -287.374553)
			(xy 78.946748 -287.42313) (xy 78.931164 -287.469811) (xy 78.908293 -287.513388) (xy 78.878728 -287.552732)
			(xy 78.843235 -287.586824) (xy 78.802732 -287.61478) (xy 78.75827 -287.635878) (xy 78.710999 -287.64957)
			(xy 78.662144 -287.655502) (xy 78.612969 -287.653521) (xy 78.56475 -287.643677) (xy 78.518734 -287.626225)
			(xy 78.476113 -287.601618) (xy 78.437992 -287.570493) (xy 78.405357 -287.533656) (xy 78.379054 -287.49206)
			(xy 78.359763 -287.446784) (xy 78.347986 -287.399) (xy 78.344026 -287.349946) (xy 78.005178 -287.349946)
			(xy 78.004683 -287.374553) (xy 77.996788 -287.42313) (xy 77.981204 -287.469811) (xy 77.958333 -287.513388)
			(xy 77.928768 -287.552732) (xy 77.893275 -287.586824) (xy 77.852772 -287.61478) (xy 77.80831 -287.635878)
			(xy 77.761039 -287.64957) (xy 77.712184 -287.655502) (xy 77.663009 -287.653521) (xy 77.61479 -287.643677)
			(xy 77.568774 -287.626225) (xy 77.526153 -287.601618) (xy 77.488032 -287.570493) (xy 77.455397 -287.533656)
			(xy 77.429094 -287.49206) (xy 77.409803 -287.446784) (xy 77.398026 -287.399) (xy 77.394066 -287.349946)
			(xy 77.055218 -287.349946) (xy 77.054723 -287.374553) (xy 77.046828 -287.42313) (xy 77.031244 -287.469811)
			(xy 77.008373 -287.513388) (xy 76.978808 -287.552732) (xy 76.943315 -287.586824) (xy 76.902812 -287.61478)
			(xy 76.85835 -287.635878) (xy 76.811079 -287.64957) (xy 76.762224 -287.655502) (xy 76.713049 -287.653521)
			(xy 76.66483 -287.643677) (xy 76.618814 -287.626225) (xy 76.576193 -287.601618) (xy 76.538072 -287.570493)
			(xy 76.505437 -287.533656) (xy 76.479134 -287.49206) (xy 76.459843 -287.446784) (xy 76.448066 -287.399)
			(xy 76.444106 -287.349946) (xy 76.127102 -287.349946) (xy 76.126598 -287.375654) (xy 76.118555 -287.426436)
			(xy 76.102667 -287.475335) (xy 76.079324 -287.521147) (xy 76.049103 -287.562743) (xy 76.012747 -287.599099)
			(xy 75.971151 -287.62932) (xy 75.925339 -287.652663) (xy 75.87644 -287.668551) (xy 75.825658 -287.676594)
			(xy 75.774242 -287.676594) (xy 75.72346 -287.668551) (xy 75.674561 -287.652663) (xy 75.628749 -287.62932)
			(xy 75.587153 -287.599099) (xy 75.550797 -287.562743) (xy 75.520576 -287.521147) (xy 75.497233 -287.475335)
			(xy 75.481345 -287.426436) (xy 75.473302 -287.375654) (xy 75.176384 -287.375654) (xy 75.168341 -287.426436)
			(xy 75.152453 -287.475335) (xy 75.12911 -287.521147) (xy 75.098889 -287.562743) (xy 75.062533 -287.599099)
			(xy 75.020937 -287.62932) (xy 74.975125 -287.652663) (xy 74.926226 -287.668551) (xy 74.875444 -287.676594)
			(xy 74.824028 -287.676594) (xy 74.773246 -287.668551) (xy 74.724347 -287.652663) (xy 74.678535 -287.62932)
			(xy 74.636939 -287.599099) (xy 74.600583 -287.562743) (xy 74.570362 -287.521147) (xy 74.547019 -287.475335)
			(xy 74.531131 -287.426436) (xy 74.523088 -287.375654) (xy 74.20441 -287.375654) (xy 74.196694 -287.42313)
			(xy 74.18111 -287.469811) (xy 74.158239 -287.513388) (xy 74.128674 -287.552732) (xy 74.093181 -287.586824)
			(xy 74.052678 -287.61478) (xy 74.008216 -287.635878) (xy 73.960945 -287.64957) (xy 73.91209 -287.655502)
			(xy 73.862915 -287.653521) (xy 73.814696 -287.643677) (xy 73.76868 -287.626225) (xy 73.726059 -287.601618)
			(xy 73.687938 -287.570493) (xy 73.655303 -287.533656) (xy 73.629 -287.49206) (xy 73.609709 -287.446784)
			(xy 73.597932 -287.399) (xy 73.593972 -287.349946) (xy 49.181004 -287.349946) (xy 49.181004 -287.824926)
			(xy 49.368976 -287.824926) (xy 49.372936 -287.775872) (xy 49.384713 -287.728088) (xy 49.404004 -287.682812)
			(xy 49.430307 -287.641216) (xy 49.462942 -287.604379) (xy 49.501063 -287.573254) (xy 49.543684 -287.548647)
			(xy 49.5897 -287.531195) (xy 49.637919 -287.521351) (xy 49.687094 -287.51937) (xy 49.735949 -287.525302)
			(xy 49.78322 -287.538994) (xy 49.827682 -287.560092) (xy 49.868185 -287.588048) (xy 49.903678 -287.62214)
			(xy 49.933243 -287.661484) (xy 49.956114 -287.705061) (xy 49.971698 -287.751742) (xy 49.979593 -287.800319)
			(xy 49.980088 -287.824926) (xy 50.31919 -287.824926) (xy 50.32315 -287.775872) (xy 50.334927 -287.728088)
			(xy 50.354218 -287.682812) (xy 50.380521 -287.641216) (xy 50.413156 -287.604379) (xy 50.451277 -287.573254)
			(xy 50.493898 -287.548647) (xy 50.539914 -287.531195) (xy 50.588133 -287.521351) (xy 50.637308 -287.51937)
			(xy 50.686163 -287.525302) (xy 50.733434 -287.538994) (xy 50.777896 -287.560092) (xy 50.818399 -287.588048)
			(xy 50.853892 -287.62214) (xy 50.883457 -287.661484) (xy 50.906328 -287.705061) (xy 50.921912 -287.751742)
			(xy 50.929807 -287.800319) (xy 50.930302 -287.824926) (xy 51.26915 -287.824926) (xy 51.27311 -287.775872)
			(xy 51.284887 -287.728088) (xy 51.304178 -287.682812) (xy 51.330481 -287.641216) (xy 51.363116 -287.604379)
			(xy 51.401237 -287.573254) (xy 51.443858 -287.548647) (xy 51.489874 -287.531195) (xy 51.538093 -287.521351)
			(xy 51.587268 -287.51937) (xy 51.636123 -287.525302) (xy 51.683394 -287.538994) (xy 51.727856 -287.560092)
			(xy 51.768359 -287.588048) (xy 51.803852 -287.62214) (xy 51.833417 -287.661484) (xy 51.856288 -287.705061)
			(xy 51.871872 -287.751742) (xy 51.879767 -287.800319) (xy 51.880262 -287.824926) (xy 52.21911 -287.824926)
			(xy 52.22307 -287.775872) (xy 52.234847 -287.728088) (xy 52.254138 -287.682812) (xy 52.280441 -287.641216)
			(xy 52.313076 -287.604379) (xy 52.351197 -287.573254) (xy 52.393818 -287.548647) (xy 52.439834 -287.531195)
			(xy 52.488053 -287.521351) (xy 52.537228 -287.51937) (xy 52.586083 -287.525302) (xy 52.633354 -287.538994)
			(xy 52.677816 -287.560092) (xy 52.718319 -287.588048) (xy 52.753812 -287.62214) (xy 52.783377 -287.661484)
			(xy 52.806248 -287.705061) (xy 52.821832 -287.751742) (xy 52.829727 -287.800319) (xy 52.830222 -287.824926)
			(xy 53.16907 -287.824926) (xy 53.17303 -287.775872) (xy 53.184807 -287.728088) (xy 53.204098 -287.682812)
			(xy 53.230401 -287.641216) (xy 53.263036 -287.604379) (xy 53.301157 -287.573254) (xy 53.343778 -287.548647)
			(xy 53.389794 -287.531195) (xy 53.438013 -287.521351) (xy 53.487188 -287.51937) (xy 53.536043 -287.525302)
			(xy 53.583314 -287.538994) (xy 53.627776 -287.560092) (xy 53.668279 -287.588048) (xy 53.703772 -287.62214)
			(xy 53.733337 -287.661484) (xy 53.756208 -287.705061) (xy 53.771792 -287.751742) (xy 53.779687 -287.800319)
			(xy 53.780182 -287.824926) (xy 54.11903 -287.824926) (xy 54.12299 -287.775872) (xy 54.134767 -287.728088)
			(xy 54.154058 -287.682812) (xy 54.180361 -287.641216) (xy 54.212996 -287.604379) (xy 54.251117 -287.573254)
			(xy 54.293738 -287.548647) (xy 54.339754 -287.531195) (xy 54.387973 -287.521351) (xy 54.437148 -287.51937)
			(xy 54.486003 -287.525302) (xy 54.533274 -287.538994) (xy 54.577736 -287.560092) (xy 54.618239 -287.588048)
			(xy 54.653732 -287.62214) (xy 54.683297 -287.661484) (xy 54.706168 -287.705061) (xy 54.721752 -287.751742)
			(xy 54.729647 -287.800319) (xy 54.730142 -287.824926) (xy 55.06899 -287.824926) (xy 55.07295 -287.775872)
			(xy 55.084727 -287.728088) (xy 55.104018 -287.682812) (xy 55.130321 -287.641216) (xy 55.162956 -287.604379)
			(xy 55.201077 -287.573254) (xy 55.243698 -287.548647) (xy 55.289714 -287.531195) (xy 55.337933 -287.521351)
			(xy 55.387108 -287.51937) (xy 55.435963 -287.525302) (xy 55.483234 -287.538994) (xy 55.527696 -287.560092)
			(xy 55.568199 -287.588048) (xy 55.603692 -287.62214) (xy 55.633257 -287.661484) (xy 55.656128 -287.705061)
			(xy 55.671712 -287.751742) (xy 55.679607 -287.800319) (xy 55.680102 -287.824926) (xy 56.01895 -287.824926)
			(xy 56.02291 -287.775872) (xy 56.034687 -287.728088) (xy 56.053978 -287.682812) (xy 56.080281 -287.641216)
			(xy 56.112916 -287.604379) (xy 56.151037 -287.573254) (xy 56.193658 -287.548647) (xy 56.239674 -287.531195)
			(xy 56.287893 -287.521351) (xy 56.337068 -287.51937) (xy 56.385923 -287.525302) (xy 56.433194 -287.538994)
			(xy 56.477656 -287.560092) (xy 56.518159 -287.588048) (xy 56.553652 -287.62214) (xy 56.583217 -287.661484)
			(xy 56.606088 -287.705061) (xy 56.621672 -287.751742) (xy 56.629567 -287.800319) (xy 56.630062 -287.824926)
			(xy 56.969164 -287.824926) (xy 56.973124 -287.775872) (xy 56.984901 -287.728088) (xy 57.004192 -287.682812)
			(xy 57.030495 -287.641216) (xy 57.06313 -287.604379) (xy 57.101251 -287.573254) (xy 57.143872 -287.548647)
			(xy 57.189888 -287.531195) (xy 57.238107 -287.521351) (xy 57.287282 -287.51937) (xy 57.336137 -287.525302)
			(xy 57.383408 -287.538994) (xy 57.42787 -287.560092) (xy 57.468373 -287.588048) (xy 57.503866 -287.62214)
			(xy 57.533431 -287.661484) (xy 57.553624 -287.699958) (xy 57.944016 -287.699958) (xy 57.947976 -287.650904)
			(xy 57.959753 -287.60312) (xy 57.979044 -287.557844) (xy 58.005347 -287.516248) (xy 58.037982 -287.479411)
			(xy 58.076103 -287.448286) (xy 58.118724 -287.423679) (xy 58.16474 -287.406227) (xy 58.212959 -287.396383)
			(xy 58.262134 -287.394402) (xy 58.310989 -287.400334) (xy 58.35826 -287.414026) (xy 58.402722 -287.435124)
			(xy 58.443225 -287.46308) (xy 58.478718 -287.497172) (xy 58.508283 -287.536516) (xy 58.531154 -287.580093)
			(xy 58.546738 -287.626774) (xy 58.554633 -287.675351) (xy 58.555128 -287.699958) (xy 58.554633 -287.724565)
			(xy 58.546738 -287.773142) (xy 58.531154 -287.819823) (xy 58.508283 -287.8634) (xy 58.480888 -287.899856)
			(xy 59.819044 -287.899856) (xy 59.823004 -287.850802) (xy 59.834781 -287.803018) (xy 59.854072 -287.757742)
			(xy 59.880375 -287.716146) (xy 59.91301 -287.679309) (xy 59.951131 -287.648184) (xy 59.993752 -287.623577)
			(xy 60.039768 -287.606125) (xy 60.087987 -287.596281) (xy 60.137162 -287.5943) (xy 60.186017 -287.600232)
			(xy 60.233288 -287.613924) (xy 60.27775 -287.635022) (xy 60.318253 -287.662978) (xy 60.353746 -287.69707)
			(xy 60.383311 -287.736414) (xy 60.406182 -287.779991) (xy 60.421183 -287.824926) (xy 60.769004 -287.824926)
			(xy 60.772964 -287.775872) (xy 60.784741 -287.728088) (xy 60.804032 -287.682812) (xy 60.830335 -287.641216)
			(xy 60.86297 -287.604379) (xy 60.901091 -287.573254) (xy 60.943712 -287.548647) (xy 60.989728 -287.531195)
			(xy 61.037947 -287.521351) (xy 61.087122 -287.51937) (xy 61.135977 -287.525302) (xy 61.183248 -287.538994)
			(xy 61.22771 -287.560092) (xy 61.268213 -287.588048) (xy 61.303706 -287.62214) (xy 61.333271 -287.661484)
			(xy 61.356142 -287.705061) (xy 61.371726 -287.751742) (xy 61.379621 -287.800319) (xy 61.380116 -287.824926)
			(xy 61.718964 -287.824926) (xy 61.722924 -287.775872) (xy 61.734701 -287.728088) (xy 61.753992 -287.682812)
			(xy 61.780295 -287.641216) (xy 61.81293 -287.604379) (xy 61.851051 -287.573254) (xy 61.893672 -287.548647)
			(xy 61.939688 -287.531195) (xy 61.987907 -287.521351) (xy 62.037082 -287.51937) (xy 62.085937 -287.525302)
			(xy 62.133208 -287.538994) (xy 62.17767 -287.560092) (xy 62.218173 -287.588048) (xy 62.253666 -287.62214)
			(xy 62.283231 -287.661484) (xy 62.306102 -287.705061) (xy 62.321686 -287.751742) (xy 62.329581 -287.800319)
			(xy 62.330076 -287.824926) (xy 62.669178 -287.824926) (xy 62.673138 -287.775872) (xy 62.684915 -287.728088)
			(xy 62.704206 -287.682812) (xy 62.730509 -287.641216) (xy 62.763144 -287.604379) (xy 62.801265 -287.573254)
			(xy 62.843886 -287.548647) (xy 62.889902 -287.531195) (xy 62.938121 -287.521351) (xy 62.987296 -287.51937)
			(xy 63.036151 -287.525302) (xy 63.083422 -287.538994) (xy 63.127884 -287.560092) (xy 63.168387 -287.588048)
			(xy 63.20388 -287.62214) (xy 63.233445 -287.661484) (xy 63.256316 -287.705061) (xy 63.2719 -287.751742)
			(xy 63.279795 -287.800319) (xy 63.28029 -287.824926) (xy 63.619138 -287.824926) (xy 63.623098 -287.775872)
			(xy 63.634875 -287.728088) (xy 63.654166 -287.682812) (xy 63.680469 -287.641216) (xy 63.713104 -287.604379)
			(xy 63.751225 -287.573254) (xy 63.793846 -287.548647) (xy 63.839862 -287.531195) (xy 63.888081 -287.521351)
			(xy 63.937256 -287.51937) (xy 63.986111 -287.525302) (xy 64.033382 -287.538994) (xy 64.077844 -287.560092)
			(xy 64.118347 -287.588048) (xy 64.15384 -287.62214) (xy 64.183405 -287.661484) (xy 64.206276 -287.705061)
			(xy 64.22186 -287.751742) (xy 64.229755 -287.800319) (xy 64.23025 -287.824926) (xy 64.569098 -287.824926)
			(xy 64.573058 -287.775872) (xy 64.584835 -287.728088) (xy 64.604126 -287.682812) (xy 64.630429 -287.641216)
			(xy 64.663064 -287.604379) (xy 64.701185 -287.573254) (xy 64.743806 -287.548647) (xy 64.789822 -287.531195)
			(xy 64.838041 -287.521351) (xy 64.887216 -287.51937) (xy 64.936071 -287.525302) (xy 64.983342 -287.538994)
			(xy 65.027804 -287.560092) (xy 65.068307 -287.588048) (xy 65.1038 -287.62214) (xy 65.133365 -287.661484)
			(xy 65.156236 -287.705061) (xy 65.17182 -287.751742) (xy 65.179715 -287.800319) (xy 65.18021 -287.824926)
			(xy 65.519058 -287.824926) (xy 65.523018 -287.775872) (xy 65.534795 -287.728088) (xy 65.554086 -287.682812)
			(xy 65.580389 -287.641216) (xy 65.613024 -287.604379) (xy 65.651145 -287.573254) (xy 65.693766 -287.548647)
			(xy 65.739782 -287.531195) (xy 65.788001 -287.521351) (xy 65.837176 -287.51937) (xy 65.886031 -287.525302)
			(xy 65.933302 -287.538994) (xy 65.977764 -287.560092) (xy 66.018267 -287.588048) (xy 66.05376 -287.62214)
			(xy 66.083325 -287.661484) (xy 66.106196 -287.705061) (xy 66.12178 -287.751742) (xy 66.129675 -287.800319)
			(xy 66.13017 -287.824926) (xy 66.469018 -287.824926) (xy 66.472978 -287.775872) (xy 66.484755 -287.728088)
			(xy 66.504046 -287.682812) (xy 66.530349 -287.641216) (xy 66.562984 -287.604379) (xy 66.601105 -287.573254)
			(xy 66.643726 -287.548647) (xy 66.689742 -287.531195) (xy 66.737961 -287.521351) (xy 66.787136 -287.51937)
			(xy 66.835991 -287.525302) (xy 66.883262 -287.538994) (xy 66.927724 -287.560092) (xy 66.968227 -287.588048)
			(xy 67.00372 -287.62214) (xy 67.033285 -287.661484) (xy 67.056156 -287.705061) (xy 67.07174 -287.751742)
			(xy 67.079635 -287.800319) (xy 67.08013 -287.824926) (xy 67.418978 -287.824926) (xy 67.422938 -287.775872)
			(xy 67.434715 -287.728088) (xy 67.454006 -287.682812) (xy 67.480309 -287.641216) (xy 67.512944 -287.604379)
			(xy 67.551065 -287.573254) (xy 67.593686 -287.548647) (xy 67.639702 -287.531195) (xy 67.687921 -287.521351)
			(xy 67.737096 -287.51937) (xy 67.785951 -287.525302) (xy 67.833222 -287.538994) (xy 67.877684 -287.560092)
			(xy 67.918187 -287.588048) (xy 67.95368 -287.62214) (xy 67.983245 -287.661484) (xy 68.006116 -287.705061)
			(xy 68.0217 -287.751742) (xy 68.029595 -287.800319) (xy 68.03009 -287.824926) (xy 68.368938 -287.824926)
			(xy 68.372898 -287.775872) (xy 68.384675 -287.728088) (xy 68.403966 -287.682812) (xy 68.430269 -287.641216)
			(xy 68.462904 -287.604379) (xy 68.501025 -287.573254) (xy 68.543646 -287.548647) (xy 68.589662 -287.531195)
			(xy 68.637881 -287.521351) (xy 68.687056 -287.51937) (xy 68.735911 -287.525302) (xy 68.783182 -287.538994)
			(xy 68.827644 -287.560092) (xy 68.868147 -287.588048) (xy 68.90364 -287.62214) (xy 68.933205 -287.661484)
			(xy 68.956076 -287.705061) (xy 68.97166 -287.751742) (xy 68.979555 -287.800319) (xy 68.98005 -287.824926)
			(xy 70.269112 -287.824926) (xy 70.273072 -287.775872) (xy 70.284849 -287.728088) (xy 70.30414 -287.682812)
			(xy 70.330443 -287.641216) (xy 70.363078 -287.604379) (xy 70.401199 -287.573254) (xy 70.44382 -287.548647)
			(xy 70.489836 -287.531195) (xy 70.538055 -287.521351) (xy 70.58723 -287.51937) (xy 70.636085 -287.525302)
			(xy 70.683356 -287.538994) (xy 70.727818 -287.560092) (xy 70.768321 -287.588048) (xy 70.803814 -287.62214)
			(xy 70.833379 -287.661484) (xy 70.85625 -287.705061) (xy 70.871834 -287.751742) (xy 70.879729 -287.800319)
			(xy 70.880224 -287.824926) (xy 70.879729 -287.849533) (xy 70.871834 -287.89811) (xy 70.85625 -287.944791)
			(xy 70.833379 -287.988368) (xy 70.803814 -288.027712) (xy 70.768321 -288.061804) (xy 70.727818 -288.08976)
			(xy 70.683356 -288.110858) (xy 70.636085 -288.12455) (xy 70.58723 -288.130482) (xy 70.538055 -288.128501)
			(xy 70.489836 -288.118657) (xy 70.44382 -288.101205) (xy 70.401199 -288.076598) (xy 70.363078 -288.045473)
			(xy 70.330443 -288.008636) (xy 70.30414 -287.96704) (xy 70.284849 -287.921764) (xy 70.273072 -287.87398)
			(xy 70.269112 -287.824926) (xy 68.98005 -287.824926) (xy 68.979555 -287.849533) (xy 68.97166 -287.89811)
			(xy 68.956076 -287.944791) (xy 68.933205 -287.988368) (xy 68.90364 -288.027712) (xy 68.868147 -288.061804)
			(xy 68.827644 -288.08976) (xy 68.783182 -288.110858) (xy 68.735911 -288.12455) (xy 68.687056 -288.130482)
			(xy 68.637881 -288.128501) (xy 68.589662 -288.118657) (xy 68.543646 -288.101205) (xy 68.501025 -288.076598)
			(xy 68.462904 -288.045473) (xy 68.430269 -288.008636) (xy 68.403966 -287.96704) (xy 68.384675 -287.921764)
			(xy 68.372898 -287.87398) (xy 68.368938 -287.824926) (xy 68.03009 -287.824926) (xy 68.029595 -287.849533)
			(xy 68.0217 -287.89811) (xy 68.006116 -287.944791) (xy 67.983245 -287.988368) (xy 67.95368 -288.027712)
			(xy 67.918187 -288.061804) (xy 67.877684 -288.08976) (xy 67.833222 -288.110858) (xy 67.785951 -288.12455)
			(xy 67.737096 -288.130482) (xy 67.687921 -288.128501) (xy 67.639702 -288.118657) (xy 67.593686 -288.101205)
			(xy 67.551065 -288.076598) (xy 67.512944 -288.045473) (xy 67.480309 -288.008636) (xy 67.454006 -287.96704)
			(xy 67.434715 -287.921764) (xy 67.422938 -287.87398) (xy 67.418978 -287.824926) (xy 67.08013 -287.824926)
			(xy 67.079635 -287.849533) (xy 67.07174 -287.89811) (xy 67.056156 -287.944791) (xy 67.033285 -287.988368)
			(xy 67.00372 -288.027712) (xy 66.968227 -288.061804) (xy 66.927724 -288.08976) (xy 66.883262 -288.110858)
			(xy 66.835991 -288.12455) (xy 66.787136 -288.130482) (xy 66.737961 -288.128501) (xy 66.689742 -288.118657)
			(xy 66.643726 -288.101205) (xy 66.601105 -288.076598) (xy 66.562984 -288.045473) (xy 66.530349 -288.008636)
			(xy 66.504046 -287.96704) (xy 66.484755 -287.921764) (xy 66.472978 -287.87398) (xy 66.469018 -287.824926)
			(xy 66.13017 -287.824926) (xy 66.129675 -287.849533) (xy 66.12178 -287.89811) (xy 66.106196 -287.944791)
			(xy 66.083325 -287.988368) (xy 66.05376 -288.027712) (xy 66.018267 -288.061804) (xy 65.977764 -288.08976)
			(xy 65.933302 -288.110858) (xy 65.886031 -288.12455) (xy 65.837176 -288.130482) (xy 65.788001 -288.128501)
			(xy 65.739782 -288.118657) (xy 65.693766 -288.101205) (xy 65.651145 -288.076598) (xy 65.613024 -288.045473)
			(xy 65.580389 -288.008636) (xy 65.554086 -287.96704) (xy 65.534795 -287.921764) (xy 65.523018 -287.87398)
			(xy 65.519058 -287.824926) (xy 65.18021 -287.824926) (xy 65.179715 -287.849533) (xy 65.17182 -287.89811)
			(xy 65.156236 -287.944791) (xy 65.133365 -287.988368) (xy 65.1038 -288.027712) (xy 65.068307 -288.061804)
			(xy 65.027804 -288.08976) (xy 64.983342 -288.110858) (xy 64.936071 -288.12455) (xy 64.887216 -288.130482)
			(xy 64.838041 -288.128501) (xy 64.789822 -288.118657) (xy 64.743806 -288.101205) (xy 64.701185 -288.076598)
			(xy 64.663064 -288.045473) (xy 64.630429 -288.008636) (xy 64.604126 -287.96704) (xy 64.584835 -287.921764)
			(xy 64.573058 -287.87398) (xy 64.569098 -287.824926) (xy 64.23025 -287.824926) (xy 64.229755 -287.849533)
			(xy 64.22186 -287.89811) (xy 64.206276 -287.944791) (xy 64.183405 -287.988368) (xy 64.15384 -288.027712)
			(xy 64.118347 -288.061804) (xy 64.077844 -288.08976) (xy 64.033382 -288.110858) (xy 63.986111 -288.12455)
			(xy 63.937256 -288.130482) (xy 63.888081 -288.128501) (xy 63.839862 -288.118657) (xy 63.793846 -288.101205)
			(xy 63.751225 -288.076598) (xy 63.713104 -288.045473) (xy 63.680469 -288.008636) (xy 63.654166 -287.96704)
			(xy 63.634875 -287.921764) (xy 63.623098 -287.87398) (xy 63.619138 -287.824926) (xy 63.28029 -287.824926)
			(xy 63.279795 -287.849533) (xy 63.2719 -287.89811) (xy 63.256316 -287.944791) (xy 63.233445 -287.988368)
			(xy 63.20388 -288.027712) (xy 63.168387 -288.061804) (xy 63.127884 -288.08976) (xy 63.083422 -288.110858)
			(xy 63.036151 -288.12455) (xy 62.987296 -288.130482) (xy 62.938121 -288.128501) (xy 62.889902 -288.118657)
			(xy 62.843886 -288.101205) (xy 62.801265 -288.076598) (xy 62.763144 -288.045473) (xy 62.730509 -288.008636)
			(xy 62.704206 -287.96704) (xy 62.684915 -287.921764) (xy 62.673138 -287.87398) (xy 62.669178 -287.824926)
			(xy 62.330076 -287.824926) (xy 62.329581 -287.849533) (xy 62.321686 -287.89811) (xy 62.306102 -287.944791)
			(xy 62.283231 -287.988368) (xy 62.253666 -288.027712) (xy 62.218173 -288.061804) (xy 62.17767 -288.08976)
			(xy 62.133208 -288.110858) (xy 62.085937 -288.12455) (xy 62.037082 -288.130482) (xy 61.987907 -288.128501)
			(xy 61.939688 -288.118657) (xy 61.893672 -288.101205) (xy 61.851051 -288.076598) (xy 61.81293 -288.045473)
			(xy 61.780295 -288.008636) (xy 61.753992 -287.96704) (xy 61.734701 -287.921764) (xy 61.722924 -287.87398)
			(xy 61.718964 -287.824926) (xy 61.380116 -287.824926) (xy 61.379621 -287.849533) (xy 61.371726 -287.89811)
			(xy 61.356142 -287.944791) (xy 61.333271 -287.988368) (xy 61.303706 -288.027712) (xy 61.268213 -288.061804)
			(xy 61.22771 -288.08976) (xy 61.183248 -288.110858) (xy 61.135977 -288.12455) (xy 61.087122 -288.130482)
			(xy 61.037947 -288.128501) (xy 60.989728 -288.118657) (xy 60.943712 -288.101205) (xy 60.901091 -288.076598)
			(xy 60.86297 -288.045473) (xy 60.830335 -288.008636) (xy 60.804032 -287.96704) (xy 60.784741 -287.921764)
			(xy 60.772964 -287.87398) (xy 60.769004 -287.824926) (xy 60.421183 -287.824926) (xy 60.421766 -287.826672)
			(xy 60.429661 -287.875249) (xy 60.430156 -287.899856) (xy 60.429661 -287.924463) (xy 60.421766 -287.97304)
			(xy 60.406182 -288.019721) (xy 60.383311 -288.063298) (xy 60.353746 -288.102642) (xy 60.318253 -288.136734)
			(xy 60.27775 -288.16469) (xy 60.233288 -288.185788) (xy 60.186017 -288.19948) (xy 60.137162 -288.205412)
			(xy 60.087987 -288.203431) (xy 60.039768 -288.193587) (xy 59.993752 -288.176135) (xy 59.951131 -288.151528)
			(xy 59.91301 -288.120403) (xy 59.880375 -288.083566) (xy 59.854072 -288.04197) (xy 59.834781 -287.996694)
			(xy 59.823004 -287.94891) (xy 59.819044 -287.899856) (xy 58.480888 -287.899856) (xy 58.478718 -287.902744)
			(xy 58.443225 -287.936836) (xy 58.402722 -287.964792) (xy 58.35826 -287.98589) (xy 58.310989 -287.999582)
			(xy 58.262134 -288.005514) (xy 58.212959 -288.003533) (xy 58.16474 -287.993689) (xy 58.118724 -287.976237)
			(xy 58.076103 -287.95163) (xy 58.037982 -287.920505) (xy 58.005347 -287.883668) (xy 57.979044 -287.842072)
			(xy 57.959753 -287.796796) (xy 57.947976 -287.749012) (xy 57.944016 -287.699958) (xy 57.553624 -287.699958)
			(xy 57.556302 -287.705061) (xy 57.571886 -287.751742) (xy 57.579781 -287.800319) (xy 57.580276 -287.824926)
			(xy 57.579781 -287.849533) (xy 57.571886 -287.89811) (xy 57.556302 -287.944791) (xy 57.533431 -287.988368)
			(xy 57.503866 -288.027712) (xy 57.468373 -288.061804) (xy 57.42787 -288.08976) (xy 57.383408 -288.110858)
			(xy 57.336137 -288.12455) (xy 57.287282 -288.130482) (xy 57.238107 -288.128501) (xy 57.189888 -288.118657)
			(xy 57.143872 -288.101205) (xy 57.101251 -288.076598) (xy 57.06313 -288.045473) (xy 57.030495 -288.008636)
			(xy 57.004192 -287.96704) (xy 56.984901 -287.921764) (xy 56.973124 -287.87398) (xy 56.969164 -287.824926)
			(xy 56.630062 -287.824926) (xy 56.629567 -287.849533) (xy 56.621672 -287.89811) (xy 56.606088 -287.944791)
			(xy 56.583217 -287.988368) (xy 56.553652 -288.027712) (xy 56.518159 -288.061804) (xy 56.477656 -288.08976)
			(xy 56.433194 -288.110858) (xy 56.385923 -288.12455) (xy 56.337068 -288.130482) (xy 56.287893 -288.128501)
			(xy 56.239674 -288.118657) (xy 56.193658 -288.101205) (xy 56.151037 -288.076598) (xy 56.112916 -288.045473)
			(xy 56.080281 -288.008636) (xy 56.053978 -287.96704) (xy 56.034687 -287.921764) (xy 56.02291 -287.87398)
			(xy 56.01895 -287.824926) (xy 55.680102 -287.824926) (xy 55.679607 -287.849533) (xy 55.671712 -287.89811)
			(xy 55.656128 -287.944791) (xy 55.633257 -287.988368) (xy 55.603692 -288.027712) (xy 55.568199 -288.061804)
			(xy 55.527696 -288.08976) (xy 55.483234 -288.110858) (xy 55.435963 -288.12455) (xy 55.387108 -288.130482)
			(xy 55.337933 -288.128501) (xy 55.289714 -288.118657) (xy 55.243698 -288.101205) (xy 55.201077 -288.076598)
			(xy 55.162956 -288.045473) (xy 55.130321 -288.008636) (xy 55.104018 -287.96704) (xy 55.084727 -287.921764)
			(xy 55.07295 -287.87398) (xy 55.06899 -287.824926) (xy 54.730142 -287.824926) (xy 54.729647 -287.849533)
			(xy 54.721752 -287.89811) (xy 54.706168 -287.944791) (xy 54.683297 -287.988368) (xy 54.653732 -288.027712)
			(xy 54.618239 -288.061804) (xy 54.577736 -288.08976) (xy 54.533274 -288.110858) (xy 54.486003 -288.12455)
			(xy 54.437148 -288.130482) (xy 54.387973 -288.128501) (xy 54.339754 -288.118657) (xy 54.293738 -288.101205)
			(xy 54.251117 -288.076598) (xy 54.212996 -288.045473) (xy 54.180361 -288.008636) (xy 54.154058 -287.96704)
			(xy 54.134767 -287.921764) (xy 54.12299 -287.87398) (xy 54.11903 -287.824926) (xy 53.780182 -287.824926)
			(xy 53.779687 -287.849533) (xy 53.771792 -287.89811) (xy 53.756208 -287.944791) (xy 53.733337 -287.988368)
			(xy 53.703772 -288.027712) (xy 53.668279 -288.061804) (xy 53.627776 -288.08976) (xy 53.583314 -288.110858)
			(xy 53.536043 -288.12455) (xy 53.487188 -288.130482) (xy 53.438013 -288.128501) (xy 53.389794 -288.118657)
			(xy 53.343778 -288.101205) (xy 53.301157 -288.076598) (xy 53.263036 -288.045473) (xy 53.230401 -288.008636)
			(xy 53.204098 -287.96704) (xy 53.184807 -287.921764) (xy 53.17303 -287.87398) (xy 53.16907 -287.824926)
			(xy 52.830222 -287.824926) (xy 52.829727 -287.849533) (xy 52.821832 -287.89811) (xy 52.806248 -287.944791)
			(xy 52.783377 -287.988368) (xy 52.753812 -288.027712) (xy 52.718319 -288.061804) (xy 52.677816 -288.08976)
			(xy 52.633354 -288.110858) (xy 52.586083 -288.12455) (xy 52.537228 -288.130482) (xy 52.488053 -288.128501)
			(xy 52.439834 -288.118657) (xy 52.393818 -288.101205) (xy 52.351197 -288.076598) (xy 52.313076 -288.045473)
			(xy 52.280441 -288.008636) (xy 52.254138 -287.96704) (xy 52.234847 -287.921764) (xy 52.22307 -287.87398)
			(xy 52.21911 -287.824926) (xy 51.880262 -287.824926) (xy 51.879767 -287.849533) (xy 51.871872 -287.89811)
			(xy 51.856288 -287.944791) (xy 51.833417 -287.988368) (xy 51.803852 -288.027712) (xy 51.768359 -288.061804)
			(xy 51.727856 -288.08976) (xy 51.683394 -288.110858) (xy 51.636123 -288.12455) (xy 51.587268 -288.130482)
			(xy 51.538093 -288.128501) (xy 51.489874 -288.118657) (xy 51.443858 -288.101205) (xy 51.401237 -288.076598)
			(xy 51.363116 -288.045473) (xy 51.330481 -288.008636) (xy 51.304178 -287.96704) (xy 51.284887 -287.921764)
			(xy 51.27311 -287.87398) (xy 51.26915 -287.824926) (xy 50.930302 -287.824926) (xy 50.929807 -287.849533)
			(xy 50.921912 -287.89811) (xy 50.906328 -287.944791) (xy 50.883457 -287.988368) (xy 50.853892 -288.027712)
			(xy 50.818399 -288.061804) (xy 50.777896 -288.08976) (xy 50.733434 -288.110858) (xy 50.686163 -288.12455)
			(xy 50.637308 -288.130482) (xy 50.588133 -288.128501) (xy 50.539914 -288.118657) (xy 50.493898 -288.101205)
			(xy 50.451277 -288.076598) (xy 50.413156 -288.045473) (xy 50.380521 -288.008636) (xy 50.354218 -287.96704)
			(xy 50.334927 -287.921764) (xy 50.32315 -287.87398) (xy 50.31919 -287.824926) (xy 49.980088 -287.824926)
			(xy 49.979593 -287.849533) (xy 49.971698 -287.89811) (xy 49.956114 -287.944791) (xy 49.933243 -287.988368)
			(xy 49.903678 -288.027712) (xy 49.868185 -288.061804) (xy 49.827682 -288.08976) (xy 49.78322 -288.110858)
			(xy 49.735949 -288.12455) (xy 49.687094 -288.130482) (xy 49.637919 -288.128501) (xy 49.5897 -288.118657)
			(xy 49.543684 -288.101205) (xy 49.501063 -288.076598) (xy 49.462942 -288.045473) (xy 49.430307 -288.008636)
			(xy 49.404004 -287.96704) (xy 49.384713 -287.921764) (xy 49.372936 -287.87398) (xy 49.368976 -287.824926)
			(xy 49.181004 -287.824926) (xy 49.181004 -288.299906) (xy 73.593972 -288.299906) (xy 73.597932 -288.250852)
			(xy 73.609709 -288.203068) (xy 73.629 -288.157792) (xy 73.655303 -288.116196) (xy 73.687938 -288.079359)
			(xy 73.726059 -288.048234) (xy 73.76868 -288.023627) (xy 73.814696 -288.006175) (xy 73.862915 -287.996331)
			(xy 73.91209 -287.99435) (xy 73.960945 -288.000282) (xy 74.008216 -288.013974) (xy 74.052678 -288.035072)
			(xy 74.093181 -288.063028) (xy 74.128674 -288.09712) (xy 74.158239 -288.136464) (xy 74.18111 -288.180041)
			(xy 74.196694 -288.226722) (xy 74.204589 -288.275299) (xy 74.205084 -288.299906) (xy 74.544186 -288.299906)
			(xy 74.548146 -288.250852) (xy 74.559923 -288.203068) (xy 74.579214 -288.157792) (xy 74.605517 -288.116196)
			(xy 74.638152 -288.079359) (xy 74.676273 -288.048234) (xy 74.718894 -288.023627) (xy 74.76491 -288.006175)
			(xy 74.813129 -287.996331) (xy 74.862304 -287.99435) (xy 74.911159 -288.000282) (xy 74.95843 -288.013974)
			(xy 75.002892 -288.035072) (xy 75.043395 -288.063028) (xy 75.078888 -288.09712) (xy 75.108453 -288.136464)
			(xy 75.131324 -288.180041) (xy 75.146908 -288.226722) (xy 75.154803 -288.275299) (xy 75.155298 -288.299906)
			(xy 75.494146 -288.299906) (xy 75.498106 -288.250852) (xy 75.509883 -288.203068) (xy 75.529174 -288.157792)
			(xy 75.555477 -288.116196) (xy 75.588112 -288.079359) (xy 75.626233 -288.048234) (xy 75.668854 -288.023627)
			(xy 75.71487 -288.006175) (xy 75.763089 -287.996331) (xy 75.812264 -287.99435) (xy 75.861119 -288.000282)
			(xy 75.90839 -288.013974) (xy 75.952852 -288.035072) (xy 75.993355 -288.063028) (xy 76.028848 -288.09712)
			(xy 76.058413 -288.136464) (xy 76.081284 -288.180041) (xy 76.096868 -288.226722) (xy 76.104763 -288.275299)
			(xy 76.105258 -288.299906) (xy 76.104763 -288.324513) (xy 76.104584 -288.325614) (xy 76.423262 -288.325614)
			(xy 76.423262 -288.274198) (xy 76.431305 -288.223416) (xy 76.447193 -288.174517) (xy 76.470536 -288.128705)
			(xy 76.500757 -288.087109) (xy 76.537113 -288.050753) (xy 76.578709 -288.020532) (xy 76.624521 -287.997189)
			(xy 76.67342 -287.981301) (xy 76.724202 -287.973258) (xy 76.775618 -287.973258) (xy 76.8264 -287.981301)
			(xy 76.875299 -287.997189) (xy 76.921111 -288.020532) (xy 76.962707 -288.050753) (xy 76.999063 -288.087109)
			(xy 77.029284 -288.128705) (xy 77.052627 -288.174517) (xy 77.068515 -288.223416) (xy 77.076558 -288.274198)
			(xy 77.077062 -288.299906) (xy 77.076558 -288.325614) (xy 77.373222 -288.325614) (xy 77.373222 -288.274198)
			(xy 77.381265 -288.223416) (xy 77.397153 -288.174517) (xy 77.420496 -288.128705) (xy 77.450717 -288.087109)
			(xy 77.487073 -288.050753) (xy 77.528669 -288.020532) (xy 77.574481 -287.997189) (xy 77.62338 -287.981301)
			(xy 77.674162 -287.973258) (xy 77.725578 -287.973258) (xy 77.77636 -287.981301) (xy 77.825259 -287.997189)
			(xy 77.871071 -288.020532) (xy 77.912667 -288.050753) (xy 77.949023 -288.087109) (xy 77.979244 -288.128705)
			(xy 78.002587 -288.174517) (xy 78.018475 -288.223416) (xy 78.026518 -288.274198) (xy 78.027022 -288.299906)
			(xy 78.026859 -288.308201) (xy 78.344052 -288.308201) (xy 78.346737 -288.258626) (xy 78.357407 -288.210138)
			(xy 78.375781 -288.164015) (xy 78.401375 -288.121473) (xy 78.433515 -288.083632) (xy 78.471354 -288.051489)
			(xy 78.513894 -288.025892) (xy 78.560015 -288.007514) (xy 78.608502 -287.99684) (xy 78.658077 -287.994151)
			(xy 78.707434 -287.999518) (xy 78.755272 -288.0128) (xy 78.800331 -288.033646) (xy 78.841424 -288.061507)
			(xy 78.877468 -288.09565) (xy 78.907514 -288.135174) (xy 78.930769 -288.179039) (xy 78.946621 -288.226088)
			(xy 78.954652 -288.275082) (xy 78.955138 -288.299906) (xy 78.954962 -288.314089) (xy 78.952289 -288.342329)
			(xy 78.949804 -288.356294) (xy 78.947518 -288.36874) (xy 78.954884 -288.392362) (xy 79.032354 -288.469832)
			(xy 79.055976 -288.477198) (xy 79.068422 -288.474912) (xy 79.082388 -288.472437) (xy 79.110628 -288.469764)
			(xy 79.12481 -288.469578) (xy 79.134681 -288.46965) (xy 79.154382 -288.470922) (xy 79.16418 -288.472118)
			(xy 79.176118 -288.473642) (xy 79.198724 -288.465768) (xy 79.272384 -288.389314) (xy 79.279242 -288.366454)
			(xy 79.277464 -288.354516) (xy 79.275308 -288.340967) (xy 79.27302 -288.313625) (xy 79.272892 -288.299906)
			(xy 79.273396 -288.274218) (xy 79.281433 -288.223475) (xy 79.297309 -288.174614) (xy 79.320633 -288.128838)
			(xy 79.35083 -288.087274) (xy 79.387158 -288.050946) (xy 79.428722 -288.020749) (xy 79.474498 -287.997425)
			(xy 79.523359 -287.981549) (xy 79.574102 -287.973512) (xy 79.625478 -287.973512) (xy 79.676221 -287.981549)
			(xy 79.725082 -287.997425) (xy 79.770858 -288.020749) (xy 79.812422 -288.050946) (xy 79.84875 -288.087274)
			(xy 79.878947 -288.128838) (xy 79.902271 -288.174614) (xy 79.918147 -288.223475) (xy 79.926184 -288.274218)
			(xy 79.926688 -288.299906) (xy 79.926541 -288.313624) (xy 79.924253 -288.340965) (xy 79.922116 -288.354516)
			(xy 79.920338 -288.366454) (xy 79.927196 -288.389314) (xy 80.000856 -288.465768) (xy 80.023462 -288.473642)
			(xy 80.0354 -288.472118) (xy 80.045199 -288.470925) (xy 80.064899 -288.469657) (xy 80.07477 -288.469578)
			(xy 80.084641 -288.469654) (xy 80.104342 -288.470923) (xy 80.11414 -288.472118) (xy 80.126078 -288.473642)
			(xy 80.148684 -288.465768) (xy 80.222344 -288.389314) (xy 80.229202 -288.366454) (xy 80.227424 -288.354516)
			(xy 80.225267 -288.340967) (xy 80.22298 -288.313625) (xy 80.222852 -288.299906) (xy 80.223356 -288.274218)
			(xy 80.231393 -288.223475) (xy 80.247269 -288.174614) (xy 80.270593 -288.128838) (xy 80.30079 -288.087274)
			(xy 80.337118 -288.050946) (xy 80.378682 -288.020749) (xy 80.424458 -287.997425) (xy 80.473319 -287.981549)
			(xy 80.524062 -287.973512) (xy 80.575438 -287.973512) (xy 80.626181 -287.981549) (xy 80.675042 -287.997425)
			(xy 80.720818 -288.020749) (xy 80.762382 -288.050946) (xy 80.79871 -288.087274) (xy 80.828907 -288.128838)
			(xy 80.852231 -288.174614) (xy 80.868107 -288.223475) (xy 80.876144 -288.274218) (xy 80.876648 -288.299906)
			(xy 80.876501 -288.313624) (xy 80.874213 -288.340965) (xy 80.872076 -288.354516) (xy 80.870044 -288.366454)
			(xy 80.877156 -288.389314) (xy 80.950816 -288.465768) (xy 80.973422 -288.473642) (xy 80.985614 -288.472118)
			(xy 80.995414 -288.470933) (xy 81.015113 -288.46966) (xy 81.024984 -288.469578) (xy 81.039167 -288.469757)
			(xy 81.067407 -288.472428) (xy 81.081372 -288.474912) (xy 81.093818 -288.477198) (xy 81.11744 -288.469832)
			(xy 81.19491 -288.392362) (xy 81.202276 -288.36874) (xy 81.19999 -288.356294) (xy 81.197516 -288.342328)
			(xy 81.194843 -288.314088) (xy 81.194656 -288.299906) (xy 81.195178 -288.274651) (xy 81.203491 -288.224829)
			(xy 81.219892 -288.177055) (xy 81.243933 -288.132632) (xy 81.274957 -288.092772) (xy 81.312119 -288.058562)
			(xy 81.354405 -288.030936) (xy 81.400661 -288.010646) (xy 81.449626 -287.998246) (xy 81.499964 -287.994075)
			(xy 81.550302 -287.998246) (xy 81.599267 -288.010646) (xy 81.645523 -288.030936) (xy 81.687809 -288.058562)
			(xy 81.724971 -288.092772) (xy 81.755995 -288.132632) (xy 81.780036 -288.177055) (xy 81.796437 -288.224829)
			(xy 81.80475 -288.274651) (xy 81.805272 -288.299906) (xy 81.805097 -288.314089) (xy 81.802424 -288.342329)
			(xy 81.799938 -288.356294) (xy 81.797652 -288.36874) (xy 81.805018 -288.392362) (xy 81.882488 -288.469832)
			(xy 81.90611 -288.477198) (xy 81.918556 -288.474912) (xy 81.932521 -288.472432) (xy 81.960761 -288.469763)
			(xy 81.974944 -288.469578) (xy 81.989127 -288.469763) (xy 82.017367 -288.472429) (xy 82.031332 -288.474912)
			(xy 82.043778 -288.477198) (xy 82.0674 -288.469832) (xy 82.14487 -288.392362) (xy 82.152236 -288.36874)
			(xy 82.14995 -288.356294) (xy 82.147477 -288.342328) (xy 82.144803 -288.314088) (xy 82.144616 -288.299906)
			(xy 82.145138 -288.274651) (xy 82.153451 -288.224829) (xy 82.169852 -288.177055) (xy 82.193893 -288.132632)
			(xy 82.224917 -288.092772) (xy 82.262079 -288.058562) (xy 82.304365 -288.030936) (xy 82.350621 -288.010646)
			(xy 82.399586 -287.998246) (xy 82.449924 -287.994075) (xy 82.500262 -287.998246) (xy 82.549227 -288.010646)
			(xy 82.595483 -288.030936) (xy 82.637769 -288.058562) (xy 82.674931 -288.092772) (xy 82.705955 -288.132632)
			(xy 82.729996 -288.177055) (xy 82.746397 -288.224829) (xy 82.750339 -288.248452) (xy 87.595944 -288.248452)
			(xy 87.595944 -288.193948) (xy 87.6037 -288.139999) (xy 87.619055 -288.087702) (xy 87.641695 -288.038123)
			(xy 87.671161 -287.99227) (xy 87.706852 -287.951077) (xy 87.748041 -287.915382) (xy 87.793891 -287.885913)
			(xy 87.843468 -287.863267) (xy 87.895763 -287.847908) (xy 87.949712 -287.840146) (xy 87.976964 -287.839658)
			(xy 88.003079 -287.840142) (xy 88.054821 -287.847275) (xy 88.105106 -287.861398) (xy 88.152996 -287.882247)
			(xy 88.197594 -287.909433) (xy 88.238067 -287.942448) (xy 88.273659 -287.980675) (xy 88.303705 -288.023399)
			(xy 88.316054 -288.046414) (xy 88.322658 -288.059368) (xy 88.346788 -288.0741) (xy 88.466168 -288.0741)
			(xy 88.490298 -288.059368) (xy 88.496902 -288.046414) (xy 88.510278 -288.021628) (xy 88.543152 -287.975899)
			(xy 88.582393 -287.935501) (xy 88.627148 -287.901312) (xy 88.676444 -287.874076) (xy 88.729209 -287.854386)
			(xy 88.784296 -287.842669) (xy 88.81237 -287.84042) (xy 88.823292 -287.839658) (xy 88.84285 -287.829244)
			(xy 88.902794 -287.749996) (xy 88.90762 -287.728406) (xy 88.905334 -287.717484) (xy 88.900979 -287.696416)
			(xy 88.896272 -287.653651) (xy 88.895936 -287.63214) (xy 88.896447 -287.603492) (xy 88.904601 -287.546778)
			(xy 88.920744 -287.491803) (xy 88.944545 -287.439684) (xy 88.975522 -287.391483) (xy 89.013043 -287.348181)
			(xy 89.056345 -287.31066) (xy 89.104546 -287.279683) (xy 89.156665 -287.255882) (xy 89.21164 -287.239739)
			(xy 89.268354 -287.231585) (xy 89.32565 -287.231585) (xy 89.382364 -287.239739) (xy 89.437339 -287.255882)
			(xy 89.489458 -287.279683) (xy 89.537659 -287.31066) (xy 89.580961 -287.348181) (xy 89.618482 -287.391483)
			(xy 89.649459 -287.439684) (xy 89.67326 -287.491803) (xy 89.689403 -287.546778) (xy 89.697557 -287.603492)
			(xy 89.698068 -287.63214) (xy 89.697744 -287.654301) (xy 89.692774 -287.698345) (xy 89.688162 -287.720024)
			(xy 89.685368 -287.73247) (xy 89.691718 -287.756346) (xy 89.765124 -287.836356) (xy 89.788492 -287.844738)
			(xy 89.800938 -287.843214) (xy 89.813639 -287.84158) (xy 89.839187 -287.839801) (xy 89.851992 -287.839658)
			(xy 89.871307 -287.839909) (xy 89.909737 -287.843853) (xy 89.9287 -287.847532) (xy 89.94267 -287.850326)
			(xy 89.969594 -287.840674) (xy 90.044016 -287.747202) (xy 90.047572 -287.718754) (xy 90.041476 -287.705546)
			(xy 90.029955 -287.679249) (xy 90.013688 -287.624189) (xy 90.00543 -287.567373) (xy 90.0049 -287.538668)
			(xy 90.005411 -287.51002) (xy 90.013565 -287.453306) (xy 90.029708 -287.398331) (xy 90.053509 -287.346212)
			(xy 90.084486 -287.298011) (xy 90.122007 -287.254709) (xy 90.165309 -287.217188) (xy 90.21351 -287.186211)
			(xy 90.265629 -287.16241) (xy 90.320604 -287.146267) (xy 90.377318 -287.138113) (xy 90.434614 -287.138113)
			(xy 90.491328 -287.146267) (xy 90.546303 -287.16241) (xy 90.598422 -287.186211) (xy 90.646623 -287.217188)
			(xy 90.689925 -287.254709) (xy 90.727446 -287.298011) (xy 90.758423 -287.346212) (xy 90.782224 -287.398331)
			(xy 90.798367 -287.453306) (xy 90.806521 -287.51002) (xy 90.807032 -287.538668) (xy 90.806542 -287.565932)
			(xy 90.799096 -287.61995) (xy 90.784416 -287.672466) (xy 90.774012 -287.697672) (xy 90.768932 -287.70961)
			(xy 90.770964 -287.73501) (xy 90.831924 -287.82772) (xy 90.85453 -287.839658) (xy 90.867484 -287.839658)
			(xy 90.894759 -287.840128) (xy 90.948761 -287.847825) (xy 91.001117 -287.863134) (xy 91.050759 -287.885744)
			(xy 91.096674 -287.915194) (xy 91.137927 -287.950884) (xy 91.173676 -287.992085) (xy 91.203192 -288.037957)
			(xy 91.225874 -288.087567) (xy 91.241259 -288.1399) (xy 91.249033 -288.193892) (xy 91.2495 -288.221166)
			(xy 91.469716 -288.221166) (xy 91.473787 -288.165544) (xy 91.485913 -288.111107) (xy 91.505836 -288.059016)
			(xy 91.533132 -288.010381) (xy 91.567218 -287.966238) (xy 91.607367 -287.927529) (xy 91.652725 -287.895078)
			(xy 91.702325 -287.869577) (xy 91.755109 -287.85157) (xy 91.809952 -287.84144) (xy 91.865686 -287.839403)
			(xy 91.921123 -287.845503) (xy 91.97508 -287.859609) (xy 92.026409 -287.881421) (xy 92.074015 -287.910475)
			(xy 92.116883 -287.94615) (xy 92.1541 -287.987687) (xy 92.184873 -288.0342) (xy 92.208545 -288.084697)
			(xy 92.21873 -288.11855) (xy 92.517974 -288.11855) (xy 92.522045 -288.062928) (xy 92.534171 -288.008491)
			(xy 92.554094 -287.9564) (xy 92.58139 -287.907765) (xy 92.615476 -287.863622) (xy 92.655625 -287.824913)
			(xy 92.700983 -287.792462) (xy 92.750583 -287.766961) (xy 92.803367 -287.748954) (xy 92.85821 -287.738824)
			(xy 92.913944 -287.736787) (xy 92.969381 -287.742887) (xy 93.023338 -287.756993) (xy 93.074667 -287.778805)
			(xy 93.122273 -287.807859) (xy 93.165141 -287.843534) (xy 93.202358 -287.885071) (xy 93.233131 -287.931584)
			(xy 93.256803 -287.982081) (xy 93.272871 -288.035488) (xy 93.280991 -288.090664) (xy 93.2815 -288.11855)
			(xy 93.280991 -288.146436) (xy 93.272871 -288.201612) (xy 93.256803 -288.255019) (xy 93.233131 -288.305516)
			(xy 93.202358 -288.352029) (xy 93.165141 -288.393566) (xy 93.122273 -288.429241) (xy 93.074667 -288.458295)
			(xy 93.023338 -288.480107) (xy 92.969381 -288.494213) (xy 92.913944 -288.500313) (xy 92.85821 -288.498276)
			(xy 92.803367 -288.488146) (xy 92.750583 -288.470139) (xy 92.700983 -288.444638) (xy 92.655625 -288.412187)
			(xy 92.615476 -288.373478) (xy 92.58139 -288.329335) (xy 92.554094 -288.2807) (xy 92.534171 -288.228609)
			(xy 92.522045 -288.174172) (xy 92.517974 -288.11855) (xy 92.21873 -288.11855) (xy 92.224613 -288.138104)
			(xy 92.232733 -288.19328) (xy 92.233242 -288.221166) (xy 92.232733 -288.249052) (xy 92.224613 -288.304228)
			(xy 92.208545 -288.357635) (xy 92.184873 -288.408132) (xy 92.1541 -288.454645) (xy 92.116883 -288.496182)
			(xy 92.074015 -288.531857) (xy 92.026409 -288.560911) (xy 91.97508 -288.582723) (xy 91.921123 -288.596829)
			(xy 91.865686 -288.602929) (xy 91.809952 -288.600892) (xy 91.755109 -288.590762) (xy 91.702325 -288.572755)
			(xy 91.652725 -288.547254) (xy 91.607367 -288.514803) (xy 91.567218 -288.476094) (xy 91.533132 -288.431951)
			(xy 91.505836 -288.383316) (xy 91.485913 -288.331225) (xy 91.473787 -288.276788) (xy 91.469716 -288.221166)
			(xy 91.2495 -288.221166) (xy 91.249014 -288.248417) (xy 91.241258 -288.302365) (xy 91.225903 -288.35466)
			(xy 91.203261 -288.404237) (xy 91.173795 -288.450087) (xy 91.138104 -288.491278) (xy 91.096913 -288.526969)
			(xy 91.051063 -288.556435) (xy 91.001486 -288.579077) (xy 90.949191 -288.594432) (xy 90.895243 -288.602188)
			(xy 90.840741 -288.602188) (xy 90.786793 -288.594432) (xy 90.734498 -288.579077) (xy 90.684921 -288.556435)
			(xy 90.639071 -288.526969) (xy 90.59788 -288.491278) (xy 90.562189 -288.450087) (xy 90.532723 -288.404237)
			(xy 90.510081 -288.35466) (xy 90.494726 -288.302365) (xy 90.48697 -288.248417) (xy 90.486484 -288.221166)
			(xy 90.486857 -288.196867) (xy 90.493011 -288.14866) (xy 90.505227 -288.101622) (xy 90.513916 -288.078926)
			(xy 90.518742 -288.066988) (xy 90.515948 -288.041588) (xy 90.452702 -287.950656) (xy 90.429842 -287.939226)
			(xy 90.416888 -287.93948) (xy 90.405966 -287.93948) (xy 90.383684 -287.939221) (xy 90.339386 -287.934387)
			(xy 90.317574 -287.929828) (xy 90.303604 -287.926526) (xy 90.276426 -287.93567) (xy 90.200226 -288.027872)
			(xy 90.196162 -288.056066) (xy 90.202004 -288.069274) (xy 90.21194 -288.093353) (xy 90.225964 -288.143518)
			(xy 90.233051 -288.195122) (xy 90.2335 -288.221166) (xy 90.233014 -288.248417) (xy 90.225258 -288.302365)
			(xy 90.209903 -288.35466) (xy 90.187261 -288.404237) (xy 90.157795 -288.450087) (xy 90.122104 -288.491278)
			(xy 90.080913 -288.526969) (xy 90.035063 -288.556435) (xy 89.985486 -288.579077) (xy 89.933191 -288.594432)
			(xy 89.879243 -288.602188) (xy 89.824741 -288.602188) (xy 89.770793 -288.594432) (xy 89.718498 -288.579077)
			(xy 89.668921 -288.556435) (xy 89.623071 -288.526969) (xy 89.58188 -288.491278) (xy 89.546189 -288.450087)
			(xy 89.516723 -288.404237) (xy 89.494081 -288.35466) (xy 89.478726 -288.302365) (xy 89.47097 -288.248417)
			(xy 89.470484 -288.221166) (xy 89.470694 -288.202696) (xy 89.474255 -288.165927) (xy 89.477596 -288.14776)
			(xy 89.480136 -288.135314) (xy 89.473024 -288.111692) (xy 89.397586 -288.033714) (xy 89.373964 -288.02584)
			(xy 89.361518 -288.027872) (xy 89.34833 -288.029905) (xy 89.321766 -288.032449) (xy 89.308432 -288.032952)
			(xy 89.297256 -288.033206) (xy 89.277444 -288.043112) (xy 89.214706 -288.120328) (xy 89.209372 -288.141664)
			(xy 89.211404 -288.152586) (xy 89.214291 -288.169583) (xy 89.217344 -288.203926) (xy 89.2175 -288.221166)
			(xy 89.217013 -288.248418) (xy 89.20926 -288.302369) (xy 89.193908 -288.354667) (xy 89.171269 -288.404247)
			(xy 89.141804 -288.450101) (xy 89.106113 -288.491294) (xy 89.064922 -288.526988) (xy 89.01907 -288.556457)
			(xy 88.969491 -288.579099) (xy 88.917194 -288.594455) (xy 88.863244 -288.602211) (xy 88.835992 -288.602674)
			(xy 88.809874 -288.602262) (xy 88.758127 -288.595122) (xy 88.707839 -288.580991) (xy 88.659947 -288.560132)
			(xy 88.615349 -288.532936) (xy 88.574877 -288.49991) (xy 88.539288 -288.461673) (xy 88.509248 -288.418938)
			(xy 88.496902 -288.395918) (xy 88.490298 -288.382964) (xy 88.466168 -288.368232) (xy 88.346788 -288.368232)
			(xy 88.322658 -288.382964) (xy 88.316054 -288.395918) (xy 88.30371 -288.41894) (xy 88.273678 -288.461682)
			(xy 88.238093 -288.499925) (xy 88.197622 -288.532953) (xy 88.153021 -288.560148) (xy 88.105126 -288.581002)
			(xy 88.054833 -288.595123) (xy 88.003083 -288.602248) (xy 87.976964 -288.602674) (xy 87.949712 -288.602254)
			(xy 87.895763 -288.594492) (xy 87.843468 -288.579133) (xy 87.793891 -288.556487) (xy 87.748041 -288.527018)
			(xy 87.706852 -288.491323) (xy 87.671161 -288.45013) (xy 87.641695 -288.404277) (xy 87.619055 -288.354698)
			(xy 87.6037 -288.302401) (xy 87.595944 -288.248452) (xy 82.750339 -288.248452) (xy 82.75471 -288.274651)
			(xy 82.755232 -288.299906) (xy 82.755056 -288.314089) (xy 82.752383 -288.342329) (xy 82.749898 -288.356294)
			(xy 82.747612 -288.36874) (xy 82.754978 -288.392362) (xy 82.832448 -288.469832) (xy 82.85607 -288.477198)
			(xy 82.868516 -288.474912) (xy 82.882482 -288.472437) (xy 82.910722 -288.469764) (xy 82.924904 -288.469578)
			(xy 82.949725 -288.470082) (xy 82.998712 -288.478114) (xy 83.045755 -288.493965) (xy 83.089613 -288.517218)
			(xy 83.129132 -288.547261) (xy 83.163269 -288.583301) (xy 83.191127 -288.624389) (xy 83.21197 -288.669443)
			(xy 83.225249 -288.717275) (xy 83.230615 -288.766626) (xy 83.227926 -288.816194) (xy 83.217254 -288.864675)
			(xy 83.198878 -288.91079) (xy 83.173284 -288.953325) (xy 83.141146 -288.991159) (xy 83.10331 -289.023295)
			(xy 83.060774 -289.048886) (xy 83.014658 -289.067259) (xy 82.966176 -289.077929) (xy 82.916608 -289.080615)
			(xy 82.867257 -289.075246) (xy 82.819426 -289.061963) (xy 82.774373 -289.041118) (xy 82.733287 -289.013258)
			(xy 82.697249 -288.979118) (xy 82.667209 -288.939598) (xy 82.643958 -288.895738) (xy 82.62811 -288.848695)
			(xy 82.620081 -288.799707) (xy 82.619596 -288.774886) (xy 82.619771 -288.760703) (xy 82.622444 -288.732463)
			(xy 82.62493 -288.718498) (xy 82.627216 -288.706052) (xy 82.61985 -288.68243) (xy 82.54238 -288.60496)
			(xy 82.518758 -288.597594) (xy 82.506312 -288.59988) (xy 82.492345 -288.602351) (xy 82.464106 -288.605026)
			(xy 82.449924 -288.605214) (xy 82.435741 -288.605034) (xy 82.407501 -288.602364) (xy 82.393536 -288.59988)
			(xy 82.38109 -288.597594) (xy 82.357468 -288.60496) (xy 82.279998 -288.68243) (xy 82.272632 -288.706052)
			(xy 82.274918 -288.718498) (xy 82.27739 -288.732465) (xy 82.280065 -288.760704) (xy 82.280252 -288.774886)
			(xy 82.27973 -288.800141) (xy 82.271417 -288.849963) (xy 82.255016 -288.897737) (xy 82.230975 -288.94216)
			(xy 82.199951 -288.98202) (xy 82.162789 -289.01623) (xy 82.120503 -289.043856) (xy 82.074247 -289.064146)
			(xy 82.025282 -289.076546) (xy 81.974944 -289.080717) (xy 81.924606 -289.076546) (xy 81.875641 -289.064146)
			(xy 81.829385 -289.043856) (xy 81.787099 -289.01623) (xy 81.749937 -288.98202) (xy 81.718913 -288.94216)
			(xy 81.694872 -288.897737) (xy 81.678471 -288.849963) (xy 81.670158 -288.800141) (xy 81.669636 -288.774886)
			(xy 81.66981 -288.760703) (xy 81.672484 -288.732463) (xy 81.67497 -288.718498) (xy 81.677256 -288.706052)
			(xy 81.66989 -288.68243) (xy 81.59242 -288.60496) (xy 81.568798 -288.597594) (xy 81.556352 -288.59988)
			(xy 81.542387 -288.602359) (xy 81.514147 -288.605029) (xy 81.499964 -288.605214) (xy 81.485781 -288.605042)
			(xy 81.457541 -288.602367) (xy 81.443576 -288.59988) (xy 81.43113 -288.597594) (xy 81.407508 -288.60496)
			(xy 81.330038 -288.68243) (xy 81.322672 -288.706052) (xy 81.324958 -288.718498) (xy 81.32743 -288.732465)
			(xy 81.330105 -288.760704) (xy 81.330292 -288.774886) (xy 81.32977 -288.800141) (xy 81.321457 -288.849963)
			(xy 81.305056 -288.897737) (xy 81.281015 -288.94216) (xy 81.249991 -288.98202) (xy 81.212829 -289.01623)
			(xy 81.170543 -289.043856) (xy 81.124287 -289.064146) (xy 81.075322 -289.076546) (xy 81.024984 -289.080717)
			(xy 80.974646 -289.076546) (xy 80.925681 -289.064146) (xy 80.879425 -289.043856) (xy 80.837139 -289.01623)
			(xy 80.799977 -288.98202) (xy 80.768953 -288.94216) (xy 80.744912 -288.897737) (xy 80.728511 -288.849963)
			(xy 80.720198 -288.800141) (xy 80.719676 -288.774886) (xy 80.719747 -288.765015) (xy 80.721019 -288.745314)
			(xy 80.722216 -288.735516) (xy 80.72374 -288.723578) (xy 80.715866 -288.700718) (xy 80.639412 -288.627312)
			(xy 80.616552 -288.6202) (xy 80.60436 -288.622232) (xy 80.59081 -288.624383) (xy 80.563469 -288.626674)
			(xy 80.54975 -288.626804) (xy 80.536032 -288.626663) (xy 80.508691 -288.624371) (xy 80.49514 -288.622232)
			(xy 80.483202 -288.620454) (xy 80.460342 -288.627312) (xy 80.383888 -288.700972) (xy 80.376014 -288.723578)
			(xy 80.377538 -288.735516) (xy 80.378723 -288.745316) (xy 80.379996 -288.765015) (xy 80.380078 -288.774886)
			(xy 80.379556 -288.800141) (xy 80.371243 -288.849963) (xy 80.354842 -288.897737) (xy 80.330801 -288.94216)
			(xy 80.299777 -288.98202) (xy 80.262615 -289.01623) (xy 80.220329 -289.043856) (xy 80.174073 -289.064146)
			(xy 80.125108 -289.076546) (xy 80.07477 -289.080717) (xy 80.024432 -289.076546) (xy 79.975467 -289.064146)
			(xy 79.929211 -289.043856) (xy 79.886925 -289.01623) (xy 79.849763 -288.98202) (xy 79.818739 -288.94216)
			(xy 79.794698 -288.897737) (xy 79.778297 -288.849963) (xy 79.769984 -288.800141) (xy 79.769462 -288.774886)
			(xy 79.769533 -288.765015) (xy 79.770805 -288.745314) (xy 79.772002 -288.735516) (xy 79.773526 -288.723578)
			(xy 79.765652 -288.700972) (xy 79.689198 -288.627312) (xy 79.666338 -288.620454) (xy 79.6544 -288.622232)
			(xy 79.640851 -288.62439) (xy 79.613509 -288.626677) (xy 79.59979 -288.626804) (xy 79.586072 -288.626658)
			(xy 79.558731 -288.62437) (xy 79.54518 -288.622232) (xy 79.533242 -288.620454) (xy 79.510382 -288.627312)
			(xy 79.433928 -288.700972) (xy 79.426054 -288.723578) (xy 79.427578 -288.735516) (xy 79.428763 -288.745316)
			(xy 79.430036 -288.765015) (xy 79.430118 -288.774886) (xy 79.429596 -288.800141) (xy 79.421283 -288.849963)
			(xy 79.404882 -288.897737) (xy 79.380841 -288.94216) (xy 79.349817 -288.98202) (xy 79.312655 -289.01623)
			(xy 79.270369 -289.043856) (xy 79.224113 -289.064146) (xy 79.175148 -289.076546) (xy 79.12481 -289.080717)
			(xy 79.074472 -289.076546) (xy 79.025507 -289.064146) (xy 78.979251 -289.043856) (xy 78.936965 -289.01623)
			(xy 78.899803 -288.98202) (xy 78.868779 -288.94216) (xy 78.844738 -288.897737) (xy 78.828337 -288.849963)
			(xy 78.820024 -288.800141) (xy 78.819502 -288.774886) (xy 78.819677 -288.760703) (xy 78.82235 -288.732463)
			(xy 78.824836 -288.718498) (xy 78.827122 -288.706052) (xy 78.819756 -288.68243) (xy 78.742286 -288.60496)
			(xy 78.718664 -288.597594) (xy 78.706218 -288.59988) (xy 78.692253 -288.602364) (xy 78.664013 -288.605031)
			(xy 78.64983 -288.605214) (xy 78.625006 -288.604754) (xy 78.576012 -288.596727) (xy 78.528961 -288.580879)
			(xy 78.485095 -288.557627) (xy 78.445568 -288.527584) (xy 78.411422 -288.491543) (xy 78.383558 -288.450452)
			(xy 78.362708 -288.405394) (xy 78.349423 -288.357557) (xy 78.344052 -288.308201) (xy 78.026859 -288.308201)
			(xy 78.026518 -288.325614) (xy 78.018475 -288.376396) (xy 78.002587 -288.425295) (xy 77.979244 -288.471107)
			(xy 77.949023 -288.512703) (xy 77.912667 -288.549059) (xy 77.871071 -288.57928) (xy 77.825259 -288.602623)
			(xy 77.77636 -288.618511) (xy 77.725578 -288.626554) (xy 77.674162 -288.626554) (xy 77.62338 -288.618511)
			(xy 77.574481 -288.602623) (xy 77.528669 -288.57928) (xy 77.487073 -288.549059) (xy 77.450717 -288.512703)
			(xy 77.420496 -288.471107) (xy 77.397153 -288.425295) (xy 77.381265 -288.376396) (xy 77.373222 -288.325614)
			(xy 77.076558 -288.325614) (xy 77.068515 -288.376396) (xy 77.052627 -288.425295) (xy 77.029284 -288.471107)
			(xy 76.999063 -288.512703) (xy 76.962707 -288.549059) (xy 76.921111 -288.57928) (xy 76.875299 -288.602623)
			(xy 76.8264 -288.618511) (xy 76.775618 -288.626554) (xy 76.724202 -288.626554) (xy 76.67342 -288.618511)
			(xy 76.624521 -288.602623) (xy 76.578709 -288.57928) (xy 76.537113 -288.549059) (xy 76.500757 -288.512703)
			(xy 76.470536 -288.471107) (xy 76.447193 -288.425295) (xy 76.431305 -288.376396) (xy 76.423262 -288.325614)
			(xy 76.104584 -288.325614) (xy 76.096868 -288.37309) (xy 76.081284 -288.419771) (xy 76.058413 -288.463348)
			(xy 76.028848 -288.502692) (xy 75.993355 -288.536784) (xy 75.952852 -288.56474) (xy 75.90839 -288.585838)
			(xy 75.861119 -288.59953) (xy 75.812264 -288.605462) (xy 75.763089 -288.603481) (xy 75.71487 -288.593637)
			(xy 75.668854 -288.576185) (xy 75.626233 -288.551578) (xy 75.588112 -288.520453) (xy 75.555477 -288.483616)
			(xy 75.529174 -288.44202) (xy 75.509883 -288.396744) (xy 75.498106 -288.34896) (xy 75.494146 -288.299906)
			(xy 75.155298 -288.299906) (xy 75.154803 -288.324513) (xy 75.146908 -288.37309) (xy 75.131324 -288.419771)
			(xy 75.108453 -288.463348) (xy 75.078888 -288.502692) (xy 75.043395 -288.536784) (xy 75.002892 -288.56474)
			(xy 74.95843 -288.585838) (xy 74.911159 -288.59953) (xy 74.862304 -288.605462) (xy 74.813129 -288.603481)
			(xy 74.76491 -288.593637) (xy 74.718894 -288.576185) (xy 74.676273 -288.551578) (xy 74.638152 -288.520453)
			(xy 74.605517 -288.483616) (xy 74.579214 -288.44202) (xy 74.559923 -288.396744) (xy 74.548146 -288.34896)
			(xy 74.544186 -288.299906) (xy 74.205084 -288.299906) (xy 74.204589 -288.324513) (xy 74.196694 -288.37309)
			(xy 74.18111 -288.419771) (xy 74.158239 -288.463348) (xy 74.128674 -288.502692) (xy 74.093181 -288.536784)
			(xy 74.052678 -288.56474) (xy 74.008216 -288.585838) (xy 73.960945 -288.59953) (xy 73.91209 -288.605462)
			(xy 73.862915 -288.603481) (xy 73.814696 -288.593637) (xy 73.76868 -288.576185) (xy 73.726059 -288.551578)
			(xy 73.687938 -288.520453) (xy 73.655303 -288.483616) (xy 73.629 -288.44202) (xy 73.609709 -288.396744)
			(xy 73.597932 -288.34896) (xy 73.593972 -288.299906) (xy 49.181004 -288.299906) (xy 49.181004 -288.774886)
			(xy 49.368976 -288.774886) (xy 49.372936 -288.725832) (xy 49.384713 -288.678048) (xy 49.404004 -288.632772)
			(xy 49.430307 -288.591176) (xy 49.462942 -288.554339) (xy 49.501063 -288.523214) (xy 49.543684 -288.498607)
			(xy 49.5897 -288.481155) (xy 49.637919 -288.471311) (xy 49.687094 -288.46933) (xy 49.735949 -288.475262)
			(xy 49.78322 -288.488954) (xy 49.827682 -288.510052) (xy 49.868185 -288.538008) (xy 49.903678 -288.5721)
			(xy 49.933243 -288.611444) (xy 49.956114 -288.655021) (xy 49.971698 -288.701702) (xy 49.979593 -288.750279)
			(xy 49.980088 -288.774886) (xy 50.31919 -288.774886) (xy 50.32315 -288.725832) (xy 50.334927 -288.678048)
			(xy 50.354218 -288.632772) (xy 50.380521 -288.591176) (xy 50.413156 -288.554339) (xy 50.451277 -288.523214)
			(xy 50.493898 -288.498607) (xy 50.539914 -288.481155) (xy 50.588133 -288.471311) (xy 50.637308 -288.46933)
			(xy 50.686163 -288.475262) (xy 50.733434 -288.488954) (xy 50.777896 -288.510052) (xy 50.818399 -288.538008)
			(xy 50.853892 -288.5721) (xy 50.883457 -288.611444) (xy 50.906328 -288.655021) (xy 50.921912 -288.701702)
			(xy 50.929807 -288.750279) (xy 50.930302 -288.774886) (xy 51.26915 -288.774886) (xy 51.27311 -288.725832)
			(xy 51.284887 -288.678048) (xy 51.304178 -288.632772) (xy 51.330481 -288.591176) (xy 51.363116 -288.554339)
			(xy 51.401237 -288.523214) (xy 51.443858 -288.498607) (xy 51.489874 -288.481155) (xy 51.538093 -288.471311)
			(xy 51.587268 -288.46933) (xy 51.636123 -288.475262) (xy 51.683394 -288.488954) (xy 51.727856 -288.510052)
			(xy 51.768359 -288.538008) (xy 51.803852 -288.5721) (xy 51.833417 -288.611444) (xy 51.856288 -288.655021)
			(xy 51.871872 -288.701702) (xy 51.879767 -288.750279) (xy 51.880262 -288.774886) (xy 52.21911 -288.774886)
			(xy 52.22307 -288.725832) (xy 52.234847 -288.678048) (xy 52.254138 -288.632772) (xy 52.280441 -288.591176)
			(xy 52.313076 -288.554339) (xy 52.351197 -288.523214) (xy 52.393818 -288.498607) (xy 52.439834 -288.481155)
			(xy 52.488053 -288.471311) (xy 52.537228 -288.46933) (xy 52.586083 -288.475262) (xy 52.633354 -288.488954)
			(xy 52.677816 -288.510052) (xy 52.718319 -288.538008) (xy 52.753812 -288.5721) (xy 52.783377 -288.611444)
			(xy 52.806248 -288.655021) (xy 52.821832 -288.701702) (xy 52.829727 -288.750279) (xy 52.830222 -288.774886)
			(xy 53.16907 -288.774886) (xy 53.17303 -288.725832) (xy 53.184807 -288.678048) (xy 53.204098 -288.632772)
			(xy 53.230401 -288.591176) (xy 53.263036 -288.554339) (xy 53.301157 -288.523214) (xy 53.343778 -288.498607)
			(xy 53.389794 -288.481155) (xy 53.438013 -288.471311) (xy 53.487188 -288.46933) (xy 53.536043 -288.475262)
			(xy 53.583314 -288.488954) (xy 53.627776 -288.510052) (xy 53.668279 -288.538008) (xy 53.703772 -288.5721)
			(xy 53.733337 -288.611444) (xy 53.756208 -288.655021) (xy 53.771792 -288.701702) (xy 53.779687 -288.750279)
			(xy 53.780182 -288.774886) (xy 54.11903 -288.774886) (xy 54.12299 -288.725832) (xy 54.134767 -288.678048)
			(xy 54.154058 -288.632772) (xy 54.180361 -288.591176) (xy 54.212996 -288.554339) (xy 54.251117 -288.523214)
			(xy 54.293738 -288.498607) (xy 54.339754 -288.481155) (xy 54.387973 -288.471311) (xy 54.437148 -288.46933)
			(xy 54.486003 -288.475262) (xy 54.533274 -288.488954) (xy 54.577736 -288.510052) (xy 54.618239 -288.538008)
			(xy 54.653732 -288.5721) (xy 54.683297 -288.611444) (xy 54.706168 -288.655021) (xy 54.721752 -288.701702)
			(xy 54.729647 -288.750279) (xy 54.730142 -288.774886) (xy 55.06899 -288.774886) (xy 55.07295 -288.725832)
			(xy 55.084727 -288.678048) (xy 55.104018 -288.632772) (xy 55.130321 -288.591176) (xy 55.162956 -288.554339)
			(xy 55.201077 -288.523214) (xy 55.243698 -288.498607) (xy 55.289714 -288.481155) (xy 55.337933 -288.471311)
			(xy 55.387108 -288.46933) (xy 55.435963 -288.475262) (xy 55.483234 -288.488954) (xy 55.527696 -288.510052)
			(xy 55.568199 -288.538008) (xy 55.603692 -288.5721) (xy 55.633257 -288.611444) (xy 55.656128 -288.655021)
			(xy 55.671712 -288.701702) (xy 55.679607 -288.750279) (xy 55.680102 -288.774886) (xy 56.01895 -288.774886)
			(xy 56.02291 -288.725832) (xy 56.034687 -288.678048) (xy 56.053978 -288.632772) (xy 56.080281 -288.591176)
			(xy 56.112916 -288.554339) (xy 56.151037 -288.523214) (xy 56.193658 -288.498607) (xy 56.239674 -288.481155)
			(xy 56.287893 -288.471311) (xy 56.337068 -288.46933) (xy 56.385923 -288.475262) (xy 56.433194 -288.488954)
			(xy 56.477656 -288.510052) (xy 56.518159 -288.538008) (xy 56.553652 -288.5721) (xy 56.583217 -288.611444)
			(xy 56.606088 -288.655021) (xy 56.621672 -288.701702) (xy 56.629567 -288.750279) (xy 56.630062 -288.774886)
			(xy 56.969164 -288.774886) (xy 56.973124 -288.725832) (xy 56.984901 -288.678048) (xy 57.004192 -288.632772)
			(xy 57.030495 -288.591176) (xy 57.06313 -288.554339) (xy 57.101251 -288.523214) (xy 57.143872 -288.498607)
			(xy 57.189888 -288.481155) (xy 57.238107 -288.471311) (xy 57.287282 -288.46933) (xy 57.336137 -288.475262)
			(xy 57.383408 -288.488954) (xy 57.42787 -288.510052) (xy 57.468373 -288.538008) (xy 57.503866 -288.5721)
			(xy 57.533431 -288.611444) (xy 57.556302 -288.655021) (xy 57.571886 -288.701702) (xy 57.579781 -288.750279)
			(xy 57.580276 -288.774886) (xy 57.919124 -288.774886) (xy 57.923084 -288.725832) (xy 57.934861 -288.678048)
			(xy 57.954152 -288.632772) (xy 57.980455 -288.591176) (xy 58.01309 -288.554339) (xy 58.051211 -288.523214)
			(xy 58.093832 -288.498607) (xy 58.139848 -288.481155) (xy 58.188067 -288.471311) (xy 58.237242 -288.46933)
			(xy 58.286097 -288.475262) (xy 58.333368 -288.488954) (xy 58.37783 -288.510052) (xy 58.418333 -288.538008)
			(xy 58.453826 -288.5721) (xy 58.483391 -288.611444) (xy 58.506262 -288.655021) (xy 58.521846 -288.701702)
			(xy 58.529741 -288.750279) (xy 58.530236 -288.774886) (xy 59.819044 -288.774886) (xy 59.823004 -288.725832)
			(xy 59.834781 -288.678048) (xy 59.854072 -288.632772) (xy 59.880375 -288.591176) (xy 59.91301 -288.554339)
			(xy 59.951131 -288.523214) (xy 59.993752 -288.498607) (xy 60.039768 -288.481155) (xy 60.087987 -288.471311)
			(xy 60.137162 -288.46933) (xy 60.186017 -288.475262) (xy 60.233288 -288.488954) (xy 60.27775 -288.510052)
			(xy 60.318253 -288.538008) (xy 60.353746 -288.5721) (xy 60.383311 -288.611444) (xy 60.406182 -288.655021)
			(xy 60.421766 -288.701702) (xy 60.429661 -288.750279) (xy 60.430156 -288.774886) (xy 60.769004 -288.774886)
			(xy 60.772964 -288.725832) (xy 60.784741 -288.678048) (xy 60.804032 -288.632772) (xy 60.830335 -288.591176)
			(xy 60.86297 -288.554339) (xy 60.901091 -288.523214) (xy 60.943712 -288.498607) (xy 60.989728 -288.481155)
			(xy 61.037947 -288.471311) (xy 61.087122 -288.46933) (xy 61.135977 -288.475262) (xy 61.183248 -288.488954)
			(xy 61.22771 -288.510052) (xy 61.268213 -288.538008) (xy 61.303706 -288.5721) (xy 61.333271 -288.611444)
			(xy 61.356142 -288.655021) (xy 61.371726 -288.701702) (xy 61.379621 -288.750279) (xy 61.380116 -288.774886)
			(xy 61.718964 -288.774886) (xy 61.722924 -288.725832) (xy 61.734701 -288.678048) (xy 61.753992 -288.632772)
			(xy 61.780295 -288.591176) (xy 61.81293 -288.554339) (xy 61.851051 -288.523214) (xy 61.893672 -288.498607)
			(xy 61.939688 -288.481155) (xy 61.987907 -288.471311) (xy 62.037082 -288.46933) (xy 62.085937 -288.475262)
			(xy 62.133208 -288.488954) (xy 62.17767 -288.510052) (xy 62.218173 -288.538008) (xy 62.253666 -288.5721)
			(xy 62.283231 -288.611444) (xy 62.306102 -288.655021) (xy 62.321686 -288.701702) (xy 62.329581 -288.750279)
			(xy 62.330076 -288.774886) (xy 62.669178 -288.774886) (xy 62.673138 -288.725832) (xy 62.684915 -288.678048)
			(xy 62.704206 -288.632772) (xy 62.730509 -288.591176) (xy 62.763144 -288.554339) (xy 62.801265 -288.523214)
			(xy 62.843886 -288.498607) (xy 62.889902 -288.481155) (xy 62.938121 -288.471311) (xy 62.987296 -288.46933)
			(xy 63.036151 -288.475262) (xy 63.083422 -288.488954) (xy 63.127884 -288.510052) (xy 63.168387 -288.538008)
			(xy 63.20388 -288.5721) (xy 63.233445 -288.611444) (xy 63.256316 -288.655021) (xy 63.2719 -288.701702)
			(xy 63.279795 -288.750279) (xy 63.28029 -288.774886) (xy 63.619138 -288.774886) (xy 63.623098 -288.725832)
			(xy 63.634875 -288.678048) (xy 63.654166 -288.632772) (xy 63.680469 -288.591176) (xy 63.713104 -288.554339)
			(xy 63.751225 -288.523214) (xy 63.793846 -288.498607) (xy 63.839862 -288.481155) (xy 63.888081 -288.471311)
			(xy 63.937256 -288.46933) (xy 63.986111 -288.475262) (xy 64.033382 -288.488954) (xy 64.077844 -288.510052)
			(xy 64.118347 -288.538008) (xy 64.15384 -288.5721) (xy 64.183405 -288.611444) (xy 64.206276 -288.655021)
			(xy 64.22186 -288.701702) (xy 64.229755 -288.750279) (xy 64.23025 -288.774886) (xy 64.569098 -288.774886)
			(xy 64.573058 -288.725832) (xy 64.584835 -288.678048) (xy 64.604126 -288.632772) (xy 64.630429 -288.591176)
			(xy 64.663064 -288.554339) (xy 64.701185 -288.523214) (xy 64.743806 -288.498607) (xy 64.789822 -288.481155)
			(xy 64.838041 -288.471311) (xy 64.887216 -288.46933) (xy 64.936071 -288.475262) (xy 64.983342 -288.488954)
			(xy 65.027804 -288.510052) (xy 65.068307 -288.538008) (xy 65.1038 -288.5721) (xy 65.133365 -288.611444)
			(xy 65.156236 -288.655021) (xy 65.17182 -288.701702) (xy 65.179715 -288.750279) (xy 65.18021 -288.774886)
			(xy 65.519058 -288.774886) (xy 65.523018 -288.725832) (xy 65.534795 -288.678048) (xy 65.554086 -288.632772)
			(xy 65.580389 -288.591176) (xy 65.613024 -288.554339) (xy 65.651145 -288.523214) (xy 65.693766 -288.498607)
			(xy 65.739782 -288.481155) (xy 65.788001 -288.471311) (xy 65.837176 -288.46933) (xy 65.886031 -288.475262)
			(xy 65.933302 -288.488954) (xy 65.977764 -288.510052) (xy 66.018267 -288.538008) (xy 66.05376 -288.5721)
			(xy 66.083325 -288.611444) (xy 66.106196 -288.655021) (xy 66.12178 -288.701702) (xy 66.129675 -288.750279)
			(xy 66.13017 -288.774886) (xy 66.469018 -288.774886) (xy 66.472978 -288.725832) (xy 66.484755 -288.678048)
			(xy 66.504046 -288.632772) (xy 66.530349 -288.591176) (xy 66.562984 -288.554339) (xy 66.601105 -288.523214)
			(xy 66.643726 -288.498607) (xy 66.689742 -288.481155) (xy 66.737961 -288.471311) (xy 66.787136 -288.46933)
			(xy 66.835991 -288.475262) (xy 66.883262 -288.488954) (xy 66.927724 -288.510052) (xy 66.968227 -288.538008)
			(xy 67.00372 -288.5721) (xy 67.033285 -288.611444) (xy 67.056156 -288.655021) (xy 67.07174 -288.701702)
			(xy 67.079635 -288.750279) (xy 67.08013 -288.774886) (xy 67.418978 -288.774886) (xy 67.422938 -288.725832)
			(xy 67.434715 -288.678048) (xy 67.454006 -288.632772) (xy 67.480309 -288.591176) (xy 67.512944 -288.554339)
			(xy 67.551065 -288.523214) (xy 67.593686 -288.498607) (xy 67.639702 -288.481155) (xy 67.687921 -288.471311)
			(xy 67.737096 -288.46933) (xy 67.785951 -288.475262) (xy 67.833222 -288.488954) (xy 67.877684 -288.510052)
			(xy 67.918187 -288.538008) (xy 67.95368 -288.5721) (xy 67.983245 -288.611444) (xy 68.006116 -288.655021)
			(xy 68.0217 -288.701702) (xy 68.029595 -288.750279) (xy 68.03009 -288.774886) (xy 68.368938 -288.774886)
			(xy 68.372898 -288.725832) (xy 68.384675 -288.678048) (xy 68.403966 -288.632772) (xy 68.430269 -288.591176)
			(xy 68.462904 -288.554339) (xy 68.501025 -288.523214) (xy 68.543646 -288.498607) (xy 68.589662 -288.481155)
			(xy 68.637881 -288.471311) (xy 68.687056 -288.46933) (xy 68.735911 -288.475262) (xy 68.783182 -288.488954)
			(xy 68.827644 -288.510052) (xy 68.868147 -288.538008) (xy 68.90364 -288.5721) (xy 68.933205 -288.611444)
			(xy 68.956076 -288.655021) (xy 68.97166 -288.701702) (xy 68.979555 -288.750279) (xy 68.98005 -288.774886)
			(xy 69.319152 -288.774886) (xy 69.323112 -288.725832) (xy 69.334889 -288.678048) (xy 69.35418 -288.632772)
			(xy 69.380483 -288.591176) (xy 69.413118 -288.554339) (xy 69.451239 -288.523214) (xy 69.49386 -288.498607)
			(xy 69.539876 -288.481155) (xy 69.588095 -288.471311) (xy 69.63727 -288.46933) (xy 69.686125 -288.475262)
			(xy 69.733396 -288.488954) (xy 69.777858 -288.510052) (xy 69.818361 -288.538008) (xy 69.853854 -288.5721)
			(xy 69.883419 -288.611444) (xy 69.90629 -288.655021) (xy 69.921874 -288.701702) (xy 69.929769 -288.750279)
			(xy 69.930264 -288.774886) (xy 70.269112 -288.774886) (xy 70.273072 -288.725832) (xy 70.284849 -288.678048)
			(xy 70.30414 -288.632772) (xy 70.330443 -288.591176) (xy 70.363078 -288.554339) (xy 70.401199 -288.523214)
			(xy 70.44382 -288.498607) (xy 70.489836 -288.481155) (xy 70.538055 -288.471311) (xy 70.58723 -288.46933)
			(xy 70.636085 -288.475262) (xy 70.683356 -288.488954) (xy 70.727818 -288.510052) (xy 70.768321 -288.538008)
			(xy 70.803814 -288.5721) (xy 70.833379 -288.611444) (xy 70.85625 -288.655021) (xy 70.871834 -288.701702)
			(xy 70.879729 -288.750279) (xy 70.880224 -288.774886) (xy 71.219072 -288.774886) (xy 71.223032 -288.725832)
			(xy 71.234809 -288.678048) (xy 71.2541 -288.632772) (xy 71.280403 -288.591176) (xy 71.313038 -288.554339)
			(xy 71.351159 -288.523214) (xy 71.39378 -288.498607) (xy 71.439796 -288.481155) (xy 71.488015 -288.471311)
			(xy 71.53719 -288.46933) (xy 71.586045 -288.475262) (xy 71.633316 -288.488954) (xy 71.677778 -288.510052)
			(xy 71.718281 -288.538008) (xy 71.753774 -288.5721) (xy 71.783339 -288.611444) (xy 71.80621 -288.655021)
			(xy 71.821794 -288.701702) (xy 71.829689 -288.750279) (xy 71.830184 -288.774886) (xy 72.169032 -288.774886)
			(xy 72.172992 -288.725832) (xy 72.184769 -288.678048) (xy 72.20406 -288.632772) (xy 72.230363 -288.591176)
			(xy 72.262998 -288.554339) (xy 72.301119 -288.523214) (xy 72.34374 -288.498607) (xy 72.389756 -288.481155)
			(xy 72.437975 -288.471311) (xy 72.48715 -288.46933) (xy 72.536005 -288.475262) (xy 72.583276 -288.488954)
			(xy 72.627738 -288.510052) (xy 72.668241 -288.538008) (xy 72.703734 -288.5721) (xy 72.733299 -288.611444)
			(xy 72.75617 -288.655021) (xy 72.771754 -288.701702) (xy 72.779649 -288.750279) (xy 72.780144 -288.774886)
			(xy 72.779649 -288.799493) (xy 72.771754 -288.84807) (xy 72.75617 -288.894751) (xy 72.733299 -288.938328)
			(xy 72.703734 -288.977672) (xy 72.668241 -289.011764) (xy 72.627738 -289.03972) (xy 72.583276 -289.060818)
			(xy 72.536005 -289.07451) (xy 72.48715 -289.080442) (xy 72.437975 -289.078461) (xy 72.389756 -289.068617)
			(xy 72.34374 -289.051165) (xy 72.301119 -289.026558) (xy 72.262998 -288.995433) (xy 72.230363 -288.958596)
			(xy 72.20406 -288.917) (xy 72.184769 -288.871724) (xy 72.172992 -288.82394) (xy 72.169032 -288.774886)
			(xy 71.830184 -288.774886) (xy 71.829689 -288.799493) (xy 71.821794 -288.84807) (xy 71.80621 -288.894751)
			(xy 71.783339 -288.938328) (xy 71.753774 -288.977672) (xy 71.718281 -289.011764) (xy 71.677778 -289.03972)
			(xy 71.633316 -289.060818) (xy 71.586045 -289.07451) (xy 71.53719 -289.080442) (xy 71.488015 -289.078461)
			(xy 71.439796 -289.068617) (xy 71.39378 -289.051165) (xy 71.351159 -289.026558) (xy 71.313038 -288.995433)
			(xy 71.280403 -288.958596) (xy 71.2541 -288.917) (xy 71.234809 -288.871724) (xy 71.223032 -288.82394)
			(xy 71.219072 -288.774886) (xy 70.880224 -288.774886) (xy 70.879729 -288.799493) (xy 70.871834 -288.84807)
			(xy 70.85625 -288.894751) (xy 70.833379 -288.938328) (xy 70.803814 -288.977672) (xy 70.768321 -289.011764)
			(xy 70.727818 -289.03972) (xy 70.683356 -289.060818) (xy 70.636085 -289.07451) (xy 70.58723 -289.080442)
			(xy 70.538055 -289.078461) (xy 70.489836 -289.068617) (xy 70.44382 -289.051165) (xy 70.401199 -289.026558)
			(xy 70.363078 -288.995433) (xy 70.330443 -288.958596) (xy 70.30414 -288.917) (xy 70.284849 -288.871724)
			(xy 70.273072 -288.82394) (xy 70.269112 -288.774886) (xy 69.930264 -288.774886) (xy 69.929769 -288.799493)
			(xy 69.921874 -288.84807) (xy 69.90629 -288.894751) (xy 69.883419 -288.938328) (xy 69.853854 -288.977672)
			(xy 69.818361 -289.011764) (xy 69.777858 -289.03972) (xy 69.733396 -289.060818) (xy 69.686125 -289.07451)
			(xy 69.63727 -289.080442) (xy 69.588095 -289.078461) (xy 69.539876 -289.068617) (xy 69.49386 -289.051165)
			(xy 69.451239 -289.026558) (xy 69.413118 -288.995433) (xy 69.380483 -288.958596) (xy 69.35418 -288.917)
			(xy 69.334889 -288.871724) (xy 69.323112 -288.82394) (xy 69.319152 -288.774886) (xy 68.98005 -288.774886)
			(xy 68.979555 -288.799493) (xy 68.97166 -288.84807) (xy 68.956076 -288.894751) (xy 68.933205 -288.938328)
			(xy 68.90364 -288.977672) (xy 68.868147 -289.011764) (xy 68.827644 -289.03972) (xy 68.783182 -289.060818)
			(xy 68.735911 -289.07451) (xy 68.687056 -289.080442) (xy 68.637881 -289.078461) (xy 68.589662 -289.068617)
			(xy 68.543646 -289.051165) (xy 68.501025 -289.026558) (xy 68.462904 -288.995433) (xy 68.430269 -288.958596)
			(xy 68.403966 -288.917) (xy 68.384675 -288.871724) (xy 68.372898 -288.82394) (xy 68.368938 -288.774886)
			(xy 68.03009 -288.774886) (xy 68.029595 -288.799493) (xy 68.0217 -288.84807) (xy 68.006116 -288.894751)
			(xy 67.983245 -288.938328) (xy 67.95368 -288.977672) (xy 67.918187 -289.011764) (xy 67.877684 -289.03972)
			(xy 67.833222 -289.060818) (xy 67.785951 -289.07451) (xy 67.737096 -289.080442) (xy 67.687921 -289.078461)
			(xy 67.639702 -289.068617) (xy 67.593686 -289.051165) (xy 67.551065 -289.026558) (xy 67.512944 -288.995433)
			(xy 67.480309 -288.958596) (xy 67.454006 -288.917) (xy 67.434715 -288.871724) (xy 67.422938 -288.82394)
			(xy 67.418978 -288.774886) (xy 67.08013 -288.774886) (xy 67.079635 -288.799493) (xy 67.07174 -288.84807)
			(xy 67.056156 -288.894751) (xy 67.033285 -288.938328) (xy 67.00372 -288.977672) (xy 66.968227 -289.011764)
			(xy 66.927724 -289.03972) (xy 66.883262 -289.060818) (xy 66.835991 -289.07451) (xy 66.787136 -289.080442)
			(xy 66.737961 -289.078461) (xy 66.689742 -289.068617) (xy 66.643726 -289.051165) (xy 66.601105 -289.026558)
			(xy 66.562984 -288.995433) (xy 66.530349 -288.958596) (xy 66.504046 -288.917) (xy 66.484755 -288.871724)
			(xy 66.472978 -288.82394) (xy 66.469018 -288.774886) (xy 66.13017 -288.774886) (xy 66.129675 -288.799493)
			(xy 66.12178 -288.84807) (xy 66.106196 -288.894751) (xy 66.083325 -288.938328) (xy 66.05376 -288.977672)
			(xy 66.018267 -289.011764) (xy 65.977764 -289.03972) (xy 65.933302 -289.060818) (xy 65.886031 -289.07451)
			(xy 65.837176 -289.080442) (xy 65.788001 -289.078461) (xy 65.739782 -289.068617) (xy 65.693766 -289.051165)
			(xy 65.651145 -289.026558) (xy 65.613024 -288.995433) (xy 65.580389 -288.958596) (xy 65.554086 -288.917)
			(xy 65.534795 -288.871724) (xy 65.523018 -288.82394) (xy 65.519058 -288.774886) (xy 65.18021 -288.774886)
			(xy 65.179715 -288.799493) (xy 65.17182 -288.84807) (xy 65.156236 -288.894751) (xy 65.133365 -288.938328)
			(xy 65.1038 -288.977672) (xy 65.068307 -289.011764) (xy 65.027804 -289.03972) (xy 64.983342 -289.060818)
			(xy 64.936071 -289.07451) (xy 64.887216 -289.080442) (xy 64.838041 -289.078461) (xy 64.789822 -289.068617)
			(xy 64.743806 -289.051165) (xy 64.701185 -289.026558) (xy 64.663064 -288.995433) (xy 64.630429 -288.958596)
			(xy 64.604126 -288.917) (xy 64.584835 -288.871724) (xy 64.573058 -288.82394) (xy 64.569098 -288.774886)
			(xy 64.23025 -288.774886) (xy 64.229755 -288.799493) (xy 64.22186 -288.84807) (xy 64.206276 -288.894751)
			(xy 64.183405 -288.938328) (xy 64.15384 -288.977672) (xy 64.118347 -289.011764) (xy 64.077844 -289.03972)
			(xy 64.033382 -289.060818) (xy 63.986111 -289.07451) (xy 63.937256 -289.080442) (xy 63.888081 -289.078461)
			(xy 63.839862 -289.068617) (xy 63.793846 -289.051165) (xy 63.751225 -289.026558) (xy 63.713104 -288.995433)
			(xy 63.680469 -288.958596) (xy 63.654166 -288.917) (xy 63.634875 -288.871724) (xy 63.623098 -288.82394)
			(xy 63.619138 -288.774886) (xy 63.28029 -288.774886) (xy 63.279795 -288.799493) (xy 63.2719 -288.84807)
			(xy 63.256316 -288.894751) (xy 63.233445 -288.938328) (xy 63.20388 -288.977672) (xy 63.168387 -289.011764)
			(xy 63.127884 -289.03972) (xy 63.083422 -289.060818) (xy 63.036151 -289.07451) (xy 62.987296 -289.080442)
			(xy 62.938121 -289.078461) (xy 62.889902 -289.068617) (xy 62.843886 -289.051165) (xy 62.801265 -289.026558)
			(xy 62.763144 -288.995433) (xy 62.730509 -288.958596) (xy 62.704206 -288.917) (xy 62.684915 -288.871724)
			(xy 62.673138 -288.82394) (xy 62.669178 -288.774886) (xy 62.330076 -288.774886) (xy 62.329581 -288.799493)
			(xy 62.321686 -288.84807) (xy 62.306102 -288.894751) (xy 62.283231 -288.938328) (xy 62.253666 -288.977672)
			(xy 62.218173 -289.011764) (xy 62.17767 -289.03972) (xy 62.133208 -289.060818) (xy 62.085937 -289.07451)
			(xy 62.037082 -289.080442) (xy 61.987907 -289.078461) (xy 61.939688 -289.068617) (xy 61.893672 -289.051165)
			(xy 61.851051 -289.026558) (xy 61.81293 -288.995433) (xy 61.780295 -288.958596) (xy 61.753992 -288.917)
			(xy 61.734701 -288.871724) (xy 61.722924 -288.82394) (xy 61.718964 -288.774886) (xy 61.380116 -288.774886)
			(xy 61.379621 -288.799493) (xy 61.371726 -288.84807) (xy 61.356142 -288.894751) (xy 61.333271 -288.938328)
			(xy 61.303706 -288.977672) (xy 61.268213 -289.011764) (xy 61.22771 -289.03972) (xy 61.183248 -289.060818)
			(xy 61.135977 -289.07451) (xy 61.087122 -289.080442) (xy 61.037947 -289.078461) (xy 60.989728 -289.068617)
			(xy 60.943712 -289.051165) (xy 60.901091 -289.026558) (xy 60.86297 -288.995433) (xy 60.830335 -288.958596)
			(xy 60.804032 -288.917) (xy 60.784741 -288.871724) (xy 60.772964 -288.82394) (xy 60.769004 -288.774886)
			(xy 60.430156 -288.774886) (xy 60.429661 -288.799493) (xy 60.421766 -288.84807) (xy 60.406182 -288.894751)
			(xy 60.383311 -288.938328) (xy 60.353746 -288.977672) (xy 60.318253 -289.011764) (xy 60.27775 -289.03972)
			(xy 60.233288 -289.060818) (xy 60.186017 -289.07451) (xy 60.137162 -289.080442) (xy 60.087987 -289.078461)
			(xy 60.039768 -289.068617) (xy 59.993752 -289.051165) (xy 59.951131 -289.026558) (xy 59.91301 -288.995433)
			(xy 59.880375 -288.958596) (xy 59.854072 -288.917) (xy 59.834781 -288.871724) (xy 59.823004 -288.82394)
			(xy 59.819044 -288.774886) (xy 58.530236 -288.774886) (xy 58.529741 -288.799493) (xy 58.521846 -288.84807)
			(xy 58.506262 -288.894751) (xy 58.483391 -288.938328) (xy 58.453826 -288.977672) (xy 58.418333 -289.011764)
			(xy 58.37783 -289.03972) (xy 58.333368 -289.060818) (xy 58.286097 -289.07451) (xy 58.237242 -289.080442)
			(xy 58.188067 -289.078461) (xy 58.139848 -289.068617) (xy 58.093832 -289.051165) (xy 58.051211 -289.026558)
			(xy 58.01309 -288.995433) (xy 57.980455 -288.958596) (xy 57.954152 -288.917) (xy 57.934861 -288.871724)
			(xy 57.923084 -288.82394) (xy 57.919124 -288.774886) (xy 57.580276 -288.774886) (xy 57.579781 -288.799493)
			(xy 57.571886 -288.84807) (xy 57.556302 -288.894751) (xy 57.533431 -288.938328) (xy 57.503866 -288.977672)
			(xy 57.468373 -289.011764) (xy 57.42787 -289.03972) (xy 57.383408 -289.060818) (xy 57.336137 -289.07451)
			(xy 57.287282 -289.080442) (xy 57.238107 -289.078461) (xy 57.189888 -289.068617) (xy 57.143872 -289.051165)
			(xy 57.101251 -289.026558) (xy 57.06313 -288.995433) (xy 57.030495 -288.958596) (xy 57.004192 -288.917)
			(xy 56.984901 -288.871724) (xy 56.973124 -288.82394) (xy 56.969164 -288.774886) (xy 56.630062 -288.774886)
			(xy 56.629567 -288.799493) (xy 56.621672 -288.84807) (xy 56.606088 -288.894751) (xy 56.583217 -288.938328)
			(xy 56.553652 -288.977672) (xy 56.518159 -289.011764) (xy 56.477656 -289.03972) (xy 56.433194 -289.060818)
			(xy 56.385923 -289.07451) (xy 56.337068 -289.080442) (xy 56.287893 -289.078461) (xy 56.239674 -289.068617)
			(xy 56.193658 -289.051165) (xy 56.151037 -289.026558) (xy 56.112916 -288.995433) (xy 56.080281 -288.958596)
			(xy 56.053978 -288.917) (xy 56.034687 -288.871724) (xy 56.02291 -288.82394) (xy 56.01895 -288.774886)
			(xy 55.680102 -288.774886) (xy 55.679607 -288.799493) (xy 55.671712 -288.84807) (xy 55.656128 -288.894751)
			(xy 55.633257 -288.938328) (xy 55.603692 -288.977672) (xy 55.568199 -289.011764) (xy 55.527696 -289.03972)
			(xy 55.483234 -289.060818) (xy 55.435963 -289.07451) (xy 55.387108 -289.080442) (xy 55.337933 -289.078461)
			(xy 55.289714 -289.068617) (xy 55.243698 -289.051165) (xy 55.201077 -289.026558) (xy 55.162956 -288.995433)
			(xy 55.130321 -288.958596) (xy 55.104018 -288.917) (xy 55.084727 -288.871724) (xy 55.07295 -288.82394)
			(xy 55.06899 -288.774886) (xy 54.730142 -288.774886) (xy 54.729647 -288.799493) (xy 54.721752 -288.84807)
			(xy 54.706168 -288.894751) (xy 54.683297 -288.938328) (xy 54.653732 -288.977672) (xy 54.618239 -289.011764)
			(xy 54.577736 -289.03972) (xy 54.533274 -289.060818) (xy 54.486003 -289.07451) (xy 54.437148 -289.080442)
			(xy 54.387973 -289.078461) (xy 54.339754 -289.068617) (xy 54.293738 -289.051165) (xy 54.251117 -289.026558)
			(xy 54.212996 -288.995433) (xy 54.180361 -288.958596) (xy 54.154058 -288.917) (xy 54.134767 -288.871724)
			(xy 54.12299 -288.82394) (xy 54.11903 -288.774886) (xy 53.780182 -288.774886) (xy 53.779687 -288.799493)
			(xy 53.771792 -288.84807) (xy 53.756208 -288.894751) (xy 53.733337 -288.938328) (xy 53.703772 -288.977672)
			(xy 53.668279 -289.011764) (xy 53.627776 -289.03972) (xy 53.583314 -289.060818) (xy 53.536043 -289.07451)
			(xy 53.487188 -289.080442) (xy 53.438013 -289.078461) (xy 53.389794 -289.068617) (xy 53.343778 -289.051165)
			(xy 53.301157 -289.026558) (xy 53.263036 -288.995433) (xy 53.230401 -288.958596) (xy 53.204098 -288.917)
			(xy 53.184807 -288.871724) (xy 53.17303 -288.82394) (xy 53.16907 -288.774886) (xy 52.830222 -288.774886)
			(xy 52.829727 -288.799493) (xy 52.821832 -288.84807) (xy 52.806248 -288.894751) (xy 52.783377 -288.938328)
			(xy 52.753812 -288.977672) (xy 52.718319 -289.011764) (xy 52.677816 -289.03972) (xy 52.633354 -289.060818)
			(xy 52.586083 -289.07451) (xy 52.537228 -289.080442) (xy 52.488053 -289.078461) (xy 52.439834 -289.068617)
			(xy 52.393818 -289.051165) (xy 52.351197 -289.026558) (xy 52.313076 -288.995433) (xy 52.280441 -288.958596)
			(xy 52.254138 -288.917) (xy 52.234847 -288.871724) (xy 52.22307 -288.82394) (xy 52.21911 -288.774886)
			(xy 51.880262 -288.774886) (xy 51.879767 -288.799493) (xy 51.871872 -288.84807) (xy 51.856288 -288.894751)
			(xy 51.833417 -288.938328) (xy 51.803852 -288.977672) (xy 51.768359 -289.011764) (xy 51.727856 -289.03972)
			(xy 51.683394 -289.060818) (xy 51.636123 -289.07451) (xy 51.587268 -289.080442) (xy 51.538093 -289.078461)
			(xy 51.489874 -289.068617) (xy 51.443858 -289.051165) (xy 51.401237 -289.026558) (xy 51.363116 -288.995433)
			(xy 51.330481 -288.958596) (xy 51.304178 -288.917) (xy 51.284887 -288.871724) (xy 51.27311 -288.82394)
			(xy 51.26915 -288.774886) (xy 50.930302 -288.774886) (xy 50.929807 -288.799493) (xy 50.921912 -288.84807)
			(xy 50.906328 -288.894751) (xy 50.883457 -288.938328) (xy 50.853892 -288.977672) (xy 50.818399 -289.011764)
			(xy 50.777896 -289.03972) (xy 50.733434 -289.060818) (xy 50.686163 -289.07451) (xy 50.637308 -289.080442)
			(xy 50.588133 -289.078461) (xy 50.539914 -289.068617) (xy 50.493898 -289.051165) (xy 50.451277 -289.026558)
			(xy 50.413156 -288.995433) (xy 50.380521 -288.958596) (xy 50.354218 -288.917) (xy 50.334927 -288.871724)
			(xy 50.32315 -288.82394) (xy 50.31919 -288.774886) (xy 49.980088 -288.774886) (xy 49.979593 -288.799493)
			(xy 49.971698 -288.84807) (xy 49.956114 -288.894751) (xy 49.933243 -288.938328) (xy 49.903678 -288.977672)
			(xy 49.868185 -289.011764) (xy 49.827682 -289.03972) (xy 49.78322 -289.060818) (xy 49.735949 -289.07451)
			(xy 49.687094 -289.080442) (xy 49.637919 -289.078461) (xy 49.5897 -289.068617) (xy 49.543684 -289.051165)
			(xy 49.501063 -289.026558) (xy 49.462942 -288.995433) (xy 49.430307 -288.958596) (xy 49.404004 -288.917)
			(xy 49.384713 -288.871724) (xy 49.372936 -288.82394) (xy 49.368976 -288.774886) (xy 49.181004 -288.774886)
			(xy 49.181004 -289.724846) (xy 49.368976 -289.724846) (xy 49.372936 -289.675792) (xy 49.384713 -289.628008)
			(xy 49.404004 -289.582732) (xy 49.430307 -289.541136) (xy 49.462942 -289.504299) (xy 49.501063 -289.473174)
			(xy 49.543684 -289.448567) (xy 49.5897 -289.431115) (xy 49.637919 -289.421271) (xy 49.687094 -289.41929)
			(xy 49.735949 -289.425222) (xy 49.78322 -289.438914) (xy 49.827682 -289.460012) (xy 49.868185 -289.487968)
			(xy 49.903678 -289.52206) (xy 49.933243 -289.561404) (xy 49.956114 -289.604981) (xy 49.971698 -289.651662)
			(xy 49.979593 -289.700239) (xy 49.980088 -289.724846) (xy 50.31919 -289.724846) (xy 50.32315 -289.675792)
			(xy 50.334927 -289.628008) (xy 50.354218 -289.582732) (xy 50.380521 -289.541136) (xy 50.413156 -289.504299)
			(xy 50.451277 -289.473174) (xy 50.493898 -289.448567) (xy 50.539914 -289.431115) (xy 50.588133 -289.421271)
			(xy 50.637308 -289.41929) (xy 50.686163 -289.425222) (xy 50.733434 -289.438914) (xy 50.777896 -289.460012)
			(xy 50.818399 -289.487968) (xy 50.853892 -289.52206) (xy 50.883457 -289.561404) (xy 50.906328 -289.604981)
			(xy 50.921912 -289.651662) (xy 50.929807 -289.700239) (xy 50.930302 -289.724846) (xy 51.26915 -289.724846)
			(xy 51.27311 -289.675792) (xy 51.284887 -289.628008) (xy 51.304178 -289.582732) (xy 51.330481 -289.541136)
			(xy 51.363116 -289.504299) (xy 51.401237 -289.473174) (xy 51.443858 -289.448567) (xy 51.489874 -289.431115)
			(xy 51.538093 -289.421271) (xy 51.587268 -289.41929) (xy 51.636123 -289.425222) (xy 51.683394 -289.438914)
			(xy 51.727856 -289.460012) (xy 51.768359 -289.487968) (xy 51.803852 -289.52206) (xy 51.833417 -289.561404)
			(xy 51.856288 -289.604981) (xy 51.871872 -289.651662) (xy 51.879767 -289.700239) (xy 51.880262 -289.724846)
			(xy 52.21911 -289.724846) (xy 52.22307 -289.675792) (xy 52.234847 -289.628008) (xy 52.254138 -289.582732)
			(xy 52.280441 -289.541136) (xy 52.313076 -289.504299) (xy 52.351197 -289.473174) (xy 52.393818 -289.448567)
			(xy 52.439834 -289.431115) (xy 52.488053 -289.421271) (xy 52.537228 -289.41929) (xy 52.586083 -289.425222)
			(xy 52.633354 -289.438914) (xy 52.677816 -289.460012) (xy 52.718319 -289.487968) (xy 52.753812 -289.52206)
			(xy 52.783377 -289.561404) (xy 52.806248 -289.604981) (xy 52.821832 -289.651662) (xy 52.829727 -289.700239)
			(xy 52.830222 -289.724846) (xy 53.16907 -289.724846) (xy 53.17303 -289.675792) (xy 53.184807 -289.628008)
			(xy 53.204098 -289.582732) (xy 53.230401 -289.541136) (xy 53.263036 -289.504299) (xy 53.301157 -289.473174)
			(xy 53.343778 -289.448567) (xy 53.389794 -289.431115) (xy 53.438013 -289.421271) (xy 53.487188 -289.41929)
			(xy 53.536043 -289.425222) (xy 53.583314 -289.438914) (xy 53.627776 -289.460012) (xy 53.668279 -289.487968)
			(xy 53.703772 -289.52206) (xy 53.733337 -289.561404) (xy 53.756208 -289.604981) (xy 53.771792 -289.651662)
			(xy 53.779687 -289.700239) (xy 53.780182 -289.724846) (xy 54.11903 -289.724846) (xy 54.12299 -289.675792)
			(xy 54.134767 -289.628008) (xy 54.154058 -289.582732) (xy 54.180361 -289.541136) (xy 54.212996 -289.504299)
			(xy 54.251117 -289.473174) (xy 54.293738 -289.448567) (xy 54.339754 -289.431115) (xy 54.387973 -289.421271)
			(xy 54.437148 -289.41929) (xy 54.486003 -289.425222) (xy 54.533274 -289.438914) (xy 54.577736 -289.460012)
			(xy 54.618239 -289.487968) (xy 54.653732 -289.52206) (xy 54.683297 -289.561404) (xy 54.706168 -289.604981)
			(xy 54.721752 -289.651662) (xy 54.729647 -289.700239) (xy 54.730142 -289.724846) (xy 55.06899 -289.724846)
			(xy 55.07295 -289.675792) (xy 55.084727 -289.628008) (xy 55.104018 -289.582732) (xy 55.130321 -289.541136)
			(xy 55.162956 -289.504299) (xy 55.201077 -289.473174) (xy 55.243698 -289.448567) (xy 55.289714 -289.431115)
			(xy 55.337933 -289.421271) (xy 55.387108 -289.41929) (xy 55.435963 -289.425222) (xy 55.483234 -289.438914)
			(xy 55.527696 -289.460012) (xy 55.568199 -289.487968) (xy 55.603692 -289.52206) (xy 55.633257 -289.561404)
			(xy 55.656128 -289.604981) (xy 55.671712 -289.651662) (xy 55.679607 -289.700239) (xy 55.680102 -289.724846)
			(xy 56.01895 -289.724846) (xy 56.02291 -289.675792) (xy 56.034687 -289.628008) (xy 56.053978 -289.582732)
			(xy 56.080281 -289.541136) (xy 56.112916 -289.504299) (xy 56.151037 -289.473174) (xy 56.193658 -289.448567)
			(xy 56.239674 -289.431115) (xy 56.287893 -289.421271) (xy 56.337068 -289.41929) (xy 56.385923 -289.425222)
			(xy 56.433194 -289.438914) (xy 56.477656 -289.460012) (xy 56.518159 -289.487968) (xy 56.553652 -289.52206)
			(xy 56.583217 -289.561404) (xy 56.606088 -289.604981) (xy 56.621672 -289.651662) (xy 56.629567 -289.700239)
			(xy 56.630062 -289.724846) (xy 56.969164 -289.724846) (xy 56.973124 -289.675792) (xy 56.984901 -289.628008)
			(xy 57.004192 -289.582732) (xy 57.030495 -289.541136) (xy 57.06313 -289.504299) (xy 57.101251 -289.473174)
			(xy 57.143872 -289.448567) (xy 57.189888 -289.431115) (xy 57.238107 -289.421271) (xy 57.287282 -289.41929)
			(xy 57.336137 -289.425222) (xy 57.383408 -289.438914) (xy 57.42787 -289.460012) (xy 57.468373 -289.487968)
			(xy 57.503866 -289.52206) (xy 57.533431 -289.561404) (xy 57.556302 -289.604981) (xy 57.571886 -289.651662)
			(xy 57.579781 -289.700239) (xy 57.580276 -289.724846) (xy 57.919124 -289.724846) (xy 57.923084 -289.675792)
			(xy 57.934861 -289.628008) (xy 57.954152 -289.582732) (xy 57.980455 -289.541136) (xy 58.01309 -289.504299)
			(xy 58.051211 -289.473174) (xy 58.093832 -289.448567) (xy 58.139848 -289.431115) (xy 58.188067 -289.421271)
			(xy 58.237242 -289.41929) (xy 58.286097 -289.425222) (xy 58.333368 -289.438914) (xy 58.37783 -289.460012)
			(xy 58.418333 -289.487968) (xy 58.453826 -289.52206) (xy 58.483391 -289.561404) (xy 58.506262 -289.604981)
			(xy 58.521846 -289.651662) (xy 58.529741 -289.700239) (xy 58.530236 -289.724846) (xy 59.819044 -289.724846)
			(xy 59.823004 -289.675792) (xy 59.834781 -289.628008) (xy 59.854072 -289.582732) (xy 59.880375 -289.541136)
			(xy 59.91301 -289.504299) (xy 59.951131 -289.473174) (xy 59.993752 -289.448567) (xy 60.039768 -289.431115)
			(xy 60.087987 -289.421271) (xy 60.137162 -289.41929) (xy 60.186017 -289.425222) (xy 60.233288 -289.438914)
			(xy 60.27775 -289.460012) (xy 60.318253 -289.487968) (xy 60.353746 -289.52206) (xy 60.383311 -289.561404)
			(xy 60.406182 -289.604981) (xy 60.421766 -289.651662) (xy 60.429661 -289.700239) (xy 60.430156 -289.724846)
			(xy 60.769004 -289.724846) (xy 60.772964 -289.675792) (xy 60.784741 -289.628008) (xy 60.804032 -289.582732)
			(xy 60.830335 -289.541136) (xy 60.86297 -289.504299) (xy 60.901091 -289.473174) (xy 60.943712 -289.448567)
			(xy 60.989728 -289.431115) (xy 61.037947 -289.421271) (xy 61.087122 -289.41929) (xy 61.135977 -289.425222)
			(xy 61.183248 -289.438914) (xy 61.22771 -289.460012) (xy 61.268213 -289.487968) (xy 61.303706 -289.52206)
			(xy 61.333271 -289.561404) (xy 61.356142 -289.604981) (xy 61.371726 -289.651662) (xy 61.379621 -289.700239)
			(xy 61.380116 -289.724846) (xy 61.718964 -289.724846) (xy 61.722924 -289.675792) (xy 61.734701 -289.628008)
			(xy 61.753992 -289.582732) (xy 61.780295 -289.541136) (xy 61.81293 -289.504299) (xy 61.851051 -289.473174)
			(xy 61.893672 -289.448567) (xy 61.939688 -289.431115) (xy 61.987907 -289.421271) (xy 62.037082 -289.41929)
			(xy 62.085937 -289.425222) (xy 62.133208 -289.438914) (xy 62.17767 -289.460012) (xy 62.218173 -289.487968)
			(xy 62.253666 -289.52206) (xy 62.283231 -289.561404) (xy 62.306102 -289.604981) (xy 62.321686 -289.651662)
			(xy 62.329581 -289.700239) (xy 62.330076 -289.724846) (xy 62.669178 -289.724846) (xy 62.673138 -289.675792)
			(xy 62.684915 -289.628008) (xy 62.704206 -289.582732) (xy 62.730509 -289.541136) (xy 62.763144 -289.504299)
			(xy 62.801265 -289.473174) (xy 62.843886 -289.448567) (xy 62.889902 -289.431115) (xy 62.938121 -289.421271)
			(xy 62.987296 -289.41929) (xy 63.036151 -289.425222) (xy 63.083422 -289.438914) (xy 63.127884 -289.460012)
			(xy 63.168387 -289.487968) (xy 63.20388 -289.52206) (xy 63.233445 -289.561404) (xy 63.256316 -289.604981)
			(xy 63.2719 -289.651662) (xy 63.279795 -289.700239) (xy 63.28029 -289.724846) (xy 63.619138 -289.724846)
			(xy 63.623098 -289.675792) (xy 63.634875 -289.628008) (xy 63.654166 -289.582732) (xy 63.680469 -289.541136)
			(xy 63.713104 -289.504299) (xy 63.751225 -289.473174) (xy 63.793846 -289.448567) (xy 63.839862 -289.431115)
			(xy 63.888081 -289.421271) (xy 63.937256 -289.41929) (xy 63.986111 -289.425222) (xy 64.033382 -289.438914)
			(xy 64.077844 -289.460012) (xy 64.118347 -289.487968) (xy 64.15384 -289.52206) (xy 64.183405 -289.561404)
			(xy 64.206276 -289.604981) (xy 64.22186 -289.651662) (xy 64.229755 -289.700239) (xy 64.23025 -289.724846)
			(xy 64.569098 -289.724846) (xy 64.573058 -289.675792) (xy 64.584835 -289.628008) (xy 64.604126 -289.582732)
			(xy 64.630429 -289.541136) (xy 64.663064 -289.504299) (xy 64.701185 -289.473174) (xy 64.743806 -289.448567)
			(xy 64.789822 -289.431115) (xy 64.838041 -289.421271) (xy 64.887216 -289.41929) (xy 64.936071 -289.425222)
			(xy 64.983342 -289.438914) (xy 65.027804 -289.460012) (xy 65.068307 -289.487968) (xy 65.1038 -289.52206)
			(xy 65.133365 -289.561404) (xy 65.156236 -289.604981) (xy 65.17182 -289.651662) (xy 65.179715 -289.700239)
			(xy 65.18021 -289.724846) (xy 65.519058 -289.724846) (xy 65.523018 -289.675792) (xy 65.534795 -289.628008)
			(xy 65.554086 -289.582732) (xy 65.580389 -289.541136) (xy 65.613024 -289.504299) (xy 65.651145 -289.473174)
			(xy 65.693766 -289.448567) (xy 65.739782 -289.431115) (xy 65.788001 -289.421271) (xy 65.837176 -289.41929)
			(xy 65.886031 -289.425222) (xy 65.933302 -289.438914) (xy 65.977764 -289.460012) (xy 66.018267 -289.487968)
			(xy 66.05376 -289.52206) (xy 66.083325 -289.561404) (xy 66.106196 -289.604981) (xy 66.12178 -289.651662)
			(xy 66.129675 -289.700239) (xy 66.13017 -289.724846) (xy 66.469018 -289.724846) (xy 66.472978 -289.675792)
			(xy 66.484755 -289.628008) (xy 66.504046 -289.582732) (xy 66.530349 -289.541136) (xy 66.562984 -289.504299)
			(xy 66.601105 -289.473174) (xy 66.643726 -289.448567) (xy 66.689742 -289.431115) (xy 66.737961 -289.421271)
			(xy 66.787136 -289.41929) (xy 66.835991 -289.425222) (xy 66.883262 -289.438914) (xy 66.927724 -289.460012)
			(xy 66.968227 -289.487968) (xy 67.00372 -289.52206) (xy 67.033285 -289.561404) (xy 67.056156 -289.604981)
			(xy 67.07174 -289.651662) (xy 67.079635 -289.700239) (xy 67.08013 -289.724846) (xy 67.418978 -289.724846)
			(xy 67.422938 -289.675792) (xy 67.434715 -289.628008) (xy 67.454006 -289.582732) (xy 67.480309 -289.541136)
			(xy 67.512944 -289.504299) (xy 67.551065 -289.473174) (xy 67.593686 -289.448567) (xy 67.639702 -289.431115)
			(xy 67.687921 -289.421271) (xy 67.737096 -289.41929) (xy 67.785951 -289.425222) (xy 67.833222 -289.438914)
			(xy 67.877684 -289.460012) (xy 67.918187 -289.487968) (xy 67.95368 -289.52206) (xy 67.983245 -289.561404)
			(xy 68.006116 -289.604981) (xy 68.0217 -289.651662) (xy 68.029595 -289.700239) (xy 68.03009 -289.724846)
			(xy 68.368938 -289.724846) (xy 68.372898 -289.675792) (xy 68.384675 -289.628008) (xy 68.403966 -289.582732)
			(xy 68.430269 -289.541136) (xy 68.462904 -289.504299) (xy 68.501025 -289.473174) (xy 68.543646 -289.448567)
			(xy 68.589662 -289.431115) (xy 68.637881 -289.421271) (xy 68.687056 -289.41929) (xy 68.735911 -289.425222)
			(xy 68.783182 -289.438914) (xy 68.827644 -289.460012) (xy 68.868147 -289.487968) (xy 68.90364 -289.52206)
			(xy 68.933205 -289.561404) (xy 68.956076 -289.604981) (xy 68.97166 -289.651662) (xy 68.979555 -289.700239)
			(xy 68.98005 -289.724846) (xy 69.319152 -289.724846) (xy 69.323112 -289.675792) (xy 69.334889 -289.628008)
			(xy 69.35418 -289.582732) (xy 69.380483 -289.541136) (xy 69.413118 -289.504299) (xy 69.451239 -289.473174)
			(xy 69.49386 -289.448567) (xy 69.539876 -289.431115) (xy 69.588095 -289.421271) (xy 69.63727 -289.41929)
			(xy 69.686125 -289.425222) (xy 69.733396 -289.438914) (xy 69.777858 -289.460012) (xy 69.818361 -289.487968)
			(xy 69.853854 -289.52206) (xy 69.883419 -289.561404) (xy 69.90629 -289.604981) (xy 69.921874 -289.651662)
			(xy 69.929769 -289.700239) (xy 69.930264 -289.724846) (xy 70.269112 -289.724846) (xy 70.273072 -289.675792)
			(xy 70.284849 -289.628008) (xy 70.30414 -289.582732) (xy 70.330443 -289.541136) (xy 70.363078 -289.504299)
			(xy 70.401199 -289.473174) (xy 70.44382 -289.448567) (xy 70.489836 -289.431115) (xy 70.538055 -289.421271)
			(xy 70.58723 -289.41929) (xy 70.636085 -289.425222) (xy 70.683356 -289.438914) (xy 70.727818 -289.460012)
			(xy 70.768321 -289.487968) (xy 70.803814 -289.52206) (xy 70.833379 -289.561404) (xy 70.85625 -289.604981)
			(xy 70.871834 -289.651662) (xy 70.879729 -289.700239) (xy 70.880224 -289.724846) (xy 71.219072 -289.724846)
			(xy 71.223032 -289.675792) (xy 71.234809 -289.628008) (xy 71.2541 -289.582732) (xy 71.280403 -289.541136)
			(xy 71.313038 -289.504299) (xy 71.351159 -289.473174) (xy 71.39378 -289.448567) (xy 71.439796 -289.431115)
			(xy 71.488015 -289.421271) (xy 71.53719 -289.41929) (xy 71.586045 -289.425222) (xy 71.633316 -289.438914)
			(xy 71.677778 -289.460012) (xy 71.718281 -289.487968) (xy 71.753774 -289.52206) (xy 71.783339 -289.561404)
			(xy 71.80621 -289.604981) (xy 71.821794 -289.651662) (xy 71.829689 -289.700239) (xy 71.830184 -289.724846)
			(xy 72.169032 -289.724846) (xy 72.172992 -289.675792) (xy 72.184769 -289.628008) (xy 72.20406 -289.582732)
			(xy 72.230363 -289.541136) (xy 72.262998 -289.504299) (xy 72.301119 -289.473174) (xy 72.34374 -289.448567)
			(xy 72.389756 -289.431115) (xy 72.437975 -289.421271) (xy 72.48715 -289.41929) (xy 72.536005 -289.425222)
			(xy 72.583276 -289.438914) (xy 72.627738 -289.460012) (xy 72.668241 -289.487968) (xy 72.703734 -289.52206)
			(xy 72.733299 -289.561404) (xy 72.75617 -289.604981) (xy 72.771754 -289.651662) (xy 72.779649 -289.700239)
			(xy 72.779976 -289.716507) (xy 73.119127 -289.716507) (xy 73.124496 -289.667166) (xy 73.137775 -289.619343)
			(xy 73.158617 -289.574298) (xy 73.186471 -289.533218) (xy 73.220603 -289.497186) (xy 73.260116 -289.46715)
			(xy 73.303967 -289.443902) (xy 73.351001 -289.428054) (xy 73.39998 -289.420024) (xy 73.424796 -289.419538)
			(xy 73.438979 -289.419714) (xy 73.467219 -289.422387) (xy 73.481184 -289.424872) (xy 73.49363 -289.427158)
			(xy 73.517252 -289.419792) (xy 73.594722 -289.342322) (xy 73.602088 -289.3187) (xy 73.599802 -289.306254)
			(xy 73.597323 -289.292289) (xy 73.594653 -289.264049) (xy 73.594468 -289.249866) (xy 73.59499 -289.224611)
			(xy 73.603303 -289.174789) (xy 73.619704 -289.127015) (xy 73.643745 -289.082592) (xy 73.674769 -289.042732)
			(xy 73.711931 -289.008522) (xy 73.754217 -288.980896) (xy 73.800473 -288.960606) (xy 73.849438 -288.948206)
			(xy 73.899776 -288.944035) (xy 73.950114 -288.948206) (xy 73.999079 -288.960606) (xy 74.045335 -288.980896)
			(xy 74.087621 -289.008522) (xy 74.124783 -289.042732) (xy 74.155807 -289.082592) (xy 74.157121 -289.08502)
			(xy 85.787736 -289.08502) (xy 85.791807 -289.029398) (xy 85.803933 -288.974961) (xy 85.823856 -288.92287)
			(xy 85.851152 -288.874235) (xy 85.885238 -288.830092) (xy 85.925387 -288.791383) (xy 85.970745 -288.758932)
			(xy 86.020345 -288.733431) (xy 86.073129 -288.715424) (xy 86.127972 -288.705294) (xy 86.183706 -288.703257)
			(xy 86.239143 -288.709357) (xy 86.2931 -288.723463) (xy 86.344429 -288.745275) (xy 86.392035 -288.774329)
			(xy 86.434903 -288.810004) (xy 86.47212 -288.851541) (xy 86.502893 -288.898054) (xy 86.526565 -288.948551)
			(xy 86.542633 -289.001958) (xy 86.550753 -289.057134) (xy 86.551262 -289.08502) (xy 86.550753 -289.112906)
			(xy 86.542633 -289.168082) (xy 86.526565 -289.221489) (xy 86.502893 -289.271986) (xy 86.47212 -289.318499)
			(xy 86.434903 -289.360036) (xy 86.392035 -289.395711) (xy 86.344429 -289.424765) (xy 86.2931 -289.446577)
			(xy 86.239143 -289.460683) (xy 86.183706 -289.466783) (xy 86.127972 -289.464746) (xy 86.073129 -289.454616)
			(xy 86.020345 -289.436609) (xy 85.970745 -289.411108) (xy 85.925387 -289.378657) (xy 85.885238 -289.339948)
			(xy 85.851152 -289.295805) (xy 85.823856 -289.24717) (xy 85.803933 -289.195079) (xy 85.791807 -289.140642)
			(xy 85.787736 -289.08502) (xy 74.157121 -289.08502) (xy 74.179848 -289.127015) (xy 74.196249 -289.174789)
			(xy 74.204562 -289.224611) (xy 74.205084 -289.249866) (xy 74.204903 -289.264049) (xy 74.202234 -289.292289)
			(xy 74.19975 -289.306254) (xy 74.197464 -289.3187) (xy 74.20483 -289.342576) (xy 74.282046 -289.419792)
			(xy 74.306176 -289.427158) (xy 74.318368 -289.424872) (xy 74.332396 -289.42238) (xy 74.360764 -289.419713)
			(xy 74.37501 -289.419538) (xy 74.399829 -289.419989) (xy 74.448813 -289.42802) (xy 74.495853 -289.443871)
			(xy 74.539708 -289.467122) (xy 74.579225 -289.497162) (xy 74.613361 -289.5332) (xy 74.641217 -289.574284)
			(xy 74.66206 -289.619335) (xy 74.675341 -289.667163) (xy 74.680709 -289.71651) (xy 74.680257 -289.724846)
			(xy 75.969126 -289.724846) (xy 75.973086 -289.675792) (xy 75.984863 -289.628008) (xy 76.004154 -289.582732)
			(xy 76.030457 -289.541136) (xy 76.063092 -289.504299) (xy 76.101213 -289.473174) (xy 76.143834 -289.448567)
			(xy 76.18985 -289.431115) (xy 76.238069 -289.421271) (xy 76.287244 -289.41929) (xy 76.336099 -289.425222)
			(xy 76.38337 -289.438914) (xy 76.427832 -289.460012) (xy 76.468335 -289.487968) (xy 76.503828 -289.52206)
			(xy 76.533393 -289.561404) (xy 76.556264 -289.604981) (xy 76.571848 -289.651662) (xy 76.579743 -289.700239)
			(xy 76.580238 -289.724846) (xy 76.919086 -289.724846) (xy 76.923046 -289.675792) (xy 76.934823 -289.628008)
			(xy 76.954114 -289.582732) (xy 76.980417 -289.541136) (xy 77.013052 -289.504299) (xy 77.051173 -289.473174)
			(xy 77.093794 -289.448567) (xy 77.13981 -289.431115) (xy 77.188029 -289.421271) (xy 77.237204 -289.41929)
			(xy 77.286059 -289.425222) (xy 77.33333 -289.438914) (xy 77.377792 -289.460012) (xy 77.418295 -289.487968)
			(xy 77.453788 -289.52206) (xy 77.483353 -289.561404) (xy 77.506224 -289.604981) (xy 77.521808 -289.651662)
			(xy 77.529703 -289.700239) (xy 77.530198 -289.724846) (xy 77.869046 -289.724846) (xy 77.873006 -289.675792)
			(xy 77.884783 -289.628008) (xy 77.904074 -289.582732) (xy 77.930377 -289.541136) (xy 77.963012 -289.504299)
			(xy 78.001133 -289.473174) (xy 78.043754 -289.448567) (xy 78.08977 -289.431115) (xy 78.137989 -289.421271)
			(xy 78.187164 -289.41929) (xy 78.236019 -289.425222) (xy 78.28329 -289.438914) (xy 78.327752 -289.460012)
			(xy 78.368255 -289.487968) (xy 78.403748 -289.52206) (xy 78.433313 -289.561404) (xy 78.456184 -289.604981)
			(xy 78.471768 -289.651662) (xy 78.479663 -289.700239) (xy 78.480158 -289.724846) (xy 78.819006 -289.724846)
			(xy 78.822966 -289.675792) (xy 78.834743 -289.628008) (xy 78.854034 -289.582732) (xy 78.880337 -289.541136)
			(xy 78.912972 -289.504299) (xy 78.951093 -289.473174) (xy 78.993714 -289.448567) (xy 79.03973 -289.431115)
			(xy 79.087949 -289.421271) (xy 79.137124 -289.41929) (xy 79.185979 -289.425222) (xy 79.23325 -289.438914)
			(xy 79.277712 -289.460012) (xy 79.318215 -289.487968) (xy 79.353708 -289.52206) (xy 79.383273 -289.561404)
			(xy 79.406144 -289.604981) (xy 79.421728 -289.651662) (xy 79.429623 -289.700239) (xy 79.430118 -289.724846)
			(xy 79.768966 -289.724846) (xy 79.772926 -289.675792) (xy 79.784703 -289.628008) (xy 79.803994 -289.582732)
			(xy 79.830297 -289.541136) (xy 79.862932 -289.504299) (xy 79.901053 -289.473174) (xy 79.943674 -289.448567)
			(xy 79.98969 -289.431115) (xy 80.037909 -289.421271) (xy 80.087084 -289.41929) (xy 80.135939 -289.425222)
			(xy 80.18321 -289.438914) (xy 80.227672 -289.460012) (xy 80.268175 -289.487968) (xy 80.303668 -289.52206)
			(xy 80.333233 -289.561404) (xy 80.356104 -289.604981) (xy 80.371688 -289.651662) (xy 80.379583 -289.700239)
			(xy 80.380078 -289.724846) (xy 80.71918 -289.724846) (xy 80.72314 -289.675792) (xy 80.734917 -289.628008)
			(xy 80.754208 -289.582732) (xy 80.780511 -289.541136) (xy 80.813146 -289.504299) (xy 80.851267 -289.473174)
			(xy 80.893888 -289.448567) (xy 80.939904 -289.431115) (xy 80.988123 -289.421271) (xy 81.037298 -289.41929)
			(xy 81.086153 -289.425222) (xy 81.133424 -289.438914) (xy 81.177886 -289.460012) (xy 81.218389 -289.487968)
			(xy 81.253882 -289.52206) (xy 81.283447 -289.561404) (xy 81.306318 -289.604981) (xy 81.321902 -289.651662)
			(xy 81.329797 -289.700239) (xy 81.330292 -289.724846) (xy 81.66914 -289.724846) (xy 81.6731 -289.675792)
			(xy 81.684877 -289.628008) (xy 81.704168 -289.582732) (xy 81.730471 -289.541136) (xy 81.763106 -289.504299)
			(xy 81.801227 -289.473174) (xy 81.843848 -289.448567) (xy 81.889864 -289.431115) (xy 81.938083 -289.421271)
			(xy 81.987258 -289.41929) (xy 82.036113 -289.425222) (xy 82.083384 -289.438914) (xy 82.127846 -289.460012)
			(xy 82.168349 -289.487968) (xy 82.203842 -289.52206) (xy 82.233407 -289.561404) (xy 82.256278 -289.604981)
			(xy 82.271862 -289.651662) (xy 82.279757 -289.700239) (xy 82.280252 -289.724846) (xy 82.6191 -289.724846)
			(xy 82.62306 -289.675792) (xy 82.634837 -289.628008) (xy 82.654128 -289.582732) (xy 82.680431 -289.541136)
			(xy 82.713066 -289.504299) (xy 82.751187 -289.473174) (xy 82.793808 -289.448567) (xy 82.839824 -289.431115)
			(xy 82.888043 -289.421271) (xy 82.937218 -289.41929) (xy 82.986073 -289.425222) (xy 83.033344 -289.438914)
			(xy 83.077806 -289.460012) (xy 83.118309 -289.487968) (xy 83.153802 -289.52206) (xy 83.183367 -289.561404)
			(xy 83.206238 -289.604981) (xy 83.221822 -289.651662) (xy 83.229717 -289.700239) (xy 83.230212 -289.724846)
			(xy 83.229717 -289.749453) (xy 83.221822 -289.79803) (xy 83.206238 -289.844711) (xy 83.183367 -289.888288)
			(xy 83.153802 -289.927632) (xy 83.118309 -289.961724) (xy 83.077806 -289.98968) (xy 83.033344 -290.010778)
			(xy 82.986073 -290.02447) (xy 82.937218 -290.030402) (xy 82.888043 -290.028421) (xy 82.839824 -290.018577)
			(xy 82.793808 -290.001125) (xy 82.751187 -289.976518) (xy 82.713066 -289.945393) (xy 82.680431 -289.908556)
			(xy 82.654128 -289.86696) (xy 82.634837 -289.821684) (xy 82.62306 -289.7739) (xy 82.6191 -289.724846)
			(xy 82.280252 -289.724846) (xy 82.279757 -289.749453) (xy 82.271862 -289.79803) (xy 82.256278 -289.844711)
			(xy 82.233407 -289.888288) (xy 82.203842 -289.927632) (xy 82.168349 -289.961724) (xy 82.127846 -289.98968)
			(xy 82.083384 -290.010778) (xy 82.036113 -290.02447) (xy 81.987258 -290.030402) (xy 81.938083 -290.028421)
			(xy 81.889864 -290.018577) (xy 81.843848 -290.001125) (xy 81.801227 -289.976518) (xy 81.763106 -289.945393)
			(xy 81.730471 -289.908556) (xy 81.704168 -289.86696) (xy 81.684877 -289.821684) (xy 81.6731 -289.7739)
			(xy 81.66914 -289.724846) (xy 81.330292 -289.724846) (xy 81.329797 -289.749453) (xy 81.321902 -289.79803)
			(xy 81.306318 -289.844711) (xy 81.283447 -289.888288) (xy 81.253882 -289.927632) (xy 81.218389 -289.961724)
			(xy 81.177886 -289.98968) (xy 81.133424 -290.010778) (xy 81.086153 -290.02447) (xy 81.037298 -290.030402)
			(xy 80.988123 -290.028421) (xy 80.939904 -290.018577) (xy 80.893888 -290.001125) (xy 80.851267 -289.976518)
			(xy 80.813146 -289.945393) (xy 80.780511 -289.908556) (xy 80.754208 -289.86696) (xy 80.734917 -289.821684)
			(xy 80.72314 -289.7739) (xy 80.71918 -289.724846) (xy 80.380078 -289.724846) (xy 80.379583 -289.749453)
			(xy 80.371688 -289.79803) (xy 80.356104 -289.844711) (xy 80.333233 -289.888288) (xy 80.303668 -289.927632)
			(xy 80.268175 -289.961724) (xy 80.227672 -289.98968) (xy 80.18321 -290.010778) (xy 80.135939 -290.02447)
			(xy 80.087084 -290.030402) (xy 80.037909 -290.028421) (xy 79.98969 -290.018577) (xy 79.943674 -290.001125)
			(xy 79.901053 -289.976518) (xy 79.862932 -289.945393) (xy 79.830297 -289.908556) (xy 79.803994 -289.86696)
			(xy 79.784703 -289.821684) (xy 79.772926 -289.7739) (xy 79.768966 -289.724846) (xy 79.430118 -289.724846)
			(xy 79.429623 -289.749453) (xy 79.421728 -289.79803) (xy 79.406144 -289.844711) (xy 79.383273 -289.888288)
			(xy 79.353708 -289.927632) (xy 79.318215 -289.961724) (xy 79.277712 -289.98968) (xy 79.23325 -290.010778)
			(xy 79.185979 -290.02447) (xy 79.137124 -290.030402) (xy 79.087949 -290.028421) (xy 79.03973 -290.018577)
			(xy 78.993714 -290.001125) (xy 78.951093 -289.976518) (xy 78.912972 -289.945393) (xy 78.880337 -289.908556)
			(xy 78.854034 -289.86696) (xy 78.834743 -289.821684) (xy 78.822966 -289.7739) (xy 78.819006 -289.724846)
			(xy 78.480158 -289.724846) (xy 78.479663 -289.749453) (xy 78.471768 -289.79803) (xy 78.456184 -289.844711)
			(xy 78.433313 -289.888288) (xy 78.403748 -289.927632) (xy 78.368255 -289.961724) (xy 78.327752 -289.98968)
			(xy 78.28329 -290.010778) (xy 78.236019 -290.02447) (xy 78.187164 -290.030402) (xy 78.137989 -290.028421)
			(xy 78.08977 -290.018577) (xy 78.043754 -290.001125) (xy 78.001133 -289.976518) (xy 77.963012 -289.945393)
			(xy 77.930377 -289.908556) (xy 77.904074 -289.86696) (xy 77.884783 -289.821684) (xy 77.873006 -289.7739)
			(xy 77.869046 -289.724846) (xy 77.530198 -289.724846) (xy 77.529703 -289.749453) (xy 77.521808 -289.79803)
			(xy 77.506224 -289.844711) (xy 77.483353 -289.888288) (xy 77.453788 -289.927632) (xy 77.418295 -289.961724)
			(xy 77.377792 -289.98968) (xy 77.33333 -290.010778) (xy 77.286059 -290.02447) (xy 77.237204 -290.030402)
			(xy 77.188029 -290.028421) (xy 77.13981 -290.018577) (xy 77.093794 -290.001125) (xy 77.051173 -289.976518)
			(xy 77.013052 -289.945393) (xy 76.980417 -289.908556) (xy 76.954114 -289.86696) (xy 76.934823 -289.821684)
			(xy 76.923046 -289.7739) (xy 76.919086 -289.724846) (xy 76.580238 -289.724846) (xy 76.579743 -289.749453)
			(xy 76.571848 -289.79803) (xy 76.556264 -289.844711) (xy 76.533393 -289.888288) (xy 76.503828 -289.927632)
			(xy 76.468335 -289.961724) (xy 76.427832 -289.98968) (xy 76.38337 -290.010778) (xy 76.336099 -290.02447)
			(xy 76.287244 -290.030402) (xy 76.238069 -290.028421) (xy 76.18985 -290.018577) (xy 76.143834 -290.001125)
			(xy 76.101213 -289.976518) (xy 76.063092 -289.945393) (xy 76.030457 -289.908556) (xy 76.004154 -289.86696)
			(xy 75.984863 -289.821684) (xy 75.973086 -289.7739) (xy 75.969126 -289.724846) (xy 74.680257 -289.724846)
			(xy 74.678023 -289.766076) (xy 74.667354 -289.814554) (xy 74.648983 -289.860667) (xy 74.623394 -289.903201)
			(xy 74.591261 -289.941035) (xy 74.553431 -289.973173) (xy 74.510899 -289.998767) (xy 74.464788 -290.017143)
			(xy 74.416311 -290.027818) (xy 74.366746 -290.03051) (xy 74.317399 -290.025147) (xy 74.269568 -290.011873)
			(xy 74.224516 -289.991035) (xy 74.183428 -289.963183) (xy 74.147387 -289.929051) (xy 74.117342 -289.889539)
			(xy 74.094085 -289.845686) (xy 74.078229 -289.798648) (xy 74.070192 -289.749665) (xy 74.069702 -289.724846)
			(xy 74.069885 -289.710663) (xy 74.072553 -289.682423) (xy 74.075036 -289.668458) (xy 74.077322 -289.656012)
			(xy 74.069956 -289.632136) (xy 73.99274 -289.55492) (xy 73.96861 -289.547554) (xy 73.956418 -289.54984)
			(xy 73.942388 -289.55232) (xy 73.914022 -289.554995) (xy 73.899776 -289.555174) (xy 73.885593 -289.555001)
			(xy 73.857353 -289.552327) (xy 73.843388 -289.54984) (xy 73.830942 -289.547554) (xy 73.80732 -289.55492)
			(xy 73.72985 -289.63239) (xy 73.722484 -289.656012) (xy 73.72477 -289.668458) (xy 73.72725 -289.682423)
			(xy 73.72992 -289.710663) (xy 73.730104 -289.724846) (xy 73.729573 -289.749662) (xy 73.721536 -289.79864)
			(xy 73.705682 -289.845672) (xy 73.682427 -289.88952) (xy 73.652386 -289.929028) (xy 73.616349 -289.963156)
			(xy 73.575265 -289.991004) (xy 73.530218 -290.011839) (xy 73.482393 -290.025112) (xy 73.433051 -290.030474)
			(xy 73.383491 -290.027782) (xy 73.33502 -290.017108) (xy 73.288914 -289.998733) (xy 73.246388 -289.973142)
			(xy 73.208562 -289.941008) (xy 73.176434 -289.903178) (xy 73.150848 -289.860648) (xy 73.13248 -289.81454)
			(xy 73.121812 -289.766067) (xy 73.119127 -289.716507) (xy 72.779976 -289.716507) (xy 72.780144 -289.724846)
			(xy 72.779649 -289.749453) (xy 72.771754 -289.79803) (xy 72.75617 -289.844711) (xy 72.733299 -289.888288)
			(xy 72.703734 -289.927632) (xy 72.668241 -289.961724) (xy 72.627738 -289.98968) (xy 72.583276 -290.010778)
			(xy 72.536005 -290.02447) (xy 72.48715 -290.030402) (xy 72.437975 -290.028421) (xy 72.389756 -290.018577)
			(xy 72.34374 -290.001125) (xy 72.301119 -289.976518) (xy 72.262998 -289.945393) (xy 72.230363 -289.908556)
			(xy 72.20406 -289.86696) (xy 72.184769 -289.821684) (xy 72.172992 -289.7739) (xy 72.169032 -289.724846)
			(xy 71.830184 -289.724846) (xy 71.829689 -289.749453) (xy 71.821794 -289.79803) (xy 71.80621 -289.844711)
			(xy 71.783339 -289.888288) (xy 71.753774 -289.927632) (xy 71.718281 -289.961724) (xy 71.677778 -289.98968)
			(xy 71.633316 -290.010778) (xy 71.586045 -290.02447) (xy 71.53719 -290.030402) (xy 71.488015 -290.028421)
			(xy 71.439796 -290.018577) (xy 71.39378 -290.001125) (xy 71.351159 -289.976518) (xy 71.313038 -289.945393)
			(xy 71.280403 -289.908556) (xy 71.2541 -289.86696) (xy 71.234809 -289.821684) (xy 71.223032 -289.7739)
			(xy 71.219072 -289.724846) (xy 70.880224 -289.724846) (xy 70.879729 -289.749453) (xy 70.871834 -289.79803)
			(xy 70.85625 -289.844711) (xy 70.833379 -289.888288) (xy 70.803814 -289.927632) (xy 70.768321 -289.961724)
			(xy 70.727818 -289.98968) (xy 70.683356 -290.010778) (xy 70.636085 -290.02447) (xy 70.58723 -290.030402)
			(xy 70.538055 -290.028421) (xy 70.489836 -290.018577) (xy 70.44382 -290.001125) (xy 70.401199 -289.976518)
			(xy 70.363078 -289.945393) (xy 70.330443 -289.908556) (xy 70.30414 -289.86696) (xy 70.284849 -289.821684)
			(xy 70.273072 -289.7739) (xy 70.269112 -289.724846) (xy 69.930264 -289.724846) (xy 69.929769 -289.749453)
			(xy 69.921874 -289.79803) (xy 69.90629 -289.844711) (xy 69.883419 -289.888288) (xy 69.853854 -289.927632)
			(xy 69.818361 -289.961724) (xy 69.777858 -289.98968) (xy 69.733396 -290.010778) (xy 69.686125 -290.02447)
			(xy 69.63727 -290.030402) (xy 69.588095 -290.028421) (xy 69.539876 -290.018577) (xy 69.49386 -290.001125)
			(xy 69.451239 -289.976518) (xy 69.413118 -289.945393) (xy 69.380483 -289.908556) (xy 69.35418 -289.86696)
			(xy 69.334889 -289.821684) (xy 69.323112 -289.7739) (xy 69.319152 -289.724846) (xy 68.98005 -289.724846)
			(xy 68.979555 -289.749453) (xy 68.97166 -289.79803) (xy 68.956076 -289.844711) (xy 68.933205 -289.888288)
			(xy 68.90364 -289.927632) (xy 68.868147 -289.961724) (xy 68.827644 -289.98968) (xy 68.783182 -290.010778)
			(xy 68.735911 -290.02447) (xy 68.687056 -290.030402) (xy 68.637881 -290.028421) (xy 68.589662 -290.018577)
			(xy 68.543646 -290.001125) (xy 68.501025 -289.976518) (xy 68.462904 -289.945393) (xy 68.430269 -289.908556)
			(xy 68.403966 -289.86696) (xy 68.384675 -289.821684) (xy 68.372898 -289.7739) (xy 68.368938 -289.724846)
			(xy 68.03009 -289.724846) (xy 68.029595 -289.749453) (xy 68.0217 -289.79803) (xy 68.006116 -289.844711)
			(xy 67.983245 -289.888288) (xy 67.95368 -289.927632) (xy 67.918187 -289.961724) (xy 67.877684 -289.98968)
			(xy 67.833222 -290.010778) (xy 67.785951 -290.02447) (xy 67.737096 -290.030402) (xy 67.687921 -290.028421)
			(xy 67.639702 -290.018577) (xy 67.593686 -290.001125) (xy 67.551065 -289.976518) (xy 67.512944 -289.945393)
			(xy 67.480309 -289.908556) (xy 67.454006 -289.86696) (xy 67.434715 -289.821684) (xy 67.422938 -289.7739)
			(xy 67.418978 -289.724846) (xy 67.08013 -289.724846) (xy 67.079635 -289.749453) (xy 67.07174 -289.79803)
			(xy 67.056156 -289.844711) (xy 67.033285 -289.888288) (xy 67.00372 -289.927632) (xy 66.968227 -289.961724)
			(xy 66.927724 -289.98968) (xy 66.883262 -290.010778) (xy 66.835991 -290.02447) (xy 66.787136 -290.030402)
			(xy 66.737961 -290.028421) (xy 66.689742 -290.018577) (xy 66.643726 -290.001125) (xy 66.601105 -289.976518)
			(xy 66.562984 -289.945393) (xy 66.530349 -289.908556) (xy 66.504046 -289.86696) (xy 66.484755 -289.821684)
			(xy 66.472978 -289.7739) (xy 66.469018 -289.724846) (xy 66.13017 -289.724846) (xy 66.129675 -289.749453)
			(xy 66.12178 -289.79803) (xy 66.106196 -289.844711) (xy 66.083325 -289.888288) (xy 66.05376 -289.927632)
			(xy 66.018267 -289.961724) (xy 65.977764 -289.98968) (xy 65.933302 -290.010778) (xy 65.886031 -290.02447)
			(xy 65.837176 -290.030402) (xy 65.788001 -290.028421) (xy 65.739782 -290.018577) (xy 65.693766 -290.001125)
			(xy 65.651145 -289.976518) (xy 65.613024 -289.945393) (xy 65.580389 -289.908556) (xy 65.554086 -289.86696)
			(xy 65.534795 -289.821684) (xy 65.523018 -289.7739) (xy 65.519058 -289.724846) (xy 65.18021 -289.724846)
			(xy 65.179715 -289.749453) (xy 65.17182 -289.79803) (xy 65.156236 -289.844711) (xy 65.133365 -289.888288)
			(xy 65.1038 -289.927632) (xy 65.068307 -289.961724) (xy 65.027804 -289.98968) (xy 64.983342 -290.010778)
			(xy 64.936071 -290.02447) (xy 64.887216 -290.030402) (xy 64.838041 -290.028421) (xy 64.789822 -290.018577)
			(xy 64.743806 -290.001125) (xy 64.701185 -289.976518) (xy 64.663064 -289.945393) (xy 64.630429 -289.908556)
			(xy 64.604126 -289.86696) (xy 64.584835 -289.821684) (xy 64.573058 -289.7739) (xy 64.569098 -289.724846)
			(xy 64.23025 -289.724846) (xy 64.229755 -289.749453) (xy 64.22186 -289.79803) (xy 64.206276 -289.844711)
			(xy 64.183405 -289.888288) (xy 64.15384 -289.927632) (xy 64.118347 -289.961724) (xy 64.077844 -289.98968)
			(xy 64.033382 -290.010778) (xy 63.986111 -290.02447) (xy 63.937256 -290.030402) (xy 63.888081 -290.028421)
			(xy 63.839862 -290.018577) (xy 63.793846 -290.001125) (xy 63.751225 -289.976518) (xy 63.713104 -289.945393)
			(xy 63.680469 -289.908556) (xy 63.654166 -289.86696) (xy 63.634875 -289.821684) (xy 63.623098 -289.7739)
			(xy 63.619138 -289.724846) (xy 63.28029 -289.724846) (xy 63.279795 -289.749453) (xy 63.2719 -289.79803)
			(xy 63.256316 -289.844711) (xy 63.233445 -289.888288) (xy 63.20388 -289.927632) (xy 63.168387 -289.961724)
			(xy 63.127884 -289.98968) (xy 63.083422 -290.010778) (xy 63.036151 -290.02447) (xy 62.987296 -290.030402)
			(xy 62.938121 -290.028421) (xy 62.889902 -290.018577) (xy 62.843886 -290.001125) (xy 62.801265 -289.976518)
			(xy 62.763144 -289.945393) (xy 62.730509 -289.908556) (xy 62.704206 -289.86696) (xy 62.684915 -289.821684)
			(xy 62.673138 -289.7739) (xy 62.669178 -289.724846) (xy 62.330076 -289.724846) (xy 62.329581 -289.749453)
			(xy 62.321686 -289.79803) (xy 62.306102 -289.844711) (xy 62.283231 -289.888288) (xy 62.253666 -289.927632)
			(xy 62.218173 -289.961724) (xy 62.17767 -289.98968) (xy 62.133208 -290.010778) (xy 62.085937 -290.02447)
			(xy 62.037082 -290.030402) (xy 61.987907 -290.028421) (xy 61.939688 -290.018577) (xy 61.893672 -290.001125)
			(xy 61.851051 -289.976518) (xy 61.81293 -289.945393) (xy 61.780295 -289.908556) (xy 61.753992 -289.86696)
			(xy 61.734701 -289.821684) (xy 61.722924 -289.7739) (xy 61.718964 -289.724846) (xy 61.380116 -289.724846)
			(xy 61.379621 -289.749453) (xy 61.371726 -289.79803) (xy 61.356142 -289.844711) (xy 61.333271 -289.888288)
			(xy 61.303706 -289.927632) (xy 61.268213 -289.961724) (xy 61.22771 -289.98968) (xy 61.183248 -290.010778)
			(xy 61.135977 -290.02447) (xy 61.087122 -290.030402) (xy 61.037947 -290.028421) (xy 60.989728 -290.018577)
			(xy 60.943712 -290.001125) (xy 60.901091 -289.976518) (xy 60.86297 -289.945393) (xy 60.830335 -289.908556)
			(xy 60.804032 -289.86696) (xy 60.784741 -289.821684) (xy 60.772964 -289.7739) (xy 60.769004 -289.724846)
			(xy 60.430156 -289.724846) (xy 60.429661 -289.749453) (xy 60.421766 -289.79803) (xy 60.406182 -289.844711)
			(xy 60.383311 -289.888288) (xy 60.353746 -289.927632) (xy 60.318253 -289.961724) (xy 60.27775 -289.98968)
			(xy 60.233288 -290.010778) (xy 60.186017 -290.02447) (xy 60.137162 -290.030402) (xy 60.087987 -290.028421)
			(xy 60.039768 -290.018577) (xy 59.993752 -290.001125) (xy 59.951131 -289.976518) (xy 59.91301 -289.945393)
			(xy 59.880375 -289.908556) (xy 59.854072 -289.86696) (xy 59.834781 -289.821684) (xy 59.823004 -289.7739)
			(xy 59.819044 -289.724846) (xy 58.530236 -289.724846) (xy 58.529741 -289.749453) (xy 58.521846 -289.79803)
			(xy 58.506262 -289.844711) (xy 58.483391 -289.888288) (xy 58.453826 -289.927632) (xy 58.418333 -289.961724)
			(xy 58.37783 -289.98968) (xy 58.333368 -290.010778) (xy 58.286097 -290.02447) (xy 58.237242 -290.030402)
			(xy 58.188067 -290.028421) (xy 58.139848 -290.018577) (xy 58.093832 -290.001125) (xy 58.051211 -289.976518)
			(xy 58.01309 -289.945393) (xy 57.980455 -289.908556) (xy 57.954152 -289.86696) (xy 57.934861 -289.821684)
			(xy 57.923084 -289.7739) (xy 57.919124 -289.724846) (xy 57.580276 -289.724846) (xy 57.579781 -289.749453)
			(xy 57.571886 -289.79803) (xy 57.556302 -289.844711) (xy 57.533431 -289.888288) (xy 57.503866 -289.927632)
			(xy 57.468373 -289.961724) (xy 57.42787 -289.98968) (xy 57.383408 -290.010778) (xy 57.336137 -290.02447)
			(xy 57.287282 -290.030402) (xy 57.238107 -290.028421) (xy 57.189888 -290.018577) (xy 57.143872 -290.001125)
			(xy 57.101251 -289.976518) (xy 57.06313 -289.945393) (xy 57.030495 -289.908556) (xy 57.004192 -289.86696)
			(xy 56.984901 -289.821684) (xy 56.973124 -289.7739) (xy 56.969164 -289.724846) (xy 56.630062 -289.724846)
			(xy 56.629567 -289.749453) (xy 56.621672 -289.79803) (xy 56.606088 -289.844711) (xy 56.583217 -289.888288)
			(xy 56.553652 -289.927632) (xy 56.518159 -289.961724) (xy 56.477656 -289.98968) (xy 56.433194 -290.010778)
			(xy 56.385923 -290.02447) (xy 56.337068 -290.030402) (xy 56.287893 -290.028421) (xy 56.239674 -290.018577)
			(xy 56.193658 -290.001125) (xy 56.151037 -289.976518) (xy 56.112916 -289.945393) (xy 56.080281 -289.908556)
			(xy 56.053978 -289.86696) (xy 56.034687 -289.821684) (xy 56.02291 -289.7739) (xy 56.01895 -289.724846)
			(xy 55.680102 -289.724846) (xy 55.679607 -289.749453) (xy 55.671712 -289.79803) (xy 55.656128 -289.844711)
			(xy 55.633257 -289.888288) (xy 55.603692 -289.927632) (xy 55.568199 -289.961724) (xy 55.527696 -289.98968)
			(xy 55.483234 -290.010778) (xy 55.435963 -290.02447) (xy 55.387108 -290.030402) (xy 55.337933 -290.028421)
			(xy 55.289714 -290.018577) (xy 55.243698 -290.001125) (xy 55.201077 -289.976518) (xy 55.162956 -289.945393)
			(xy 55.130321 -289.908556) (xy 55.104018 -289.86696) (xy 55.084727 -289.821684) (xy 55.07295 -289.7739)
			(xy 55.06899 -289.724846) (xy 54.730142 -289.724846) (xy 54.729647 -289.749453) (xy 54.721752 -289.79803)
			(xy 54.706168 -289.844711) (xy 54.683297 -289.888288) (xy 54.653732 -289.927632) (xy 54.618239 -289.961724)
			(xy 54.577736 -289.98968) (xy 54.533274 -290.010778) (xy 54.486003 -290.02447) (xy 54.437148 -290.030402)
			(xy 54.387973 -290.028421) (xy 54.339754 -290.018577) (xy 54.293738 -290.001125) (xy 54.251117 -289.976518)
			(xy 54.212996 -289.945393) (xy 54.180361 -289.908556) (xy 54.154058 -289.86696) (xy 54.134767 -289.821684)
			(xy 54.12299 -289.7739) (xy 54.11903 -289.724846) (xy 53.780182 -289.724846) (xy 53.779687 -289.749453)
			(xy 53.771792 -289.79803) (xy 53.756208 -289.844711) (xy 53.733337 -289.888288) (xy 53.703772 -289.927632)
			(xy 53.668279 -289.961724) (xy 53.627776 -289.98968) (xy 53.583314 -290.010778) (xy 53.536043 -290.02447)
			(xy 53.487188 -290.030402) (xy 53.438013 -290.028421) (xy 53.389794 -290.018577) (xy 53.343778 -290.001125)
			(xy 53.301157 -289.976518) (xy 53.263036 -289.945393) (xy 53.230401 -289.908556) (xy 53.204098 -289.86696)
			(xy 53.184807 -289.821684) (xy 53.17303 -289.7739) (xy 53.16907 -289.724846) (xy 52.830222 -289.724846)
			(xy 52.829727 -289.749453) (xy 52.821832 -289.79803) (xy 52.806248 -289.844711) (xy 52.783377 -289.888288)
			(xy 52.753812 -289.927632) (xy 52.718319 -289.961724) (xy 52.677816 -289.98968) (xy 52.633354 -290.010778)
			(xy 52.586083 -290.02447) (xy 52.537228 -290.030402) (xy 52.488053 -290.028421) (xy 52.439834 -290.018577)
			(xy 52.393818 -290.001125) (xy 52.351197 -289.976518) (xy 52.313076 -289.945393) (xy 52.280441 -289.908556)
			(xy 52.254138 -289.86696) (xy 52.234847 -289.821684) (xy 52.22307 -289.7739) (xy 52.21911 -289.724846)
			(xy 51.880262 -289.724846) (xy 51.879767 -289.749453) (xy 51.871872 -289.79803) (xy 51.856288 -289.844711)
			(xy 51.833417 -289.888288) (xy 51.803852 -289.927632) (xy 51.768359 -289.961724) (xy 51.727856 -289.98968)
			(xy 51.683394 -290.010778) (xy 51.636123 -290.02447) (xy 51.587268 -290.030402) (xy 51.538093 -290.028421)
			(xy 51.489874 -290.018577) (xy 51.443858 -290.001125) (xy 51.401237 -289.976518) (xy 51.363116 -289.945393)
			(xy 51.330481 -289.908556) (xy 51.304178 -289.86696) (xy 51.284887 -289.821684) (xy 51.27311 -289.7739)
			(xy 51.26915 -289.724846) (xy 50.930302 -289.724846) (xy 50.929807 -289.749453) (xy 50.921912 -289.79803)
			(xy 50.906328 -289.844711) (xy 50.883457 -289.888288) (xy 50.853892 -289.927632) (xy 50.818399 -289.961724)
			(xy 50.777896 -289.98968) (xy 50.733434 -290.010778) (xy 50.686163 -290.02447) (xy 50.637308 -290.030402)
			(xy 50.588133 -290.028421) (xy 50.539914 -290.018577) (xy 50.493898 -290.001125) (xy 50.451277 -289.976518)
			(xy 50.413156 -289.945393) (xy 50.380521 -289.908556) (xy 50.354218 -289.86696) (xy 50.334927 -289.821684)
			(xy 50.32315 -289.7739) (xy 50.31919 -289.724846) (xy 49.980088 -289.724846) (xy 49.979593 -289.749453)
			(xy 49.971698 -289.79803) (xy 49.956114 -289.844711) (xy 49.933243 -289.888288) (xy 49.903678 -289.927632)
			(xy 49.868185 -289.961724) (xy 49.827682 -289.98968) (xy 49.78322 -290.010778) (xy 49.735949 -290.02447)
			(xy 49.687094 -290.030402) (xy 49.637919 -290.028421) (xy 49.5897 -290.018577) (xy 49.543684 -290.001125)
			(xy 49.501063 -289.976518) (xy 49.462942 -289.945393) (xy 49.430307 -289.908556) (xy 49.404004 -289.86696)
			(xy 49.384713 -289.821684) (xy 49.372936 -289.7739) (xy 49.368976 -289.724846) (xy 49.181004 -289.724846)
			(xy 49.181004 -290.674806) (xy 49.368976 -290.674806) (xy 49.372936 -290.625752) (xy 49.384713 -290.577968)
			(xy 49.404004 -290.532692) (xy 49.430307 -290.491096) (xy 49.462942 -290.454259) (xy 49.501063 -290.423134)
			(xy 49.543684 -290.398527) (xy 49.5897 -290.381075) (xy 49.637919 -290.371231) (xy 49.687094 -290.36925)
			(xy 49.735949 -290.375182) (xy 49.78322 -290.388874) (xy 49.827682 -290.409972) (xy 49.868185 -290.437928)
			(xy 49.903678 -290.47202) (xy 49.933243 -290.511364) (xy 49.956114 -290.554941) (xy 49.971698 -290.601622)
			(xy 49.979593 -290.650199) (xy 49.980088 -290.674806) (xy 50.31919 -290.674806) (xy 50.32315 -290.625752)
			(xy 50.334927 -290.577968) (xy 50.354218 -290.532692) (xy 50.380521 -290.491096) (xy 50.413156 -290.454259)
			(xy 50.451277 -290.423134) (xy 50.493898 -290.398527) (xy 50.539914 -290.381075) (xy 50.588133 -290.371231)
			(xy 50.637308 -290.36925) (xy 50.686163 -290.375182) (xy 50.733434 -290.388874) (xy 50.777896 -290.409972)
			(xy 50.818399 -290.437928) (xy 50.853892 -290.47202) (xy 50.883457 -290.511364) (xy 50.906328 -290.554941)
			(xy 50.921912 -290.601622) (xy 50.929807 -290.650199) (xy 50.930302 -290.674806) (xy 51.26915 -290.674806)
			(xy 51.27311 -290.625752) (xy 51.284887 -290.577968) (xy 51.304178 -290.532692) (xy 51.330481 -290.491096)
			(xy 51.363116 -290.454259) (xy 51.401237 -290.423134) (xy 51.443858 -290.398527) (xy 51.489874 -290.381075)
			(xy 51.538093 -290.371231) (xy 51.587268 -290.36925) (xy 51.636123 -290.375182) (xy 51.683394 -290.388874)
			(xy 51.727856 -290.409972) (xy 51.768359 -290.437928) (xy 51.803852 -290.47202) (xy 51.833417 -290.511364)
			(xy 51.856288 -290.554941) (xy 51.871872 -290.601622) (xy 51.879767 -290.650199) (xy 51.880262 -290.674806)
			(xy 52.21911 -290.674806) (xy 52.22307 -290.625752) (xy 52.234847 -290.577968) (xy 52.254138 -290.532692)
			(xy 52.280441 -290.491096) (xy 52.313076 -290.454259) (xy 52.351197 -290.423134) (xy 52.393818 -290.398527)
			(xy 52.439834 -290.381075) (xy 52.488053 -290.371231) (xy 52.537228 -290.36925) (xy 52.586083 -290.375182)
			(xy 52.633354 -290.388874) (xy 52.677816 -290.409972) (xy 52.718319 -290.437928) (xy 52.753812 -290.47202)
			(xy 52.783377 -290.511364) (xy 52.806248 -290.554941) (xy 52.821832 -290.601622) (xy 52.829727 -290.650199)
			(xy 52.830222 -290.674806) (xy 53.16907 -290.674806) (xy 53.17303 -290.625752) (xy 53.184807 -290.577968)
			(xy 53.204098 -290.532692) (xy 53.230401 -290.491096) (xy 53.263036 -290.454259) (xy 53.301157 -290.423134)
			(xy 53.343778 -290.398527) (xy 53.389794 -290.381075) (xy 53.438013 -290.371231) (xy 53.487188 -290.36925)
			(xy 53.536043 -290.375182) (xy 53.583314 -290.388874) (xy 53.627776 -290.409972) (xy 53.668279 -290.437928)
			(xy 53.703772 -290.47202) (xy 53.733337 -290.511364) (xy 53.756208 -290.554941) (xy 53.771792 -290.601622)
			(xy 53.779687 -290.650199) (xy 53.780182 -290.674806) (xy 54.11903 -290.674806) (xy 54.12299 -290.625752)
			(xy 54.134767 -290.577968) (xy 54.154058 -290.532692) (xy 54.180361 -290.491096) (xy 54.212996 -290.454259)
			(xy 54.251117 -290.423134) (xy 54.293738 -290.398527) (xy 54.339754 -290.381075) (xy 54.387973 -290.371231)
			(xy 54.437148 -290.36925) (xy 54.486003 -290.375182) (xy 54.533274 -290.388874) (xy 54.577736 -290.409972)
			(xy 54.618239 -290.437928) (xy 54.653732 -290.47202) (xy 54.683297 -290.511364) (xy 54.706168 -290.554941)
			(xy 54.721752 -290.601622) (xy 54.729647 -290.650199) (xy 54.730142 -290.674806) (xy 55.06899 -290.674806)
			(xy 55.07295 -290.625752) (xy 55.084727 -290.577968) (xy 55.104018 -290.532692) (xy 55.130321 -290.491096)
			(xy 55.162956 -290.454259) (xy 55.201077 -290.423134) (xy 55.243698 -290.398527) (xy 55.289714 -290.381075)
			(xy 55.337933 -290.371231) (xy 55.387108 -290.36925) (xy 55.435963 -290.375182) (xy 55.483234 -290.388874)
			(xy 55.527696 -290.409972) (xy 55.568199 -290.437928) (xy 55.603692 -290.47202) (xy 55.633257 -290.511364)
			(xy 55.656128 -290.554941) (xy 55.671712 -290.601622) (xy 55.679607 -290.650199) (xy 55.680102 -290.674806)
			(xy 56.01895 -290.674806) (xy 56.02291 -290.625752) (xy 56.034687 -290.577968) (xy 56.053978 -290.532692)
			(xy 56.080281 -290.491096) (xy 56.112916 -290.454259) (xy 56.151037 -290.423134) (xy 56.193658 -290.398527)
			(xy 56.239674 -290.381075) (xy 56.287893 -290.371231) (xy 56.337068 -290.36925) (xy 56.385923 -290.375182)
			(xy 56.433194 -290.388874) (xy 56.477656 -290.409972) (xy 56.518159 -290.437928) (xy 56.553652 -290.47202)
			(xy 56.583217 -290.511364) (xy 56.606088 -290.554941) (xy 56.621672 -290.601622) (xy 56.629567 -290.650199)
			(xy 56.630062 -290.674806) (xy 56.969164 -290.674806) (xy 56.973124 -290.625752) (xy 56.984901 -290.577968)
			(xy 57.004192 -290.532692) (xy 57.030495 -290.491096) (xy 57.06313 -290.454259) (xy 57.101251 -290.423134)
			(xy 57.143872 -290.398527) (xy 57.189888 -290.381075) (xy 57.238107 -290.371231) (xy 57.287282 -290.36925)
			(xy 57.336137 -290.375182) (xy 57.383408 -290.388874) (xy 57.42787 -290.409972) (xy 57.468373 -290.437928)
			(xy 57.503866 -290.47202) (xy 57.533431 -290.511364) (xy 57.556302 -290.554941) (xy 57.571886 -290.601622)
			(xy 57.579781 -290.650199) (xy 57.580276 -290.674806) (xy 57.919124 -290.674806) (xy 57.923084 -290.625752)
			(xy 57.934861 -290.577968) (xy 57.954152 -290.532692) (xy 57.980455 -290.491096) (xy 58.01309 -290.454259)
			(xy 58.051211 -290.423134) (xy 58.093832 -290.398527) (xy 58.139848 -290.381075) (xy 58.188067 -290.371231)
			(xy 58.237242 -290.36925) (xy 58.286097 -290.375182) (xy 58.333368 -290.388874) (xy 58.37783 -290.409972)
			(xy 58.418333 -290.437928) (xy 58.453826 -290.47202) (xy 58.483391 -290.511364) (xy 58.506262 -290.554941)
			(xy 58.521846 -290.601622) (xy 58.529741 -290.650199) (xy 58.530236 -290.674806) (xy 59.819044 -290.674806)
			(xy 59.823004 -290.625752) (xy 59.834781 -290.577968) (xy 59.854072 -290.532692) (xy 59.880375 -290.491096)
			(xy 59.91301 -290.454259) (xy 59.951131 -290.423134) (xy 59.993752 -290.398527) (xy 60.039768 -290.381075)
			(xy 60.087987 -290.371231) (xy 60.137162 -290.36925) (xy 60.186017 -290.375182) (xy 60.233288 -290.388874)
			(xy 60.27775 -290.409972) (xy 60.318253 -290.437928) (xy 60.353746 -290.47202) (xy 60.383311 -290.511364)
			(xy 60.406182 -290.554941) (xy 60.421766 -290.601622) (xy 60.429661 -290.650199) (xy 60.430156 -290.674806)
			(xy 60.769004 -290.674806) (xy 60.772964 -290.625752) (xy 60.784741 -290.577968) (xy 60.804032 -290.532692)
			(xy 60.830335 -290.491096) (xy 60.86297 -290.454259) (xy 60.901091 -290.423134) (xy 60.943712 -290.398527)
			(xy 60.989728 -290.381075) (xy 61.037947 -290.371231) (xy 61.087122 -290.36925) (xy 61.135977 -290.375182)
			(xy 61.183248 -290.388874) (xy 61.22771 -290.409972) (xy 61.268213 -290.437928) (xy 61.303706 -290.47202)
			(xy 61.333271 -290.511364) (xy 61.356142 -290.554941) (xy 61.371726 -290.601622) (xy 61.379621 -290.650199)
			(xy 61.380116 -290.674806) (xy 61.718964 -290.674806) (xy 61.722924 -290.625752) (xy 61.734701 -290.577968)
			(xy 61.753992 -290.532692) (xy 61.780295 -290.491096) (xy 61.81293 -290.454259) (xy 61.851051 -290.423134)
			(xy 61.893672 -290.398527) (xy 61.939688 -290.381075) (xy 61.987907 -290.371231) (xy 62.037082 -290.36925)
			(xy 62.085937 -290.375182) (xy 62.133208 -290.388874) (xy 62.17767 -290.409972) (xy 62.218173 -290.437928)
			(xy 62.253666 -290.47202) (xy 62.283231 -290.511364) (xy 62.306102 -290.554941) (xy 62.321686 -290.601622)
			(xy 62.329581 -290.650199) (xy 62.330076 -290.674806) (xy 62.669178 -290.674806) (xy 62.673138 -290.625752)
			(xy 62.684915 -290.577968) (xy 62.704206 -290.532692) (xy 62.730509 -290.491096) (xy 62.763144 -290.454259)
			(xy 62.801265 -290.423134) (xy 62.843886 -290.398527) (xy 62.889902 -290.381075) (xy 62.938121 -290.371231)
			(xy 62.987296 -290.36925) (xy 63.036151 -290.375182) (xy 63.083422 -290.388874) (xy 63.127884 -290.409972)
			(xy 63.168387 -290.437928) (xy 63.20388 -290.47202) (xy 63.233445 -290.511364) (xy 63.256316 -290.554941)
			(xy 63.2719 -290.601622) (xy 63.279795 -290.650199) (xy 63.28029 -290.674806) (xy 63.619138 -290.674806)
			(xy 63.623098 -290.625752) (xy 63.634875 -290.577968) (xy 63.654166 -290.532692) (xy 63.680469 -290.491096)
			(xy 63.713104 -290.454259) (xy 63.751225 -290.423134) (xy 63.793846 -290.398527) (xy 63.839862 -290.381075)
			(xy 63.888081 -290.371231) (xy 63.937256 -290.36925) (xy 63.986111 -290.375182) (xy 64.033382 -290.388874)
			(xy 64.077844 -290.409972) (xy 64.118347 -290.437928) (xy 64.15384 -290.47202) (xy 64.183405 -290.511364)
			(xy 64.206276 -290.554941) (xy 64.22186 -290.601622) (xy 64.229755 -290.650199) (xy 64.23025 -290.674806)
			(xy 64.569098 -290.674806) (xy 64.573058 -290.625752) (xy 64.584835 -290.577968) (xy 64.604126 -290.532692)
			(xy 64.630429 -290.491096) (xy 64.663064 -290.454259) (xy 64.701185 -290.423134) (xy 64.743806 -290.398527)
			(xy 64.789822 -290.381075) (xy 64.838041 -290.371231) (xy 64.887216 -290.36925) (xy 64.936071 -290.375182)
			(xy 64.983342 -290.388874) (xy 65.027804 -290.409972) (xy 65.068307 -290.437928) (xy 65.1038 -290.47202)
			(xy 65.133365 -290.511364) (xy 65.156236 -290.554941) (xy 65.17182 -290.601622) (xy 65.179715 -290.650199)
			(xy 65.18021 -290.674806) (xy 65.519058 -290.674806) (xy 65.523018 -290.625752) (xy 65.534795 -290.577968)
			(xy 65.554086 -290.532692) (xy 65.580389 -290.491096) (xy 65.613024 -290.454259) (xy 65.651145 -290.423134)
			(xy 65.693766 -290.398527) (xy 65.739782 -290.381075) (xy 65.788001 -290.371231) (xy 65.837176 -290.36925)
			(xy 65.886031 -290.375182) (xy 65.933302 -290.388874) (xy 65.977764 -290.409972) (xy 66.018267 -290.437928)
			(xy 66.05376 -290.47202) (xy 66.083325 -290.511364) (xy 66.106196 -290.554941) (xy 66.12178 -290.601622)
			(xy 66.129675 -290.650199) (xy 66.13017 -290.674806) (xy 66.469018 -290.674806) (xy 66.472978 -290.625752)
			(xy 66.484755 -290.577968) (xy 66.504046 -290.532692) (xy 66.530349 -290.491096) (xy 66.562984 -290.454259)
			(xy 66.601105 -290.423134) (xy 66.643726 -290.398527) (xy 66.689742 -290.381075) (xy 66.737961 -290.371231)
			(xy 66.787136 -290.36925) (xy 66.835991 -290.375182) (xy 66.883262 -290.388874) (xy 66.927724 -290.409972)
			(xy 66.968227 -290.437928) (xy 67.00372 -290.47202) (xy 67.033285 -290.511364) (xy 67.056156 -290.554941)
			(xy 67.07174 -290.601622) (xy 67.079635 -290.650199) (xy 67.08013 -290.674806) (xy 67.418978 -290.674806)
			(xy 67.422938 -290.625752) (xy 67.434715 -290.577968) (xy 67.454006 -290.532692) (xy 67.480309 -290.491096)
			(xy 67.512944 -290.454259) (xy 67.551065 -290.423134) (xy 67.593686 -290.398527) (xy 67.639702 -290.381075)
			(xy 67.687921 -290.371231) (xy 67.737096 -290.36925) (xy 67.785951 -290.375182) (xy 67.833222 -290.388874)
			(xy 67.877684 -290.409972) (xy 67.918187 -290.437928) (xy 67.95368 -290.47202) (xy 67.983245 -290.511364)
			(xy 68.006116 -290.554941) (xy 68.0217 -290.601622) (xy 68.029595 -290.650199) (xy 68.03009 -290.674806)
			(xy 68.368938 -290.674806) (xy 68.372898 -290.625752) (xy 68.384675 -290.577968) (xy 68.403966 -290.532692)
			(xy 68.430269 -290.491096) (xy 68.462904 -290.454259) (xy 68.501025 -290.423134) (xy 68.543646 -290.398527)
			(xy 68.589662 -290.381075) (xy 68.637881 -290.371231) (xy 68.687056 -290.36925) (xy 68.735911 -290.375182)
			(xy 68.783182 -290.388874) (xy 68.827644 -290.409972) (xy 68.868147 -290.437928) (xy 68.90364 -290.47202)
			(xy 68.933205 -290.511364) (xy 68.956076 -290.554941) (xy 68.97166 -290.601622) (xy 68.979555 -290.650199)
			(xy 68.98005 -290.674806) (xy 69.319152 -290.674806) (xy 69.323112 -290.625752) (xy 69.334889 -290.577968)
			(xy 69.35418 -290.532692) (xy 69.380483 -290.491096) (xy 69.413118 -290.454259) (xy 69.451239 -290.423134)
			(xy 69.49386 -290.398527) (xy 69.539876 -290.381075) (xy 69.588095 -290.371231) (xy 69.63727 -290.36925)
			(xy 69.686125 -290.375182) (xy 69.733396 -290.388874) (xy 69.777858 -290.409972) (xy 69.818361 -290.437928)
			(xy 69.853854 -290.47202) (xy 69.883419 -290.511364) (xy 69.90629 -290.554941) (xy 69.921874 -290.601622)
			(xy 69.929769 -290.650199) (xy 69.930264 -290.674806) (xy 70.269112 -290.674806) (xy 70.273072 -290.625752)
			(xy 70.284849 -290.577968) (xy 70.30414 -290.532692) (xy 70.330443 -290.491096) (xy 70.363078 -290.454259)
			(xy 70.401199 -290.423134) (xy 70.44382 -290.398527) (xy 70.489836 -290.381075) (xy 70.538055 -290.371231)
			(xy 70.58723 -290.36925) (xy 70.636085 -290.375182) (xy 70.683356 -290.388874) (xy 70.727818 -290.409972)
			(xy 70.768321 -290.437928) (xy 70.803814 -290.47202) (xy 70.833379 -290.511364) (xy 70.85625 -290.554941)
			(xy 70.871834 -290.601622) (xy 70.879729 -290.650199) (xy 70.880224 -290.674806) (xy 71.219072 -290.674806)
			(xy 71.223032 -290.625752) (xy 71.234809 -290.577968) (xy 71.2541 -290.532692) (xy 71.280403 -290.491096)
			(xy 71.313038 -290.454259) (xy 71.351159 -290.423134) (xy 71.39378 -290.398527) (xy 71.439796 -290.381075)
			(xy 71.488015 -290.371231) (xy 71.53719 -290.36925) (xy 71.586045 -290.375182) (xy 71.633316 -290.388874)
			(xy 71.677778 -290.409972) (xy 71.718281 -290.437928) (xy 71.753774 -290.47202) (xy 71.783339 -290.511364)
			(xy 71.80621 -290.554941) (xy 71.821794 -290.601622) (xy 71.829689 -290.650199) (xy 71.830184 -290.674806)
			(xy 72.169032 -290.674806) (xy 72.172992 -290.625752) (xy 72.184769 -290.577968) (xy 72.20406 -290.532692)
			(xy 72.230363 -290.491096) (xy 72.262998 -290.454259) (xy 72.301119 -290.423134) (xy 72.34374 -290.398527)
			(xy 72.389756 -290.381075) (xy 72.437975 -290.371231) (xy 72.48715 -290.36925) (xy 72.536005 -290.375182)
			(xy 72.583276 -290.388874) (xy 72.627738 -290.409972) (xy 72.668241 -290.437928) (xy 72.703734 -290.47202)
			(xy 72.733299 -290.511364) (xy 72.75617 -290.554941) (xy 72.771754 -290.601622) (xy 72.779649 -290.650199)
			(xy 72.780144 -290.674806) (xy 73.118992 -290.674806) (xy 73.122952 -290.625752) (xy 73.134729 -290.577968)
			(xy 73.15402 -290.532692) (xy 73.180323 -290.491096) (xy 73.212958 -290.454259) (xy 73.251079 -290.423134)
			(xy 73.2937 -290.398527) (xy 73.339716 -290.381075) (xy 73.387935 -290.371231) (xy 73.43711 -290.36925)
			(xy 73.485965 -290.375182) (xy 73.533236 -290.388874) (xy 73.577698 -290.409972) (xy 73.618201 -290.437928)
			(xy 73.653694 -290.47202) (xy 73.683259 -290.511364) (xy 73.70613 -290.554941) (xy 73.721714 -290.601622)
			(xy 73.729609 -290.650199) (xy 73.730104 -290.674806) (xy 74.068952 -290.674806) (xy 74.072912 -290.625752)
			(xy 74.084689 -290.577968) (xy 74.10398 -290.532692) (xy 74.130283 -290.491096) (xy 74.162918 -290.454259)
			(xy 74.201039 -290.423134) (xy 74.24366 -290.398527) (xy 74.289676 -290.381075) (xy 74.337895 -290.371231)
			(xy 74.38707 -290.36925) (xy 74.435925 -290.375182) (xy 74.483196 -290.388874) (xy 74.527658 -290.409972)
			(xy 74.568161 -290.437928) (xy 74.603654 -290.47202) (xy 74.633219 -290.511364) (xy 74.65609 -290.554941)
			(xy 74.671674 -290.601622) (xy 74.679569 -290.650199) (xy 74.680064 -290.674806) (xy 75.019166 -290.674806)
			(xy 75.023126 -290.625752) (xy 75.034903 -290.577968) (xy 75.054194 -290.532692) (xy 75.080497 -290.491096)
			(xy 75.113132 -290.454259) (xy 75.151253 -290.423134) (xy 75.193874 -290.398527) (xy 75.23989 -290.381075)
			(xy 75.288109 -290.371231) (xy 75.337284 -290.36925) (xy 75.386139 -290.375182) (xy 75.43341 -290.388874)
			(xy 75.477872 -290.409972) (xy 75.518375 -290.437928) (xy 75.553868 -290.47202) (xy 75.583433 -290.511364)
			(xy 75.606304 -290.554941) (xy 75.621888 -290.601622) (xy 75.629783 -290.650199) (xy 75.630278 -290.674806)
			(xy 75.969126 -290.674806) (xy 75.973086 -290.625752) (xy 75.984863 -290.577968) (xy 76.004154 -290.532692)
			(xy 76.030457 -290.491096) (xy 76.063092 -290.454259) (xy 76.101213 -290.423134) (xy 76.143834 -290.398527)
			(xy 76.18985 -290.381075) (xy 76.238069 -290.371231) (xy 76.287244 -290.36925) (xy 76.336099 -290.375182)
			(xy 76.38337 -290.388874) (xy 76.427832 -290.409972) (xy 76.468335 -290.437928) (xy 76.503828 -290.47202)
			(xy 76.533393 -290.511364) (xy 76.556264 -290.554941) (xy 76.571848 -290.601622) (xy 76.579743 -290.650199)
			(xy 76.580238 -290.674806) (xy 76.919086 -290.674806) (xy 76.923046 -290.625752) (xy 76.934823 -290.577968)
			(xy 76.954114 -290.532692) (xy 76.980417 -290.491096) (xy 77.013052 -290.454259) (xy 77.051173 -290.423134)
			(xy 77.093794 -290.398527) (xy 77.13981 -290.381075) (xy 77.188029 -290.371231) (xy 77.237204 -290.36925)
			(xy 77.286059 -290.375182) (xy 77.33333 -290.388874) (xy 77.377792 -290.409972) (xy 77.418295 -290.437928)
			(xy 77.453788 -290.47202) (xy 77.483353 -290.511364) (xy 77.506224 -290.554941) (xy 77.521808 -290.601622)
			(xy 77.529703 -290.650199) (xy 77.530198 -290.674806) (xy 77.869046 -290.674806) (xy 77.873006 -290.625752)
			(xy 77.884783 -290.577968) (xy 77.904074 -290.532692) (xy 77.930377 -290.491096) (xy 77.963012 -290.454259)
			(xy 78.001133 -290.423134) (xy 78.043754 -290.398527) (xy 78.08977 -290.381075) (xy 78.137989 -290.371231)
			(xy 78.187164 -290.36925) (xy 78.236019 -290.375182) (xy 78.28329 -290.388874) (xy 78.327752 -290.409972)
			(xy 78.368255 -290.437928) (xy 78.403748 -290.47202) (xy 78.433313 -290.511364) (xy 78.456184 -290.554941)
			(xy 78.471768 -290.601622) (xy 78.479663 -290.650199) (xy 78.480158 -290.674806) (xy 78.819006 -290.674806)
			(xy 78.822966 -290.625752) (xy 78.834743 -290.577968) (xy 78.854034 -290.532692) (xy 78.880337 -290.491096)
			(xy 78.912972 -290.454259) (xy 78.951093 -290.423134) (xy 78.993714 -290.398527) (xy 79.03973 -290.381075)
			(xy 79.087949 -290.371231) (xy 79.137124 -290.36925) (xy 79.185979 -290.375182) (xy 79.23325 -290.388874)
			(xy 79.277712 -290.409972) (xy 79.318215 -290.437928) (xy 79.353708 -290.47202) (xy 79.383273 -290.511364)
			(xy 79.406144 -290.554941) (xy 79.421728 -290.601622) (xy 79.429623 -290.650199) (xy 79.430118 -290.674806)
			(xy 79.768966 -290.674806) (xy 79.772926 -290.625752) (xy 79.784703 -290.577968) (xy 79.803994 -290.532692)
			(xy 79.830297 -290.491096) (xy 79.862932 -290.454259) (xy 79.901053 -290.423134) (xy 79.943674 -290.398527)
			(xy 79.98969 -290.381075) (xy 80.037909 -290.371231) (xy 80.087084 -290.36925) (xy 80.135939 -290.375182)
			(xy 80.18321 -290.388874) (xy 80.227672 -290.409972) (xy 80.268175 -290.437928) (xy 80.303668 -290.47202)
			(xy 80.333233 -290.511364) (xy 80.356104 -290.554941) (xy 80.371688 -290.601622) (xy 80.379583 -290.650199)
			(xy 80.380078 -290.674806) (xy 80.71918 -290.674806) (xy 80.72314 -290.625752) (xy 80.734917 -290.577968)
			(xy 80.754208 -290.532692) (xy 80.780511 -290.491096) (xy 80.813146 -290.454259) (xy 80.851267 -290.423134)
			(xy 80.893888 -290.398527) (xy 80.939904 -290.381075) (xy 80.988123 -290.371231) (xy 81.037298 -290.36925)
			(xy 81.086153 -290.375182) (xy 81.133424 -290.388874) (xy 81.177886 -290.409972) (xy 81.218389 -290.437928)
			(xy 81.253882 -290.47202) (xy 81.283447 -290.511364) (xy 81.306318 -290.554941) (xy 81.321902 -290.601622)
			(xy 81.329797 -290.650199) (xy 81.330292 -290.674806) (xy 81.66914 -290.674806) (xy 81.6731 -290.625752)
			(xy 81.684877 -290.577968) (xy 81.704168 -290.532692) (xy 81.730471 -290.491096) (xy 81.763106 -290.454259)
			(xy 81.801227 -290.423134) (xy 81.843848 -290.398527) (xy 81.889864 -290.381075) (xy 81.938083 -290.371231)
			(xy 81.987258 -290.36925) (xy 82.036113 -290.375182) (xy 82.083384 -290.388874) (xy 82.127846 -290.409972)
			(xy 82.168349 -290.437928) (xy 82.203842 -290.47202) (xy 82.233407 -290.511364) (xy 82.256278 -290.554941)
			(xy 82.271862 -290.601622) (xy 82.279757 -290.650199) (xy 82.280252 -290.674806) (xy 82.6191 -290.674806)
			(xy 82.62306 -290.625752) (xy 82.634837 -290.577968) (xy 82.654128 -290.532692) (xy 82.680431 -290.491096)
			(xy 82.713066 -290.454259) (xy 82.751187 -290.423134) (xy 82.793808 -290.398527) (xy 82.839824 -290.381075)
			(xy 82.888043 -290.371231) (xy 82.937218 -290.36925) (xy 82.986073 -290.375182) (xy 83.033344 -290.388874)
			(xy 83.077806 -290.409972) (xy 83.118309 -290.437928) (xy 83.126927 -290.446206) (xy 85.153752 -290.446206)
			(xy 85.157823 -290.390584) (xy 85.169949 -290.336147) (xy 85.189872 -290.284056) (xy 85.217168 -290.235421)
			(xy 85.251254 -290.191278) (xy 85.291403 -290.152569) (xy 85.336761 -290.120118) (xy 85.386361 -290.094617)
			(xy 85.439145 -290.07661) (xy 85.493988 -290.06648) (xy 85.549722 -290.064443) (xy 85.605159 -290.070543)
			(xy 85.659116 -290.084649) (xy 85.710445 -290.106461) (xy 85.758051 -290.135515) (xy 85.800919 -290.17119)
			(xy 85.838136 -290.212727) (xy 85.854304 -290.237164) (xy 89.164412 -290.237164) (xy 89.168483 -290.181542)
			(xy 89.180609 -290.127105) (xy 89.200532 -290.075014) (xy 89.227828 -290.026379) (xy 89.261914 -289.982236)
			(xy 89.302063 -289.943527) (xy 89.347421 -289.911076) (xy 89.397021 -289.885575) (xy 89.449805 -289.867568)
			(xy 89.504648 -289.857438) (xy 89.560382 -289.855401) (xy 89.615819 -289.861501) (xy 89.669776 -289.875607)
			(xy 89.721105 -289.897419) (xy 89.768711 -289.926473) (xy 89.811579 -289.962148) (xy 89.848796 -290.003685)
			(xy 89.879569 -290.050198) (xy 89.903241 -290.100695) (xy 89.919309 -290.154102) (xy 89.927429 -290.209278)
			(xy 89.927938 -290.237164) (xy 89.927429 -290.26505) (xy 89.919309 -290.320226) (xy 89.903241 -290.373633)
			(xy 89.879569 -290.42413) (xy 89.848796 -290.470643) (xy 89.811579 -290.51218) (xy 89.768711 -290.547855)
			(xy 89.721105 -290.576909) (xy 89.669776 -290.598721) (xy 89.615819 -290.612827) (xy 89.560382 -290.618927)
			(xy 89.504648 -290.61689) (xy 89.449805 -290.60676) (xy 89.397021 -290.588753) (xy 89.347421 -290.563252)
			(xy 89.302063 -290.530801) (xy 89.261914 -290.492092) (xy 89.227828 -290.447949) (xy 89.200532 -290.399314)
			(xy 89.180609 -290.347223) (xy 89.168483 -290.292786) (xy 89.164412 -290.237164) (xy 85.854304 -290.237164)
			(xy 85.868909 -290.25924) (xy 85.892581 -290.309737) (xy 85.908649 -290.363144) (xy 85.916769 -290.41832)
			(xy 85.917278 -290.446206) (xy 85.916769 -290.474092) (xy 85.908649 -290.529268) (xy 85.892581 -290.582675)
			(xy 85.868909 -290.633172) (xy 85.838136 -290.679685) (xy 85.800919 -290.721222) (xy 85.758051 -290.756897)
			(xy 85.710445 -290.785951) (xy 85.659116 -290.807763) (xy 85.605159 -290.821869) (xy 85.549722 -290.827969)
			(xy 85.493988 -290.825932) (xy 85.439145 -290.815802) (xy 85.386361 -290.797795) (xy 85.336761 -290.772294)
			(xy 85.291403 -290.739843) (xy 85.251254 -290.701134) (xy 85.217168 -290.656991) (xy 85.189872 -290.608356)
			(xy 85.169949 -290.556265) (xy 85.157823 -290.501828) (xy 85.153752 -290.446206) (xy 83.126927 -290.446206)
			(xy 83.153802 -290.47202) (xy 83.183367 -290.511364) (xy 83.206238 -290.554941) (xy 83.221822 -290.601622)
			(xy 83.229717 -290.650199) (xy 83.230212 -290.674806) (xy 83.229717 -290.699413) (xy 83.221822 -290.74799)
			(xy 83.206238 -290.794671) (xy 83.183367 -290.838248) (xy 83.153802 -290.877592) (xy 83.118309 -290.911684)
			(xy 83.077806 -290.93964) (xy 83.033344 -290.960738) (xy 82.986073 -290.97443) (xy 82.937218 -290.980362)
			(xy 82.888043 -290.978381) (xy 82.839824 -290.968537) (xy 82.793808 -290.951085) (xy 82.751187 -290.926478)
			(xy 82.713066 -290.895353) (xy 82.680431 -290.858516) (xy 82.654128 -290.81692) (xy 82.634837 -290.771644)
			(xy 82.62306 -290.72386) (xy 82.6191 -290.674806) (xy 82.280252 -290.674806) (xy 82.279757 -290.699413)
			(xy 82.271862 -290.74799) (xy 82.256278 -290.794671) (xy 82.233407 -290.838248) (xy 82.203842 -290.877592)
			(xy 82.168349 -290.911684) (xy 82.127846 -290.93964) (xy 82.083384 -290.960738) (xy 82.036113 -290.97443)
			(xy 81.987258 -290.980362) (xy 81.938083 -290.978381) (xy 81.889864 -290.968537) (xy 81.843848 -290.951085)
			(xy 81.801227 -290.926478) (xy 81.763106 -290.895353) (xy 81.730471 -290.858516) (xy 81.704168 -290.81692)
			(xy 81.684877 -290.771644) (xy 81.6731 -290.72386) (xy 81.66914 -290.674806) (xy 81.330292 -290.674806)
			(xy 81.329797 -290.699413) (xy 81.321902 -290.74799) (xy 81.306318 -290.794671) (xy 81.283447 -290.838248)
			(xy 81.253882 -290.877592) (xy 81.218389 -290.911684) (xy 81.177886 -290.93964) (xy 81.133424 -290.960738)
			(xy 81.086153 -290.97443) (xy 81.037298 -290.980362) (xy 80.988123 -290.978381) (xy 80.939904 -290.968537)
			(xy 80.893888 -290.951085) (xy 80.851267 -290.926478) (xy 80.813146 -290.895353) (xy 80.780511 -290.858516)
			(xy 80.754208 -290.81692) (xy 80.734917 -290.771644) (xy 80.72314 -290.72386) (xy 80.71918 -290.674806)
			(xy 80.380078 -290.674806) (xy 80.379583 -290.699413) (xy 80.371688 -290.74799) (xy 80.356104 -290.794671)
			(xy 80.333233 -290.838248) (xy 80.303668 -290.877592) (xy 80.268175 -290.911684) (xy 80.227672 -290.93964)
			(xy 80.18321 -290.960738) (xy 80.135939 -290.97443) (xy 80.087084 -290.980362) (xy 80.037909 -290.978381)
			(xy 79.98969 -290.968537) (xy 79.943674 -290.951085) (xy 79.901053 -290.926478) (xy 79.862932 -290.895353)
			(xy 79.830297 -290.858516) (xy 79.803994 -290.81692) (xy 79.784703 -290.771644) (xy 79.772926 -290.72386)
			(xy 79.768966 -290.674806) (xy 79.430118 -290.674806) (xy 79.429623 -290.699413) (xy 79.421728 -290.74799)
			(xy 79.406144 -290.794671) (xy 79.383273 -290.838248) (xy 79.353708 -290.877592) (xy 79.318215 -290.911684)
			(xy 79.277712 -290.93964) (xy 79.23325 -290.960738) (xy 79.185979 -290.97443) (xy 79.137124 -290.980362)
			(xy 79.087949 -290.978381) (xy 79.03973 -290.968537) (xy 78.993714 -290.951085) (xy 78.951093 -290.926478)
			(xy 78.912972 -290.895353) (xy 78.880337 -290.858516) (xy 78.854034 -290.81692) (xy 78.834743 -290.771644)
			(xy 78.822966 -290.72386) (xy 78.819006 -290.674806) (xy 78.480158 -290.674806) (xy 78.479663 -290.699413)
			(xy 78.471768 -290.74799) (xy 78.456184 -290.794671) (xy 78.433313 -290.838248) (xy 78.403748 -290.877592)
			(xy 78.368255 -290.911684) (xy 78.327752 -290.93964) (xy 78.28329 -290.960738) (xy 78.236019 -290.97443)
			(xy 78.187164 -290.980362) (xy 78.137989 -290.978381) (xy 78.08977 -290.968537) (xy 78.043754 -290.951085)
			(xy 78.001133 -290.926478) (xy 77.963012 -290.895353) (xy 77.930377 -290.858516) (xy 77.904074 -290.81692)
			(xy 77.884783 -290.771644) (xy 77.873006 -290.72386) (xy 77.869046 -290.674806) (xy 77.530198 -290.674806)
			(xy 77.529703 -290.699413) (xy 77.521808 -290.74799) (xy 77.506224 -290.794671) (xy 77.483353 -290.838248)
			(xy 77.453788 -290.877592) (xy 77.418295 -290.911684) (xy 77.377792 -290.93964) (xy 77.33333 -290.960738)
			(xy 77.286059 -290.97443) (xy 77.237204 -290.980362) (xy 77.188029 -290.978381) (xy 77.13981 -290.968537)
			(xy 77.093794 -290.951085) (xy 77.051173 -290.926478) (xy 77.013052 -290.895353) (xy 76.980417 -290.858516)
			(xy 76.954114 -290.81692) (xy 76.934823 -290.771644) (xy 76.923046 -290.72386) (xy 76.919086 -290.674806)
			(xy 76.580238 -290.674806) (xy 76.579743 -290.699413) (xy 76.571848 -290.74799) (xy 76.556264 -290.794671)
			(xy 76.533393 -290.838248) (xy 76.503828 -290.877592) (xy 76.468335 -290.911684) (xy 76.427832 -290.93964)
			(xy 76.38337 -290.960738) (xy 76.336099 -290.97443) (xy 76.287244 -290.980362) (xy 76.238069 -290.978381)
			(xy 76.18985 -290.968537) (xy 76.143834 -290.951085) (xy 76.101213 -290.926478) (xy 76.063092 -290.895353)
			(xy 76.030457 -290.858516) (xy 76.004154 -290.81692) (xy 75.984863 -290.771644) (xy 75.973086 -290.72386)
			(xy 75.969126 -290.674806) (xy 75.630278 -290.674806) (xy 75.629783 -290.699413) (xy 75.621888 -290.74799)
			(xy 75.606304 -290.794671) (xy 75.583433 -290.838248) (xy 75.553868 -290.877592) (xy 75.518375 -290.911684)
			(xy 75.477872 -290.93964) (xy 75.43341 -290.960738) (xy 75.386139 -290.97443) (xy 75.337284 -290.980362)
			(xy 75.288109 -290.978381) (xy 75.23989 -290.968537) (xy 75.193874 -290.951085) (xy 75.151253 -290.926478)
			(xy 75.113132 -290.895353) (xy 75.080497 -290.858516) (xy 75.054194 -290.81692) (xy 75.034903 -290.771644)
			(xy 75.023126 -290.72386) (xy 75.019166 -290.674806) (xy 74.680064 -290.674806) (xy 74.679569 -290.699413)
			(xy 74.671674 -290.74799) (xy 74.65609 -290.794671) (xy 74.633219 -290.838248) (xy 74.603654 -290.877592)
			(xy 74.568161 -290.911684) (xy 74.527658 -290.93964) (xy 74.483196 -290.960738) (xy 74.435925 -290.97443)
			(xy 74.38707 -290.980362) (xy 74.337895 -290.978381) (xy 74.289676 -290.968537) (xy 74.24366 -290.951085)
			(xy 74.201039 -290.926478) (xy 74.162918 -290.895353) (xy 74.130283 -290.858516) (xy 74.10398 -290.81692)
			(xy 74.084689 -290.771644) (xy 74.072912 -290.72386) (xy 74.068952 -290.674806) (xy 73.730104 -290.674806)
			(xy 73.729609 -290.699413) (xy 73.721714 -290.74799) (xy 73.70613 -290.794671) (xy 73.683259 -290.838248)
			(xy 73.653694 -290.877592) (xy 73.618201 -290.911684) (xy 73.577698 -290.93964) (xy 73.533236 -290.960738)
			(xy 73.485965 -290.97443) (xy 73.43711 -290.980362) (xy 73.387935 -290.978381) (xy 73.339716 -290.968537)
			(xy 73.2937 -290.951085) (xy 73.251079 -290.926478) (xy 73.212958 -290.895353) (xy 73.180323 -290.858516)
			(xy 73.15402 -290.81692) (xy 73.134729 -290.771644) (xy 73.122952 -290.72386) (xy 73.118992 -290.674806)
			(xy 72.780144 -290.674806) (xy 72.779649 -290.699413) (xy 72.771754 -290.74799) (xy 72.75617 -290.794671)
			(xy 72.733299 -290.838248) (xy 72.703734 -290.877592) (xy 72.668241 -290.911684) (xy 72.627738 -290.93964)
			(xy 72.583276 -290.960738) (xy 72.536005 -290.97443) (xy 72.48715 -290.980362) (xy 72.437975 -290.978381)
			(xy 72.389756 -290.968537) (xy 72.34374 -290.951085) (xy 72.301119 -290.926478) (xy 72.262998 -290.895353)
			(xy 72.230363 -290.858516) (xy 72.20406 -290.81692) (xy 72.184769 -290.771644) (xy 72.172992 -290.72386)
			(xy 72.169032 -290.674806) (xy 71.830184 -290.674806) (xy 71.829689 -290.699413) (xy 71.821794 -290.74799)
			(xy 71.80621 -290.794671) (xy 71.783339 -290.838248) (xy 71.753774 -290.877592) (xy 71.718281 -290.911684)
			(xy 71.677778 -290.93964) (xy 71.633316 -290.960738) (xy 71.586045 -290.97443) (xy 71.53719 -290.980362)
			(xy 71.488015 -290.978381) (xy 71.439796 -290.968537) (xy 71.39378 -290.951085) (xy 71.351159 -290.926478)
			(xy 71.313038 -290.895353) (xy 71.280403 -290.858516) (xy 71.2541 -290.81692) (xy 71.234809 -290.771644)
			(xy 71.223032 -290.72386) (xy 71.219072 -290.674806) (xy 70.880224 -290.674806) (xy 70.879729 -290.699413)
			(xy 70.871834 -290.74799) (xy 70.85625 -290.794671) (xy 70.833379 -290.838248) (xy 70.803814 -290.877592)
			(xy 70.768321 -290.911684) (xy 70.727818 -290.93964) (xy 70.683356 -290.960738) (xy 70.636085 -290.97443)
			(xy 70.58723 -290.980362) (xy 70.538055 -290.978381) (xy 70.489836 -290.968537) (xy 70.44382 -290.951085)
			(xy 70.401199 -290.926478) (xy 70.363078 -290.895353) (xy 70.330443 -290.858516) (xy 70.30414 -290.81692)
			(xy 70.284849 -290.771644) (xy 70.273072 -290.72386) (xy 70.269112 -290.674806) (xy 69.930264 -290.674806)
			(xy 69.929769 -290.699413) (xy 69.921874 -290.74799) (xy 69.90629 -290.794671) (xy 69.883419 -290.838248)
			(xy 69.853854 -290.877592) (xy 69.818361 -290.911684) (xy 69.777858 -290.93964) (xy 69.733396 -290.960738)
			(xy 69.686125 -290.97443) (xy 69.63727 -290.980362) (xy 69.588095 -290.978381) (xy 69.539876 -290.968537)
			(xy 69.49386 -290.951085) (xy 69.451239 -290.926478) (xy 69.413118 -290.895353) (xy 69.380483 -290.858516)
			(xy 69.35418 -290.81692) (xy 69.334889 -290.771644) (xy 69.323112 -290.72386) (xy 69.319152 -290.674806)
			(xy 68.98005 -290.674806) (xy 68.979555 -290.699413) (xy 68.97166 -290.74799) (xy 68.956076 -290.794671)
			(xy 68.933205 -290.838248) (xy 68.90364 -290.877592) (xy 68.868147 -290.911684) (xy 68.827644 -290.93964)
			(xy 68.783182 -290.960738) (xy 68.735911 -290.97443) (xy 68.687056 -290.980362) (xy 68.637881 -290.978381)
			(xy 68.589662 -290.968537) (xy 68.543646 -290.951085) (xy 68.501025 -290.926478) (xy 68.462904 -290.895353)
			(xy 68.430269 -290.858516) (xy 68.403966 -290.81692) (xy 68.384675 -290.771644) (xy 68.372898 -290.72386)
			(xy 68.368938 -290.674806) (xy 68.03009 -290.674806) (xy 68.029595 -290.699413) (xy 68.0217 -290.74799)
			(xy 68.006116 -290.794671) (xy 67.983245 -290.838248) (xy 67.95368 -290.877592) (xy 67.918187 -290.911684)
			(xy 67.877684 -290.93964) (xy 67.833222 -290.960738) (xy 67.785951 -290.97443) (xy 67.737096 -290.980362)
			(xy 67.687921 -290.978381) (xy 67.639702 -290.968537) (xy 67.593686 -290.951085) (xy 67.551065 -290.926478)
			(xy 67.512944 -290.895353) (xy 67.480309 -290.858516) (xy 67.454006 -290.81692) (xy 67.434715 -290.771644)
			(xy 67.422938 -290.72386) (xy 67.418978 -290.674806) (xy 67.08013 -290.674806) (xy 67.079635 -290.699413)
			(xy 67.07174 -290.74799) (xy 67.056156 -290.794671) (xy 67.033285 -290.838248) (xy 67.00372 -290.877592)
			(xy 66.968227 -290.911684) (xy 66.927724 -290.93964) (xy 66.883262 -290.960738) (xy 66.835991 -290.97443)
			(xy 66.787136 -290.980362) (xy 66.737961 -290.978381) (xy 66.689742 -290.968537) (xy 66.643726 -290.951085)
			(xy 66.601105 -290.926478) (xy 66.562984 -290.895353) (xy 66.530349 -290.858516) (xy 66.504046 -290.81692)
			(xy 66.484755 -290.771644) (xy 66.472978 -290.72386) (xy 66.469018 -290.674806) (xy 66.13017 -290.674806)
			(xy 66.129675 -290.699413) (xy 66.12178 -290.74799) (xy 66.106196 -290.794671) (xy 66.083325 -290.838248)
			(xy 66.05376 -290.877592) (xy 66.018267 -290.911684) (xy 65.977764 -290.93964) (xy 65.933302 -290.960738)
			(xy 65.886031 -290.97443) (xy 65.837176 -290.980362) (xy 65.788001 -290.978381) (xy 65.739782 -290.968537)
			(xy 65.693766 -290.951085) (xy 65.651145 -290.926478) (xy 65.613024 -290.895353) (xy 65.580389 -290.858516)
			(xy 65.554086 -290.81692) (xy 65.534795 -290.771644) (xy 65.523018 -290.72386) (xy 65.519058 -290.674806)
			(xy 65.18021 -290.674806) (xy 65.179715 -290.699413) (xy 65.17182 -290.74799) (xy 65.156236 -290.794671)
			(xy 65.133365 -290.838248) (xy 65.1038 -290.877592) (xy 65.068307 -290.911684) (xy 65.027804 -290.93964)
			(xy 64.983342 -290.960738) (xy 64.936071 -290.97443) (xy 64.887216 -290.980362) (xy 64.838041 -290.978381)
			(xy 64.789822 -290.968537) (xy 64.743806 -290.951085) (xy 64.701185 -290.926478) (xy 64.663064 -290.895353)
			(xy 64.630429 -290.858516) (xy 64.604126 -290.81692) (xy 64.584835 -290.771644) (xy 64.573058 -290.72386)
			(xy 64.569098 -290.674806) (xy 64.23025 -290.674806) (xy 64.229755 -290.699413) (xy 64.22186 -290.74799)
			(xy 64.206276 -290.794671) (xy 64.183405 -290.838248) (xy 64.15384 -290.877592) (xy 64.118347 -290.911684)
			(xy 64.077844 -290.93964) (xy 64.033382 -290.960738) (xy 63.986111 -290.97443) (xy 63.937256 -290.980362)
			(xy 63.888081 -290.978381) (xy 63.839862 -290.968537) (xy 63.793846 -290.951085) (xy 63.751225 -290.926478)
			(xy 63.713104 -290.895353) (xy 63.680469 -290.858516) (xy 63.654166 -290.81692) (xy 63.634875 -290.771644)
			(xy 63.623098 -290.72386) (xy 63.619138 -290.674806) (xy 63.28029 -290.674806) (xy 63.279795 -290.699413)
			(xy 63.2719 -290.74799) (xy 63.256316 -290.794671) (xy 63.233445 -290.838248) (xy 63.20388 -290.877592)
			(xy 63.168387 -290.911684) (xy 63.127884 -290.93964) (xy 63.083422 -290.960738) (xy 63.036151 -290.97443)
			(xy 62.987296 -290.980362) (xy 62.938121 -290.978381) (xy 62.889902 -290.968537) (xy 62.843886 -290.951085)
			(xy 62.801265 -290.926478) (xy 62.763144 -290.895353) (xy 62.730509 -290.858516) (xy 62.704206 -290.81692)
			(xy 62.684915 -290.771644) (xy 62.673138 -290.72386) (xy 62.669178 -290.674806) (xy 62.330076 -290.674806)
			(xy 62.329581 -290.699413) (xy 62.321686 -290.74799) (xy 62.306102 -290.794671) (xy 62.283231 -290.838248)
			(xy 62.253666 -290.877592) (xy 62.218173 -290.911684) (xy 62.17767 -290.93964) (xy 62.133208 -290.960738)
			(xy 62.085937 -290.97443) (xy 62.037082 -290.980362) (xy 61.987907 -290.978381) (xy 61.939688 -290.968537)
			(xy 61.893672 -290.951085) (xy 61.851051 -290.926478) (xy 61.81293 -290.895353) (xy 61.780295 -290.858516)
			(xy 61.753992 -290.81692) (xy 61.734701 -290.771644) (xy 61.722924 -290.72386) (xy 61.718964 -290.674806)
			(xy 61.380116 -290.674806) (xy 61.379621 -290.699413) (xy 61.371726 -290.74799) (xy 61.356142 -290.794671)
			(xy 61.333271 -290.838248) (xy 61.303706 -290.877592) (xy 61.268213 -290.911684) (xy 61.22771 -290.93964)
			(xy 61.183248 -290.960738) (xy 61.135977 -290.97443) (xy 61.087122 -290.980362) (xy 61.037947 -290.978381)
			(xy 60.989728 -290.968537) (xy 60.943712 -290.951085) (xy 60.901091 -290.926478) (xy 60.86297 -290.895353)
			(xy 60.830335 -290.858516) (xy 60.804032 -290.81692) (xy 60.784741 -290.771644) (xy 60.772964 -290.72386)
			(xy 60.769004 -290.674806) (xy 60.430156 -290.674806) (xy 60.429661 -290.699413) (xy 60.421766 -290.74799)
			(xy 60.406182 -290.794671) (xy 60.383311 -290.838248) (xy 60.353746 -290.877592) (xy 60.318253 -290.911684)
			(xy 60.27775 -290.93964) (xy 60.233288 -290.960738) (xy 60.186017 -290.97443) (xy 60.137162 -290.980362)
			(xy 60.087987 -290.978381) (xy 60.039768 -290.968537) (xy 59.993752 -290.951085) (xy 59.951131 -290.926478)
			(xy 59.91301 -290.895353) (xy 59.880375 -290.858516) (xy 59.854072 -290.81692) (xy 59.834781 -290.771644)
			(xy 59.823004 -290.72386) (xy 59.819044 -290.674806) (xy 58.530236 -290.674806) (xy 58.529741 -290.699413)
			(xy 58.521846 -290.74799) (xy 58.506262 -290.794671) (xy 58.483391 -290.838248) (xy 58.453826 -290.877592)
			(xy 58.418333 -290.911684) (xy 58.37783 -290.93964) (xy 58.333368 -290.960738) (xy 58.286097 -290.97443)
			(xy 58.237242 -290.980362) (xy 58.188067 -290.978381) (xy 58.139848 -290.968537) (xy 58.093832 -290.951085)
			(xy 58.051211 -290.926478) (xy 58.01309 -290.895353) (xy 57.980455 -290.858516) (xy 57.954152 -290.81692)
			(xy 57.934861 -290.771644) (xy 57.923084 -290.72386) (xy 57.919124 -290.674806) (xy 57.580276 -290.674806)
			(xy 57.579781 -290.699413) (xy 57.571886 -290.74799) (xy 57.556302 -290.794671) (xy 57.533431 -290.838248)
			(xy 57.503866 -290.877592) (xy 57.468373 -290.911684) (xy 57.42787 -290.93964) (xy 57.383408 -290.960738)
			(xy 57.336137 -290.97443) (xy 57.287282 -290.980362) (xy 57.238107 -290.978381) (xy 57.189888 -290.968537)
			(xy 57.143872 -290.951085) (xy 57.101251 -290.926478) (xy 57.06313 -290.895353) (xy 57.030495 -290.858516)
			(xy 57.004192 -290.81692) (xy 56.984901 -290.771644) (xy 56.973124 -290.72386) (xy 56.969164 -290.674806)
			(xy 56.630062 -290.674806) (xy 56.629567 -290.699413) (xy 56.621672 -290.74799) (xy 56.606088 -290.794671)
			(xy 56.583217 -290.838248) (xy 56.553652 -290.877592) (xy 56.518159 -290.911684) (xy 56.477656 -290.93964)
			(xy 56.433194 -290.960738) (xy 56.385923 -290.97443) (xy 56.337068 -290.980362) (xy 56.287893 -290.978381)
			(xy 56.239674 -290.968537) (xy 56.193658 -290.951085) (xy 56.151037 -290.926478) (xy 56.112916 -290.895353)
			(xy 56.080281 -290.858516) (xy 56.053978 -290.81692) (xy 56.034687 -290.771644) (xy 56.02291 -290.72386)
			(xy 56.01895 -290.674806) (xy 55.680102 -290.674806) (xy 55.679607 -290.699413) (xy 55.671712 -290.74799)
			(xy 55.656128 -290.794671) (xy 55.633257 -290.838248) (xy 55.603692 -290.877592) (xy 55.568199 -290.911684)
			(xy 55.527696 -290.93964) (xy 55.483234 -290.960738) (xy 55.435963 -290.97443) (xy 55.387108 -290.980362)
			(xy 55.337933 -290.978381) (xy 55.289714 -290.968537) (xy 55.243698 -290.951085) (xy 55.201077 -290.926478)
			(xy 55.162956 -290.895353) (xy 55.130321 -290.858516) (xy 55.104018 -290.81692) (xy 55.084727 -290.771644)
			(xy 55.07295 -290.72386) (xy 55.06899 -290.674806) (xy 54.730142 -290.674806) (xy 54.729647 -290.699413)
			(xy 54.721752 -290.74799) (xy 54.706168 -290.794671) (xy 54.683297 -290.838248) (xy 54.653732 -290.877592)
			(xy 54.618239 -290.911684) (xy 54.577736 -290.93964) (xy 54.533274 -290.960738) (xy 54.486003 -290.97443)
			(xy 54.437148 -290.980362) (xy 54.387973 -290.978381) (xy 54.339754 -290.968537) (xy 54.293738 -290.951085)
			(xy 54.251117 -290.926478) (xy 54.212996 -290.895353) (xy 54.180361 -290.858516) (xy 54.154058 -290.81692)
			(xy 54.134767 -290.771644) (xy 54.12299 -290.72386) (xy 54.11903 -290.674806) (xy 53.780182 -290.674806)
			(xy 53.779687 -290.699413) (xy 53.771792 -290.74799) (xy 53.756208 -290.794671) (xy 53.733337 -290.838248)
			(xy 53.703772 -290.877592) (xy 53.668279 -290.911684) (xy 53.627776 -290.93964) (xy 53.583314 -290.960738)
			(xy 53.536043 -290.97443) (xy 53.487188 -290.980362) (xy 53.438013 -290.978381) (xy 53.389794 -290.968537)
			(xy 53.343778 -290.951085) (xy 53.301157 -290.926478) (xy 53.263036 -290.895353) (xy 53.230401 -290.858516)
			(xy 53.204098 -290.81692) (xy 53.184807 -290.771644) (xy 53.17303 -290.72386) (xy 53.16907 -290.674806)
			(xy 52.830222 -290.674806) (xy 52.829727 -290.699413) (xy 52.821832 -290.74799) (xy 52.806248 -290.794671)
			(xy 52.783377 -290.838248) (xy 52.753812 -290.877592) (xy 52.718319 -290.911684) (xy 52.677816 -290.93964)
			(xy 52.633354 -290.960738) (xy 52.586083 -290.97443) (xy 52.537228 -290.980362) (xy 52.488053 -290.978381)
			(xy 52.439834 -290.968537) (xy 52.393818 -290.951085) (xy 52.351197 -290.926478) (xy 52.313076 -290.895353)
			(xy 52.280441 -290.858516) (xy 52.254138 -290.81692) (xy 52.234847 -290.771644) (xy 52.22307 -290.72386)
			(xy 52.21911 -290.674806) (xy 51.880262 -290.674806) (xy 51.879767 -290.699413) (xy 51.871872 -290.74799)
			(xy 51.856288 -290.794671) (xy 51.833417 -290.838248) (xy 51.803852 -290.877592) (xy 51.768359 -290.911684)
			(xy 51.727856 -290.93964) (xy 51.683394 -290.960738) (xy 51.636123 -290.97443) (xy 51.587268 -290.980362)
			(xy 51.538093 -290.978381) (xy 51.489874 -290.968537) (xy 51.443858 -290.951085) (xy 51.401237 -290.926478)
			(xy 51.363116 -290.895353) (xy 51.330481 -290.858516) (xy 51.304178 -290.81692) (xy 51.284887 -290.771644)
			(xy 51.27311 -290.72386) (xy 51.26915 -290.674806) (xy 50.930302 -290.674806) (xy 50.929807 -290.699413)
			(xy 50.921912 -290.74799) (xy 50.906328 -290.794671) (xy 50.883457 -290.838248) (xy 50.853892 -290.877592)
			(xy 50.818399 -290.911684) (xy 50.777896 -290.93964) (xy 50.733434 -290.960738) (xy 50.686163 -290.97443)
			(xy 50.637308 -290.980362) (xy 50.588133 -290.978381) (xy 50.539914 -290.968537) (xy 50.493898 -290.951085)
			(xy 50.451277 -290.926478) (xy 50.413156 -290.895353) (xy 50.380521 -290.858516) (xy 50.354218 -290.81692)
			(xy 50.334927 -290.771644) (xy 50.32315 -290.72386) (xy 50.31919 -290.674806) (xy 49.980088 -290.674806)
			(xy 49.979593 -290.699413) (xy 49.971698 -290.74799) (xy 49.956114 -290.794671) (xy 49.933243 -290.838248)
			(xy 49.903678 -290.877592) (xy 49.868185 -290.911684) (xy 49.827682 -290.93964) (xy 49.78322 -290.960738)
			(xy 49.735949 -290.97443) (xy 49.687094 -290.980362) (xy 49.637919 -290.978381) (xy 49.5897 -290.968537)
			(xy 49.543684 -290.951085) (xy 49.501063 -290.926478) (xy 49.462942 -290.895353) (xy 49.430307 -290.858516)
			(xy 49.404004 -290.81692) (xy 49.384713 -290.771644) (xy 49.372936 -290.72386) (xy 49.368976 -290.674806)
			(xy 49.181004 -290.674806) (xy 49.181004 -291.624766) (xy 50.31919 -291.624766) (xy 50.32315 -291.575712)
			(xy 50.334927 -291.527928) (xy 50.354218 -291.482652) (xy 50.380521 -291.441056) (xy 50.413156 -291.404219)
			(xy 50.451277 -291.373094) (xy 50.493898 -291.348487) (xy 50.539914 -291.331035) (xy 50.588133 -291.321191)
			(xy 50.637308 -291.31921) (xy 50.686163 -291.325142) (xy 50.733434 -291.338834) (xy 50.777896 -291.359932)
			(xy 50.818399 -291.387888) (xy 50.853892 -291.42198) (xy 50.883457 -291.461324) (xy 50.906328 -291.504901)
			(xy 50.921912 -291.551582) (xy 50.929807 -291.600159) (xy 50.930302 -291.624766) (xy 51.26915 -291.624766)
			(xy 51.27311 -291.575712) (xy 51.284887 -291.527928) (xy 51.304178 -291.482652) (xy 51.330481 -291.441056)
			(xy 51.363116 -291.404219) (xy 51.401237 -291.373094) (xy 51.443858 -291.348487) (xy 51.489874 -291.331035)
			(xy 51.538093 -291.321191) (xy 51.587268 -291.31921) (xy 51.636123 -291.325142) (xy 51.683394 -291.338834)
			(xy 51.727856 -291.359932) (xy 51.768359 -291.387888) (xy 51.803852 -291.42198) (xy 51.833417 -291.461324)
			(xy 51.856288 -291.504901) (xy 51.871872 -291.551582) (xy 51.879767 -291.600159) (xy 51.880262 -291.624766)
			(xy 52.21911 -291.624766) (xy 52.22307 -291.575712) (xy 52.234847 -291.527928) (xy 52.254138 -291.482652)
			(xy 52.280441 -291.441056) (xy 52.313076 -291.404219) (xy 52.351197 -291.373094) (xy 52.393818 -291.348487)
			(xy 52.439834 -291.331035) (xy 52.488053 -291.321191) (xy 52.537228 -291.31921) (xy 52.586083 -291.325142)
			(xy 52.633354 -291.338834) (xy 52.677816 -291.359932) (xy 52.718319 -291.387888) (xy 52.753812 -291.42198)
			(xy 52.783377 -291.461324) (xy 52.806248 -291.504901) (xy 52.821832 -291.551582) (xy 52.829727 -291.600159)
			(xy 52.830222 -291.624766) (xy 53.16907 -291.624766) (xy 53.17303 -291.575712) (xy 53.184807 -291.527928)
			(xy 53.204098 -291.482652) (xy 53.230401 -291.441056) (xy 53.263036 -291.404219) (xy 53.301157 -291.373094)
			(xy 53.343778 -291.348487) (xy 53.389794 -291.331035) (xy 53.438013 -291.321191) (xy 53.487188 -291.31921)
			(xy 53.536043 -291.325142) (xy 53.583314 -291.338834) (xy 53.627776 -291.359932) (xy 53.668279 -291.387888)
			(xy 53.703772 -291.42198) (xy 53.733337 -291.461324) (xy 53.756208 -291.504901) (xy 53.771792 -291.551582)
			(xy 53.779687 -291.600159) (xy 53.780182 -291.624766) (xy 54.11903 -291.624766) (xy 54.12299 -291.575712)
			(xy 54.134767 -291.527928) (xy 54.154058 -291.482652) (xy 54.180361 -291.441056) (xy 54.212996 -291.404219)
			(xy 54.251117 -291.373094) (xy 54.293738 -291.348487) (xy 54.339754 -291.331035) (xy 54.387973 -291.321191)
			(xy 54.437148 -291.31921) (xy 54.486003 -291.325142) (xy 54.533274 -291.338834) (xy 54.577736 -291.359932)
			(xy 54.618239 -291.387888) (xy 54.653732 -291.42198) (xy 54.683297 -291.461324) (xy 54.706168 -291.504901)
			(xy 54.721752 -291.551582) (xy 54.729647 -291.600159) (xy 54.730142 -291.624766) (xy 55.06899 -291.624766)
			(xy 55.07295 -291.575712) (xy 55.084727 -291.527928) (xy 55.104018 -291.482652) (xy 55.130321 -291.441056)
			(xy 55.162956 -291.404219) (xy 55.201077 -291.373094) (xy 55.243698 -291.348487) (xy 55.289714 -291.331035)
			(xy 55.337933 -291.321191) (xy 55.387108 -291.31921) (xy 55.435963 -291.325142) (xy 55.483234 -291.338834)
			(xy 55.527696 -291.359932) (xy 55.568199 -291.387888) (xy 55.603692 -291.42198) (xy 55.633257 -291.461324)
			(xy 55.656128 -291.504901) (xy 55.671712 -291.551582) (xy 55.679607 -291.600159) (xy 55.680102 -291.624766)
			(xy 56.01895 -291.624766) (xy 56.02291 -291.575712) (xy 56.034687 -291.527928) (xy 56.053978 -291.482652)
			(xy 56.080281 -291.441056) (xy 56.112916 -291.404219) (xy 56.151037 -291.373094) (xy 56.193658 -291.348487)
			(xy 56.239674 -291.331035) (xy 56.287893 -291.321191) (xy 56.337068 -291.31921) (xy 56.385923 -291.325142)
			(xy 56.433194 -291.338834) (xy 56.477656 -291.359932) (xy 56.518159 -291.387888) (xy 56.553652 -291.42198)
			(xy 56.583217 -291.461324) (xy 56.606088 -291.504901) (xy 56.621672 -291.551582) (xy 56.629567 -291.600159)
			(xy 56.630062 -291.624766) (xy 56.969164 -291.624766) (xy 56.973124 -291.575712) (xy 56.984901 -291.527928)
			(xy 57.004192 -291.482652) (xy 57.030495 -291.441056) (xy 57.06313 -291.404219) (xy 57.101251 -291.373094)
			(xy 57.143872 -291.348487) (xy 57.189888 -291.331035) (xy 57.238107 -291.321191) (xy 57.287282 -291.31921)
			(xy 57.336137 -291.325142) (xy 57.383408 -291.338834) (xy 57.42787 -291.359932) (xy 57.468373 -291.387888)
			(xy 57.503866 -291.42198) (xy 57.533431 -291.461324) (xy 57.556302 -291.504901) (xy 57.571886 -291.551582)
			(xy 57.579781 -291.600159) (xy 57.580276 -291.624766) (xy 57.919124 -291.624766) (xy 57.923084 -291.575712)
			(xy 57.934861 -291.527928) (xy 57.954152 -291.482652) (xy 57.980455 -291.441056) (xy 58.01309 -291.404219)
			(xy 58.051211 -291.373094) (xy 58.093832 -291.348487) (xy 58.139848 -291.331035) (xy 58.188067 -291.321191)
			(xy 58.237242 -291.31921) (xy 58.286097 -291.325142) (xy 58.333368 -291.338834) (xy 58.37783 -291.359932)
			(xy 58.418333 -291.387888) (xy 58.453826 -291.42198) (xy 58.483391 -291.461324) (xy 58.506262 -291.504901)
			(xy 58.521846 -291.551582) (xy 58.529741 -291.600159) (xy 58.530236 -291.624766) (xy 59.819044 -291.624766)
			(xy 59.823004 -291.575712) (xy 59.834781 -291.527928) (xy 59.854072 -291.482652) (xy 59.880375 -291.441056)
			(xy 59.91301 -291.404219) (xy 59.951131 -291.373094) (xy 59.993752 -291.348487) (xy 60.039768 -291.331035)
			(xy 60.087987 -291.321191) (xy 60.137162 -291.31921) (xy 60.186017 -291.325142) (xy 60.233288 -291.338834)
			(xy 60.27775 -291.359932) (xy 60.318253 -291.387888) (xy 60.353746 -291.42198) (xy 60.383311 -291.461324)
			(xy 60.406182 -291.504901) (xy 60.421766 -291.551582) (xy 60.429661 -291.600159) (xy 60.430156 -291.624766)
			(xy 60.769004 -291.624766) (xy 60.772964 -291.575712) (xy 60.784741 -291.527928) (xy 60.804032 -291.482652)
			(xy 60.830335 -291.441056) (xy 60.86297 -291.404219) (xy 60.901091 -291.373094) (xy 60.943712 -291.348487)
			(xy 60.989728 -291.331035) (xy 61.037947 -291.321191) (xy 61.087122 -291.31921) (xy 61.135977 -291.325142)
			(xy 61.183248 -291.338834) (xy 61.22771 -291.359932) (xy 61.268213 -291.387888) (xy 61.303706 -291.42198)
			(xy 61.333271 -291.461324) (xy 61.356142 -291.504901) (xy 61.371726 -291.551582) (xy 61.379621 -291.600159)
			(xy 61.380116 -291.624766) (xy 61.718964 -291.624766) (xy 61.722924 -291.575712) (xy 61.734701 -291.527928)
			(xy 61.753992 -291.482652) (xy 61.780295 -291.441056) (xy 61.81293 -291.404219) (xy 61.851051 -291.373094)
			(xy 61.893672 -291.348487) (xy 61.939688 -291.331035) (xy 61.987907 -291.321191) (xy 62.037082 -291.31921)
			(xy 62.085937 -291.325142) (xy 62.133208 -291.338834) (xy 62.17767 -291.359932) (xy 62.218173 -291.387888)
			(xy 62.253666 -291.42198) (xy 62.283231 -291.461324) (xy 62.306102 -291.504901) (xy 62.321686 -291.551582)
			(xy 62.329581 -291.600159) (xy 62.330076 -291.624766) (xy 62.669178 -291.624766) (xy 62.673138 -291.575712)
			(xy 62.684915 -291.527928) (xy 62.704206 -291.482652) (xy 62.730509 -291.441056) (xy 62.763144 -291.404219)
			(xy 62.801265 -291.373094) (xy 62.843886 -291.348487) (xy 62.889902 -291.331035) (xy 62.938121 -291.321191)
			(xy 62.987296 -291.31921) (xy 63.036151 -291.325142) (xy 63.083422 -291.338834) (xy 63.127884 -291.359932)
			(xy 63.168387 -291.387888) (xy 63.20388 -291.42198) (xy 63.233445 -291.461324) (xy 63.256316 -291.504901)
			(xy 63.2719 -291.551582) (xy 63.279795 -291.600159) (xy 63.28029 -291.624766) (xy 63.619138 -291.624766)
			(xy 63.623098 -291.575712) (xy 63.634875 -291.527928) (xy 63.654166 -291.482652) (xy 63.680469 -291.441056)
			(xy 63.713104 -291.404219) (xy 63.751225 -291.373094) (xy 63.793846 -291.348487) (xy 63.839862 -291.331035)
			(xy 63.888081 -291.321191) (xy 63.937256 -291.31921) (xy 63.986111 -291.325142) (xy 64.033382 -291.338834)
			(xy 64.077844 -291.359932) (xy 64.118347 -291.387888) (xy 64.15384 -291.42198) (xy 64.183405 -291.461324)
			(xy 64.206276 -291.504901) (xy 64.22186 -291.551582) (xy 64.229755 -291.600159) (xy 64.23025 -291.624766)
			(xy 64.569098 -291.624766) (xy 64.573058 -291.575712) (xy 64.584835 -291.527928) (xy 64.604126 -291.482652)
			(xy 64.630429 -291.441056) (xy 64.663064 -291.404219) (xy 64.701185 -291.373094) (xy 64.743806 -291.348487)
			(xy 64.789822 -291.331035) (xy 64.838041 -291.321191) (xy 64.887216 -291.31921) (xy 64.936071 -291.325142)
			(xy 64.983342 -291.338834) (xy 65.027804 -291.359932) (xy 65.068307 -291.387888) (xy 65.1038 -291.42198)
			(xy 65.133365 -291.461324) (xy 65.156236 -291.504901) (xy 65.17182 -291.551582) (xy 65.179715 -291.600159)
			(xy 65.18021 -291.624766) (xy 65.519058 -291.624766) (xy 65.523018 -291.575712) (xy 65.534795 -291.527928)
			(xy 65.554086 -291.482652) (xy 65.580389 -291.441056) (xy 65.613024 -291.404219) (xy 65.651145 -291.373094)
			(xy 65.693766 -291.348487) (xy 65.739782 -291.331035) (xy 65.788001 -291.321191) (xy 65.837176 -291.31921)
			(xy 65.886031 -291.325142) (xy 65.933302 -291.338834) (xy 65.977764 -291.359932) (xy 66.018267 -291.387888)
			(xy 66.05376 -291.42198) (xy 66.083325 -291.461324) (xy 66.106196 -291.504901) (xy 66.12178 -291.551582)
			(xy 66.129675 -291.600159) (xy 66.13017 -291.624766) (xy 66.469018 -291.624766) (xy 66.472978 -291.575712)
			(xy 66.484755 -291.527928) (xy 66.504046 -291.482652) (xy 66.530349 -291.441056) (xy 66.562984 -291.404219)
			(xy 66.601105 -291.373094) (xy 66.643726 -291.348487) (xy 66.689742 -291.331035) (xy 66.737961 -291.321191)
			(xy 66.787136 -291.31921) (xy 66.835991 -291.325142) (xy 66.883262 -291.338834) (xy 66.927724 -291.359932)
			(xy 66.968227 -291.387888) (xy 67.00372 -291.42198) (xy 67.033285 -291.461324) (xy 67.056156 -291.504901)
			(xy 67.07174 -291.551582) (xy 67.079635 -291.600159) (xy 67.08013 -291.624766) (xy 67.418978 -291.624766)
			(xy 67.422938 -291.575712) (xy 67.434715 -291.527928) (xy 67.454006 -291.482652) (xy 67.480309 -291.441056)
			(xy 67.512944 -291.404219) (xy 67.551065 -291.373094) (xy 67.593686 -291.348487) (xy 67.639702 -291.331035)
			(xy 67.687921 -291.321191) (xy 67.737096 -291.31921) (xy 67.785951 -291.325142) (xy 67.833222 -291.338834)
			(xy 67.877684 -291.359932) (xy 67.918187 -291.387888) (xy 67.95368 -291.42198) (xy 67.983245 -291.461324)
			(xy 68.006116 -291.504901) (xy 68.0217 -291.551582) (xy 68.029595 -291.600159) (xy 68.03009 -291.624766)
			(xy 68.368938 -291.624766) (xy 68.372898 -291.575712) (xy 68.384675 -291.527928) (xy 68.403966 -291.482652)
			(xy 68.430269 -291.441056) (xy 68.462904 -291.404219) (xy 68.501025 -291.373094) (xy 68.543646 -291.348487)
			(xy 68.589662 -291.331035) (xy 68.637881 -291.321191) (xy 68.687056 -291.31921) (xy 68.735911 -291.325142)
			(xy 68.783182 -291.338834) (xy 68.827644 -291.359932) (xy 68.868147 -291.387888) (xy 68.90364 -291.42198)
			(xy 68.933205 -291.461324) (xy 68.956076 -291.504901) (xy 68.97166 -291.551582) (xy 68.979555 -291.600159)
			(xy 68.98005 -291.624766) (xy 69.319152 -291.624766) (xy 69.323112 -291.575712) (xy 69.334889 -291.527928)
			(xy 69.35418 -291.482652) (xy 69.380483 -291.441056) (xy 69.413118 -291.404219) (xy 69.451239 -291.373094)
			(xy 69.49386 -291.348487) (xy 69.539876 -291.331035) (xy 69.588095 -291.321191) (xy 69.63727 -291.31921)
			(xy 69.686125 -291.325142) (xy 69.733396 -291.338834) (xy 69.777858 -291.359932) (xy 69.818361 -291.387888)
			(xy 69.853854 -291.42198) (xy 69.883419 -291.461324) (xy 69.90629 -291.504901) (xy 69.921874 -291.551582)
			(xy 69.929769 -291.600159) (xy 69.930264 -291.624766) (xy 70.269112 -291.624766) (xy 70.273072 -291.575712)
			(xy 70.284849 -291.527928) (xy 70.30414 -291.482652) (xy 70.330443 -291.441056) (xy 70.363078 -291.404219)
			(xy 70.401199 -291.373094) (xy 70.44382 -291.348487) (xy 70.489836 -291.331035) (xy 70.538055 -291.321191)
			(xy 70.58723 -291.31921) (xy 70.636085 -291.325142) (xy 70.683356 -291.338834) (xy 70.727818 -291.359932)
			(xy 70.768321 -291.387888) (xy 70.803814 -291.42198) (xy 70.833379 -291.461324) (xy 70.85625 -291.504901)
			(xy 70.871834 -291.551582) (xy 70.879729 -291.600159) (xy 70.880224 -291.624766) (xy 71.219072 -291.624766)
			(xy 71.223032 -291.575712) (xy 71.234809 -291.527928) (xy 71.2541 -291.482652) (xy 71.280403 -291.441056)
			(xy 71.313038 -291.404219) (xy 71.351159 -291.373094) (xy 71.39378 -291.348487) (xy 71.439796 -291.331035)
			(xy 71.488015 -291.321191) (xy 71.53719 -291.31921) (xy 71.586045 -291.325142) (xy 71.633316 -291.338834)
			(xy 71.677778 -291.359932) (xy 71.718281 -291.387888) (xy 71.753774 -291.42198) (xy 71.783339 -291.461324)
			(xy 71.80621 -291.504901) (xy 71.821794 -291.551582) (xy 71.829689 -291.600159) (xy 71.830184 -291.624766)
			(xy 72.169032 -291.624766) (xy 72.172992 -291.575712) (xy 72.184769 -291.527928) (xy 72.20406 -291.482652)
			(xy 72.230363 -291.441056) (xy 72.262998 -291.404219) (xy 72.301119 -291.373094) (xy 72.34374 -291.348487)
			(xy 72.389756 -291.331035) (xy 72.437975 -291.321191) (xy 72.48715 -291.31921) (xy 72.536005 -291.325142)
			(xy 72.583276 -291.338834) (xy 72.627738 -291.359932) (xy 72.668241 -291.387888) (xy 72.703734 -291.42198)
			(xy 72.733299 -291.461324) (xy 72.75617 -291.504901) (xy 72.771754 -291.551582) (xy 72.779649 -291.600159)
			(xy 72.780144 -291.624766) (xy 73.118992 -291.624766) (xy 73.122952 -291.575712) (xy 73.134729 -291.527928)
			(xy 73.15402 -291.482652) (xy 73.180323 -291.441056) (xy 73.212958 -291.404219) (xy 73.251079 -291.373094)
			(xy 73.2937 -291.348487) (xy 73.339716 -291.331035) (xy 73.387935 -291.321191) (xy 73.43711 -291.31921)
			(xy 73.485965 -291.325142) (xy 73.533236 -291.338834) (xy 73.577698 -291.359932) (xy 73.618201 -291.387888)
			(xy 73.653694 -291.42198) (xy 73.683259 -291.461324) (xy 73.70613 -291.504901) (xy 73.721714 -291.551582)
			(xy 73.729609 -291.600159) (xy 73.730104 -291.624766) (xy 74.069206 -291.624766) (xy 74.073166 -291.575712)
			(xy 74.084943 -291.527928) (xy 74.104234 -291.482652) (xy 74.130537 -291.441056) (xy 74.163172 -291.404219)
			(xy 74.201293 -291.373094) (xy 74.243914 -291.348487) (xy 74.28993 -291.331035) (xy 74.338149 -291.321191)
			(xy 74.387324 -291.31921) (xy 74.436179 -291.325142) (xy 74.48345 -291.338834) (xy 74.527912 -291.359932)
			(xy 74.568415 -291.387888) (xy 74.603908 -291.42198) (xy 74.633473 -291.461324) (xy 74.656344 -291.504901)
			(xy 74.671928 -291.551582) (xy 74.679823 -291.600159) (xy 74.680318 -291.624766) (xy 75.969126 -291.624766)
			(xy 75.973086 -291.575712) (xy 75.984863 -291.527928) (xy 76.004154 -291.482652) (xy 76.030457 -291.441056)
			(xy 76.063092 -291.404219) (xy 76.101213 -291.373094) (xy 76.143834 -291.348487) (xy 76.18985 -291.331035)
			(xy 76.238069 -291.321191) (xy 76.287244 -291.31921) (xy 76.336099 -291.325142) (xy 76.38337 -291.338834)
			(xy 76.427832 -291.359932) (xy 76.468335 -291.387888) (xy 76.503828 -291.42198) (xy 76.533393 -291.461324)
			(xy 76.556264 -291.504901) (xy 76.571848 -291.551582) (xy 76.579743 -291.600159) (xy 76.580238 -291.624766)
			(xy 76.919086 -291.624766) (xy 76.923046 -291.575712) (xy 76.934823 -291.527928) (xy 76.954114 -291.482652)
			(xy 76.980417 -291.441056) (xy 77.013052 -291.404219) (xy 77.051173 -291.373094) (xy 77.093794 -291.348487)
			(xy 77.13981 -291.331035) (xy 77.188029 -291.321191) (xy 77.237204 -291.31921) (xy 77.286059 -291.325142)
			(xy 77.33333 -291.338834) (xy 77.377792 -291.359932) (xy 77.418295 -291.387888) (xy 77.453788 -291.42198)
			(xy 77.483353 -291.461324) (xy 77.506224 -291.504901) (xy 77.521808 -291.551582) (xy 77.529703 -291.600159)
			(xy 77.530198 -291.624766) (xy 77.869046 -291.624766) (xy 77.873006 -291.575712) (xy 77.884783 -291.527928)
			(xy 77.904074 -291.482652) (xy 77.930377 -291.441056) (xy 77.963012 -291.404219) (xy 78.001133 -291.373094)
			(xy 78.043754 -291.348487) (xy 78.08977 -291.331035) (xy 78.137989 -291.321191) (xy 78.187164 -291.31921)
			(xy 78.236019 -291.325142) (xy 78.28329 -291.338834) (xy 78.327752 -291.359932) (xy 78.368255 -291.387888)
			(xy 78.403748 -291.42198) (xy 78.433313 -291.461324) (xy 78.456184 -291.504901) (xy 78.471768 -291.551582)
			(xy 78.479663 -291.600159) (xy 78.480158 -291.624766) (xy 78.819006 -291.624766) (xy 78.822966 -291.575712)
			(xy 78.834743 -291.527928) (xy 78.854034 -291.482652) (xy 78.880337 -291.441056) (xy 78.912972 -291.404219)
			(xy 78.951093 -291.373094) (xy 78.993714 -291.348487) (xy 79.03973 -291.331035) (xy 79.087949 -291.321191)
			(xy 79.137124 -291.31921) (xy 79.185979 -291.325142) (xy 79.23325 -291.338834) (xy 79.277712 -291.359932)
			(xy 79.318215 -291.387888) (xy 79.353708 -291.42198) (xy 79.383273 -291.461324) (xy 79.406144 -291.504901)
			(xy 79.421728 -291.551582) (xy 79.429623 -291.600159) (xy 79.430118 -291.624766) (xy 79.768966 -291.624766)
			(xy 79.772926 -291.575712) (xy 79.784703 -291.527928) (xy 79.803994 -291.482652) (xy 79.830297 -291.441056)
			(xy 79.862932 -291.404219) (xy 79.901053 -291.373094) (xy 79.943674 -291.348487) (xy 79.98969 -291.331035)
			(xy 80.037909 -291.321191) (xy 80.087084 -291.31921) (xy 80.135939 -291.325142) (xy 80.18321 -291.338834)
			(xy 80.227672 -291.359932) (xy 80.268175 -291.387888) (xy 80.303668 -291.42198) (xy 80.333233 -291.461324)
			(xy 80.356104 -291.504901) (xy 80.371688 -291.551582) (xy 80.379583 -291.600159) (xy 80.380078 -291.624766)
			(xy 80.71918 -291.624766) (xy 80.72314 -291.575712) (xy 80.734917 -291.527928) (xy 80.754208 -291.482652)
			(xy 80.780511 -291.441056) (xy 80.813146 -291.404219) (xy 80.851267 -291.373094) (xy 80.893888 -291.348487)
			(xy 80.939904 -291.331035) (xy 80.988123 -291.321191) (xy 81.037298 -291.31921) (xy 81.086153 -291.325142)
			(xy 81.133424 -291.338834) (xy 81.177886 -291.359932) (xy 81.218389 -291.387888) (xy 81.253882 -291.42198)
			(xy 81.283447 -291.461324) (xy 81.306318 -291.504901) (xy 81.321902 -291.551582) (xy 81.329797 -291.600159)
			(xy 81.330292 -291.624766) (xy 81.66914 -291.624766) (xy 81.6731 -291.575712) (xy 81.684877 -291.527928)
			(xy 81.704168 -291.482652) (xy 81.730471 -291.441056) (xy 81.763106 -291.404219) (xy 81.801227 -291.373094)
			(xy 81.843848 -291.348487) (xy 81.889864 -291.331035) (xy 81.938083 -291.321191) (xy 81.987258 -291.31921)
			(xy 82.036113 -291.325142) (xy 82.083384 -291.338834) (xy 82.127846 -291.359932) (xy 82.168349 -291.387888)
			(xy 82.203842 -291.42198) (xy 82.233407 -291.461324) (xy 82.256278 -291.504901) (xy 82.271862 -291.551582)
			(xy 82.279757 -291.600159) (xy 82.280252 -291.624766) (xy 82.6191 -291.624766) (xy 82.62306 -291.575712)
			(xy 82.634837 -291.527928) (xy 82.654128 -291.482652) (xy 82.680431 -291.441056) (xy 82.713066 -291.404219)
			(xy 82.751187 -291.373094) (xy 82.793808 -291.348487) (xy 82.839824 -291.331035) (xy 82.888043 -291.321191)
			(xy 82.937218 -291.31921) (xy 82.986073 -291.325142) (xy 83.033344 -291.338834) (xy 83.077806 -291.359932)
			(xy 83.118309 -291.387888) (xy 83.153802 -291.42198) (xy 83.183367 -291.461324) (xy 83.185296 -291.465)
			(xy 86.104982 -291.465) (xy 86.109053 -291.409378) (xy 86.121179 -291.354941) (xy 86.141102 -291.30285)
			(xy 86.168398 -291.254215) (xy 86.202484 -291.210072) (xy 86.242633 -291.171363) (xy 86.287991 -291.138912)
			(xy 86.337591 -291.113411) (xy 86.390375 -291.095404) (xy 86.445218 -291.085274) (xy 86.500952 -291.083237)
			(xy 86.556389 -291.089337) (xy 86.610346 -291.103443) (xy 86.661675 -291.125255) (xy 86.709281 -291.154309)
			(xy 86.752149 -291.189984) (xy 86.789366 -291.231521) (xy 86.820139 -291.278034) (xy 86.843811 -291.328531)
			(xy 86.859879 -291.381938) (xy 86.867999 -291.437114) (xy 86.868508 -291.465) (xy 86.867999 -291.492886)
			(xy 86.859879 -291.548062) (xy 86.84666 -291.592) (xy 88.441782 -291.592) (xy 88.445853 -291.536378)
			(xy 88.457979 -291.481941) (xy 88.477902 -291.42985) (xy 88.505198 -291.381215) (xy 88.539284 -291.337072)
			(xy 88.579433 -291.298363) (xy 88.624791 -291.265912) (xy 88.674391 -291.240411) (xy 88.727175 -291.222404)
			(xy 88.782018 -291.212274) (xy 88.837752 -291.210237) (xy 88.893189 -291.216337) (xy 88.947146 -291.230443)
			(xy 88.998475 -291.252255) (xy 89.046081 -291.281309) (xy 89.088949 -291.316984) (xy 89.126166 -291.358521)
			(xy 89.156939 -291.405034) (xy 89.180611 -291.455531) (xy 89.196679 -291.508938) (xy 89.204799 -291.564114)
			(xy 89.205308 -291.592) (xy 89.204799 -291.619886) (xy 89.196679 -291.675062) (xy 89.180611 -291.728469)
			(xy 89.156939 -291.778966) (xy 89.126166 -291.825479) (xy 89.088949 -291.867016) (xy 89.046081 -291.902691)
			(xy 88.998475 -291.931745) (xy 88.947146 -291.953557) (xy 88.893189 -291.967663) (xy 88.837752 -291.973763)
			(xy 88.782018 -291.971726) (xy 88.727175 -291.961596) (xy 88.674391 -291.943589) (xy 88.624791 -291.918088)
			(xy 88.579433 -291.885637) (xy 88.539284 -291.846928) (xy 88.505198 -291.802785) (xy 88.477902 -291.75415)
			(xy 88.457979 -291.702059) (xy 88.445853 -291.647622) (xy 88.441782 -291.592) (xy 86.84666 -291.592)
			(xy 86.843811 -291.601469) (xy 86.820139 -291.651966) (xy 86.789366 -291.698479) (xy 86.752149 -291.740016)
			(xy 86.709281 -291.775691) (xy 86.661675 -291.804745) (xy 86.610346 -291.826557) (xy 86.556389 -291.840663)
			(xy 86.500952 -291.846763) (xy 86.445218 -291.844726) (xy 86.390375 -291.834596) (xy 86.337591 -291.816589)
			(xy 86.287991 -291.791088) (xy 86.242633 -291.758637) (xy 86.202484 -291.719928) (xy 86.168398 -291.675785)
			(xy 86.141102 -291.62715) (xy 86.121179 -291.575059) (xy 86.109053 -291.520622) (xy 86.104982 -291.465)
			(xy 83.185296 -291.465) (xy 83.206238 -291.504901) (xy 83.221822 -291.551582) (xy 83.229717 -291.600159)
			(xy 83.230212 -291.624766) (xy 83.229717 -291.649373) (xy 83.221822 -291.69795) (xy 83.206238 -291.744631)
			(xy 83.183367 -291.788208) (xy 83.153802 -291.827552) (xy 83.118309 -291.861644) (xy 83.077806 -291.8896)
			(xy 83.033344 -291.910698) (xy 82.986073 -291.92439) (xy 82.937218 -291.930322) (xy 82.888043 -291.928341)
			(xy 82.839824 -291.918497) (xy 82.793808 -291.901045) (xy 82.751187 -291.876438) (xy 82.713066 -291.845313)
			(xy 82.680431 -291.808476) (xy 82.654128 -291.76688) (xy 82.634837 -291.721604) (xy 82.62306 -291.67382)
			(xy 82.6191 -291.624766) (xy 82.280252 -291.624766) (xy 82.279757 -291.649373) (xy 82.271862 -291.69795)
			(xy 82.256278 -291.744631) (xy 82.233407 -291.788208) (xy 82.203842 -291.827552) (xy 82.168349 -291.861644)
			(xy 82.127846 -291.8896) (xy 82.083384 -291.910698) (xy 82.036113 -291.92439) (xy 81.987258 -291.930322)
			(xy 81.938083 -291.928341) (xy 81.889864 -291.918497) (xy 81.843848 -291.901045) (xy 81.801227 -291.876438)
			(xy 81.763106 -291.845313) (xy 81.730471 -291.808476) (xy 81.704168 -291.76688) (xy 81.684877 -291.721604)
			(xy 81.6731 -291.67382) (xy 81.66914 -291.624766) (xy 81.330292 -291.624766) (xy 81.329797 -291.649373)
			(xy 81.321902 -291.69795) (xy 81.306318 -291.744631) (xy 81.283447 -291.788208) (xy 81.253882 -291.827552)
			(xy 81.218389 -291.861644) (xy 81.177886 -291.8896) (xy 81.133424 -291.910698) (xy 81.086153 -291.92439)
			(xy 81.037298 -291.930322) (xy 80.988123 -291.928341) (xy 80.939904 -291.918497) (xy 80.893888 -291.901045)
			(xy 80.851267 -291.876438) (xy 80.813146 -291.845313) (xy 80.780511 -291.808476) (xy 80.754208 -291.76688)
			(xy 80.734917 -291.721604) (xy 80.72314 -291.67382) (xy 80.71918 -291.624766) (xy 80.380078 -291.624766)
			(xy 80.379583 -291.649373) (xy 80.371688 -291.69795) (xy 80.356104 -291.744631) (xy 80.333233 -291.788208)
			(xy 80.303668 -291.827552) (xy 80.268175 -291.861644) (xy 80.227672 -291.8896) (xy 80.18321 -291.910698)
			(xy 80.135939 -291.92439) (xy 80.087084 -291.930322) (xy 80.037909 -291.928341) (xy 79.98969 -291.918497)
			(xy 79.943674 -291.901045) (xy 79.901053 -291.876438) (xy 79.862932 -291.845313) (xy 79.830297 -291.808476)
			(xy 79.803994 -291.76688) (xy 79.784703 -291.721604) (xy 79.772926 -291.67382) (xy 79.768966 -291.624766)
			(xy 79.430118 -291.624766) (xy 79.429623 -291.649373) (xy 79.421728 -291.69795) (xy 79.406144 -291.744631)
			(xy 79.383273 -291.788208) (xy 79.353708 -291.827552) (xy 79.318215 -291.861644) (xy 79.277712 -291.8896)
			(xy 79.23325 -291.910698) (xy 79.185979 -291.92439) (xy 79.137124 -291.930322) (xy 79.087949 -291.928341)
			(xy 79.03973 -291.918497) (xy 78.993714 -291.901045) (xy 78.951093 -291.876438) (xy 78.912972 -291.845313)
			(xy 78.880337 -291.808476) (xy 78.854034 -291.76688) (xy 78.834743 -291.721604) (xy 78.822966 -291.67382)
			(xy 78.819006 -291.624766) (xy 78.480158 -291.624766) (xy 78.479663 -291.649373) (xy 78.471768 -291.69795)
			(xy 78.456184 -291.744631) (xy 78.433313 -291.788208) (xy 78.403748 -291.827552) (xy 78.368255 -291.861644)
			(xy 78.327752 -291.8896) (xy 78.28329 -291.910698) (xy 78.236019 -291.92439) (xy 78.187164 -291.930322)
			(xy 78.137989 -291.928341) (xy 78.08977 -291.918497) (xy 78.043754 -291.901045) (xy 78.001133 -291.876438)
			(xy 77.963012 -291.845313) (xy 77.930377 -291.808476) (xy 77.904074 -291.76688) (xy 77.884783 -291.721604)
			(xy 77.873006 -291.67382) (xy 77.869046 -291.624766) (xy 77.530198 -291.624766) (xy 77.529703 -291.649373)
			(xy 77.521808 -291.69795) (xy 77.506224 -291.744631) (xy 77.483353 -291.788208) (xy 77.453788 -291.827552)
			(xy 77.418295 -291.861644) (xy 77.377792 -291.8896) (xy 77.33333 -291.910698) (xy 77.286059 -291.92439)
			(xy 77.237204 -291.930322) (xy 77.188029 -291.928341) (xy 77.13981 -291.918497) (xy 77.093794 -291.901045)
			(xy 77.051173 -291.876438) (xy 77.013052 -291.845313) (xy 76.980417 -291.808476) (xy 76.954114 -291.76688)
			(xy 76.934823 -291.721604) (xy 76.923046 -291.67382) (xy 76.919086 -291.624766) (xy 76.580238 -291.624766)
			(xy 76.579743 -291.649373) (xy 76.571848 -291.69795) (xy 76.556264 -291.744631) (xy 76.533393 -291.788208)
			(xy 76.503828 -291.827552) (xy 76.468335 -291.861644) (xy 76.427832 -291.8896) (xy 76.38337 -291.910698)
			(xy 76.336099 -291.92439) (xy 76.287244 -291.930322) (xy 76.238069 -291.928341) (xy 76.18985 -291.918497)
			(xy 76.143834 -291.901045) (xy 76.101213 -291.876438) (xy 76.063092 -291.845313) (xy 76.030457 -291.808476)
			(xy 76.004154 -291.76688) (xy 75.984863 -291.721604) (xy 75.973086 -291.67382) (xy 75.969126 -291.624766)
			(xy 74.680318 -291.624766) (xy 74.679823 -291.649373) (xy 74.671928 -291.69795) (xy 74.656344 -291.744631)
			(xy 74.633473 -291.788208) (xy 74.603908 -291.827552) (xy 74.568415 -291.861644) (xy 74.527912 -291.8896)
			(xy 74.48345 -291.910698) (xy 74.436179 -291.92439) (xy 74.387324 -291.930322) (xy 74.338149 -291.928341)
			(xy 74.28993 -291.918497) (xy 74.243914 -291.901045) (xy 74.201293 -291.876438) (xy 74.163172 -291.845313)
			(xy 74.130537 -291.808476) (xy 74.104234 -291.76688) (xy 74.084943 -291.721604) (xy 74.073166 -291.67382)
			(xy 74.069206 -291.624766) (xy 73.730104 -291.624766) (xy 73.729609 -291.649373) (xy 73.721714 -291.69795)
			(xy 73.70613 -291.744631) (xy 73.683259 -291.788208) (xy 73.653694 -291.827552) (xy 73.618201 -291.861644)
			(xy 73.577698 -291.8896) (xy 73.533236 -291.910698) (xy 73.485965 -291.92439) (xy 73.43711 -291.930322)
			(xy 73.387935 -291.928341) (xy 73.339716 -291.918497) (xy 73.2937 -291.901045) (xy 73.251079 -291.876438)
			(xy 73.212958 -291.845313) (xy 73.180323 -291.808476) (xy 73.15402 -291.76688) (xy 73.134729 -291.721604)
			(xy 73.122952 -291.67382) (xy 73.118992 -291.624766) (xy 72.780144 -291.624766) (xy 72.779649 -291.649373)
			(xy 72.771754 -291.69795) (xy 72.75617 -291.744631) (xy 72.733299 -291.788208) (xy 72.703734 -291.827552)
			(xy 72.668241 -291.861644) (xy 72.627738 -291.8896) (xy 72.583276 -291.910698) (xy 72.536005 -291.92439)
			(xy 72.48715 -291.930322) (xy 72.437975 -291.928341) (xy 72.389756 -291.918497) (xy 72.34374 -291.901045)
			(xy 72.301119 -291.876438) (xy 72.262998 -291.845313) (xy 72.230363 -291.808476) (xy 72.20406 -291.76688)
			(xy 72.184769 -291.721604) (xy 72.172992 -291.67382) (xy 72.169032 -291.624766) (xy 71.830184 -291.624766)
			(xy 71.829689 -291.649373) (xy 71.821794 -291.69795) (xy 71.80621 -291.744631) (xy 71.783339 -291.788208)
			(xy 71.753774 -291.827552) (xy 71.718281 -291.861644) (xy 71.677778 -291.8896) (xy 71.633316 -291.910698)
			(xy 71.586045 -291.92439) (xy 71.53719 -291.930322) (xy 71.488015 -291.928341) (xy 71.439796 -291.918497)
			(xy 71.39378 -291.901045) (xy 71.351159 -291.876438) (xy 71.313038 -291.845313) (xy 71.280403 -291.808476)
			(xy 71.2541 -291.76688) (xy 71.234809 -291.721604) (xy 71.223032 -291.67382) (xy 71.219072 -291.624766)
			(xy 70.880224 -291.624766) (xy 70.879729 -291.649373) (xy 70.871834 -291.69795) (xy 70.85625 -291.744631)
			(xy 70.833379 -291.788208) (xy 70.803814 -291.827552) (xy 70.768321 -291.861644) (xy 70.727818 -291.8896)
			(xy 70.683356 -291.910698) (xy 70.636085 -291.92439) (xy 70.58723 -291.930322) (xy 70.538055 -291.928341)
			(xy 70.489836 -291.918497) (xy 70.44382 -291.901045) (xy 70.401199 -291.876438) (xy 70.363078 -291.845313)
			(xy 70.330443 -291.808476) (xy 70.30414 -291.76688) (xy 70.284849 -291.721604) (xy 70.273072 -291.67382)
			(xy 70.269112 -291.624766) (xy 69.930264 -291.624766) (xy 69.929769 -291.649373) (xy 69.921874 -291.69795)
			(xy 69.90629 -291.744631) (xy 69.883419 -291.788208) (xy 69.853854 -291.827552) (xy 69.818361 -291.861644)
			(xy 69.777858 -291.8896) (xy 69.733396 -291.910698) (xy 69.686125 -291.92439) (xy 69.63727 -291.930322)
			(xy 69.588095 -291.928341) (xy 69.539876 -291.918497) (xy 69.49386 -291.901045) (xy 69.451239 -291.876438)
			(xy 69.413118 -291.845313) (xy 69.380483 -291.808476) (xy 69.35418 -291.76688) (xy 69.334889 -291.721604)
			(xy 69.323112 -291.67382) (xy 69.319152 -291.624766) (xy 68.98005 -291.624766) (xy 68.979555 -291.649373)
			(xy 68.97166 -291.69795) (xy 68.956076 -291.744631) (xy 68.933205 -291.788208) (xy 68.90364 -291.827552)
			(xy 68.868147 -291.861644) (xy 68.827644 -291.8896) (xy 68.783182 -291.910698) (xy 68.735911 -291.92439)
			(xy 68.687056 -291.930322) (xy 68.637881 -291.928341) (xy 68.589662 -291.918497) (xy 68.543646 -291.901045)
			(xy 68.501025 -291.876438) (xy 68.462904 -291.845313) (xy 68.430269 -291.808476) (xy 68.403966 -291.76688)
			(xy 68.384675 -291.721604) (xy 68.372898 -291.67382) (xy 68.368938 -291.624766) (xy 68.03009 -291.624766)
			(xy 68.029595 -291.649373) (xy 68.0217 -291.69795) (xy 68.006116 -291.744631) (xy 67.983245 -291.788208)
			(xy 67.95368 -291.827552) (xy 67.918187 -291.861644) (xy 67.877684 -291.8896) (xy 67.833222 -291.910698)
			(xy 67.785951 -291.92439) (xy 67.737096 -291.930322) (xy 67.687921 -291.928341) (xy 67.639702 -291.918497)
			(xy 67.593686 -291.901045) (xy 67.551065 -291.876438) (xy 67.512944 -291.845313) (xy 67.480309 -291.808476)
			(xy 67.454006 -291.76688) (xy 67.434715 -291.721604) (xy 67.422938 -291.67382) (xy 67.418978 -291.624766)
			(xy 67.08013 -291.624766) (xy 67.079635 -291.649373) (xy 67.07174 -291.69795) (xy 67.056156 -291.744631)
			(xy 67.033285 -291.788208) (xy 67.00372 -291.827552) (xy 66.968227 -291.861644) (xy 66.927724 -291.8896)
			(xy 66.883262 -291.910698) (xy 66.835991 -291.92439) (xy 66.787136 -291.930322) (xy 66.737961 -291.928341)
			(xy 66.689742 -291.918497) (xy 66.643726 -291.901045) (xy 66.601105 -291.876438) (xy 66.562984 -291.845313)
			(xy 66.530349 -291.808476) (xy 66.504046 -291.76688) (xy 66.484755 -291.721604) (xy 66.472978 -291.67382)
			(xy 66.469018 -291.624766) (xy 66.13017 -291.624766) (xy 66.129675 -291.649373) (xy 66.12178 -291.69795)
			(xy 66.106196 -291.744631) (xy 66.083325 -291.788208) (xy 66.05376 -291.827552) (xy 66.018267 -291.861644)
			(xy 65.977764 -291.8896) (xy 65.933302 -291.910698) (xy 65.886031 -291.92439) (xy 65.837176 -291.930322)
			(xy 65.788001 -291.928341) (xy 65.739782 -291.918497) (xy 65.693766 -291.901045) (xy 65.651145 -291.876438)
			(xy 65.613024 -291.845313) (xy 65.580389 -291.808476) (xy 65.554086 -291.76688) (xy 65.534795 -291.721604)
			(xy 65.523018 -291.67382) (xy 65.519058 -291.624766) (xy 65.18021 -291.624766) (xy 65.179715 -291.649373)
			(xy 65.17182 -291.69795) (xy 65.156236 -291.744631) (xy 65.133365 -291.788208) (xy 65.1038 -291.827552)
			(xy 65.068307 -291.861644) (xy 65.027804 -291.8896) (xy 64.983342 -291.910698) (xy 64.936071 -291.92439)
			(xy 64.887216 -291.930322) (xy 64.838041 -291.928341) (xy 64.789822 -291.918497) (xy 64.743806 -291.901045)
			(xy 64.701185 -291.876438) (xy 64.663064 -291.845313) (xy 64.630429 -291.808476) (xy 64.604126 -291.76688)
			(xy 64.584835 -291.721604) (xy 64.573058 -291.67382) (xy 64.569098 -291.624766) (xy 64.23025 -291.624766)
			(xy 64.229755 -291.649373) (xy 64.22186 -291.69795) (xy 64.206276 -291.744631) (xy 64.183405 -291.788208)
			(xy 64.15384 -291.827552) (xy 64.118347 -291.861644) (xy 64.077844 -291.8896) (xy 64.033382 -291.910698)
			(xy 63.986111 -291.92439) (xy 63.937256 -291.930322) (xy 63.888081 -291.928341) (xy 63.839862 -291.918497)
			(xy 63.793846 -291.901045) (xy 63.751225 -291.876438) (xy 63.713104 -291.845313) (xy 63.680469 -291.808476)
			(xy 63.654166 -291.76688) (xy 63.634875 -291.721604) (xy 63.623098 -291.67382) (xy 63.619138 -291.624766)
			(xy 63.28029 -291.624766) (xy 63.279795 -291.649373) (xy 63.2719 -291.69795) (xy 63.256316 -291.744631)
			(xy 63.233445 -291.788208) (xy 63.20388 -291.827552) (xy 63.168387 -291.861644) (xy 63.127884 -291.8896)
			(xy 63.083422 -291.910698) (xy 63.036151 -291.92439) (xy 62.987296 -291.930322) (xy 62.938121 -291.928341)
			(xy 62.889902 -291.918497) (xy 62.843886 -291.901045) (xy 62.801265 -291.876438) (xy 62.763144 -291.845313)
			(xy 62.730509 -291.808476) (xy 62.704206 -291.76688) (xy 62.684915 -291.721604) (xy 62.673138 -291.67382)
			(xy 62.669178 -291.624766) (xy 62.330076 -291.624766) (xy 62.329581 -291.649373) (xy 62.321686 -291.69795)
			(xy 62.306102 -291.744631) (xy 62.283231 -291.788208) (xy 62.253666 -291.827552) (xy 62.218173 -291.861644)
			(xy 62.17767 -291.8896) (xy 62.133208 -291.910698) (xy 62.085937 -291.92439) (xy 62.037082 -291.930322)
			(xy 61.987907 -291.928341) (xy 61.939688 -291.918497) (xy 61.893672 -291.901045) (xy 61.851051 -291.876438)
			(xy 61.81293 -291.845313) (xy 61.780295 -291.808476) (xy 61.753992 -291.76688) (xy 61.734701 -291.721604)
			(xy 61.722924 -291.67382) (xy 61.718964 -291.624766) (xy 61.380116 -291.624766) (xy 61.379621 -291.649373)
			(xy 61.371726 -291.69795) (xy 61.356142 -291.744631) (xy 61.333271 -291.788208) (xy 61.303706 -291.827552)
			(xy 61.268213 -291.861644) (xy 61.22771 -291.8896) (xy 61.183248 -291.910698) (xy 61.135977 -291.92439)
			(xy 61.087122 -291.930322) (xy 61.037947 -291.928341) (xy 60.989728 -291.918497) (xy 60.943712 -291.901045)
			(xy 60.901091 -291.876438) (xy 60.86297 -291.845313) (xy 60.830335 -291.808476) (xy 60.804032 -291.76688)
			(xy 60.784741 -291.721604) (xy 60.772964 -291.67382) (xy 60.769004 -291.624766) (xy 60.430156 -291.624766)
			(xy 60.429661 -291.649373) (xy 60.421766 -291.69795) (xy 60.406182 -291.744631) (xy 60.383311 -291.788208)
			(xy 60.353746 -291.827552) (xy 60.318253 -291.861644) (xy 60.27775 -291.8896) (xy 60.233288 -291.910698)
			(xy 60.186017 -291.92439) (xy 60.137162 -291.930322) (xy 60.087987 -291.928341) (xy 60.039768 -291.918497)
			(xy 59.993752 -291.901045) (xy 59.951131 -291.876438) (xy 59.91301 -291.845313) (xy 59.880375 -291.808476)
			(xy 59.854072 -291.76688) (xy 59.834781 -291.721604) (xy 59.823004 -291.67382) (xy 59.819044 -291.624766)
			(xy 58.530236 -291.624766) (xy 58.529741 -291.649373) (xy 58.521846 -291.69795) (xy 58.506262 -291.744631)
			(xy 58.483391 -291.788208) (xy 58.453826 -291.827552) (xy 58.418333 -291.861644) (xy 58.37783 -291.8896)
			(xy 58.333368 -291.910698) (xy 58.286097 -291.92439) (xy 58.237242 -291.930322) (xy 58.188067 -291.928341)
			(xy 58.139848 -291.918497) (xy 58.093832 -291.901045) (xy 58.051211 -291.876438) (xy 58.01309 -291.845313)
			(xy 57.980455 -291.808476) (xy 57.954152 -291.76688) (xy 57.934861 -291.721604) (xy 57.923084 -291.67382)
			(xy 57.919124 -291.624766) (xy 57.580276 -291.624766) (xy 57.579781 -291.649373) (xy 57.571886 -291.69795)
			(xy 57.556302 -291.744631) (xy 57.533431 -291.788208) (xy 57.503866 -291.827552) (xy 57.468373 -291.861644)
			(xy 57.42787 -291.8896) (xy 57.383408 -291.910698) (xy 57.336137 -291.92439) (xy 57.287282 -291.930322)
			(xy 57.238107 -291.928341) (xy 57.189888 -291.918497) (xy 57.143872 -291.901045) (xy 57.101251 -291.876438)
			(xy 57.06313 -291.845313) (xy 57.030495 -291.808476) (xy 57.004192 -291.76688) (xy 56.984901 -291.721604)
			(xy 56.973124 -291.67382) (xy 56.969164 -291.624766) (xy 56.630062 -291.624766) (xy 56.629567 -291.649373)
			(xy 56.621672 -291.69795) (xy 56.606088 -291.744631) (xy 56.583217 -291.788208) (xy 56.553652 -291.827552)
			(xy 56.518159 -291.861644) (xy 56.477656 -291.8896) (xy 56.433194 -291.910698) (xy 56.385923 -291.92439)
			(xy 56.337068 -291.930322) (xy 56.287893 -291.928341) (xy 56.239674 -291.918497) (xy 56.193658 -291.901045)
			(xy 56.151037 -291.876438) (xy 56.112916 -291.845313) (xy 56.080281 -291.808476) (xy 56.053978 -291.76688)
			(xy 56.034687 -291.721604) (xy 56.02291 -291.67382) (xy 56.01895 -291.624766) (xy 55.680102 -291.624766)
			(xy 55.679607 -291.649373) (xy 55.671712 -291.69795) (xy 55.656128 -291.744631) (xy 55.633257 -291.788208)
			(xy 55.603692 -291.827552) (xy 55.568199 -291.861644) (xy 55.527696 -291.8896) (xy 55.483234 -291.910698)
			(xy 55.435963 -291.92439) (xy 55.387108 -291.930322) (xy 55.337933 -291.928341) (xy 55.289714 -291.918497)
			(xy 55.243698 -291.901045) (xy 55.201077 -291.876438) (xy 55.162956 -291.845313) (xy 55.130321 -291.808476)
			(xy 55.104018 -291.76688) (xy 55.084727 -291.721604) (xy 55.07295 -291.67382) (xy 55.06899 -291.624766)
			(xy 54.730142 -291.624766) (xy 54.729647 -291.649373) (xy 54.721752 -291.69795) (xy 54.706168 -291.744631)
			(xy 54.683297 -291.788208) (xy 54.653732 -291.827552) (xy 54.618239 -291.861644) (xy 54.577736 -291.8896)
			(xy 54.533274 -291.910698) (xy 54.486003 -291.92439) (xy 54.437148 -291.930322) (xy 54.387973 -291.928341)
			(xy 54.339754 -291.918497) (xy 54.293738 -291.901045) (xy 54.251117 -291.876438) (xy 54.212996 -291.845313)
			(xy 54.180361 -291.808476) (xy 54.154058 -291.76688) (xy 54.134767 -291.721604) (xy 54.12299 -291.67382)
			(xy 54.11903 -291.624766) (xy 53.780182 -291.624766) (xy 53.779687 -291.649373) (xy 53.771792 -291.69795)
			(xy 53.756208 -291.744631) (xy 53.733337 -291.788208) (xy 53.703772 -291.827552) (xy 53.668279 -291.861644)
			(xy 53.627776 -291.8896) (xy 53.583314 -291.910698) (xy 53.536043 -291.92439) (xy 53.487188 -291.930322)
			(xy 53.438013 -291.928341) (xy 53.389794 -291.918497) (xy 53.343778 -291.901045) (xy 53.301157 -291.876438)
			(xy 53.263036 -291.845313) (xy 53.230401 -291.808476) (xy 53.204098 -291.76688) (xy 53.184807 -291.721604)
			(xy 53.17303 -291.67382) (xy 53.16907 -291.624766) (xy 52.830222 -291.624766) (xy 52.829727 -291.649373)
			(xy 52.821832 -291.69795) (xy 52.806248 -291.744631) (xy 52.783377 -291.788208) (xy 52.753812 -291.827552)
			(xy 52.718319 -291.861644) (xy 52.677816 -291.8896) (xy 52.633354 -291.910698) (xy 52.586083 -291.92439)
			(xy 52.537228 -291.930322) (xy 52.488053 -291.928341) (xy 52.439834 -291.918497) (xy 52.393818 -291.901045)
			(xy 52.351197 -291.876438) (xy 52.313076 -291.845313) (xy 52.280441 -291.808476) (xy 52.254138 -291.76688)
			(xy 52.234847 -291.721604) (xy 52.22307 -291.67382) (xy 52.21911 -291.624766) (xy 51.880262 -291.624766)
			(xy 51.879767 -291.649373) (xy 51.871872 -291.69795) (xy 51.856288 -291.744631) (xy 51.833417 -291.788208)
			(xy 51.803852 -291.827552) (xy 51.768359 -291.861644) (xy 51.727856 -291.8896) (xy 51.683394 -291.910698)
			(xy 51.636123 -291.92439) (xy 51.587268 -291.930322) (xy 51.538093 -291.928341) (xy 51.489874 -291.918497)
			(xy 51.443858 -291.901045) (xy 51.401237 -291.876438) (xy 51.363116 -291.845313) (xy 51.330481 -291.808476)
			(xy 51.304178 -291.76688) (xy 51.284887 -291.721604) (xy 51.27311 -291.67382) (xy 51.26915 -291.624766)
			(xy 50.930302 -291.624766) (xy 50.929807 -291.649373) (xy 50.921912 -291.69795) (xy 50.906328 -291.744631)
			(xy 50.883457 -291.788208) (xy 50.853892 -291.827552) (xy 50.818399 -291.861644) (xy 50.777896 -291.8896)
			(xy 50.733434 -291.910698) (xy 50.686163 -291.92439) (xy 50.637308 -291.930322) (xy 50.588133 -291.928341)
			(xy 50.539914 -291.918497) (xy 50.493898 -291.901045) (xy 50.451277 -291.876438) (xy 50.413156 -291.845313)
			(xy 50.380521 -291.808476) (xy 50.354218 -291.76688) (xy 50.334927 -291.721604) (xy 50.32315 -291.67382)
			(xy 50.31919 -291.624766) (xy 49.181004 -291.624766) (xy 49.181004 -292.122098) (xy 93.25737 -292.122098)
			(xy 93.257787 -292.095493) (xy 93.26517 -292.042797) (xy 93.279808 -291.991639) (xy 93.301415 -291.943013)
			(xy 93.329572 -291.897863) (xy 93.363732 -291.857065) (xy 93.403233 -291.821413) (xy 93.42501 -291.806122)
			(xy 93.436442 -291.797727) (xy 93.454643 -291.775997) (xy 93.466161 -291.750097) (xy 93.470107 -291.722027)
			(xy 93.466176 -291.693955) (xy 93.454672 -291.668049) (xy 93.436483 -291.646309) (xy 93.42501 -291.637974)
			(xy 93.403212 -291.622717) (xy 93.363735 -291.587043) (xy 93.329595 -291.546233) (xy 93.301453 -291.501076)
			(xy 93.279855 -291.452449) (xy 93.26522 -291.401294) (xy 93.257831 -291.348602) (xy 93.25737 -291.321998)
			(xy 93.257856 -291.294747) (xy 93.265612 -291.240799) (xy 93.280967 -291.188504) (xy 93.303609 -291.138927)
			(xy 93.333075 -291.093077) (xy 93.368766 -291.051886) (xy 93.409957 -291.016195) (xy 93.455807 -290.986729)
			(xy 93.505384 -290.964087) (xy 93.557679 -290.948732) (xy 93.611627 -290.940976) (xy 93.666129 -290.940976)
			(xy 93.720077 -290.948732) (xy 93.772372 -290.964087) (xy 93.821949 -290.986729) (xy 93.867799 -291.016195)
			(xy 93.90899 -291.051886) (xy 93.944681 -291.093077) (xy 93.974147 -291.138927) (xy 93.996789 -291.188504)
			(xy 94.012144 -291.240799) (xy 94.0199 -291.294747) (xy 94.020386 -291.321998) (xy 94.019942 -291.348602)
			(xy 94.01256 -291.401296) (xy 93.997925 -291.452452) (xy 93.976322 -291.501077) (xy 93.94817 -291.546227)
			(xy 93.914015 -291.587026) (xy 93.87452 -291.622681) (xy 93.852746 -291.637974) (xy 93.841215 -291.646246)
			(xy 93.823002 -291.668001) (xy 93.811482 -291.693929) (xy 93.807545 -291.722027) (xy 93.811497 -291.750123)
			(xy 93.82303 -291.776045) (xy 93.841255 -291.79779) (xy 93.852746 -291.806122) (xy 93.874532 -291.821395)
			(xy 93.914012 -291.857065) (xy 93.948154 -291.897872) (xy 93.976298 -291.943025) (xy 93.997898 -291.99165)
			(xy 94.012535 -292.042804) (xy 94.019925 -292.095495) (xy 94.020386 -292.122098) (xy 94.0199 -292.149349)
			(xy 94.012144 -292.203297) (xy 93.996789 -292.255592) (xy 93.974147 -292.305169) (xy 93.944681 -292.351019)
			(xy 93.90899 -292.39221) (xy 93.867799 -292.427901) (xy 93.821949 -292.457367) (xy 93.772372 -292.480009)
			(xy 93.720077 -292.495364) (xy 93.666129 -292.50312) (xy 93.611627 -292.50312) (xy 93.557679 -292.495364)
			(xy 93.505384 -292.480009) (xy 93.455807 -292.457367) (xy 93.409957 -292.427901) (xy 93.368766 -292.39221)
			(xy 93.333075 -292.351019) (xy 93.303609 -292.305169) (xy 93.280967 -292.255592) (xy 93.265612 -292.203297)
			(xy 93.257856 -292.149349) (xy 93.25737 -292.122098) (xy 49.181004 -292.122098) (xy 49.181004 -292.574726)
			(xy 49.368976 -292.574726) (xy 49.372936 -292.525672) (xy 49.384713 -292.477888) (xy 49.404004 -292.432612)
			(xy 49.430307 -292.391016) (xy 49.462942 -292.354179) (xy 49.501063 -292.323054) (xy 49.543684 -292.298447)
			(xy 49.5897 -292.280995) (xy 49.637919 -292.271151) (xy 49.687094 -292.26917) (xy 49.735949 -292.275102)
			(xy 49.78322 -292.288794) (xy 49.827682 -292.309892) (xy 49.868185 -292.337848) (xy 49.903678 -292.37194)
			(xy 49.933243 -292.411284) (xy 49.956114 -292.454861) (xy 49.971698 -292.501542) (xy 49.979593 -292.550119)
			(xy 49.980088 -292.574726) (xy 49.980083 -292.57498) (xy 50.31919 -292.57498) (xy 50.32315 -292.525926)
			(xy 50.334927 -292.478142) (xy 50.354218 -292.432866) (xy 50.380521 -292.39127) (xy 50.413156 -292.354433)
			(xy 50.451277 -292.323308) (xy 50.493898 -292.298701) (xy 50.539914 -292.281249) (xy 50.588133 -292.271405)
			(xy 50.637308 -292.269424) (xy 50.686163 -292.275356) (xy 50.733434 -292.289048) (xy 50.777896 -292.310146)
			(xy 50.818399 -292.338102) (xy 50.853892 -292.372194) (xy 50.883457 -292.411538) (xy 50.906328 -292.455115)
			(xy 50.921912 -292.501796) (xy 50.929807 -292.550373) (xy 50.930302 -292.57498) (xy 51.26915 -292.57498)
			(xy 51.27311 -292.525926) (xy 51.284887 -292.478142) (xy 51.304178 -292.432866) (xy 51.330481 -292.39127)
			(xy 51.363116 -292.354433) (xy 51.401237 -292.323308) (xy 51.443858 -292.298701) (xy 51.489874 -292.281249)
			(xy 51.538093 -292.271405) (xy 51.587268 -292.269424) (xy 51.636123 -292.275356) (xy 51.683394 -292.289048)
			(xy 51.727856 -292.310146) (xy 51.768359 -292.338102) (xy 51.803852 -292.372194) (xy 51.833417 -292.411538)
			(xy 51.856288 -292.455115) (xy 51.871872 -292.501796) (xy 51.879767 -292.550373) (xy 51.880262 -292.57498)
			(xy 52.21911 -292.57498) (xy 52.22307 -292.525926) (xy 52.234847 -292.478142) (xy 52.254138 -292.432866)
			(xy 52.280441 -292.39127) (xy 52.313076 -292.354433) (xy 52.351197 -292.323308) (xy 52.393818 -292.298701)
			(xy 52.439834 -292.281249) (xy 52.488053 -292.271405) (xy 52.537228 -292.269424) (xy 52.586083 -292.275356)
			(xy 52.633354 -292.289048) (xy 52.677816 -292.310146) (xy 52.718319 -292.338102) (xy 52.753812 -292.372194)
			(xy 52.783377 -292.411538) (xy 52.806248 -292.455115) (xy 52.821832 -292.501796) (xy 52.829727 -292.550373)
			(xy 52.830222 -292.57498) (xy 53.16907 -292.57498) (xy 53.17303 -292.525926) (xy 53.184807 -292.478142)
			(xy 53.204098 -292.432866) (xy 53.230401 -292.39127) (xy 53.263036 -292.354433) (xy 53.301157 -292.323308)
			(xy 53.343778 -292.298701) (xy 53.389794 -292.281249) (xy 53.438013 -292.271405) (xy 53.487188 -292.269424)
			(xy 53.536043 -292.275356) (xy 53.583314 -292.289048) (xy 53.627776 -292.310146) (xy 53.668279 -292.338102)
			(xy 53.703772 -292.372194) (xy 53.733337 -292.411538) (xy 53.756208 -292.455115) (xy 53.771792 -292.501796)
			(xy 53.779687 -292.550373) (xy 53.780182 -292.57498) (xy 54.11903 -292.57498) (xy 54.12299 -292.525926)
			(xy 54.134767 -292.478142) (xy 54.154058 -292.432866) (xy 54.180361 -292.39127) (xy 54.212996 -292.354433)
			(xy 54.251117 -292.323308) (xy 54.293738 -292.298701) (xy 54.339754 -292.281249) (xy 54.387973 -292.271405)
			(xy 54.437148 -292.269424) (xy 54.486003 -292.275356) (xy 54.533274 -292.289048) (xy 54.577736 -292.310146)
			(xy 54.618239 -292.338102) (xy 54.653732 -292.372194) (xy 54.683297 -292.411538) (xy 54.706168 -292.455115)
			(xy 54.721752 -292.501796) (xy 54.729647 -292.550373) (xy 54.730142 -292.57498) (xy 55.06899 -292.57498)
			(xy 55.07295 -292.525926) (xy 55.084727 -292.478142) (xy 55.104018 -292.432866) (xy 55.130321 -292.39127)
			(xy 55.162956 -292.354433) (xy 55.201077 -292.323308) (xy 55.243698 -292.298701) (xy 55.289714 -292.281249)
			(xy 55.337933 -292.271405) (xy 55.387108 -292.269424) (xy 55.435963 -292.275356) (xy 55.483234 -292.289048)
			(xy 55.527696 -292.310146) (xy 55.568199 -292.338102) (xy 55.603692 -292.372194) (xy 55.633257 -292.411538)
			(xy 55.656128 -292.455115) (xy 55.671712 -292.501796) (xy 55.679607 -292.550373) (xy 55.680102 -292.57498)
			(xy 56.019204 -292.57498) (xy 56.023164 -292.525926) (xy 56.034941 -292.478142) (xy 56.054232 -292.432866)
			(xy 56.080535 -292.39127) (xy 56.11317 -292.354433) (xy 56.151291 -292.323308) (xy 56.193912 -292.298701)
			(xy 56.239928 -292.281249) (xy 56.288147 -292.271405) (xy 56.337322 -292.269424) (xy 56.386177 -292.275356)
			(xy 56.433448 -292.289048) (xy 56.47791 -292.310146) (xy 56.518413 -292.338102) (xy 56.553906 -292.372194)
			(xy 56.583471 -292.411538) (xy 56.606342 -292.455115) (xy 56.621926 -292.501796) (xy 56.629821 -292.550373)
			(xy 56.630316 -292.57498) (xy 56.969164 -292.57498) (xy 56.973124 -292.525926) (xy 56.984901 -292.478142)
			(xy 57.004192 -292.432866) (xy 57.030495 -292.39127) (xy 57.06313 -292.354433) (xy 57.101251 -292.323308)
			(xy 57.143872 -292.298701) (xy 57.189888 -292.281249) (xy 57.238107 -292.271405) (xy 57.287282 -292.269424)
			(xy 57.336137 -292.275356) (xy 57.383408 -292.289048) (xy 57.42787 -292.310146) (xy 57.468373 -292.338102)
			(xy 57.503866 -292.372194) (xy 57.533431 -292.411538) (xy 57.556302 -292.455115) (xy 57.571886 -292.501796)
			(xy 57.579781 -292.550373) (xy 57.580276 -292.57498) (xy 57.919124 -292.57498) (xy 57.923084 -292.525926)
			(xy 57.934861 -292.478142) (xy 57.954152 -292.432866) (xy 57.980455 -292.39127) (xy 58.01309 -292.354433)
			(xy 58.051211 -292.323308) (xy 58.093832 -292.298701) (xy 58.139848 -292.281249) (xy 58.188067 -292.271405)
			(xy 58.237242 -292.269424) (xy 58.286097 -292.275356) (xy 58.333368 -292.289048) (xy 58.37783 -292.310146)
			(xy 58.418333 -292.338102) (xy 58.453826 -292.372194) (xy 58.483391 -292.411538) (xy 58.506262 -292.455115)
			(xy 58.521846 -292.501796) (xy 58.529741 -292.550373) (xy 58.530231 -292.574726) (xy 59.819044 -292.574726)
			(xy 59.823004 -292.525672) (xy 59.834781 -292.477888) (xy 59.854072 -292.432612) (xy 59.880375 -292.391016)
			(xy 59.91301 -292.354179) (xy 59.951131 -292.323054) (xy 59.993752 -292.298447) (xy 60.039768 -292.280995)
			(xy 60.087987 -292.271151) (xy 60.137162 -292.26917) (xy 60.186017 -292.275102) (xy 60.233288 -292.288794)
			(xy 60.27775 -292.309892) (xy 60.318253 -292.337848) (xy 60.353746 -292.37194) (xy 60.383311 -292.411284)
			(xy 60.406182 -292.454861) (xy 60.421766 -292.501542) (xy 60.429661 -292.550119) (xy 60.430156 -292.574726)
			(xy 60.769004 -292.574726) (xy 60.772964 -292.525672) (xy 60.784741 -292.477888) (xy 60.804032 -292.432612)
			(xy 60.830335 -292.391016) (xy 60.86297 -292.354179) (xy 60.901091 -292.323054) (xy 60.943712 -292.298447)
			(xy 60.989728 -292.280995) (xy 61.037947 -292.271151) (xy 61.087122 -292.26917) (xy 61.135977 -292.275102)
			(xy 61.183248 -292.288794) (xy 61.22771 -292.309892) (xy 61.268213 -292.337848) (xy 61.303706 -292.37194)
			(xy 61.333271 -292.411284) (xy 61.356142 -292.454861) (xy 61.371726 -292.501542) (xy 61.379621 -292.550119)
			(xy 61.380116 -292.574726) (xy 61.718964 -292.574726) (xy 61.722924 -292.525672) (xy 61.734701 -292.477888)
			(xy 61.753992 -292.432612) (xy 61.780295 -292.391016) (xy 61.81293 -292.354179) (xy 61.851051 -292.323054)
			(xy 61.893672 -292.298447) (xy 61.939688 -292.280995) (xy 61.987907 -292.271151) (xy 62.037082 -292.26917)
			(xy 62.085937 -292.275102) (xy 62.133208 -292.288794) (xy 62.17767 -292.309892) (xy 62.218173 -292.337848)
			(xy 62.253666 -292.37194) (xy 62.283231 -292.411284) (xy 62.306102 -292.454861) (xy 62.321686 -292.501542)
			(xy 62.329581 -292.550119) (xy 62.330076 -292.574726) (xy 62.669178 -292.574726) (xy 62.673138 -292.525672)
			(xy 62.684915 -292.477888) (xy 62.704206 -292.432612) (xy 62.730509 -292.391016) (xy 62.763144 -292.354179)
			(xy 62.801265 -292.323054) (xy 62.843886 -292.298447) (xy 62.889902 -292.280995) (xy 62.938121 -292.271151)
			(xy 62.987296 -292.26917) (xy 63.036151 -292.275102) (xy 63.083422 -292.288794) (xy 63.127884 -292.309892)
			(xy 63.168387 -292.337848) (xy 63.20388 -292.37194) (xy 63.233445 -292.411284) (xy 63.256316 -292.454861)
			(xy 63.2719 -292.501542) (xy 63.279795 -292.550119) (xy 63.28029 -292.574726) (xy 63.619138 -292.574726)
			(xy 63.623098 -292.525672) (xy 63.634875 -292.477888) (xy 63.654166 -292.432612) (xy 63.680469 -292.391016)
			(xy 63.713104 -292.354179) (xy 63.751225 -292.323054) (xy 63.793846 -292.298447) (xy 63.839862 -292.280995)
			(xy 63.888081 -292.271151) (xy 63.937256 -292.26917) (xy 63.986111 -292.275102) (xy 64.033382 -292.288794)
			(xy 64.077844 -292.309892) (xy 64.118347 -292.337848) (xy 64.15384 -292.37194) (xy 64.183405 -292.411284)
			(xy 64.206276 -292.454861) (xy 64.22186 -292.501542) (xy 64.229755 -292.550119) (xy 64.23025 -292.574726)
			(xy 64.569098 -292.574726) (xy 64.573058 -292.525672) (xy 64.584835 -292.477888) (xy 64.604126 -292.432612)
			(xy 64.630429 -292.391016) (xy 64.663064 -292.354179) (xy 64.701185 -292.323054) (xy 64.743806 -292.298447)
			(xy 64.789822 -292.280995) (xy 64.838041 -292.271151) (xy 64.887216 -292.26917) (xy 64.936071 -292.275102)
			(xy 64.983342 -292.288794) (xy 65.027804 -292.309892) (xy 65.068307 -292.337848) (xy 65.1038 -292.37194)
			(xy 65.133365 -292.411284) (xy 65.156236 -292.454861) (xy 65.17182 -292.501542) (xy 65.179715 -292.550119)
			(xy 65.18021 -292.574726) (xy 65.519058 -292.574726) (xy 65.523018 -292.525672) (xy 65.534795 -292.477888)
			(xy 65.554086 -292.432612) (xy 65.580389 -292.391016) (xy 65.613024 -292.354179) (xy 65.651145 -292.323054)
			(xy 65.693766 -292.298447) (xy 65.739782 -292.280995) (xy 65.788001 -292.271151) (xy 65.837176 -292.26917)
			(xy 65.886031 -292.275102) (xy 65.933302 -292.288794) (xy 65.977764 -292.309892) (xy 66.018267 -292.337848)
			(xy 66.05376 -292.37194) (xy 66.083325 -292.411284) (xy 66.106196 -292.454861) (xy 66.12178 -292.501542)
			(xy 66.129675 -292.550119) (xy 66.13017 -292.574726) (xy 66.469018 -292.574726) (xy 66.472978 -292.525672)
			(xy 66.484755 -292.477888) (xy 66.504046 -292.432612) (xy 66.530349 -292.391016) (xy 66.562984 -292.354179)
			(xy 66.601105 -292.323054) (xy 66.643726 -292.298447) (xy 66.689742 -292.280995) (xy 66.737961 -292.271151)
			(xy 66.787136 -292.26917) (xy 66.835991 -292.275102) (xy 66.883262 -292.288794) (xy 66.927724 -292.309892)
			(xy 66.968227 -292.337848) (xy 67.00372 -292.37194) (xy 67.033285 -292.411284) (xy 67.056156 -292.454861)
			(xy 67.07174 -292.501542) (xy 67.079635 -292.550119) (xy 67.08013 -292.574726) (xy 67.418978 -292.574726)
			(xy 67.422938 -292.525672) (xy 67.434715 -292.477888) (xy 67.454006 -292.432612) (xy 67.480309 -292.391016)
			(xy 67.512944 -292.354179) (xy 67.551065 -292.323054) (xy 67.593686 -292.298447) (xy 67.639702 -292.280995)
			(xy 67.687921 -292.271151) (xy 67.737096 -292.26917) (xy 67.785951 -292.275102) (xy 67.833222 -292.288794)
			(xy 67.877684 -292.309892) (xy 67.918187 -292.337848) (xy 67.95368 -292.37194) (xy 67.983245 -292.411284)
			(xy 68.006116 -292.454861) (xy 68.0217 -292.501542) (xy 68.029595 -292.550119) (xy 68.03009 -292.574726)
			(xy 68.368938 -292.574726) (xy 68.372898 -292.525672) (xy 68.384675 -292.477888) (xy 68.403966 -292.432612)
			(xy 68.430269 -292.391016) (xy 68.462904 -292.354179) (xy 68.501025 -292.323054) (xy 68.543646 -292.298447)
			(xy 68.589662 -292.280995) (xy 68.637881 -292.271151) (xy 68.687056 -292.26917) (xy 68.735911 -292.275102)
			(xy 68.783182 -292.288794) (xy 68.827644 -292.309892) (xy 68.868147 -292.337848) (xy 68.90364 -292.37194)
			(xy 68.933205 -292.411284) (xy 68.956076 -292.454861) (xy 68.97166 -292.501542) (xy 68.979555 -292.550119)
			(xy 68.98005 -292.574726) (xy 69.319152 -292.574726) (xy 69.323112 -292.525672) (xy 69.334889 -292.477888)
			(xy 69.35418 -292.432612) (xy 69.380483 -292.391016) (xy 69.413118 -292.354179) (xy 69.451239 -292.323054)
			(xy 69.49386 -292.298447) (xy 69.539876 -292.280995) (xy 69.588095 -292.271151) (xy 69.63727 -292.26917)
			(xy 69.686125 -292.275102) (xy 69.733396 -292.288794) (xy 69.777858 -292.309892) (xy 69.818361 -292.337848)
			(xy 69.853854 -292.37194) (xy 69.883419 -292.411284) (xy 69.90629 -292.454861) (xy 69.921874 -292.501542)
			(xy 69.929769 -292.550119) (xy 69.930264 -292.574726) (xy 69.930259 -292.57498) (xy 70.269112 -292.57498)
			(xy 70.273072 -292.525926) (xy 70.284849 -292.478142) (xy 70.30414 -292.432866) (xy 70.330443 -292.39127)
			(xy 70.363078 -292.354433) (xy 70.401199 -292.323308) (xy 70.44382 -292.298701) (xy 70.489836 -292.281249)
			(xy 70.538055 -292.271405) (xy 70.58723 -292.269424) (xy 70.636085 -292.275356) (xy 70.683356 -292.289048)
			(xy 70.727818 -292.310146) (xy 70.768321 -292.338102) (xy 70.803814 -292.372194) (xy 70.833379 -292.411538)
			(xy 70.85625 -292.455115) (xy 70.871834 -292.501796) (xy 70.879729 -292.550373) (xy 70.880219 -292.574726)
			(xy 71.219072 -292.574726) (xy 71.223032 -292.525672) (xy 71.234809 -292.477888) (xy 71.2541 -292.432612)
			(xy 71.280403 -292.391016) (xy 71.313038 -292.354179) (xy 71.351159 -292.323054) (xy 71.39378 -292.298447)
			(xy 71.439796 -292.280995) (xy 71.488015 -292.271151) (xy 71.53719 -292.26917) (xy 71.586045 -292.275102)
			(xy 71.633316 -292.288794) (xy 71.677778 -292.309892) (xy 71.718281 -292.337848) (xy 71.753774 -292.37194)
			(xy 71.783339 -292.411284) (xy 71.80621 -292.454861) (xy 71.821794 -292.501542) (xy 71.829689 -292.550119)
			(xy 71.830184 -292.574726) (xy 72.169032 -292.574726) (xy 72.172992 -292.525672) (xy 72.184769 -292.477888)
			(xy 72.20406 -292.432612) (xy 72.230363 -292.391016) (xy 72.262998 -292.354179) (xy 72.301119 -292.323054)
			(xy 72.34374 -292.298447) (xy 72.389756 -292.280995) (xy 72.437975 -292.271151) (xy 72.48715 -292.26917)
			(xy 72.536005 -292.275102) (xy 72.583276 -292.288794) (xy 72.627738 -292.309892) (xy 72.668241 -292.337848)
			(xy 72.703734 -292.37194) (xy 72.733299 -292.411284) (xy 72.75617 -292.454861) (xy 72.771754 -292.501542)
			(xy 72.779649 -292.550119) (xy 72.780144 -292.574726) (xy 73.118992 -292.574726) (xy 73.122952 -292.525672)
			(xy 73.134729 -292.477888) (xy 73.15402 -292.432612) (xy 73.180323 -292.391016) (xy 73.212958 -292.354179)
			(xy 73.251079 -292.323054) (xy 73.2937 -292.298447) (xy 73.339716 -292.280995) (xy 73.387935 -292.271151)
			(xy 73.43711 -292.26917) (xy 73.485965 -292.275102) (xy 73.533236 -292.288794) (xy 73.577698 -292.309892)
			(xy 73.618201 -292.337848) (xy 73.653694 -292.37194) (xy 73.683259 -292.411284) (xy 73.70613 -292.454861)
			(xy 73.721714 -292.501542) (xy 73.729609 -292.550119) (xy 73.730104 -292.574726) (xy 74.068952 -292.574726)
			(xy 74.072912 -292.525672) (xy 74.084689 -292.477888) (xy 74.10398 -292.432612) (xy 74.130283 -292.391016)
			(xy 74.162918 -292.354179) (xy 74.201039 -292.323054) (xy 74.24366 -292.298447) (xy 74.289676 -292.280995)
			(xy 74.337895 -292.271151) (xy 74.38707 -292.26917) (xy 74.435925 -292.275102) (xy 74.483196 -292.288794)
			(xy 74.527658 -292.309892) (xy 74.568161 -292.337848) (xy 74.603654 -292.37194) (xy 74.633219 -292.411284)
			(xy 74.65609 -292.454861) (xy 74.671674 -292.501542) (xy 74.679569 -292.550119) (xy 74.680064 -292.574726)
			(xy 75.019166 -292.574726) (xy 75.023126 -292.525672) (xy 75.034903 -292.477888) (xy 75.054194 -292.432612)
			(xy 75.080497 -292.391016) (xy 75.113132 -292.354179) (xy 75.151253 -292.323054) (xy 75.193874 -292.298447)
			(xy 75.23989 -292.280995) (xy 75.288109 -292.271151) (xy 75.337284 -292.26917) (xy 75.386139 -292.275102)
			(xy 75.43341 -292.288794) (xy 75.477872 -292.309892) (xy 75.518375 -292.337848) (xy 75.553868 -292.37194)
			(xy 75.583433 -292.411284) (xy 75.606304 -292.454861) (xy 75.621888 -292.501542) (xy 75.629783 -292.550119)
			(xy 75.630278 -292.574726) (xy 75.969126 -292.574726) (xy 75.973086 -292.525672) (xy 75.984863 -292.477888)
			(xy 76.004154 -292.432612) (xy 76.030457 -292.391016) (xy 76.063092 -292.354179) (xy 76.101213 -292.323054)
			(xy 76.143834 -292.298447) (xy 76.18985 -292.280995) (xy 76.238069 -292.271151) (xy 76.287244 -292.26917)
			(xy 76.336099 -292.275102) (xy 76.38337 -292.288794) (xy 76.427832 -292.309892) (xy 76.468335 -292.337848)
			(xy 76.503828 -292.37194) (xy 76.533393 -292.411284) (xy 76.556264 -292.454861) (xy 76.571848 -292.501542)
			(xy 76.579743 -292.550119) (xy 76.580238 -292.574726) (xy 76.919086 -292.574726) (xy 76.923046 -292.525672)
			(xy 76.934823 -292.477888) (xy 76.954114 -292.432612) (xy 76.980417 -292.391016) (xy 77.013052 -292.354179)
			(xy 77.051173 -292.323054) (xy 77.093794 -292.298447) (xy 77.13981 -292.280995) (xy 77.188029 -292.271151)
			(xy 77.237204 -292.26917) (xy 77.286059 -292.275102) (xy 77.33333 -292.288794) (xy 77.377792 -292.309892)
			(xy 77.418295 -292.337848) (xy 77.453788 -292.37194) (xy 77.483353 -292.411284) (xy 77.506224 -292.454861)
			(xy 77.521808 -292.501542) (xy 77.529703 -292.550119) (xy 77.530198 -292.574726) (xy 77.869046 -292.574726)
			(xy 77.873006 -292.525672) (xy 77.884783 -292.477888) (xy 77.904074 -292.432612) (xy 77.930377 -292.391016)
			(xy 77.963012 -292.354179) (xy 78.001133 -292.323054) (xy 78.043754 -292.298447) (xy 78.08977 -292.280995)
			(xy 78.137989 -292.271151) (xy 78.187164 -292.26917) (xy 78.236019 -292.275102) (xy 78.28329 -292.288794)
			(xy 78.327752 -292.309892) (xy 78.368255 -292.337848) (xy 78.403748 -292.37194) (xy 78.433313 -292.411284)
			(xy 78.456184 -292.454861) (xy 78.471768 -292.501542) (xy 78.479663 -292.550119) (xy 78.480158 -292.574726)
			(xy 78.819006 -292.574726) (xy 78.822966 -292.525672) (xy 78.834743 -292.477888) (xy 78.854034 -292.432612)
			(xy 78.880337 -292.391016) (xy 78.912972 -292.354179) (xy 78.951093 -292.323054) (xy 78.993714 -292.298447)
			(xy 79.03973 -292.280995) (xy 79.087949 -292.271151) (xy 79.137124 -292.26917) (xy 79.185979 -292.275102)
			(xy 79.23325 -292.288794) (xy 79.277712 -292.309892) (xy 79.318215 -292.337848) (xy 79.353708 -292.37194)
			(xy 79.383273 -292.411284) (xy 79.406144 -292.454861) (xy 79.421728 -292.501542) (xy 79.429623 -292.550119)
			(xy 79.430118 -292.574726) (xy 79.768966 -292.574726) (xy 79.772926 -292.525672) (xy 79.784703 -292.477888)
			(xy 79.803994 -292.432612) (xy 79.830297 -292.391016) (xy 79.862932 -292.354179) (xy 79.901053 -292.323054)
			(xy 79.943674 -292.298447) (xy 79.98969 -292.280995) (xy 80.037909 -292.271151) (xy 80.087084 -292.26917)
			(xy 80.135939 -292.275102) (xy 80.18321 -292.288794) (xy 80.227672 -292.309892) (xy 80.268175 -292.337848)
			(xy 80.303668 -292.37194) (xy 80.333233 -292.411284) (xy 80.356104 -292.454861) (xy 80.371688 -292.501542)
			(xy 80.379583 -292.550119) (xy 80.380078 -292.574726) (xy 80.71918 -292.574726) (xy 80.72314 -292.525672)
			(xy 80.734917 -292.477888) (xy 80.754208 -292.432612) (xy 80.780511 -292.391016) (xy 80.813146 -292.354179)
			(xy 80.851267 -292.323054) (xy 80.893888 -292.298447) (xy 80.939904 -292.280995) (xy 80.988123 -292.271151)
			(xy 81.037298 -292.26917) (xy 81.086153 -292.275102) (xy 81.133424 -292.288794) (xy 81.177886 -292.309892)
			(xy 81.218389 -292.337848) (xy 81.253882 -292.37194) (xy 81.283447 -292.411284) (xy 81.306318 -292.454861)
			(xy 81.321902 -292.501542) (xy 81.329797 -292.550119) (xy 81.330292 -292.574726) (xy 81.330287 -292.57498)
			(xy 81.66914 -292.57498) (xy 81.6731 -292.525926) (xy 81.684877 -292.478142) (xy 81.704168 -292.432866)
			(xy 81.730471 -292.39127) (xy 81.763106 -292.354433) (xy 81.801227 -292.323308) (xy 81.843848 -292.298701)
			(xy 81.889864 -292.281249) (xy 81.938083 -292.271405) (xy 81.987258 -292.269424) (xy 82.036113 -292.275356)
			(xy 82.083384 -292.289048) (xy 82.127846 -292.310146) (xy 82.168349 -292.338102) (xy 82.203842 -292.372194)
			(xy 82.233407 -292.411538) (xy 82.256278 -292.455115) (xy 82.271862 -292.501796) (xy 82.279757 -292.550373)
			(xy 82.280252 -292.57498) (xy 82.6191 -292.57498) (xy 82.62306 -292.525926) (xy 82.634837 -292.478142)
			(xy 82.654128 -292.432866) (xy 82.680431 -292.39127) (xy 82.713066 -292.354433) (xy 82.751187 -292.323308)
			(xy 82.793808 -292.298701) (xy 82.839824 -292.281249) (xy 82.888043 -292.271405) (xy 82.937218 -292.269424)
			(xy 82.986073 -292.275356) (xy 83.033344 -292.289048) (xy 83.077806 -292.310146) (xy 83.118309 -292.338102)
			(xy 83.153802 -292.372194) (xy 83.183367 -292.411538) (xy 83.206238 -292.455115) (xy 83.221822 -292.501796)
			(xy 83.229717 -292.550373) (xy 83.230212 -292.57498) (xy 83.229717 -292.599587) (xy 83.221822 -292.648164)
			(xy 83.206238 -292.694845) (xy 83.183367 -292.738422) (xy 83.153802 -292.777766) (xy 83.118309 -292.811858)
			(xy 83.077806 -292.839814) (xy 83.033344 -292.860912) (xy 82.986073 -292.874604) (xy 82.937218 -292.880536)
			(xy 82.888043 -292.878555) (xy 82.839824 -292.868711) (xy 82.793808 -292.851259) (xy 82.751187 -292.826652)
			(xy 82.713066 -292.795527) (xy 82.680431 -292.75869) (xy 82.654128 -292.717094) (xy 82.634837 -292.671818)
			(xy 82.62306 -292.624034) (xy 82.6191 -292.57498) (xy 82.280252 -292.57498) (xy 82.279757 -292.599587)
			(xy 82.271862 -292.648164) (xy 82.256278 -292.694845) (xy 82.233407 -292.738422) (xy 82.203842 -292.777766)
			(xy 82.168349 -292.811858) (xy 82.127846 -292.839814) (xy 82.083384 -292.860912) (xy 82.036113 -292.874604)
			(xy 81.987258 -292.880536) (xy 81.938083 -292.878555) (xy 81.889864 -292.868711) (xy 81.843848 -292.851259)
			(xy 81.801227 -292.826652) (xy 81.763106 -292.795527) (xy 81.730471 -292.75869) (xy 81.704168 -292.717094)
			(xy 81.684877 -292.671818) (xy 81.6731 -292.624034) (xy 81.66914 -292.57498) (xy 81.330287 -292.57498)
			(xy 81.329797 -292.599333) (xy 81.321902 -292.64791) (xy 81.306318 -292.694591) (xy 81.283447 -292.738168)
			(xy 81.253882 -292.777512) (xy 81.218389 -292.811604) (xy 81.177886 -292.83956) (xy 81.133424 -292.860658)
			(xy 81.086153 -292.87435) (xy 81.037298 -292.880282) (xy 80.988123 -292.878301) (xy 80.939904 -292.868457)
			(xy 80.893888 -292.851005) (xy 80.851267 -292.826398) (xy 80.813146 -292.795273) (xy 80.780511 -292.758436)
			(xy 80.754208 -292.71684) (xy 80.734917 -292.671564) (xy 80.72314 -292.62378) (xy 80.71918 -292.574726)
			(xy 80.380078 -292.574726) (xy 80.379583 -292.599333) (xy 80.371688 -292.64791) (xy 80.356104 -292.694591)
			(xy 80.333233 -292.738168) (xy 80.303668 -292.777512) (xy 80.268175 -292.811604) (xy 80.227672 -292.83956)
			(xy 80.18321 -292.860658) (xy 80.135939 -292.87435) (xy 80.087084 -292.880282) (xy 80.037909 -292.878301)
			(xy 79.98969 -292.868457) (xy 79.943674 -292.851005) (xy 79.901053 -292.826398) (xy 79.862932 -292.795273)
			(xy 79.830297 -292.758436) (xy 79.803994 -292.71684) (xy 79.784703 -292.671564) (xy 79.772926 -292.62378)
			(xy 79.768966 -292.574726) (xy 79.430118 -292.574726) (xy 79.429623 -292.599333) (xy 79.421728 -292.64791)
			(xy 79.406144 -292.694591) (xy 79.383273 -292.738168) (xy 79.353708 -292.777512) (xy 79.318215 -292.811604)
			(xy 79.277712 -292.83956) (xy 79.23325 -292.860658) (xy 79.185979 -292.87435) (xy 79.137124 -292.880282)
			(xy 79.087949 -292.878301) (xy 79.03973 -292.868457) (xy 78.993714 -292.851005) (xy 78.951093 -292.826398)
			(xy 78.912972 -292.795273) (xy 78.880337 -292.758436) (xy 78.854034 -292.71684) (xy 78.834743 -292.671564)
			(xy 78.822966 -292.62378) (xy 78.819006 -292.574726) (xy 78.480158 -292.574726) (xy 78.479663 -292.599333)
			(xy 78.471768 -292.64791) (xy 78.456184 -292.694591) (xy 78.433313 -292.738168) (xy 78.403748 -292.777512)
			(xy 78.368255 -292.811604) (xy 78.327752 -292.83956) (xy 78.28329 -292.860658) (xy 78.236019 -292.87435)
			(xy 78.187164 -292.880282) (xy 78.137989 -292.878301) (xy 78.08977 -292.868457) (xy 78.043754 -292.851005)
			(xy 78.001133 -292.826398) (xy 77.963012 -292.795273) (xy 77.930377 -292.758436) (xy 77.904074 -292.71684)
			(xy 77.884783 -292.671564) (xy 77.873006 -292.62378) (xy 77.869046 -292.574726) (xy 77.530198 -292.574726)
			(xy 77.529703 -292.599333) (xy 77.521808 -292.64791) (xy 77.506224 -292.694591) (xy 77.483353 -292.738168)
			(xy 77.453788 -292.777512) (xy 77.418295 -292.811604) (xy 77.377792 -292.83956) (xy 77.33333 -292.860658)
			(xy 77.286059 -292.87435) (xy 77.237204 -292.880282) (xy 77.188029 -292.878301) (xy 77.13981 -292.868457)
			(xy 77.093794 -292.851005) (xy 77.051173 -292.826398) (xy 77.013052 -292.795273) (xy 76.980417 -292.758436)
			(xy 76.954114 -292.71684) (xy 76.934823 -292.671564) (xy 76.923046 -292.62378) (xy 76.919086 -292.574726)
			(xy 76.580238 -292.574726) (xy 76.579743 -292.599333) (xy 76.571848 -292.64791) (xy 76.556264 -292.694591)
			(xy 76.533393 -292.738168) (xy 76.503828 -292.777512) (xy 76.468335 -292.811604) (xy 76.427832 -292.83956)
			(xy 76.38337 -292.860658) (xy 76.336099 -292.87435) (xy 76.287244 -292.880282) (xy 76.238069 -292.878301)
			(xy 76.18985 -292.868457) (xy 76.143834 -292.851005) (xy 76.101213 -292.826398) (xy 76.063092 -292.795273)
			(xy 76.030457 -292.758436) (xy 76.004154 -292.71684) (xy 75.984863 -292.671564) (xy 75.973086 -292.62378)
			(xy 75.969126 -292.574726) (xy 75.630278 -292.574726) (xy 75.629783 -292.599333) (xy 75.621888 -292.64791)
			(xy 75.606304 -292.694591) (xy 75.583433 -292.738168) (xy 75.553868 -292.777512) (xy 75.518375 -292.811604)
			(xy 75.477872 -292.83956) (xy 75.43341 -292.860658) (xy 75.386139 -292.87435) (xy 75.337284 -292.880282)
			(xy 75.288109 -292.878301) (xy 75.23989 -292.868457) (xy 75.193874 -292.851005) (xy 75.151253 -292.826398)
			(xy 75.113132 -292.795273) (xy 75.080497 -292.758436) (xy 75.054194 -292.71684) (xy 75.034903 -292.671564)
			(xy 75.023126 -292.62378) (xy 75.019166 -292.574726) (xy 74.680064 -292.574726) (xy 74.679569 -292.599333)
			(xy 74.671674 -292.64791) (xy 74.65609 -292.694591) (xy 74.633219 -292.738168) (xy 74.603654 -292.777512)
			(xy 74.568161 -292.811604) (xy 74.527658 -292.83956) (xy 74.483196 -292.860658) (xy 74.435925 -292.87435)
			(xy 74.38707 -292.880282) (xy 74.337895 -292.878301) (xy 74.289676 -292.868457) (xy 74.24366 -292.851005)
			(xy 74.201039 -292.826398) (xy 74.162918 -292.795273) (xy 74.130283 -292.758436) (xy 74.10398 -292.71684)
			(xy 74.084689 -292.671564) (xy 74.072912 -292.62378) (xy 74.068952 -292.574726) (xy 73.730104 -292.574726)
			(xy 73.729609 -292.599333) (xy 73.721714 -292.64791) (xy 73.70613 -292.694591) (xy 73.683259 -292.738168)
			(xy 73.653694 -292.777512) (xy 73.618201 -292.811604) (xy 73.577698 -292.83956) (xy 73.533236 -292.860658)
			(xy 73.485965 -292.87435) (xy 73.43711 -292.880282) (xy 73.387935 -292.878301) (xy 73.339716 -292.868457)
			(xy 73.2937 -292.851005) (xy 73.251079 -292.826398) (xy 73.212958 -292.795273) (xy 73.180323 -292.758436)
			(xy 73.15402 -292.71684) (xy 73.134729 -292.671564) (xy 73.122952 -292.62378) (xy 73.118992 -292.574726)
			(xy 72.780144 -292.574726) (xy 72.779649 -292.599333) (xy 72.771754 -292.64791) (xy 72.75617 -292.694591)
			(xy 72.733299 -292.738168) (xy 72.703734 -292.777512) (xy 72.668241 -292.811604) (xy 72.627738 -292.83956)
			(xy 72.583276 -292.860658) (xy 72.536005 -292.87435) (xy 72.48715 -292.880282) (xy 72.437975 -292.878301)
			(xy 72.389756 -292.868457) (xy 72.34374 -292.851005) (xy 72.301119 -292.826398) (xy 72.262998 -292.795273)
			(xy 72.230363 -292.758436) (xy 72.20406 -292.71684) (xy 72.184769 -292.671564) (xy 72.172992 -292.62378)
			(xy 72.169032 -292.574726) (xy 71.830184 -292.574726) (xy 71.829689 -292.599333) (xy 71.821794 -292.64791)
			(xy 71.80621 -292.694591) (xy 71.783339 -292.738168) (xy 71.753774 -292.777512) (xy 71.718281 -292.811604)
			(xy 71.677778 -292.83956) (xy 71.633316 -292.860658) (xy 71.586045 -292.87435) (xy 71.53719 -292.880282)
			(xy 71.488015 -292.878301) (xy 71.439796 -292.868457) (xy 71.39378 -292.851005) (xy 71.351159 -292.826398)
			(xy 71.313038 -292.795273) (xy 71.280403 -292.758436) (xy 71.2541 -292.71684) (xy 71.234809 -292.671564)
			(xy 71.223032 -292.62378) (xy 71.219072 -292.574726) (xy 70.880219 -292.574726) (xy 70.880224 -292.57498)
			(xy 70.879729 -292.599587) (xy 70.871834 -292.648164) (xy 70.85625 -292.694845) (xy 70.833379 -292.738422)
			(xy 70.803814 -292.777766) (xy 70.768321 -292.811858) (xy 70.727818 -292.839814) (xy 70.683356 -292.860912)
			(xy 70.636085 -292.874604) (xy 70.58723 -292.880536) (xy 70.538055 -292.878555) (xy 70.489836 -292.868711)
			(xy 70.44382 -292.851259) (xy 70.401199 -292.826652) (xy 70.363078 -292.795527) (xy 70.330443 -292.75869)
			(xy 70.30414 -292.717094) (xy 70.284849 -292.671818) (xy 70.273072 -292.624034) (xy 70.269112 -292.57498)
			(xy 69.930259 -292.57498) (xy 69.929769 -292.599333) (xy 69.921874 -292.64791) (xy 69.90629 -292.694591)
			(xy 69.883419 -292.738168) (xy 69.853854 -292.777512) (xy 69.818361 -292.811604) (xy 69.777858 -292.83956)
			(xy 69.733396 -292.860658) (xy 69.686125 -292.87435) (xy 69.63727 -292.880282) (xy 69.588095 -292.878301)
			(xy 69.539876 -292.868457) (xy 69.49386 -292.851005) (xy 69.451239 -292.826398) (xy 69.413118 -292.795273)
			(xy 69.380483 -292.758436) (xy 69.35418 -292.71684) (xy 69.334889 -292.671564) (xy 69.323112 -292.62378)
			(xy 69.319152 -292.574726) (xy 68.98005 -292.574726) (xy 68.979555 -292.599333) (xy 68.97166 -292.64791)
			(xy 68.956076 -292.694591) (xy 68.933205 -292.738168) (xy 68.90364 -292.777512) (xy 68.868147 -292.811604)
			(xy 68.827644 -292.83956) (xy 68.783182 -292.860658) (xy 68.735911 -292.87435) (xy 68.687056 -292.880282)
			(xy 68.637881 -292.878301) (xy 68.589662 -292.868457) (xy 68.543646 -292.851005) (xy 68.501025 -292.826398)
			(xy 68.462904 -292.795273) (xy 68.430269 -292.758436) (xy 68.403966 -292.71684) (xy 68.384675 -292.671564)
			(xy 68.372898 -292.62378) (xy 68.368938 -292.574726) (xy 68.03009 -292.574726) (xy 68.029595 -292.599333)
			(xy 68.0217 -292.64791) (xy 68.006116 -292.694591) (xy 67.983245 -292.738168) (xy 67.95368 -292.777512)
			(xy 67.918187 -292.811604) (xy 67.877684 -292.83956) (xy 67.833222 -292.860658) (xy 67.785951 -292.87435)
			(xy 67.737096 -292.880282) (xy 67.687921 -292.878301) (xy 67.639702 -292.868457) (xy 67.593686 -292.851005)
			(xy 67.551065 -292.826398) (xy 67.512944 -292.795273) (xy 67.480309 -292.758436) (xy 67.454006 -292.71684)
			(xy 67.434715 -292.671564) (xy 67.422938 -292.62378) (xy 67.418978 -292.574726) (xy 67.08013 -292.574726)
			(xy 67.079635 -292.599333) (xy 67.07174 -292.64791) (xy 67.056156 -292.694591) (xy 67.033285 -292.738168)
			(xy 67.00372 -292.777512) (xy 66.968227 -292.811604) (xy 66.927724 -292.83956) (xy 66.883262 -292.860658)
			(xy 66.835991 -292.87435) (xy 66.787136 -292.880282) (xy 66.737961 -292.878301) (xy 66.689742 -292.868457)
			(xy 66.643726 -292.851005) (xy 66.601105 -292.826398) (xy 66.562984 -292.795273) (xy 66.530349 -292.758436)
			(xy 66.504046 -292.71684) (xy 66.484755 -292.671564) (xy 66.472978 -292.62378) (xy 66.469018 -292.574726)
			(xy 66.13017 -292.574726) (xy 66.129675 -292.599333) (xy 66.12178 -292.64791) (xy 66.106196 -292.694591)
			(xy 66.083325 -292.738168) (xy 66.05376 -292.777512) (xy 66.018267 -292.811604) (xy 65.977764 -292.83956)
			(xy 65.933302 -292.860658) (xy 65.886031 -292.87435) (xy 65.837176 -292.880282) (xy 65.788001 -292.878301)
			(xy 65.739782 -292.868457) (xy 65.693766 -292.851005) (xy 65.651145 -292.826398) (xy 65.613024 -292.795273)
			(xy 65.580389 -292.758436) (xy 65.554086 -292.71684) (xy 65.534795 -292.671564) (xy 65.523018 -292.62378)
			(xy 65.519058 -292.574726) (xy 65.18021 -292.574726) (xy 65.179715 -292.599333) (xy 65.17182 -292.64791)
			(xy 65.156236 -292.694591) (xy 65.133365 -292.738168) (xy 65.1038 -292.777512) (xy 65.068307 -292.811604)
			(xy 65.027804 -292.83956) (xy 64.983342 -292.860658) (xy 64.936071 -292.87435) (xy 64.887216 -292.880282)
			(xy 64.838041 -292.878301) (xy 64.789822 -292.868457) (xy 64.743806 -292.851005) (xy 64.701185 -292.826398)
			(xy 64.663064 -292.795273) (xy 64.630429 -292.758436) (xy 64.604126 -292.71684) (xy 64.584835 -292.671564)
			(xy 64.573058 -292.62378) (xy 64.569098 -292.574726) (xy 64.23025 -292.574726) (xy 64.229755 -292.599333)
			(xy 64.22186 -292.64791) (xy 64.206276 -292.694591) (xy 64.183405 -292.738168) (xy 64.15384 -292.777512)
			(xy 64.118347 -292.811604) (xy 64.077844 -292.83956) (xy 64.033382 -292.860658) (xy 63.986111 -292.87435)
			(xy 63.937256 -292.880282) (xy 63.888081 -292.878301) (xy 63.839862 -292.868457) (xy 63.793846 -292.851005)
			(xy 63.751225 -292.826398) (xy 63.713104 -292.795273) (xy 63.680469 -292.758436) (xy 63.654166 -292.71684)
			(xy 63.634875 -292.671564) (xy 63.623098 -292.62378) (xy 63.619138 -292.574726) (xy 63.28029 -292.574726)
			(xy 63.279795 -292.599333) (xy 63.2719 -292.64791) (xy 63.256316 -292.694591) (xy 63.233445 -292.738168)
			(xy 63.20388 -292.777512) (xy 63.168387 -292.811604) (xy 63.127884 -292.83956) (xy 63.083422 -292.860658)
			(xy 63.036151 -292.87435) (xy 62.987296 -292.880282) (xy 62.938121 -292.878301) (xy 62.889902 -292.868457)
			(xy 62.843886 -292.851005) (xy 62.801265 -292.826398) (xy 62.763144 -292.795273) (xy 62.730509 -292.758436)
			(xy 62.704206 -292.71684) (xy 62.684915 -292.671564) (xy 62.673138 -292.62378) (xy 62.669178 -292.574726)
			(xy 62.330076 -292.574726) (xy 62.329581 -292.599333) (xy 62.321686 -292.64791) (xy 62.306102 -292.694591)
			(xy 62.283231 -292.738168) (xy 62.253666 -292.777512) (xy 62.218173 -292.811604) (xy 62.17767 -292.83956)
			(xy 62.133208 -292.860658) (xy 62.085937 -292.87435) (xy 62.037082 -292.880282) (xy 61.987907 -292.878301)
			(xy 61.939688 -292.868457) (xy 61.893672 -292.851005) (xy 61.851051 -292.826398) (xy 61.81293 -292.795273)
			(xy 61.780295 -292.758436) (xy 61.753992 -292.71684) (xy 61.734701 -292.671564) (xy 61.722924 -292.62378)
			(xy 61.718964 -292.574726) (xy 61.380116 -292.574726) (xy 61.379621 -292.599333) (xy 61.371726 -292.64791)
			(xy 61.356142 -292.694591) (xy 61.333271 -292.738168) (xy 61.303706 -292.777512) (xy 61.268213 -292.811604)
			(xy 61.22771 -292.83956) (xy 61.183248 -292.860658) (xy 61.135977 -292.87435) (xy 61.087122 -292.880282)
			(xy 61.037947 -292.878301) (xy 60.989728 -292.868457) (xy 60.943712 -292.851005) (xy 60.901091 -292.826398)
			(xy 60.86297 -292.795273) (xy 60.830335 -292.758436) (xy 60.804032 -292.71684) (xy 60.784741 -292.671564)
			(xy 60.772964 -292.62378) (xy 60.769004 -292.574726) (xy 60.430156 -292.574726) (xy 60.429661 -292.599333)
			(xy 60.421766 -292.64791) (xy 60.406182 -292.694591) (xy 60.383311 -292.738168) (xy 60.353746 -292.777512)
			(xy 60.318253 -292.811604) (xy 60.27775 -292.83956) (xy 60.233288 -292.860658) (xy 60.186017 -292.87435)
			(xy 60.137162 -292.880282) (xy 60.087987 -292.878301) (xy 60.039768 -292.868457) (xy 59.993752 -292.851005)
			(xy 59.951131 -292.826398) (xy 59.91301 -292.795273) (xy 59.880375 -292.758436) (xy 59.854072 -292.71684)
			(xy 59.834781 -292.671564) (xy 59.823004 -292.62378) (xy 59.819044 -292.574726) (xy 58.530231 -292.574726)
			(xy 58.530236 -292.57498) (xy 58.529741 -292.599587) (xy 58.521846 -292.648164) (xy 58.506262 -292.694845)
			(xy 58.483391 -292.738422) (xy 58.453826 -292.777766) (xy 58.418333 -292.811858) (xy 58.37783 -292.839814)
			(xy 58.333368 -292.860912) (xy 58.286097 -292.874604) (xy 58.237242 -292.880536) (xy 58.188067 -292.878555)
			(xy 58.139848 -292.868711) (xy 58.093832 -292.851259) (xy 58.051211 -292.826652) (xy 58.01309 -292.795527)
			(xy 57.980455 -292.75869) (xy 57.954152 -292.717094) (xy 57.934861 -292.671818) (xy 57.923084 -292.624034)
			(xy 57.919124 -292.57498) (xy 57.580276 -292.57498) (xy 57.579781 -292.599587) (xy 57.571886 -292.648164)
			(xy 57.556302 -292.694845) (xy 57.533431 -292.738422) (xy 57.503866 -292.777766) (xy 57.468373 -292.811858)
			(xy 57.42787 -292.839814) (xy 57.383408 -292.860912) (xy 57.336137 -292.874604) (xy 57.287282 -292.880536)
			(xy 57.238107 -292.878555) (xy 57.189888 -292.868711) (xy 57.143872 -292.851259) (xy 57.101251 -292.826652)
			(xy 57.06313 -292.795527) (xy 57.030495 -292.75869) (xy 57.004192 -292.717094) (xy 56.984901 -292.671818)
			(xy 56.973124 -292.624034) (xy 56.969164 -292.57498) (xy 56.630316 -292.57498) (xy 56.629821 -292.599587)
			(xy 56.621926 -292.648164) (xy 56.606342 -292.694845) (xy 56.583471 -292.738422) (xy 56.553906 -292.777766)
			(xy 56.518413 -292.811858) (xy 56.47791 -292.839814) (xy 56.433448 -292.860912) (xy 56.386177 -292.874604)
			(xy 56.337322 -292.880536) (xy 56.288147 -292.878555) (xy 56.239928 -292.868711) (xy 56.193912 -292.851259)
			(xy 56.151291 -292.826652) (xy 56.11317 -292.795527) (xy 56.080535 -292.75869) (xy 56.054232 -292.717094)
			(xy 56.034941 -292.671818) (xy 56.023164 -292.624034) (xy 56.019204 -292.57498) (xy 55.680102 -292.57498)
			(xy 55.679607 -292.599587) (xy 55.671712 -292.648164) (xy 55.656128 -292.694845) (xy 55.633257 -292.738422)
			(xy 55.603692 -292.777766) (xy 55.568199 -292.811858) (xy 55.527696 -292.839814) (xy 55.483234 -292.860912)
			(xy 55.435963 -292.874604) (xy 55.387108 -292.880536) (xy 55.337933 -292.878555) (xy 55.289714 -292.868711)
			(xy 55.243698 -292.851259) (xy 55.201077 -292.826652) (xy 55.162956 -292.795527) (xy 55.130321 -292.75869)
			(xy 55.104018 -292.717094) (xy 55.084727 -292.671818) (xy 55.07295 -292.624034) (xy 55.06899 -292.57498)
			(xy 54.730142 -292.57498) (xy 54.729647 -292.599587) (xy 54.721752 -292.648164) (xy 54.706168 -292.694845)
			(xy 54.683297 -292.738422) (xy 54.653732 -292.777766) (xy 54.618239 -292.811858) (xy 54.577736 -292.839814)
			(xy 54.533274 -292.860912) (xy 54.486003 -292.874604) (xy 54.437148 -292.880536) (xy 54.387973 -292.878555)
			(xy 54.339754 -292.868711) (xy 54.293738 -292.851259) (xy 54.251117 -292.826652) (xy 54.212996 -292.795527)
			(xy 54.180361 -292.75869) (xy 54.154058 -292.717094) (xy 54.134767 -292.671818) (xy 54.12299 -292.624034)
			(xy 54.11903 -292.57498) (xy 53.780182 -292.57498) (xy 53.779687 -292.599587) (xy 53.771792 -292.648164)
			(xy 53.756208 -292.694845) (xy 53.733337 -292.738422) (xy 53.703772 -292.777766) (xy 53.668279 -292.811858)
			(xy 53.627776 -292.839814) (xy 53.583314 -292.860912) (xy 53.536043 -292.874604) (xy 53.487188 -292.880536)
			(xy 53.438013 -292.878555) (xy 53.389794 -292.868711) (xy 53.343778 -292.851259) (xy 53.301157 -292.826652)
			(xy 53.263036 -292.795527) (xy 53.230401 -292.75869) (xy 53.204098 -292.717094) (xy 53.184807 -292.671818)
			(xy 53.17303 -292.624034) (xy 53.16907 -292.57498) (xy 52.830222 -292.57498) (xy 52.829727 -292.599587)
			(xy 52.821832 -292.648164) (xy 52.806248 -292.694845) (xy 52.783377 -292.738422) (xy 52.753812 -292.777766)
			(xy 52.718319 -292.811858) (xy 52.677816 -292.839814) (xy 52.633354 -292.860912) (xy 52.586083 -292.874604)
			(xy 52.537228 -292.880536) (xy 52.488053 -292.878555) (xy 52.439834 -292.868711) (xy 52.393818 -292.851259)
			(xy 52.351197 -292.826652) (xy 52.313076 -292.795527) (xy 52.280441 -292.75869) (xy 52.254138 -292.717094)
			(xy 52.234847 -292.671818) (xy 52.22307 -292.624034) (xy 52.21911 -292.57498) (xy 51.880262 -292.57498)
			(xy 51.879767 -292.599587) (xy 51.871872 -292.648164) (xy 51.856288 -292.694845) (xy 51.833417 -292.738422)
			(xy 51.803852 -292.777766) (xy 51.768359 -292.811858) (xy 51.727856 -292.839814) (xy 51.683394 -292.860912)
			(xy 51.636123 -292.874604) (xy 51.587268 -292.880536) (xy 51.538093 -292.878555) (xy 51.489874 -292.868711)
			(xy 51.443858 -292.851259) (xy 51.401237 -292.826652) (xy 51.363116 -292.795527) (xy 51.330481 -292.75869)
			(xy 51.304178 -292.717094) (xy 51.284887 -292.671818) (xy 51.27311 -292.624034) (xy 51.26915 -292.57498)
			(xy 50.930302 -292.57498) (xy 50.929807 -292.599587) (xy 50.921912 -292.648164) (xy 50.906328 -292.694845)
			(xy 50.883457 -292.738422) (xy 50.853892 -292.777766) (xy 50.818399 -292.811858) (xy 50.777896 -292.839814)
			(xy 50.733434 -292.860912) (xy 50.686163 -292.874604) (xy 50.637308 -292.880536) (xy 50.588133 -292.878555)
			(xy 50.539914 -292.868711) (xy 50.493898 -292.851259) (xy 50.451277 -292.826652) (xy 50.413156 -292.795527)
			(xy 50.380521 -292.75869) (xy 50.354218 -292.717094) (xy 50.334927 -292.671818) (xy 50.32315 -292.624034)
			(xy 50.31919 -292.57498) (xy 49.980083 -292.57498) (xy 49.979593 -292.599333) (xy 49.971698 -292.64791)
			(xy 49.956114 -292.694591) (xy 49.933243 -292.738168) (xy 49.903678 -292.777512) (xy 49.868185 -292.811604)
			(xy 49.827682 -292.83956) (xy 49.78322 -292.860658) (xy 49.735949 -292.87435) (xy 49.687094 -292.880282)
			(xy 49.637919 -292.878301) (xy 49.5897 -292.868457) (xy 49.543684 -292.851005) (xy 49.501063 -292.826398)
			(xy 49.462942 -292.795273) (xy 49.430307 -292.758436) (xy 49.404004 -292.71684) (xy 49.384713 -292.671564)
			(xy 49.372936 -292.62378) (xy 49.368976 -292.574726) (xy 49.181004 -292.574726) (xy 49.181004 -292.663372)
			(xy 49.180525 -292.673095) (xy 49.173215 -292.69112) (xy 49.16678 -292.698424) (xy 49.166272 -292.699186)
			(xy 49.162208 -292.703758) (xy 49.156375 -292.710896) (xy 49.149742 -292.72808) (xy 49.149254 -292.737286)
			(xy 49.149254 -293.52494) (xy 50.31919 -293.52494) (xy 50.32315 -293.475886) (xy 50.334927 -293.428102)
			(xy 50.354218 -293.382826) (xy 50.380521 -293.34123) (xy 50.413156 -293.304393) (xy 50.451277 -293.273268)
			(xy 50.493898 -293.248661) (xy 50.539914 -293.231209) (xy 50.588133 -293.221365) (xy 50.637308 -293.219384)
			(xy 50.686163 -293.225316) (xy 50.733434 -293.239008) (xy 50.777896 -293.260106) (xy 50.818399 -293.288062)
			(xy 50.853892 -293.322154) (xy 50.883457 -293.361498) (xy 50.906328 -293.405075) (xy 50.921912 -293.451756)
			(xy 50.929807 -293.500333) (xy 50.930302 -293.52494) (xy 52.21911 -293.52494) (xy 52.22307 -293.475886)
			(xy 52.234847 -293.428102) (xy 52.254138 -293.382826) (xy 52.280441 -293.34123) (xy 52.313076 -293.304393)
			(xy 52.351197 -293.273268) (xy 52.393818 -293.248661) (xy 52.439834 -293.231209) (xy 52.488053 -293.221365)
			(xy 52.537228 -293.219384) (xy 52.586083 -293.225316) (xy 52.633354 -293.239008) (xy 52.677816 -293.260106)
			(xy 52.718319 -293.288062) (xy 52.753812 -293.322154) (xy 52.783377 -293.361498) (xy 52.806248 -293.405075)
			(xy 52.821832 -293.451756) (xy 52.829727 -293.500333) (xy 52.830222 -293.52494) (xy 54.11903 -293.52494)
			(xy 54.12299 -293.475886) (xy 54.134767 -293.428102) (xy 54.154058 -293.382826) (xy 54.180361 -293.34123)
			(xy 54.212996 -293.304393) (xy 54.251117 -293.273268) (xy 54.293738 -293.248661) (xy 54.339754 -293.231209)
			(xy 54.387973 -293.221365) (xy 54.437148 -293.219384) (xy 54.486003 -293.225316) (xy 54.533274 -293.239008)
			(xy 54.577736 -293.260106) (xy 54.618239 -293.288062) (xy 54.653732 -293.322154) (xy 54.683297 -293.361498)
			(xy 54.706168 -293.405075) (xy 54.721752 -293.451756) (xy 54.729647 -293.500333) (xy 54.730142 -293.52494)
			(xy 56.01895 -293.52494) (xy 56.02291 -293.475886) (xy 56.034687 -293.428102) (xy 56.053978 -293.382826)
			(xy 56.080281 -293.34123) (xy 56.112916 -293.304393) (xy 56.151037 -293.273268) (xy 56.193658 -293.248661)
			(xy 56.239674 -293.231209) (xy 56.287893 -293.221365) (xy 56.337068 -293.219384) (xy 56.385923 -293.225316)
			(xy 56.433194 -293.239008) (xy 56.477656 -293.260106) (xy 56.518159 -293.288062) (xy 56.553652 -293.322154)
			(xy 56.583217 -293.361498) (xy 56.606088 -293.405075) (xy 56.621672 -293.451756) (xy 56.629567 -293.500333)
			(xy 56.630062 -293.52494) (xy 57.919124 -293.52494) (xy 57.923084 -293.475886) (xy 57.934861 -293.428102)
			(xy 57.954152 -293.382826) (xy 57.980455 -293.34123) (xy 58.01309 -293.304393) (xy 58.051211 -293.273268)
			(xy 58.093832 -293.248661) (xy 58.139848 -293.231209) (xy 58.188067 -293.221365) (xy 58.237242 -293.219384)
			(xy 58.286097 -293.225316) (xy 58.333368 -293.239008) (xy 58.37783 -293.260106) (xy 58.418333 -293.288062)
			(xy 58.453826 -293.322154) (xy 58.483391 -293.361498) (xy 58.506262 -293.405075) (xy 58.521846 -293.451756)
			(xy 58.529741 -293.500333) (xy 58.530236 -293.52494) (xy 60.769004 -293.52494) (xy 60.772964 -293.475886)
			(xy 60.784741 -293.428102) (xy 60.804032 -293.382826) (xy 60.830335 -293.34123) (xy 60.86297 -293.304393)
			(xy 60.901091 -293.273268) (xy 60.943712 -293.248661) (xy 60.989728 -293.231209) (xy 61.037947 -293.221365)
			(xy 61.087122 -293.219384) (xy 61.135977 -293.225316) (xy 61.183248 -293.239008) (xy 61.22771 -293.260106)
			(xy 61.268213 -293.288062) (xy 61.303706 -293.322154) (xy 61.333271 -293.361498) (xy 61.356142 -293.405075)
			(xy 61.371726 -293.451756) (xy 61.379621 -293.500333) (xy 61.380116 -293.52494) (xy 62.669178 -293.52494)
			(xy 62.673138 -293.475886) (xy 62.684915 -293.428102) (xy 62.704206 -293.382826) (xy 62.730509 -293.34123)
			(xy 62.763144 -293.304393) (xy 62.801265 -293.273268) (xy 62.843886 -293.248661) (xy 62.889902 -293.231209)
			(xy 62.938121 -293.221365) (xy 62.987296 -293.219384) (xy 63.036151 -293.225316) (xy 63.083422 -293.239008)
			(xy 63.127884 -293.260106) (xy 63.168387 -293.288062) (xy 63.20388 -293.322154) (xy 63.233445 -293.361498)
			(xy 63.256316 -293.405075) (xy 63.2719 -293.451756) (xy 63.279795 -293.500333) (xy 63.28029 -293.52494)
			(xy 64.569098 -293.52494) (xy 64.573058 -293.475886) (xy 64.584835 -293.428102) (xy 64.604126 -293.382826)
			(xy 64.630429 -293.34123) (xy 64.663064 -293.304393) (xy 64.701185 -293.273268) (xy 64.743806 -293.248661)
			(xy 64.789822 -293.231209) (xy 64.838041 -293.221365) (xy 64.887216 -293.219384) (xy 64.936071 -293.225316)
			(xy 64.983342 -293.239008) (xy 65.027804 -293.260106) (xy 65.068307 -293.288062) (xy 65.1038 -293.322154)
			(xy 65.133365 -293.361498) (xy 65.156236 -293.405075) (xy 65.17182 -293.451756) (xy 65.179715 -293.500333)
			(xy 65.18021 -293.52494) (xy 66.469018 -293.52494) (xy 66.472978 -293.475886) (xy 66.484755 -293.428102)
			(xy 66.504046 -293.382826) (xy 66.530349 -293.34123) (xy 66.562984 -293.304393) (xy 66.601105 -293.273268)
			(xy 66.643726 -293.248661) (xy 66.689742 -293.231209) (xy 66.737961 -293.221365) (xy 66.787136 -293.219384)
			(xy 66.835991 -293.225316) (xy 66.883262 -293.239008) (xy 66.927724 -293.260106) (xy 66.968227 -293.288062)
			(xy 67.00372 -293.322154) (xy 67.033285 -293.361498) (xy 67.056156 -293.405075) (xy 67.07174 -293.451756)
			(xy 67.079635 -293.500333) (xy 67.08013 -293.52494) (xy 68.368938 -293.52494) (xy 68.372898 -293.475886)
			(xy 68.384675 -293.428102) (xy 68.403966 -293.382826) (xy 68.430269 -293.34123) (xy 68.462904 -293.304393)
			(xy 68.501025 -293.273268) (xy 68.543646 -293.248661) (xy 68.589662 -293.231209) (xy 68.637881 -293.221365)
			(xy 68.687056 -293.219384) (xy 68.735911 -293.225316) (xy 68.783182 -293.239008) (xy 68.827644 -293.260106)
			(xy 68.868147 -293.288062) (xy 68.90364 -293.322154) (xy 68.933205 -293.361498) (xy 68.956076 -293.405075)
			(xy 68.97166 -293.451756) (xy 68.979555 -293.500333) (xy 68.98005 -293.52494) (xy 69.319152 -293.52494)
			(xy 69.323112 -293.475886) (xy 69.334889 -293.428102) (xy 69.35418 -293.382826) (xy 69.380483 -293.34123)
			(xy 69.413118 -293.304393) (xy 69.451239 -293.273268) (xy 69.49386 -293.248661) (xy 69.539876 -293.231209)
			(xy 69.588095 -293.221365) (xy 69.63727 -293.219384) (xy 69.686125 -293.225316) (xy 69.733396 -293.239008)
			(xy 69.777858 -293.260106) (xy 69.818361 -293.288062) (xy 69.853854 -293.322154) (xy 69.883419 -293.361498)
			(xy 69.90629 -293.405075) (xy 69.921874 -293.451756) (xy 69.929769 -293.500333) (xy 69.930264 -293.52494)
			(xy 70.269112 -293.52494) (xy 70.273072 -293.475886) (xy 70.284849 -293.428102) (xy 70.30414 -293.382826)
			(xy 70.330443 -293.34123) (xy 70.363078 -293.304393) (xy 70.401199 -293.273268) (xy 70.44382 -293.248661)
			(xy 70.489836 -293.231209) (xy 70.538055 -293.221365) (xy 70.58723 -293.219384) (xy 70.636085 -293.225316)
			(xy 70.683356 -293.239008) (xy 70.727818 -293.260106) (xy 70.768321 -293.288062) (xy 70.803814 -293.322154)
			(xy 70.833379 -293.361498) (xy 70.85625 -293.405075) (xy 70.871834 -293.451756) (xy 70.879729 -293.500333)
			(xy 70.880224 -293.52494) (xy 71.219072 -293.52494) (xy 71.223032 -293.475886) (xy 71.234809 -293.428102)
			(xy 71.2541 -293.382826) (xy 71.280403 -293.34123) (xy 71.313038 -293.304393) (xy 71.351159 -293.273268)
			(xy 71.39378 -293.248661) (xy 71.439796 -293.231209) (xy 71.488015 -293.221365) (xy 71.53719 -293.219384)
			(xy 71.586045 -293.225316) (xy 71.633316 -293.239008) (xy 71.677778 -293.260106) (xy 71.718281 -293.288062)
			(xy 71.753774 -293.322154) (xy 71.783339 -293.361498) (xy 71.80621 -293.405075) (xy 71.821794 -293.451756)
			(xy 71.829689 -293.500333) (xy 71.830184 -293.52494) (xy 72.169032 -293.52494) (xy 72.172992 -293.475886)
			(xy 72.184769 -293.428102) (xy 72.20406 -293.382826) (xy 72.230363 -293.34123) (xy 72.262998 -293.304393)
			(xy 72.301119 -293.273268) (xy 72.34374 -293.248661) (xy 72.389756 -293.231209) (xy 72.437975 -293.221365)
			(xy 72.48715 -293.219384) (xy 72.536005 -293.225316) (xy 72.583276 -293.239008) (xy 72.627738 -293.260106)
			(xy 72.668241 -293.288062) (xy 72.703734 -293.322154) (xy 72.733299 -293.361498) (xy 72.75617 -293.405075)
			(xy 72.771754 -293.451756) (xy 72.779649 -293.500333) (xy 72.780144 -293.52494) (xy 73.118992 -293.52494)
			(xy 73.122952 -293.475886) (xy 73.134729 -293.428102) (xy 73.15402 -293.382826) (xy 73.180323 -293.34123)
			(xy 73.212958 -293.304393) (xy 73.251079 -293.273268) (xy 73.2937 -293.248661) (xy 73.339716 -293.231209)
			(xy 73.387935 -293.221365) (xy 73.43711 -293.219384) (xy 73.485965 -293.225316) (xy 73.533236 -293.239008)
			(xy 73.577698 -293.260106) (xy 73.618201 -293.288062) (xy 73.653694 -293.322154) (xy 73.683259 -293.361498)
			(xy 73.70613 -293.405075) (xy 73.721714 -293.451756) (xy 73.729609 -293.500333) (xy 73.730104 -293.52494)
			(xy 74.069206 -293.52494) (xy 74.073166 -293.475886) (xy 74.084943 -293.428102) (xy 74.104234 -293.382826)
			(xy 74.130537 -293.34123) (xy 74.163172 -293.304393) (xy 74.201293 -293.273268) (xy 74.243914 -293.248661)
			(xy 74.28993 -293.231209) (xy 74.338149 -293.221365) (xy 74.387324 -293.219384) (xy 74.436179 -293.225316)
			(xy 74.48345 -293.239008) (xy 74.527912 -293.260106) (xy 74.568415 -293.288062) (xy 74.603908 -293.322154)
			(xy 74.633473 -293.361498) (xy 74.656344 -293.405075) (xy 74.671928 -293.451756) (xy 74.679823 -293.500333)
			(xy 74.680318 -293.52494) (xy 75.019166 -293.52494) (xy 75.023126 -293.475886) (xy 75.034903 -293.428102)
			(xy 75.054194 -293.382826) (xy 75.080497 -293.34123) (xy 75.113132 -293.304393) (xy 75.151253 -293.273268)
			(xy 75.193874 -293.248661) (xy 75.23989 -293.231209) (xy 75.288109 -293.221365) (xy 75.337284 -293.219384)
			(xy 75.386139 -293.225316) (xy 75.43341 -293.239008) (xy 75.477872 -293.260106) (xy 75.518375 -293.288062)
			(xy 75.553868 -293.322154) (xy 75.583433 -293.361498) (xy 75.606304 -293.405075) (xy 75.621888 -293.451756)
			(xy 75.629783 -293.500333) (xy 75.630278 -293.52494) (xy 75.969126 -293.52494) (xy 75.973086 -293.475886)
			(xy 75.984863 -293.428102) (xy 76.004154 -293.382826) (xy 76.030457 -293.34123) (xy 76.063092 -293.304393)
			(xy 76.101213 -293.273268) (xy 76.143834 -293.248661) (xy 76.18985 -293.231209) (xy 76.238069 -293.221365)
			(xy 76.287244 -293.219384) (xy 76.336099 -293.225316) (xy 76.38337 -293.239008) (xy 76.427832 -293.260106)
			(xy 76.468335 -293.288062) (xy 76.503828 -293.322154) (xy 76.533393 -293.361498) (xy 76.556264 -293.405075)
			(xy 76.571848 -293.451756) (xy 76.579743 -293.500333) (xy 76.580238 -293.52494) (xy 76.919086 -293.52494)
			(xy 76.923046 -293.475886) (xy 76.934823 -293.428102) (xy 76.954114 -293.382826) (xy 76.980417 -293.34123)
			(xy 77.013052 -293.304393) (xy 77.051173 -293.273268) (xy 77.093794 -293.248661) (xy 77.13981 -293.231209)
			(xy 77.188029 -293.221365) (xy 77.237204 -293.219384) (xy 77.286059 -293.225316) (xy 77.33333 -293.239008)
			(xy 77.377792 -293.260106) (xy 77.418295 -293.288062) (xy 77.453788 -293.322154) (xy 77.483353 -293.361498)
			(xy 77.506224 -293.405075) (xy 77.521808 -293.451756) (xy 77.529703 -293.500333) (xy 77.530198 -293.52494)
			(xy 77.869046 -293.52494) (xy 77.873006 -293.475886) (xy 77.884783 -293.428102) (xy 77.904074 -293.382826)
			(xy 77.930377 -293.34123) (xy 77.963012 -293.304393) (xy 78.001133 -293.273268) (xy 78.043754 -293.248661)
			(xy 78.08977 -293.231209) (xy 78.137989 -293.221365) (xy 78.187164 -293.219384) (xy 78.236019 -293.225316)
			(xy 78.28329 -293.239008) (xy 78.327752 -293.260106) (xy 78.368255 -293.288062) (xy 78.403748 -293.322154)
			(xy 78.433313 -293.361498) (xy 78.456184 -293.405075) (xy 78.471768 -293.451756) (xy 78.479663 -293.500333)
			(xy 78.480158 -293.52494) (xy 78.819006 -293.52494) (xy 78.822966 -293.475886) (xy 78.834743 -293.428102)
			(xy 78.854034 -293.382826) (xy 78.880337 -293.34123) (xy 78.912972 -293.304393) (xy 78.951093 -293.273268)
			(xy 78.993714 -293.248661) (xy 79.03973 -293.231209) (xy 79.087949 -293.221365) (xy 79.137124 -293.219384)
			(xy 79.185979 -293.225316) (xy 79.23325 -293.239008) (xy 79.277712 -293.260106) (xy 79.318215 -293.288062)
			(xy 79.353708 -293.322154) (xy 79.383273 -293.361498) (xy 79.406144 -293.405075) (xy 79.421728 -293.451756)
			(xy 79.429623 -293.500333) (xy 79.430118 -293.52494) (xy 79.768966 -293.52494) (xy 79.772926 -293.475886)
			(xy 79.784703 -293.428102) (xy 79.803994 -293.382826) (xy 79.830297 -293.34123) (xy 79.862932 -293.304393)
			(xy 79.901053 -293.273268) (xy 79.943674 -293.248661) (xy 79.98969 -293.231209) (xy 80.037909 -293.221365)
			(xy 80.087084 -293.219384) (xy 80.135939 -293.225316) (xy 80.18321 -293.239008) (xy 80.227672 -293.260106)
			(xy 80.268175 -293.288062) (xy 80.303668 -293.322154) (xy 80.333233 -293.361498) (xy 80.356104 -293.405075)
			(xy 80.371688 -293.451756) (xy 80.379583 -293.500333) (xy 80.380078 -293.52494) (xy 80.71918 -293.52494)
			(xy 80.72314 -293.475886) (xy 80.734917 -293.428102) (xy 80.754208 -293.382826) (xy 80.780511 -293.34123)
			(xy 80.813146 -293.304393) (xy 80.851267 -293.273268) (xy 80.893888 -293.248661) (xy 80.939904 -293.231209)
			(xy 80.988123 -293.221365) (xy 81.037298 -293.219384) (xy 81.086153 -293.225316) (xy 81.133424 -293.239008)
			(xy 81.177886 -293.260106) (xy 81.218389 -293.288062) (xy 81.253882 -293.322154) (xy 81.283447 -293.361498)
			(xy 81.306318 -293.405075) (xy 81.321902 -293.451756) (xy 81.329797 -293.500333) (xy 81.330292 -293.52494)
			(xy 81.66914 -293.52494) (xy 81.6731 -293.475886) (xy 81.684877 -293.428102) (xy 81.704168 -293.382826)
			(xy 81.730471 -293.34123) (xy 81.763106 -293.304393) (xy 81.801227 -293.273268) (xy 81.843848 -293.248661)
			(xy 81.889864 -293.231209) (xy 81.938083 -293.221365) (xy 81.987258 -293.219384) (xy 82.036113 -293.225316)
			(xy 82.083384 -293.239008) (xy 82.127846 -293.260106) (xy 82.168349 -293.288062) (xy 82.203842 -293.322154)
			(xy 82.233407 -293.361498) (xy 82.256278 -293.405075) (xy 82.271862 -293.451756) (xy 82.279757 -293.500333)
			(xy 82.280252 -293.52494) (xy 82.6191 -293.52494) (xy 82.62306 -293.475886) (xy 82.634837 -293.428102)
			(xy 82.654128 -293.382826) (xy 82.680431 -293.34123) (xy 82.713066 -293.304393) (xy 82.751187 -293.273268)
			(xy 82.793808 -293.248661) (xy 82.839824 -293.231209) (xy 82.888043 -293.221365) (xy 82.937218 -293.219384)
			(xy 82.986073 -293.225316) (xy 83.033344 -293.239008) (xy 83.077806 -293.260106) (xy 83.118309 -293.288062)
			(xy 83.153802 -293.322154) (xy 83.183367 -293.361498) (xy 83.206238 -293.405075) (xy 83.221822 -293.451756)
			(xy 83.229717 -293.500333) (xy 83.230212 -293.52494) (xy 83.229717 -293.549547) (xy 83.221822 -293.598124)
			(xy 83.206238 -293.644805) (xy 83.183367 -293.688382) (xy 83.153802 -293.727726) (xy 83.118309 -293.761818)
			(xy 83.077806 -293.789774) (xy 83.033344 -293.810872) (xy 82.986073 -293.824564) (xy 82.937218 -293.830496)
			(xy 82.888043 -293.828515) (xy 82.839824 -293.818671) (xy 82.793808 -293.801219) (xy 82.751187 -293.776612)
			(xy 82.713066 -293.745487) (xy 82.680431 -293.70865) (xy 82.654128 -293.667054) (xy 82.634837 -293.621778)
			(xy 82.62306 -293.573994) (xy 82.6191 -293.52494) (xy 82.280252 -293.52494) (xy 82.279757 -293.549547)
			(xy 82.271862 -293.598124) (xy 82.256278 -293.644805) (xy 82.233407 -293.688382) (xy 82.203842 -293.727726)
			(xy 82.168349 -293.761818) (xy 82.127846 -293.789774) (xy 82.083384 -293.810872) (xy 82.036113 -293.824564)
			(xy 81.987258 -293.830496) (xy 81.938083 -293.828515) (xy 81.889864 -293.818671) (xy 81.843848 -293.801219)
			(xy 81.801227 -293.776612) (xy 81.763106 -293.745487) (xy 81.730471 -293.70865) (xy 81.704168 -293.667054)
			(xy 81.684877 -293.621778) (xy 81.6731 -293.573994) (xy 81.66914 -293.52494) (xy 81.330292 -293.52494)
			(xy 81.329797 -293.549547) (xy 81.321902 -293.598124) (xy 81.306318 -293.644805) (xy 81.283447 -293.688382)
			(xy 81.253882 -293.727726) (xy 81.218389 -293.761818) (xy 81.177886 -293.789774) (xy 81.133424 -293.810872)
			(xy 81.086153 -293.824564) (xy 81.037298 -293.830496) (xy 80.988123 -293.828515) (xy 80.939904 -293.818671)
			(xy 80.893888 -293.801219) (xy 80.851267 -293.776612) (xy 80.813146 -293.745487) (xy 80.780511 -293.70865)
			(xy 80.754208 -293.667054) (xy 80.734917 -293.621778) (xy 80.72314 -293.573994) (xy 80.71918 -293.52494)
			(xy 80.380078 -293.52494) (xy 80.379583 -293.549547) (xy 80.371688 -293.598124) (xy 80.356104 -293.644805)
			(xy 80.333233 -293.688382) (xy 80.303668 -293.727726) (xy 80.268175 -293.761818) (xy 80.227672 -293.789774)
			(xy 80.18321 -293.810872) (xy 80.135939 -293.824564) (xy 80.087084 -293.830496) (xy 80.037909 -293.828515)
			(xy 79.98969 -293.818671) (xy 79.943674 -293.801219) (xy 79.901053 -293.776612) (xy 79.862932 -293.745487)
			(xy 79.830297 -293.70865) (xy 79.803994 -293.667054) (xy 79.784703 -293.621778) (xy 79.772926 -293.573994)
			(xy 79.768966 -293.52494) (xy 79.430118 -293.52494) (xy 79.429623 -293.549547) (xy 79.421728 -293.598124)
			(xy 79.406144 -293.644805) (xy 79.383273 -293.688382) (xy 79.353708 -293.727726) (xy 79.318215 -293.761818)
			(xy 79.277712 -293.789774) (xy 79.23325 -293.810872) (xy 79.185979 -293.824564) (xy 79.137124 -293.830496)
			(xy 79.087949 -293.828515) (xy 79.03973 -293.818671) (xy 78.993714 -293.801219) (xy 78.951093 -293.776612)
			(xy 78.912972 -293.745487) (xy 78.880337 -293.70865) (xy 78.854034 -293.667054) (xy 78.834743 -293.621778)
			(xy 78.822966 -293.573994) (xy 78.819006 -293.52494) (xy 78.480158 -293.52494) (xy 78.479663 -293.549547)
			(xy 78.471768 -293.598124) (xy 78.456184 -293.644805) (xy 78.433313 -293.688382) (xy 78.403748 -293.727726)
			(xy 78.368255 -293.761818) (xy 78.327752 -293.789774) (xy 78.28329 -293.810872) (xy 78.236019 -293.824564)
			(xy 78.187164 -293.830496) (xy 78.137989 -293.828515) (xy 78.08977 -293.818671) (xy 78.043754 -293.801219)
			(xy 78.001133 -293.776612) (xy 77.963012 -293.745487) (xy 77.930377 -293.70865) (xy 77.904074 -293.667054)
			(xy 77.884783 -293.621778) (xy 77.873006 -293.573994) (xy 77.869046 -293.52494) (xy 77.530198 -293.52494)
			(xy 77.529703 -293.549547) (xy 77.521808 -293.598124) (xy 77.506224 -293.644805) (xy 77.483353 -293.688382)
			(xy 77.453788 -293.727726) (xy 77.418295 -293.761818) (xy 77.377792 -293.789774) (xy 77.33333 -293.810872)
			(xy 77.286059 -293.824564) (xy 77.237204 -293.830496) (xy 77.188029 -293.828515) (xy 77.13981 -293.818671)
			(xy 77.093794 -293.801219) (xy 77.051173 -293.776612) (xy 77.013052 -293.745487) (xy 76.980417 -293.70865)
			(xy 76.954114 -293.667054) (xy 76.934823 -293.621778) (xy 76.923046 -293.573994) (xy 76.919086 -293.52494)
			(xy 76.580238 -293.52494) (xy 76.579743 -293.549547) (xy 76.571848 -293.598124) (xy 76.556264 -293.644805)
			(xy 76.533393 -293.688382) (xy 76.503828 -293.727726) (xy 76.468335 -293.761818) (xy 76.427832 -293.789774)
			(xy 76.38337 -293.810872) (xy 76.336099 -293.824564) (xy 76.287244 -293.830496) (xy 76.238069 -293.828515)
			(xy 76.18985 -293.818671) (xy 76.143834 -293.801219) (xy 76.101213 -293.776612) (xy 76.063092 -293.745487)
			(xy 76.030457 -293.70865) (xy 76.004154 -293.667054) (xy 75.984863 -293.621778) (xy 75.973086 -293.573994)
			(xy 75.969126 -293.52494) (xy 75.630278 -293.52494) (xy 75.629783 -293.549547) (xy 75.621888 -293.598124)
			(xy 75.606304 -293.644805) (xy 75.583433 -293.688382) (xy 75.553868 -293.727726) (xy 75.518375 -293.761818)
			(xy 75.477872 -293.789774) (xy 75.43341 -293.810872) (xy 75.386139 -293.824564) (xy 75.337284 -293.830496)
			(xy 75.288109 -293.828515) (xy 75.23989 -293.818671) (xy 75.193874 -293.801219) (xy 75.151253 -293.776612)
			(xy 75.113132 -293.745487) (xy 75.080497 -293.70865) (xy 75.054194 -293.667054) (xy 75.034903 -293.621778)
			(xy 75.023126 -293.573994) (xy 75.019166 -293.52494) (xy 74.680318 -293.52494) (xy 74.679823 -293.549547)
			(xy 74.671928 -293.598124) (xy 74.656344 -293.644805) (xy 74.633473 -293.688382) (xy 74.603908 -293.727726)
			(xy 74.568415 -293.761818) (xy 74.527912 -293.789774) (xy 74.48345 -293.810872) (xy 74.436179 -293.824564)
			(xy 74.387324 -293.830496) (xy 74.338149 -293.828515) (xy 74.28993 -293.818671) (xy 74.243914 -293.801219)
			(xy 74.201293 -293.776612) (xy 74.163172 -293.745487) (xy 74.130537 -293.70865) (xy 74.104234 -293.667054)
			(xy 74.084943 -293.621778) (xy 74.073166 -293.573994) (xy 74.069206 -293.52494) (xy 73.730104 -293.52494)
			(xy 73.729609 -293.549547) (xy 73.721714 -293.598124) (xy 73.70613 -293.644805) (xy 73.683259 -293.688382)
			(xy 73.653694 -293.727726) (xy 73.618201 -293.761818) (xy 73.577698 -293.789774) (xy 73.533236 -293.810872)
			(xy 73.485965 -293.824564) (xy 73.43711 -293.830496) (xy 73.387935 -293.828515) (xy 73.339716 -293.818671)
			(xy 73.2937 -293.801219) (xy 73.251079 -293.776612) (xy 73.212958 -293.745487) (xy 73.180323 -293.70865)
			(xy 73.15402 -293.667054) (xy 73.134729 -293.621778) (xy 73.122952 -293.573994) (xy 73.118992 -293.52494)
			(xy 72.780144 -293.52494) (xy 72.779649 -293.549547) (xy 72.771754 -293.598124) (xy 72.75617 -293.644805)
			(xy 72.733299 -293.688382) (xy 72.703734 -293.727726) (xy 72.668241 -293.761818) (xy 72.627738 -293.789774)
			(xy 72.583276 -293.810872) (xy 72.536005 -293.824564) (xy 72.48715 -293.830496) (xy 72.437975 -293.828515)
			(xy 72.389756 -293.818671) (xy 72.34374 -293.801219) (xy 72.301119 -293.776612) (xy 72.262998 -293.745487)
			(xy 72.230363 -293.70865) (xy 72.20406 -293.667054) (xy 72.184769 -293.621778) (xy 72.172992 -293.573994)
			(xy 72.169032 -293.52494) (xy 71.830184 -293.52494) (xy 71.829689 -293.549547) (xy 71.821794 -293.598124)
			(xy 71.80621 -293.644805) (xy 71.783339 -293.688382) (xy 71.753774 -293.727726) (xy 71.718281 -293.761818)
			(xy 71.677778 -293.789774) (xy 71.633316 -293.810872) (xy 71.586045 -293.824564) (xy 71.53719 -293.830496)
			(xy 71.488015 -293.828515) (xy 71.439796 -293.818671) (xy 71.39378 -293.801219) (xy 71.351159 -293.776612)
			(xy 71.313038 -293.745487) (xy 71.280403 -293.70865) (xy 71.2541 -293.667054) (xy 71.234809 -293.621778)
			(xy 71.223032 -293.573994) (xy 71.219072 -293.52494) (xy 70.880224 -293.52494) (xy 70.879729 -293.549547)
			(xy 70.871834 -293.598124) (xy 70.85625 -293.644805) (xy 70.833379 -293.688382) (xy 70.803814 -293.727726)
			(xy 70.768321 -293.761818) (xy 70.727818 -293.789774) (xy 70.683356 -293.810872) (xy 70.636085 -293.824564)
			(xy 70.58723 -293.830496) (xy 70.538055 -293.828515) (xy 70.489836 -293.818671) (xy 70.44382 -293.801219)
			(xy 70.401199 -293.776612) (xy 70.363078 -293.745487) (xy 70.330443 -293.70865) (xy 70.30414 -293.667054)
			(xy 70.284849 -293.621778) (xy 70.273072 -293.573994) (xy 70.269112 -293.52494) (xy 69.930264 -293.52494)
			(xy 69.929769 -293.549547) (xy 69.921874 -293.598124) (xy 69.90629 -293.644805) (xy 69.883419 -293.688382)
			(xy 69.853854 -293.727726) (xy 69.818361 -293.761818) (xy 69.777858 -293.789774) (xy 69.733396 -293.810872)
			(xy 69.686125 -293.824564) (xy 69.63727 -293.830496) (xy 69.588095 -293.828515) (xy 69.539876 -293.818671)
			(xy 69.49386 -293.801219) (xy 69.451239 -293.776612) (xy 69.413118 -293.745487) (xy 69.380483 -293.70865)
			(xy 69.35418 -293.667054) (xy 69.334889 -293.621778) (xy 69.323112 -293.573994) (xy 69.319152 -293.52494)
			(xy 68.98005 -293.52494) (xy 68.979555 -293.549547) (xy 68.97166 -293.598124) (xy 68.956076 -293.644805)
			(xy 68.933205 -293.688382) (xy 68.90364 -293.727726) (xy 68.868147 -293.761818) (xy 68.827644 -293.789774)
			(xy 68.783182 -293.810872) (xy 68.735911 -293.824564) (xy 68.687056 -293.830496) (xy 68.637881 -293.828515)
			(xy 68.589662 -293.818671) (xy 68.543646 -293.801219) (xy 68.501025 -293.776612) (xy 68.462904 -293.745487)
			(xy 68.430269 -293.70865) (xy 68.403966 -293.667054) (xy 68.384675 -293.621778) (xy 68.372898 -293.573994)
			(xy 68.368938 -293.52494) (xy 67.08013 -293.52494) (xy 67.079635 -293.549547) (xy 67.07174 -293.598124)
			(xy 67.056156 -293.644805) (xy 67.033285 -293.688382) (xy 67.00372 -293.727726) (xy 66.968227 -293.761818)
			(xy 66.927724 -293.789774) (xy 66.883262 -293.810872) (xy 66.835991 -293.824564) (xy 66.787136 -293.830496)
			(xy 66.737961 -293.828515) (xy 66.689742 -293.818671) (xy 66.643726 -293.801219) (xy 66.601105 -293.776612)
			(xy 66.562984 -293.745487) (xy 66.530349 -293.70865) (xy 66.504046 -293.667054) (xy 66.484755 -293.621778)
			(xy 66.472978 -293.573994) (xy 66.469018 -293.52494) (xy 65.18021 -293.52494) (xy 65.179715 -293.549547)
			(xy 65.17182 -293.598124) (xy 65.156236 -293.644805) (xy 65.133365 -293.688382) (xy 65.1038 -293.727726)
			(xy 65.068307 -293.761818) (xy 65.027804 -293.789774) (xy 64.983342 -293.810872) (xy 64.936071 -293.824564)
			(xy 64.887216 -293.830496) (xy 64.838041 -293.828515) (xy 64.789822 -293.818671) (xy 64.743806 -293.801219)
			(xy 64.701185 -293.776612) (xy 64.663064 -293.745487) (xy 64.630429 -293.70865) (xy 64.604126 -293.667054)
			(xy 64.584835 -293.621778) (xy 64.573058 -293.573994) (xy 64.569098 -293.52494) (xy 63.28029 -293.52494)
			(xy 63.279795 -293.549547) (xy 63.2719 -293.598124) (xy 63.256316 -293.644805) (xy 63.233445 -293.688382)
			(xy 63.20388 -293.727726) (xy 63.168387 -293.761818) (xy 63.127884 -293.789774) (xy 63.083422 -293.810872)
			(xy 63.036151 -293.824564) (xy 62.987296 -293.830496) (xy 62.938121 -293.828515) (xy 62.889902 -293.818671)
			(xy 62.843886 -293.801219) (xy 62.801265 -293.776612) (xy 62.763144 -293.745487) (xy 62.730509 -293.70865)
			(xy 62.704206 -293.667054) (xy 62.684915 -293.621778) (xy 62.673138 -293.573994) (xy 62.669178 -293.52494)
			(xy 61.380116 -293.52494) (xy 61.379621 -293.549547) (xy 61.371726 -293.598124) (xy 61.356142 -293.644805)
			(xy 61.333271 -293.688382) (xy 61.303706 -293.727726) (xy 61.268213 -293.761818) (xy 61.22771 -293.789774)
			(xy 61.183248 -293.810872) (xy 61.135977 -293.824564) (xy 61.087122 -293.830496) (xy 61.037947 -293.828515)
			(xy 60.989728 -293.818671) (xy 60.943712 -293.801219) (xy 60.901091 -293.776612) (xy 60.86297 -293.745487)
			(xy 60.830335 -293.70865) (xy 60.804032 -293.667054) (xy 60.784741 -293.621778) (xy 60.772964 -293.573994)
			(xy 60.769004 -293.52494) (xy 58.530236 -293.52494) (xy 58.529741 -293.549547) (xy 58.521846 -293.598124)
			(xy 58.506262 -293.644805) (xy 58.483391 -293.688382) (xy 58.453826 -293.727726) (xy 58.418333 -293.761818)
			(xy 58.37783 -293.789774) (xy 58.333368 -293.810872) (xy 58.286097 -293.824564) (xy 58.237242 -293.830496)
			(xy 58.188067 -293.828515) (xy 58.139848 -293.818671) (xy 58.093832 -293.801219) (xy 58.051211 -293.776612)
			(xy 58.01309 -293.745487) (xy 57.980455 -293.70865) (xy 57.954152 -293.667054) (xy 57.934861 -293.621778)
			(xy 57.923084 -293.573994) (xy 57.919124 -293.52494) (xy 56.630062 -293.52494) (xy 56.629567 -293.549547)
			(xy 56.621672 -293.598124) (xy 56.606088 -293.644805) (xy 56.583217 -293.688382) (xy 56.553652 -293.727726)
			(xy 56.518159 -293.761818) (xy 56.477656 -293.789774) (xy 56.433194 -293.810872) (xy 56.385923 -293.824564)
			(xy 56.337068 -293.830496) (xy 56.287893 -293.828515) (xy 56.239674 -293.818671) (xy 56.193658 -293.801219)
			(xy 56.151037 -293.776612) (xy 56.112916 -293.745487) (xy 56.080281 -293.70865) (xy 56.053978 -293.667054)
			(xy 56.034687 -293.621778) (xy 56.02291 -293.573994) (xy 56.01895 -293.52494) (xy 54.730142 -293.52494)
			(xy 54.729647 -293.549547) (xy 54.721752 -293.598124) (xy 54.706168 -293.644805) (xy 54.683297 -293.688382)
			(xy 54.653732 -293.727726) (xy 54.618239 -293.761818) (xy 54.577736 -293.789774) (xy 54.533274 -293.810872)
			(xy 54.486003 -293.824564) (xy 54.437148 -293.830496) (xy 54.387973 -293.828515) (xy 54.339754 -293.818671)
			(xy 54.293738 -293.801219) (xy 54.251117 -293.776612) (xy 54.212996 -293.745487) (xy 54.180361 -293.70865)
			(xy 54.154058 -293.667054) (xy 54.134767 -293.621778) (xy 54.12299 -293.573994) (xy 54.11903 -293.52494)
			(xy 52.830222 -293.52494) (xy 52.829727 -293.549547) (xy 52.821832 -293.598124) (xy 52.806248 -293.644805)
			(xy 52.783377 -293.688382) (xy 52.753812 -293.727726) (xy 52.718319 -293.761818) (xy 52.677816 -293.789774)
			(xy 52.633354 -293.810872) (xy 52.586083 -293.824564) (xy 52.537228 -293.830496) (xy 52.488053 -293.828515)
			(xy 52.439834 -293.818671) (xy 52.393818 -293.801219) (xy 52.351197 -293.776612) (xy 52.313076 -293.745487)
			(xy 52.280441 -293.70865) (xy 52.254138 -293.667054) (xy 52.234847 -293.621778) (xy 52.22307 -293.573994)
			(xy 52.21911 -293.52494) (xy 50.930302 -293.52494) (xy 50.929807 -293.549547) (xy 50.921912 -293.598124)
			(xy 50.906328 -293.644805) (xy 50.883457 -293.688382) (xy 50.853892 -293.727726) (xy 50.818399 -293.761818)
			(xy 50.777896 -293.789774) (xy 50.733434 -293.810872) (xy 50.686163 -293.824564) (xy 50.637308 -293.830496)
			(xy 50.588133 -293.828515) (xy 50.539914 -293.818671) (xy 50.493898 -293.801219) (xy 50.451277 -293.776612)
			(xy 50.413156 -293.745487) (xy 50.380521 -293.70865) (xy 50.354218 -293.667054) (xy 50.334927 -293.621778)
			(xy 50.32315 -293.573994) (xy 50.31919 -293.52494) (xy 49.149254 -293.52494) (xy 49.149254 -294.4749)
			(xy 49.368976 -294.4749) (xy 49.372936 -294.425846) (xy 49.384713 -294.378062) (xy 49.404004 -294.332786)
			(xy 49.430307 -294.29119) (xy 49.462942 -294.254353) (xy 49.501063 -294.223228) (xy 49.543684 -294.198621)
			(xy 49.5897 -294.181169) (xy 49.637919 -294.171325) (xy 49.687094 -294.169344) (xy 49.735949 -294.175276)
			(xy 49.78322 -294.188968) (xy 49.827682 -294.210066) (xy 49.868185 -294.238022) (xy 49.903678 -294.272114)
			(xy 49.933243 -294.311458) (xy 49.956114 -294.355035) (xy 49.971698 -294.401716) (xy 49.979593 -294.450293)
			(xy 49.980088 -294.4749) (xy 51.26915 -294.4749) (xy 51.27311 -294.425846) (xy 51.284887 -294.378062)
			(xy 51.304178 -294.332786) (xy 51.330481 -294.29119) (xy 51.363116 -294.254353) (xy 51.401237 -294.223228)
			(xy 51.443858 -294.198621) (xy 51.489874 -294.181169) (xy 51.538093 -294.171325) (xy 51.587268 -294.169344)
			(xy 51.636123 -294.175276) (xy 51.683394 -294.188968) (xy 51.727856 -294.210066) (xy 51.768359 -294.238022)
			(xy 51.803852 -294.272114) (xy 51.833417 -294.311458) (xy 51.856288 -294.355035) (xy 51.871872 -294.401716)
			(xy 51.879767 -294.450293) (xy 51.880262 -294.4749) (xy 53.16907 -294.4749) (xy 53.17303 -294.425846)
			(xy 53.184807 -294.378062) (xy 53.204098 -294.332786) (xy 53.230401 -294.29119) (xy 53.263036 -294.254353)
			(xy 53.301157 -294.223228) (xy 53.343778 -294.198621) (xy 53.389794 -294.181169) (xy 53.438013 -294.171325)
			(xy 53.487188 -294.169344) (xy 53.536043 -294.175276) (xy 53.583314 -294.188968) (xy 53.627776 -294.210066)
			(xy 53.668279 -294.238022) (xy 53.703772 -294.272114) (xy 53.733337 -294.311458) (xy 53.756208 -294.355035)
			(xy 53.771792 -294.401716) (xy 53.779687 -294.450293) (xy 53.780182 -294.4749) (xy 55.06899 -294.4749)
			(xy 55.07295 -294.425846) (xy 55.084727 -294.378062) (xy 55.104018 -294.332786) (xy 55.130321 -294.29119)
			(xy 55.162956 -294.254353) (xy 55.201077 -294.223228) (xy 55.243698 -294.198621) (xy 55.289714 -294.181169)
			(xy 55.337933 -294.171325) (xy 55.387108 -294.169344) (xy 55.435963 -294.175276) (xy 55.483234 -294.188968)
			(xy 55.527696 -294.210066) (xy 55.568199 -294.238022) (xy 55.603692 -294.272114) (xy 55.633257 -294.311458)
			(xy 55.656128 -294.355035) (xy 55.671712 -294.401716) (xy 55.679607 -294.450293) (xy 55.680102 -294.4749)
			(xy 56.969164 -294.4749) (xy 56.973124 -294.425846) (xy 56.984901 -294.378062) (xy 57.004192 -294.332786)
			(xy 57.030495 -294.29119) (xy 57.06313 -294.254353) (xy 57.101251 -294.223228) (xy 57.143872 -294.198621)
			(xy 57.189888 -294.181169) (xy 57.238107 -294.171325) (xy 57.287282 -294.169344) (xy 57.336137 -294.175276)
			(xy 57.383408 -294.188968) (xy 57.42787 -294.210066) (xy 57.468373 -294.238022) (xy 57.503866 -294.272114)
			(xy 57.533431 -294.311458) (xy 57.556302 -294.355035) (xy 57.571886 -294.401716) (xy 57.579781 -294.450293)
			(xy 57.580276 -294.4749) (xy 59.819044 -294.4749) (xy 59.823004 -294.425846) (xy 59.834781 -294.378062)
			(xy 59.854072 -294.332786) (xy 59.880375 -294.29119) (xy 59.91301 -294.254353) (xy 59.951131 -294.223228)
			(xy 59.993752 -294.198621) (xy 60.039768 -294.181169) (xy 60.087987 -294.171325) (xy 60.137162 -294.169344)
			(xy 60.186017 -294.175276) (xy 60.233288 -294.188968) (xy 60.27775 -294.210066) (xy 60.318253 -294.238022)
			(xy 60.353746 -294.272114) (xy 60.383311 -294.311458) (xy 60.406182 -294.355035) (xy 60.421766 -294.401716)
			(xy 60.429661 -294.450293) (xy 60.430156 -294.4749) (xy 61.718964 -294.4749) (xy 61.722924 -294.425846)
			(xy 61.734701 -294.378062) (xy 61.753992 -294.332786) (xy 61.780295 -294.29119) (xy 61.81293 -294.254353)
			(xy 61.851051 -294.223228) (xy 61.893672 -294.198621) (xy 61.939688 -294.181169) (xy 61.987907 -294.171325)
			(xy 62.037082 -294.169344) (xy 62.085937 -294.175276) (xy 62.133208 -294.188968) (xy 62.17767 -294.210066)
			(xy 62.218173 -294.238022) (xy 62.253666 -294.272114) (xy 62.283231 -294.311458) (xy 62.306102 -294.355035)
			(xy 62.321686 -294.401716) (xy 62.329581 -294.450293) (xy 62.330076 -294.4749) (xy 63.619138 -294.4749)
			(xy 63.623098 -294.425846) (xy 63.634875 -294.378062) (xy 63.654166 -294.332786) (xy 63.680469 -294.29119)
			(xy 63.713104 -294.254353) (xy 63.751225 -294.223228) (xy 63.793846 -294.198621) (xy 63.839862 -294.181169)
			(xy 63.888081 -294.171325) (xy 63.937256 -294.169344) (xy 63.986111 -294.175276) (xy 64.033382 -294.188968)
			(xy 64.077844 -294.210066) (xy 64.118347 -294.238022) (xy 64.15384 -294.272114) (xy 64.183405 -294.311458)
			(xy 64.206276 -294.355035) (xy 64.22186 -294.401716) (xy 64.229755 -294.450293) (xy 64.23025 -294.4749)
			(xy 65.519058 -294.4749) (xy 65.523018 -294.425846) (xy 65.534795 -294.378062) (xy 65.554086 -294.332786)
			(xy 65.580389 -294.29119) (xy 65.613024 -294.254353) (xy 65.651145 -294.223228) (xy 65.693766 -294.198621)
			(xy 65.739782 -294.181169) (xy 65.788001 -294.171325) (xy 65.837176 -294.169344) (xy 65.886031 -294.175276)
			(xy 65.933302 -294.188968) (xy 65.977764 -294.210066) (xy 66.018267 -294.238022) (xy 66.05376 -294.272114)
			(xy 66.083325 -294.311458) (xy 66.106196 -294.355035) (xy 66.12178 -294.401716) (xy 66.129675 -294.450293)
			(xy 66.13017 -294.4749) (xy 66.469018 -294.4749) (xy 66.472978 -294.425846) (xy 66.484755 -294.378062)
			(xy 66.504046 -294.332786) (xy 66.530349 -294.29119) (xy 66.562984 -294.254353) (xy 66.601105 -294.223228)
			(xy 66.643726 -294.198621) (xy 66.689742 -294.181169) (xy 66.737961 -294.171325) (xy 66.787136 -294.169344)
			(xy 66.835991 -294.175276) (xy 66.883262 -294.188968) (xy 66.927724 -294.210066) (xy 66.968227 -294.238022)
			(xy 67.00372 -294.272114) (xy 67.033285 -294.311458) (xy 67.056156 -294.355035) (xy 67.07174 -294.401716)
			(xy 67.079635 -294.450293) (xy 67.08013 -294.4749) (xy 67.418978 -294.4749) (xy 67.422938 -294.425846)
			(xy 67.434715 -294.378062) (xy 67.454006 -294.332786) (xy 67.480309 -294.29119) (xy 67.512944 -294.254353)
			(xy 67.551065 -294.223228) (xy 67.593686 -294.198621) (xy 67.639702 -294.181169) (xy 67.687921 -294.171325)
			(xy 67.737096 -294.169344) (xy 67.785951 -294.175276) (xy 67.833222 -294.188968) (xy 67.877684 -294.210066)
			(xy 67.918187 -294.238022) (xy 67.95368 -294.272114) (xy 67.983245 -294.311458) (xy 68.006116 -294.355035)
			(xy 68.0217 -294.401716) (xy 68.029595 -294.450293) (xy 68.03009 -294.4749) (xy 68.368938 -294.4749)
			(xy 68.372898 -294.425846) (xy 68.384675 -294.378062) (xy 68.403966 -294.332786) (xy 68.430269 -294.29119)
			(xy 68.462904 -294.254353) (xy 68.501025 -294.223228) (xy 68.543646 -294.198621) (xy 68.589662 -294.181169)
			(xy 68.637881 -294.171325) (xy 68.687056 -294.169344) (xy 68.735911 -294.175276) (xy 68.783182 -294.188968)
			(xy 68.827644 -294.210066) (xy 68.868147 -294.238022) (xy 68.90364 -294.272114) (xy 68.933205 -294.311458)
			(xy 68.956076 -294.355035) (xy 68.97166 -294.401716) (xy 68.979555 -294.450293) (xy 68.98005 -294.4749)
			(xy 69.319152 -294.4749) (xy 69.323112 -294.425846) (xy 69.334889 -294.378062) (xy 69.35418 -294.332786)
			(xy 69.380483 -294.29119) (xy 69.413118 -294.254353) (xy 69.451239 -294.223228) (xy 69.49386 -294.198621)
			(xy 69.539876 -294.181169) (xy 69.588095 -294.171325) (xy 69.63727 -294.169344) (xy 69.686125 -294.175276)
			(xy 69.733396 -294.188968) (xy 69.777858 -294.210066) (xy 69.818361 -294.238022) (xy 69.853854 -294.272114)
			(xy 69.883419 -294.311458) (xy 69.90629 -294.355035) (xy 69.921874 -294.401716) (xy 69.929769 -294.450293)
			(xy 69.930264 -294.4749) (xy 70.269112 -294.4749) (xy 70.273072 -294.425846) (xy 70.284849 -294.378062)
			(xy 70.30414 -294.332786) (xy 70.330443 -294.29119) (xy 70.363078 -294.254353) (xy 70.401199 -294.223228)
			(xy 70.44382 -294.198621) (xy 70.489836 -294.181169) (xy 70.538055 -294.171325) (xy 70.58723 -294.169344)
			(xy 70.636085 -294.175276) (xy 70.683356 -294.188968) (xy 70.727818 -294.210066) (xy 70.768321 -294.238022)
			(xy 70.803814 -294.272114) (xy 70.833379 -294.311458) (xy 70.85625 -294.355035) (xy 70.871834 -294.401716)
			(xy 70.879729 -294.450293) (xy 70.880224 -294.4749) (xy 71.219072 -294.4749) (xy 71.223032 -294.425846)
			(xy 71.234809 -294.378062) (xy 71.2541 -294.332786) (xy 71.280403 -294.29119) (xy 71.313038 -294.254353)
			(xy 71.351159 -294.223228) (xy 71.39378 -294.198621) (xy 71.439796 -294.181169) (xy 71.488015 -294.171325)
			(xy 71.53719 -294.169344) (xy 71.586045 -294.175276) (xy 71.633316 -294.188968) (xy 71.677778 -294.210066)
			(xy 71.718281 -294.238022) (xy 71.753774 -294.272114) (xy 71.783339 -294.311458) (xy 71.80621 -294.355035)
			(xy 71.821794 -294.401716) (xy 71.829689 -294.450293) (xy 71.830184 -294.4749) (xy 72.169032 -294.4749)
			(xy 72.172992 -294.425846) (xy 72.184769 -294.378062) (xy 72.20406 -294.332786) (xy 72.230363 -294.29119)
			(xy 72.262998 -294.254353) (xy 72.301119 -294.223228) (xy 72.34374 -294.198621) (xy 72.389756 -294.181169)
			(xy 72.437975 -294.171325) (xy 72.48715 -294.169344) (xy 72.536005 -294.175276) (xy 72.583276 -294.188968)
			(xy 72.627738 -294.210066) (xy 72.668241 -294.238022) (xy 72.703734 -294.272114) (xy 72.733299 -294.311458)
			(xy 72.75617 -294.355035) (xy 72.771754 -294.401716) (xy 72.779649 -294.450293) (xy 72.780144 -294.4749)
			(xy 73.118992 -294.4749) (xy 73.122952 -294.425846) (xy 73.134729 -294.378062) (xy 73.15402 -294.332786)
			(xy 73.180323 -294.29119) (xy 73.212958 -294.254353) (xy 73.251079 -294.223228) (xy 73.2937 -294.198621)
			(xy 73.339716 -294.181169) (xy 73.387935 -294.171325) (xy 73.43711 -294.169344) (xy 73.485965 -294.175276)
			(xy 73.533236 -294.188968) (xy 73.577698 -294.210066) (xy 73.618201 -294.238022) (xy 73.653694 -294.272114)
			(xy 73.683259 -294.311458) (xy 73.70613 -294.355035) (xy 73.721714 -294.401716) (xy 73.729609 -294.450293)
			(xy 73.730104 -294.4749) (xy 74.068952 -294.4749) (xy 74.072912 -294.425846) (xy 74.084689 -294.378062)
			(xy 74.10398 -294.332786) (xy 74.130283 -294.29119) (xy 74.162918 -294.254353) (xy 74.201039 -294.223228)
			(xy 74.24366 -294.198621) (xy 74.289676 -294.181169) (xy 74.337895 -294.171325) (xy 74.38707 -294.169344)
			(xy 74.435925 -294.175276) (xy 74.483196 -294.188968) (xy 74.527658 -294.210066) (xy 74.568161 -294.238022)
			(xy 74.603654 -294.272114) (xy 74.633219 -294.311458) (xy 74.65609 -294.355035) (xy 74.671674 -294.401716)
			(xy 74.679569 -294.450293) (xy 74.680064 -294.4749) (xy 75.019166 -294.4749) (xy 75.023126 -294.425846)
			(xy 75.034903 -294.378062) (xy 75.054194 -294.332786) (xy 75.080497 -294.29119) (xy 75.113132 -294.254353)
			(xy 75.151253 -294.223228) (xy 75.193874 -294.198621) (xy 75.23989 -294.181169) (xy 75.288109 -294.171325)
			(xy 75.337284 -294.169344) (xy 75.386139 -294.175276) (xy 75.43341 -294.188968) (xy 75.477872 -294.210066)
			(xy 75.518375 -294.238022) (xy 75.553868 -294.272114) (xy 75.583433 -294.311458) (xy 75.606304 -294.355035)
			(xy 75.621888 -294.401716) (xy 75.629783 -294.450293) (xy 75.630278 -294.4749) (xy 75.969126 -294.4749)
			(xy 75.973086 -294.425846) (xy 75.984863 -294.378062) (xy 76.004154 -294.332786) (xy 76.030457 -294.29119)
			(xy 76.063092 -294.254353) (xy 76.101213 -294.223228) (xy 76.143834 -294.198621) (xy 76.18985 -294.181169)
			(xy 76.238069 -294.171325) (xy 76.287244 -294.169344) (xy 76.336099 -294.175276) (xy 76.38337 -294.188968)
			(xy 76.427832 -294.210066) (xy 76.468335 -294.238022) (xy 76.503828 -294.272114) (xy 76.533393 -294.311458)
			(xy 76.556264 -294.355035) (xy 76.571848 -294.401716) (xy 76.579743 -294.450293) (xy 76.580238 -294.4749)
			(xy 76.919086 -294.4749) (xy 76.923046 -294.425846) (xy 76.934823 -294.378062) (xy 76.954114 -294.332786)
			(xy 76.980417 -294.29119) (xy 77.013052 -294.254353) (xy 77.051173 -294.223228) (xy 77.093794 -294.198621)
			(xy 77.13981 -294.181169) (xy 77.188029 -294.171325) (xy 77.237204 -294.169344) (xy 77.286059 -294.175276)
			(xy 77.33333 -294.188968) (xy 77.377792 -294.210066) (xy 77.418295 -294.238022) (xy 77.453788 -294.272114)
			(xy 77.483353 -294.311458) (xy 77.506224 -294.355035) (xy 77.521808 -294.401716) (xy 77.529703 -294.450293)
			(xy 77.530198 -294.4749) (xy 77.869046 -294.4749) (xy 77.873006 -294.425846) (xy 77.884783 -294.378062)
			(xy 77.904074 -294.332786) (xy 77.930377 -294.29119) (xy 77.963012 -294.254353) (xy 78.001133 -294.223228)
			(xy 78.043754 -294.198621) (xy 78.08977 -294.181169) (xy 78.137989 -294.171325) (xy 78.187164 -294.169344)
			(xy 78.236019 -294.175276) (xy 78.28329 -294.188968) (xy 78.327752 -294.210066) (xy 78.368255 -294.238022)
			(xy 78.403748 -294.272114) (xy 78.433313 -294.311458) (xy 78.456184 -294.355035) (xy 78.471768 -294.401716)
			(xy 78.479663 -294.450293) (xy 78.480158 -294.4749) (xy 78.819006 -294.4749) (xy 78.822966 -294.425846)
			(xy 78.834743 -294.378062) (xy 78.854034 -294.332786) (xy 78.880337 -294.29119) (xy 78.912972 -294.254353)
			(xy 78.951093 -294.223228) (xy 78.993714 -294.198621) (xy 79.03973 -294.181169) (xy 79.087949 -294.171325)
			(xy 79.137124 -294.169344) (xy 79.185979 -294.175276) (xy 79.23325 -294.188968) (xy 79.277712 -294.210066)
			(xy 79.318215 -294.238022) (xy 79.353708 -294.272114) (xy 79.383273 -294.311458) (xy 79.406144 -294.355035)
			(xy 79.421728 -294.401716) (xy 79.429623 -294.450293) (xy 79.430118 -294.4749) (xy 79.768966 -294.4749)
			(xy 79.772926 -294.425846) (xy 79.784703 -294.378062) (xy 79.803994 -294.332786) (xy 79.830297 -294.29119)
			(xy 79.862932 -294.254353) (xy 79.901053 -294.223228) (xy 79.943674 -294.198621) (xy 79.98969 -294.181169)
			(xy 80.037909 -294.171325) (xy 80.087084 -294.169344) (xy 80.135939 -294.175276) (xy 80.18321 -294.188968)
			(xy 80.227672 -294.210066) (xy 80.268175 -294.238022) (xy 80.303668 -294.272114) (xy 80.333233 -294.311458)
			(xy 80.356104 -294.355035) (xy 80.371688 -294.401716) (xy 80.379583 -294.450293) (xy 80.380078 -294.4749)
			(xy 80.71918 -294.4749) (xy 80.72314 -294.425846) (xy 80.734917 -294.378062) (xy 80.754208 -294.332786)
			(xy 80.780511 -294.29119) (xy 80.813146 -294.254353) (xy 80.851267 -294.223228) (xy 80.893888 -294.198621)
			(xy 80.939904 -294.181169) (xy 80.988123 -294.171325) (xy 81.037298 -294.169344) (xy 81.086153 -294.175276)
			(xy 81.133424 -294.188968) (xy 81.177886 -294.210066) (xy 81.218389 -294.238022) (xy 81.253882 -294.272114)
			(xy 81.283447 -294.311458) (xy 81.306318 -294.355035) (xy 81.321902 -294.401716) (xy 81.329797 -294.450293)
			(xy 81.330292 -294.4749) (xy 81.66914 -294.4749) (xy 81.6731 -294.425846) (xy 81.684877 -294.378062)
			(xy 81.704168 -294.332786) (xy 81.730471 -294.29119) (xy 81.763106 -294.254353) (xy 81.801227 -294.223228)
			(xy 81.843848 -294.198621) (xy 81.889864 -294.181169) (xy 81.938083 -294.171325) (xy 81.987258 -294.169344)
			(xy 82.036113 -294.175276) (xy 82.083384 -294.188968) (xy 82.127846 -294.210066) (xy 82.168349 -294.238022)
			(xy 82.203842 -294.272114) (xy 82.233407 -294.311458) (xy 82.256278 -294.355035) (xy 82.271862 -294.401716)
			(xy 82.279757 -294.450293) (xy 82.280252 -294.4749) (xy 82.6191 -294.4749) (xy 82.62306 -294.425846)
			(xy 82.634837 -294.378062) (xy 82.654128 -294.332786) (xy 82.680431 -294.29119) (xy 82.713066 -294.254353)
			(xy 82.751187 -294.223228) (xy 82.793808 -294.198621) (xy 82.839824 -294.181169) (xy 82.888043 -294.171325)
			(xy 82.937218 -294.169344) (xy 82.986073 -294.175276) (xy 83.033344 -294.188968) (xy 83.077806 -294.210066)
			(xy 83.118309 -294.238022) (xy 83.153802 -294.272114) (xy 83.183367 -294.311458) (xy 83.206238 -294.355035)
			(xy 83.221822 -294.401716) (xy 83.229717 -294.450293) (xy 83.230212 -294.4749) (xy 83.229717 -294.499507)
			(xy 83.221822 -294.548084) (xy 83.206238 -294.594765) (xy 83.183367 -294.638342) (xy 83.153802 -294.677686)
			(xy 83.120227 -294.709936) (xy 89.163026 -294.709936) (xy 89.163028 -294.655424) (xy 89.170789 -294.601467)
			(xy 89.186151 -294.549165) (xy 89.208799 -294.49958) (xy 89.238274 -294.453724) (xy 89.273975 -294.41253)
			(xy 89.315175 -294.376836) (xy 89.361037 -294.347368) (xy 89.410625 -294.324728) (xy 89.46293 -294.309376)
			(xy 89.516888 -294.301624) (xy 89.544144 -294.301164) (xy 89.569544 -294.301926) (xy 89.584276 -294.302414)
			(xy 89.613006 -294.295872) (xy 89.638673 -294.281399) (xy 89.65914 -294.260202) (xy 89.672703 -294.234044)
			(xy 89.678235 -294.205102) (xy 89.675274 -294.175786) (xy 89.670128 -294.161972) (xy 89.660964 -294.13877)
			(xy 89.648075 -294.090579) (xy 89.641576 -294.041119) (xy 89.641172 -294.016176) (xy 89.641704 -293.988927)
			(xy 89.649463 -293.934983) (xy 89.664821 -293.882693) (xy 89.687463 -293.83312) (xy 89.716931 -293.787275)
			(xy 89.752622 -293.746089) (xy 89.793812 -293.710403) (xy 89.839661 -293.680941) (xy 89.889236 -293.658304)
			(xy 89.941529 -293.642953) (xy 89.995473 -293.635201) (xy 90.049972 -293.635204) (xy 90.103916 -293.642963)
			(xy 90.156206 -293.65832) (xy 90.205779 -293.680963) (xy 90.251624 -293.71043) (xy 90.29281 -293.746121)
			(xy 90.328497 -293.787311) (xy 90.357958 -293.83316) (xy 90.380595 -293.882735) (xy 90.395946 -293.935027)
			(xy 90.402498 -293.980616) (xy 91.28074 -293.980616) (xy 91.284811 -293.924994) (xy 91.296937 -293.870557)
			(xy 91.31686 -293.818466) (xy 91.344156 -293.769831) (xy 91.378242 -293.725688) (xy 91.418391 -293.686979)
			(xy 91.463749 -293.654528) (xy 91.513349 -293.629027) (xy 91.566133 -293.61102) (xy 91.620976 -293.60089)
			(xy 91.67671 -293.598853) (xy 91.732147 -293.604953) (xy 91.786104 -293.619059) (xy 91.837433 -293.640871)
			(xy 91.885039 -293.669925) (xy 91.927907 -293.7056) (xy 91.965124 -293.747137) (xy 91.995897 -293.79365)
			(xy 92.019569 -293.844147) (xy 92.035637 -293.897554) (xy 92.043757 -293.95273) (xy 92.044266 -293.980616)
			(xy 92.043757 -294.008502) (xy 92.035637 -294.063678) (xy 92.019569 -294.117085) (xy 91.995897 -294.167582)
			(xy 91.965124 -294.214095) (xy 91.927907 -294.255632) (xy 91.885039 -294.291307) (xy 91.837433 -294.320361)
			(xy 91.786104 -294.342173) (xy 91.732147 -294.356279) (xy 91.67671 -294.362379) (xy 91.620976 -294.360342)
			(xy 91.566133 -294.350212) (xy 91.513349 -294.332205) (xy 91.463749 -294.306704) (xy 91.418391 -294.274253)
			(xy 91.378242 -294.235544) (xy 91.344156 -294.191401) (xy 91.31686 -294.142766) (xy 91.296937 -294.090675)
			(xy 91.284811 -294.036238) (xy 91.28074 -293.980616) (xy 90.402498 -293.980616) (xy 90.403699 -293.988972)
			(xy 90.403696 -294.043471) (xy 90.395937 -294.097414) (xy 90.38058 -294.149705) (xy 90.357938 -294.199278)
			(xy 90.328471 -294.245123) (xy 90.29278 -294.286309) (xy 90.25159 -294.321996) (xy 90.205741 -294.351458)
			(xy 90.156166 -294.374095) (xy 90.103874 -294.389446) (xy 90.049929 -294.397199) (xy 90.02268 -294.397684)
			(xy 89.99728 -294.396922) (xy 89.982549 -294.396526) (xy 89.953832 -294.403059) (xy 89.928174 -294.417517)
			(xy 89.907712 -294.438698) (xy 89.894147 -294.464839) (xy 89.888608 -294.493765) (xy 89.889394 -294.50157)
			(xy 90.53652 -294.50157) (xy 90.540591 -294.445948) (xy 90.552717 -294.391511) (xy 90.57264 -294.33942)
			(xy 90.599936 -294.290785) (xy 90.634022 -294.246642) (xy 90.674171 -294.207933) (xy 90.719529 -294.175482)
			(xy 90.769129 -294.149981) (xy 90.821913 -294.131974) (xy 90.876756 -294.121844) (xy 90.93249 -294.119807)
			(xy 90.987927 -294.125907) (xy 91.041884 -294.140013) (xy 91.093213 -294.161825) (xy 91.140819 -294.190879)
			(xy 91.183687 -294.226554) (xy 91.220904 -294.268091) (xy 91.251677 -294.314604) (xy 91.275349 -294.365101)
			(xy 91.291417 -294.418508) (xy 91.299537 -294.473684) (xy 91.300046 -294.50157) (xy 91.299537 -294.529456)
			(xy 91.291417 -294.584632) (xy 91.275349 -294.638039) (xy 91.251677 -294.688536) (xy 91.220904 -294.735049)
			(xy 91.183687 -294.776586) (xy 91.140819 -294.812261) (xy 91.093213 -294.841315) (xy 91.041884 -294.863127)
			(xy 90.987927 -294.877233) (xy 90.93249 -294.883333) (xy 90.876756 -294.881296) (xy 90.821913 -294.871166)
			(xy 90.769129 -294.853159) (xy 90.719529 -294.827658) (xy 90.674171 -294.795207) (xy 90.634022 -294.756498)
			(xy 90.599936 -294.712355) (xy 90.57264 -294.66372) (xy 90.552717 -294.611629) (xy 90.540591 -294.557192)
			(xy 90.53652 -294.50157) (xy 89.889394 -294.50157) (xy 89.891557 -294.523067) (xy 89.896696 -294.536876)
			(xy 89.905845 -294.560083) (xy 89.91874 -294.608272) (xy 89.925244 -294.65773) (xy 89.925652 -294.682672)
			(xy 89.925175 -294.709928) (xy 89.917421 -294.763886) (xy 89.902066 -294.81619) (xy 89.879424 -294.865778)
			(xy 89.849955 -294.911637) (xy 89.814259 -294.952836) (xy 89.773063 -294.988536) (xy 89.727206 -295.018009)
			(xy 89.67762 -295.040655) (xy 89.625317 -295.056014) (xy 89.57136 -295.063773) (xy 89.516848 -295.063773)
			(xy 89.462891 -295.056016) (xy 89.410587 -295.040658) (xy 89.361001 -295.018012) (xy 89.315143 -294.98854)
			(xy 89.273947 -294.952842) (xy 89.23825 -294.911644) (xy 89.20878 -294.865785) (xy 89.186137 -294.816198)
			(xy 89.170781 -294.763893) (xy 89.163026 -294.709936) (xy 83.120227 -294.709936) (xy 83.118309 -294.711778)
			(xy 83.077806 -294.739734) (xy 83.033344 -294.760832) (xy 82.986073 -294.774524) (xy 82.937218 -294.780456)
			(xy 82.888043 -294.778475) (xy 82.839824 -294.768631) (xy 82.793808 -294.751179) (xy 82.751187 -294.726572)
			(xy 82.713066 -294.695447) (xy 82.680431 -294.65861) (xy 82.654128 -294.617014) (xy 82.634837 -294.571738)
			(xy 82.62306 -294.523954) (xy 82.6191 -294.4749) (xy 82.280252 -294.4749) (xy 82.279757 -294.499507)
			(xy 82.271862 -294.548084) (xy 82.256278 -294.594765) (xy 82.233407 -294.638342) (xy 82.203842 -294.677686)
			(xy 82.168349 -294.711778) (xy 82.127846 -294.739734) (xy 82.083384 -294.760832) (xy 82.036113 -294.774524)
			(xy 81.987258 -294.780456) (xy 81.938083 -294.778475) (xy 81.889864 -294.768631) (xy 81.843848 -294.751179)
			(xy 81.801227 -294.726572) (xy 81.763106 -294.695447) (xy 81.730471 -294.65861) (xy 81.704168 -294.617014)
			(xy 81.684877 -294.571738) (xy 81.6731 -294.523954) (xy 81.66914 -294.4749) (xy 81.330292 -294.4749)
			(xy 81.329797 -294.499507) (xy 81.321902 -294.548084) (xy 81.306318 -294.594765) (xy 81.283447 -294.638342)
			(xy 81.253882 -294.677686) (xy 81.218389 -294.711778) (xy 81.177886 -294.739734) (xy 81.133424 -294.760832)
			(xy 81.086153 -294.774524) (xy 81.037298 -294.780456) (xy 80.988123 -294.778475) (xy 80.939904 -294.768631)
			(xy 80.893888 -294.751179) (xy 80.851267 -294.726572) (xy 80.813146 -294.695447) (xy 80.780511 -294.65861)
			(xy 80.754208 -294.617014) (xy 80.734917 -294.571738) (xy 80.72314 -294.523954) (xy 80.71918 -294.4749)
			(xy 80.380078 -294.4749) (xy 80.379583 -294.499507) (xy 80.371688 -294.548084) (xy 80.356104 -294.594765)
			(xy 80.333233 -294.638342) (xy 80.303668 -294.677686) (xy 80.268175 -294.711778) (xy 80.227672 -294.739734)
			(xy 80.18321 -294.760832) (xy 80.135939 -294.774524) (xy 80.087084 -294.780456) (xy 80.037909 -294.778475)
			(xy 79.98969 -294.768631) (xy 79.943674 -294.751179) (xy 79.901053 -294.726572) (xy 79.862932 -294.695447)
			(xy 79.830297 -294.65861) (xy 79.803994 -294.617014) (xy 79.784703 -294.571738) (xy 79.772926 -294.523954)
			(xy 79.768966 -294.4749) (xy 79.430118 -294.4749) (xy 79.429623 -294.499507) (xy 79.421728 -294.548084)
			(xy 79.406144 -294.594765) (xy 79.383273 -294.638342) (xy 79.353708 -294.677686) (xy 79.318215 -294.711778)
			(xy 79.277712 -294.739734) (xy 79.23325 -294.760832) (xy 79.185979 -294.774524) (xy 79.137124 -294.780456)
			(xy 79.087949 -294.778475) (xy 79.03973 -294.768631) (xy 78.993714 -294.751179) (xy 78.951093 -294.726572)
			(xy 78.912972 -294.695447) (xy 78.880337 -294.65861) (xy 78.854034 -294.617014) (xy 78.834743 -294.571738)
			(xy 78.822966 -294.523954) (xy 78.819006 -294.4749) (xy 78.480158 -294.4749) (xy 78.479663 -294.499507)
			(xy 78.471768 -294.548084) (xy 78.456184 -294.594765) (xy 78.433313 -294.638342) (xy 78.403748 -294.677686)
			(xy 78.368255 -294.711778) (xy 78.327752 -294.739734) (xy 78.28329 -294.760832) (xy 78.236019 -294.774524)
			(xy 78.187164 -294.780456) (xy 78.137989 -294.778475) (xy 78.08977 -294.768631) (xy 78.043754 -294.751179)
			(xy 78.001133 -294.726572) (xy 77.963012 -294.695447) (xy 77.930377 -294.65861) (xy 77.904074 -294.617014)
			(xy 77.884783 -294.571738) (xy 77.873006 -294.523954) (xy 77.869046 -294.4749) (xy 77.530198 -294.4749)
			(xy 77.529703 -294.499507) (xy 77.521808 -294.548084) (xy 77.506224 -294.594765) (xy 77.483353 -294.638342)
			(xy 77.453788 -294.677686) (xy 77.418295 -294.711778) (xy 77.377792 -294.739734) (xy 77.33333 -294.760832)
			(xy 77.286059 -294.774524) (xy 77.237204 -294.780456) (xy 77.188029 -294.778475) (xy 77.13981 -294.768631)
			(xy 77.093794 -294.751179) (xy 77.051173 -294.726572) (xy 77.013052 -294.695447) (xy 76.980417 -294.65861)
			(xy 76.954114 -294.617014) (xy 76.934823 -294.571738) (xy 76.923046 -294.523954) (xy 76.919086 -294.4749)
			(xy 76.580238 -294.4749) (xy 76.579743 -294.499507) (xy 76.571848 -294.548084) (xy 76.556264 -294.594765)
			(xy 76.533393 -294.638342) (xy 76.503828 -294.677686) (xy 76.468335 -294.711778) (xy 76.427832 -294.739734)
			(xy 76.38337 -294.760832) (xy 76.336099 -294.774524) (xy 76.287244 -294.780456) (xy 76.238069 -294.778475)
			(xy 76.18985 -294.768631) (xy 76.143834 -294.751179) (xy 76.101213 -294.726572) (xy 76.063092 -294.695447)
			(xy 76.030457 -294.65861) (xy 76.004154 -294.617014) (xy 75.984863 -294.571738) (xy 75.973086 -294.523954)
			(xy 75.969126 -294.4749) (xy 75.630278 -294.4749) (xy 75.629783 -294.499507) (xy 75.621888 -294.548084)
			(xy 75.606304 -294.594765) (xy 75.583433 -294.638342) (xy 75.553868 -294.677686) (xy 75.518375 -294.711778)
			(xy 75.477872 -294.739734) (xy 75.43341 -294.760832) (xy 75.386139 -294.774524) (xy 75.337284 -294.780456)
			(xy 75.288109 -294.778475) (xy 75.23989 -294.768631) (xy 75.193874 -294.751179) (xy 75.151253 -294.726572)
			(xy 75.113132 -294.695447) (xy 75.080497 -294.65861) (xy 75.054194 -294.617014) (xy 75.034903 -294.571738)
			(xy 75.023126 -294.523954) (xy 75.019166 -294.4749) (xy 74.680064 -294.4749) (xy 74.679569 -294.499507)
			(xy 74.671674 -294.548084) (xy 74.65609 -294.594765) (xy 74.633219 -294.638342) (xy 74.603654 -294.677686)
			(xy 74.568161 -294.711778) (xy 74.527658 -294.739734) (xy 74.483196 -294.760832) (xy 74.435925 -294.774524)
			(xy 74.38707 -294.780456) (xy 74.337895 -294.778475) (xy 74.289676 -294.768631) (xy 74.24366 -294.751179)
			(xy 74.201039 -294.726572) (xy 74.162918 -294.695447) (xy 74.130283 -294.65861) (xy 74.10398 -294.617014)
			(xy 74.084689 -294.571738) (xy 74.072912 -294.523954) (xy 74.068952 -294.4749) (xy 73.730104 -294.4749)
			(xy 73.729609 -294.499507) (xy 73.721714 -294.548084) (xy 73.70613 -294.594765) (xy 73.683259 -294.638342)
			(xy 73.653694 -294.677686) (xy 73.618201 -294.711778) (xy 73.577698 -294.739734) (xy 73.533236 -294.760832)
			(xy 73.485965 -294.774524) (xy 73.43711 -294.780456) (xy 73.387935 -294.778475) (xy 73.339716 -294.768631)
			(xy 73.2937 -294.751179) (xy 73.251079 -294.726572) (xy 73.212958 -294.695447) (xy 73.180323 -294.65861)
			(xy 73.15402 -294.617014) (xy 73.134729 -294.571738) (xy 73.122952 -294.523954) (xy 73.118992 -294.4749)
			(xy 72.780144 -294.4749) (xy 72.779649 -294.499507) (xy 72.771754 -294.548084) (xy 72.75617 -294.594765)
			(xy 72.733299 -294.638342) (xy 72.703734 -294.677686) (xy 72.668241 -294.711778) (xy 72.627738 -294.739734)
			(xy 72.583276 -294.760832) (xy 72.536005 -294.774524) (xy 72.48715 -294.780456) (xy 72.437975 -294.778475)
			(xy 72.389756 -294.768631) (xy 72.34374 -294.751179) (xy 72.301119 -294.726572) (xy 72.262998 -294.695447)
			(xy 72.230363 -294.65861) (xy 72.20406 -294.617014) (xy 72.184769 -294.571738) (xy 72.172992 -294.523954)
			(xy 72.169032 -294.4749) (xy 71.830184 -294.4749) (xy 71.829689 -294.499507) (xy 71.821794 -294.548084)
			(xy 71.80621 -294.594765) (xy 71.783339 -294.638342) (xy 71.753774 -294.677686) (xy 71.718281 -294.711778)
			(xy 71.677778 -294.739734) (xy 71.633316 -294.760832) (xy 71.586045 -294.774524) (xy 71.53719 -294.780456)
			(xy 71.488015 -294.778475) (xy 71.439796 -294.768631) (xy 71.39378 -294.751179) (xy 71.351159 -294.726572)
			(xy 71.313038 -294.695447) (xy 71.280403 -294.65861) (xy 71.2541 -294.617014) (xy 71.234809 -294.571738)
			(xy 71.223032 -294.523954) (xy 71.219072 -294.4749) (xy 70.880224 -294.4749) (xy 70.879729 -294.499507)
			(xy 70.871834 -294.548084) (xy 70.85625 -294.594765) (xy 70.833379 -294.638342) (xy 70.803814 -294.677686)
			(xy 70.768321 -294.711778) (xy 70.727818 -294.739734) (xy 70.683356 -294.760832) (xy 70.636085 -294.774524)
			(xy 70.58723 -294.780456) (xy 70.538055 -294.778475) (xy 70.489836 -294.768631) (xy 70.44382 -294.751179)
			(xy 70.401199 -294.726572) (xy 70.363078 -294.695447) (xy 70.330443 -294.65861) (xy 70.30414 -294.617014)
			(xy 70.284849 -294.571738) (xy 70.273072 -294.523954) (xy 70.269112 -294.4749) (xy 69.930264 -294.4749)
			(xy 69.929769 -294.499507) (xy 69.921874 -294.548084) (xy 69.90629 -294.594765) (xy 69.883419 -294.638342)
			(xy 69.853854 -294.677686) (xy 69.818361 -294.711778) (xy 69.777858 -294.739734) (xy 69.733396 -294.760832)
			(xy 69.686125 -294.774524) (xy 69.63727 -294.780456) (xy 69.588095 -294.778475) (xy 69.539876 -294.768631)
			(xy 69.49386 -294.751179) (xy 69.451239 -294.726572) (xy 69.413118 -294.695447) (xy 69.380483 -294.65861)
			(xy 69.35418 -294.617014) (xy 69.334889 -294.571738) (xy 69.323112 -294.523954) (xy 69.319152 -294.4749)
			(xy 68.98005 -294.4749) (xy 68.979555 -294.499507) (xy 68.97166 -294.548084) (xy 68.956076 -294.594765)
			(xy 68.933205 -294.638342) (xy 68.90364 -294.677686) (xy 68.868147 -294.711778) (xy 68.827644 -294.739734)
			(xy 68.783182 -294.760832) (xy 68.735911 -294.774524) (xy 68.687056 -294.780456) (xy 68.637881 -294.778475)
			(xy 68.589662 -294.768631) (xy 68.543646 -294.751179) (xy 68.501025 -294.726572) (xy 68.462904 -294.695447)
			(xy 68.430269 -294.65861) (xy 68.403966 -294.617014) (xy 68.384675 -294.571738) (xy 68.372898 -294.523954)
			(xy 68.368938 -294.4749) (xy 68.03009 -294.4749) (xy 68.029595 -294.499507) (xy 68.0217 -294.548084)
			(xy 68.006116 -294.594765) (xy 67.983245 -294.638342) (xy 67.95368 -294.677686) (xy 67.918187 -294.711778)
			(xy 67.877684 -294.739734) (xy 67.833222 -294.760832) (xy 67.785951 -294.774524) (xy 67.737096 -294.780456)
			(xy 67.687921 -294.778475) (xy 67.639702 -294.768631) (xy 67.593686 -294.751179) (xy 67.551065 -294.726572)
			(xy 67.512944 -294.695447) (xy 67.480309 -294.65861) (xy 67.454006 -294.617014) (xy 67.434715 -294.571738)
			(xy 67.422938 -294.523954) (xy 67.418978 -294.4749) (xy 67.08013 -294.4749) (xy 67.079635 -294.499507)
			(xy 67.07174 -294.548084) (xy 67.056156 -294.594765) (xy 67.033285 -294.638342) (xy 67.00372 -294.677686)
			(xy 66.968227 -294.711778) (xy 66.927724 -294.739734) (xy 66.883262 -294.760832) (xy 66.835991 -294.774524)
			(xy 66.787136 -294.780456) (xy 66.737961 -294.778475) (xy 66.689742 -294.768631) (xy 66.643726 -294.751179)
			(xy 66.601105 -294.726572) (xy 66.562984 -294.695447) (xy 66.530349 -294.65861) (xy 66.504046 -294.617014)
			(xy 66.484755 -294.571738) (xy 66.472978 -294.523954) (xy 66.469018 -294.4749) (xy 66.13017 -294.4749)
			(xy 66.129675 -294.499507) (xy 66.12178 -294.548084) (xy 66.106196 -294.594765) (xy 66.083325 -294.638342)
			(xy 66.05376 -294.677686) (xy 66.018267 -294.711778) (xy 65.977764 -294.739734) (xy 65.933302 -294.760832)
			(xy 65.886031 -294.774524) (xy 65.837176 -294.780456) (xy 65.788001 -294.778475) (xy 65.739782 -294.768631)
			(xy 65.693766 -294.751179) (xy 65.651145 -294.726572) (xy 65.613024 -294.695447) (xy 65.580389 -294.65861)
			(xy 65.554086 -294.617014) (xy 65.534795 -294.571738) (xy 65.523018 -294.523954) (xy 65.519058 -294.4749)
			(xy 64.23025 -294.4749) (xy 64.229755 -294.499507) (xy 64.22186 -294.548084) (xy 64.206276 -294.594765)
			(xy 64.183405 -294.638342) (xy 64.15384 -294.677686) (xy 64.118347 -294.711778) (xy 64.077844 -294.739734)
			(xy 64.033382 -294.760832) (xy 63.986111 -294.774524) (xy 63.937256 -294.780456) (xy 63.888081 -294.778475)
			(xy 63.839862 -294.768631) (xy 63.793846 -294.751179) (xy 63.751225 -294.726572) (xy 63.713104 -294.695447)
			(xy 63.680469 -294.65861) (xy 63.654166 -294.617014) (xy 63.634875 -294.571738) (xy 63.623098 -294.523954)
			(xy 63.619138 -294.4749) (xy 62.330076 -294.4749) (xy 62.329581 -294.499507) (xy 62.321686 -294.548084)
			(xy 62.306102 -294.594765) (xy 62.283231 -294.638342) (xy 62.253666 -294.677686) (xy 62.218173 -294.711778)
			(xy 62.17767 -294.739734) (xy 62.133208 -294.760832) (xy 62.085937 -294.774524) (xy 62.037082 -294.780456)
			(xy 61.987907 -294.778475) (xy 61.939688 -294.768631) (xy 61.893672 -294.751179) (xy 61.851051 -294.726572)
			(xy 61.81293 -294.695447) (xy 61.780295 -294.65861) (xy 61.753992 -294.617014) (xy 61.734701 -294.571738)
			(xy 61.722924 -294.523954) (xy 61.718964 -294.4749) (xy 60.430156 -294.4749) (xy 60.429661 -294.499507)
			(xy 60.421766 -294.548084) (xy 60.406182 -294.594765) (xy 60.383311 -294.638342) (xy 60.353746 -294.677686)
			(xy 60.318253 -294.711778) (xy 60.27775 -294.739734) (xy 60.233288 -294.760832) (xy 60.186017 -294.774524)
			(xy 60.137162 -294.780456) (xy 60.087987 -294.778475) (xy 60.039768 -294.768631) (xy 59.993752 -294.751179)
			(xy 59.951131 -294.726572) (xy 59.91301 -294.695447) (xy 59.880375 -294.65861) (xy 59.854072 -294.617014)
			(xy 59.834781 -294.571738) (xy 59.823004 -294.523954) (xy 59.819044 -294.4749) (xy 57.580276 -294.4749)
			(xy 57.579781 -294.499507) (xy 57.571886 -294.548084) (xy 57.556302 -294.594765) (xy 57.533431 -294.638342)
			(xy 57.503866 -294.677686) (xy 57.468373 -294.711778) (xy 57.42787 -294.739734) (xy 57.383408 -294.760832)
			(xy 57.336137 -294.774524) (xy 57.287282 -294.780456) (xy 57.238107 -294.778475) (xy 57.189888 -294.768631)
			(xy 57.143872 -294.751179) (xy 57.101251 -294.726572) (xy 57.06313 -294.695447) (xy 57.030495 -294.65861)
			(xy 57.004192 -294.617014) (xy 56.984901 -294.571738) (xy 56.973124 -294.523954) (xy 56.969164 -294.4749)
			(xy 55.680102 -294.4749) (xy 55.679607 -294.499507) (xy 55.671712 -294.548084) (xy 55.656128 -294.594765)
			(xy 55.633257 -294.638342) (xy 55.603692 -294.677686) (xy 55.568199 -294.711778) (xy 55.527696 -294.739734)
			(xy 55.483234 -294.760832) (xy 55.435963 -294.774524) (xy 55.387108 -294.780456) (xy 55.337933 -294.778475)
			(xy 55.289714 -294.768631) (xy 55.243698 -294.751179) (xy 55.201077 -294.726572) (xy 55.162956 -294.695447)
			(xy 55.130321 -294.65861) (xy 55.104018 -294.617014) (xy 55.084727 -294.571738) (xy 55.07295 -294.523954)
			(xy 55.06899 -294.4749) (xy 53.780182 -294.4749) (xy 53.779687 -294.499507) (xy 53.771792 -294.548084)
			(xy 53.756208 -294.594765) (xy 53.733337 -294.638342) (xy 53.703772 -294.677686) (xy 53.668279 -294.711778)
			(xy 53.627776 -294.739734) (xy 53.583314 -294.760832) (xy 53.536043 -294.774524) (xy 53.487188 -294.780456)
			(xy 53.438013 -294.778475) (xy 53.389794 -294.768631) (xy 53.343778 -294.751179) (xy 53.301157 -294.726572)
			(xy 53.263036 -294.695447) (xy 53.230401 -294.65861) (xy 53.204098 -294.617014) (xy 53.184807 -294.571738)
			(xy 53.17303 -294.523954) (xy 53.16907 -294.4749) (xy 51.880262 -294.4749) (xy 51.879767 -294.499507)
			(xy 51.871872 -294.548084) (xy 51.856288 -294.594765) (xy 51.833417 -294.638342) (xy 51.803852 -294.677686)
			(xy 51.768359 -294.711778) (xy 51.727856 -294.739734) (xy 51.683394 -294.760832) (xy 51.636123 -294.774524)
			(xy 51.587268 -294.780456) (xy 51.538093 -294.778475) (xy 51.489874 -294.768631) (xy 51.443858 -294.751179)
			(xy 51.401237 -294.726572) (xy 51.363116 -294.695447) (xy 51.330481 -294.65861) (xy 51.304178 -294.617014)
			(xy 51.284887 -294.571738) (xy 51.27311 -294.523954) (xy 51.26915 -294.4749) (xy 49.980088 -294.4749)
			(xy 49.979593 -294.499507) (xy 49.971698 -294.548084) (xy 49.956114 -294.594765) (xy 49.933243 -294.638342)
			(xy 49.903678 -294.677686) (xy 49.868185 -294.711778) (xy 49.827682 -294.739734) (xy 49.78322 -294.760832)
			(xy 49.735949 -294.774524) (xy 49.687094 -294.780456) (xy 49.637919 -294.778475) (xy 49.5897 -294.768631)
			(xy 49.543684 -294.751179) (xy 49.501063 -294.726572) (xy 49.462942 -294.695447) (xy 49.430307 -294.65861)
			(xy 49.404004 -294.617014) (xy 49.384713 -294.571738) (xy 49.372936 -294.523954) (xy 49.368976 -294.4749)
			(xy 49.149254 -294.4749) (xy 49.149254 -295.355518) (xy 92.615764 -295.355518) (xy 92.619835 -295.299896)
			(xy 92.631961 -295.245459) (xy 92.651884 -295.193368) (xy 92.67918 -295.144733) (xy 92.713266 -295.10059)
			(xy 92.753415 -295.061881) (xy 92.798773 -295.02943) (xy 92.848373 -295.003929) (xy 92.901157 -294.985922)
			(xy 92.956 -294.975792) (xy 93.011734 -294.973755) (xy 93.067171 -294.979855) (xy 93.121128 -294.993961)
			(xy 93.172457 -295.015773) (xy 93.220063 -295.044827) (xy 93.262931 -295.080502) (xy 93.300148 -295.122039)
			(xy 93.330921 -295.168552) (xy 93.354593 -295.219049) (xy 93.370661 -295.272456) (xy 93.378781 -295.327632)
			(xy 93.37929 -295.355518) (xy 93.378781 -295.383404) (xy 93.370661 -295.43858) (xy 93.354593 -295.491987)
			(xy 93.330921 -295.542484) (xy 93.300148 -295.588997) (xy 93.262931 -295.630534) (xy 93.220063 -295.666209)
			(xy 93.172457 -295.695263) (xy 93.121128 -295.717075) (xy 93.067171 -295.731181) (xy 93.011734 -295.737281)
			(xy 92.956 -295.735244) (xy 92.901157 -295.725114) (xy 92.848373 -295.707107) (xy 92.798773 -295.681606)
			(xy 92.753415 -295.649155) (xy 92.713266 -295.610446) (xy 92.67918 -295.566303) (xy 92.651884 -295.517668)
			(xy 92.631961 -295.465577) (xy 92.619835 -295.41114) (xy 92.615764 -295.355518) (xy 49.149254 -295.355518)
			(xy 49.149254 -296.37482) (xy 50.31919 -296.37482) (xy 50.32315 -296.325766) (xy 50.334927 -296.277982)
			(xy 50.354218 -296.232706) (xy 50.380521 -296.19111) (xy 50.413156 -296.154273) (xy 50.451277 -296.123148)
			(xy 50.493898 -296.098541) (xy 50.539914 -296.081089) (xy 50.588133 -296.071245) (xy 50.637308 -296.069264)
			(xy 50.686163 -296.075196) (xy 50.733434 -296.088888) (xy 50.777896 -296.109986) (xy 50.818399 -296.137942)
			(xy 50.853892 -296.172034) (xy 50.883457 -296.211378) (xy 50.906328 -296.254955) (xy 50.921912 -296.301636)
			(xy 50.929807 -296.350213) (xy 50.930302 -296.37482) (xy 52.21911 -296.37482) (xy 52.22307 -296.325766)
			(xy 52.234847 -296.277982) (xy 52.254138 -296.232706) (xy 52.280441 -296.19111) (xy 52.313076 -296.154273)
			(xy 52.351197 -296.123148) (xy 52.393818 -296.098541) (xy 52.439834 -296.081089) (xy 52.488053 -296.071245)
			(xy 52.537228 -296.069264) (xy 52.586083 -296.075196) (xy 52.633354 -296.088888) (xy 52.677816 -296.109986)
			(xy 52.718319 -296.137942) (xy 52.753812 -296.172034) (xy 52.783377 -296.211378) (xy 52.806248 -296.254955)
			(xy 52.821832 -296.301636) (xy 52.829727 -296.350213) (xy 52.830222 -296.37482) (xy 54.11903 -296.37482)
			(xy 54.12299 -296.325766) (xy 54.134767 -296.277982) (xy 54.154058 -296.232706) (xy 54.180361 -296.19111)
			(xy 54.212996 -296.154273) (xy 54.251117 -296.123148) (xy 54.293738 -296.098541) (xy 54.339754 -296.081089)
			(xy 54.387973 -296.071245) (xy 54.437148 -296.069264) (xy 54.486003 -296.075196) (xy 54.533274 -296.088888)
			(xy 54.577736 -296.109986) (xy 54.618239 -296.137942) (xy 54.653732 -296.172034) (xy 54.683297 -296.211378)
			(xy 54.706168 -296.254955) (xy 54.721752 -296.301636) (xy 54.729647 -296.350213) (xy 54.730142 -296.37482)
			(xy 56.019204 -296.37482) (xy 56.023164 -296.325766) (xy 56.034941 -296.277982) (xy 56.054232 -296.232706)
			(xy 56.080535 -296.19111) (xy 56.11317 -296.154273) (xy 56.151291 -296.123148) (xy 56.193912 -296.098541)
			(xy 56.239928 -296.081089) (xy 56.288147 -296.071245) (xy 56.337322 -296.069264) (xy 56.386177 -296.075196)
			(xy 56.433448 -296.088888) (xy 56.47791 -296.109986) (xy 56.518413 -296.137942) (xy 56.553906 -296.172034)
			(xy 56.583471 -296.211378) (xy 56.606342 -296.254955) (xy 56.621926 -296.301636) (xy 56.629821 -296.350213)
			(xy 56.630316 -296.37482) (xy 57.919124 -296.37482) (xy 57.923084 -296.325766) (xy 57.934861 -296.277982)
			(xy 57.954152 -296.232706) (xy 57.980455 -296.19111) (xy 58.01309 -296.154273) (xy 58.051211 -296.123148)
			(xy 58.093832 -296.098541) (xy 58.139848 -296.081089) (xy 58.188067 -296.071245) (xy 58.237242 -296.069264)
			(xy 58.286097 -296.075196) (xy 58.333368 -296.088888) (xy 58.37783 -296.109986) (xy 58.418333 -296.137942)
			(xy 58.453826 -296.172034) (xy 58.483391 -296.211378) (xy 58.506262 -296.254955) (xy 58.521846 -296.301636)
			(xy 58.529741 -296.350213) (xy 58.530236 -296.37482) (xy 60.769004 -296.37482) (xy 60.772964 -296.325766)
			(xy 60.784741 -296.277982) (xy 60.804032 -296.232706) (xy 60.830335 -296.19111) (xy 60.86297 -296.154273)
			(xy 60.901091 -296.123148) (xy 60.943712 -296.098541) (xy 60.989728 -296.081089) (xy 61.037947 -296.071245)
			(xy 61.087122 -296.069264) (xy 61.135977 -296.075196) (xy 61.183248 -296.088888) (xy 61.22771 -296.109986)
			(xy 61.268213 -296.137942) (xy 61.303706 -296.172034) (xy 61.333271 -296.211378) (xy 61.356142 -296.254955)
			(xy 61.371726 -296.301636) (xy 61.379621 -296.350213) (xy 61.380116 -296.37482) (xy 62.669178 -296.37482)
			(xy 62.673138 -296.325766) (xy 62.684915 -296.277982) (xy 62.704206 -296.232706) (xy 62.730509 -296.19111)
			(xy 62.763144 -296.154273) (xy 62.801265 -296.123148) (xy 62.843886 -296.098541) (xy 62.889902 -296.081089)
			(xy 62.938121 -296.071245) (xy 62.987296 -296.069264) (xy 63.036151 -296.075196) (xy 63.083422 -296.088888)
			(xy 63.127884 -296.109986) (xy 63.168387 -296.137942) (xy 63.20388 -296.172034) (xy 63.233445 -296.211378)
			(xy 63.256316 -296.254955) (xy 63.2719 -296.301636) (xy 63.279795 -296.350213) (xy 63.28029 -296.37482)
			(xy 64.569098 -296.37482) (xy 64.573058 -296.325766) (xy 64.584835 -296.277982) (xy 64.604126 -296.232706)
			(xy 64.630429 -296.19111) (xy 64.663064 -296.154273) (xy 64.701185 -296.123148) (xy 64.743806 -296.098541)
			(xy 64.789822 -296.081089) (xy 64.838041 -296.071245) (xy 64.887216 -296.069264) (xy 64.936071 -296.075196)
			(xy 64.983342 -296.088888) (xy 65.027804 -296.109986) (xy 65.068307 -296.137942) (xy 65.1038 -296.172034)
			(xy 65.133365 -296.211378) (xy 65.156236 -296.254955) (xy 65.17182 -296.301636) (xy 65.179715 -296.350213)
			(xy 65.18021 -296.37482) (xy 66.469018 -296.37482) (xy 66.472978 -296.325766) (xy 66.484755 -296.277982)
			(xy 66.504046 -296.232706) (xy 66.530349 -296.19111) (xy 66.562984 -296.154273) (xy 66.601105 -296.123148)
			(xy 66.643726 -296.098541) (xy 66.689742 -296.081089) (xy 66.737961 -296.071245) (xy 66.787136 -296.069264)
			(xy 66.835991 -296.075196) (xy 66.883262 -296.088888) (xy 66.927724 -296.109986) (xy 66.968227 -296.137942)
			(xy 67.00372 -296.172034) (xy 67.033285 -296.211378) (xy 67.056156 -296.254955) (xy 67.07174 -296.301636)
			(xy 67.079635 -296.350213) (xy 67.08013 -296.37482) (xy 67.418978 -296.37482) (xy 67.422938 -296.325766)
			(xy 67.434715 -296.277982) (xy 67.454006 -296.232706) (xy 67.480309 -296.19111) (xy 67.512944 -296.154273)
			(xy 67.551065 -296.123148) (xy 67.593686 -296.098541) (xy 67.639702 -296.081089) (xy 67.687921 -296.071245)
			(xy 67.737096 -296.069264) (xy 67.785951 -296.075196) (xy 67.833222 -296.088888) (xy 67.877684 -296.109986)
			(xy 67.918187 -296.137942) (xy 67.95368 -296.172034) (xy 67.983245 -296.211378) (xy 68.006116 -296.254955)
			(xy 68.0217 -296.301636) (xy 68.029595 -296.350213) (xy 68.03009 -296.37482) (xy 68.368938 -296.37482)
			(xy 68.372898 -296.325766) (xy 68.384675 -296.277982) (xy 68.403966 -296.232706) (xy 68.430269 -296.19111)
			(xy 68.462904 -296.154273) (xy 68.501025 -296.123148) (xy 68.543646 -296.098541) (xy 68.589662 -296.081089)
			(xy 68.637881 -296.071245) (xy 68.687056 -296.069264) (xy 68.735911 -296.075196) (xy 68.783182 -296.088888)
			(xy 68.827644 -296.109986) (xy 68.868147 -296.137942) (xy 68.90364 -296.172034) (xy 68.933205 -296.211378)
			(xy 68.956076 -296.254955) (xy 68.97166 -296.301636) (xy 68.979555 -296.350213) (xy 68.98005 -296.37482)
			(xy 69.319152 -296.37482) (xy 69.323112 -296.325766) (xy 69.334889 -296.277982) (xy 69.35418 -296.232706)
			(xy 69.380483 -296.19111) (xy 69.413118 -296.154273) (xy 69.451239 -296.123148) (xy 69.49386 -296.098541)
			(xy 69.539876 -296.081089) (xy 69.588095 -296.071245) (xy 69.63727 -296.069264) (xy 69.686125 -296.075196)
			(xy 69.733396 -296.088888) (xy 69.777858 -296.109986) (xy 69.818361 -296.137942) (xy 69.853854 -296.172034)
			(xy 69.883419 -296.211378) (xy 69.90629 -296.254955) (xy 69.921874 -296.301636) (xy 69.929769 -296.350213)
			(xy 69.930264 -296.37482) (xy 70.269112 -296.37482) (xy 70.273072 -296.325766) (xy 70.284849 -296.277982)
			(xy 70.30414 -296.232706) (xy 70.330443 -296.19111) (xy 70.363078 -296.154273) (xy 70.401199 -296.123148)
			(xy 70.44382 -296.098541) (xy 70.489836 -296.081089) (xy 70.538055 -296.071245) (xy 70.58723 -296.069264)
			(xy 70.636085 -296.075196) (xy 70.683356 -296.088888) (xy 70.727818 -296.109986) (xy 70.768321 -296.137942)
			(xy 70.803814 -296.172034) (xy 70.833379 -296.211378) (xy 70.85625 -296.254955) (xy 70.871834 -296.301636)
			(xy 70.879729 -296.350213) (xy 70.880224 -296.37482) (xy 71.219072 -296.37482) (xy 71.223032 -296.325766)
			(xy 71.234809 -296.277982) (xy 71.2541 -296.232706) (xy 71.280403 -296.19111) (xy 71.313038 -296.154273)
			(xy 71.351159 -296.123148) (xy 71.39378 -296.098541) (xy 71.439796 -296.081089) (xy 71.488015 -296.071245)
			(xy 71.53719 -296.069264) (xy 71.586045 -296.075196) (xy 71.633316 -296.088888) (xy 71.677778 -296.109986)
			(xy 71.718281 -296.137942) (xy 71.753774 -296.172034) (xy 71.783339 -296.211378) (xy 71.80621 -296.254955)
			(xy 71.821794 -296.301636) (xy 71.829689 -296.350213) (xy 71.830184 -296.37482) (xy 72.169032 -296.37482)
			(xy 72.172992 -296.325766) (xy 72.184769 -296.277982) (xy 72.20406 -296.232706) (xy 72.230363 -296.19111)
			(xy 72.262998 -296.154273) (xy 72.301119 -296.123148) (xy 72.34374 -296.098541) (xy 72.389756 -296.081089)
			(xy 72.437975 -296.071245) (xy 72.48715 -296.069264) (xy 72.536005 -296.075196) (xy 72.583276 -296.088888)
			(xy 72.627738 -296.109986) (xy 72.668241 -296.137942) (xy 72.703734 -296.172034) (xy 72.733299 -296.211378)
			(xy 72.75617 -296.254955) (xy 72.771754 -296.301636) (xy 72.779649 -296.350213) (xy 72.780144 -296.37482)
			(xy 73.118992 -296.37482) (xy 73.122952 -296.325766) (xy 73.134729 -296.277982) (xy 73.15402 -296.232706)
			(xy 73.180323 -296.19111) (xy 73.212958 -296.154273) (xy 73.251079 -296.123148) (xy 73.2937 -296.098541)
			(xy 73.339716 -296.081089) (xy 73.387935 -296.071245) (xy 73.43711 -296.069264) (xy 73.485965 -296.075196)
			(xy 73.533236 -296.088888) (xy 73.577698 -296.109986) (xy 73.618201 -296.137942) (xy 73.653694 -296.172034)
			(xy 73.683259 -296.211378) (xy 73.70613 -296.254955) (xy 73.721714 -296.301636) (xy 73.729609 -296.350213)
			(xy 73.730104 -296.37482) (xy 74.068952 -296.37482) (xy 74.072912 -296.325766) (xy 74.084689 -296.277982)
			(xy 74.10398 -296.232706) (xy 74.130283 -296.19111) (xy 74.162918 -296.154273) (xy 74.201039 -296.123148)
			(xy 74.24366 -296.098541) (xy 74.289676 -296.081089) (xy 74.337895 -296.071245) (xy 74.38707 -296.069264)
			(xy 74.435925 -296.075196) (xy 74.483196 -296.088888) (xy 74.527658 -296.109986) (xy 74.568161 -296.137942)
			(xy 74.603654 -296.172034) (xy 74.633219 -296.211378) (xy 74.65609 -296.254955) (xy 74.671674 -296.301636)
			(xy 74.679569 -296.350213) (xy 74.680064 -296.37482) (xy 75.019166 -296.37482) (xy 75.023126 -296.325766)
			(xy 75.034903 -296.277982) (xy 75.054194 -296.232706) (xy 75.080497 -296.19111) (xy 75.113132 -296.154273)
			(xy 75.151253 -296.123148) (xy 75.193874 -296.098541) (xy 75.23989 -296.081089) (xy 75.288109 -296.071245)
			(xy 75.337284 -296.069264) (xy 75.386139 -296.075196) (xy 75.43341 -296.088888) (xy 75.477872 -296.109986)
			(xy 75.518375 -296.137942) (xy 75.553868 -296.172034) (xy 75.583433 -296.211378) (xy 75.606304 -296.254955)
			(xy 75.621888 -296.301636) (xy 75.629783 -296.350213) (xy 75.630278 -296.37482) (xy 75.969126 -296.37482)
			(xy 75.973086 -296.325766) (xy 75.984863 -296.277982) (xy 76.004154 -296.232706) (xy 76.030457 -296.19111)
			(xy 76.063092 -296.154273) (xy 76.101213 -296.123148) (xy 76.143834 -296.098541) (xy 76.18985 -296.081089)
			(xy 76.238069 -296.071245) (xy 76.287244 -296.069264) (xy 76.336099 -296.075196) (xy 76.38337 -296.088888)
			(xy 76.427832 -296.109986) (xy 76.468335 -296.137942) (xy 76.503828 -296.172034) (xy 76.533393 -296.211378)
			(xy 76.556264 -296.254955) (xy 76.571848 -296.301636) (xy 76.579743 -296.350213) (xy 76.580238 -296.37482)
			(xy 76.919086 -296.37482) (xy 76.923046 -296.325766) (xy 76.934823 -296.277982) (xy 76.954114 -296.232706)
			(xy 76.980417 -296.19111) (xy 77.013052 -296.154273) (xy 77.051173 -296.123148) (xy 77.093794 -296.098541)
			(xy 77.13981 -296.081089) (xy 77.188029 -296.071245) (xy 77.237204 -296.069264) (xy 77.286059 -296.075196)
			(xy 77.33333 -296.088888) (xy 77.377792 -296.109986) (xy 77.418295 -296.137942) (xy 77.453788 -296.172034)
			(xy 77.483353 -296.211378) (xy 77.506224 -296.254955) (xy 77.521808 -296.301636) (xy 77.529703 -296.350213)
			(xy 77.530198 -296.37482) (xy 77.869046 -296.37482) (xy 77.873006 -296.325766) (xy 77.884783 -296.277982)
			(xy 77.904074 -296.232706) (xy 77.930377 -296.19111) (xy 77.963012 -296.154273) (xy 78.001133 -296.123148)
			(xy 78.043754 -296.098541) (xy 78.08977 -296.081089) (xy 78.137989 -296.071245) (xy 78.187164 -296.069264)
			(xy 78.236019 -296.075196) (xy 78.28329 -296.088888) (xy 78.327752 -296.109986) (xy 78.368255 -296.137942)
			(xy 78.403748 -296.172034) (xy 78.433313 -296.211378) (xy 78.456184 -296.254955) (xy 78.471768 -296.301636)
			(xy 78.479663 -296.350213) (xy 78.480158 -296.37482) (xy 78.819006 -296.37482) (xy 78.822966 -296.325766)
			(xy 78.834743 -296.277982) (xy 78.854034 -296.232706) (xy 78.880337 -296.19111) (xy 78.912972 -296.154273)
			(xy 78.951093 -296.123148) (xy 78.993714 -296.098541) (xy 79.03973 -296.081089) (xy 79.087949 -296.071245)
			(xy 79.137124 -296.069264) (xy 79.185979 -296.075196) (xy 79.23325 -296.088888) (xy 79.277712 -296.109986)
			(xy 79.318215 -296.137942) (xy 79.353708 -296.172034) (xy 79.383273 -296.211378) (xy 79.406144 -296.254955)
			(xy 79.421728 -296.301636) (xy 79.429623 -296.350213) (xy 79.430118 -296.37482) (xy 79.768966 -296.37482)
			(xy 79.772926 -296.325766) (xy 79.784703 -296.277982) (xy 79.803994 -296.232706) (xy 79.830297 -296.19111)
			(xy 79.862932 -296.154273) (xy 79.901053 -296.123148) (xy 79.943674 -296.098541) (xy 79.98969 -296.081089)
			(xy 80.037909 -296.071245) (xy 80.087084 -296.069264) (xy 80.135939 -296.075196) (xy 80.18321 -296.088888)
			(xy 80.227672 -296.109986) (xy 80.268175 -296.137942) (xy 80.303668 -296.172034) (xy 80.333233 -296.211378)
			(xy 80.356104 -296.254955) (xy 80.371688 -296.301636) (xy 80.379583 -296.350213) (xy 80.380078 -296.37482)
			(xy 80.71918 -296.37482) (xy 80.72314 -296.325766) (xy 80.734917 -296.277982) (xy 80.754208 -296.232706)
			(xy 80.780511 -296.19111) (xy 80.813146 -296.154273) (xy 80.851267 -296.123148) (xy 80.893888 -296.098541)
			(xy 80.939904 -296.081089) (xy 80.988123 -296.071245) (xy 81.037298 -296.069264) (xy 81.086153 -296.075196)
			(xy 81.133424 -296.088888) (xy 81.177886 -296.109986) (xy 81.218389 -296.137942) (xy 81.253882 -296.172034)
			(xy 81.283447 -296.211378) (xy 81.306318 -296.254955) (xy 81.321902 -296.301636) (xy 81.329797 -296.350213)
			(xy 81.330292 -296.37482) (xy 81.66914 -296.37482) (xy 81.6731 -296.325766) (xy 81.684877 -296.277982)
			(xy 81.704168 -296.232706) (xy 81.730471 -296.19111) (xy 81.763106 -296.154273) (xy 81.801227 -296.123148)
			(xy 81.843848 -296.098541) (xy 81.889864 -296.081089) (xy 81.938083 -296.071245) (xy 81.987258 -296.069264)
			(xy 82.036113 -296.075196) (xy 82.083384 -296.088888) (xy 82.127846 -296.109986) (xy 82.168349 -296.137942)
			(xy 82.203842 -296.172034) (xy 82.233407 -296.211378) (xy 82.256278 -296.254955) (xy 82.271862 -296.301636)
			(xy 82.279757 -296.350213) (xy 82.280252 -296.37482) (xy 82.6191 -296.37482) (xy 82.62306 -296.325766)
			(xy 82.634837 -296.277982) (xy 82.654128 -296.232706) (xy 82.680431 -296.19111) (xy 82.713066 -296.154273)
			(xy 82.751187 -296.123148) (xy 82.793808 -296.098541) (xy 82.839824 -296.081089) (xy 82.888043 -296.071245)
			(xy 82.937218 -296.069264) (xy 82.986073 -296.075196) (xy 83.033344 -296.088888) (xy 83.077806 -296.109986)
			(xy 83.118309 -296.137942) (xy 83.153802 -296.172034) (xy 83.183367 -296.211378) (xy 83.206238 -296.254955)
			(xy 83.221822 -296.301636) (xy 83.229717 -296.350213) (xy 83.230212 -296.37482) (xy 83.229717 -296.399427)
			(xy 83.221822 -296.448004) (xy 83.206238 -296.494685) (xy 83.183367 -296.538262) (xy 83.153802 -296.577606)
			(xy 83.118309 -296.611698) (xy 83.116318 -296.613072) (xy 89.262456 -296.613072) (xy 89.266527 -296.55745)
			(xy 89.278653 -296.503013) (xy 89.298576 -296.450922) (xy 89.325872 -296.402287) (xy 89.359958 -296.358144)
			(xy 89.400107 -296.319435) (xy 89.445465 -296.286984) (xy 89.495065 -296.261483) (xy 89.547849 -296.243476)
			(xy 89.602692 -296.233346) (xy 89.658426 -296.231309) (xy 89.713863 -296.237409) (xy 89.76782 -296.251515)
			(xy 89.819149 -296.273327) (xy 89.866755 -296.302381) (xy 89.909623 -296.338056) (xy 89.94684 -296.379593)
			(xy 89.977613 -296.426106) (xy 90.001285 -296.476603) (xy 90.017353 -296.53001) (xy 90.025473 -296.585186)
			(xy 90.025982 -296.613072) (xy 90.537282 -296.613072) (xy 90.541353 -296.55745) (xy 90.553479 -296.503013)
			(xy 90.573402 -296.450922) (xy 90.600698 -296.402287) (xy 90.634784 -296.358144) (xy 90.674933 -296.319435)
			(xy 90.720291 -296.286984) (xy 90.769891 -296.261483) (xy 90.822675 -296.243476) (xy 90.877518 -296.233346)
			(xy 90.933252 -296.231309) (xy 90.988689 -296.237409) (xy 91.042646 -296.251515) (xy 91.093975 -296.273327)
			(xy 91.141581 -296.302381) (xy 91.184449 -296.338056) (xy 91.221666 -296.379593) (xy 91.252439 -296.426106)
			(xy 91.276111 -296.476603) (xy 91.292179 -296.53001) (xy 91.300299 -296.585186) (xy 91.300808 -296.613072)
			(xy 91.300299 -296.640958) (xy 91.292179 -296.696134) (xy 91.276111 -296.749541) (xy 91.252439 -296.800038)
			(xy 91.221666 -296.846551) (xy 91.184449 -296.888088) (xy 91.141581 -296.923763) (xy 91.093975 -296.952817)
			(xy 91.042646 -296.974629) (xy 90.988689 -296.988735) (xy 90.933252 -296.994835) (xy 90.877518 -296.992798)
			(xy 90.822675 -296.982668) (xy 90.769891 -296.964661) (xy 90.720291 -296.93916) (xy 90.674933 -296.906709)
			(xy 90.634784 -296.868) (xy 90.600698 -296.823857) (xy 90.573402 -296.775222) (xy 90.553479 -296.723131)
			(xy 90.541353 -296.668694) (xy 90.537282 -296.613072) (xy 90.025982 -296.613072) (xy 90.025473 -296.640958)
			(xy 90.017353 -296.696134) (xy 90.001285 -296.749541) (xy 89.977613 -296.800038) (xy 89.94684 -296.846551)
			(xy 89.909623 -296.888088) (xy 89.866755 -296.923763) (xy 89.819149 -296.952817) (xy 89.76782 -296.974629)
			(xy 89.713863 -296.988735) (xy 89.658426 -296.994835) (xy 89.602692 -296.992798) (xy 89.547849 -296.982668)
			(xy 89.495065 -296.964661) (xy 89.445465 -296.93916) (xy 89.400107 -296.906709) (xy 89.359958 -296.868)
			(xy 89.325872 -296.823857) (xy 89.298576 -296.775222) (xy 89.278653 -296.723131) (xy 89.266527 -296.668694)
			(xy 89.262456 -296.613072) (xy 83.116318 -296.613072) (xy 83.077806 -296.639654) (xy 83.033344 -296.660752)
			(xy 82.986073 -296.674444) (xy 82.937218 -296.680376) (xy 82.888043 -296.678395) (xy 82.839824 -296.668551)
			(xy 82.793808 -296.651099) (xy 82.751187 -296.626492) (xy 82.713066 -296.595367) (xy 82.680431 -296.55853)
			(xy 82.654128 -296.516934) (xy 82.634837 -296.471658) (xy 82.62306 -296.423874) (xy 82.6191 -296.37482)
			(xy 82.280252 -296.37482) (xy 82.279757 -296.399427) (xy 82.271862 -296.448004) (xy 82.256278 -296.494685)
			(xy 82.233407 -296.538262) (xy 82.203842 -296.577606) (xy 82.168349 -296.611698) (xy 82.127846 -296.639654)
			(xy 82.083384 -296.660752) (xy 82.036113 -296.674444) (xy 81.987258 -296.680376) (xy 81.938083 -296.678395)
			(xy 81.889864 -296.668551) (xy 81.843848 -296.651099) (xy 81.801227 -296.626492) (xy 81.763106 -296.595367)
			(xy 81.730471 -296.55853) (xy 81.704168 -296.516934) (xy 81.684877 -296.471658) (xy 81.6731 -296.423874)
			(xy 81.66914 -296.37482) (xy 81.330292 -296.37482) (xy 81.329797 -296.399427) (xy 81.321902 -296.448004)
			(xy 81.306318 -296.494685) (xy 81.283447 -296.538262) (xy 81.253882 -296.577606) (xy 81.218389 -296.611698)
			(xy 81.177886 -296.639654) (xy 81.133424 -296.660752) (xy 81.086153 -296.674444) (xy 81.037298 -296.680376)
			(xy 80.988123 -296.678395) (xy 80.939904 -296.668551) (xy 80.893888 -296.651099) (xy 80.851267 -296.626492)
			(xy 80.813146 -296.595367) (xy 80.780511 -296.55853) (xy 80.754208 -296.516934) (xy 80.734917 -296.471658)
			(xy 80.72314 -296.423874) (xy 80.71918 -296.37482) (xy 80.380078 -296.37482) (xy 80.379583 -296.399427)
			(xy 80.371688 -296.448004) (xy 80.356104 -296.494685) (xy 80.333233 -296.538262) (xy 80.303668 -296.577606)
			(xy 80.268175 -296.611698) (xy 80.227672 -296.639654) (xy 80.18321 -296.660752) (xy 80.135939 -296.674444)
			(xy 80.087084 -296.680376) (xy 80.037909 -296.678395) (xy 79.98969 -296.668551) (xy 79.943674 -296.651099)
			(xy 79.901053 -296.626492) (xy 79.862932 -296.595367) (xy 79.830297 -296.55853) (xy 79.803994 -296.516934)
			(xy 79.784703 -296.471658) (xy 79.772926 -296.423874) (xy 79.768966 -296.37482) (xy 79.430118 -296.37482)
			(xy 79.429623 -296.399427) (xy 79.421728 -296.448004) (xy 79.406144 -296.494685) (xy 79.383273 -296.538262)
			(xy 79.353708 -296.577606) (xy 79.318215 -296.611698) (xy 79.277712 -296.639654) (xy 79.23325 -296.660752)
			(xy 79.185979 -296.674444) (xy 79.137124 -296.680376) (xy 79.087949 -296.678395) (xy 79.03973 -296.668551)
			(xy 78.993714 -296.651099) (xy 78.951093 -296.626492) (xy 78.912972 -296.595367) (xy 78.880337 -296.55853)
			(xy 78.854034 -296.516934) (xy 78.834743 -296.471658) (xy 78.822966 -296.423874) (xy 78.819006 -296.37482)
			(xy 78.480158 -296.37482) (xy 78.479663 -296.399427) (xy 78.471768 -296.448004) (xy 78.456184 -296.494685)
			(xy 78.433313 -296.538262) (xy 78.403748 -296.577606) (xy 78.368255 -296.611698) (xy 78.327752 -296.639654)
			(xy 78.28329 -296.660752) (xy 78.236019 -296.674444) (xy 78.187164 -296.680376) (xy 78.137989 -296.678395)
			(xy 78.08977 -296.668551) (xy 78.043754 -296.651099) (xy 78.001133 -296.626492) (xy 77.963012 -296.595367)
			(xy 77.930377 -296.55853) (xy 77.904074 -296.516934) (xy 77.884783 -296.471658) (xy 77.873006 -296.423874)
			(xy 77.869046 -296.37482) (xy 77.530198 -296.37482) (xy 77.529703 -296.399427) (xy 77.521808 -296.448004)
			(xy 77.506224 -296.494685) (xy 77.483353 -296.538262) (xy 77.453788 -296.577606) (xy 77.418295 -296.611698)
			(xy 77.377792 -296.639654) (xy 77.33333 -296.660752) (xy 77.286059 -296.674444) (xy 77.237204 -296.680376)
			(xy 77.188029 -296.678395) (xy 77.13981 -296.668551) (xy 77.093794 -296.651099) (xy 77.051173 -296.626492)
			(xy 77.013052 -296.595367) (xy 76.980417 -296.55853) (xy 76.954114 -296.516934) (xy 76.934823 -296.471658)
			(xy 76.923046 -296.423874) (xy 76.919086 -296.37482) (xy 76.580238 -296.37482) (xy 76.579743 -296.399427)
			(xy 76.571848 -296.448004) (xy 76.556264 -296.494685) (xy 76.533393 -296.538262) (xy 76.503828 -296.577606)
			(xy 76.468335 -296.611698) (xy 76.427832 -296.639654) (xy 76.38337 -296.660752) (xy 76.336099 -296.674444)
			(xy 76.287244 -296.680376) (xy 76.238069 -296.678395) (xy 76.18985 -296.668551) (xy 76.143834 -296.651099)
			(xy 76.101213 -296.626492) (xy 76.063092 -296.595367) (xy 76.030457 -296.55853) (xy 76.004154 -296.516934)
			(xy 75.984863 -296.471658) (xy 75.973086 -296.423874) (xy 75.969126 -296.37482) (xy 75.630278 -296.37482)
			(xy 75.629783 -296.399427) (xy 75.621888 -296.448004) (xy 75.606304 -296.494685) (xy 75.583433 -296.538262)
			(xy 75.553868 -296.577606) (xy 75.518375 -296.611698) (xy 75.477872 -296.639654) (xy 75.43341 -296.660752)
			(xy 75.386139 -296.674444) (xy 75.337284 -296.680376) (xy 75.288109 -296.678395) (xy 75.23989 -296.668551)
			(xy 75.193874 -296.651099) (xy 75.151253 -296.626492) (xy 75.113132 -296.595367) (xy 75.080497 -296.55853)
			(xy 75.054194 -296.516934) (xy 75.034903 -296.471658) (xy 75.023126 -296.423874) (xy 75.019166 -296.37482)
			(xy 74.680064 -296.37482) (xy 74.679569 -296.399427) (xy 74.671674 -296.448004) (xy 74.65609 -296.494685)
			(xy 74.633219 -296.538262) (xy 74.603654 -296.577606) (xy 74.568161 -296.611698) (xy 74.527658 -296.639654)
			(xy 74.483196 -296.660752) (xy 74.435925 -296.674444) (xy 74.38707 -296.680376) (xy 74.337895 -296.678395)
			(xy 74.289676 -296.668551) (xy 74.24366 -296.651099) (xy 74.201039 -296.626492) (xy 74.162918 -296.595367)
			(xy 74.130283 -296.55853) (xy 74.10398 -296.516934) (xy 74.084689 -296.471658) (xy 74.072912 -296.423874)
			(xy 74.068952 -296.37482) (xy 73.730104 -296.37482) (xy 73.729609 -296.399427) (xy 73.721714 -296.448004)
			(xy 73.70613 -296.494685) (xy 73.683259 -296.538262) (xy 73.653694 -296.577606) (xy 73.618201 -296.611698)
			(xy 73.577698 -296.639654) (xy 73.533236 -296.660752) (xy 73.485965 -296.674444) (xy 73.43711 -296.680376)
			(xy 73.387935 -296.678395) (xy 73.339716 -296.668551) (xy 73.2937 -296.651099) (xy 73.251079 -296.626492)
			(xy 73.212958 -296.595367) (xy 73.180323 -296.55853) (xy 73.15402 -296.516934) (xy 73.134729 -296.471658)
			(xy 73.122952 -296.423874) (xy 73.118992 -296.37482) (xy 72.780144 -296.37482) (xy 72.779649 -296.399427)
			(xy 72.771754 -296.448004) (xy 72.75617 -296.494685) (xy 72.733299 -296.538262) (xy 72.703734 -296.577606)
			(xy 72.668241 -296.611698) (xy 72.627738 -296.639654) (xy 72.583276 -296.660752) (xy 72.536005 -296.674444)
			(xy 72.48715 -296.680376) (xy 72.437975 -296.678395) (xy 72.389756 -296.668551) (xy 72.34374 -296.651099)
			(xy 72.301119 -296.626492) (xy 72.262998 -296.595367) (xy 72.230363 -296.55853) (xy 72.20406 -296.516934)
			(xy 72.184769 -296.471658) (xy 72.172992 -296.423874) (xy 72.169032 -296.37482) (xy 71.830184 -296.37482)
			(xy 71.829689 -296.399427) (xy 71.821794 -296.448004) (xy 71.80621 -296.494685) (xy 71.783339 -296.538262)
			(xy 71.753774 -296.577606) (xy 71.718281 -296.611698) (xy 71.677778 -296.639654) (xy 71.633316 -296.660752)
			(xy 71.586045 -296.674444) (xy 71.53719 -296.680376) (xy 71.488015 -296.678395) (xy 71.439796 -296.668551)
			(xy 71.39378 -296.651099) (xy 71.351159 -296.626492) (xy 71.313038 -296.595367) (xy 71.280403 -296.55853)
			(xy 71.2541 -296.516934) (xy 71.234809 -296.471658) (xy 71.223032 -296.423874) (xy 71.219072 -296.37482)
			(xy 70.880224 -296.37482) (xy 70.879729 -296.399427) (xy 70.871834 -296.448004) (xy 70.85625 -296.494685)
			(xy 70.833379 -296.538262) (xy 70.803814 -296.577606) (xy 70.768321 -296.611698) (xy 70.727818 -296.639654)
			(xy 70.683356 -296.660752) (xy 70.636085 -296.674444) (xy 70.58723 -296.680376) (xy 70.538055 -296.678395)
			(xy 70.489836 -296.668551) (xy 70.44382 -296.651099) (xy 70.401199 -296.626492) (xy 70.363078 -296.595367)
			(xy 70.330443 -296.55853) (xy 70.30414 -296.516934) (xy 70.284849 -296.471658) (xy 70.273072 -296.423874)
			(xy 70.269112 -296.37482) (xy 69.930264 -296.37482) (xy 69.929769 -296.399427) (xy 69.921874 -296.448004)
			(xy 69.90629 -296.494685) (xy 69.883419 -296.538262) (xy 69.853854 -296.577606) (xy 69.818361 -296.611698)
			(xy 69.777858 -296.639654) (xy 69.733396 -296.660752) (xy 69.686125 -296.674444) (xy 69.63727 -296.680376)
			(xy 69.588095 -296.678395) (xy 69.539876 -296.668551) (xy 69.49386 -296.651099) (xy 69.451239 -296.626492)
			(xy 69.413118 -296.595367) (xy 69.380483 -296.55853) (xy 69.35418 -296.516934) (xy 69.334889 -296.471658)
			(xy 69.323112 -296.423874) (xy 69.319152 -296.37482) (xy 68.98005 -296.37482) (xy 68.979555 -296.399427)
			(xy 68.97166 -296.448004) (xy 68.956076 -296.494685) (xy 68.933205 -296.538262) (xy 68.90364 -296.577606)
			(xy 68.868147 -296.611698) (xy 68.827644 -296.639654) (xy 68.783182 -296.660752) (xy 68.735911 -296.674444)
			(xy 68.687056 -296.680376) (xy 68.637881 -296.678395) (xy 68.589662 -296.668551) (xy 68.543646 -296.651099)
			(xy 68.501025 -296.626492) (xy 68.462904 -296.595367) (xy 68.430269 -296.55853) (xy 68.403966 -296.516934)
			(xy 68.384675 -296.471658) (xy 68.372898 -296.423874) (xy 68.368938 -296.37482) (xy 68.03009 -296.37482)
			(xy 68.029595 -296.399427) (xy 68.0217 -296.448004) (xy 68.006116 -296.494685) (xy 67.983245 -296.538262)
			(xy 67.95368 -296.577606) (xy 67.918187 -296.611698) (xy 67.877684 -296.639654) (xy 67.833222 -296.660752)
			(xy 67.785951 -296.674444) (xy 67.737096 -296.680376) (xy 67.687921 -296.678395) (xy 67.639702 -296.668551)
			(xy 67.593686 -296.651099) (xy 67.551065 -296.626492) (xy 67.512944 -296.595367) (xy 67.480309 -296.55853)
			(xy 67.454006 -296.516934) (xy 67.434715 -296.471658) (xy 67.422938 -296.423874) (xy 67.418978 -296.37482)
			(xy 67.08013 -296.37482) (xy 67.079635 -296.399427) (xy 67.07174 -296.448004) (xy 67.056156 -296.494685)
			(xy 67.033285 -296.538262) (xy 67.00372 -296.577606) (xy 66.968227 -296.611698) (xy 66.927724 -296.639654)
			(xy 66.883262 -296.660752) (xy 66.835991 -296.674444) (xy 66.787136 -296.680376) (xy 66.737961 -296.678395)
			(xy 66.689742 -296.668551) (xy 66.643726 -296.651099) (xy 66.601105 -296.626492) (xy 66.562984 -296.595367)
			(xy 66.530349 -296.55853) (xy 66.504046 -296.516934) (xy 66.484755 -296.471658) (xy 66.472978 -296.423874)
			(xy 66.469018 -296.37482) (xy 65.18021 -296.37482) (xy 65.179715 -296.399427) (xy 65.17182 -296.448004)
			(xy 65.156236 -296.494685) (xy 65.133365 -296.538262) (xy 65.1038 -296.577606) (xy 65.068307 -296.611698)
			(xy 65.027804 -296.639654) (xy 64.983342 -296.660752) (xy 64.936071 -296.674444) (xy 64.887216 -296.680376)
			(xy 64.838041 -296.678395) (xy 64.789822 -296.668551) (xy 64.743806 -296.651099) (xy 64.701185 -296.626492)
			(xy 64.663064 -296.595367) (xy 64.630429 -296.55853) (xy 64.604126 -296.516934) (xy 64.584835 -296.471658)
			(xy 64.573058 -296.423874) (xy 64.569098 -296.37482) (xy 63.28029 -296.37482) (xy 63.279795 -296.399427)
			(xy 63.2719 -296.448004) (xy 63.256316 -296.494685) (xy 63.233445 -296.538262) (xy 63.20388 -296.577606)
			(xy 63.168387 -296.611698) (xy 63.127884 -296.639654) (xy 63.083422 -296.660752) (xy 63.036151 -296.674444)
			(xy 62.987296 -296.680376) (xy 62.938121 -296.678395) (xy 62.889902 -296.668551) (xy 62.843886 -296.651099)
			(xy 62.801265 -296.626492) (xy 62.763144 -296.595367) (xy 62.730509 -296.55853) (xy 62.704206 -296.516934)
			(xy 62.684915 -296.471658) (xy 62.673138 -296.423874) (xy 62.669178 -296.37482) (xy 61.380116 -296.37482)
			(xy 61.379621 -296.399427) (xy 61.371726 -296.448004) (xy 61.356142 -296.494685) (xy 61.333271 -296.538262)
			(xy 61.303706 -296.577606) (xy 61.268213 -296.611698) (xy 61.22771 -296.639654) (xy 61.183248 -296.660752)
			(xy 61.135977 -296.674444) (xy 61.087122 -296.680376) (xy 61.037947 -296.678395) (xy 60.989728 -296.668551)
			(xy 60.943712 -296.651099) (xy 60.901091 -296.626492) (xy 60.86297 -296.595367) (xy 60.830335 -296.55853)
			(xy 60.804032 -296.516934) (xy 60.784741 -296.471658) (xy 60.772964 -296.423874) (xy 60.769004 -296.37482)
			(xy 58.530236 -296.37482) (xy 58.529741 -296.399427) (xy 58.521846 -296.448004) (xy 58.506262 -296.494685)
			(xy 58.483391 -296.538262) (xy 58.453826 -296.577606) (xy 58.418333 -296.611698) (xy 58.37783 -296.639654)
			(xy 58.333368 -296.660752) (xy 58.286097 -296.674444) (xy 58.237242 -296.680376) (xy 58.188067 -296.678395)
			(xy 58.139848 -296.668551) (xy 58.093832 -296.651099) (xy 58.051211 -296.626492) (xy 58.01309 -296.595367)
			(xy 57.980455 -296.55853) (xy 57.954152 -296.516934) (xy 57.934861 -296.471658) (xy 57.923084 -296.423874)
			(xy 57.919124 -296.37482) (xy 56.630316 -296.37482) (xy 56.629821 -296.399427) (xy 56.621926 -296.448004)
			(xy 56.606342 -296.494685) (xy 56.583471 -296.538262) (xy 56.553906 -296.577606) (xy 56.518413 -296.611698)
			(xy 56.47791 -296.639654) (xy 56.433448 -296.660752) (xy 56.386177 -296.674444) (xy 56.337322 -296.680376)
			(xy 56.288147 -296.678395) (xy 56.239928 -296.668551) (xy 56.193912 -296.651099) (xy 56.151291 -296.626492)
			(xy 56.11317 -296.595367) (xy 56.080535 -296.55853) (xy 56.054232 -296.516934) (xy 56.034941 -296.471658)
			(xy 56.023164 -296.423874) (xy 56.019204 -296.37482) (xy 54.730142 -296.37482) (xy 54.729647 -296.399427)
			(xy 54.721752 -296.448004) (xy 54.706168 -296.494685) (xy 54.683297 -296.538262) (xy 54.653732 -296.577606)
			(xy 54.618239 -296.611698) (xy 54.577736 -296.639654) (xy 54.533274 -296.660752) (xy 54.486003 -296.674444)
			(xy 54.437148 -296.680376) (xy 54.387973 -296.678395) (xy 54.339754 -296.668551) (xy 54.293738 -296.651099)
			(xy 54.251117 -296.626492) (xy 54.212996 -296.595367) (xy 54.180361 -296.55853) (xy 54.154058 -296.516934)
			(xy 54.134767 -296.471658) (xy 54.12299 -296.423874) (xy 54.11903 -296.37482) (xy 52.830222 -296.37482)
			(xy 52.829727 -296.399427) (xy 52.821832 -296.448004) (xy 52.806248 -296.494685) (xy 52.783377 -296.538262)
			(xy 52.753812 -296.577606) (xy 52.718319 -296.611698) (xy 52.677816 -296.639654) (xy 52.633354 -296.660752)
			(xy 52.586083 -296.674444) (xy 52.537228 -296.680376) (xy 52.488053 -296.678395) (xy 52.439834 -296.668551)
			(xy 52.393818 -296.651099) (xy 52.351197 -296.626492) (xy 52.313076 -296.595367) (xy 52.280441 -296.55853)
			(xy 52.254138 -296.516934) (xy 52.234847 -296.471658) (xy 52.22307 -296.423874) (xy 52.21911 -296.37482)
			(xy 50.930302 -296.37482) (xy 50.929807 -296.399427) (xy 50.921912 -296.448004) (xy 50.906328 -296.494685)
			(xy 50.883457 -296.538262) (xy 50.853892 -296.577606) (xy 50.818399 -296.611698) (xy 50.777896 -296.639654)
			(xy 50.733434 -296.660752) (xy 50.686163 -296.674444) (xy 50.637308 -296.680376) (xy 50.588133 -296.678395)
			(xy 50.539914 -296.668551) (xy 50.493898 -296.651099) (xy 50.451277 -296.626492) (xy 50.413156 -296.595367)
			(xy 50.380521 -296.55853) (xy 50.354218 -296.516934) (xy 50.334927 -296.471658) (xy 50.32315 -296.423874)
			(xy 50.31919 -296.37482) (xy 49.149254 -296.37482) (xy 49.149254 -297.32478) (xy 49.368976 -297.32478)
			(xy 49.372936 -297.275726) (xy 49.384713 -297.227942) (xy 49.404004 -297.182666) (xy 49.430307 -297.14107)
			(xy 49.462942 -297.104233) (xy 49.501063 -297.073108) (xy 49.543684 -297.048501) (xy 49.5897 -297.031049)
			(xy 49.637919 -297.021205) (xy 49.687094 -297.019224) (xy 49.735949 -297.025156) (xy 49.78322 -297.038848)
			(xy 49.827682 -297.059946) (xy 49.868185 -297.087902) (xy 49.903678 -297.121994) (xy 49.933243 -297.161338)
			(xy 49.956114 -297.204915) (xy 49.971698 -297.251596) (xy 49.979593 -297.300173) (xy 49.980088 -297.32478)
			(xy 51.26915 -297.32478) (xy 51.27311 -297.275726) (xy 51.284887 -297.227942) (xy 51.304178 -297.182666)
			(xy 51.330481 -297.14107) (xy 51.363116 -297.104233) (xy 51.401237 -297.073108) (xy 51.443858 -297.048501)
			(xy 51.489874 -297.031049) (xy 51.538093 -297.021205) (xy 51.587268 -297.019224) (xy 51.636123 -297.025156)
			(xy 51.683394 -297.038848) (xy 51.727856 -297.059946) (xy 51.768359 -297.087902) (xy 51.803852 -297.121994)
			(xy 51.833417 -297.161338) (xy 51.856288 -297.204915) (xy 51.871872 -297.251596) (xy 51.879767 -297.300173)
			(xy 51.880262 -297.32478) (xy 53.16907 -297.32478) (xy 53.17303 -297.275726) (xy 53.184807 -297.227942)
			(xy 53.204098 -297.182666) (xy 53.230401 -297.14107) (xy 53.263036 -297.104233) (xy 53.301157 -297.073108)
			(xy 53.343778 -297.048501) (xy 53.389794 -297.031049) (xy 53.438013 -297.021205) (xy 53.487188 -297.019224)
			(xy 53.536043 -297.025156) (xy 53.583314 -297.038848) (xy 53.627776 -297.059946) (xy 53.668279 -297.087902)
			(xy 53.703772 -297.121994) (xy 53.733337 -297.161338) (xy 53.756208 -297.204915) (xy 53.771792 -297.251596)
			(xy 53.779687 -297.300173) (xy 53.780182 -297.32478) (xy 55.06899 -297.32478) (xy 55.07295 -297.275726)
			(xy 55.084727 -297.227942) (xy 55.104018 -297.182666) (xy 55.130321 -297.14107) (xy 55.162956 -297.104233)
			(xy 55.201077 -297.073108) (xy 55.243698 -297.048501) (xy 55.289714 -297.031049) (xy 55.337933 -297.021205)
			(xy 55.387108 -297.019224) (xy 55.435963 -297.025156) (xy 55.483234 -297.038848) (xy 55.527696 -297.059946)
			(xy 55.568199 -297.087902) (xy 55.603692 -297.121994) (xy 55.633257 -297.161338) (xy 55.656128 -297.204915)
			(xy 55.671712 -297.251596) (xy 55.679607 -297.300173) (xy 55.680102 -297.32478) (xy 56.969164 -297.32478)
			(xy 56.973124 -297.275726) (xy 56.984901 -297.227942) (xy 57.004192 -297.182666) (xy 57.030495 -297.14107)
			(xy 57.06313 -297.104233) (xy 57.101251 -297.073108) (xy 57.143872 -297.048501) (xy 57.189888 -297.031049)
			(xy 57.238107 -297.021205) (xy 57.287282 -297.019224) (xy 57.336137 -297.025156) (xy 57.383408 -297.038848)
			(xy 57.42787 -297.059946) (xy 57.468373 -297.087902) (xy 57.503866 -297.121994) (xy 57.533431 -297.161338)
			(xy 57.556302 -297.204915) (xy 57.571886 -297.251596) (xy 57.579781 -297.300173) (xy 57.580276 -297.32478)
			(xy 59.819044 -297.32478) (xy 59.823004 -297.275726) (xy 59.834781 -297.227942) (xy 59.854072 -297.182666)
			(xy 59.880375 -297.14107) (xy 59.91301 -297.104233) (xy 59.951131 -297.073108) (xy 59.993752 -297.048501)
			(xy 60.039768 -297.031049) (xy 60.087987 -297.021205) (xy 60.137162 -297.019224) (xy 60.186017 -297.025156)
			(xy 60.233288 -297.038848) (xy 60.27775 -297.059946) (xy 60.318253 -297.087902) (xy 60.353746 -297.121994)
			(xy 60.383311 -297.161338) (xy 60.406182 -297.204915) (xy 60.421766 -297.251596) (xy 60.429661 -297.300173)
			(xy 60.430156 -297.32478) (xy 61.718964 -297.32478) (xy 61.722924 -297.275726) (xy 61.734701 -297.227942)
			(xy 61.753992 -297.182666) (xy 61.780295 -297.14107) (xy 61.81293 -297.104233) (xy 61.851051 -297.073108)
			(xy 61.893672 -297.048501) (xy 61.939688 -297.031049) (xy 61.987907 -297.021205) (xy 62.037082 -297.019224)
			(xy 62.085937 -297.025156) (xy 62.133208 -297.038848) (xy 62.17767 -297.059946) (xy 62.218173 -297.087902)
			(xy 62.253666 -297.121994) (xy 62.283231 -297.161338) (xy 62.306102 -297.204915) (xy 62.321686 -297.251596)
			(xy 62.329581 -297.300173) (xy 62.330076 -297.32478) (xy 63.619138 -297.32478) (xy 63.623098 -297.275726)
			(xy 63.634875 -297.227942) (xy 63.654166 -297.182666) (xy 63.680469 -297.14107) (xy 63.713104 -297.104233)
			(xy 63.751225 -297.073108) (xy 63.793846 -297.048501) (xy 63.839862 -297.031049) (xy 63.888081 -297.021205)
			(xy 63.937256 -297.019224) (xy 63.986111 -297.025156) (xy 64.033382 -297.038848) (xy 64.077844 -297.059946)
			(xy 64.118347 -297.087902) (xy 64.15384 -297.121994) (xy 64.183405 -297.161338) (xy 64.206276 -297.204915)
			(xy 64.22186 -297.251596) (xy 64.229755 -297.300173) (xy 64.23025 -297.32478) (xy 65.519058 -297.32478)
			(xy 65.523018 -297.275726) (xy 65.534795 -297.227942) (xy 65.554086 -297.182666) (xy 65.580389 -297.14107)
			(xy 65.613024 -297.104233) (xy 65.651145 -297.073108) (xy 65.693766 -297.048501) (xy 65.739782 -297.031049)
			(xy 65.788001 -297.021205) (xy 65.837176 -297.019224) (xy 65.886031 -297.025156) (xy 65.933302 -297.038848)
			(xy 65.977764 -297.059946) (xy 66.018267 -297.087902) (xy 66.05376 -297.121994) (xy 66.083325 -297.161338)
			(xy 66.106196 -297.204915) (xy 66.12178 -297.251596) (xy 66.129675 -297.300173) (xy 66.13017 -297.32478)
			(xy 66.469018 -297.32478) (xy 66.472978 -297.275726) (xy 66.484755 -297.227942) (xy 66.504046 -297.182666)
			(xy 66.530349 -297.14107) (xy 66.562984 -297.104233) (xy 66.601105 -297.073108) (xy 66.643726 -297.048501)
			(xy 66.689742 -297.031049) (xy 66.737961 -297.021205) (xy 66.787136 -297.019224) (xy 66.835991 -297.025156)
			(xy 66.883262 -297.038848) (xy 66.927724 -297.059946) (xy 66.968227 -297.087902) (xy 67.00372 -297.121994)
			(xy 67.033285 -297.161338) (xy 67.056156 -297.204915) (xy 67.07174 -297.251596) (xy 67.079635 -297.300173)
			(xy 67.08013 -297.32478) (xy 67.418978 -297.32478) (xy 67.422938 -297.275726) (xy 67.434715 -297.227942)
			(xy 67.454006 -297.182666) (xy 67.480309 -297.14107) (xy 67.512944 -297.104233) (xy 67.551065 -297.073108)
			(xy 67.593686 -297.048501) (xy 67.639702 -297.031049) (xy 67.687921 -297.021205) (xy 67.737096 -297.019224)
			(xy 67.785951 -297.025156) (xy 67.833222 -297.038848) (xy 67.877684 -297.059946) (xy 67.918187 -297.087902)
			(xy 67.95368 -297.121994) (xy 67.983245 -297.161338) (xy 68.006116 -297.204915) (xy 68.0217 -297.251596)
			(xy 68.029595 -297.300173) (xy 68.03009 -297.32478) (xy 68.368938 -297.32478) (xy 68.372898 -297.275726)
			(xy 68.384675 -297.227942) (xy 68.403966 -297.182666) (xy 68.430269 -297.14107) (xy 68.462904 -297.104233)
			(xy 68.501025 -297.073108) (xy 68.543646 -297.048501) (xy 68.589662 -297.031049) (xy 68.637881 -297.021205)
			(xy 68.687056 -297.019224) (xy 68.735911 -297.025156) (xy 68.783182 -297.038848) (xy 68.827644 -297.059946)
			(xy 68.868147 -297.087902) (xy 68.90364 -297.121994) (xy 68.933205 -297.161338) (xy 68.956076 -297.204915)
			(xy 68.97166 -297.251596) (xy 68.979555 -297.300173) (xy 68.98005 -297.32478) (xy 69.319152 -297.32478)
			(xy 69.323112 -297.275726) (xy 69.334889 -297.227942) (xy 69.35418 -297.182666) (xy 69.380483 -297.14107)
			(xy 69.413118 -297.104233) (xy 69.451239 -297.073108) (xy 69.49386 -297.048501) (xy 69.539876 -297.031049)
			(xy 69.588095 -297.021205) (xy 69.63727 -297.019224) (xy 69.686125 -297.025156) (xy 69.733396 -297.038848)
			(xy 69.777858 -297.059946) (xy 69.818361 -297.087902) (xy 69.853854 -297.121994) (xy 69.883419 -297.161338)
			(xy 69.90629 -297.204915) (xy 69.921874 -297.251596) (xy 69.929769 -297.300173) (xy 69.930264 -297.32478)
			(xy 70.269112 -297.32478) (xy 70.273072 -297.275726) (xy 70.284849 -297.227942) (xy 70.30414 -297.182666)
			(xy 70.330443 -297.14107) (xy 70.363078 -297.104233) (xy 70.401199 -297.073108) (xy 70.44382 -297.048501)
			(xy 70.489836 -297.031049) (xy 70.538055 -297.021205) (xy 70.58723 -297.019224) (xy 70.636085 -297.025156)
			(xy 70.683356 -297.038848) (xy 70.727818 -297.059946) (xy 70.768321 -297.087902) (xy 70.803814 -297.121994)
			(xy 70.833379 -297.161338) (xy 70.85625 -297.204915) (xy 70.871834 -297.251596) (xy 70.879729 -297.300173)
			(xy 70.880224 -297.32478) (xy 71.219072 -297.32478) (xy 71.223032 -297.275726) (xy 71.234809 -297.227942)
			(xy 71.2541 -297.182666) (xy 71.280403 -297.14107) (xy 71.313038 -297.104233) (xy 71.351159 -297.073108)
			(xy 71.39378 -297.048501) (xy 71.439796 -297.031049) (xy 71.488015 -297.021205) (xy 71.53719 -297.019224)
			(xy 71.586045 -297.025156) (xy 71.633316 -297.038848) (xy 71.677778 -297.059946) (xy 71.718281 -297.087902)
			(xy 71.753774 -297.121994) (xy 71.783339 -297.161338) (xy 71.80621 -297.204915) (xy 71.821794 -297.251596)
			(xy 71.829689 -297.300173) (xy 71.830184 -297.32478) (xy 72.169032 -297.32478) (xy 72.172992 -297.275726)
			(xy 72.184769 -297.227942) (xy 72.20406 -297.182666) (xy 72.230363 -297.14107) (xy 72.262998 -297.104233)
			(xy 72.301119 -297.073108) (xy 72.34374 -297.048501) (xy 72.389756 -297.031049) (xy 72.437975 -297.021205)
			(xy 72.48715 -297.019224) (xy 72.536005 -297.025156) (xy 72.583276 -297.038848) (xy 72.627738 -297.059946)
			(xy 72.668241 -297.087902) (xy 72.703734 -297.121994) (xy 72.733299 -297.161338) (xy 72.75617 -297.204915)
			(xy 72.771754 -297.251596) (xy 72.779649 -297.300173) (xy 72.780144 -297.32478) (xy 73.118992 -297.32478)
			(xy 73.122952 -297.275726) (xy 73.134729 -297.227942) (xy 73.15402 -297.182666) (xy 73.180323 -297.14107)
			(xy 73.212958 -297.104233) (xy 73.251079 -297.073108) (xy 73.2937 -297.048501) (xy 73.339716 -297.031049)
			(xy 73.387935 -297.021205) (xy 73.43711 -297.019224) (xy 73.485965 -297.025156) (xy 73.533236 -297.038848)
			(xy 73.577698 -297.059946) (xy 73.618201 -297.087902) (xy 73.653694 -297.121994) (xy 73.683259 -297.161338)
			(xy 73.70613 -297.204915) (xy 73.721714 -297.251596) (xy 73.729609 -297.300173) (xy 73.730104 -297.32478)
			(xy 74.069206 -297.32478) (xy 74.073166 -297.275726) (xy 74.084943 -297.227942) (xy 74.104234 -297.182666)
			(xy 74.130537 -297.14107) (xy 74.163172 -297.104233) (xy 74.201293 -297.073108) (xy 74.243914 -297.048501)
			(xy 74.28993 -297.031049) (xy 74.338149 -297.021205) (xy 74.387324 -297.019224) (xy 74.436179 -297.025156)
			(xy 74.48345 -297.038848) (xy 74.527912 -297.059946) (xy 74.568415 -297.087902) (xy 74.603908 -297.121994)
			(xy 74.633473 -297.161338) (xy 74.656344 -297.204915) (xy 74.671928 -297.251596) (xy 74.679823 -297.300173)
			(xy 74.680318 -297.32478) (xy 75.019166 -297.32478) (xy 75.023126 -297.275726) (xy 75.034903 -297.227942)
			(xy 75.054194 -297.182666) (xy 75.080497 -297.14107) (xy 75.113132 -297.104233) (xy 75.151253 -297.073108)
			(xy 75.193874 -297.048501) (xy 75.23989 -297.031049) (xy 75.288109 -297.021205) (xy 75.337284 -297.019224)
			(xy 75.386139 -297.025156) (xy 75.43341 -297.038848) (xy 75.477872 -297.059946) (xy 75.518375 -297.087902)
			(xy 75.553868 -297.121994) (xy 75.583433 -297.161338) (xy 75.606304 -297.204915) (xy 75.621888 -297.251596)
			(xy 75.629783 -297.300173) (xy 75.630278 -297.32478) (xy 75.969126 -297.32478) (xy 75.973086 -297.275726)
			(xy 75.984863 -297.227942) (xy 76.004154 -297.182666) (xy 76.030457 -297.14107) (xy 76.063092 -297.104233)
			(xy 76.101213 -297.073108) (xy 76.143834 -297.048501) (xy 76.18985 -297.031049) (xy 76.238069 -297.021205)
			(xy 76.287244 -297.019224) (xy 76.336099 -297.025156) (xy 76.38337 -297.038848) (xy 76.427832 -297.059946)
			(xy 76.468335 -297.087902) (xy 76.503828 -297.121994) (xy 76.533393 -297.161338) (xy 76.556264 -297.204915)
			(xy 76.571848 -297.251596) (xy 76.579743 -297.300173) (xy 76.580238 -297.32478) (xy 76.919086 -297.32478)
			(xy 76.923046 -297.275726) (xy 76.934823 -297.227942) (xy 76.954114 -297.182666) (xy 76.980417 -297.14107)
			(xy 77.013052 -297.104233) (xy 77.051173 -297.073108) (xy 77.093794 -297.048501) (xy 77.13981 -297.031049)
			(xy 77.188029 -297.021205) (xy 77.237204 -297.019224) (xy 77.286059 -297.025156) (xy 77.33333 -297.038848)
			(xy 77.377792 -297.059946) (xy 77.418295 -297.087902) (xy 77.453788 -297.121994) (xy 77.483353 -297.161338)
			(xy 77.506224 -297.204915) (xy 77.521808 -297.251596) (xy 77.529703 -297.300173) (xy 77.530198 -297.32478)
			(xy 77.869046 -297.32478) (xy 77.873006 -297.275726) (xy 77.884783 -297.227942) (xy 77.904074 -297.182666)
			(xy 77.930377 -297.14107) (xy 77.963012 -297.104233) (xy 78.001133 -297.073108) (xy 78.043754 -297.048501)
			(xy 78.08977 -297.031049) (xy 78.137989 -297.021205) (xy 78.187164 -297.019224) (xy 78.236019 -297.025156)
			(xy 78.28329 -297.038848) (xy 78.327752 -297.059946) (xy 78.368255 -297.087902) (xy 78.403748 -297.121994)
			(xy 78.433313 -297.161338) (xy 78.456184 -297.204915) (xy 78.471768 -297.251596) (xy 78.479663 -297.300173)
			(xy 78.480158 -297.32478) (xy 78.819006 -297.32478) (xy 78.822966 -297.275726) (xy 78.834743 -297.227942)
			(xy 78.854034 -297.182666) (xy 78.880337 -297.14107) (xy 78.912972 -297.104233) (xy 78.951093 -297.073108)
			(xy 78.993714 -297.048501) (xy 79.03973 -297.031049) (xy 79.087949 -297.021205) (xy 79.137124 -297.019224)
			(xy 79.185979 -297.025156) (xy 79.23325 -297.038848) (xy 79.277712 -297.059946) (xy 79.318215 -297.087902)
			(xy 79.353708 -297.121994) (xy 79.383273 -297.161338) (xy 79.406144 -297.204915) (xy 79.421728 -297.251596)
			(xy 79.429623 -297.300173) (xy 79.430118 -297.32478) (xy 79.768966 -297.32478) (xy 79.772926 -297.275726)
			(xy 79.784703 -297.227942) (xy 79.803994 -297.182666) (xy 79.830297 -297.14107) (xy 79.862932 -297.104233)
			(xy 79.901053 -297.073108) (xy 79.943674 -297.048501) (xy 79.98969 -297.031049) (xy 80.037909 -297.021205)
			(xy 80.087084 -297.019224) (xy 80.135939 -297.025156) (xy 80.18321 -297.038848) (xy 80.227672 -297.059946)
			(xy 80.268175 -297.087902) (xy 80.303668 -297.121994) (xy 80.333233 -297.161338) (xy 80.356104 -297.204915)
			(xy 80.371688 -297.251596) (xy 80.379583 -297.300173) (xy 80.380078 -297.32478) (xy 80.71918 -297.32478)
			(xy 80.72314 -297.275726) (xy 80.734917 -297.227942) (xy 80.754208 -297.182666) (xy 80.780511 -297.14107)
			(xy 80.813146 -297.104233) (xy 80.851267 -297.073108) (xy 80.893888 -297.048501) (xy 80.939904 -297.031049)
			(xy 80.988123 -297.021205) (xy 81.037298 -297.019224) (xy 81.086153 -297.025156) (xy 81.133424 -297.038848)
			(xy 81.177886 -297.059946) (xy 81.218389 -297.087902) (xy 81.253882 -297.121994) (xy 81.283447 -297.161338)
			(xy 81.306318 -297.204915) (xy 81.321902 -297.251596) (xy 81.329797 -297.300173) (xy 81.330292 -297.32478)
			(xy 81.66914 -297.32478) (xy 81.6731 -297.275726) (xy 81.684877 -297.227942) (xy 81.704168 -297.182666)
			(xy 81.730471 -297.14107) (xy 81.763106 -297.104233) (xy 81.801227 -297.073108) (xy 81.843848 -297.048501)
			(xy 81.889864 -297.031049) (xy 81.938083 -297.021205) (xy 81.987258 -297.019224) (xy 82.036113 -297.025156)
			(xy 82.083384 -297.038848) (xy 82.127846 -297.059946) (xy 82.168349 -297.087902) (xy 82.203842 -297.121994)
			(xy 82.233407 -297.161338) (xy 82.256278 -297.204915) (xy 82.271862 -297.251596) (xy 82.279757 -297.300173)
			(xy 82.280252 -297.32478) (xy 82.6191 -297.32478) (xy 82.62306 -297.275726) (xy 82.634837 -297.227942)
			(xy 82.654128 -297.182666) (xy 82.680431 -297.14107) (xy 82.713066 -297.104233) (xy 82.751187 -297.073108)
			(xy 82.793808 -297.048501) (xy 82.839824 -297.031049) (xy 82.888043 -297.021205) (xy 82.937218 -297.019224)
			(xy 82.986073 -297.025156) (xy 83.033344 -297.038848) (xy 83.077806 -297.059946) (xy 83.118309 -297.087902)
			(xy 83.153802 -297.121994) (xy 83.183367 -297.161338) (xy 83.206238 -297.204915) (xy 83.221822 -297.251596)
			(xy 83.229717 -297.300173) (xy 83.230212 -297.32478) (xy 83.229717 -297.349387) (xy 83.221822 -297.397964)
			(xy 83.206238 -297.444645) (xy 83.183367 -297.488222) (xy 83.153802 -297.527566) (xy 83.118309 -297.561658)
			(xy 83.077806 -297.589614) (xy 83.033344 -297.610712) (xy 82.986073 -297.624404) (xy 82.937218 -297.630336)
			(xy 82.888043 -297.628355) (xy 82.839824 -297.618511) (xy 82.793808 -297.601059) (xy 82.751187 -297.576452)
			(xy 82.713066 -297.545327) (xy 82.680431 -297.50849) (xy 82.654128 -297.466894) (xy 82.634837 -297.421618)
			(xy 82.62306 -297.373834) (xy 82.6191 -297.32478) (xy 82.280252 -297.32478) (xy 82.279757 -297.349387)
			(xy 82.271862 -297.397964) (xy 82.256278 -297.444645) (xy 82.233407 -297.488222) (xy 82.203842 -297.527566)
			(xy 82.168349 -297.561658) (xy 82.127846 -297.589614) (xy 82.083384 -297.610712) (xy 82.036113 -297.624404)
			(xy 81.987258 -297.630336) (xy 81.938083 -297.628355) (xy 81.889864 -297.618511) (xy 81.843848 -297.601059)
			(xy 81.801227 -297.576452) (xy 81.763106 -297.545327) (xy 81.730471 -297.50849) (xy 81.704168 -297.466894)
			(xy 81.684877 -297.421618) (xy 81.6731 -297.373834) (xy 81.66914 -297.32478) (xy 81.330292 -297.32478)
			(xy 81.329797 -297.349387) (xy 81.321902 -297.397964) (xy 81.306318 -297.444645) (xy 81.283447 -297.488222)
			(xy 81.253882 -297.527566) (xy 81.218389 -297.561658) (xy 81.177886 -297.589614) (xy 81.133424 -297.610712)
			(xy 81.086153 -297.624404) (xy 81.037298 -297.630336) (xy 80.988123 -297.628355) (xy 80.939904 -297.618511)
			(xy 80.893888 -297.601059) (xy 80.851267 -297.576452) (xy 80.813146 -297.545327) (xy 80.780511 -297.50849)
			(xy 80.754208 -297.466894) (xy 80.734917 -297.421618) (xy 80.72314 -297.373834) (xy 80.71918 -297.32478)
			(xy 80.380078 -297.32478) (xy 80.379583 -297.349387) (xy 80.371688 -297.397964) (xy 80.356104 -297.444645)
			(xy 80.333233 -297.488222) (xy 80.303668 -297.527566) (xy 80.268175 -297.561658) (xy 80.227672 -297.589614)
			(xy 80.18321 -297.610712) (xy 80.135939 -297.624404) (xy 80.087084 -297.630336) (xy 80.037909 -297.628355)
			(xy 79.98969 -297.618511) (xy 79.943674 -297.601059) (xy 79.901053 -297.576452) (xy 79.862932 -297.545327)
			(xy 79.830297 -297.50849) (xy 79.803994 -297.466894) (xy 79.784703 -297.421618) (xy 79.772926 -297.373834)
			(xy 79.768966 -297.32478) (xy 79.430118 -297.32478) (xy 79.429623 -297.349387) (xy 79.421728 -297.397964)
			(xy 79.406144 -297.444645) (xy 79.383273 -297.488222) (xy 79.353708 -297.527566) (xy 79.318215 -297.561658)
			(xy 79.277712 -297.589614) (xy 79.23325 -297.610712) (xy 79.185979 -297.624404) (xy 79.137124 -297.630336)
			(xy 79.087949 -297.628355) (xy 79.03973 -297.618511) (xy 78.993714 -297.601059) (xy 78.951093 -297.576452)
			(xy 78.912972 -297.545327) (xy 78.880337 -297.50849) (xy 78.854034 -297.466894) (xy 78.834743 -297.421618)
			(xy 78.822966 -297.373834) (xy 78.819006 -297.32478) (xy 78.480158 -297.32478) (xy 78.479663 -297.349387)
			(xy 78.471768 -297.397964) (xy 78.456184 -297.444645) (xy 78.433313 -297.488222) (xy 78.403748 -297.527566)
			(xy 78.368255 -297.561658) (xy 78.327752 -297.589614) (xy 78.28329 -297.610712) (xy 78.236019 -297.624404)
			(xy 78.187164 -297.630336) (xy 78.137989 -297.628355) (xy 78.08977 -297.618511) (xy 78.043754 -297.601059)
			(xy 78.001133 -297.576452) (xy 77.963012 -297.545327) (xy 77.930377 -297.50849) (xy 77.904074 -297.466894)
			(xy 77.884783 -297.421618) (xy 77.873006 -297.373834) (xy 77.869046 -297.32478) (xy 77.530198 -297.32478)
			(xy 77.529703 -297.349387) (xy 77.521808 -297.397964) (xy 77.506224 -297.444645) (xy 77.483353 -297.488222)
			(xy 77.453788 -297.527566) (xy 77.418295 -297.561658) (xy 77.377792 -297.589614) (xy 77.33333 -297.610712)
			(xy 77.286059 -297.624404) (xy 77.237204 -297.630336) (xy 77.188029 -297.628355) (xy 77.13981 -297.618511)
			(xy 77.093794 -297.601059) (xy 77.051173 -297.576452) (xy 77.013052 -297.545327) (xy 76.980417 -297.50849)
			(xy 76.954114 -297.466894) (xy 76.934823 -297.421618) (xy 76.923046 -297.373834) (xy 76.919086 -297.32478)
			(xy 76.580238 -297.32478) (xy 76.579743 -297.349387) (xy 76.571848 -297.397964) (xy 76.556264 -297.444645)
			(xy 76.533393 -297.488222) (xy 76.503828 -297.527566) (xy 76.468335 -297.561658) (xy 76.427832 -297.589614)
			(xy 76.38337 -297.610712) (xy 76.336099 -297.624404) (xy 76.287244 -297.630336) (xy 76.238069 -297.628355)
			(xy 76.18985 -297.618511) (xy 76.143834 -297.601059) (xy 76.101213 -297.576452) (xy 76.063092 -297.545327)
			(xy 76.030457 -297.50849) (xy 76.004154 -297.466894) (xy 75.984863 -297.421618) (xy 75.973086 -297.373834)
			(xy 75.969126 -297.32478) (xy 75.630278 -297.32478) (xy 75.629783 -297.349387) (xy 75.621888 -297.397964)
			(xy 75.606304 -297.444645) (xy 75.583433 -297.488222) (xy 75.553868 -297.527566) (xy 75.518375 -297.561658)
			(xy 75.477872 -297.589614) (xy 75.43341 -297.610712) (xy 75.386139 -297.624404) (xy 75.337284 -297.630336)
			(xy 75.288109 -297.628355) (xy 75.23989 -297.618511) (xy 75.193874 -297.601059) (xy 75.151253 -297.576452)
			(xy 75.113132 -297.545327) (xy 75.080497 -297.50849) (xy 75.054194 -297.466894) (xy 75.034903 -297.421618)
			(xy 75.023126 -297.373834) (xy 75.019166 -297.32478) (xy 74.680318 -297.32478) (xy 74.679823 -297.349387)
			(xy 74.671928 -297.397964) (xy 74.656344 -297.444645) (xy 74.633473 -297.488222) (xy 74.603908 -297.527566)
			(xy 74.568415 -297.561658) (xy 74.527912 -297.589614) (xy 74.48345 -297.610712) (xy 74.436179 -297.624404)
			(xy 74.387324 -297.630336) (xy 74.338149 -297.628355) (xy 74.28993 -297.618511) (xy 74.243914 -297.601059)
			(xy 74.201293 -297.576452) (xy 74.163172 -297.545327) (xy 74.130537 -297.50849) (xy 74.104234 -297.466894)
			(xy 74.084943 -297.421618) (xy 74.073166 -297.373834) (xy 74.069206 -297.32478) (xy 73.730104 -297.32478)
			(xy 73.729609 -297.349387) (xy 73.721714 -297.397964) (xy 73.70613 -297.444645) (xy 73.683259 -297.488222)
			(xy 73.653694 -297.527566) (xy 73.618201 -297.561658) (xy 73.577698 -297.589614) (xy 73.533236 -297.610712)
			(xy 73.485965 -297.624404) (xy 73.43711 -297.630336) (xy 73.387935 -297.628355) (xy 73.339716 -297.618511)
			(xy 73.2937 -297.601059) (xy 73.251079 -297.576452) (xy 73.212958 -297.545327) (xy 73.180323 -297.50849)
			(xy 73.15402 -297.466894) (xy 73.134729 -297.421618) (xy 73.122952 -297.373834) (xy 73.118992 -297.32478)
			(xy 72.780144 -297.32478) (xy 72.779649 -297.349387) (xy 72.771754 -297.397964) (xy 72.75617 -297.444645)
			(xy 72.733299 -297.488222) (xy 72.703734 -297.527566) (xy 72.668241 -297.561658) (xy 72.627738 -297.589614)
			(xy 72.583276 -297.610712) (xy 72.536005 -297.624404) (xy 72.48715 -297.630336) (xy 72.437975 -297.628355)
			(xy 72.389756 -297.618511) (xy 72.34374 -297.601059) (xy 72.301119 -297.576452) (xy 72.262998 -297.545327)
			(xy 72.230363 -297.50849) (xy 72.20406 -297.466894) (xy 72.184769 -297.421618) (xy 72.172992 -297.373834)
			(xy 72.169032 -297.32478) (xy 71.830184 -297.32478) (xy 71.829689 -297.349387) (xy 71.821794 -297.397964)
			(xy 71.80621 -297.444645) (xy 71.783339 -297.488222) (xy 71.753774 -297.527566) (xy 71.718281 -297.561658)
			(xy 71.677778 -297.589614) (xy 71.633316 -297.610712) (xy 71.586045 -297.624404) (xy 71.53719 -297.630336)
			(xy 71.488015 -297.628355) (xy 71.439796 -297.618511) (xy 71.39378 -297.601059) (xy 71.351159 -297.576452)
			(xy 71.313038 -297.545327) (xy 71.280403 -297.50849) (xy 71.2541 -297.466894) (xy 71.234809 -297.421618)
			(xy 71.223032 -297.373834) (xy 71.219072 -297.32478) (xy 70.880224 -297.32478) (xy 70.879729 -297.349387)
			(xy 70.871834 -297.397964) (xy 70.85625 -297.444645) (xy 70.833379 -297.488222) (xy 70.803814 -297.527566)
			(xy 70.768321 -297.561658) (xy 70.727818 -297.589614) (xy 70.683356 -297.610712) (xy 70.636085 -297.624404)
			(xy 70.58723 -297.630336) (xy 70.538055 -297.628355) (xy 70.489836 -297.618511) (xy 70.44382 -297.601059)
			(xy 70.401199 -297.576452) (xy 70.363078 -297.545327) (xy 70.330443 -297.50849) (xy 70.30414 -297.466894)
			(xy 70.284849 -297.421618) (xy 70.273072 -297.373834) (xy 70.269112 -297.32478) (xy 69.930264 -297.32478)
			(xy 69.929769 -297.349387) (xy 69.921874 -297.397964) (xy 69.90629 -297.444645) (xy 69.883419 -297.488222)
			(xy 69.853854 -297.527566) (xy 69.818361 -297.561658) (xy 69.777858 -297.589614) (xy 69.733396 -297.610712)
			(xy 69.686125 -297.624404) (xy 69.63727 -297.630336) (xy 69.588095 -297.628355) (xy 69.539876 -297.618511)
			(xy 69.49386 -297.601059) (xy 69.451239 -297.576452) (xy 69.413118 -297.545327) (xy 69.380483 -297.50849)
			(xy 69.35418 -297.466894) (xy 69.334889 -297.421618) (xy 69.323112 -297.373834) (xy 69.319152 -297.32478)
			(xy 68.98005 -297.32478) (xy 68.979555 -297.349387) (xy 68.97166 -297.397964) (xy 68.956076 -297.444645)
			(xy 68.933205 -297.488222) (xy 68.90364 -297.527566) (xy 68.868147 -297.561658) (xy 68.827644 -297.589614)
			(xy 68.783182 -297.610712) (xy 68.735911 -297.624404) (xy 68.687056 -297.630336) (xy 68.637881 -297.628355)
			(xy 68.589662 -297.618511) (xy 68.543646 -297.601059) (xy 68.501025 -297.576452) (xy 68.462904 -297.545327)
			(xy 68.430269 -297.50849) (xy 68.403966 -297.466894) (xy 68.384675 -297.421618) (xy 68.372898 -297.373834)
			(xy 68.368938 -297.32478) (xy 68.03009 -297.32478) (xy 68.029595 -297.349387) (xy 68.0217 -297.397964)
			(xy 68.006116 -297.444645) (xy 67.983245 -297.488222) (xy 67.95368 -297.527566) (xy 67.918187 -297.561658)
			(xy 67.877684 -297.589614) (xy 67.833222 -297.610712) (xy 67.785951 -297.624404) (xy 67.737096 -297.630336)
			(xy 67.687921 -297.628355) (xy 67.639702 -297.618511) (xy 67.593686 -297.601059) (xy 67.551065 -297.576452)
			(xy 67.512944 -297.545327) (xy 67.480309 -297.50849) (xy 67.454006 -297.466894) (xy 67.434715 -297.421618)
			(xy 67.422938 -297.373834) (xy 67.418978 -297.32478) (xy 67.08013 -297.32478) (xy 67.079635 -297.349387)
			(xy 67.07174 -297.397964) (xy 67.056156 -297.444645) (xy 67.033285 -297.488222) (xy 67.00372 -297.527566)
			(xy 66.968227 -297.561658) (xy 66.927724 -297.589614) (xy 66.883262 -297.610712) (xy 66.835991 -297.624404)
			(xy 66.787136 -297.630336) (xy 66.737961 -297.628355) (xy 66.689742 -297.618511) (xy 66.643726 -297.601059)
			(xy 66.601105 -297.576452) (xy 66.562984 -297.545327) (xy 66.530349 -297.50849) (xy 66.504046 -297.466894)
			(xy 66.484755 -297.421618) (xy 66.472978 -297.373834) (xy 66.469018 -297.32478) (xy 66.13017 -297.32478)
			(xy 66.129675 -297.349387) (xy 66.12178 -297.397964) (xy 66.106196 -297.444645) (xy 66.083325 -297.488222)
			(xy 66.05376 -297.527566) (xy 66.018267 -297.561658) (xy 65.977764 -297.589614) (xy 65.933302 -297.610712)
			(xy 65.886031 -297.624404) (xy 65.837176 -297.630336) (xy 65.788001 -297.628355) (xy 65.739782 -297.618511)
			(xy 65.693766 -297.601059) (xy 65.651145 -297.576452) (xy 65.613024 -297.545327) (xy 65.580389 -297.50849)
			(xy 65.554086 -297.466894) (xy 65.534795 -297.421618) (xy 65.523018 -297.373834) (xy 65.519058 -297.32478)
			(xy 64.23025 -297.32478) (xy 64.229755 -297.349387) (xy 64.22186 -297.397964) (xy 64.206276 -297.444645)
			(xy 64.183405 -297.488222) (xy 64.15384 -297.527566) (xy 64.118347 -297.561658) (xy 64.077844 -297.589614)
			(xy 64.033382 -297.610712) (xy 63.986111 -297.624404) (xy 63.937256 -297.630336) (xy 63.888081 -297.628355)
			(xy 63.839862 -297.618511) (xy 63.793846 -297.601059) (xy 63.751225 -297.576452) (xy 63.713104 -297.545327)
			(xy 63.680469 -297.50849) (xy 63.654166 -297.466894) (xy 63.634875 -297.421618) (xy 63.623098 -297.373834)
			(xy 63.619138 -297.32478) (xy 62.330076 -297.32478) (xy 62.329581 -297.349387) (xy 62.321686 -297.397964)
			(xy 62.306102 -297.444645) (xy 62.283231 -297.488222) (xy 62.253666 -297.527566) (xy 62.218173 -297.561658)
			(xy 62.17767 -297.589614) (xy 62.133208 -297.610712) (xy 62.085937 -297.624404) (xy 62.037082 -297.630336)
			(xy 61.987907 -297.628355) (xy 61.939688 -297.618511) (xy 61.893672 -297.601059) (xy 61.851051 -297.576452)
			(xy 61.81293 -297.545327) (xy 61.780295 -297.50849) (xy 61.753992 -297.466894) (xy 61.734701 -297.421618)
			(xy 61.722924 -297.373834) (xy 61.718964 -297.32478) (xy 60.430156 -297.32478) (xy 60.429661 -297.349387)
			(xy 60.421766 -297.397964) (xy 60.406182 -297.444645) (xy 60.383311 -297.488222) (xy 60.353746 -297.527566)
			(xy 60.318253 -297.561658) (xy 60.27775 -297.589614) (xy 60.233288 -297.610712) (xy 60.186017 -297.624404)
			(xy 60.137162 -297.630336) (xy 60.087987 -297.628355) (xy 60.039768 -297.618511) (xy 59.993752 -297.601059)
			(xy 59.951131 -297.576452) (xy 59.91301 -297.545327) (xy 59.880375 -297.50849) (xy 59.854072 -297.466894)
			(xy 59.834781 -297.421618) (xy 59.823004 -297.373834) (xy 59.819044 -297.32478) (xy 57.580276 -297.32478)
			(xy 57.579781 -297.349387) (xy 57.571886 -297.397964) (xy 57.556302 -297.444645) (xy 57.533431 -297.488222)
			(xy 57.503866 -297.527566) (xy 57.468373 -297.561658) (xy 57.42787 -297.589614) (xy 57.383408 -297.610712)
			(xy 57.336137 -297.624404) (xy 57.287282 -297.630336) (xy 57.238107 -297.628355) (xy 57.189888 -297.618511)
			(xy 57.143872 -297.601059) (xy 57.101251 -297.576452) (xy 57.06313 -297.545327) (xy 57.030495 -297.50849)
			(xy 57.004192 -297.466894) (xy 56.984901 -297.421618) (xy 56.973124 -297.373834) (xy 56.969164 -297.32478)
			(xy 55.680102 -297.32478) (xy 55.679607 -297.349387) (xy 55.671712 -297.397964) (xy 55.656128 -297.444645)
			(xy 55.633257 -297.488222) (xy 55.603692 -297.527566) (xy 55.568199 -297.561658) (xy 55.527696 -297.589614)
			(xy 55.483234 -297.610712) (xy 55.435963 -297.624404) (xy 55.387108 -297.630336) (xy 55.337933 -297.628355)
			(xy 55.289714 -297.618511) (xy 55.243698 -297.601059) (xy 55.201077 -297.576452) (xy 55.162956 -297.545327)
			(xy 55.130321 -297.50849) (xy 55.104018 -297.466894) (xy 55.084727 -297.421618) (xy 55.07295 -297.373834)
			(xy 55.06899 -297.32478) (xy 53.780182 -297.32478) (xy 53.779687 -297.349387) (xy 53.771792 -297.397964)
			(xy 53.756208 -297.444645) (xy 53.733337 -297.488222) (xy 53.703772 -297.527566) (xy 53.668279 -297.561658)
			(xy 53.627776 -297.589614) (xy 53.583314 -297.610712) (xy 53.536043 -297.624404) (xy 53.487188 -297.630336)
			(xy 53.438013 -297.628355) (xy 53.389794 -297.618511) (xy 53.343778 -297.601059) (xy 53.301157 -297.576452)
			(xy 53.263036 -297.545327) (xy 53.230401 -297.50849) (xy 53.204098 -297.466894) (xy 53.184807 -297.421618)
			(xy 53.17303 -297.373834) (xy 53.16907 -297.32478) (xy 51.880262 -297.32478) (xy 51.879767 -297.349387)
			(xy 51.871872 -297.397964) (xy 51.856288 -297.444645) (xy 51.833417 -297.488222) (xy 51.803852 -297.527566)
			(xy 51.768359 -297.561658) (xy 51.727856 -297.589614) (xy 51.683394 -297.610712) (xy 51.636123 -297.624404)
			(xy 51.587268 -297.630336) (xy 51.538093 -297.628355) (xy 51.489874 -297.618511) (xy 51.443858 -297.601059)
			(xy 51.401237 -297.576452) (xy 51.363116 -297.545327) (xy 51.330481 -297.50849) (xy 51.304178 -297.466894)
			(xy 51.284887 -297.421618) (xy 51.27311 -297.373834) (xy 51.26915 -297.32478) (xy 49.980088 -297.32478)
			(xy 49.979593 -297.349387) (xy 49.971698 -297.397964) (xy 49.956114 -297.444645) (xy 49.933243 -297.488222)
			(xy 49.903678 -297.527566) (xy 49.868185 -297.561658) (xy 49.827682 -297.589614) (xy 49.78322 -297.610712)
			(xy 49.735949 -297.624404) (xy 49.687094 -297.630336) (xy 49.637919 -297.628355) (xy 49.5897 -297.618511)
			(xy 49.543684 -297.601059) (xy 49.501063 -297.576452) (xy 49.462942 -297.545327) (xy 49.430307 -297.50849)
			(xy 49.404004 -297.466894) (xy 49.384713 -297.421618) (xy 49.372936 -297.373834) (xy 49.368976 -297.32478)
			(xy 49.149254 -297.32478) (xy 49.149254 -297.95851) (xy 84.756242 -297.95851) (xy 84.760313 -297.902888)
			(xy 84.772439 -297.848451) (xy 84.792362 -297.79636) (xy 84.819658 -297.747725) (xy 84.853744 -297.703582)
			(xy 84.893893 -297.664873) (xy 84.939251 -297.632422) (xy 84.988851 -297.606921) (xy 85.041635 -297.588914)
			(xy 85.096478 -297.578784) (xy 85.152212 -297.576747) (xy 85.207649 -297.582847) (xy 85.261606 -297.596953)
			(xy 85.312935 -297.618765) (xy 85.360541 -297.647819) (xy 85.395394 -297.676824) (xy 86.299546 -297.676824)
			(xy 86.303617 -297.621202) (xy 86.315743 -297.566765) (xy 86.335666 -297.514674) (xy 86.362962 -297.466039)
			(xy 86.397048 -297.421896) (xy 86.437197 -297.383187) (xy 86.482555 -297.350736) (xy 86.532155 -297.325235)
			(xy 86.584939 -297.307228) (xy 86.639782 -297.297098) (xy 86.695516 -297.295061) (xy 86.750953 -297.301161)
			(xy 86.80491 -297.315267) (xy 86.856239 -297.337079) (xy 86.903845 -297.366133) (xy 86.914281 -297.374818)
			(xy 92.615764 -297.374818) (xy 92.619835 -297.319196) (xy 92.631961 -297.264759) (xy 92.651884 -297.212668)
			(xy 92.67918 -297.164033) (xy 92.713266 -297.11989) (xy 92.753415 -297.081181) (xy 92.798773 -297.04873)
			(xy 92.848373 -297.023229) (xy 92.901157 -297.005222) (xy 92.956 -296.995092) (xy 93.011734 -296.993055)
			(xy 93.067171 -296.999155) (xy 93.121128 -297.013261) (xy 93.172457 -297.035073) (xy 93.220063 -297.064127)
			(xy 93.262931 -297.099802) (xy 93.300148 -297.141339) (xy 93.330921 -297.187852) (xy 93.354593 -297.238349)
			(xy 93.370661 -297.291756) (xy 93.378781 -297.346932) (xy 93.37929 -297.374818) (xy 93.378781 -297.402704)
			(xy 93.370661 -297.45788) (xy 93.354593 -297.511287) (xy 93.330921 -297.561784) (xy 93.300148 -297.608297)
			(xy 93.262931 -297.649834) (xy 93.220063 -297.685509) (xy 93.172457 -297.714563) (xy 93.121128 -297.736375)
			(xy 93.067171 -297.750481) (xy 93.011734 -297.756581) (xy 92.956 -297.754544) (xy 92.901157 -297.744414)
			(xy 92.848373 -297.726407) (xy 92.798773 -297.700906) (xy 92.753415 -297.668455) (xy 92.713266 -297.629746)
			(xy 92.67918 -297.585603) (xy 92.651884 -297.536968) (xy 92.631961 -297.484877) (xy 92.619835 -297.43044)
			(xy 92.615764 -297.374818) (xy 86.914281 -297.374818) (xy 86.946713 -297.401808) (xy 86.98393 -297.443345)
			(xy 87.014703 -297.489858) (xy 87.038375 -297.540355) (xy 87.054443 -297.593762) (xy 87.062563 -297.648938)
			(xy 87.063072 -297.676824) (xy 87.062563 -297.70471) (xy 87.054443 -297.759886) (xy 87.038375 -297.813293)
			(xy 87.014703 -297.86379) (xy 86.98393 -297.910303) (xy 86.946713 -297.95184) (xy 86.903845 -297.987515)
			(xy 86.856239 -298.016569) (xy 86.80491 -298.038381) (xy 86.750953 -298.052487) (xy 86.695516 -298.058587)
			(xy 86.639782 -298.05655) (xy 86.584939 -298.04642) (xy 86.532155 -298.028413) (xy 86.482555 -298.002912)
			(xy 86.437197 -297.970461) (xy 86.397048 -297.931752) (xy 86.362962 -297.887609) (xy 86.335666 -297.838974)
			(xy 86.315743 -297.786883) (xy 86.303617 -297.732446) (xy 86.299546 -297.676824) (xy 85.395394 -297.676824)
			(xy 85.403409 -297.683494) (xy 85.440626 -297.725031) (xy 85.471399 -297.771544) (xy 85.495071 -297.822041)
			(xy 85.511139 -297.875448) (xy 85.519259 -297.930624) (xy 85.519768 -297.95851) (xy 85.519259 -297.986396)
			(xy 85.511139 -298.041572) (xy 85.495071 -298.094979) (xy 85.471399 -298.145476) (xy 85.440626 -298.191989)
			(xy 85.403409 -298.233526) (xy 85.360541 -298.269201) (xy 85.312935 -298.298255) (xy 85.261606 -298.320067)
			(xy 85.207649 -298.334173) (xy 85.152212 -298.340273) (xy 85.096478 -298.338236) (xy 85.041635 -298.328106)
			(xy 84.988851 -298.310099) (xy 84.939251 -298.284598) (xy 84.893893 -298.252147) (xy 84.853744 -298.213438)
			(xy 84.819658 -298.169295) (xy 84.792362 -298.12066) (xy 84.772439 -298.068569) (xy 84.760313 -298.014132)
			(xy 84.756242 -297.95851) (xy 49.149254 -297.95851) (xy 49.149254 -298.27474) (xy 50.31919 -298.27474)
			(xy 50.32315 -298.225686) (xy 50.334927 -298.177902) (xy 50.354218 -298.132626) (xy 50.380521 -298.09103)
			(xy 50.413156 -298.054193) (xy 50.451277 -298.023068) (xy 50.493898 -297.998461) (xy 50.539914 -297.981009)
			(xy 50.588133 -297.971165) (xy 50.637308 -297.969184) (xy 50.686163 -297.975116) (xy 50.733434 -297.988808)
			(xy 50.777896 -298.009906) (xy 50.818399 -298.037862) (xy 50.853892 -298.071954) (xy 50.883457 -298.111298)
			(xy 50.906328 -298.154875) (xy 50.921912 -298.201556) (xy 50.929807 -298.250133) (xy 50.930302 -298.27474)
			(xy 52.21911 -298.27474) (xy 52.22307 -298.225686) (xy 52.234847 -298.177902) (xy 52.254138 -298.132626)
			(xy 52.280441 -298.09103) (xy 52.313076 -298.054193) (xy 52.351197 -298.023068) (xy 52.393818 -297.998461)
			(xy 52.439834 -297.981009) (xy 52.488053 -297.971165) (xy 52.537228 -297.969184) (xy 52.586083 -297.975116)
			(xy 52.633354 -297.988808) (xy 52.677816 -298.009906) (xy 52.718319 -298.037862) (xy 52.753812 -298.071954)
			(xy 52.783377 -298.111298) (xy 52.806248 -298.154875) (xy 52.821832 -298.201556) (xy 52.829727 -298.250133)
			(xy 52.830222 -298.27474) (xy 54.11903 -298.27474) (xy 54.12299 -298.225686) (xy 54.134767 -298.177902)
			(xy 54.154058 -298.132626) (xy 54.180361 -298.09103) (xy 54.212996 -298.054193) (xy 54.251117 -298.023068)
			(xy 54.293738 -297.998461) (xy 54.339754 -297.981009) (xy 54.387973 -297.971165) (xy 54.437148 -297.969184)
			(xy 54.486003 -297.975116) (xy 54.533274 -297.988808) (xy 54.577736 -298.009906) (xy 54.618239 -298.037862)
			(xy 54.653732 -298.071954) (xy 54.683297 -298.111298) (xy 54.706168 -298.154875) (xy 54.721752 -298.201556)
			(xy 54.729647 -298.250133) (xy 54.730142 -298.27474) (xy 56.01895 -298.27474) (xy 56.02291 -298.225686)
			(xy 56.034687 -298.177902) (xy 56.053978 -298.132626) (xy 56.080281 -298.09103) (xy 56.112916 -298.054193)
			(xy 56.151037 -298.023068) (xy 56.193658 -297.998461) (xy 56.239674 -297.981009) (xy 56.287893 -297.971165)
			(xy 56.337068 -297.969184) (xy 56.385923 -297.975116) (xy 56.433194 -297.988808) (xy 56.477656 -298.009906)
			(xy 56.518159 -298.037862) (xy 56.553652 -298.071954) (xy 56.583217 -298.111298) (xy 56.606088 -298.154875)
			(xy 56.621672 -298.201556) (xy 56.629567 -298.250133) (xy 56.630062 -298.27474) (xy 57.919124 -298.27474)
			(xy 57.923084 -298.225686) (xy 57.934861 -298.177902) (xy 57.954152 -298.132626) (xy 57.980455 -298.09103)
			(xy 58.01309 -298.054193) (xy 58.051211 -298.023068) (xy 58.093832 -297.998461) (xy 58.139848 -297.981009)
			(xy 58.188067 -297.971165) (xy 58.237242 -297.969184) (xy 58.286097 -297.975116) (xy 58.333368 -297.988808)
			(xy 58.37783 -298.009906) (xy 58.418333 -298.037862) (xy 58.453826 -298.071954) (xy 58.483391 -298.111298)
			(xy 58.506262 -298.154875) (xy 58.521846 -298.201556) (xy 58.529741 -298.250133) (xy 58.530236 -298.27474)
			(xy 60.769004 -298.27474) (xy 60.772964 -298.225686) (xy 60.784741 -298.177902) (xy 60.804032 -298.132626)
			(xy 60.830335 -298.09103) (xy 60.86297 -298.054193) (xy 60.901091 -298.023068) (xy 60.943712 -297.998461)
			(xy 60.989728 -297.981009) (xy 61.037947 -297.971165) (xy 61.087122 -297.969184) (xy 61.135977 -297.975116)
			(xy 61.183248 -297.988808) (xy 61.22771 -298.009906) (xy 61.268213 -298.037862) (xy 61.303706 -298.071954)
			(xy 61.333271 -298.111298) (xy 61.356142 -298.154875) (xy 61.371726 -298.201556) (xy 61.379621 -298.250133)
			(xy 61.380116 -298.27474) (xy 62.669178 -298.27474) (xy 62.673138 -298.225686) (xy 62.684915 -298.177902)
			(xy 62.704206 -298.132626) (xy 62.730509 -298.09103) (xy 62.763144 -298.054193) (xy 62.801265 -298.023068)
			(xy 62.843886 -297.998461) (xy 62.889902 -297.981009) (xy 62.938121 -297.971165) (xy 62.987296 -297.969184)
			(xy 63.036151 -297.975116) (xy 63.083422 -297.988808) (xy 63.127884 -298.009906) (xy 63.168387 -298.037862)
			(xy 63.20388 -298.071954) (xy 63.233445 -298.111298) (xy 63.256316 -298.154875) (xy 63.2719 -298.201556)
			(xy 63.279795 -298.250133) (xy 63.28029 -298.27474) (xy 64.569098 -298.27474) (xy 64.573058 -298.225686)
			(xy 64.584835 -298.177902) (xy 64.604126 -298.132626) (xy 64.630429 -298.09103) (xy 64.663064 -298.054193)
			(xy 64.701185 -298.023068) (xy 64.743806 -297.998461) (xy 64.789822 -297.981009) (xy 64.838041 -297.971165)
			(xy 64.887216 -297.969184) (xy 64.936071 -297.975116) (xy 64.983342 -297.988808) (xy 65.027804 -298.009906)
			(xy 65.068307 -298.037862) (xy 65.1038 -298.071954) (xy 65.133365 -298.111298) (xy 65.156236 -298.154875)
			(xy 65.17182 -298.201556) (xy 65.179715 -298.250133) (xy 65.18021 -298.27474) (xy 66.469018 -298.27474)
			(xy 66.472978 -298.225686) (xy 66.484755 -298.177902) (xy 66.504046 -298.132626) (xy 66.530349 -298.09103)
			(xy 66.562984 -298.054193) (xy 66.601105 -298.023068) (xy 66.643726 -297.998461) (xy 66.689742 -297.981009)
			(xy 66.737961 -297.971165) (xy 66.787136 -297.969184) (xy 66.835991 -297.975116) (xy 66.883262 -297.988808)
			(xy 66.927724 -298.009906) (xy 66.968227 -298.037862) (xy 67.00372 -298.071954) (xy 67.033285 -298.111298)
			(xy 67.056156 -298.154875) (xy 67.07174 -298.201556) (xy 67.079635 -298.250133) (xy 67.08013 -298.27474)
			(xy 68.368938 -298.27474) (xy 68.372898 -298.225686) (xy 68.384675 -298.177902) (xy 68.403966 -298.132626)
			(xy 68.430269 -298.09103) (xy 68.462904 -298.054193) (xy 68.501025 -298.023068) (xy 68.543646 -297.998461)
			(xy 68.589662 -297.981009) (xy 68.637881 -297.971165) (xy 68.687056 -297.969184) (xy 68.735911 -297.975116)
			(xy 68.783182 -297.988808) (xy 68.827644 -298.009906) (xy 68.868147 -298.037862) (xy 68.90364 -298.071954)
			(xy 68.933205 -298.111298) (xy 68.956076 -298.154875) (xy 68.97166 -298.201556) (xy 68.979555 -298.250133)
			(xy 68.98005 -298.27474) (xy 69.319152 -298.27474) (xy 69.323112 -298.225686) (xy 69.334889 -298.177902)
			(xy 69.35418 -298.132626) (xy 69.380483 -298.09103) (xy 69.413118 -298.054193) (xy 69.451239 -298.023068)
			(xy 69.49386 -297.998461) (xy 69.539876 -297.981009) (xy 69.588095 -297.971165) (xy 69.63727 -297.969184)
			(xy 69.686125 -297.975116) (xy 69.733396 -297.988808) (xy 69.777858 -298.009906) (xy 69.818361 -298.037862)
			(xy 69.853854 -298.071954) (xy 69.883419 -298.111298) (xy 69.90629 -298.154875) (xy 69.921874 -298.201556)
			(xy 69.929769 -298.250133) (xy 69.930264 -298.27474) (xy 70.269112 -298.27474) (xy 70.273072 -298.225686)
			(xy 70.284849 -298.177902) (xy 70.30414 -298.132626) (xy 70.330443 -298.09103) (xy 70.363078 -298.054193)
			(xy 70.401199 -298.023068) (xy 70.44382 -297.998461) (xy 70.489836 -297.981009) (xy 70.538055 -297.971165)
			(xy 70.58723 -297.969184) (xy 70.636085 -297.975116) (xy 70.683356 -297.988808) (xy 70.727818 -298.009906)
			(xy 70.768321 -298.037862) (xy 70.803814 -298.071954) (xy 70.833379 -298.111298) (xy 70.85625 -298.154875)
			(xy 70.871834 -298.201556) (xy 70.879729 -298.250133) (xy 70.880224 -298.27474) (xy 71.219072 -298.27474)
			(xy 71.223032 -298.225686) (xy 71.234809 -298.177902) (xy 71.2541 -298.132626) (xy 71.280403 -298.09103)
			(xy 71.313038 -298.054193) (xy 71.351159 -298.023068) (xy 71.39378 -297.998461) (xy 71.439796 -297.981009)
			(xy 71.488015 -297.971165) (xy 71.53719 -297.969184) (xy 71.586045 -297.975116) (xy 71.633316 -297.988808)
			(xy 71.677778 -298.009906) (xy 71.718281 -298.037862) (xy 71.753774 -298.071954) (xy 71.783339 -298.111298)
			(xy 71.80621 -298.154875) (xy 71.821794 -298.201556) (xy 71.829689 -298.250133) (xy 71.830184 -298.27474)
			(xy 72.169032 -298.27474) (xy 72.172992 -298.225686) (xy 72.184769 -298.177902) (xy 72.20406 -298.132626)
			(xy 72.230363 -298.09103) (xy 72.262998 -298.054193) (xy 72.301119 -298.023068) (xy 72.34374 -297.998461)
			(xy 72.389756 -297.981009) (xy 72.437975 -297.971165) (xy 72.48715 -297.969184) (xy 72.536005 -297.975116)
			(xy 72.583276 -297.988808) (xy 72.627738 -298.009906) (xy 72.668241 -298.037862) (xy 72.703734 -298.071954)
			(xy 72.733299 -298.111298) (xy 72.75617 -298.154875) (xy 72.771754 -298.201556) (xy 72.779649 -298.250133)
			(xy 72.780144 -298.27474) (xy 73.118992 -298.27474) (xy 73.122952 -298.225686) (xy 73.134729 -298.177902)
			(xy 73.15402 -298.132626) (xy 73.180323 -298.09103) (xy 73.212958 -298.054193) (xy 73.251079 -298.023068)
			(xy 73.2937 -297.998461) (xy 73.339716 -297.981009) (xy 73.387935 -297.971165) (xy 73.43711 -297.969184)
			(xy 73.485965 -297.975116) (xy 73.533236 -297.988808) (xy 73.577698 -298.009906) (xy 73.618201 -298.037862)
			(xy 73.653694 -298.071954) (xy 73.683259 -298.111298) (xy 73.70613 -298.154875) (xy 73.721714 -298.201556)
			(xy 73.729609 -298.250133) (xy 73.730104 -298.27474) (xy 74.068952 -298.27474) (xy 74.072912 -298.225686)
			(xy 74.084689 -298.177902) (xy 74.10398 -298.132626) (xy 74.130283 -298.09103) (xy 74.162918 -298.054193)
			(xy 74.201039 -298.023068) (xy 74.24366 -297.998461) (xy 74.289676 -297.981009) (xy 74.337895 -297.971165)
			(xy 74.38707 -297.969184) (xy 74.435925 -297.975116) (xy 74.483196 -297.988808) (xy 74.527658 -298.009906)
			(xy 74.568161 -298.037862) (xy 74.603654 -298.071954) (xy 74.633219 -298.111298) (xy 74.65609 -298.154875)
			(xy 74.671674 -298.201556) (xy 74.679569 -298.250133) (xy 74.680064 -298.27474) (xy 75.019166 -298.27474)
			(xy 75.023126 -298.225686) (xy 75.034903 -298.177902) (xy 75.054194 -298.132626) (xy 75.080497 -298.09103)
			(xy 75.113132 -298.054193) (xy 75.151253 -298.023068) (xy 75.193874 -297.998461) (xy 75.23989 -297.981009)
			(xy 75.288109 -297.971165) (xy 75.337284 -297.969184) (xy 75.386139 -297.975116) (xy 75.43341 -297.988808)
			(xy 75.477872 -298.009906) (xy 75.518375 -298.037862) (xy 75.553868 -298.071954) (xy 75.583433 -298.111298)
			(xy 75.606304 -298.154875) (xy 75.621888 -298.201556) (xy 75.629783 -298.250133) (xy 75.630278 -298.27474)
			(xy 75.969126 -298.27474) (xy 75.973086 -298.225686) (xy 75.984863 -298.177902) (xy 76.004154 -298.132626)
			(xy 76.030457 -298.09103) (xy 76.063092 -298.054193) (xy 76.101213 -298.023068) (xy 76.143834 -297.998461)
			(xy 76.18985 -297.981009) (xy 76.238069 -297.971165) (xy 76.287244 -297.969184) (xy 76.336099 -297.975116)
			(xy 76.38337 -297.988808) (xy 76.427832 -298.009906) (xy 76.468335 -298.037862) (xy 76.503828 -298.071954)
			(xy 76.533393 -298.111298) (xy 76.556264 -298.154875) (xy 76.571848 -298.201556) (xy 76.579743 -298.250133)
			(xy 76.580238 -298.27474) (xy 76.919086 -298.27474) (xy 76.923046 -298.225686) (xy 76.934823 -298.177902)
			(xy 76.954114 -298.132626) (xy 76.980417 -298.09103) (xy 77.013052 -298.054193) (xy 77.051173 -298.023068)
			(xy 77.093794 -297.998461) (xy 77.13981 -297.981009) (xy 77.188029 -297.971165) (xy 77.237204 -297.969184)
			(xy 77.286059 -297.975116) (xy 77.33333 -297.988808) (xy 77.377792 -298.009906) (xy 77.418295 -298.037862)
			(xy 77.453788 -298.071954) (xy 77.483353 -298.111298) (xy 77.506224 -298.154875) (xy 77.521808 -298.201556)
			(xy 77.529703 -298.250133) (xy 77.530198 -298.27474) (xy 77.869046 -298.27474) (xy 77.873006 -298.225686)
			(xy 77.884783 -298.177902) (xy 77.904074 -298.132626) (xy 77.930377 -298.09103) (xy 77.963012 -298.054193)
			(xy 78.001133 -298.023068) (xy 78.043754 -297.998461) (xy 78.08977 -297.981009) (xy 78.137989 -297.971165)
			(xy 78.187164 -297.969184) (xy 78.236019 -297.975116) (xy 78.28329 -297.988808) (xy 78.327752 -298.009906)
			(xy 78.368255 -298.037862) (xy 78.403748 -298.071954) (xy 78.433313 -298.111298) (xy 78.456184 -298.154875)
			(xy 78.471768 -298.201556) (xy 78.479663 -298.250133) (xy 78.480158 -298.27474) (xy 78.819006 -298.27474)
			(xy 78.822966 -298.225686) (xy 78.834743 -298.177902) (xy 78.854034 -298.132626) (xy 78.880337 -298.09103)
			(xy 78.912972 -298.054193) (xy 78.951093 -298.023068) (xy 78.993714 -297.998461) (xy 79.03973 -297.981009)
			(xy 79.087949 -297.971165) (xy 79.137124 -297.969184) (xy 79.185979 -297.975116) (xy 79.23325 -297.988808)
			(xy 79.277712 -298.009906) (xy 79.318215 -298.037862) (xy 79.353708 -298.071954) (xy 79.383273 -298.111298)
			(xy 79.406144 -298.154875) (xy 79.421728 -298.201556) (xy 79.429623 -298.250133) (xy 79.430118 -298.27474)
			(xy 79.768966 -298.27474) (xy 79.772926 -298.225686) (xy 79.784703 -298.177902) (xy 79.803994 -298.132626)
			(xy 79.830297 -298.09103) (xy 79.862932 -298.054193) (xy 79.901053 -298.023068) (xy 79.943674 -297.998461)
			(xy 79.98969 -297.981009) (xy 80.037909 -297.971165) (xy 80.087084 -297.969184) (xy 80.135939 -297.975116)
			(xy 80.18321 -297.988808) (xy 80.227672 -298.009906) (xy 80.268175 -298.037862) (xy 80.303668 -298.071954)
			(xy 80.333233 -298.111298) (xy 80.356104 -298.154875) (xy 80.371688 -298.201556) (xy 80.379583 -298.250133)
			(xy 80.380078 -298.27474) (xy 80.71918 -298.27474) (xy 80.72314 -298.225686) (xy 80.734917 -298.177902)
			(xy 80.754208 -298.132626) (xy 80.780511 -298.09103) (xy 80.813146 -298.054193) (xy 80.851267 -298.023068)
			(xy 80.893888 -297.998461) (xy 80.939904 -297.981009) (xy 80.988123 -297.971165) (xy 81.037298 -297.969184)
			(xy 81.086153 -297.975116) (xy 81.133424 -297.988808) (xy 81.177886 -298.009906) (xy 81.218389 -298.037862)
			(xy 81.253882 -298.071954) (xy 81.283447 -298.111298) (xy 81.306318 -298.154875) (xy 81.321902 -298.201556)
			(xy 81.329797 -298.250133) (xy 81.330292 -298.27474) (xy 81.66914 -298.27474) (xy 81.6731 -298.225686)
			(xy 81.684877 -298.177902) (xy 81.704168 -298.132626) (xy 81.730471 -298.09103) (xy 81.763106 -298.054193)
			(xy 81.801227 -298.023068) (xy 81.843848 -297.998461) (xy 81.889864 -297.981009) (xy 81.938083 -297.971165)
			(xy 81.987258 -297.969184) (xy 82.036113 -297.975116) (xy 82.083384 -297.988808) (xy 82.127846 -298.009906)
			(xy 82.168349 -298.037862) (xy 82.203842 -298.071954) (xy 82.233407 -298.111298) (xy 82.256278 -298.154875)
			(xy 82.271862 -298.201556) (xy 82.279757 -298.250133) (xy 82.280252 -298.27474) (xy 82.6191 -298.27474)
			(xy 82.62306 -298.225686) (xy 82.634837 -298.177902) (xy 82.654128 -298.132626) (xy 82.680431 -298.09103)
			(xy 82.713066 -298.054193) (xy 82.751187 -298.023068) (xy 82.793808 -297.998461) (xy 82.839824 -297.981009)
			(xy 82.888043 -297.971165) (xy 82.937218 -297.969184) (xy 82.986073 -297.975116) (xy 83.033344 -297.988808)
			(xy 83.077806 -298.009906) (xy 83.118309 -298.037862) (xy 83.153802 -298.071954) (xy 83.183367 -298.111298)
			(xy 83.206238 -298.154875) (xy 83.221822 -298.201556) (xy 83.229717 -298.250133) (xy 83.230212 -298.27474)
			(xy 83.229717 -298.299347) (xy 83.221822 -298.347924) (xy 83.221246 -298.349649) (xy 83.66759 -298.349649)
			(xy 83.66759 -298.296351) (xy 83.675533 -298.243647) (xy 83.691243 -298.192717) (xy 83.714369 -298.144696)
			(xy 83.744393 -298.100659) (xy 83.780645 -298.061588) (xy 83.822316 -298.028357) (xy 83.868474 -298.001708)
			(xy 83.918088 -297.982236) (xy 83.97005 -297.970376) (xy 84.0232 -297.966393) (xy 84.07635 -297.970376)
			(xy 84.128312 -297.982236) (xy 84.177926 -298.001708) (xy 84.224084 -298.028357) (xy 84.265755 -298.061588)
			(xy 84.302007 -298.100659) (xy 84.332031 -298.144696) (xy 84.355157 -298.192717) (xy 84.370867 -298.243647)
			(xy 84.37881 -298.296351) (xy 84.379308 -298.323) (xy 84.37881 -298.349649) (xy 84.370867 -298.402353)
			(xy 84.355157 -298.453283) (xy 84.332031 -298.501304) (xy 84.302007 -298.545341) (xy 84.265755 -298.584412)
			(xy 84.224084 -298.617643) (xy 84.177926 -298.644292) (xy 84.128312 -298.663764) (xy 84.07635 -298.675624)
			(xy 84.0232 -298.679608) (xy 83.97005 -298.675624) (xy 83.918088 -298.663764) (xy 83.868474 -298.644292)
			(xy 83.822316 -298.617643) (xy 83.780645 -298.584412) (xy 83.744393 -298.545341) (xy 83.714369 -298.501304)
			(xy 83.691243 -298.453283) (xy 83.675533 -298.402353) (xy 83.66759 -298.349649) (xy 83.221246 -298.349649)
			(xy 83.206238 -298.394605) (xy 83.183367 -298.438182) (xy 83.153802 -298.477526) (xy 83.118309 -298.511618)
			(xy 83.077806 -298.539574) (xy 83.033344 -298.560672) (xy 82.986073 -298.574364) (xy 82.937218 -298.580296)
			(xy 82.888043 -298.578315) (xy 82.839824 -298.568471) (xy 82.793808 -298.551019) (xy 82.751187 -298.526412)
			(xy 82.713066 -298.495287) (xy 82.680431 -298.45845) (xy 82.654128 -298.416854) (xy 82.634837 -298.371578)
			(xy 82.62306 -298.323794) (xy 82.6191 -298.27474) (xy 82.280252 -298.27474) (xy 82.279757 -298.299347)
			(xy 82.271862 -298.347924) (xy 82.256278 -298.394605) (xy 82.233407 -298.438182) (xy 82.203842 -298.477526)
			(xy 82.168349 -298.511618) (xy 82.127846 -298.539574) (xy 82.083384 -298.560672) (xy 82.036113 -298.574364)
			(xy 81.987258 -298.580296) (xy 81.938083 -298.578315) (xy 81.889864 -298.568471) (xy 81.843848 -298.551019)
			(xy 81.801227 -298.526412) (xy 81.763106 -298.495287) (xy 81.730471 -298.45845) (xy 81.704168 -298.416854)
			(xy 81.684877 -298.371578) (xy 81.6731 -298.323794) (xy 81.66914 -298.27474) (xy 81.330292 -298.27474)
			(xy 81.329797 -298.299347) (xy 81.321902 -298.347924) (xy 81.306318 -298.394605) (xy 81.283447 -298.438182)
			(xy 81.253882 -298.477526) (xy 81.218389 -298.511618) (xy 81.177886 -298.539574) (xy 81.133424 -298.560672)
			(xy 81.086153 -298.574364) (xy 81.037298 -298.580296) (xy 80.988123 -298.578315) (xy 80.939904 -298.568471)
			(xy 80.893888 -298.551019) (xy 80.851267 -298.526412) (xy 80.813146 -298.495287) (xy 80.780511 -298.45845)
			(xy 80.754208 -298.416854) (xy 80.734917 -298.371578) (xy 80.72314 -298.323794) (xy 80.71918 -298.27474)
			(xy 80.380078 -298.27474) (xy 80.379583 -298.299347) (xy 80.371688 -298.347924) (xy 80.356104 -298.394605)
			(xy 80.333233 -298.438182) (xy 80.303668 -298.477526) (xy 80.268175 -298.511618) (xy 80.227672 -298.539574)
			(xy 80.18321 -298.560672) (xy 80.135939 -298.574364) (xy 80.087084 -298.580296) (xy 80.037909 -298.578315)
			(xy 79.98969 -298.568471) (xy 79.943674 -298.551019) (xy 79.901053 -298.526412) (xy 79.862932 -298.495287)
			(xy 79.830297 -298.45845) (xy 79.803994 -298.416854) (xy 79.784703 -298.371578) (xy 79.772926 -298.323794)
			(xy 79.768966 -298.27474) (xy 79.430118 -298.27474) (xy 79.429623 -298.299347) (xy 79.421728 -298.347924)
			(xy 79.406144 -298.394605) (xy 79.383273 -298.438182) (xy 79.353708 -298.477526) (xy 79.318215 -298.511618)
			(xy 79.277712 -298.539574) (xy 79.23325 -298.560672) (xy 79.185979 -298.574364) (xy 79.137124 -298.580296)
			(xy 79.087949 -298.578315) (xy 79.03973 -298.568471) (xy 78.993714 -298.551019) (xy 78.951093 -298.526412)
			(xy 78.912972 -298.495287) (xy 78.880337 -298.45845) (xy 78.854034 -298.416854) (xy 78.834743 -298.371578)
			(xy 78.822966 -298.323794) (xy 78.819006 -298.27474) (xy 78.480158 -298.27474) (xy 78.479663 -298.299347)
			(xy 78.471768 -298.347924) (xy 78.456184 -298.394605) (xy 78.433313 -298.438182) (xy 78.403748 -298.477526)
			(xy 78.368255 -298.511618) (xy 78.327752 -298.539574) (xy 78.28329 -298.560672) (xy 78.236019 -298.574364)
			(xy 78.187164 -298.580296) (xy 78.137989 -298.578315) (xy 78.08977 -298.568471) (xy 78.043754 -298.551019)
			(xy 78.001133 -298.526412) (xy 77.963012 -298.495287) (xy 77.930377 -298.45845) (xy 77.904074 -298.416854)
			(xy 77.884783 -298.371578) (xy 77.873006 -298.323794) (xy 77.869046 -298.27474) (xy 77.530198 -298.27474)
			(xy 77.529703 -298.299347) (xy 77.521808 -298.347924) (xy 77.506224 -298.394605) (xy 77.483353 -298.438182)
			(xy 77.453788 -298.477526) (xy 77.418295 -298.511618) (xy 77.377792 -298.539574) (xy 77.33333 -298.560672)
			(xy 77.286059 -298.574364) (xy 77.237204 -298.580296) (xy 77.188029 -298.578315) (xy 77.13981 -298.568471)
			(xy 77.093794 -298.551019) (xy 77.051173 -298.526412) (xy 77.013052 -298.495287) (xy 76.980417 -298.45845)
			(xy 76.954114 -298.416854) (xy 76.934823 -298.371578) (xy 76.923046 -298.323794) (xy 76.919086 -298.27474)
			(xy 76.580238 -298.27474) (xy 76.579743 -298.299347) (xy 76.571848 -298.347924) (xy 76.556264 -298.394605)
			(xy 76.533393 -298.438182) (xy 76.503828 -298.477526) (xy 76.468335 -298.511618) (xy 76.427832 -298.539574)
			(xy 76.38337 -298.560672) (xy 76.336099 -298.574364) (xy 76.287244 -298.580296) (xy 76.238069 -298.578315)
			(xy 76.18985 -298.568471) (xy 76.143834 -298.551019) (xy 76.101213 -298.526412) (xy 76.063092 -298.495287)
			(xy 76.030457 -298.45845) (xy 76.004154 -298.416854) (xy 75.984863 -298.371578) (xy 75.973086 -298.323794)
			(xy 75.969126 -298.27474) (xy 75.630278 -298.27474) (xy 75.629783 -298.299347) (xy 75.621888 -298.347924)
			(xy 75.606304 -298.394605) (xy 75.583433 -298.438182) (xy 75.553868 -298.477526) (xy 75.518375 -298.511618)
			(xy 75.477872 -298.539574) (xy 75.43341 -298.560672) (xy 75.386139 -298.574364) (xy 75.337284 -298.580296)
			(xy 75.288109 -298.578315) (xy 75.23989 -298.568471) (xy 75.193874 -298.551019) (xy 75.151253 -298.526412)
			(xy 75.113132 -298.495287) (xy 75.080497 -298.45845) (xy 75.054194 -298.416854) (xy 75.034903 -298.371578)
			(xy 75.023126 -298.323794) (xy 75.019166 -298.27474) (xy 74.680064 -298.27474) (xy 74.679569 -298.299347)
			(xy 74.671674 -298.347924) (xy 74.65609 -298.394605) (xy 74.633219 -298.438182) (xy 74.603654 -298.477526)
			(xy 74.568161 -298.511618) (xy 74.527658 -298.539574) (xy 74.483196 -298.560672) (xy 74.435925 -298.574364)
			(xy 74.38707 -298.580296) (xy 74.337895 -298.578315) (xy 74.289676 -298.568471) (xy 74.24366 -298.551019)
			(xy 74.201039 -298.526412) (xy 74.162918 -298.495287) (xy 74.130283 -298.45845) (xy 74.10398 -298.416854)
			(xy 74.084689 -298.371578) (xy 74.072912 -298.323794) (xy 74.068952 -298.27474) (xy 73.730104 -298.27474)
			(xy 73.729609 -298.299347) (xy 73.721714 -298.347924) (xy 73.70613 -298.394605) (xy 73.683259 -298.438182)
			(xy 73.653694 -298.477526) (xy 73.618201 -298.511618) (xy 73.577698 -298.539574) (xy 73.533236 -298.560672)
			(xy 73.485965 -298.574364) (xy 73.43711 -298.580296) (xy 73.387935 -298.578315) (xy 73.339716 -298.568471)
			(xy 73.2937 -298.551019) (xy 73.251079 -298.526412) (xy 73.212958 -298.495287) (xy 73.180323 -298.45845)
			(xy 73.15402 -298.416854) (xy 73.134729 -298.371578) (xy 73.122952 -298.323794) (xy 73.118992 -298.27474)
			(xy 72.780144 -298.27474) (xy 72.779649 -298.299347) (xy 72.771754 -298.347924) (xy 72.75617 -298.394605)
			(xy 72.733299 -298.438182) (xy 72.703734 -298.477526) (xy 72.668241 -298.511618) (xy 72.627738 -298.539574)
			(xy 72.583276 -298.560672) (xy 72.536005 -298.574364) (xy 72.48715 -298.580296) (xy 72.437975 -298.578315)
			(xy 72.389756 -298.568471) (xy 72.34374 -298.551019) (xy 72.301119 -298.526412) (xy 72.262998 -298.495287)
			(xy 72.230363 -298.45845) (xy 72.20406 -298.416854) (xy 72.184769 -298.371578) (xy 72.172992 -298.323794)
			(xy 72.169032 -298.27474) (xy 71.830184 -298.27474) (xy 71.829689 -298.299347) (xy 71.821794 -298.347924)
			(xy 71.80621 -298.394605) (xy 71.783339 -298.438182) (xy 71.753774 -298.477526) (xy 71.718281 -298.511618)
			(xy 71.677778 -298.539574) (xy 71.633316 -298.560672) (xy 71.586045 -298.574364) (xy 71.53719 -298.580296)
			(xy 71.488015 -298.578315) (xy 71.439796 -298.568471) (xy 71.39378 -298.551019) (xy 71.351159 -298.526412)
			(xy 71.313038 -298.495287) (xy 71.280403 -298.45845) (xy 71.2541 -298.416854) (xy 71.234809 -298.371578)
			(xy 71.223032 -298.323794) (xy 71.219072 -298.27474) (xy 70.880224 -298.27474) (xy 70.879729 -298.299347)
			(xy 70.871834 -298.347924) (xy 70.85625 -298.394605) (xy 70.833379 -298.438182) (xy 70.803814 -298.477526)
			(xy 70.768321 -298.511618) (xy 70.727818 -298.539574) (xy 70.683356 -298.560672) (xy 70.636085 -298.574364)
			(xy 70.58723 -298.580296) (xy 70.538055 -298.578315) (xy 70.489836 -298.568471) (xy 70.44382 -298.551019)
			(xy 70.401199 -298.526412) (xy 70.363078 -298.495287) (xy 70.330443 -298.45845) (xy 70.30414 -298.416854)
			(xy 70.284849 -298.371578) (xy 70.273072 -298.323794) (xy 70.269112 -298.27474) (xy 69.930264 -298.27474)
			(xy 69.929769 -298.299347) (xy 69.921874 -298.347924) (xy 69.90629 -298.394605) (xy 69.883419 -298.438182)
			(xy 69.853854 -298.477526) (xy 69.818361 -298.511618) (xy 69.777858 -298.539574) (xy 69.733396 -298.560672)
			(xy 69.686125 -298.574364) (xy 69.63727 -298.580296) (xy 69.588095 -298.578315) (xy 69.539876 -298.568471)
			(xy 69.49386 -298.551019) (xy 69.451239 -298.526412) (xy 69.413118 -298.495287) (xy 69.380483 -298.45845)
			(xy 69.35418 -298.416854) (xy 69.334889 -298.371578) (xy 69.323112 -298.323794) (xy 69.319152 -298.27474)
			(xy 68.98005 -298.27474) (xy 68.979555 -298.299347) (xy 68.97166 -298.347924) (xy 68.956076 -298.394605)
			(xy 68.933205 -298.438182) (xy 68.90364 -298.477526) (xy 68.868147 -298.511618) (xy 68.827644 -298.539574)
			(xy 68.783182 -298.560672) (xy 68.735911 -298.574364) (xy 68.687056 -298.580296) (xy 68.637881 -298.578315)
			(xy 68.589662 -298.568471) (xy 68.543646 -298.551019) (xy 68.501025 -298.526412) (xy 68.462904 -298.495287)
			(xy 68.430269 -298.45845) (xy 68.403966 -298.416854) (xy 68.384675 -298.371578) (xy 68.372898 -298.323794)
			(xy 68.368938 -298.27474) (xy 67.08013 -298.27474) (xy 67.079635 -298.299347) (xy 67.07174 -298.347924)
			(xy 67.056156 -298.394605) (xy 67.033285 -298.438182) (xy 67.00372 -298.477526) (xy 66.968227 -298.511618)
			(xy 66.927724 -298.539574) (xy 66.883262 -298.560672) (xy 66.835991 -298.574364) (xy 66.787136 -298.580296)
			(xy 66.737961 -298.578315) (xy 66.689742 -298.568471) (xy 66.643726 -298.551019) (xy 66.601105 -298.526412)
			(xy 66.562984 -298.495287) (xy 66.530349 -298.45845) (xy 66.504046 -298.416854) (xy 66.484755 -298.371578)
			(xy 66.472978 -298.323794) (xy 66.469018 -298.27474) (xy 65.18021 -298.27474) (xy 65.179715 -298.299347)
			(xy 65.17182 -298.347924) (xy 65.156236 -298.394605) (xy 65.133365 -298.438182) (xy 65.1038 -298.477526)
			(xy 65.068307 -298.511618) (xy 65.027804 -298.539574) (xy 64.983342 -298.560672) (xy 64.936071 -298.574364)
			(xy 64.887216 -298.580296) (xy 64.838041 -298.578315) (xy 64.789822 -298.568471) (xy 64.743806 -298.551019)
			(xy 64.701185 -298.526412) (xy 64.663064 -298.495287) (xy 64.630429 -298.45845) (xy 64.604126 -298.416854)
			(xy 64.584835 -298.371578) (xy 64.573058 -298.323794) (xy 64.569098 -298.27474) (xy 63.28029 -298.27474)
			(xy 63.279795 -298.299347) (xy 63.2719 -298.347924) (xy 63.256316 -298.394605) (xy 63.233445 -298.438182)
			(xy 63.20388 -298.477526) (xy 63.168387 -298.511618) (xy 63.127884 -298.539574) (xy 63.083422 -298.560672)
			(xy 63.036151 -298.574364) (xy 62.987296 -298.580296) (xy 62.938121 -298.578315) (xy 62.889902 -298.568471)
			(xy 62.843886 -298.551019) (xy 62.801265 -298.526412) (xy 62.763144 -298.495287) (xy 62.730509 -298.45845)
			(xy 62.704206 -298.416854) (xy 62.684915 -298.371578) (xy 62.673138 -298.323794) (xy 62.669178 -298.27474)
			(xy 61.380116 -298.27474) (xy 61.379621 -298.299347) (xy 61.371726 -298.347924) (xy 61.356142 -298.394605)
			(xy 61.333271 -298.438182) (xy 61.303706 -298.477526) (xy 61.268213 -298.511618) (xy 61.22771 -298.539574)
			(xy 61.183248 -298.560672) (xy 61.135977 -298.574364) (xy 61.087122 -298.580296) (xy 61.037947 -298.578315)
			(xy 60.989728 -298.568471) (xy 60.943712 -298.551019) (xy 60.901091 -298.526412) (xy 60.86297 -298.495287)
			(xy 60.830335 -298.45845) (xy 60.804032 -298.416854) (xy 60.784741 -298.371578) (xy 60.772964 -298.323794)
			(xy 60.769004 -298.27474) (xy 58.530236 -298.27474) (xy 58.529741 -298.299347) (xy 58.521846 -298.347924)
			(xy 58.506262 -298.394605) (xy 58.483391 -298.438182) (xy 58.453826 -298.477526) (xy 58.418333 -298.511618)
			(xy 58.37783 -298.539574) (xy 58.333368 -298.560672) (xy 58.286097 -298.574364) (xy 58.237242 -298.580296)
			(xy 58.188067 -298.578315) (xy 58.139848 -298.568471) (xy 58.093832 -298.551019) (xy 58.051211 -298.526412)
			(xy 58.01309 -298.495287) (xy 57.980455 -298.45845) (xy 57.954152 -298.416854) (xy 57.934861 -298.371578)
			(xy 57.923084 -298.323794) (xy 57.919124 -298.27474) (xy 56.630062 -298.27474) (xy 56.629567 -298.299347)
			(xy 56.621672 -298.347924) (xy 56.606088 -298.394605) (xy 56.583217 -298.438182) (xy 56.553652 -298.477526)
			(xy 56.518159 -298.511618) (xy 56.477656 -298.539574) (xy 56.433194 -298.560672) (xy 56.385923 -298.574364)
			(xy 56.337068 -298.580296) (xy 56.287893 -298.578315) (xy 56.239674 -298.568471) (xy 56.193658 -298.551019)
			(xy 56.151037 -298.526412) (xy 56.112916 -298.495287) (xy 56.080281 -298.45845) (xy 56.053978 -298.416854)
			(xy 56.034687 -298.371578) (xy 56.02291 -298.323794) (xy 56.01895 -298.27474) (xy 54.730142 -298.27474)
			(xy 54.729647 -298.299347) (xy 54.721752 -298.347924) (xy 54.706168 -298.394605) (xy 54.683297 -298.438182)
			(xy 54.653732 -298.477526) (xy 54.618239 -298.511618) (xy 54.577736 -298.539574) (xy 54.533274 -298.560672)
			(xy 54.486003 -298.574364) (xy 54.437148 -298.580296) (xy 54.387973 -298.578315) (xy 54.339754 -298.568471)
			(xy 54.293738 -298.551019) (xy 54.251117 -298.526412) (xy 54.212996 -298.495287) (xy 54.180361 -298.45845)
			(xy 54.154058 -298.416854) (xy 54.134767 -298.371578) (xy 54.12299 -298.323794) (xy 54.11903 -298.27474)
			(xy 52.830222 -298.27474) (xy 52.829727 -298.299347) (xy 52.821832 -298.347924) (xy 52.806248 -298.394605)
			(xy 52.783377 -298.438182) (xy 52.753812 -298.477526) (xy 52.718319 -298.511618) (xy 52.677816 -298.539574)
			(xy 52.633354 -298.560672) (xy 52.586083 -298.574364) (xy 52.537228 -298.580296) (xy 52.488053 -298.578315)
			(xy 52.439834 -298.568471) (xy 52.393818 -298.551019) (xy 52.351197 -298.526412) (xy 52.313076 -298.495287)
			(xy 52.280441 -298.45845) (xy 52.254138 -298.416854) (xy 52.234847 -298.371578) (xy 52.22307 -298.323794)
			(xy 52.21911 -298.27474) (xy 50.930302 -298.27474) (xy 50.929807 -298.299347) (xy 50.921912 -298.347924)
			(xy 50.906328 -298.394605) (xy 50.883457 -298.438182) (xy 50.853892 -298.477526) (xy 50.818399 -298.511618)
			(xy 50.777896 -298.539574) (xy 50.733434 -298.560672) (xy 50.686163 -298.574364) (xy 50.637308 -298.580296)
			(xy 50.588133 -298.578315) (xy 50.539914 -298.568471) (xy 50.493898 -298.551019) (xy 50.451277 -298.526412)
			(xy 50.413156 -298.495287) (xy 50.380521 -298.45845) (xy 50.354218 -298.416854) (xy 50.334927 -298.371578)
			(xy 50.32315 -298.323794) (xy 50.31919 -298.27474) (xy 49.149254 -298.27474) (xy 49.149254 -298.7294)
			(xy 86.488268 -298.7294) (xy 86.492339 -298.673778) (xy 86.504465 -298.619341) (xy 86.524388 -298.56725)
			(xy 86.551684 -298.518615) (xy 86.58577 -298.474472) (xy 86.625919 -298.435763) (xy 86.671277 -298.403312)
			(xy 86.720877 -298.377811) (xy 86.773661 -298.359804) (xy 86.828504 -298.349674) (xy 86.884238 -298.347637)
			(xy 86.939675 -298.353737) (xy 86.993632 -298.367843) (xy 87.044961 -298.389655) (xy 87.092567 -298.418709)
			(xy 87.135435 -298.454384) (xy 87.172652 -298.495921) (xy 87.203425 -298.542434) (xy 87.227097 -298.592931)
			(xy 87.243165 -298.646338) (xy 87.251285 -298.701514) (xy 87.251794 -298.7294) (xy 87.251285 -298.757286)
			(xy 87.243165 -298.812462) (xy 87.227097 -298.865869) (xy 87.203425 -298.916366) (xy 87.172652 -298.962879)
			(xy 87.135435 -299.004416) (xy 87.092567 -299.040091) (xy 87.044961 -299.069145) (xy 86.993632 -299.090957)
			(xy 86.939675 -299.105063) (xy 86.884238 -299.111163) (xy 86.828504 -299.109126) (xy 86.773661 -299.098996)
			(xy 86.720877 -299.080989) (xy 86.671277 -299.055488) (xy 86.625919 -299.023037) (xy 86.58577 -298.984328)
			(xy 86.551684 -298.940185) (xy 86.524388 -298.89155) (xy 86.504465 -298.839459) (xy 86.492339 -298.785022)
			(xy 86.488268 -298.7294) (xy 49.149254 -298.7294) (xy 49.149254 -299.224954) (xy 49.368976 -299.224954)
			(xy 49.372936 -299.1759) (xy 49.384713 -299.128116) (xy 49.404004 -299.08284) (xy 49.430307 -299.041244)
			(xy 49.462942 -299.004407) (xy 49.501063 -298.973282) (xy 49.543684 -298.948675) (xy 49.5897 -298.931223)
			(xy 49.637919 -298.921379) (xy 49.687094 -298.919398) (xy 49.735949 -298.92533) (xy 49.78322 -298.939022)
			(xy 49.827682 -298.96012) (xy 49.868185 -298.988076) (xy 49.903678 -299.022168) (xy 49.933243 -299.061512)
			(xy 49.956114 -299.105089) (xy 49.971698 -299.15177) (xy 49.979593 -299.200347) (xy 49.980088 -299.224954)
			(xy 50.31919 -299.224954) (xy 50.32315 -299.1759) (xy 50.334927 -299.128116) (xy 50.354218 -299.08284)
			(xy 50.380521 -299.041244) (xy 50.413156 -299.004407) (xy 50.451277 -298.973282) (xy 50.493898 -298.948675)
			(xy 50.539914 -298.931223) (xy 50.588133 -298.921379) (xy 50.637308 -298.919398) (xy 50.686163 -298.92533)
			(xy 50.733434 -298.939022) (xy 50.777896 -298.96012) (xy 50.818399 -298.988076) (xy 50.853892 -299.022168)
			(xy 50.883457 -299.061512) (xy 50.906328 -299.105089) (xy 50.921912 -299.15177) (xy 50.929807 -299.200347)
			(xy 50.930302 -299.224954) (xy 51.26915 -299.224954) (xy 51.27311 -299.1759) (xy 51.284887 -299.128116)
			(xy 51.304178 -299.08284) (xy 51.330481 -299.041244) (xy 51.363116 -299.004407) (xy 51.401237 -298.973282)
			(xy 51.443858 -298.948675) (xy 51.489874 -298.931223) (xy 51.538093 -298.921379) (xy 51.587268 -298.919398)
			(xy 51.636123 -298.92533) (xy 51.683394 -298.939022) (xy 51.727856 -298.96012) (xy 51.768359 -298.988076)
			(xy 51.803852 -299.022168) (xy 51.833417 -299.061512) (xy 51.856288 -299.105089) (xy 51.871872 -299.15177)
			(xy 51.879767 -299.200347) (xy 51.880262 -299.224954) (xy 52.21911 -299.224954) (xy 52.22307 -299.1759)
			(xy 52.234847 -299.128116) (xy 52.254138 -299.08284) (xy 52.280441 -299.041244) (xy 52.313076 -299.004407)
			(xy 52.351197 -298.973282) (xy 52.393818 -298.948675) (xy 52.439834 -298.931223) (xy 52.488053 -298.921379)
			(xy 52.537228 -298.919398) (xy 52.586083 -298.92533) (xy 52.633354 -298.939022) (xy 52.677816 -298.96012)
			(xy 52.718319 -298.988076) (xy 52.753812 -299.022168) (xy 52.783377 -299.061512) (xy 52.806248 -299.105089)
			(xy 52.821832 -299.15177) (xy 52.829727 -299.200347) (xy 52.830222 -299.224954) (xy 53.16907 -299.224954)
			(xy 53.17303 -299.1759) (xy 53.184807 -299.128116) (xy 53.204098 -299.08284) (xy 53.230401 -299.041244)
			(xy 53.263036 -299.004407) (xy 53.301157 -298.973282) (xy 53.343778 -298.948675) (xy 53.389794 -298.931223)
			(xy 53.438013 -298.921379) (xy 53.487188 -298.919398) (xy 53.536043 -298.92533) (xy 53.583314 -298.939022)
			(xy 53.627776 -298.96012) (xy 53.668279 -298.988076) (xy 53.703772 -299.022168) (xy 53.733337 -299.061512)
			(xy 53.756208 -299.105089) (xy 53.771792 -299.15177) (xy 53.779687 -299.200347) (xy 53.780182 -299.224954)
			(xy 54.11903 -299.224954) (xy 54.12299 -299.1759) (xy 54.134767 -299.128116) (xy 54.154058 -299.08284)
			(xy 54.180361 -299.041244) (xy 54.212996 -299.004407) (xy 54.251117 -298.973282) (xy 54.293738 -298.948675)
			(xy 54.339754 -298.931223) (xy 54.387973 -298.921379) (xy 54.437148 -298.919398) (xy 54.486003 -298.92533)
			(xy 54.533274 -298.939022) (xy 54.577736 -298.96012) (xy 54.618239 -298.988076) (xy 54.653732 -299.022168)
			(xy 54.683297 -299.061512) (xy 54.706168 -299.105089) (xy 54.721752 -299.15177) (xy 54.729647 -299.200347)
			(xy 54.730142 -299.224954) (xy 55.06899 -299.224954) (xy 55.07295 -299.1759) (xy 55.084727 -299.128116)
			(xy 55.104018 -299.08284) (xy 55.130321 -299.041244) (xy 55.162956 -299.004407) (xy 55.201077 -298.973282)
			(xy 55.243698 -298.948675) (xy 55.289714 -298.931223) (xy 55.337933 -298.921379) (xy 55.387108 -298.919398)
			(xy 55.435963 -298.92533) (xy 55.483234 -298.939022) (xy 55.527696 -298.96012) (xy 55.568199 -298.988076)
			(xy 55.603692 -299.022168) (xy 55.633257 -299.061512) (xy 55.656128 -299.105089) (xy 55.671712 -299.15177)
			(xy 55.679607 -299.200347) (xy 55.680102 -299.224954) (xy 56.01895 -299.224954) (xy 56.02291 -299.1759)
			(xy 56.034687 -299.128116) (xy 56.053978 -299.08284) (xy 56.080281 -299.041244) (xy 56.112916 -299.004407)
			(xy 56.151037 -298.973282) (xy 56.193658 -298.948675) (xy 56.239674 -298.931223) (xy 56.287893 -298.921379)
			(xy 56.337068 -298.919398) (xy 56.385923 -298.92533) (xy 56.433194 -298.939022) (xy 56.477656 -298.96012)
			(xy 56.518159 -298.988076) (xy 56.553652 -299.022168) (xy 56.583217 -299.061512) (xy 56.606088 -299.105089)
			(xy 56.621672 -299.15177) (xy 56.629567 -299.200347) (xy 56.630062 -299.224954) (xy 56.969164 -299.224954)
			(xy 56.973124 -299.1759) (xy 56.984901 -299.128116) (xy 57.004192 -299.08284) (xy 57.030495 -299.041244)
			(xy 57.06313 -299.004407) (xy 57.101251 -298.973282) (xy 57.143872 -298.948675) (xy 57.189888 -298.931223)
			(xy 57.238107 -298.921379) (xy 57.287282 -298.919398) (xy 57.336137 -298.92533) (xy 57.383408 -298.939022)
			(xy 57.42787 -298.96012) (xy 57.468373 -298.988076) (xy 57.503866 -299.022168) (xy 57.533431 -299.061512)
			(xy 57.556302 -299.105089) (xy 57.571886 -299.15177) (xy 57.579781 -299.200347) (xy 57.580276 -299.224954)
			(xy 57.919124 -299.224954) (xy 57.923084 -299.1759) (xy 57.934861 -299.128116) (xy 57.954152 -299.08284)
			(xy 57.980455 -299.041244) (xy 58.01309 -299.004407) (xy 58.051211 -298.973282) (xy 58.093832 -298.948675)
			(xy 58.139848 -298.931223) (xy 58.188067 -298.921379) (xy 58.237242 -298.919398) (xy 58.286097 -298.92533)
			(xy 58.333368 -298.939022) (xy 58.37783 -298.96012) (xy 58.418333 -298.988076) (xy 58.453826 -299.022168)
			(xy 58.483391 -299.061512) (xy 58.506262 -299.105089) (xy 58.521846 -299.15177) (xy 58.529741 -299.200347)
			(xy 58.530236 -299.224954) (xy 59.819044 -299.224954) (xy 59.823004 -299.1759) (xy 59.834781 -299.128116)
			(xy 59.854072 -299.08284) (xy 59.880375 -299.041244) (xy 59.91301 -299.004407) (xy 59.951131 -298.973282)
			(xy 59.993752 -298.948675) (xy 60.039768 -298.931223) (xy 60.087987 -298.921379) (xy 60.137162 -298.919398)
			(xy 60.186017 -298.92533) (xy 60.233288 -298.939022) (xy 60.27775 -298.96012) (xy 60.318253 -298.988076)
			(xy 60.353746 -299.022168) (xy 60.383311 -299.061512) (xy 60.406182 -299.105089) (xy 60.421766 -299.15177)
			(xy 60.429661 -299.200347) (xy 60.430156 -299.224954) (xy 60.769004 -299.224954) (xy 60.772964 -299.1759)
			(xy 60.784741 -299.128116) (xy 60.804032 -299.08284) (xy 60.830335 -299.041244) (xy 60.86297 -299.004407)
			(xy 60.901091 -298.973282) (xy 60.943712 -298.948675) (xy 60.989728 -298.931223) (xy 61.037947 -298.921379)
			(xy 61.087122 -298.919398) (xy 61.135977 -298.92533) (xy 61.183248 -298.939022) (xy 61.22771 -298.96012)
			(xy 61.268213 -298.988076) (xy 61.303706 -299.022168) (xy 61.333271 -299.061512) (xy 61.356142 -299.105089)
			(xy 61.371726 -299.15177) (xy 61.379621 -299.200347) (xy 61.380116 -299.224954) (xy 61.718964 -299.224954)
			(xy 61.722924 -299.1759) (xy 61.734701 -299.128116) (xy 61.753992 -299.08284) (xy 61.780295 -299.041244)
			(xy 61.81293 -299.004407) (xy 61.851051 -298.973282) (xy 61.893672 -298.948675) (xy 61.939688 -298.931223)
			(xy 61.987907 -298.921379) (xy 62.037082 -298.919398) (xy 62.085937 -298.92533) (xy 62.133208 -298.939022)
			(xy 62.17767 -298.96012) (xy 62.218173 -298.988076) (xy 62.253666 -299.022168) (xy 62.283231 -299.061512)
			(xy 62.306102 -299.105089) (xy 62.321686 -299.15177) (xy 62.329581 -299.200347) (xy 62.330076 -299.224954)
			(xy 62.669178 -299.224954) (xy 62.673138 -299.1759) (xy 62.684915 -299.128116) (xy 62.704206 -299.08284)
			(xy 62.730509 -299.041244) (xy 62.763144 -299.004407) (xy 62.801265 -298.973282) (xy 62.843886 -298.948675)
			(xy 62.889902 -298.931223) (xy 62.938121 -298.921379) (xy 62.987296 -298.919398) (xy 63.036151 -298.92533)
			(xy 63.083422 -298.939022) (xy 63.127884 -298.96012) (xy 63.168387 -298.988076) (xy 63.20388 -299.022168)
			(xy 63.233445 -299.061512) (xy 63.256316 -299.105089) (xy 63.2719 -299.15177) (xy 63.279795 -299.200347)
			(xy 63.28029 -299.224954) (xy 63.619138 -299.224954) (xy 63.623098 -299.1759) (xy 63.634875 -299.128116)
			(xy 63.654166 -299.08284) (xy 63.680469 -299.041244) (xy 63.713104 -299.004407) (xy 63.751225 -298.973282)
			(xy 63.793846 -298.948675) (xy 63.839862 -298.931223) (xy 63.888081 -298.921379) (xy 63.937256 -298.919398)
			(xy 63.986111 -298.92533) (xy 64.033382 -298.939022) (xy 64.077844 -298.96012) (xy 64.118347 -298.988076)
			(xy 64.15384 -299.022168) (xy 64.183405 -299.061512) (xy 64.206276 -299.105089) (xy 64.22186 -299.15177)
			(xy 64.229755 -299.200347) (xy 64.23025 -299.224954) (xy 64.569098 -299.224954) (xy 64.573058 -299.1759)
			(xy 64.584835 -299.128116) (xy 64.604126 -299.08284) (xy 64.630429 -299.041244) (xy 64.663064 -299.004407)
			(xy 64.701185 -298.973282) (xy 64.743806 -298.948675) (xy 64.789822 -298.931223) (xy 64.838041 -298.921379)
			(xy 64.887216 -298.919398) (xy 64.936071 -298.92533) (xy 64.983342 -298.939022) (xy 65.027804 -298.96012)
			(xy 65.068307 -298.988076) (xy 65.1038 -299.022168) (xy 65.133365 -299.061512) (xy 65.156236 -299.105089)
			(xy 65.17182 -299.15177) (xy 65.179715 -299.200347) (xy 65.18021 -299.224954) (xy 65.519058 -299.224954)
			(xy 65.523018 -299.1759) (xy 65.534795 -299.128116) (xy 65.554086 -299.08284) (xy 65.580389 -299.041244)
			(xy 65.613024 -299.004407) (xy 65.651145 -298.973282) (xy 65.693766 -298.948675) (xy 65.739782 -298.931223)
			(xy 65.788001 -298.921379) (xy 65.837176 -298.919398) (xy 65.886031 -298.92533) (xy 65.933302 -298.939022)
			(xy 65.977764 -298.96012) (xy 66.018267 -298.988076) (xy 66.05376 -299.022168) (xy 66.083325 -299.061512)
			(xy 66.106196 -299.105089) (xy 66.12178 -299.15177) (xy 66.129675 -299.200347) (xy 66.13017 -299.224954)
			(xy 66.469018 -299.224954) (xy 66.472978 -299.1759) (xy 66.484755 -299.128116) (xy 66.504046 -299.08284)
			(xy 66.530349 -299.041244) (xy 66.562984 -299.004407) (xy 66.601105 -298.973282) (xy 66.643726 -298.948675)
			(xy 66.689742 -298.931223) (xy 66.737961 -298.921379) (xy 66.787136 -298.919398) (xy 66.835991 -298.92533)
			(xy 66.883262 -298.939022) (xy 66.927724 -298.96012) (xy 66.968227 -298.988076) (xy 67.00372 -299.022168)
			(xy 67.033285 -299.061512) (xy 67.056156 -299.105089) (xy 67.07174 -299.15177) (xy 67.079635 -299.200347)
			(xy 67.08013 -299.224954) (xy 67.418978 -299.224954) (xy 67.422938 -299.1759) (xy 67.434715 -299.128116)
			(xy 67.454006 -299.08284) (xy 67.480309 -299.041244) (xy 67.512944 -299.004407) (xy 67.551065 -298.973282)
			(xy 67.593686 -298.948675) (xy 67.639702 -298.931223) (xy 67.687921 -298.921379) (xy 67.737096 -298.919398)
			(xy 67.785951 -298.92533) (xy 67.833222 -298.939022) (xy 67.877684 -298.96012) (xy 67.918187 -298.988076)
			(xy 67.95368 -299.022168) (xy 67.983245 -299.061512) (xy 68.006116 -299.105089) (xy 68.0217 -299.15177)
			(xy 68.029595 -299.200347) (xy 68.03009 -299.224954) (xy 68.368938 -299.224954) (xy 68.372898 -299.1759)
			(xy 68.384675 -299.128116) (xy 68.403966 -299.08284) (xy 68.430269 -299.041244) (xy 68.462904 -299.004407)
			(xy 68.501025 -298.973282) (xy 68.543646 -298.948675) (xy 68.589662 -298.931223) (xy 68.637881 -298.921379)
			(xy 68.687056 -298.919398) (xy 68.735911 -298.92533) (xy 68.783182 -298.939022) (xy 68.827644 -298.96012)
			(xy 68.868147 -298.988076) (xy 68.90364 -299.022168) (xy 68.933205 -299.061512) (xy 68.956076 -299.105089)
			(xy 68.97166 -299.15177) (xy 68.979555 -299.200347) (xy 68.98005 -299.224954) (xy 69.319152 -299.224954)
			(xy 69.323112 -299.1759) (xy 69.334889 -299.128116) (xy 69.35418 -299.08284) (xy 69.380483 -299.041244)
			(xy 69.413118 -299.004407) (xy 69.451239 -298.973282) (xy 69.49386 -298.948675) (xy 69.539876 -298.931223)
			(xy 69.588095 -298.921379) (xy 69.63727 -298.919398) (xy 69.686125 -298.92533) (xy 69.733396 -298.939022)
			(xy 69.777858 -298.96012) (xy 69.818361 -298.988076) (xy 69.853854 -299.022168) (xy 69.883419 -299.061512)
			(xy 69.90629 -299.105089) (xy 69.921874 -299.15177) (xy 69.929769 -299.200347) (xy 69.930264 -299.224954)
			(xy 70.269112 -299.224954) (xy 70.273072 -299.1759) (xy 70.284849 -299.128116) (xy 70.30414 -299.08284)
			(xy 70.330443 -299.041244) (xy 70.363078 -299.004407) (xy 70.401199 -298.973282) (xy 70.44382 -298.948675)
			(xy 70.489836 -298.931223) (xy 70.538055 -298.921379) (xy 70.58723 -298.919398) (xy 70.636085 -298.92533)
			(xy 70.683356 -298.939022) (xy 70.727818 -298.96012) (xy 70.768321 -298.988076) (xy 70.803814 -299.022168)
			(xy 70.833379 -299.061512) (xy 70.85625 -299.105089) (xy 70.871834 -299.15177) (xy 70.879729 -299.200347)
			(xy 70.880224 -299.224954) (xy 71.219072 -299.224954) (xy 71.223032 -299.1759) (xy 71.234809 -299.128116)
			(xy 71.2541 -299.08284) (xy 71.280403 -299.041244) (xy 71.313038 -299.004407) (xy 71.351159 -298.973282)
			(xy 71.39378 -298.948675) (xy 71.439796 -298.931223) (xy 71.488015 -298.921379) (xy 71.53719 -298.919398)
			(xy 71.586045 -298.92533) (xy 71.633316 -298.939022) (xy 71.677778 -298.96012) (xy 71.718281 -298.988076)
			(xy 71.753774 -299.022168) (xy 71.783339 -299.061512) (xy 71.80621 -299.105089) (xy 71.821794 -299.15177)
			(xy 71.829689 -299.200347) (xy 71.830184 -299.224954) (xy 72.169032 -299.224954) (xy 72.172992 -299.1759)
			(xy 72.184769 -299.128116) (xy 72.20406 -299.08284) (xy 72.230363 -299.041244) (xy 72.262998 -299.004407)
			(xy 72.301119 -298.973282) (xy 72.34374 -298.948675) (xy 72.389756 -298.931223) (xy 72.437975 -298.921379)
			(xy 72.48715 -298.919398) (xy 72.536005 -298.92533) (xy 72.583276 -298.939022) (xy 72.627738 -298.96012)
			(xy 72.668241 -298.988076) (xy 72.703734 -299.022168) (xy 72.733299 -299.061512) (xy 72.75617 -299.105089)
			(xy 72.771754 -299.15177) (xy 72.779649 -299.200347) (xy 72.780144 -299.224954) (xy 73.118992 -299.224954)
			(xy 73.122952 -299.1759) (xy 73.134729 -299.128116) (xy 73.15402 -299.08284) (xy 73.180323 -299.041244)
			(xy 73.212958 -299.004407) (xy 73.251079 -298.973282) (xy 73.2937 -298.948675) (xy 73.339716 -298.931223)
			(xy 73.387935 -298.921379) (xy 73.43711 -298.919398) (xy 73.485965 -298.92533) (xy 73.533236 -298.939022)
			(xy 73.577698 -298.96012) (xy 73.618201 -298.988076) (xy 73.653694 -299.022168) (xy 73.683259 -299.061512)
			(xy 73.70613 -299.105089) (xy 73.721714 -299.15177) (xy 73.729609 -299.200347) (xy 73.730104 -299.224954)
			(xy 75.969126 -299.224954) (xy 75.973086 -299.1759) (xy 75.984863 -299.128116) (xy 76.004154 -299.08284)
			(xy 76.030457 -299.041244) (xy 76.063092 -299.004407) (xy 76.101213 -298.973282) (xy 76.143834 -298.948675)
			(xy 76.18985 -298.931223) (xy 76.238069 -298.921379) (xy 76.287244 -298.919398) (xy 76.336099 -298.92533)
			(xy 76.38337 -298.939022) (xy 76.427832 -298.96012) (xy 76.468335 -298.988076) (xy 76.503828 -299.022168)
			(xy 76.533393 -299.061512) (xy 76.556264 -299.105089) (xy 76.571848 -299.15177) (xy 76.579743 -299.200347)
			(xy 76.580238 -299.224954) (xy 76.919086 -299.224954) (xy 76.923046 -299.1759) (xy 76.934823 -299.128116)
			(xy 76.954114 -299.08284) (xy 76.980417 -299.041244) (xy 77.013052 -299.004407) (xy 77.051173 -298.973282)
			(xy 77.093794 -298.948675) (xy 77.13981 -298.931223) (xy 77.188029 -298.921379) (xy 77.237204 -298.919398)
			(xy 77.286059 -298.92533) (xy 77.33333 -298.939022) (xy 77.377792 -298.96012) (xy 77.418295 -298.988076)
			(xy 77.453788 -299.022168) (xy 77.483353 -299.061512) (xy 77.506224 -299.105089) (xy 77.521808 -299.15177)
			(xy 77.529703 -299.200347) (xy 77.530198 -299.224954) (xy 77.869046 -299.224954) (xy 77.873006 -299.1759)
			(xy 77.884783 -299.128116) (xy 77.904074 -299.08284) (xy 77.930377 -299.041244) (xy 77.963012 -299.004407)
			(xy 78.001133 -298.973282) (xy 78.043754 -298.948675) (xy 78.08977 -298.931223) (xy 78.137989 -298.921379)
			(xy 78.187164 -298.919398) (xy 78.236019 -298.92533) (xy 78.28329 -298.939022) (xy 78.327752 -298.96012)
			(xy 78.368255 -298.988076) (xy 78.403748 -299.022168) (xy 78.433313 -299.061512) (xy 78.456184 -299.105089)
			(xy 78.471768 -299.15177) (xy 78.479663 -299.200347) (xy 78.480158 -299.224954) (xy 78.819006 -299.224954)
			(xy 78.822966 -299.1759) (xy 78.834743 -299.128116) (xy 78.854034 -299.08284) (xy 78.880337 -299.041244)
			(xy 78.912972 -299.004407) (xy 78.951093 -298.973282) (xy 78.993714 -298.948675) (xy 79.03973 -298.931223)
			(xy 79.087949 -298.921379) (xy 79.137124 -298.919398) (xy 79.185979 -298.92533) (xy 79.23325 -298.939022)
			(xy 79.277712 -298.96012) (xy 79.318215 -298.988076) (xy 79.353708 -299.022168) (xy 79.383273 -299.061512)
			(xy 79.406144 -299.105089) (xy 79.421728 -299.15177) (xy 79.429623 -299.200347) (xy 79.430118 -299.224954)
			(xy 79.768966 -299.224954) (xy 79.772926 -299.1759) (xy 79.784703 -299.128116) (xy 79.803994 -299.08284)
			(xy 79.830297 -299.041244) (xy 79.862932 -299.004407) (xy 79.901053 -298.973282) (xy 79.943674 -298.948675)
			(xy 79.98969 -298.931223) (xy 80.037909 -298.921379) (xy 80.087084 -298.919398) (xy 80.135939 -298.92533)
			(xy 80.18321 -298.939022) (xy 80.227672 -298.96012) (xy 80.268175 -298.988076) (xy 80.303668 -299.022168)
			(xy 80.333233 -299.061512) (xy 80.356104 -299.105089) (xy 80.371688 -299.15177) (xy 80.379583 -299.200347)
			(xy 80.380078 -299.224954) (xy 80.71918 -299.224954) (xy 80.72314 -299.1759) (xy 80.734917 -299.128116)
			(xy 80.754208 -299.08284) (xy 80.780511 -299.041244) (xy 80.813146 -299.004407) (xy 80.851267 -298.973282)
			(xy 80.893888 -298.948675) (xy 80.939904 -298.931223) (xy 80.988123 -298.921379) (xy 81.037298 -298.919398)
			(xy 81.086153 -298.92533) (xy 81.133424 -298.939022) (xy 81.177886 -298.96012) (xy 81.218389 -298.988076)
			(xy 81.253882 -299.022168) (xy 81.283447 -299.061512) (xy 81.306318 -299.105089) (xy 81.321902 -299.15177)
			(xy 81.329797 -299.200347) (xy 81.330292 -299.224954) (xy 81.66914 -299.224954) (xy 81.6731 -299.1759)
			(xy 81.684877 -299.128116) (xy 81.704168 -299.08284) (xy 81.730471 -299.041244) (xy 81.763106 -299.004407)
			(xy 81.801227 -298.973282) (xy 81.843848 -298.948675) (xy 81.889864 -298.931223) (xy 81.938083 -298.921379)
			(xy 81.987258 -298.919398) (xy 82.036113 -298.92533) (xy 82.083384 -298.939022) (xy 82.127846 -298.96012)
			(xy 82.168349 -298.988076) (xy 82.203842 -299.022168) (xy 82.233407 -299.061512) (xy 82.256278 -299.105089)
			(xy 82.271862 -299.15177) (xy 82.279757 -299.200347) (xy 82.280252 -299.224954) (xy 82.6191 -299.224954)
			(xy 82.62306 -299.1759) (xy 82.634837 -299.128116) (xy 82.654128 -299.08284) (xy 82.680431 -299.041244)
			(xy 82.713066 -299.004407) (xy 82.751187 -298.973282) (xy 82.793808 -298.948675) (xy 82.839824 -298.931223)
			(xy 82.888043 -298.921379) (xy 82.937218 -298.919398) (xy 82.986073 -298.92533) (xy 83.033344 -298.939022)
			(xy 83.077806 -298.96012) (xy 83.118309 -298.988076) (xy 83.153802 -299.022168) (xy 83.183367 -299.061512)
			(xy 83.206238 -299.105089) (xy 83.221822 -299.15177) (xy 83.229717 -299.200347) (xy 83.230212 -299.224954)
			(xy 83.229717 -299.249561) (xy 83.221822 -299.298138) (xy 83.206238 -299.344819) (xy 83.183367 -299.388396)
			(xy 83.153802 -299.42774) (xy 83.118309 -299.461832) (xy 83.077806 -299.489788) (xy 83.033344 -299.510886)
			(xy 82.986073 -299.524578) (xy 82.937218 -299.53051) (xy 82.888043 -299.528529) (xy 82.839824 -299.518685)
			(xy 82.793808 -299.501233) (xy 82.751187 -299.476626) (xy 82.713066 -299.445501) (xy 82.680431 -299.408664)
			(xy 82.654128 -299.367068) (xy 82.634837 -299.321792) (xy 82.62306 -299.274008) (xy 82.6191 -299.224954)
			(xy 82.280252 -299.224954) (xy 82.279757 -299.249561) (xy 82.271862 -299.298138) (xy 82.256278 -299.344819)
			(xy 82.233407 -299.388396) (xy 82.203842 -299.42774) (xy 82.168349 -299.461832) (xy 82.127846 -299.489788)
			(xy 82.083384 -299.510886) (xy 82.036113 -299.524578) (xy 81.987258 -299.53051) (xy 81.938083 -299.528529)
			(xy 81.889864 -299.518685) (xy 81.843848 -299.501233) (xy 81.801227 -299.476626) (xy 81.763106 -299.445501)
			(xy 81.730471 -299.408664) (xy 81.704168 -299.367068) (xy 81.684877 -299.321792) (xy 81.6731 -299.274008)
			(xy 81.66914 -299.224954) (xy 81.330292 -299.224954) (xy 81.329797 -299.249561) (xy 81.321902 -299.298138)
			(xy 81.306318 -299.344819) (xy 81.283447 -299.388396) (xy 81.253882 -299.42774) (xy 81.218389 -299.461832)
			(xy 81.177886 -299.489788) (xy 81.133424 -299.510886) (xy 81.086153 -299.524578) (xy 81.037298 -299.53051)
			(xy 80.988123 -299.528529) (xy 80.939904 -299.518685) (xy 80.893888 -299.501233) (xy 80.851267 -299.476626)
			(xy 80.813146 -299.445501) (xy 80.780511 -299.408664) (xy 80.754208 -299.367068) (xy 80.734917 -299.321792)
			(xy 80.72314 -299.274008) (xy 80.71918 -299.224954) (xy 80.380078 -299.224954) (xy 80.379583 -299.249561)
			(xy 80.371688 -299.298138) (xy 80.356104 -299.344819) (xy 80.333233 -299.388396) (xy 80.303668 -299.42774)
			(xy 80.268175 -299.461832) (xy 80.227672 -299.489788) (xy 80.18321 -299.510886) (xy 80.135939 -299.524578)
			(xy 80.087084 -299.53051) (xy 80.037909 -299.528529) (xy 79.98969 -299.518685) (xy 79.943674 -299.501233)
			(xy 79.901053 -299.476626) (xy 79.862932 -299.445501) (xy 79.830297 -299.408664) (xy 79.803994 -299.367068)
			(xy 79.784703 -299.321792) (xy 79.772926 -299.274008) (xy 79.768966 -299.224954) (xy 79.430118 -299.224954)
			(xy 79.429623 -299.249561) (xy 79.421728 -299.298138) (xy 79.406144 -299.344819) (xy 79.383273 -299.388396)
			(xy 79.353708 -299.42774) (xy 79.318215 -299.461832) (xy 79.277712 -299.489788) (xy 79.23325 -299.510886)
			(xy 79.185979 -299.524578) (xy 79.137124 -299.53051) (xy 79.087949 -299.528529) (xy 79.03973 -299.518685)
			(xy 78.993714 -299.501233) (xy 78.951093 -299.476626) (xy 78.912972 -299.445501) (xy 78.880337 -299.408664)
			(xy 78.854034 -299.367068) (xy 78.834743 -299.321792) (xy 78.822966 -299.274008) (xy 78.819006 -299.224954)
			(xy 78.480158 -299.224954) (xy 78.479663 -299.249561) (xy 78.471768 -299.298138) (xy 78.456184 -299.344819)
			(xy 78.433313 -299.388396) (xy 78.403748 -299.42774) (xy 78.368255 -299.461832) (xy 78.327752 -299.489788)
			(xy 78.28329 -299.510886) (xy 78.236019 -299.524578) (xy 78.187164 -299.53051) (xy 78.137989 -299.528529)
			(xy 78.08977 -299.518685) (xy 78.043754 -299.501233) (xy 78.001133 -299.476626) (xy 77.963012 -299.445501)
			(xy 77.930377 -299.408664) (xy 77.904074 -299.367068) (xy 77.884783 -299.321792) (xy 77.873006 -299.274008)
			(xy 77.869046 -299.224954) (xy 77.530198 -299.224954) (xy 77.529703 -299.249561) (xy 77.521808 -299.298138)
			(xy 77.506224 -299.344819) (xy 77.483353 -299.388396) (xy 77.453788 -299.42774) (xy 77.418295 -299.461832)
			(xy 77.377792 -299.489788) (xy 77.33333 -299.510886) (xy 77.286059 -299.524578) (xy 77.237204 -299.53051)
			(xy 77.188029 -299.528529) (xy 77.13981 -299.518685) (xy 77.093794 -299.501233) (xy 77.051173 -299.476626)
			(xy 77.013052 -299.445501) (xy 76.980417 -299.408664) (xy 76.954114 -299.367068) (xy 76.934823 -299.321792)
			(xy 76.923046 -299.274008) (xy 76.919086 -299.224954) (xy 76.580238 -299.224954) (xy 76.579743 -299.249561)
			(xy 76.571848 -299.298138) (xy 76.556264 -299.344819) (xy 76.533393 -299.388396) (xy 76.503828 -299.42774)
			(xy 76.468335 -299.461832) (xy 76.427832 -299.489788) (xy 76.38337 -299.510886) (xy 76.336099 -299.524578)
			(xy 76.287244 -299.53051) (xy 76.238069 -299.528529) (xy 76.18985 -299.518685) (xy 76.143834 -299.501233)
			(xy 76.101213 -299.476626) (xy 76.063092 -299.445501) (xy 76.030457 -299.408664) (xy 76.004154 -299.367068)
			(xy 75.984863 -299.321792) (xy 75.973086 -299.274008) (xy 75.969126 -299.224954) (xy 73.730104 -299.224954)
			(xy 73.729609 -299.249561) (xy 73.721714 -299.298138) (xy 73.70613 -299.344819) (xy 73.683259 -299.388396)
			(xy 73.653694 -299.42774) (xy 73.618201 -299.461832) (xy 73.577698 -299.489788) (xy 73.533236 -299.510886)
			(xy 73.485965 -299.524578) (xy 73.43711 -299.53051) (xy 73.387935 -299.528529) (xy 73.339716 -299.518685)
			(xy 73.2937 -299.501233) (xy 73.251079 -299.476626) (xy 73.212958 -299.445501) (xy 73.180323 -299.408664)
			(xy 73.15402 -299.367068) (xy 73.134729 -299.321792) (xy 73.122952 -299.274008) (xy 73.118992 -299.224954)
			(xy 72.780144 -299.224954) (xy 72.779649 -299.249561) (xy 72.771754 -299.298138) (xy 72.75617 -299.344819)
			(xy 72.733299 -299.388396) (xy 72.703734 -299.42774) (xy 72.668241 -299.461832) (xy 72.627738 -299.489788)
			(xy 72.583276 -299.510886) (xy 72.536005 -299.524578) (xy 72.48715 -299.53051) (xy 72.437975 -299.528529)
			(xy 72.389756 -299.518685) (xy 72.34374 -299.501233) (xy 72.301119 -299.476626) (xy 72.262998 -299.445501)
			(xy 72.230363 -299.408664) (xy 72.20406 -299.367068) (xy 72.184769 -299.321792) (xy 72.172992 -299.274008)
			(xy 72.169032 -299.224954) (xy 71.830184 -299.224954) (xy 71.829689 -299.249561) (xy 71.821794 -299.298138)
			(xy 71.80621 -299.344819) (xy 71.783339 -299.388396) (xy 71.753774 -299.42774) (xy 71.718281 -299.461832)
			(xy 71.677778 -299.489788) (xy 71.633316 -299.510886) (xy 71.586045 -299.524578) (xy 71.53719 -299.53051)
			(xy 71.488015 -299.528529) (xy 71.439796 -299.518685) (xy 71.39378 -299.501233) (xy 71.351159 -299.476626)
			(xy 71.313038 -299.445501) (xy 71.280403 -299.408664) (xy 71.2541 -299.367068) (xy 71.234809 -299.321792)
			(xy 71.223032 -299.274008) (xy 71.219072 -299.224954) (xy 70.880224 -299.224954) (xy 70.879729 -299.249561)
			(xy 70.871834 -299.298138) (xy 70.85625 -299.344819) (xy 70.833379 -299.388396) (xy 70.803814 -299.42774)
			(xy 70.768321 -299.461832) (xy 70.727818 -299.489788) (xy 70.683356 -299.510886) (xy 70.636085 -299.524578)
			(xy 70.58723 -299.53051) (xy 70.538055 -299.528529) (xy 70.489836 -299.518685) (xy 70.44382 -299.501233)
			(xy 70.401199 -299.476626) (xy 70.363078 -299.445501) (xy 70.330443 -299.408664) (xy 70.30414 -299.367068)
			(xy 70.284849 -299.321792) (xy 70.273072 -299.274008) (xy 70.269112 -299.224954) (xy 69.930264 -299.224954)
			(xy 69.929769 -299.249561) (xy 69.921874 -299.298138) (xy 69.90629 -299.344819) (xy 69.883419 -299.388396)
			(xy 69.853854 -299.42774) (xy 69.818361 -299.461832) (xy 69.777858 -299.489788) (xy 69.733396 -299.510886)
			(xy 69.686125 -299.524578) (xy 69.63727 -299.53051) (xy 69.588095 -299.528529) (xy 69.539876 -299.518685)
			(xy 69.49386 -299.501233) (xy 69.451239 -299.476626) (xy 69.413118 -299.445501) (xy 69.380483 -299.408664)
			(xy 69.35418 -299.367068) (xy 69.334889 -299.321792) (xy 69.323112 -299.274008) (xy 69.319152 -299.224954)
			(xy 68.98005 -299.224954) (xy 68.979555 -299.249561) (xy 68.97166 -299.298138) (xy 68.956076 -299.344819)
			(xy 68.933205 -299.388396) (xy 68.90364 -299.42774) (xy 68.868147 -299.461832) (xy 68.827644 -299.489788)
			(xy 68.783182 -299.510886) (xy 68.735911 -299.524578) (xy 68.687056 -299.53051) (xy 68.637881 -299.528529)
			(xy 68.589662 -299.518685) (xy 68.543646 -299.501233) (xy 68.501025 -299.476626) (xy 68.462904 -299.445501)
			(xy 68.430269 -299.408664) (xy 68.403966 -299.367068) (xy 68.384675 -299.321792) (xy 68.372898 -299.274008)
			(xy 68.368938 -299.224954) (xy 68.03009 -299.224954) (xy 68.029595 -299.249561) (xy 68.0217 -299.298138)
			(xy 68.006116 -299.344819) (xy 67.983245 -299.388396) (xy 67.95368 -299.42774) (xy 67.918187 -299.461832)
			(xy 67.877684 -299.489788) (xy 67.833222 -299.510886) (xy 67.785951 -299.524578) (xy 67.737096 -299.53051)
			(xy 67.687921 -299.528529) (xy 67.639702 -299.518685) (xy 67.593686 -299.501233) (xy 67.551065 -299.476626)
			(xy 67.512944 -299.445501) (xy 67.480309 -299.408664) (xy 67.454006 -299.367068) (xy 67.434715 -299.321792)
			(xy 67.422938 -299.274008) (xy 67.418978 -299.224954) (xy 67.08013 -299.224954) (xy 67.079635 -299.249561)
			(xy 67.07174 -299.298138) (xy 67.056156 -299.344819) (xy 67.033285 -299.388396) (xy 67.00372 -299.42774)
			(xy 66.968227 -299.461832) (xy 66.927724 -299.489788) (xy 66.883262 -299.510886) (xy 66.835991 -299.524578)
			(xy 66.787136 -299.53051) (xy 66.737961 -299.528529) (xy 66.689742 -299.518685) (xy 66.643726 -299.501233)
			(xy 66.601105 -299.476626) (xy 66.562984 -299.445501) (xy 66.530349 -299.408664) (xy 66.504046 -299.367068)
			(xy 66.484755 -299.321792) (xy 66.472978 -299.274008) (xy 66.469018 -299.224954) (xy 66.13017 -299.224954)
			(xy 66.129675 -299.249561) (xy 66.12178 -299.298138) (xy 66.106196 -299.344819) (xy 66.083325 -299.388396)
			(xy 66.05376 -299.42774) (xy 66.018267 -299.461832) (xy 65.977764 -299.489788) (xy 65.933302 -299.510886)
			(xy 65.886031 -299.524578) (xy 65.837176 -299.53051) (xy 65.788001 -299.528529) (xy 65.739782 -299.518685)
			(xy 65.693766 -299.501233) (xy 65.651145 -299.476626) (xy 65.613024 -299.445501) (xy 65.580389 -299.408664)
			(xy 65.554086 -299.367068) (xy 65.534795 -299.321792) (xy 65.523018 -299.274008) (xy 65.519058 -299.224954)
			(xy 65.18021 -299.224954) (xy 65.179715 -299.249561) (xy 65.17182 -299.298138) (xy 65.156236 -299.344819)
			(xy 65.133365 -299.388396) (xy 65.1038 -299.42774) (xy 65.068307 -299.461832) (xy 65.027804 -299.489788)
			(xy 64.983342 -299.510886) (xy 64.936071 -299.524578) (xy 64.887216 -299.53051) (xy 64.838041 -299.528529)
			(xy 64.789822 -299.518685) (xy 64.743806 -299.501233) (xy 64.701185 -299.476626) (xy 64.663064 -299.445501)
			(xy 64.630429 -299.408664) (xy 64.604126 -299.367068) (xy 64.584835 -299.321792) (xy 64.573058 -299.274008)
			(xy 64.569098 -299.224954) (xy 64.23025 -299.224954) (xy 64.229755 -299.249561) (xy 64.22186 -299.298138)
			(xy 64.206276 -299.344819) (xy 64.183405 -299.388396) (xy 64.15384 -299.42774) (xy 64.118347 -299.461832)
			(xy 64.077844 -299.489788) (xy 64.033382 -299.510886) (xy 63.986111 -299.524578) (xy 63.937256 -299.53051)
			(xy 63.888081 -299.528529) (xy 63.839862 -299.518685) (xy 63.793846 -299.501233) (xy 63.751225 -299.476626)
			(xy 63.713104 -299.445501) (xy 63.680469 -299.408664) (xy 63.654166 -299.367068) (xy 63.634875 -299.321792)
			(xy 63.623098 -299.274008) (xy 63.619138 -299.224954) (xy 63.28029 -299.224954) (xy 63.279795 -299.249561)
			(xy 63.2719 -299.298138) (xy 63.256316 -299.344819) (xy 63.233445 -299.388396) (xy 63.20388 -299.42774)
			(xy 63.168387 -299.461832) (xy 63.127884 -299.489788) (xy 63.083422 -299.510886) (xy 63.036151 -299.524578)
			(xy 62.987296 -299.53051) (xy 62.938121 -299.528529) (xy 62.889902 -299.518685) (xy 62.843886 -299.501233)
			(xy 62.801265 -299.476626) (xy 62.763144 -299.445501) (xy 62.730509 -299.408664) (xy 62.704206 -299.367068)
			(xy 62.684915 -299.321792) (xy 62.673138 -299.274008) (xy 62.669178 -299.224954) (xy 62.330076 -299.224954)
			(xy 62.329581 -299.249561) (xy 62.321686 -299.298138) (xy 62.306102 -299.344819) (xy 62.283231 -299.388396)
			(xy 62.253666 -299.42774) (xy 62.218173 -299.461832) (xy 62.17767 -299.489788) (xy 62.133208 -299.510886)
			(xy 62.085937 -299.524578) (xy 62.037082 -299.53051) (xy 61.987907 -299.528529) (xy 61.939688 -299.518685)
			(xy 61.893672 -299.501233) (xy 61.851051 -299.476626) (xy 61.81293 -299.445501) (xy 61.780295 -299.408664)
			(xy 61.753992 -299.367068) (xy 61.734701 -299.321792) (xy 61.722924 -299.274008) (xy 61.718964 -299.224954)
			(xy 61.380116 -299.224954) (xy 61.379621 -299.249561) (xy 61.371726 -299.298138) (xy 61.356142 -299.344819)
			(xy 61.333271 -299.388396) (xy 61.303706 -299.42774) (xy 61.268213 -299.461832) (xy 61.22771 -299.489788)
			(xy 61.183248 -299.510886) (xy 61.135977 -299.524578) (xy 61.087122 -299.53051) (xy 61.037947 -299.528529)
			(xy 60.989728 -299.518685) (xy 60.943712 -299.501233) (xy 60.901091 -299.476626) (xy 60.86297 -299.445501)
			(xy 60.830335 -299.408664) (xy 60.804032 -299.367068) (xy 60.784741 -299.321792) (xy 60.772964 -299.274008)
			(xy 60.769004 -299.224954) (xy 60.430156 -299.224954) (xy 60.429661 -299.249561) (xy 60.421766 -299.298138)
			(xy 60.406182 -299.344819) (xy 60.383311 -299.388396) (xy 60.353746 -299.42774) (xy 60.318253 -299.461832)
			(xy 60.27775 -299.489788) (xy 60.233288 -299.510886) (xy 60.186017 -299.524578) (xy 60.137162 -299.53051)
			(xy 60.087987 -299.528529) (xy 60.039768 -299.518685) (xy 59.993752 -299.501233) (xy 59.951131 -299.476626)
			(xy 59.91301 -299.445501) (xy 59.880375 -299.408664) (xy 59.854072 -299.367068) (xy 59.834781 -299.321792)
			(xy 59.823004 -299.274008) (xy 59.819044 -299.224954) (xy 58.530236 -299.224954) (xy 58.529741 -299.249561)
			(xy 58.521846 -299.298138) (xy 58.506262 -299.344819) (xy 58.483391 -299.388396) (xy 58.453826 -299.42774)
			(xy 58.418333 -299.461832) (xy 58.37783 -299.489788) (xy 58.333368 -299.510886) (xy 58.286097 -299.524578)
			(xy 58.237242 -299.53051) (xy 58.188067 -299.528529) (xy 58.139848 -299.518685) (xy 58.093832 -299.501233)
			(xy 58.051211 -299.476626) (xy 58.01309 -299.445501) (xy 57.980455 -299.408664) (xy 57.954152 -299.367068)
			(xy 57.934861 -299.321792) (xy 57.923084 -299.274008) (xy 57.919124 -299.224954) (xy 57.580276 -299.224954)
			(xy 57.579781 -299.249561) (xy 57.571886 -299.298138) (xy 57.556302 -299.344819) (xy 57.533431 -299.388396)
			(xy 57.503866 -299.42774) (xy 57.468373 -299.461832) (xy 57.42787 -299.489788) (xy 57.383408 -299.510886)
			(xy 57.336137 -299.524578) (xy 57.287282 -299.53051) (xy 57.238107 -299.528529) (xy 57.189888 -299.518685)
			(xy 57.143872 -299.501233) (xy 57.101251 -299.476626) (xy 57.06313 -299.445501) (xy 57.030495 -299.408664)
			(xy 57.004192 -299.367068) (xy 56.984901 -299.321792) (xy 56.973124 -299.274008) (xy 56.969164 -299.224954)
			(xy 56.630062 -299.224954) (xy 56.629567 -299.249561) (xy 56.621672 -299.298138) (xy 56.606088 -299.344819)
			(xy 56.583217 -299.388396) (xy 56.553652 -299.42774) (xy 56.518159 -299.461832) (xy 56.477656 -299.489788)
			(xy 56.433194 -299.510886) (xy 56.385923 -299.524578) (xy 56.337068 -299.53051) (xy 56.287893 -299.528529)
			(xy 56.239674 -299.518685) (xy 56.193658 -299.501233) (xy 56.151037 -299.476626) (xy 56.112916 -299.445501)
			(xy 56.080281 -299.408664) (xy 56.053978 -299.367068) (xy 56.034687 -299.321792) (xy 56.02291 -299.274008)
			(xy 56.01895 -299.224954) (xy 55.680102 -299.224954) (xy 55.679607 -299.249561) (xy 55.671712 -299.298138)
			(xy 55.656128 -299.344819) (xy 55.633257 -299.388396) (xy 55.603692 -299.42774) (xy 55.568199 -299.461832)
			(xy 55.527696 -299.489788) (xy 55.483234 -299.510886) (xy 55.435963 -299.524578) (xy 55.387108 -299.53051)
			(xy 55.337933 -299.528529) (xy 55.289714 -299.518685) (xy 55.243698 -299.501233) (xy 55.201077 -299.476626)
			(xy 55.162956 -299.445501) (xy 55.130321 -299.408664) (xy 55.104018 -299.367068) (xy 55.084727 -299.321792)
			(xy 55.07295 -299.274008) (xy 55.06899 -299.224954) (xy 54.730142 -299.224954) (xy 54.729647 -299.249561)
			(xy 54.721752 -299.298138) (xy 54.706168 -299.344819) (xy 54.683297 -299.388396) (xy 54.653732 -299.42774)
			(xy 54.618239 -299.461832) (xy 54.577736 -299.489788) (xy 54.533274 -299.510886) (xy 54.486003 -299.524578)
			(xy 54.437148 -299.53051) (xy 54.387973 -299.528529) (xy 54.339754 -299.518685) (xy 54.293738 -299.501233)
			(xy 54.251117 -299.476626) (xy 54.212996 -299.445501) (xy 54.180361 -299.408664) (xy 54.154058 -299.367068)
			(xy 54.134767 -299.321792) (xy 54.12299 -299.274008) (xy 54.11903 -299.224954) (xy 53.780182 -299.224954)
			(xy 53.779687 -299.249561) (xy 53.771792 -299.298138) (xy 53.756208 -299.344819) (xy 53.733337 -299.388396)
			(xy 53.703772 -299.42774) (xy 53.668279 -299.461832) (xy 53.627776 -299.489788) (xy 53.583314 -299.510886)
			(xy 53.536043 -299.524578) (xy 53.487188 -299.53051) (xy 53.438013 -299.528529) (xy 53.389794 -299.518685)
			(xy 53.343778 -299.501233) (xy 53.301157 -299.476626) (xy 53.263036 -299.445501) (xy 53.230401 -299.408664)
			(xy 53.204098 -299.367068) (xy 53.184807 -299.321792) (xy 53.17303 -299.274008) (xy 53.16907 -299.224954)
			(xy 52.830222 -299.224954) (xy 52.829727 -299.249561) (xy 52.821832 -299.298138) (xy 52.806248 -299.344819)
			(xy 52.783377 -299.388396) (xy 52.753812 -299.42774) (xy 52.718319 -299.461832) (xy 52.677816 -299.489788)
			(xy 52.633354 -299.510886) (xy 52.586083 -299.524578) (xy 52.537228 -299.53051) (xy 52.488053 -299.528529)
			(xy 52.439834 -299.518685) (xy 52.393818 -299.501233) (xy 52.351197 -299.476626) (xy 52.313076 -299.445501)
			(xy 52.280441 -299.408664) (xy 52.254138 -299.367068) (xy 52.234847 -299.321792) (xy 52.22307 -299.274008)
			(xy 52.21911 -299.224954) (xy 51.880262 -299.224954) (xy 51.879767 -299.249561) (xy 51.871872 -299.298138)
			(xy 51.856288 -299.344819) (xy 51.833417 -299.388396) (xy 51.803852 -299.42774) (xy 51.768359 -299.461832)
			(xy 51.727856 -299.489788) (xy 51.683394 -299.510886) (xy 51.636123 -299.524578) (xy 51.587268 -299.53051)
			(xy 51.538093 -299.528529) (xy 51.489874 -299.518685) (xy 51.443858 -299.501233) (xy 51.401237 -299.476626)
			(xy 51.363116 -299.445501) (xy 51.330481 -299.408664) (xy 51.304178 -299.367068) (xy 51.284887 -299.321792)
			(xy 51.27311 -299.274008) (xy 51.26915 -299.224954) (xy 50.930302 -299.224954) (xy 50.929807 -299.249561)
			(xy 50.921912 -299.298138) (xy 50.906328 -299.344819) (xy 50.883457 -299.388396) (xy 50.853892 -299.42774)
			(xy 50.818399 -299.461832) (xy 50.777896 -299.489788) (xy 50.733434 -299.510886) (xy 50.686163 -299.524578)
			(xy 50.637308 -299.53051) (xy 50.588133 -299.528529) (xy 50.539914 -299.518685) (xy 50.493898 -299.501233)
			(xy 50.451277 -299.476626) (xy 50.413156 -299.445501) (xy 50.380521 -299.408664) (xy 50.354218 -299.367068)
			(xy 50.334927 -299.321792) (xy 50.32315 -299.274008) (xy 50.31919 -299.224954) (xy 49.980088 -299.224954)
			(xy 49.979593 -299.249561) (xy 49.971698 -299.298138) (xy 49.956114 -299.344819) (xy 49.933243 -299.388396)
			(xy 49.903678 -299.42774) (xy 49.868185 -299.461832) (xy 49.827682 -299.489788) (xy 49.78322 -299.510886)
			(xy 49.735949 -299.524578) (xy 49.687094 -299.53051) (xy 49.637919 -299.528529) (xy 49.5897 -299.518685)
			(xy 49.543684 -299.501233) (xy 49.501063 -299.476626) (xy 49.462942 -299.445501) (xy 49.430307 -299.408664)
			(xy 49.404004 -299.367068) (xy 49.384713 -299.321792) (xy 49.372936 -299.274008) (xy 49.368976 -299.224954)
			(xy 49.149254 -299.224954) (xy 49.149254 -299.76445) (xy 88.041732 -299.76445) (xy 88.045803 -299.708828)
			(xy 88.057929 -299.654391) (xy 88.077852 -299.6023) (xy 88.105148 -299.553665) (xy 88.139234 -299.509522)
			(xy 88.179383 -299.470813) (xy 88.224741 -299.438362) (xy 88.274341 -299.412861) (xy 88.327125 -299.394854)
			(xy 88.381968 -299.384724) (xy 88.437702 -299.382687) (xy 88.493139 -299.388787) (xy 88.547096 -299.402893)
			(xy 88.598425 -299.424705) (xy 88.646031 -299.453759) (xy 88.688899 -299.489434) (xy 88.726116 -299.530971)
			(xy 88.756889 -299.577484) (xy 88.769164 -299.603668) (xy 90.31046 -299.603668) (xy 90.314531 -299.548046)
			(xy 90.326657 -299.493609) (xy 90.34658 -299.441518) (xy 90.373876 -299.392883) (xy 90.407962 -299.34874)
			(xy 90.448111 -299.310031) (xy 90.493469 -299.27758) (xy 90.543069 -299.252079) (xy 90.595853 -299.234072)
			(xy 90.650696 -299.223942) (xy 90.70643 -299.221905) (xy 90.761867 -299.228005) (xy 90.815824 -299.242111)
			(xy 90.867153 -299.263923) (xy 90.914759 -299.292977) (xy 90.957627 -299.328652) (xy 90.994844 -299.370189)
			(xy 91.025617 -299.416702) (xy 91.049289 -299.467199) (xy 91.065357 -299.520606) (xy 91.073477 -299.575782)
			(xy 91.073986 -299.603668) (xy 91.073477 -299.631554) (xy 91.065357 -299.68673) (xy 91.049289 -299.740137)
			(xy 91.030747 -299.77969) (xy 92.63837 -299.77969) (xy 92.642441 -299.724068) (xy 92.654567 -299.669631)
			(xy 92.67449 -299.61754) (xy 92.701786 -299.568905) (xy 92.735872 -299.524762) (xy 92.776021 -299.486053)
			(xy 92.821379 -299.453602) (xy 92.870979 -299.428101) (xy 92.923763 -299.410094) (xy 92.978606 -299.399964)
			(xy 93.03434 -299.397927) (xy 93.089777 -299.404027) (xy 93.143734 -299.418133) (xy 93.195063 -299.439945)
			(xy 93.242669 -299.468999) (xy 93.285537 -299.504674) (xy 93.322754 -299.546211) (xy 93.353527 -299.592724)
			(xy 93.377199 -299.643221) (xy 93.393267 -299.696628) (xy 93.401387 -299.751804) (xy 93.401896 -299.77969)
			(xy 93.401387 -299.807576) (xy 93.393267 -299.862752) (xy 93.377199 -299.916159) (xy 93.353527 -299.966656)
			(xy 93.322754 -300.013169) (xy 93.285537 -300.054706) (xy 93.242669 -300.090381) (xy 93.195063 -300.119435)
			(xy 93.143734 -300.141247) (xy 93.089777 -300.155353) (xy 93.03434 -300.161453) (xy 92.978606 -300.159416)
			(xy 92.923763 -300.149286) (xy 92.870979 -300.131279) (xy 92.821379 -300.105778) (xy 92.776021 -300.073327)
			(xy 92.735872 -300.034618) (xy 92.701786 -299.990475) (xy 92.67449 -299.94184) (xy 92.654567 -299.889749)
			(xy 92.642441 -299.835312) (xy 92.63837 -299.77969) (xy 91.030747 -299.77969) (xy 91.025617 -299.790634)
			(xy 90.994844 -299.837147) (xy 90.957627 -299.878684) (xy 90.914759 -299.914359) (xy 90.867153 -299.943413)
			(xy 90.815824 -299.965225) (xy 90.761867 -299.979331) (xy 90.70643 -299.985431) (xy 90.650696 -299.983394)
			(xy 90.595853 -299.973264) (xy 90.543069 -299.955257) (xy 90.493469 -299.929756) (xy 90.448111 -299.897305)
			(xy 90.407962 -299.858596) (xy 90.373876 -299.814453) (xy 90.34658 -299.765818) (xy 90.326657 -299.713727)
			(xy 90.314531 -299.65929) (xy 90.31046 -299.603668) (xy 88.769164 -299.603668) (xy 88.780561 -299.627981)
			(xy 88.796629 -299.681388) (xy 88.804749 -299.736564) (xy 88.805258 -299.76445) (xy 88.804749 -299.792336)
			(xy 88.796629 -299.847512) (xy 88.780561 -299.900919) (xy 88.756889 -299.951416) (xy 88.726116 -299.997929)
			(xy 88.688899 -300.039466) (xy 88.646031 -300.075141) (xy 88.598425 -300.104195) (xy 88.547096 -300.126007)
			(xy 88.493139 -300.140113) (xy 88.437702 -300.146213) (xy 88.381968 -300.144176) (xy 88.327125 -300.134046)
			(xy 88.274341 -300.116039) (xy 88.224741 -300.090538) (xy 88.179383 -300.058087) (xy 88.139234 -300.019378)
			(xy 88.105148 -299.975235) (xy 88.077852 -299.9266) (xy 88.057929 -299.874509) (xy 88.045803 -299.820072)
			(xy 88.041732 -299.76445) (xy 49.149254 -299.76445) (xy 49.149254 -300.174914) (xy 50.31919 -300.174914)
			(xy 50.32315 -300.12586) (xy 50.334927 -300.078076) (xy 50.354218 -300.0328) (xy 50.380521 -299.991204)
			(xy 50.413156 -299.954367) (xy 50.451277 -299.923242) (xy 50.493898 -299.898635) (xy 50.539914 -299.881183)
			(xy 50.588133 -299.871339) (xy 50.637308 -299.869358) (xy 50.686163 -299.87529) (xy 50.733434 -299.888982)
			(xy 50.777896 -299.91008) (xy 50.818399 -299.938036) (xy 50.853892 -299.972128) (xy 50.883457 -300.011472)
			(xy 50.906328 -300.055049) (xy 50.921912 -300.10173) (xy 50.929807 -300.150307) (xy 50.930302 -300.174914)
			(xy 51.26915 -300.174914) (xy 51.27311 -300.12586) (xy 51.284887 -300.078076) (xy 51.304178 -300.0328)
			(xy 51.330481 -299.991204) (xy 51.363116 -299.954367) (xy 51.401237 -299.923242) (xy 51.443858 -299.898635)
			(xy 51.489874 -299.881183) (xy 51.538093 -299.871339) (xy 51.587268 -299.869358) (xy 51.636123 -299.87529)
			(xy 51.683394 -299.888982) (xy 51.727856 -299.91008) (xy 51.768359 -299.938036) (xy 51.803852 -299.972128)
			(xy 51.833417 -300.011472) (xy 51.856288 -300.055049) (xy 51.871872 -300.10173) (xy 51.879767 -300.150307)
			(xy 51.880262 -300.174914) (xy 52.21911 -300.174914) (xy 52.22307 -300.12586) (xy 52.234847 -300.078076)
			(xy 52.254138 -300.0328) (xy 52.280441 -299.991204) (xy 52.313076 -299.954367) (xy 52.351197 -299.923242)
			(xy 52.393818 -299.898635) (xy 52.439834 -299.881183) (xy 52.488053 -299.871339) (xy 52.537228 -299.869358)
			(xy 52.586083 -299.87529) (xy 52.633354 -299.888982) (xy 52.677816 -299.91008) (xy 52.718319 -299.938036)
			(xy 52.753812 -299.972128) (xy 52.783377 -300.011472) (xy 52.806248 -300.055049) (xy 52.821832 -300.10173)
			(xy 52.829727 -300.150307) (xy 52.830222 -300.174914) (xy 53.16907 -300.174914) (xy 53.17303 -300.12586)
			(xy 53.184807 -300.078076) (xy 53.204098 -300.0328) (xy 53.230401 -299.991204) (xy 53.263036 -299.954367)
			(xy 53.301157 -299.923242) (xy 53.343778 -299.898635) (xy 53.389794 -299.881183) (xy 53.438013 -299.871339)
			(xy 53.487188 -299.869358) (xy 53.536043 -299.87529) (xy 53.583314 -299.888982) (xy 53.627776 -299.91008)
			(xy 53.668279 -299.938036) (xy 53.703772 -299.972128) (xy 53.733337 -300.011472) (xy 53.756208 -300.055049)
			(xy 53.771792 -300.10173) (xy 53.779687 -300.150307) (xy 53.780182 -300.174914) (xy 54.11903 -300.174914)
			(xy 54.12299 -300.12586) (xy 54.134767 -300.078076) (xy 54.154058 -300.0328) (xy 54.180361 -299.991204)
			(xy 54.212996 -299.954367) (xy 54.251117 -299.923242) (xy 54.293738 -299.898635) (xy 54.339754 -299.881183)
			(xy 54.387973 -299.871339) (xy 54.437148 -299.869358) (xy 54.486003 -299.87529) (xy 54.533274 -299.888982)
			(xy 54.577736 -299.91008) (xy 54.618239 -299.938036) (xy 54.653732 -299.972128) (xy 54.683297 -300.011472)
			(xy 54.706168 -300.055049) (xy 54.721752 -300.10173) (xy 54.729647 -300.150307) (xy 54.730142 -300.174914)
			(xy 55.06899 -300.174914) (xy 55.07295 -300.12586) (xy 55.084727 -300.078076) (xy 55.104018 -300.0328)
			(xy 55.130321 -299.991204) (xy 55.162956 -299.954367) (xy 55.201077 -299.923242) (xy 55.243698 -299.898635)
			(xy 55.289714 -299.881183) (xy 55.337933 -299.871339) (xy 55.387108 -299.869358) (xy 55.435963 -299.87529)
			(xy 55.483234 -299.888982) (xy 55.527696 -299.91008) (xy 55.568199 -299.938036) (xy 55.603692 -299.972128)
			(xy 55.633257 -300.011472) (xy 55.656128 -300.055049) (xy 55.671712 -300.10173) (xy 55.679607 -300.150307)
			(xy 55.680102 -300.174914) (xy 56.01895 -300.174914) (xy 56.02291 -300.12586) (xy 56.034687 -300.078076)
			(xy 56.053978 -300.0328) (xy 56.080281 -299.991204) (xy 56.112916 -299.954367) (xy 56.151037 -299.923242)
			(xy 56.193658 -299.898635) (xy 56.239674 -299.881183) (xy 56.287893 -299.871339) (xy 56.337068 -299.869358)
			(xy 56.385923 -299.87529) (xy 56.433194 -299.888982) (xy 56.477656 -299.91008) (xy 56.518159 -299.938036)
			(xy 56.553652 -299.972128) (xy 56.583217 -300.011472) (xy 56.606088 -300.055049) (xy 56.621672 -300.10173)
			(xy 56.629567 -300.150307) (xy 56.630062 -300.174914) (xy 56.969164 -300.174914) (xy 56.973124 -300.12586)
			(xy 56.984901 -300.078076) (xy 57.004192 -300.0328) (xy 57.030495 -299.991204) (xy 57.06313 -299.954367)
			(xy 57.101251 -299.923242) (xy 57.143872 -299.898635) (xy 57.189888 -299.881183) (xy 57.238107 -299.871339)
			(xy 57.287282 -299.869358) (xy 57.336137 -299.87529) (xy 57.383408 -299.888982) (xy 57.42787 -299.91008)
			(xy 57.468373 -299.938036) (xy 57.503866 -299.972128) (xy 57.533431 -300.011472) (xy 57.556302 -300.055049)
			(xy 57.571886 -300.10173) (xy 57.579781 -300.150307) (xy 57.580276 -300.174914) (xy 57.919124 -300.174914)
			(xy 57.923084 -300.12586) (xy 57.934861 -300.078076) (xy 57.954152 -300.0328) (xy 57.980455 -299.991204)
			(xy 58.01309 -299.954367) (xy 58.051211 -299.923242) (xy 58.093832 -299.898635) (xy 58.139848 -299.881183)
			(xy 58.188067 -299.871339) (xy 58.237242 -299.869358) (xy 58.286097 -299.87529) (xy 58.333368 -299.888982)
			(xy 58.37783 -299.91008) (xy 58.418333 -299.938036) (xy 58.453826 -299.972128) (xy 58.483391 -300.011472)
			(xy 58.506262 -300.055049) (xy 58.521846 -300.10173) (xy 58.529741 -300.150307) (xy 58.530236 -300.174914)
			(xy 59.819044 -300.174914) (xy 59.823004 -300.12586) (xy 59.834781 -300.078076) (xy 59.854072 -300.0328)
			(xy 59.880375 -299.991204) (xy 59.91301 -299.954367) (xy 59.951131 -299.923242) (xy 59.993752 -299.898635)
			(xy 60.039768 -299.881183) (xy 60.087987 -299.871339) (xy 60.137162 -299.869358) (xy 60.186017 -299.87529)
			(xy 60.233288 -299.888982) (xy 60.27775 -299.91008) (xy 60.318253 -299.938036) (xy 60.353746 -299.972128)
			(xy 60.383311 -300.011472) (xy 60.406182 -300.055049) (xy 60.421766 -300.10173) (xy 60.429661 -300.150307)
			(xy 60.430156 -300.174914) (xy 60.769004 -300.174914) (xy 60.772964 -300.12586) (xy 60.784741 -300.078076)
			(xy 60.804032 -300.0328) (xy 60.830335 -299.991204) (xy 60.86297 -299.954367) (xy 60.901091 -299.923242)
			(xy 60.943712 -299.898635) (xy 60.989728 -299.881183) (xy 61.037947 -299.871339) (xy 61.087122 -299.869358)
			(xy 61.135977 -299.87529) (xy 61.183248 -299.888982) (xy 61.22771 -299.91008) (xy 61.268213 -299.938036)
			(xy 61.303706 -299.972128) (xy 61.333271 -300.011472) (xy 61.356142 -300.055049) (xy 61.371726 -300.10173)
			(xy 61.379621 -300.150307) (xy 61.380116 -300.174914) (xy 61.718964 -300.174914) (xy 61.722924 -300.12586)
			(xy 61.734701 -300.078076) (xy 61.753992 -300.0328) (xy 61.780295 -299.991204) (xy 61.81293 -299.954367)
			(xy 61.851051 -299.923242) (xy 61.893672 -299.898635) (xy 61.939688 -299.881183) (xy 61.987907 -299.871339)
			(xy 62.037082 -299.869358) (xy 62.085937 -299.87529) (xy 62.133208 -299.888982) (xy 62.17767 -299.91008)
			(xy 62.218173 -299.938036) (xy 62.253666 -299.972128) (xy 62.283231 -300.011472) (xy 62.306102 -300.055049)
			(xy 62.321686 -300.10173) (xy 62.329581 -300.150307) (xy 62.330076 -300.174914) (xy 62.669178 -300.174914)
			(xy 62.673138 -300.12586) (xy 62.684915 -300.078076) (xy 62.704206 -300.0328) (xy 62.730509 -299.991204)
			(xy 62.763144 -299.954367) (xy 62.801265 -299.923242) (xy 62.843886 -299.898635) (xy 62.889902 -299.881183)
			(xy 62.938121 -299.871339) (xy 62.987296 -299.869358) (xy 63.036151 -299.87529) (xy 63.083422 -299.888982)
			(xy 63.127884 -299.91008) (xy 63.168387 -299.938036) (xy 63.20388 -299.972128) (xy 63.233445 -300.011472)
			(xy 63.256316 -300.055049) (xy 63.2719 -300.10173) (xy 63.279795 -300.150307) (xy 63.28029 -300.174914)
			(xy 63.619138 -300.174914) (xy 63.623098 -300.12586) (xy 63.634875 -300.078076) (xy 63.654166 -300.0328)
			(xy 63.680469 -299.991204) (xy 63.713104 -299.954367) (xy 63.751225 -299.923242) (xy 63.793846 -299.898635)
			(xy 63.839862 -299.881183) (xy 63.888081 -299.871339) (xy 63.937256 -299.869358) (xy 63.986111 -299.87529)
			(xy 64.033382 -299.888982) (xy 64.077844 -299.91008) (xy 64.118347 -299.938036) (xy 64.15384 -299.972128)
			(xy 64.183405 -300.011472) (xy 64.206276 -300.055049) (xy 64.22186 -300.10173) (xy 64.229755 -300.150307)
			(xy 64.23025 -300.174914) (xy 64.569098 -300.174914) (xy 64.573058 -300.12586) (xy 64.584835 -300.078076)
			(xy 64.604126 -300.0328) (xy 64.630429 -299.991204) (xy 64.663064 -299.954367) (xy 64.701185 -299.923242)
			(xy 64.743806 -299.898635) (xy 64.789822 -299.881183) (xy 64.838041 -299.871339) (xy 64.887216 -299.869358)
			(xy 64.936071 -299.87529) (xy 64.983342 -299.888982) (xy 65.027804 -299.91008) (xy 65.068307 -299.938036)
			(xy 65.1038 -299.972128) (xy 65.133365 -300.011472) (xy 65.156236 -300.055049) (xy 65.17182 -300.10173)
			(xy 65.179715 -300.150307) (xy 65.18021 -300.174914) (xy 65.519058 -300.174914) (xy 65.523018 -300.12586)
			(xy 65.534795 -300.078076) (xy 65.554086 -300.0328) (xy 65.580389 -299.991204) (xy 65.613024 -299.954367)
			(xy 65.651145 -299.923242) (xy 65.693766 -299.898635) (xy 65.739782 -299.881183) (xy 65.788001 -299.871339)
			(xy 65.837176 -299.869358) (xy 65.886031 -299.87529) (xy 65.933302 -299.888982) (xy 65.977764 -299.91008)
			(xy 66.018267 -299.938036) (xy 66.05376 -299.972128) (xy 66.083325 -300.011472) (xy 66.106196 -300.055049)
			(xy 66.12178 -300.10173) (xy 66.129675 -300.150307) (xy 66.13017 -300.174914) (xy 66.469018 -300.174914)
			(xy 66.472978 -300.12586) (xy 66.484755 -300.078076) (xy 66.504046 -300.0328) (xy 66.530349 -299.991204)
			(xy 66.562984 -299.954367) (xy 66.601105 -299.923242) (xy 66.643726 -299.898635) (xy 66.689742 -299.881183)
			(xy 66.737961 -299.871339) (xy 66.787136 -299.869358) (xy 66.835991 -299.87529) (xy 66.883262 -299.888982)
			(xy 66.927724 -299.91008) (xy 66.968227 -299.938036) (xy 67.00372 -299.972128) (xy 67.033285 -300.011472)
			(xy 67.056156 -300.055049) (xy 67.07174 -300.10173) (xy 67.079635 -300.150307) (xy 67.08013 -300.174914)
			(xy 67.418978 -300.174914) (xy 67.422938 -300.12586) (xy 67.434715 -300.078076) (xy 67.454006 -300.0328)
			(xy 67.480309 -299.991204) (xy 67.512944 -299.954367) (xy 67.551065 -299.923242) (xy 67.593686 -299.898635)
			(xy 67.639702 -299.881183) (xy 67.687921 -299.871339) (xy 67.737096 -299.869358) (xy 67.785951 -299.87529)
			(xy 67.833222 -299.888982) (xy 67.877684 -299.91008) (xy 67.918187 -299.938036) (xy 67.95368 -299.972128)
			(xy 67.983245 -300.011472) (xy 68.006116 -300.055049) (xy 68.0217 -300.10173) (xy 68.029595 -300.150307)
			(xy 68.03009 -300.174914) (xy 68.368938 -300.174914) (xy 68.372898 -300.12586) (xy 68.384675 -300.078076)
			(xy 68.403966 -300.0328) (xy 68.430269 -299.991204) (xy 68.462904 -299.954367) (xy 68.501025 -299.923242)
			(xy 68.543646 -299.898635) (xy 68.589662 -299.881183) (xy 68.637881 -299.871339) (xy 68.687056 -299.869358)
			(xy 68.735911 -299.87529) (xy 68.783182 -299.888982) (xy 68.827644 -299.91008) (xy 68.868147 -299.938036)
			(xy 68.90364 -299.972128) (xy 68.933205 -300.011472) (xy 68.956076 -300.055049) (xy 68.97166 -300.10173)
			(xy 68.979555 -300.150307) (xy 68.98005 -300.174914) (xy 69.319152 -300.174914) (xy 69.323112 -300.12586)
			(xy 69.334889 -300.078076) (xy 69.35418 -300.0328) (xy 69.380483 -299.991204) (xy 69.413118 -299.954367)
			(xy 69.451239 -299.923242) (xy 69.49386 -299.898635) (xy 69.539876 -299.881183) (xy 69.588095 -299.871339)
			(xy 69.63727 -299.869358) (xy 69.686125 -299.87529) (xy 69.733396 -299.888982) (xy 69.777858 -299.91008)
			(xy 69.818361 -299.938036) (xy 69.853854 -299.972128) (xy 69.883419 -300.011472) (xy 69.90629 -300.055049)
			(xy 69.921874 -300.10173) (xy 69.929769 -300.150307) (xy 69.930264 -300.174914) (xy 70.269112 -300.174914)
			(xy 70.273072 -300.12586) (xy 70.284849 -300.078076) (xy 70.30414 -300.0328) (xy 70.330443 -299.991204)
			(xy 70.363078 -299.954367) (xy 70.401199 -299.923242) (xy 70.44382 -299.898635) (xy 70.489836 -299.881183)
			(xy 70.538055 -299.871339) (xy 70.58723 -299.869358) (xy 70.636085 -299.87529) (xy 70.683356 -299.888982)
			(xy 70.727818 -299.91008) (xy 70.768321 -299.938036) (xy 70.803814 -299.972128) (xy 70.833379 -300.011472)
			(xy 70.85625 -300.055049) (xy 70.871834 -300.10173) (xy 70.879729 -300.150307) (xy 70.880224 -300.174914)
			(xy 71.219072 -300.174914) (xy 71.223032 -300.12586) (xy 71.234809 -300.078076) (xy 71.2541 -300.0328)
			(xy 71.280403 -299.991204) (xy 71.313038 -299.954367) (xy 71.351159 -299.923242) (xy 71.39378 -299.898635)
			(xy 71.439796 -299.881183) (xy 71.488015 -299.871339) (xy 71.53719 -299.869358) (xy 71.586045 -299.87529)
			(xy 71.633316 -299.888982) (xy 71.677778 -299.91008) (xy 71.718281 -299.938036) (xy 71.753774 -299.972128)
			(xy 71.783339 -300.011472) (xy 71.80621 -300.055049) (xy 71.821794 -300.10173) (xy 71.829689 -300.150307)
			(xy 71.830184 -300.174914) (xy 72.169032 -300.174914) (xy 72.172992 -300.12586) (xy 72.184769 -300.078076)
			(xy 72.20406 -300.0328) (xy 72.230363 -299.991204) (xy 72.262998 -299.954367) (xy 72.301119 -299.923242)
			(xy 72.34374 -299.898635) (xy 72.389756 -299.881183) (xy 72.437975 -299.871339) (xy 72.48715 -299.869358)
			(xy 72.536005 -299.87529) (xy 72.583276 -299.888982) (xy 72.627738 -299.91008) (xy 72.668241 -299.938036)
			(xy 72.703734 -299.972128) (xy 72.733299 -300.011472) (xy 72.75617 -300.055049) (xy 72.771754 -300.10173)
			(xy 72.779649 -300.150307) (xy 72.780144 -300.174914) (xy 73.118992 -300.174914) (xy 73.122952 -300.12586)
			(xy 73.134729 -300.078076) (xy 73.15402 -300.0328) (xy 73.180323 -299.991204) (xy 73.212958 -299.954367)
			(xy 73.251079 -299.923242) (xy 73.2937 -299.898635) (xy 73.339716 -299.881183) (xy 73.387935 -299.871339)
			(xy 73.43711 -299.869358) (xy 73.485965 -299.87529) (xy 73.533236 -299.888982) (xy 73.577698 -299.91008)
			(xy 73.618201 -299.938036) (xy 73.653694 -299.972128) (xy 73.683259 -300.011472) (xy 73.70613 -300.055049)
			(xy 73.721714 -300.10173) (xy 73.729609 -300.150307) (xy 73.730104 -300.174914) (xy 74.068952 -300.174914)
			(xy 74.072912 -300.12586) (xy 74.084689 -300.078076) (xy 74.10398 -300.0328) (xy 74.130283 -299.991204)
			(xy 74.162918 -299.954367) (xy 74.201039 -299.923242) (xy 74.24366 -299.898635) (xy 74.289676 -299.881183)
			(xy 74.337895 -299.871339) (xy 74.38707 -299.869358) (xy 74.435925 -299.87529) (xy 74.483196 -299.888982)
			(xy 74.527658 -299.91008) (xy 74.568161 -299.938036) (xy 74.603654 -299.972128) (xy 74.633219 -300.011472)
			(xy 74.65609 -300.055049) (xy 74.671674 -300.10173) (xy 74.679569 -300.150307) (xy 74.680064 -300.174914)
			(xy 75.969126 -300.174914) (xy 75.973086 -300.12586) (xy 75.984863 -300.078076) (xy 76.004154 -300.0328)
			(xy 76.030457 -299.991204) (xy 76.063092 -299.954367) (xy 76.101213 -299.923242) (xy 76.143834 -299.898635)
			(xy 76.18985 -299.881183) (xy 76.238069 -299.871339) (xy 76.287244 -299.869358) (xy 76.336099 -299.87529)
			(xy 76.38337 -299.888982) (xy 76.427832 -299.91008) (xy 76.468335 -299.938036) (xy 76.503828 -299.972128)
			(xy 76.533393 -300.011472) (xy 76.556264 -300.055049) (xy 76.571848 -300.10173) (xy 76.579743 -300.150307)
			(xy 76.580238 -300.174914) (xy 76.919086 -300.174914) (xy 76.923046 -300.12586) (xy 76.934823 -300.078076)
			(xy 76.954114 -300.0328) (xy 76.980417 -299.991204) (xy 77.013052 -299.954367) (xy 77.051173 -299.923242)
			(xy 77.093794 -299.898635) (xy 77.13981 -299.881183) (xy 77.188029 -299.871339) (xy 77.237204 -299.869358)
			(xy 77.286059 -299.87529) (xy 77.33333 -299.888982) (xy 77.377792 -299.91008) (xy 77.418295 -299.938036)
			(xy 77.453788 -299.972128) (xy 77.483353 -300.011472) (xy 77.506224 -300.055049) (xy 77.521808 -300.10173)
			(xy 77.529703 -300.150307) (xy 77.530198 -300.174914) (xy 77.869046 -300.174914) (xy 77.873006 -300.12586)
			(xy 77.884783 -300.078076) (xy 77.904074 -300.0328) (xy 77.930377 -299.991204) (xy 77.963012 -299.954367)
			(xy 78.001133 -299.923242) (xy 78.043754 -299.898635) (xy 78.08977 -299.881183) (xy 78.137989 -299.871339)
			(xy 78.187164 -299.869358) (xy 78.236019 -299.87529) (xy 78.28329 -299.888982) (xy 78.327752 -299.91008)
			(xy 78.368255 -299.938036) (xy 78.403748 -299.972128) (xy 78.433313 -300.011472) (xy 78.456184 -300.055049)
			(xy 78.471768 -300.10173) (xy 78.479663 -300.150307) (xy 78.480158 -300.174914) (xy 78.819006 -300.174914)
			(xy 78.822966 -300.12586) (xy 78.834743 -300.078076) (xy 78.854034 -300.0328) (xy 78.880337 -299.991204)
			(xy 78.912972 -299.954367) (xy 78.951093 -299.923242) (xy 78.993714 -299.898635) (xy 79.03973 -299.881183)
			(xy 79.087949 -299.871339) (xy 79.137124 -299.869358) (xy 79.185979 -299.87529) (xy 79.23325 -299.888982)
			(xy 79.277712 -299.91008) (xy 79.318215 -299.938036) (xy 79.353708 -299.972128) (xy 79.383273 -300.011472)
			(xy 79.406144 -300.055049) (xy 79.421728 -300.10173) (xy 79.429623 -300.150307) (xy 79.430118 -300.174914)
			(xy 79.768966 -300.174914) (xy 79.772926 -300.12586) (xy 79.784703 -300.078076) (xy 79.803994 -300.0328)
			(xy 79.830297 -299.991204) (xy 79.862932 -299.954367) (xy 79.901053 -299.923242) (xy 79.943674 -299.898635)
			(xy 79.98969 -299.881183) (xy 80.037909 -299.871339) (xy 80.087084 -299.869358) (xy 80.135939 -299.87529)
			(xy 80.18321 -299.888982) (xy 80.227672 -299.91008) (xy 80.268175 -299.938036) (xy 80.303668 -299.972128)
			(xy 80.333233 -300.011472) (xy 80.356104 -300.055049) (xy 80.371688 -300.10173) (xy 80.379583 -300.150307)
			(xy 80.380078 -300.174914) (xy 80.71918 -300.174914) (xy 80.72314 -300.12586) (xy 80.734917 -300.078076)
			(xy 80.754208 -300.0328) (xy 80.780511 -299.991204) (xy 80.813146 -299.954367) (xy 80.851267 -299.923242)
			(xy 80.893888 -299.898635) (xy 80.939904 -299.881183) (xy 80.988123 -299.871339) (xy 81.037298 -299.869358)
			(xy 81.086153 -299.87529) (xy 81.133424 -299.888982) (xy 81.177886 -299.91008) (xy 81.218389 -299.938036)
			(xy 81.253882 -299.972128) (xy 81.283447 -300.011472) (xy 81.306318 -300.055049) (xy 81.321902 -300.10173)
			(xy 81.329797 -300.150307) (xy 81.330292 -300.174914) (xy 81.66914 -300.174914) (xy 81.6731 -300.12586)
			(xy 81.684877 -300.078076) (xy 81.704168 -300.0328) (xy 81.730471 -299.991204) (xy 81.763106 -299.954367)
			(xy 81.801227 -299.923242) (xy 81.843848 -299.898635) (xy 81.889864 -299.881183) (xy 81.938083 -299.871339)
			(xy 81.987258 -299.869358) (xy 82.036113 -299.87529) (xy 82.083384 -299.888982) (xy 82.127846 -299.91008)
			(xy 82.168349 -299.938036) (xy 82.203842 -299.972128) (xy 82.233407 -300.011472) (xy 82.256278 -300.055049)
			(xy 82.271862 -300.10173) (xy 82.279757 -300.150307) (xy 82.280252 -300.174914) (xy 82.6191 -300.174914)
			(xy 82.62306 -300.12586) (xy 82.634837 -300.078076) (xy 82.654128 -300.0328) (xy 82.680431 -299.991204)
			(xy 82.713066 -299.954367) (xy 82.751187 -299.923242) (xy 82.793808 -299.898635) (xy 82.839824 -299.881183)
			(xy 82.888043 -299.871339) (xy 82.937218 -299.869358) (xy 82.986073 -299.87529) (xy 83.033344 -299.888982)
			(xy 83.077806 -299.91008) (xy 83.118309 -299.938036) (xy 83.153802 -299.972128) (xy 83.183367 -300.011472)
			(xy 83.206238 -300.055049) (xy 83.221822 -300.10173) (xy 83.229717 -300.150307) (xy 83.230212 -300.174914)
			(xy 83.229717 -300.199521) (xy 83.221822 -300.248098) (xy 83.206238 -300.294779) (xy 83.183367 -300.338356)
			(xy 83.153802 -300.3777) (xy 83.138034 -300.392846) (xy 93.257876 -300.392846) (xy 93.261947 -300.337224)
			(xy 93.274073 -300.282787) (xy 93.293996 -300.230696) (xy 93.321292 -300.182061) (xy 93.355378 -300.137918)
			(xy 93.395527 -300.099209) (xy 93.440885 -300.066758) (xy 93.490485 -300.041257) (xy 93.543269 -300.02325)
			(xy 93.598112 -300.01312) (xy 93.653846 -300.011083) (xy 93.709283 -300.017183) (xy 93.76324 -300.031289)
			(xy 93.814569 -300.053101) (xy 93.862175 -300.082155) (xy 93.905043 -300.11783) (xy 93.94226 -300.159367)
			(xy 93.973033 -300.20588) (xy 93.996705 -300.256377) (xy 94.012773 -300.309784) (xy 94.020893 -300.36496)
			(xy 94.021402 -300.392846) (xy 94.020893 -300.420732) (xy 94.012773 -300.475908) (xy 93.996705 -300.529315)
			(xy 93.973033 -300.579812) (xy 93.94226 -300.626325) (xy 93.905043 -300.667862) (xy 93.862175 -300.703537)
			(xy 93.814569 -300.732591) (xy 93.76324 -300.754403) (xy 93.709283 -300.768509) (xy 93.653846 -300.774609)
			(xy 93.598112 -300.772572) (xy 93.543269 -300.762442) (xy 93.490485 -300.744435) (xy 93.440885 -300.718934)
			(xy 93.395527 -300.686483) (xy 93.355378 -300.647774) (xy 93.321292 -300.603631) (xy 93.293996 -300.554996)
			(xy 93.274073 -300.502905) (xy 93.261947 -300.448468) (xy 93.257876 -300.392846) (xy 83.138034 -300.392846)
			(xy 83.118309 -300.411792) (xy 83.077806 -300.439748) (xy 83.033344 -300.460846) (xy 82.986073 -300.474538)
			(xy 82.937218 -300.48047) (xy 82.888043 -300.478489) (xy 82.839824 -300.468645) (xy 82.793808 -300.451193)
			(xy 82.751187 -300.426586) (xy 82.713066 -300.395461) (xy 82.680431 -300.358624) (xy 82.654128 -300.317028)
			(xy 82.634837 -300.271752) (xy 82.62306 -300.223968) (xy 82.6191 -300.174914) (xy 82.280252 -300.174914)
			(xy 82.279757 -300.199521) (xy 82.271862 -300.248098) (xy 82.256278 -300.294779) (xy 82.233407 -300.338356)
			(xy 82.203842 -300.3777) (xy 82.168349 -300.411792) (xy 82.127846 -300.439748) (xy 82.083384 -300.460846)
			(xy 82.036113 -300.474538) (xy 81.987258 -300.48047) (xy 81.938083 -300.478489) (xy 81.889864 -300.468645)
			(xy 81.843848 -300.451193) (xy 81.801227 -300.426586) (xy 81.763106 -300.395461) (xy 81.730471 -300.358624)
			(xy 81.704168 -300.317028) (xy 81.684877 -300.271752) (xy 81.6731 -300.223968) (xy 81.66914 -300.174914)
			(xy 81.330292 -300.174914) (xy 81.329797 -300.199521) (xy 81.321902 -300.248098) (xy 81.306318 -300.294779)
			(xy 81.283447 -300.338356) (xy 81.253882 -300.3777) (xy 81.218389 -300.411792) (xy 81.177886 -300.439748)
			(xy 81.133424 -300.460846) (xy 81.086153 -300.474538) (xy 81.037298 -300.48047) (xy 80.988123 -300.478489)
			(xy 80.939904 -300.468645) (xy 80.893888 -300.451193) (xy 80.851267 -300.426586) (xy 80.813146 -300.395461)
			(xy 80.780511 -300.358624) (xy 80.754208 -300.317028) (xy 80.734917 -300.271752) (xy 80.72314 -300.223968)
			(xy 80.71918 -300.174914) (xy 80.380078 -300.174914) (xy 80.379583 -300.199521) (xy 80.371688 -300.248098)
			(xy 80.356104 -300.294779) (xy 80.333233 -300.338356) (xy 80.303668 -300.3777) (xy 80.268175 -300.411792)
			(xy 80.227672 -300.439748) (xy 80.18321 -300.460846) (xy 80.135939 -300.474538) (xy 80.087084 -300.48047)
			(xy 80.037909 -300.478489) (xy 79.98969 -300.468645) (xy 79.943674 -300.451193) (xy 79.901053 -300.426586)
			(xy 79.862932 -300.395461) (xy 79.830297 -300.358624) (xy 79.803994 -300.317028) (xy 79.784703 -300.271752)
			(xy 79.772926 -300.223968) (xy 79.768966 -300.174914) (xy 79.430118 -300.174914) (xy 79.429623 -300.199521)
			(xy 79.421728 -300.248098) (xy 79.406144 -300.294779) (xy 79.383273 -300.338356) (xy 79.353708 -300.3777)
			(xy 79.318215 -300.411792) (xy 79.277712 -300.439748) (xy 79.23325 -300.460846) (xy 79.185979 -300.474538)
			(xy 79.137124 -300.48047) (xy 79.087949 -300.478489) (xy 79.03973 -300.468645) (xy 78.993714 -300.451193)
			(xy 78.951093 -300.426586) (xy 78.912972 -300.395461) (xy 78.880337 -300.358624) (xy 78.854034 -300.317028)
			(xy 78.834743 -300.271752) (xy 78.822966 -300.223968) (xy 78.819006 -300.174914) (xy 78.480158 -300.174914)
			(xy 78.479663 -300.199521) (xy 78.471768 -300.248098) (xy 78.456184 -300.294779) (xy 78.433313 -300.338356)
			(xy 78.403748 -300.3777) (xy 78.368255 -300.411792) (xy 78.327752 -300.439748) (xy 78.28329 -300.460846)
			(xy 78.236019 -300.474538) (xy 78.187164 -300.48047) (xy 78.137989 -300.478489) (xy 78.08977 -300.468645)
			(xy 78.043754 -300.451193) (xy 78.001133 -300.426586) (xy 77.963012 -300.395461) (xy 77.930377 -300.358624)
			(xy 77.904074 -300.317028) (xy 77.884783 -300.271752) (xy 77.873006 -300.223968) (xy 77.869046 -300.174914)
			(xy 77.530198 -300.174914) (xy 77.529703 -300.199521) (xy 77.521808 -300.248098) (xy 77.506224 -300.294779)
			(xy 77.483353 -300.338356) (xy 77.453788 -300.3777) (xy 77.418295 -300.411792) (xy 77.377792 -300.439748)
			(xy 77.33333 -300.460846) (xy 77.286059 -300.474538) (xy 77.237204 -300.48047) (xy 77.188029 -300.478489)
			(xy 77.13981 -300.468645) (xy 77.093794 -300.451193) (xy 77.051173 -300.426586) (xy 77.013052 -300.395461)
			(xy 76.980417 -300.358624) (xy 76.954114 -300.317028) (xy 76.934823 -300.271752) (xy 76.923046 -300.223968)
			(xy 76.919086 -300.174914) (xy 76.580238 -300.174914) (xy 76.579743 -300.199521) (xy 76.571848 -300.248098)
			(xy 76.556264 -300.294779) (xy 76.533393 -300.338356) (xy 76.503828 -300.3777) (xy 76.468335 -300.411792)
			(xy 76.427832 -300.439748) (xy 76.38337 -300.460846) (xy 76.336099 -300.474538) (xy 76.287244 -300.48047)
			(xy 76.238069 -300.478489) (xy 76.18985 -300.468645) (xy 76.143834 -300.451193) (xy 76.101213 -300.426586)
			(xy 76.063092 -300.395461) (xy 76.030457 -300.358624) (xy 76.004154 -300.317028) (xy 75.984863 -300.271752)
			(xy 75.973086 -300.223968) (xy 75.969126 -300.174914) (xy 74.680064 -300.174914) (xy 74.679569 -300.199521)
			(xy 74.671674 -300.248098) (xy 74.65609 -300.294779) (xy 74.633219 -300.338356) (xy 74.603654 -300.3777)
			(xy 74.568161 -300.411792) (xy 74.527658 -300.439748) (xy 74.483196 -300.460846) (xy 74.435925 -300.474538)
			(xy 74.38707 -300.48047) (xy 74.337895 -300.478489) (xy 74.289676 -300.468645) (xy 74.24366 -300.451193)
			(xy 74.201039 -300.426586) (xy 74.162918 -300.395461) (xy 74.130283 -300.358624) (xy 74.10398 -300.317028)
			(xy 74.084689 -300.271752) (xy 74.072912 -300.223968) (xy 74.068952 -300.174914) (xy 73.730104 -300.174914)
			(xy 73.729609 -300.199521) (xy 73.721714 -300.248098) (xy 73.70613 -300.294779) (xy 73.683259 -300.338356)
			(xy 73.653694 -300.3777) (xy 73.618201 -300.411792) (xy 73.577698 -300.439748) (xy 73.533236 -300.460846)
			(xy 73.485965 -300.474538) (xy 73.43711 -300.48047) (xy 73.387935 -300.478489) (xy 73.339716 -300.468645)
			(xy 73.2937 -300.451193) (xy 73.251079 -300.426586) (xy 73.212958 -300.395461) (xy 73.180323 -300.358624)
			(xy 73.15402 -300.317028) (xy 73.134729 -300.271752) (xy 73.122952 -300.223968) (xy 73.118992 -300.174914)
			(xy 72.780144 -300.174914) (xy 72.779649 -300.199521) (xy 72.771754 -300.248098) (xy 72.75617 -300.294779)
			(xy 72.733299 -300.338356) (xy 72.703734 -300.3777) (xy 72.668241 -300.411792) (xy 72.627738 -300.439748)
			(xy 72.583276 -300.460846) (xy 72.536005 -300.474538) (xy 72.48715 -300.48047) (xy 72.437975 -300.478489)
			(xy 72.389756 -300.468645) (xy 72.34374 -300.451193) (xy 72.301119 -300.426586) (xy 72.262998 -300.395461)
			(xy 72.230363 -300.358624) (xy 72.20406 -300.317028) (xy 72.184769 -300.271752) (xy 72.172992 -300.223968)
			(xy 72.169032 -300.174914) (xy 71.830184 -300.174914) (xy 71.829689 -300.199521) (xy 71.821794 -300.248098)
			(xy 71.80621 -300.294779) (xy 71.783339 -300.338356) (xy 71.753774 -300.3777) (xy 71.718281 -300.411792)
			(xy 71.677778 -300.439748) (xy 71.633316 -300.460846) (xy 71.586045 -300.474538) (xy 71.53719 -300.48047)
			(xy 71.488015 -300.478489) (xy 71.439796 -300.468645) (xy 71.39378 -300.451193) (xy 71.351159 -300.426586)
			(xy 71.313038 -300.395461) (xy 71.280403 -300.358624) (xy 71.2541 -300.317028) (xy 71.234809 -300.271752)
			(xy 71.223032 -300.223968) (xy 71.219072 -300.174914) (xy 70.880224 -300.174914) (xy 70.879729 -300.199521)
			(xy 70.871834 -300.248098) (xy 70.85625 -300.294779) (xy 70.833379 -300.338356) (xy 70.803814 -300.3777)
			(xy 70.768321 -300.411792) (xy 70.727818 -300.439748) (xy 70.683356 -300.460846) (xy 70.636085 -300.474538)
			(xy 70.58723 -300.48047) (xy 70.538055 -300.478489) (xy 70.489836 -300.468645) (xy 70.44382 -300.451193)
			(xy 70.401199 -300.426586) (xy 70.363078 -300.395461) (xy 70.330443 -300.358624) (xy 70.30414 -300.317028)
			(xy 70.284849 -300.271752) (xy 70.273072 -300.223968) (xy 70.269112 -300.174914) (xy 69.930264 -300.174914)
			(xy 69.929769 -300.199521) (xy 69.921874 -300.248098) (xy 69.90629 -300.294779) (xy 69.883419 -300.338356)
			(xy 69.853854 -300.3777) (xy 69.818361 -300.411792) (xy 69.777858 -300.439748) (xy 69.733396 -300.460846)
			(xy 69.686125 -300.474538) (xy 69.63727 -300.48047) (xy 69.588095 -300.478489) (xy 69.539876 -300.468645)
			(xy 69.49386 -300.451193) (xy 69.451239 -300.426586) (xy 69.413118 -300.395461) (xy 69.380483 -300.358624)
			(xy 69.35418 -300.317028) (xy 69.334889 -300.271752) (xy 69.323112 -300.223968) (xy 69.319152 -300.174914)
			(xy 68.98005 -300.174914) (xy 68.979555 -300.199521) (xy 68.97166 -300.248098) (xy 68.956076 -300.294779)
			(xy 68.933205 -300.338356) (xy 68.90364 -300.3777) (xy 68.868147 -300.411792) (xy 68.827644 -300.439748)
			(xy 68.783182 -300.460846) (xy 68.735911 -300.474538) (xy 68.687056 -300.48047) (xy 68.637881 -300.478489)
			(xy 68.589662 -300.468645) (xy 68.543646 -300.451193) (xy 68.501025 -300.426586) (xy 68.462904 -300.395461)
			(xy 68.430269 -300.358624) (xy 68.403966 -300.317028) (xy 68.384675 -300.271752) (xy 68.372898 -300.223968)
			(xy 68.368938 -300.174914) (xy 68.03009 -300.174914) (xy 68.029595 -300.199521) (xy 68.0217 -300.248098)
			(xy 68.006116 -300.294779) (xy 67.983245 -300.338356) (xy 67.95368 -300.3777) (xy 67.918187 -300.411792)
			(xy 67.877684 -300.439748) (xy 67.833222 -300.460846) (xy 67.785951 -300.474538) (xy 67.737096 -300.48047)
			(xy 67.687921 -300.478489) (xy 67.639702 -300.468645) (xy 67.593686 -300.451193) (xy 67.551065 -300.426586)
			(xy 67.512944 -300.395461) (xy 67.480309 -300.358624) (xy 67.454006 -300.317028) (xy 67.434715 -300.271752)
			(xy 67.422938 -300.223968) (xy 67.418978 -300.174914) (xy 67.08013 -300.174914) (xy 67.079635 -300.199521)
			(xy 67.07174 -300.248098) (xy 67.056156 -300.294779) (xy 67.033285 -300.338356) (xy 67.00372 -300.3777)
			(xy 66.968227 -300.411792) (xy 66.927724 -300.439748) (xy 66.883262 -300.460846) (xy 66.835991 -300.474538)
			(xy 66.787136 -300.48047) (xy 66.737961 -300.478489) (xy 66.689742 -300.468645) (xy 66.643726 -300.451193)
			(xy 66.601105 -300.426586) (xy 66.562984 -300.395461) (xy 66.530349 -300.358624) (xy 66.504046 -300.317028)
			(xy 66.484755 -300.271752) (xy 66.472978 -300.223968) (xy 66.469018 -300.174914) (xy 66.13017 -300.174914)
			(xy 66.129675 -300.199521) (xy 66.12178 -300.248098) (xy 66.106196 -300.294779) (xy 66.083325 -300.338356)
			(xy 66.05376 -300.3777) (xy 66.018267 -300.411792) (xy 65.977764 -300.439748) (xy 65.933302 -300.460846)
			(xy 65.886031 -300.474538) (xy 65.837176 -300.48047) (xy 65.788001 -300.478489) (xy 65.739782 -300.468645)
			(xy 65.693766 -300.451193) (xy 65.651145 -300.426586) (xy 65.613024 -300.395461) (xy 65.580389 -300.358624)
			(xy 65.554086 -300.317028) (xy 65.534795 -300.271752) (xy 65.523018 -300.223968) (xy 65.519058 -300.174914)
			(xy 65.18021 -300.174914) (xy 65.179715 -300.199521) (xy 65.17182 -300.248098) (xy 65.156236 -300.294779)
			(xy 65.133365 -300.338356) (xy 65.1038 -300.3777) (xy 65.068307 -300.411792) (xy 65.027804 -300.439748)
			(xy 64.983342 -300.460846) (xy 64.936071 -300.474538) (xy 64.887216 -300.48047) (xy 64.838041 -300.478489)
			(xy 64.789822 -300.468645) (xy 64.743806 -300.451193) (xy 64.701185 -300.426586) (xy 64.663064 -300.395461)
			(xy 64.630429 -300.358624) (xy 64.604126 -300.317028) (xy 64.584835 -300.271752) (xy 64.573058 -300.223968)
			(xy 64.569098 -300.174914) (xy 64.23025 -300.174914) (xy 64.229755 -300.199521) (xy 64.22186 -300.248098)
			(xy 64.206276 -300.294779) (xy 64.183405 -300.338356) (xy 64.15384 -300.3777) (xy 64.118347 -300.411792)
			(xy 64.077844 -300.439748) (xy 64.033382 -300.460846) (xy 63.986111 -300.474538) (xy 63.937256 -300.48047)
			(xy 63.888081 -300.478489) (xy 63.839862 -300.468645) (xy 63.793846 -300.451193) (xy 63.751225 -300.426586)
			(xy 63.713104 -300.395461) (xy 63.680469 -300.358624) (xy 63.654166 -300.317028) (xy 63.634875 -300.271752)
			(xy 63.623098 -300.223968) (xy 63.619138 -300.174914) (xy 63.28029 -300.174914) (xy 63.279795 -300.199521)
			(xy 63.2719 -300.248098) (xy 63.256316 -300.294779) (xy 63.233445 -300.338356) (xy 63.20388 -300.3777)
			(xy 63.168387 -300.411792) (xy 63.127884 -300.439748) (xy 63.083422 -300.460846) (xy 63.036151 -300.474538)
			(xy 62.987296 -300.48047) (xy 62.938121 -300.478489) (xy 62.889902 -300.468645) (xy 62.843886 -300.451193)
			(xy 62.801265 -300.426586) (xy 62.763144 -300.395461) (xy 62.730509 -300.358624) (xy 62.704206 -300.317028)
			(xy 62.684915 -300.271752) (xy 62.673138 -300.223968) (xy 62.669178 -300.174914) (xy 62.330076 -300.174914)
			(xy 62.329581 -300.199521) (xy 62.321686 -300.248098) (xy 62.306102 -300.294779) (xy 62.283231 -300.338356)
			(xy 62.253666 -300.3777) (xy 62.218173 -300.411792) (xy 62.17767 -300.439748) (xy 62.133208 -300.460846)
			(xy 62.085937 -300.474538) (xy 62.037082 -300.48047) (xy 61.987907 -300.478489) (xy 61.939688 -300.468645)
			(xy 61.893672 -300.451193) (xy 61.851051 -300.426586) (xy 61.81293 -300.395461) (xy 61.780295 -300.358624)
			(xy 61.753992 -300.317028) (xy 61.734701 -300.271752) (xy 61.722924 -300.223968) (xy 61.718964 -300.174914)
			(xy 61.380116 -300.174914) (xy 61.379621 -300.199521) (xy 61.371726 -300.248098) (xy 61.356142 -300.294779)
			(xy 61.333271 -300.338356) (xy 61.303706 -300.3777) (xy 61.268213 -300.411792) (xy 61.22771 -300.439748)
			(xy 61.183248 -300.460846) (xy 61.135977 -300.474538) (xy 61.087122 -300.48047) (xy 61.037947 -300.478489)
			(xy 60.989728 -300.468645) (xy 60.943712 -300.451193) (xy 60.901091 -300.426586) (xy 60.86297 -300.395461)
			(xy 60.830335 -300.358624) (xy 60.804032 -300.317028) (xy 60.784741 -300.271752) (xy 60.772964 -300.223968)
			(xy 60.769004 -300.174914) (xy 60.430156 -300.174914) (xy 60.429661 -300.199521) (xy 60.421766 -300.248098)
			(xy 60.406182 -300.294779) (xy 60.383311 -300.338356) (xy 60.353746 -300.3777) (xy 60.318253 -300.411792)
			(xy 60.27775 -300.439748) (xy 60.233288 -300.460846) (xy 60.186017 -300.474538) (xy 60.137162 -300.48047)
			(xy 60.087987 -300.478489) (xy 60.039768 -300.468645) (xy 59.993752 -300.451193) (xy 59.951131 -300.426586)
			(xy 59.91301 -300.395461) (xy 59.880375 -300.358624) (xy 59.854072 -300.317028) (xy 59.834781 -300.271752)
			(xy 59.823004 -300.223968) (xy 59.819044 -300.174914) (xy 58.530236 -300.174914) (xy 58.529741 -300.199521)
			(xy 58.521846 -300.248098) (xy 58.506262 -300.294779) (xy 58.483391 -300.338356) (xy 58.453826 -300.3777)
			(xy 58.418333 -300.411792) (xy 58.37783 -300.439748) (xy 58.333368 -300.460846) (xy 58.286097 -300.474538)
			(xy 58.237242 -300.48047) (xy 58.188067 -300.478489) (xy 58.139848 -300.468645) (xy 58.093832 -300.451193)
			(xy 58.051211 -300.426586) (xy 58.01309 -300.395461) (xy 57.980455 -300.358624) (xy 57.954152 -300.317028)
			(xy 57.934861 -300.271752) (xy 57.923084 -300.223968) (xy 57.919124 -300.174914) (xy 57.580276 -300.174914)
			(xy 57.579781 -300.199521) (xy 57.571886 -300.248098) (xy 57.556302 -300.294779) (xy 57.533431 -300.338356)
			(xy 57.503866 -300.3777) (xy 57.468373 -300.411792) (xy 57.42787 -300.439748) (xy 57.383408 -300.460846)
			(xy 57.336137 -300.474538) (xy 57.287282 -300.48047) (xy 57.238107 -300.478489) (xy 57.189888 -300.468645)
			(xy 57.143872 -300.451193) (xy 57.101251 -300.426586) (xy 57.06313 -300.395461) (xy 57.030495 -300.358624)
			(xy 57.004192 -300.317028) (xy 56.984901 -300.271752) (xy 56.973124 -300.223968) (xy 56.969164 -300.174914)
			(xy 56.630062 -300.174914) (xy 56.629567 -300.199521) (xy 56.621672 -300.248098) (xy 56.606088 -300.294779)
			(xy 56.583217 -300.338356) (xy 56.553652 -300.3777) (xy 56.518159 -300.411792) (xy 56.477656 -300.439748)
			(xy 56.433194 -300.460846) (xy 56.385923 -300.474538) (xy 56.337068 -300.48047) (xy 56.287893 -300.478489)
			(xy 56.239674 -300.468645) (xy 56.193658 -300.451193) (xy 56.151037 -300.426586) (xy 56.112916 -300.395461)
			(xy 56.080281 -300.358624) (xy 56.053978 -300.317028) (xy 56.034687 -300.271752) (xy 56.02291 -300.223968)
			(xy 56.01895 -300.174914) (xy 55.680102 -300.174914) (xy 55.679607 -300.199521) (xy 55.671712 -300.248098)
			(xy 55.656128 -300.294779) (xy 55.633257 -300.338356) (xy 55.603692 -300.3777) (xy 55.568199 -300.411792)
			(xy 55.527696 -300.439748) (xy 55.483234 -300.460846) (xy 55.435963 -300.474538) (xy 55.387108 -300.48047)
			(xy 55.337933 -300.478489) (xy 55.289714 -300.468645) (xy 55.243698 -300.451193) (xy 55.201077 -300.426586)
			(xy 55.162956 -300.395461) (xy 55.130321 -300.358624) (xy 55.104018 -300.317028) (xy 55.084727 -300.271752)
			(xy 55.07295 -300.223968) (xy 55.06899 -300.174914) (xy 54.730142 -300.174914) (xy 54.729647 -300.199521)
			(xy 54.721752 -300.248098) (xy 54.706168 -300.294779) (xy 54.683297 -300.338356) (xy 54.653732 -300.3777)
			(xy 54.618239 -300.411792) (xy 54.577736 -300.439748) (xy 54.533274 -300.460846) (xy 54.486003 -300.474538)
			(xy 54.437148 -300.48047) (xy 54.387973 -300.478489) (xy 54.339754 -300.468645) (xy 54.293738 -300.451193)
			(xy 54.251117 -300.426586) (xy 54.212996 -300.395461) (xy 54.180361 -300.358624) (xy 54.154058 -300.317028)
			(xy 54.134767 -300.271752) (xy 54.12299 -300.223968) (xy 54.11903 -300.174914) (xy 53.780182 -300.174914)
			(xy 53.779687 -300.199521) (xy 53.771792 -300.248098) (xy 53.756208 -300.294779) (xy 53.733337 -300.338356)
			(xy 53.703772 -300.3777) (xy 53.668279 -300.411792) (xy 53.627776 -300.439748) (xy 53.583314 -300.460846)
			(xy 53.536043 -300.474538) (xy 53.487188 -300.48047) (xy 53.438013 -300.478489) (xy 53.389794 -300.468645)
			(xy 53.343778 -300.451193) (xy 53.301157 -300.426586) (xy 53.263036 -300.395461) (xy 53.230401 -300.358624)
			(xy 53.204098 -300.317028) (xy 53.184807 -300.271752) (xy 53.17303 -300.223968) (xy 53.16907 -300.174914)
			(xy 52.830222 -300.174914) (xy 52.829727 -300.199521) (xy 52.821832 -300.248098) (xy 52.806248 -300.294779)
			(xy 52.783377 -300.338356) (xy 52.753812 -300.3777) (xy 52.718319 -300.411792) (xy 52.677816 -300.439748)
			(xy 52.633354 -300.460846) (xy 52.586083 -300.474538) (xy 52.537228 -300.48047) (xy 52.488053 -300.478489)
			(xy 52.439834 -300.468645) (xy 52.393818 -300.451193) (xy 52.351197 -300.426586) (xy 52.313076 -300.395461)
			(xy 52.280441 -300.358624) (xy 52.254138 -300.317028) (xy 52.234847 -300.271752) (xy 52.22307 -300.223968)
			(xy 52.21911 -300.174914) (xy 51.880262 -300.174914) (xy 51.879767 -300.199521) (xy 51.871872 -300.248098)
			(xy 51.856288 -300.294779) (xy 51.833417 -300.338356) (xy 51.803852 -300.3777) (xy 51.768359 -300.411792)
			(xy 51.727856 -300.439748) (xy 51.683394 -300.460846) (xy 51.636123 -300.474538) (xy 51.587268 -300.48047)
			(xy 51.538093 -300.478489) (xy 51.489874 -300.468645) (xy 51.443858 -300.451193) (xy 51.401237 -300.426586)
			(xy 51.363116 -300.395461) (xy 51.330481 -300.358624) (xy 51.304178 -300.317028) (xy 51.284887 -300.271752)
			(xy 51.27311 -300.223968) (xy 51.26915 -300.174914) (xy 50.930302 -300.174914) (xy 50.929807 -300.199521)
			(xy 50.921912 -300.248098) (xy 50.906328 -300.294779) (xy 50.883457 -300.338356) (xy 50.853892 -300.3777)
			(xy 50.818399 -300.411792) (xy 50.777896 -300.439748) (xy 50.733434 -300.460846) (xy 50.686163 -300.474538)
			(xy 50.637308 -300.48047) (xy 50.588133 -300.478489) (xy 50.539914 -300.468645) (xy 50.493898 -300.451193)
			(xy 50.451277 -300.426586) (xy 50.413156 -300.395461) (xy 50.380521 -300.358624) (xy 50.354218 -300.317028)
			(xy 50.334927 -300.271752) (xy 50.32315 -300.223968) (xy 50.31919 -300.174914) (xy 49.149254 -300.174914)
			(xy 49.149254 -301.124874) (xy 49.368976 -301.124874) (xy 49.372936 -301.07582) (xy 49.384713 -301.028036)
			(xy 49.404004 -300.98276) (xy 49.430307 -300.941164) (xy 49.462942 -300.904327) (xy 49.501063 -300.873202)
			(xy 49.543684 -300.848595) (xy 49.5897 -300.831143) (xy 49.637919 -300.821299) (xy 49.687094 -300.819318)
			(xy 49.735949 -300.82525) (xy 49.78322 -300.838942) (xy 49.827682 -300.86004) (xy 49.868185 -300.887996)
			(xy 49.903678 -300.922088) (xy 49.933243 -300.961432) (xy 49.956114 -301.005009) (xy 49.971698 -301.05169)
			(xy 49.979593 -301.100267) (xy 49.980088 -301.124874) (xy 50.31919 -301.124874) (xy 50.32315 -301.07582)
			(xy 50.334927 -301.028036) (xy 50.354218 -300.98276) (xy 50.380521 -300.941164) (xy 50.413156 -300.904327)
			(xy 50.451277 -300.873202) (xy 50.493898 -300.848595) (xy 50.539914 -300.831143) (xy 50.588133 -300.821299)
			(xy 50.637308 -300.819318) (xy 50.686163 -300.82525) (xy 50.733434 -300.838942) (xy 50.777896 -300.86004)
			(xy 50.818399 -300.887996) (xy 50.853892 -300.922088) (xy 50.883457 -300.961432) (xy 50.906328 -301.005009)
			(xy 50.921912 -301.05169) (xy 50.929807 -301.100267) (xy 50.930302 -301.124874) (xy 51.26915 -301.124874)
			(xy 51.27311 -301.07582) (xy 51.284887 -301.028036) (xy 51.304178 -300.98276) (xy 51.330481 -300.941164)
			(xy 51.363116 -300.904327) (xy 51.401237 -300.873202) (xy 51.443858 -300.848595) (xy 51.489874 -300.831143)
			(xy 51.538093 -300.821299) (xy 51.587268 -300.819318) (xy 51.636123 -300.82525) (xy 51.683394 -300.838942)
			(xy 51.727856 -300.86004) (xy 51.768359 -300.887996) (xy 51.803852 -300.922088) (xy 51.833417 -300.961432)
			(xy 51.856288 -301.005009) (xy 51.871872 -301.05169) (xy 51.879767 -301.100267) (xy 51.880262 -301.124874)
			(xy 52.21911 -301.124874) (xy 52.22307 -301.07582) (xy 52.234847 -301.028036) (xy 52.254138 -300.98276)
			(xy 52.280441 -300.941164) (xy 52.313076 -300.904327) (xy 52.351197 -300.873202) (xy 52.393818 -300.848595)
			(xy 52.439834 -300.831143) (xy 52.488053 -300.821299) (xy 52.537228 -300.819318) (xy 52.586083 -300.82525)
			(xy 52.633354 -300.838942) (xy 52.677816 -300.86004) (xy 52.718319 -300.887996) (xy 52.753812 -300.922088)
			(xy 52.783377 -300.961432) (xy 52.806248 -301.005009) (xy 52.821832 -301.05169) (xy 52.829727 -301.100267)
			(xy 52.830222 -301.124874) (xy 53.16907 -301.124874) (xy 53.17303 -301.07582) (xy 53.184807 -301.028036)
			(xy 53.204098 -300.98276) (xy 53.230401 -300.941164) (xy 53.263036 -300.904327) (xy 53.301157 -300.873202)
			(xy 53.343778 -300.848595) (xy 53.389794 -300.831143) (xy 53.438013 -300.821299) (xy 53.487188 -300.819318)
			(xy 53.536043 -300.82525) (xy 53.583314 -300.838942) (xy 53.627776 -300.86004) (xy 53.668279 -300.887996)
			(xy 53.703772 -300.922088) (xy 53.733337 -300.961432) (xy 53.756208 -301.005009) (xy 53.771792 -301.05169)
			(xy 53.779687 -301.100267) (xy 53.780182 -301.124874) (xy 54.11903 -301.124874) (xy 54.12299 -301.07582)
			(xy 54.134767 -301.028036) (xy 54.154058 -300.98276) (xy 54.180361 -300.941164) (xy 54.212996 -300.904327)
			(xy 54.251117 -300.873202) (xy 54.293738 -300.848595) (xy 54.339754 -300.831143) (xy 54.387973 -300.821299)
			(xy 54.437148 -300.819318) (xy 54.486003 -300.82525) (xy 54.533274 -300.838942) (xy 54.577736 -300.86004)
			(xy 54.618239 -300.887996) (xy 54.653732 -300.922088) (xy 54.683297 -300.961432) (xy 54.706168 -301.005009)
			(xy 54.721752 -301.05169) (xy 54.729647 -301.100267) (xy 54.730142 -301.124874) (xy 55.06899 -301.124874)
			(xy 55.07295 -301.07582) (xy 55.084727 -301.028036) (xy 55.104018 -300.98276) (xy 55.130321 -300.941164)
			(xy 55.162956 -300.904327) (xy 55.201077 -300.873202) (xy 55.243698 -300.848595) (xy 55.289714 -300.831143)
			(xy 55.337933 -300.821299) (xy 55.387108 -300.819318) (xy 55.435963 -300.82525) (xy 55.483234 -300.838942)
			(xy 55.527696 -300.86004) (xy 55.568199 -300.887996) (xy 55.603692 -300.922088) (xy 55.633257 -300.961432)
			(xy 55.656128 -301.005009) (xy 55.671712 -301.05169) (xy 55.679607 -301.100267) (xy 55.680102 -301.124874)
			(xy 56.01895 -301.124874) (xy 56.02291 -301.07582) (xy 56.034687 -301.028036) (xy 56.053978 -300.98276)
			(xy 56.080281 -300.941164) (xy 56.112916 -300.904327) (xy 56.151037 -300.873202) (xy 56.193658 -300.848595)
			(xy 56.239674 -300.831143) (xy 56.287893 -300.821299) (xy 56.337068 -300.819318) (xy 56.385923 -300.82525)
			(xy 56.433194 -300.838942) (xy 56.477656 -300.86004) (xy 56.518159 -300.887996) (xy 56.553652 -300.922088)
			(xy 56.583217 -300.961432) (xy 56.606088 -301.005009) (xy 56.621672 -301.05169) (xy 56.629567 -301.100267)
			(xy 56.630062 -301.124874) (xy 56.969164 -301.124874) (xy 56.973124 -301.07582) (xy 56.984901 -301.028036)
			(xy 57.004192 -300.98276) (xy 57.030495 -300.941164) (xy 57.06313 -300.904327) (xy 57.101251 -300.873202)
			(xy 57.143872 -300.848595) (xy 57.189888 -300.831143) (xy 57.238107 -300.821299) (xy 57.287282 -300.819318)
			(xy 57.336137 -300.82525) (xy 57.383408 -300.838942) (xy 57.42787 -300.86004) (xy 57.468373 -300.887996)
			(xy 57.503866 -300.922088) (xy 57.533431 -300.961432) (xy 57.556302 -301.005009) (xy 57.571886 -301.05169)
			(xy 57.579781 -301.100267) (xy 57.580276 -301.124874) (xy 57.919124 -301.124874) (xy 57.923084 -301.07582)
			(xy 57.934861 -301.028036) (xy 57.954152 -300.98276) (xy 57.980455 -300.941164) (xy 58.01309 -300.904327)
			(xy 58.051211 -300.873202) (xy 58.093832 -300.848595) (xy 58.139848 -300.831143) (xy 58.188067 -300.821299)
			(xy 58.237242 -300.819318) (xy 58.286097 -300.82525) (xy 58.333368 -300.838942) (xy 58.37783 -300.86004)
			(xy 58.418333 -300.887996) (xy 58.453826 -300.922088) (xy 58.483391 -300.961432) (xy 58.506262 -301.005009)
			(xy 58.521846 -301.05169) (xy 58.529741 -301.100267) (xy 58.530236 -301.124874) (xy 59.819044 -301.124874)
			(xy 59.823004 -301.07582) (xy 59.834781 -301.028036) (xy 59.854072 -300.98276) (xy 59.880375 -300.941164)
			(xy 59.91301 -300.904327) (xy 59.951131 -300.873202) (xy 59.993752 -300.848595) (xy 60.039768 -300.831143)
			(xy 60.087987 -300.821299) (xy 60.137162 -300.819318) (xy 60.186017 -300.82525) (xy 60.233288 -300.838942)
			(xy 60.27775 -300.86004) (xy 60.318253 -300.887996) (xy 60.353746 -300.922088) (xy 60.383311 -300.961432)
			(xy 60.406182 -301.005009) (xy 60.421766 -301.05169) (xy 60.429661 -301.100267) (xy 60.430156 -301.124874)
			(xy 60.769004 -301.124874) (xy 60.772964 -301.07582) (xy 60.784741 -301.028036) (xy 60.804032 -300.98276)
			(xy 60.830335 -300.941164) (xy 60.86297 -300.904327) (xy 60.901091 -300.873202) (xy 60.943712 -300.848595)
			(xy 60.989728 -300.831143) (xy 61.037947 -300.821299) (xy 61.087122 -300.819318) (xy 61.135977 -300.82525)
			(xy 61.183248 -300.838942) (xy 61.22771 -300.86004) (xy 61.268213 -300.887996) (xy 61.303706 -300.922088)
			(xy 61.333271 -300.961432) (xy 61.356142 -301.005009) (xy 61.371726 -301.05169) (xy 61.379621 -301.100267)
			(xy 61.380116 -301.124874) (xy 61.718964 -301.124874) (xy 61.722924 -301.07582) (xy 61.734701 -301.028036)
			(xy 61.753992 -300.98276) (xy 61.780295 -300.941164) (xy 61.81293 -300.904327) (xy 61.851051 -300.873202)
			(xy 61.893672 -300.848595) (xy 61.939688 -300.831143) (xy 61.987907 -300.821299) (xy 62.037082 -300.819318)
			(xy 62.085937 -300.82525) (xy 62.133208 -300.838942) (xy 62.17767 -300.86004) (xy 62.218173 -300.887996)
			(xy 62.253666 -300.922088) (xy 62.283231 -300.961432) (xy 62.306102 -301.005009) (xy 62.321686 -301.05169)
			(xy 62.329581 -301.100267) (xy 62.330076 -301.124874) (xy 62.669178 -301.124874) (xy 62.673138 -301.07582)
			(xy 62.684915 -301.028036) (xy 62.704206 -300.98276) (xy 62.730509 -300.941164) (xy 62.763144 -300.904327)
			(xy 62.801265 -300.873202) (xy 62.843886 -300.848595) (xy 62.889902 -300.831143) (xy 62.938121 -300.821299)
			(xy 62.987296 -300.819318) (xy 63.036151 -300.82525) (xy 63.083422 -300.838942) (xy 63.127884 -300.86004)
			(xy 63.168387 -300.887996) (xy 63.20388 -300.922088) (xy 63.233445 -300.961432) (xy 63.256316 -301.005009)
			(xy 63.2719 -301.05169) (xy 63.279795 -301.100267) (xy 63.28029 -301.124874) (xy 63.619138 -301.124874)
			(xy 63.623098 -301.07582) (xy 63.634875 -301.028036) (xy 63.654166 -300.98276) (xy 63.680469 -300.941164)
			(xy 63.713104 -300.904327) (xy 63.751225 -300.873202) (xy 63.793846 -300.848595) (xy 63.839862 -300.831143)
			(xy 63.888081 -300.821299) (xy 63.937256 -300.819318) (xy 63.986111 -300.82525) (xy 64.033382 -300.838942)
			(xy 64.077844 -300.86004) (xy 64.118347 -300.887996) (xy 64.15384 -300.922088) (xy 64.183405 -300.961432)
			(xy 64.206276 -301.005009) (xy 64.22186 -301.05169) (xy 64.229755 -301.100267) (xy 64.23025 -301.124874)
			(xy 64.569098 -301.124874) (xy 64.573058 -301.07582) (xy 64.584835 -301.028036) (xy 64.604126 -300.98276)
			(xy 64.630429 -300.941164) (xy 64.663064 -300.904327) (xy 64.701185 -300.873202) (xy 64.743806 -300.848595)
			(xy 64.789822 -300.831143) (xy 64.838041 -300.821299) (xy 64.887216 -300.819318) (xy 64.936071 -300.82525)
			(xy 64.983342 -300.838942) (xy 65.027804 -300.86004) (xy 65.068307 -300.887996) (xy 65.1038 -300.922088)
			(xy 65.133365 -300.961432) (xy 65.156236 -301.005009) (xy 65.17182 -301.05169) (xy 65.179715 -301.100267)
			(xy 65.18021 -301.124874) (xy 65.519058 -301.124874) (xy 65.523018 -301.07582) (xy 65.534795 -301.028036)
			(xy 65.554086 -300.98276) (xy 65.580389 -300.941164) (xy 65.613024 -300.904327) (xy 65.651145 -300.873202)
			(xy 65.693766 -300.848595) (xy 65.739782 -300.831143) (xy 65.788001 -300.821299) (xy 65.837176 -300.819318)
			(xy 65.886031 -300.82525) (xy 65.933302 -300.838942) (xy 65.977764 -300.86004) (xy 66.018267 -300.887996)
			(xy 66.05376 -300.922088) (xy 66.083325 -300.961432) (xy 66.106196 -301.005009) (xy 66.12178 -301.05169)
			(xy 66.129675 -301.100267) (xy 66.13017 -301.124874) (xy 66.469018 -301.124874) (xy 66.472978 -301.07582)
			(xy 66.484755 -301.028036) (xy 66.504046 -300.98276) (xy 66.530349 -300.941164) (xy 66.562984 -300.904327)
			(xy 66.601105 -300.873202) (xy 66.643726 -300.848595) (xy 66.689742 -300.831143) (xy 66.737961 -300.821299)
			(xy 66.787136 -300.819318) (xy 66.835991 -300.82525) (xy 66.883262 -300.838942) (xy 66.927724 -300.86004)
			(xy 66.968227 -300.887996) (xy 67.00372 -300.922088) (xy 67.033285 -300.961432) (xy 67.056156 -301.005009)
			(xy 67.07174 -301.05169) (xy 67.079635 -301.100267) (xy 67.08013 -301.124874) (xy 67.418978 -301.124874)
			(xy 67.422938 -301.07582) (xy 67.434715 -301.028036) (xy 67.454006 -300.98276) (xy 67.480309 -300.941164)
			(xy 67.512944 -300.904327) (xy 67.551065 -300.873202) (xy 67.593686 -300.848595) (xy 67.639702 -300.831143)
			(xy 67.687921 -300.821299) (xy 67.737096 -300.819318) (xy 67.785951 -300.82525) (xy 67.833222 -300.838942)
			(xy 67.877684 -300.86004) (xy 67.918187 -300.887996) (xy 67.95368 -300.922088) (xy 67.983245 -300.961432)
			(xy 68.006116 -301.005009) (xy 68.0217 -301.05169) (xy 68.029595 -301.100267) (xy 68.03009 -301.124874)
			(xy 68.368938 -301.124874) (xy 68.372898 -301.07582) (xy 68.384675 -301.028036) (xy 68.403966 -300.98276)
			(xy 68.430269 -300.941164) (xy 68.462904 -300.904327) (xy 68.501025 -300.873202) (xy 68.543646 -300.848595)
			(xy 68.589662 -300.831143) (xy 68.637881 -300.821299) (xy 68.687056 -300.819318) (xy 68.735911 -300.82525)
			(xy 68.783182 -300.838942) (xy 68.827644 -300.86004) (xy 68.868147 -300.887996) (xy 68.90364 -300.922088)
			(xy 68.933205 -300.961432) (xy 68.956076 -301.005009) (xy 68.97166 -301.05169) (xy 68.979555 -301.100267)
			(xy 68.98005 -301.124874) (xy 69.319152 -301.124874) (xy 69.323112 -301.07582) (xy 69.334889 -301.028036)
			(xy 69.35418 -300.98276) (xy 69.380483 -300.941164) (xy 69.413118 -300.904327) (xy 69.451239 -300.873202)
			(xy 69.49386 -300.848595) (xy 69.539876 -300.831143) (xy 69.588095 -300.821299) (xy 69.63727 -300.819318)
			(xy 69.686125 -300.82525) (xy 69.733396 -300.838942) (xy 69.777858 -300.86004) (xy 69.818361 -300.887996)
			(xy 69.853854 -300.922088) (xy 69.883419 -300.961432) (xy 69.90629 -301.005009) (xy 69.921874 -301.05169)
			(xy 69.929769 -301.100267) (xy 69.930264 -301.124874) (xy 70.269112 -301.124874) (xy 70.273072 -301.07582)
			(xy 70.284849 -301.028036) (xy 70.30414 -300.98276) (xy 70.330443 -300.941164) (xy 70.363078 -300.904327)
			(xy 70.401199 -300.873202) (xy 70.44382 -300.848595) (xy 70.489836 -300.831143) (xy 70.538055 -300.821299)
			(xy 70.58723 -300.819318) (xy 70.636085 -300.82525) (xy 70.683356 -300.838942) (xy 70.727818 -300.86004)
			(xy 70.768321 -300.887996) (xy 70.803814 -300.922088) (xy 70.833379 -300.961432) (xy 70.85625 -301.005009)
			(xy 70.871834 -301.05169) (xy 70.879729 -301.100267) (xy 70.880224 -301.124874) (xy 71.219072 -301.124874)
			(xy 71.223032 -301.07582) (xy 71.234809 -301.028036) (xy 71.2541 -300.98276) (xy 71.280403 -300.941164)
			(xy 71.313038 -300.904327) (xy 71.351159 -300.873202) (xy 71.39378 -300.848595) (xy 71.439796 -300.831143)
			(xy 71.488015 -300.821299) (xy 71.53719 -300.819318) (xy 71.586045 -300.82525) (xy 71.633316 -300.838942)
			(xy 71.677778 -300.86004) (xy 71.718281 -300.887996) (xy 71.753774 -300.922088) (xy 71.783339 -300.961432)
			(xy 71.80621 -301.005009) (xy 71.821794 -301.05169) (xy 71.829689 -301.100267) (xy 71.830184 -301.124874)
			(xy 72.169032 -301.124874) (xy 72.172992 -301.07582) (xy 72.184769 -301.028036) (xy 72.20406 -300.98276)
			(xy 72.230363 -300.941164) (xy 72.262998 -300.904327) (xy 72.301119 -300.873202) (xy 72.34374 -300.848595)
			(xy 72.389756 -300.831143) (xy 72.437975 -300.821299) (xy 72.48715 -300.819318) (xy 72.536005 -300.82525)
			(xy 72.583276 -300.838942) (xy 72.627738 -300.86004) (xy 72.668241 -300.887996) (xy 72.703734 -300.922088)
			(xy 72.733299 -300.961432) (xy 72.75617 -301.005009) (xy 72.771754 -301.05169) (xy 72.779649 -301.100267)
			(xy 72.780144 -301.124874) (xy 73.118992 -301.124874) (xy 73.122952 -301.07582) (xy 73.134729 -301.028036)
			(xy 73.15402 -300.98276) (xy 73.180323 -300.941164) (xy 73.212958 -300.904327) (xy 73.251079 -300.873202)
			(xy 73.2937 -300.848595) (xy 73.339716 -300.831143) (xy 73.387935 -300.821299) (xy 73.43711 -300.819318)
			(xy 73.485965 -300.82525) (xy 73.533236 -300.838942) (xy 73.577698 -300.86004) (xy 73.618201 -300.887996)
			(xy 73.653694 -300.922088) (xy 73.683259 -300.961432) (xy 73.70613 -301.005009) (xy 73.721714 -301.05169)
			(xy 73.729609 -301.100267) (xy 73.730104 -301.124874) (xy 73.729609 -301.149481) (xy 73.721714 -301.198058)
			(xy 73.70613 -301.244739) (xy 73.683259 -301.288316) (xy 73.653694 -301.32766) (xy 73.618201 -301.361752)
			(xy 73.577698 -301.389708) (xy 73.533236 -301.410806) (xy 73.485965 -301.424498) (xy 73.43711 -301.43043)
			(xy 73.387935 -301.428449) (xy 73.339716 -301.418605) (xy 73.2937 -301.401153) (xy 73.251079 -301.376546)
			(xy 73.212958 -301.345421) (xy 73.180323 -301.308584) (xy 73.15402 -301.266988) (xy 73.134729 -301.221712)
			(xy 73.122952 -301.173928) (xy 73.118992 -301.124874) (xy 72.780144 -301.124874) (xy 72.779649 -301.149481)
			(xy 72.771754 -301.198058) (xy 72.75617 -301.244739) (xy 72.733299 -301.288316) (xy 72.703734 -301.32766)
			(xy 72.668241 -301.361752) (xy 72.627738 -301.389708) (xy 72.583276 -301.410806) (xy 72.536005 -301.424498)
			(xy 72.48715 -301.43043) (xy 72.437975 -301.428449) (xy 72.389756 -301.418605) (xy 72.34374 -301.401153)
			(xy 72.301119 -301.376546) (xy 72.262998 -301.345421) (xy 72.230363 -301.308584) (xy 72.20406 -301.266988)
			(xy 72.184769 -301.221712) (xy 72.172992 -301.173928) (xy 72.169032 -301.124874) (xy 71.830184 -301.124874)
			(xy 71.829689 -301.149481) (xy 71.821794 -301.198058) (xy 71.80621 -301.244739) (xy 71.783339 -301.288316)
			(xy 71.753774 -301.32766) (xy 71.718281 -301.361752) (xy 71.677778 -301.389708) (xy 71.633316 -301.410806)
			(xy 71.586045 -301.424498) (xy 71.53719 -301.43043) (xy 71.488015 -301.428449) (xy 71.439796 -301.418605)
			(xy 71.39378 -301.401153) (xy 71.351159 -301.376546) (xy 71.313038 -301.345421) (xy 71.280403 -301.308584)
			(xy 71.2541 -301.266988) (xy 71.234809 -301.221712) (xy 71.223032 -301.173928) (xy 71.219072 -301.124874)
			(xy 70.880224 -301.124874) (xy 70.879729 -301.149481) (xy 70.871834 -301.198058) (xy 70.85625 -301.244739)
			(xy 70.833379 -301.288316) (xy 70.803814 -301.32766) (xy 70.768321 -301.361752) (xy 70.727818 -301.389708)
			(xy 70.683356 -301.410806) (xy 70.636085 -301.424498) (xy 70.58723 -301.43043) (xy 70.538055 -301.428449)
			(xy 70.489836 -301.418605) (xy 70.44382 -301.401153) (xy 70.401199 -301.376546) (xy 70.363078 -301.345421)
			(xy 70.330443 -301.308584) (xy 70.30414 -301.266988) (xy 70.284849 -301.221712) (xy 70.273072 -301.173928)
			(xy 70.269112 -301.124874) (xy 69.930264 -301.124874) (xy 69.929769 -301.149481) (xy 69.921874 -301.198058)
			(xy 69.90629 -301.244739) (xy 69.883419 -301.288316) (xy 69.853854 -301.32766) (xy 69.818361 -301.361752)
			(xy 69.777858 -301.389708) (xy 69.733396 -301.410806) (xy 69.686125 -301.424498) (xy 69.63727 -301.43043)
			(xy 69.588095 -301.428449) (xy 69.539876 -301.418605) (xy 69.49386 -301.401153) (xy 69.451239 -301.376546)
			(xy 69.413118 -301.345421) (xy 69.380483 -301.308584) (xy 69.35418 -301.266988) (xy 69.334889 -301.221712)
			(xy 69.323112 -301.173928) (xy 69.319152 -301.124874) (xy 68.98005 -301.124874) (xy 68.979555 -301.149481)
			(xy 68.97166 -301.198058) (xy 68.956076 -301.244739) (xy 68.933205 -301.288316) (xy 68.90364 -301.32766)
			(xy 68.868147 -301.361752) (xy 68.827644 -301.389708) (xy 68.783182 -301.410806) (xy 68.735911 -301.424498)
			(xy 68.687056 -301.43043) (xy 68.637881 -301.428449) (xy 68.589662 -301.418605) (xy 68.543646 -301.401153)
			(xy 68.501025 -301.376546) (xy 68.462904 -301.345421) (xy 68.430269 -301.308584) (xy 68.403966 -301.266988)
			(xy 68.384675 -301.221712) (xy 68.372898 -301.173928) (xy 68.368938 -301.124874) (xy 68.03009 -301.124874)
			(xy 68.029595 -301.149481) (xy 68.0217 -301.198058) (xy 68.006116 -301.244739) (xy 67.983245 -301.288316)
			(xy 67.95368 -301.32766) (xy 67.918187 -301.361752) (xy 67.877684 -301.389708) (xy 67.833222 -301.410806)
			(xy 67.785951 -301.424498) (xy 67.737096 -301.43043) (xy 67.687921 -301.428449) (xy 67.639702 -301.418605)
			(xy 67.593686 -301.401153) (xy 67.551065 -301.376546) (xy 67.512944 -301.345421) (xy 67.480309 -301.308584)
			(xy 67.454006 -301.266988) (xy 67.434715 -301.221712) (xy 67.422938 -301.173928) (xy 67.418978 -301.124874)
			(xy 67.08013 -301.124874) (xy 67.079635 -301.149481) (xy 67.07174 -301.198058) (xy 67.056156 -301.244739)
			(xy 67.033285 -301.288316) (xy 67.00372 -301.32766) (xy 66.968227 -301.361752) (xy 66.927724 -301.389708)
			(xy 66.883262 -301.410806) (xy 66.835991 -301.424498) (xy 66.787136 -301.43043) (xy 66.737961 -301.428449)
			(xy 66.689742 -301.418605) (xy 66.643726 -301.401153) (xy 66.601105 -301.376546) (xy 66.562984 -301.345421)
			(xy 66.530349 -301.308584) (xy 66.504046 -301.266988) (xy 66.484755 -301.221712) (xy 66.472978 -301.173928)
			(xy 66.469018 -301.124874) (xy 66.13017 -301.124874) (xy 66.129675 -301.149481) (xy 66.12178 -301.198058)
			(xy 66.106196 -301.244739) (xy 66.083325 -301.288316) (xy 66.05376 -301.32766) (xy 66.018267 -301.361752)
			(xy 65.977764 -301.389708) (xy 65.933302 -301.410806) (xy 65.886031 -301.424498) (xy 65.837176 -301.43043)
			(xy 65.788001 -301.428449) (xy 65.739782 -301.418605) (xy 65.693766 -301.401153) (xy 65.651145 -301.376546)
			(xy 65.613024 -301.345421) (xy 65.580389 -301.308584) (xy 65.554086 -301.266988) (xy 65.534795 -301.221712)
			(xy 65.523018 -301.173928) (xy 65.519058 -301.124874) (xy 65.18021 -301.124874) (xy 65.179715 -301.149481)
			(xy 65.17182 -301.198058) (xy 65.156236 -301.244739) (xy 65.133365 -301.288316) (xy 65.1038 -301.32766)
			(xy 65.068307 -301.361752) (xy 65.027804 -301.389708) (xy 64.983342 -301.410806) (xy 64.936071 -301.424498)
			(xy 64.887216 -301.43043) (xy 64.838041 -301.428449) (xy 64.789822 -301.418605) (xy 64.743806 -301.401153)
			(xy 64.701185 -301.376546) (xy 64.663064 -301.345421) (xy 64.630429 -301.308584) (xy 64.604126 -301.266988)
			(xy 64.584835 -301.221712) (xy 64.573058 -301.173928) (xy 64.569098 -301.124874) (xy 64.23025 -301.124874)
			(xy 64.229755 -301.149481) (xy 64.22186 -301.198058) (xy 64.206276 -301.244739) (xy 64.183405 -301.288316)
			(xy 64.15384 -301.32766) (xy 64.118347 -301.361752) (xy 64.077844 -301.389708) (xy 64.033382 -301.410806)
			(xy 63.986111 -301.424498) (xy 63.937256 -301.43043) (xy 63.888081 -301.428449) (xy 63.839862 -301.418605)
			(xy 63.793846 -301.401153) (xy 63.751225 -301.376546) (xy 63.713104 -301.345421) (xy 63.680469 -301.308584)
			(xy 63.654166 -301.266988) (xy 63.634875 -301.221712) (xy 63.623098 -301.173928) (xy 63.619138 -301.124874)
			(xy 63.28029 -301.124874) (xy 63.279795 -301.149481) (xy 63.2719 -301.198058) (xy 63.256316 -301.244739)
			(xy 63.233445 -301.288316) (xy 63.20388 -301.32766) (xy 63.168387 -301.361752) (xy 63.127884 -301.389708)
			(xy 63.083422 -301.410806) (xy 63.036151 -301.424498) (xy 62.987296 -301.43043) (xy 62.938121 -301.428449)
			(xy 62.889902 -301.418605) (xy 62.843886 -301.401153) (xy 62.801265 -301.376546) (xy 62.763144 -301.345421)
			(xy 62.730509 -301.308584) (xy 62.704206 -301.266988) (xy 62.684915 -301.221712) (xy 62.673138 -301.173928)
			(xy 62.669178 -301.124874) (xy 62.330076 -301.124874) (xy 62.329581 -301.149481) (xy 62.321686 -301.198058)
			(xy 62.306102 -301.244739) (xy 62.283231 -301.288316) (xy 62.253666 -301.32766) (xy 62.218173 -301.361752)
			(xy 62.17767 -301.389708) (xy 62.133208 -301.410806) (xy 62.085937 -301.424498) (xy 62.037082 -301.43043)
			(xy 61.987907 -301.428449) (xy 61.939688 -301.418605) (xy 61.893672 -301.401153) (xy 61.851051 -301.376546)
			(xy 61.81293 -301.345421) (xy 61.780295 -301.308584) (xy 61.753992 -301.266988) (xy 61.734701 -301.221712)
			(xy 61.722924 -301.173928) (xy 61.718964 -301.124874) (xy 61.380116 -301.124874) (xy 61.379621 -301.149481)
			(xy 61.371726 -301.198058) (xy 61.356142 -301.244739) (xy 61.333271 -301.288316) (xy 61.303706 -301.32766)
			(xy 61.268213 -301.361752) (xy 61.22771 -301.389708) (xy 61.183248 -301.410806) (xy 61.135977 -301.424498)
			(xy 61.087122 -301.43043) (xy 61.037947 -301.428449) (xy 60.989728 -301.418605) (xy 60.943712 -301.401153)
			(xy 60.901091 -301.376546) (xy 60.86297 -301.345421) (xy 60.830335 -301.308584) (xy 60.804032 -301.266988)
			(xy 60.784741 -301.221712) (xy 60.772964 -301.173928) (xy 60.769004 -301.124874) (xy 60.430156 -301.124874)
			(xy 60.429661 -301.149481) (xy 60.421766 -301.198058) (xy 60.406182 -301.244739) (xy 60.383311 -301.288316)
			(xy 60.353746 -301.32766) (xy 60.318253 -301.361752) (xy 60.27775 -301.389708) (xy 60.233288 -301.410806)
			(xy 60.186017 -301.424498) (xy 60.137162 -301.43043) (xy 60.087987 -301.428449) (xy 60.039768 -301.418605)
			(xy 59.993752 -301.401153) (xy 59.951131 -301.376546) (xy 59.91301 -301.345421) (xy 59.880375 -301.308584)
			(xy 59.854072 -301.266988) (xy 59.834781 -301.221712) (xy 59.823004 -301.173928) (xy 59.819044 -301.124874)
			(xy 58.530236 -301.124874) (xy 58.529741 -301.149481) (xy 58.521846 -301.198058) (xy 58.506262 -301.244739)
			(xy 58.483391 -301.288316) (xy 58.453826 -301.32766) (xy 58.418333 -301.361752) (xy 58.37783 -301.389708)
			(xy 58.333368 -301.410806) (xy 58.286097 -301.424498) (xy 58.237242 -301.43043) (xy 58.188067 -301.428449)
			(xy 58.139848 -301.418605) (xy 58.093832 -301.401153) (xy 58.051211 -301.376546) (xy 58.01309 -301.345421)
			(xy 57.980455 -301.308584) (xy 57.954152 -301.266988) (xy 57.934861 -301.221712) (xy 57.923084 -301.173928)
			(xy 57.919124 -301.124874) (xy 57.580276 -301.124874) (xy 57.579781 -301.149481) (xy 57.571886 -301.198058)
			(xy 57.556302 -301.244739) (xy 57.533431 -301.288316) (xy 57.503866 -301.32766) (xy 57.468373 -301.361752)
			(xy 57.42787 -301.389708) (xy 57.383408 -301.410806) (xy 57.336137 -301.424498) (xy 57.287282 -301.43043)
			(xy 57.238107 -301.428449) (xy 57.189888 -301.418605) (xy 57.143872 -301.401153) (xy 57.101251 -301.376546)
			(xy 57.06313 -301.345421) (xy 57.030495 -301.308584) (xy 57.004192 -301.266988) (xy 56.984901 -301.221712)
			(xy 56.973124 -301.173928) (xy 56.969164 -301.124874) (xy 56.630062 -301.124874) (xy 56.629567 -301.149481)
			(xy 56.621672 -301.198058) (xy 56.606088 -301.244739) (xy 56.583217 -301.288316) (xy 56.553652 -301.32766)
			(xy 56.518159 -301.361752) (xy 56.477656 -301.389708) (xy 56.433194 -301.410806) (xy 56.385923 -301.424498)
			(xy 56.337068 -301.43043) (xy 56.287893 -301.428449) (xy 56.239674 -301.418605) (xy 56.193658 -301.401153)
			(xy 56.151037 -301.376546) (xy 56.112916 -301.345421) (xy 56.080281 -301.308584) (xy 56.053978 -301.266988)
			(xy 56.034687 -301.221712) (xy 56.02291 -301.173928) (xy 56.01895 -301.124874) (xy 55.680102 -301.124874)
			(xy 55.679607 -301.149481) (xy 55.671712 -301.198058) (xy 55.656128 -301.244739) (xy 55.633257 -301.288316)
			(xy 55.603692 -301.32766) (xy 55.568199 -301.361752) (xy 55.527696 -301.389708) (xy 55.483234 -301.410806)
			(xy 55.435963 -301.424498) (xy 55.387108 -301.43043) (xy 55.337933 -301.428449) (xy 55.289714 -301.418605)
			(xy 55.243698 -301.401153) (xy 55.201077 -301.376546) (xy 55.162956 -301.345421) (xy 55.130321 -301.308584)
			(xy 55.104018 -301.266988) (xy 55.084727 -301.221712) (xy 55.07295 -301.173928) (xy 55.06899 -301.124874)
			(xy 54.730142 -301.124874) (xy 54.729647 -301.149481) (xy 54.721752 -301.198058) (xy 54.706168 -301.244739)
			(xy 54.683297 -301.288316) (xy 54.653732 -301.32766) (xy 54.618239 -301.361752) (xy 54.577736 -301.389708)
			(xy 54.533274 -301.410806) (xy 54.486003 -301.424498) (xy 54.437148 -301.43043) (xy 54.387973 -301.428449)
			(xy 54.339754 -301.418605) (xy 54.293738 -301.401153) (xy 54.251117 -301.376546) (xy 54.212996 -301.345421)
			(xy 54.180361 -301.308584) (xy 54.154058 -301.266988) (xy 54.134767 -301.221712) (xy 54.12299 -301.173928)
			(xy 54.11903 -301.124874) (xy 53.780182 -301.124874) (xy 53.779687 -301.149481) (xy 53.771792 -301.198058)
			(xy 53.756208 -301.244739) (xy 53.733337 -301.288316) (xy 53.703772 -301.32766) (xy 53.668279 -301.361752)
			(xy 53.627776 -301.389708) (xy 53.583314 -301.410806) (xy 53.536043 -301.424498) (xy 53.487188 -301.43043)
			(xy 53.438013 -301.428449) (xy 53.389794 -301.418605) (xy 53.343778 -301.401153) (xy 53.301157 -301.376546)
			(xy 53.263036 -301.345421) (xy 53.230401 -301.308584) (xy 53.204098 -301.266988) (xy 53.184807 -301.221712)
			(xy 53.17303 -301.173928) (xy 53.16907 -301.124874) (xy 52.830222 -301.124874) (xy 52.829727 -301.149481)
			(xy 52.821832 -301.198058) (xy 52.806248 -301.244739) (xy 52.783377 -301.288316) (xy 52.753812 -301.32766)
			(xy 52.718319 -301.361752) (xy 52.677816 -301.389708) (xy 52.633354 -301.410806) (xy 52.586083 -301.424498)
			(xy 52.537228 -301.43043) (xy 52.488053 -301.428449) (xy 52.439834 -301.418605) (xy 52.393818 -301.401153)
			(xy 52.351197 -301.376546) (xy 52.313076 -301.345421) (xy 52.280441 -301.308584) (xy 52.254138 -301.266988)
			(xy 52.234847 -301.221712) (xy 52.22307 -301.173928) (xy 52.21911 -301.124874) (xy 51.880262 -301.124874)
			(xy 51.879767 -301.149481) (xy 51.871872 -301.198058) (xy 51.856288 -301.244739) (xy 51.833417 -301.288316)
			(xy 51.803852 -301.32766) (xy 51.768359 -301.361752) (xy 51.727856 -301.389708) (xy 51.683394 -301.410806)
			(xy 51.636123 -301.424498) (xy 51.587268 -301.43043) (xy 51.538093 -301.428449) (xy 51.489874 -301.418605)
			(xy 51.443858 -301.401153) (xy 51.401237 -301.376546) (xy 51.363116 -301.345421) (xy 51.330481 -301.308584)
			(xy 51.304178 -301.266988) (xy 51.284887 -301.221712) (xy 51.27311 -301.173928) (xy 51.26915 -301.124874)
			(xy 50.930302 -301.124874) (xy 50.929807 -301.149481) (xy 50.921912 -301.198058) (xy 50.906328 -301.244739)
			(xy 50.883457 -301.288316) (xy 50.853892 -301.32766) (xy 50.818399 -301.361752) (xy 50.777896 -301.389708)
			(xy 50.733434 -301.410806) (xy 50.686163 -301.424498) (xy 50.637308 -301.43043) (xy 50.588133 -301.428449)
			(xy 50.539914 -301.418605) (xy 50.493898 -301.401153) (xy 50.451277 -301.376546) (xy 50.413156 -301.345421)
			(xy 50.380521 -301.308584) (xy 50.354218 -301.266988) (xy 50.334927 -301.221712) (xy 50.32315 -301.173928)
			(xy 50.31919 -301.124874) (xy 49.980088 -301.124874) (xy 49.979593 -301.149481) (xy 49.971698 -301.198058)
			(xy 49.956114 -301.244739) (xy 49.933243 -301.288316) (xy 49.903678 -301.32766) (xy 49.868185 -301.361752)
			(xy 49.827682 -301.389708) (xy 49.78322 -301.410806) (xy 49.735949 -301.424498) (xy 49.687094 -301.43043)
			(xy 49.637919 -301.428449) (xy 49.5897 -301.418605) (xy 49.543684 -301.401153) (xy 49.501063 -301.376546)
			(xy 49.462942 -301.345421) (xy 49.430307 -301.308584) (xy 49.404004 -301.266988) (xy 49.384713 -301.221712)
			(xy 49.372936 -301.173928) (xy 49.368976 -301.124874) (xy 49.149254 -301.124874) (xy 49.149254 -301.5999)
			(xy 75.494122 -301.5999) (xy 75.498293 -301.549559) (xy 75.510692 -301.500592) (xy 75.530981 -301.454332)
			(xy 75.558607 -301.412043) (xy 75.592815 -301.374876) (xy 75.632674 -301.343847) (xy 75.677097 -301.3198)
			(xy 75.724871 -301.303393) (xy 75.774694 -301.295071) (xy 75.79995 -301.294546) (xy 75.814133 -301.29473)
			(xy 75.842373 -301.297397) (xy 75.856338 -301.29988) (xy 75.868784 -301.302166) (xy 75.892406 -301.2948)
			(xy 75.969876 -301.21733) (xy 75.977242 -301.193708) (xy 75.974956 -301.181262) (xy 75.972479 -301.167296)
			(xy 75.969807 -301.139057) (xy 75.969622 -301.124874) (xy 75.970106 -301.100056) (xy 75.97814 -301.051075)
			(xy 75.993992 -301.004039) (xy 76.017245 -300.960187) (xy 76.047285 -300.920674) (xy 76.083322 -300.886542)
			(xy 76.124406 -300.858689) (xy 76.169455 -300.837849) (xy 76.217282 -300.824572) (xy 76.266627 -300.819207)
			(xy 76.316189 -300.821895) (xy 76.364664 -300.832566) (xy 76.410774 -300.850939) (xy 76.453305 -300.876529)
			(xy 76.491135 -300.908662) (xy 76.523269 -300.946492) (xy 76.54886 -300.989022) (xy 76.567233 -301.035132)
			(xy 76.577904 -301.083607) (xy 76.580143 -301.124874) (xy 76.919086 -301.124874) (xy 76.923046 -301.07582)
			(xy 76.934823 -301.028036) (xy 76.954114 -300.98276) (xy 76.980417 -300.941164) (xy 77.013052 -300.904327)
			(xy 77.051173 -300.873202) (xy 77.093794 -300.848595) (xy 77.13981 -300.831143) (xy 77.188029 -300.821299)
			(xy 77.237204 -300.819318) (xy 77.286059 -300.82525) (xy 77.33333 -300.838942) (xy 77.377792 -300.86004)
			(xy 77.418295 -300.887996) (xy 77.453788 -300.922088) (xy 77.483353 -300.961432) (xy 77.506224 -301.005009)
			(xy 77.521808 -301.05169) (xy 77.529703 -301.100267) (xy 77.530198 -301.124874) (xy 77.869046 -301.124874)
			(xy 77.873006 -301.07582) (xy 77.884783 -301.028036) (xy 77.904074 -300.98276) (xy 77.930377 -300.941164)
			(xy 77.963012 -300.904327) (xy 78.001133 -300.873202) (xy 78.043754 -300.848595) (xy 78.08977 -300.831143)
			(xy 78.137989 -300.821299) (xy 78.187164 -300.819318) (xy 78.236019 -300.82525) (xy 78.28329 -300.838942)
			(xy 78.327752 -300.86004) (xy 78.368255 -300.887996) (xy 78.403748 -300.922088) (xy 78.433313 -300.961432)
			(xy 78.456184 -301.005009) (xy 78.471768 -301.05169) (xy 78.479663 -301.100267) (xy 78.480158 -301.124874)
			(xy 78.819006 -301.124874) (xy 78.822966 -301.07582) (xy 78.834743 -301.028036) (xy 78.854034 -300.98276)
			(xy 78.880337 -300.941164) (xy 78.912972 -300.904327) (xy 78.951093 -300.873202) (xy 78.993714 -300.848595)
			(xy 79.03973 -300.831143) (xy 79.087949 -300.821299) (xy 79.137124 -300.819318) (xy 79.185979 -300.82525)
			(xy 79.23325 -300.838942) (xy 79.277712 -300.86004) (xy 79.318215 -300.887996) (xy 79.353708 -300.922088)
			(xy 79.383273 -300.961432) (xy 79.406144 -301.005009) (xy 79.421728 -301.05169) (xy 79.429623 -301.100267)
			(xy 79.430118 -301.124874) (xy 79.768966 -301.124874) (xy 79.772926 -301.07582) (xy 79.784703 -301.028036)
			(xy 79.803994 -300.98276) (xy 79.830297 -300.941164) (xy 79.862932 -300.904327) (xy 79.901053 -300.873202)
			(xy 79.943674 -300.848595) (xy 79.98969 -300.831143) (xy 80.037909 -300.821299) (xy 80.087084 -300.819318)
			(xy 80.135939 -300.82525) (xy 80.18321 -300.838942) (xy 80.227672 -300.86004) (xy 80.268175 -300.887996)
			(xy 80.303668 -300.922088) (xy 80.333233 -300.961432) (xy 80.356104 -301.005009) (xy 80.371688 -301.05169)
			(xy 80.379583 -301.100267) (xy 80.380078 -301.124874) (xy 80.71918 -301.124874) (xy 80.72314 -301.07582)
			(xy 80.734917 -301.028036) (xy 80.754208 -300.98276) (xy 80.780511 -300.941164) (xy 80.813146 -300.904327)
			(xy 80.851267 -300.873202) (xy 80.893888 -300.848595) (xy 80.939904 -300.831143) (xy 80.988123 -300.821299)
			(xy 81.037298 -300.819318) (xy 81.086153 -300.82525) (xy 81.133424 -300.838942) (xy 81.177886 -300.86004)
			(xy 81.218389 -300.887996) (xy 81.253882 -300.922088) (xy 81.283447 -300.961432) (xy 81.306318 -301.005009)
			(xy 81.321902 -301.05169) (xy 81.329797 -301.100267) (xy 81.330292 -301.124874) (xy 81.66914 -301.124874)
			(xy 81.6731 -301.07582) (xy 81.684877 -301.028036) (xy 81.704168 -300.98276) (xy 81.730471 -300.941164)
			(xy 81.763106 -300.904327) (xy 81.801227 -300.873202) (xy 81.843848 -300.848595) (xy 81.889864 -300.831143)
			(xy 81.938083 -300.821299) (xy 81.987258 -300.819318) (xy 82.036113 -300.82525) (xy 82.083384 -300.838942)
			(xy 82.127846 -300.86004) (xy 82.168349 -300.887996) (xy 82.203842 -300.922088) (xy 82.233407 -300.961432)
			(xy 82.256278 -301.005009) (xy 82.271862 -301.05169) (xy 82.279757 -301.100267) (xy 82.280252 -301.124874)
			(xy 82.6191 -301.124874) (xy 82.62306 -301.07582) (xy 82.634837 -301.028036) (xy 82.654128 -300.98276)
			(xy 82.680431 -300.941164) (xy 82.713066 -300.904327) (xy 82.751187 -300.873202) (xy 82.793808 -300.848595)
			(xy 82.839824 -300.831143) (xy 82.888043 -300.821299) (xy 82.937218 -300.819318) (xy 82.986073 -300.82525)
			(xy 83.033344 -300.838942) (xy 83.077806 -300.86004) (xy 83.118309 -300.887996) (xy 83.153802 -300.922088)
			(xy 83.183367 -300.961432) (xy 83.206238 -301.005009) (xy 83.221822 -301.05169) (xy 83.229717 -301.100267)
			(xy 83.230212 -301.124874) (xy 83.229717 -301.149481) (xy 83.221822 -301.198058) (xy 83.206238 -301.244739)
			(xy 83.183367 -301.288316) (xy 83.153802 -301.32766) (xy 83.118309 -301.361752) (xy 83.077806 -301.389708)
			(xy 83.033344 -301.410806) (xy 82.986073 -301.424498) (xy 82.937218 -301.43043) (xy 82.888043 -301.428449)
			(xy 82.839824 -301.418605) (xy 82.793808 -301.401153) (xy 82.751187 -301.376546) (xy 82.713066 -301.345421)
			(xy 82.680431 -301.308584) (xy 82.654128 -301.266988) (xy 82.634837 -301.221712) (xy 82.62306 -301.173928)
			(xy 82.6191 -301.124874) (xy 82.280252 -301.124874) (xy 82.279757 -301.149481) (xy 82.271862 -301.198058)
			(xy 82.256278 -301.244739) (xy 82.233407 -301.288316) (xy 82.203842 -301.32766) (xy 82.168349 -301.361752)
			(xy 82.127846 -301.389708) (xy 82.083384 -301.410806) (xy 82.036113 -301.424498) (xy 81.987258 -301.43043)
			(xy 81.938083 -301.428449) (xy 81.889864 -301.418605) (xy 81.843848 -301.401153) (xy 81.801227 -301.376546)
			(xy 81.763106 -301.345421) (xy 81.730471 -301.308584) (xy 81.704168 -301.266988) (xy 81.684877 -301.221712)
			(xy 81.6731 -301.173928) (xy 81.66914 -301.124874) (xy 81.330292 -301.124874) (xy 81.329797 -301.149481)
			(xy 81.321902 -301.198058) (xy 81.306318 -301.244739) (xy 81.283447 -301.288316) (xy 81.253882 -301.32766)
			(xy 81.218389 -301.361752) (xy 81.177886 -301.389708) (xy 81.133424 -301.410806) (xy 81.086153 -301.424498)
			(xy 81.037298 -301.43043) (xy 80.988123 -301.428449) (xy 80.939904 -301.418605) (xy 80.893888 -301.401153)
			(xy 80.851267 -301.376546) (xy 80.813146 -301.345421) (xy 80.780511 -301.308584) (xy 80.754208 -301.266988)
			(xy 80.734917 -301.221712) (xy 80.72314 -301.173928) (xy 80.71918 -301.124874) (xy 80.380078 -301.124874)
			(xy 80.379583 -301.149481) (xy 80.371688 -301.198058) (xy 80.356104 -301.244739) (xy 80.333233 -301.288316)
			(xy 80.303668 -301.32766) (xy 80.268175 -301.361752) (xy 80.227672 -301.389708) (xy 80.18321 -301.410806)
			(xy 80.135939 -301.424498) (xy 80.087084 -301.43043) (xy 80.037909 -301.428449) (xy 79.98969 -301.418605)
			(xy 79.943674 -301.401153) (xy 79.901053 -301.376546) (xy 79.862932 -301.345421) (xy 79.830297 -301.308584)
			(xy 79.803994 -301.266988) (xy 79.784703 -301.221712) (xy 79.772926 -301.173928) (xy 79.768966 -301.124874)
			(xy 79.430118 -301.124874) (xy 79.429623 -301.149481) (xy 79.421728 -301.198058) (xy 79.406144 -301.244739)
			(xy 79.383273 -301.288316) (xy 79.353708 -301.32766) (xy 79.318215 -301.361752) (xy 79.277712 -301.389708)
			(xy 79.23325 -301.410806) (xy 79.185979 -301.424498) (xy 79.137124 -301.43043) (xy 79.087949 -301.428449)
			(xy 79.03973 -301.418605) (xy 78.993714 -301.401153) (xy 78.951093 -301.376546) (xy 78.912972 -301.345421)
			(xy 78.880337 -301.308584) (xy 78.854034 -301.266988) (xy 78.834743 -301.221712) (xy 78.822966 -301.173928)
			(xy 78.819006 -301.124874) (xy 78.480158 -301.124874) (xy 78.479663 -301.149481) (xy 78.471768 -301.198058)
			(xy 78.456184 -301.244739) (xy 78.433313 -301.288316) (xy 78.403748 -301.32766) (xy 78.368255 -301.361752)
			(xy 78.327752 -301.389708) (xy 78.28329 -301.410806) (xy 78.236019 -301.424498) (xy 78.187164 -301.43043)
			(xy 78.137989 -301.428449) (xy 78.08977 -301.418605) (xy 78.043754 -301.401153) (xy 78.001133 -301.376546)
			(xy 77.963012 -301.345421) (xy 77.930377 -301.308584) (xy 77.904074 -301.266988) (xy 77.884783 -301.221712)
			(xy 77.873006 -301.173928) (xy 77.869046 -301.124874) (xy 77.530198 -301.124874) (xy 77.529703 -301.149481)
			(xy 77.521808 -301.198058) (xy 77.506224 -301.244739) (xy 77.483353 -301.288316) (xy 77.453788 -301.32766)
			(xy 77.418295 -301.361752) (xy 77.377792 -301.389708) (xy 77.33333 -301.410806) (xy 77.286059 -301.424498)
			(xy 77.237204 -301.43043) (xy 77.188029 -301.428449) (xy 77.13981 -301.418605) (xy 77.093794 -301.401153)
			(xy 77.051173 -301.376546) (xy 77.013052 -301.345421) (xy 76.980417 -301.308584) (xy 76.954114 -301.266988)
			(xy 76.934823 -301.221712) (xy 76.923046 -301.173928) (xy 76.919086 -301.124874) (xy 76.580143 -301.124874)
			(xy 76.580593 -301.133169) (xy 76.575229 -301.182514) (xy 76.561952 -301.230341) (xy 76.541113 -301.27539)
			(xy 76.513261 -301.316475) (xy 76.479129 -301.352512) (xy 76.439616 -301.382553) (xy 76.395765 -301.405806)
			(xy 76.348729 -301.421659) (xy 76.299748 -301.429694) (xy 76.27493 -301.430182) (xy 76.260747 -301.430002)
			(xy 76.232507 -301.427332) (xy 76.218542 -301.424848) (xy 76.206096 -301.422562) (xy 76.182474 -301.429928)
			(xy 76.105004 -301.507398) (xy 76.097638 -301.53102) (xy 76.099924 -301.543466) (xy 76.102406 -301.557431)
			(xy 76.105074 -301.585671) (xy 76.105258 -301.599854) (xy 76.105076 -301.614037) (xy 76.102408 -301.642277)
			(xy 76.099924 -301.656242) (xy 76.097638 -301.668688) (xy 76.105004 -301.69231) (xy 76.182474 -301.76978)
			(xy 76.206096 -301.777146) (xy 76.218542 -301.77486) (xy 76.232508 -301.772382) (xy 76.260747 -301.769711)
			(xy 76.27493 -301.769526) (xy 76.299747 -301.77001) (xy 76.348727 -301.778045) (xy 76.395762 -301.793897)
			(xy 76.439613 -301.81715) (xy 76.479125 -301.84719) (xy 76.513257 -301.883227) (xy 76.541109 -301.92431)
			(xy 76.561948 -301.969358) (xy 76.575224 -302.017184) (xy 76.580589 -302.066528) (xy 76.580139 -302.074834)
			(xy 76.919086 -302.074834) (xy 76.923046 -302.02578) (xy 76.934823 -301.977996) (xy 76.954114 -301.93272)
			(xy 76.980417 -301.891124) (xy 77.013052 -301.854287) (xy 77.051173 -301.823162) (xy 77.093794 -301.798555)
			(xy 77.13981 -301.781103) (xy 77.188029 -301.771259) (xy 77.237204 -301.769278) (xy 77.286059 -301.77521)
			(xy 77.33333 -301.788902) (xy 77.377792 -301.81) (xy 77.418295 -301.837956) (xy 77.453788 -301.872048)
			(xy 77.483353 -301.911392) (xy 77.506224 -301.954969) (xy 77.521808 -302.00165) (xy 77.529703 -302.050227)
			(xy 77.530198 -302.074834) (xy 77.869046 -302.074834) (xy 77.873006 -302.02578) (xy 77.884783 -301.977996)
			(xy 77.904074 -301.93272) (xy 77.930377 -301.891124) (xy 77.963012 -301.854287) (xy 78.001133 -301.823162)
			(xy 78.043754 -301.798555) (xy 78.08977 -301.781103) (xy 78.137989 -301.771259) (xy 78.187164 -301.769278)
			(xy 78.236019 -301.77521) (xy 78.28329 -301.788902) (xy 78.327752 -301.81) (xy 78.368255 -301.837956)
			(xy 78.403748 -301.872048) (xy 78.433313 -301.911392) (xy 78.456184 -301.954969) (xy 78.471768 -302.00165)
			(xy 78.479663 -302.050227) (xy 78.480158 -302.074834) (xy 78.819006 -302.074834) (xy 78.822966 -302.02578)
			(xy 78.834743 -301.977996) (xy 78.854034 -301.93272) (xy 78.880337 -301.891124) (xy 78.912972 -301.854287)
			(xy 78.951093 -301.823162) (xy 78.993714 -301.798555) (xy 79.03973 -301.781103) (xy 79.087949 -301.771259)
			(xy 79.137124 -301.769278) (xy 79.185979 -301.77521) (xy 79.23325 -301.788902) (xy 79.277712 -301.81)
			(xy 79.318215 -301.837956) (xy 79.353708 -301.872048) (xy 79.383273 -301.911392) (xy 79.406144 -301.954969)
			(xy 79.421728 -302.00165) (xy 79.429623 -302.050227) (xy 79.430118 -302.074834) (xy 79.768966 -302.074834)
			(xy 79.772926 -302.02578) (xy 79.784703 -301.977996) (xy 79.803994 -301.93272) (xy 79.830297 -301.891124)
			(xy 79.862932 -301.854287) (xy 79.901053 -301.823162) (xy 79.943674 -301.798555) (xy 79.98969 -301.781103)
			(xy 80.037909 -301.771259) (xy 80.087084 -301.769278) (xy 80.135939 -301.77521) (xy 80.18321 -301.788902)
			(xy 80.227672 -301.81) (xy 80.268175 -301.837956) (xy 80.303668 -301.872048) (xy 80.333233 -301.911392)
			(xy 80.356104 -301.954969) (xy 80.371688 -302.00165) (xy 80.379583 -302.050227) (xy 80.380078 -302.074834)
			(xy 80.71918 -302.074834) (xy 80.72314 -302.02578) (xy 80.734917 -301.977996) (xy 80.754208 -301.93272)
			(xy 80.780511 -301.891124) (xy 80.813146 -301.854287) (xy 80.851267 -301.823162) (xy 80.893888 -301.798555)
			(xy 80.939904 -301.781103) (xy 80.988123 -301.771259) (xy 81.037298 -301.769278) (xy 81.086153 -301.77521)
			(xy 81.133424 -301.788902) (xy 81.177886 -301.81) (xy 81.218389 -301.837956) (xy 81.253882 -301.872048)
			(xy 81.283447 -301.911392) (xy 81.306318 -301.954969) (xy 81.321902 -302.00165) (xy 81.329797 -302.050227)
			(xy 81.330292 -302.074834) (xy 81.66914 -302.074834) (xy 81.6731 -302.02578) (xy 81.684877 -301.977996)
			(xy 81.704168 -301.93272) (xy 81.730471 -301.891124) (xy 81.763106 -301.854287) (xy 81.801227 -301.823162)
			(xy 81.843848 -301.798555) (xy 81.889864 -301.781103) (xy 81.938083 -301.771259) (xy 81.987258 -301.769278)
			(xy 82.036113 -301.77521) (xy 82.083384 -301.788902) (xy 82.127846 -301.81) (xy 82.168349 -301.837956)
			(xy 82.203842 -301.872048) (xy 82.233407 -301.911392) (xy 82.256278 -301.954969) (xy 82.271862 -302.00165)
			(xy 82.279757 -302.050227) (xy 82.280252 -302.074834) (xy 82.6191 -302.074834) (xy 82.62306 -302.02578)
			(xy 82.634837 -301.977996) (xy 82.654128 -301.93272) (xy 82.680431 -301.891124) (xy 82.713066 -301.854287)
			(xy 82.751187 -301.823162) (xy 82.793808 -301.798555) (xy 82.839824 -301.781103) (xy 82.888043 -301.771259)
			(xy 82.937218 -301.769278) (xy 82.986073 -301.77521) (xy 83.033344 -301.788902) (xy 83.077806 -301.81)
			(xy 83.114972 -301.835653) (xy 84.836443 -301.835653) (xy 84.836443 -301.781145) (xy 84.844201 -301.727191)
			(xy 84.859558 -301.674891) (xy 84.882202 -301.625309) (xy 84.911671 -301.579454) (xy 84.947367 -301.53826)
			(xy 84.988562 -301.502566) (xy 85.034417 -301.473097) (xy 85.084 -301.450454) (xy 85.136301 -301.435099)
			(xy 85.190254 -301.427342) (xy 85.217508 -301.42688) (xy 85.229734 -301.426948) (xy 85.254137 -301.428473)
			(xy 85.266276 -301.429928) (xy 85.278214 -301.431452) (xy 85.300566 -301.423832) (xy 85.374226 -301.34941)
			(xy 85.381592 -301.327058) (xy 85.380068 -301.31512) (xy 85.378309 -301.301918) (xy 85.376401 -301.275351)
			(xy 85.376258 -301.262034) (xy 85.376787 -301.234759) (xy 85.384553 -301.180764) (xy 85.39993 -301.128426)
			(xy 85.422606 -301.078812) (xy 85.452118 -301.032934) (xy 85.487863 -300.991728) (xy 85.529114 -300.956033)
			(xy 85.575029 -300.926579) (xy 85.624671 -300.903964) (xy 85.677028 -300.888652) (xy 85.731032 -300.880954)
			(xy 85.785582 -300.881026) (xy 85.839566 -300.888868) (xy 85.891882 -300.90432) (xy 85.941464 -300.927066)
			(xy 85.9873 -300.956643) (xy 86.028456 -300.992448) (xy 86.064091 -301.033749) (xy 86.069412 -301.04207)
			(xy 90.317574 -301.04207) (xy 90.31806 -301.014819) (xy 90.325816 -300.960871) (xy 90.341171 -300.908576)
			(xy 90.363813 -300.858999) (xy 90.393279 -300.813149) (xy 90.42897 -300.771958) (xy 90.470161 -300.736267)
			(xy 90.516011 -300.706801) (xy 90.565588 -300.684159) (xy 90.617883 -300.668804) (xy 90.671831 -300.661048)
			(xy 90.726333 -300.661048) (xy 90.780281 -300.668804) (xy 90.832576 -300.684159) (xy 90.882153 -300.706801)
			(xy 90.928003 -300.736267) (xy 90.969194 -300.771958) (xy 91.004885 -300.813149) (xy 91.034351 -300.858999)
			(xy 91.056993 -300.908576) (xy 91.072348 -300.960871) (xy 91.080104 -301.014819) (xy 91.08059 -301.04207)
			(xy 91.08043 -301.050452) (xy 92.690948 -301.050452) (xy 92.695019 -300.99483) (xy 92.707145 -300.940393)
			(xy 92.727068 -300.888302) (xy 92.754364 -300.839667) (xy 92.78845 -300.795524) (xy 92.828599 -300.756815)
			(xy 92.873957 -300.724364) (xy 92.923557 -300.698863) (xy 92.976341 -300.680856) (xy 93.031184 -300.670726)
			(xy 93.086918 -300.668689) (xy 93.142355 -300.674789) (xy 93.196312 -300.688895) (xy 93.247641 -300.710707)
			(xy 93.295247 -300.739761) (xy 93.338115 -300.775436) (xy 93.375332 -300.816973) (xy 93.406105 -300.863486)
			(xy 93.429777 -300.913983) (xy 93.445845 -300.96739) (xy 93.453965 -301.022566) (xy 93.454474 -301.050452)
			(xy 93.453965 -301.078338) (xy 93.445845 -301.133514) (xy 93.429777 -301.186921) (xy 93.406105 -301.237418)
			(xy 93.375332 -301.283931) (xy 93.338115 -301.325468) (xy 93.295247 -301.361143) (xy 93.247641 -301.390197)
			(xy 93.196312 -301.412009) (xy 93.142355 -301.426115) (xy 93.086918 -301.432215) (xy 93.031184 -301.430178)
			(xy 92.976341 -301.420048) (xy 92.923557 -301.402041) (xy 92.873957 -301.37654) (xy 92.828599 -301.344089)
			(xy 92.78845 -301.30538) (xy 92.754364 -301.261237) (xy 92.727068 -301.212602) (xy 92.707145 -301.160511)
			(xy 92.695019 -301.106074) (xy 92.690948 -301.050452) (xy 91.08043 -301.050452) (xy 91.080008 -301.072563)
			(xy 91.070321 -301.132774) (xy 91.051188 -301.19068) (xy 91.023096 -301.24481) (xy 91.005406 -301.269654)
			(xy 90.998548 -301.278798) (xy 90.993976 -301.300896) (xy 91.018614 -301.399448) (xy 91.033092 -301.416974)
			(xy 91.043506 -301.4218) (xy 91.067638 -301.433754) (xy 91.112573 -301.463433) (xy 91.15289 -301.499133)
			(xy 91.18779 -301.540146) (xy 91.210938 -301.57674) (xy 91.51315 -301.57674) (xy 91.517221 -301.521118)
			(xy 91.529347 -301.466681) (xy 91.54927 -301.41459) (xy 91.576566 -301.365955) (xy 91.610652 -301.321812)
			(xy 91.650801 -301.283103) (xy 91.696159 -301.250652) (xy 91.745759 -301.225151) (xy 91.798543 -301.207144)
			(xy 91.853386 -301.197014) (xy 91.90912 -301.194977) (xy 91.964557 -301.201077) (xy 92.018514 -301.215183)
			(xy 92.069843 -301.236995) (xy 92.117449 -301.266049) (xy 92.160317 -301.301724) (xy 92.197534 -301.343261)
			(xy 92.228307 -301.389774) (xy 92.251979 -301.440271) (xy 92.268047 -301.493678) (xy 92.276167 -301.548854)
			(xy 92.276676 -301.57674) (xy 92.276167 -301.604626) (xy 92.268047 -301.659802) (xy 92.251979 -301.713209)
			(xy 92.228307 -301.763706) (xy 92.197534 -301.810219) (xy 92.160317 -301.851756) (xy 92.117449 -301.887431)
			(xy 92.069843 -301.916485) (xy 92.018514 -301.938297) (xy 91.964557 -301.952403) (xy 91.90912 -301.958503)
			(xy 91.853386 -301.956466) (xy 91.798543 -301.946336) (xy 91.745759 -301.928329) (xy 91.696159 -301.902828)
			(xy 91.650801 -301.870377) (xy 91.610652 -301.831668) (xy 91.576566 -301.787525) (xy 91.54927 -301.73889)
			(xy 91.529347 -301.686799) (xy 91.517221 -301.632362) (xy 91.51315 -301.57674) (xy 91.210938 -301.57674)
			(xy 91.216578 -301.585657) (xy 91.238683 -301.634763) (xy 91.253667 -301.686488) (xy 91.261232 -301.739806)
			(xy 91.261692 -301.766732) (xy 91.261206 -301.793983) (xy 91.25345 -301.847931) (xy 91.238095 -301.900226)
			(xy 91.215453 -301.949803) (xy 91.185987 -301.995653) (xy 91.150296 -302.036844) (xy 91.109105 -302.072535)
			(xy 91.063255 -302.102001) (xy 91.013678 -302.124643) (xy 90.961383 -302.139998) (xy 90.907435 -302.147754)
			(xy 90.852933 -302.147754) (xy 90.798985 -302.139998) (xy 90.74669 -302.124643) (xy 90.697113 -302.102001)
			(xy 90.651263 -302.072535) (xy 90.610072 -302.036844) (xy 90.574381 -301.995653) (xy 90.544915 -301.949803)
			(xy 90.522273 -301.900226) (xy 90.506918 -301.847931) (xy 90.499162 -301.793983) (xy 90.498676 -301.766732)
			(xy 90.499265 -301.73624) (xy 90.508951 -301.676029) (xy 90.528082 -301.618123) (xy 90.556171 -301.563992)
			(xy 90.57386 -301.539148) (xy 90.580718 -301.530004) (xy 90.58529 -301.507906) (xy 90.560652 -301.409354)
			(xy 90.546174 -301.391828) (xy 90.53576 -301.387002) (xy 90.511621 -301.375062) (xy 90.466688 -301.34538)
			(xy 90.426371 -301.309676) (xy 90.391474 -301.268661) (xy 90.362687 -301.223148) (xy 90.340582 -301.174041)
			(xy 90.325599 -301.122315) (xy 90.318034 -301.068996) (xy 90.317574 -301.04207) (xy 86.069412 -301.04207)
			(xy 86.093481 -301.079706) (xy 86.116024 -301.12938) (xy 86.131262 -301.181758) (xy 86.138884 -301.235774)
			(xy 86.139274 -301.26305) (xy 86.139274 -301.274226) (xy 86.148164 -301.294038) (xy 86.222078 -301.359062)
			(xy 86.242906 -301.365412) (xy 86.253828 -301.364142) (xy 86.26609 -301.362615) (xy 86.290748 -301.360962)
			(xy 86.303104 -301.36084) (xy 86.332328 -301.361372) (xy 86.390089 -301.370301) (xy 86.445814 -301.387933)
			(xy 86.498197 -301.413857) (xy 86.546015 -301.447466) (xy 86.588149 -301.487974) (xy 86.623612 -301.534433)
			(xy 86.651576 -301.585757) (xy 86.662006 -301.613062) (xy 86.666832 -301.626524) (xy 86.68893 -301.644304)
			(xy 86.806532 -301.660052) (xy 86.83244 -301.648876) (xy 86.840822 -301.637192) (xy 86.856173 -301.616072)
			(xy 86.891738 -301.577846) (xy 86.932188 -301.544832) (xy 86.976765 -301.517648) (xy 87.024636 -301.496804)
			(xy 87.074904 -301.482688) (xy 87.126628 -301.475566) (xy 87.152734 -301.47514) (xy 87.179987 -301.475532)
			(xy 87.233938 -301.483294) (xy 87.286235 -301.498654) (xy 87.335814 -301.5213) (xy 87.381666 -301.55077)
			(xy 87.383789 -301.55261) (xy 88.11971 -301.55261) (xy 88.123781 -301.496988) (xy 88.135907 -301.442551)
			(xy 88.15583 -301.39046) (xy 88.183126 -301.341825) (xy 88.217212 -301.297682) (xy 88.257361 -301.258973)
			(xy 88.302719 -301.226522) (xy 88.352319 -301.201021) (xy 88.405103 -301.183014) (xy 88.459946 -301.172884)
			(xy 88.51568 -301.170847) (xy 88.571117 -301.176947) (xy 88.625074 -301.191053) (xy 88.676403 -301.212865)
			(xy 88.724009 -301.241919) (xy 88.766877 -301.277594) (xy 88.804094 -301.319131) (xy 88.834867 -301.365644)
			(xy 88.858539 -301.416141) (xy 88.874607 -301.469548) (xy 88.882727 -301.524724) (xy 88.883236 -301.55261)
			(xy 88.882727 -301.580496) (xy 88.874607 -301.635672) (xy 88.858539 -301.689079) (xy 88.834867 -301.739576)
			(xy 88.804094 -301.786089) (xy 88.766877 -301.827626) (xy 88.724009 -301.863301) (xy 88.676403 -301.892355)
			(xy 88.625074 -301.914167) (xy 88.571117 -301.928273) (xy 88.51568 -301.934373) (xy 88.459946 -301.932336)
			(xy 88.405103 -301.922206) (xy 88.352319 -301.904199) (xy 88.302719 -301.878698) (xy 88.257361 -301.846247)
			(xy 88.217212 -301.807538) (xy 88.183126 -301.763395) (xy 88.15583 -301.71476) (xy 88.135907 -301.662669)
			(xy 88.123781 -301.608232) (xy 88.11971 -301.55261) (xy 87.383789 -301.55261) (xy 87.422858 -301.586466)
			(xy 87.45855 -301.627661) (xy 87.488017 -301.673516) (xy 87.510658 -301.723097) (xy 87.526014 -301.775395)
			(xy 87.53377 -301.829347) (xy 87.53377 -301.883853) (xy 87.526014 -301.937805) (xy 87.510658 -301.990103)
			(xy 87.488017 -302.039684) (xy 87.45855 -302.085539) (xy 87.422858 -302.126734) (xy 87.381666 -302.16243)
			(xy 87.335814 -302.1919) (xy 87.286235 -302.214546) (xy 87.233938 -302.229906) (xy 87.179987 -302.237668)
			(xy 87.152734 -302.238156) (xy 87.123511 -302.237594) (xy 87.065751 -302.228671) (xy 87.010027 -302.211043)
			(xy 86.957643 -302.185124) (xy 86.909825 -302.151519) (xy 86.867691 -302.111015) (xy 86.832227 -302.064559)
			(xy 86.804262 -302.013238) (xy 86.793832 -301.985934) (xy 86.789006 -301.972472) (xy 86.766908 -301.954692)
			(xy 86.649306 -301.938944) (xy 86.623398 -301.95012) (xy 86.615016 -301.961804) (xy 86.599641 -301.982905)
			(xy 86.56408 -302.021132) (xy 86.523634 -302.054148) (xy 86.479061 -302.081334) (xy 86.431194 -302.102181)
			(xy 86.38093 -302.116301) (xy 86.329209 -302.123427) (xy 86.303104 -302.123856) (xy 86.275807 -302.123339)
			(xy 86.221771 -302.115558) (xy 86.169396 -302.100153) (xy 86.119751 -302.07744) (xy 86.073851 -302.047883)
			(xy 86.032633 -302.012084) (xy 85.996939 -301.970776) (xy 85.967498 -301.924801) (xy 85.94491 -301.875099)
			(xy 85.929638 -301.822686) (xy 85.921993 -301.76863) (xy 85.921596 -301.741332) (xy 85.921596 -301.730156)
			(xy 85.912706 -301.710344) (xy 85.838792 -301.64532) (xy 85.817964 -301.63897) (xy 85.807042 -301.64024)
			(xy 85.79478 -301.64177) (xy 85.770122 -301.643421) (xy 85.757766 -301.643542) (xy 85.74554 -301.643474)
			(xy 85.721137 -301.641947) (xy 85.708998 -301.640494) (xy 85.69706 -301.63897) (xy 85.674708 -301.64659)
			(xy 85.601048 -301.721012) (xy 85.593682 -301.743364) (xy 85.595206 -301.755302) (xy 85.596967 -301.768503)
			(xy 85.598873 -301.795071) (xy 85.599016 -301.808388) (xy 85.598558 -301.835642) (xy 85.590802 -301.889596)
			(xy 85.575447 -301.941896) (xy 85.552805 -301.991479) (xy 85.523337 -302.037335) (xy 85.487642 -302.07853)
			(xy 85.446449 -302.114226) (xy 85.400594 -302.143697) (xy 85.351012 -302.166341) (xy 85.298713 -302.181699)
			(xy 85.244759 -302.189457) (xy 85.190251 -302.189457) (xy 85.136298 -302.181701) (xy 85.083998 -302.166345)
			(xy 85.034415 -302.143702) (xy 84.98856 -302.114233) (xy 84.947365 -302.078538) (xy 84.91167 -302.037343)
			(xy 84.8822 -301.991488) (xy 84.859557 -301.941906) (xy 84.8442 -301.889606) (xy 84.836443 -301.835653)
			(xy 83.114972 -301.835653) (xy 83.118309 -301.837956) (xy 83.153802 -301.872048) (xy 83.183367 -301.911392)
			(xy 83.206238 -301.954969) (xy 83.221822 -302.00165) (xy 83.229717 -302.050227) (xy 83.230212 -302.074834)
			(xy 83.229717 -302.099441) (xy 83.221822 -302.148018) (xy 83.206238 -302.194699) (xy 83.183367 -302.238276)
			(xy 83.153802 -302.27762) (xy 83.118309 -302.311712) (xy 83.077806 -302.339668) (xy 83.033344 -302.360766)
			(xy 82.986073 -302.374458) (xy 82.937218 -302.38039) (xy 82.888043 -302.378409) (xy 82.839824 -302.368565)
			(xy 82.793808 -302.351113) (xy 82.751187 -302.326506) (xy 82.713066 -302.295381) (xy 82.680431 -302.258544)
			(xy 82.654128 -302.216948) (xy 82.634837 -302.171672) (xy 82.62306 -302.123888) (xy 82.6191 -302.074834)
			(xy 82.280252 -302.074834) (xy 82.279757 -302.099441) (xy 82.271862 -302.148018) (xy 82.256278 -302.194699)
			(xy 82.233407 -302.238276) (xy 82.203842 -302.27762) (xy 82.168349 -302.311712) (xy 82.127846 -302.339668)
			(xy 82.083384 -302.360766) (xy 82.036113 -302.374458) (xy 81.987258 -302.38039) (xy 81.938083 -302.378409)
			(xy 81.889864 -302.368565) (xy 81.843848 -302.351113) (xy 81.801227 -302.326506) (xy 81.763106 -302.295381)
			(xy 81.730471 -302.258544) (xy 81.704168 -302.216948) (xy 81.684877 -302.171672) (xy 81.6731 -302.123888)
			(xy 81.66914 -302.074834) (xy 81.330292 -302.074834) (xy 81.329797 -302.099441) (xy 81.321902 -302.148018)
			(xy 81.306318 -302.194699) (xy 81.283447 -302.238276) (xy 81.253882 -302.27762) (xy 81.218389 -302.311712)
			(xy 81.177886 -302.339668) (xy 81.133424 -302.360766) (xy 81.086153 -302.374458) (xy 81.037298 -302.38039)
			(xy 80.988123 -302.378409) (xy 80.939904 -302.368565) (xy 80.893888 -302.351113) (xy 80.851267 -302.326506)
			(xy 80.813146 -302.295381) (xy 80.780511 -302.258544) (xy 80.754208 -302.216948) (xy 80.734917 -302.171672)
			(xy 80.72314 -302.123888) (xy 80.71918 -302.074834) (xy 80.380078 -302.074834) (xy 80.379583 -302.099441)
			(xy 80.371688 -302.148018) (xy 80.356104 -302.194699) (xy 80.333233 -302.238276) (xy 80.303668 -302.27762)
			(xy 80.268175 -302.311712) (xy 80.227672 -302.339668) (xy 80.18321 -302.360766) (xy 80.135939 -302.374458)
			(xy 80.087084 -302.38039) (xy 80.037909 -302.378409) (xy 79.98969 -302.368565) (xy 79.943674 -302.351113)
			(xy 79.901053 -302.326506) (xy 79.862932 -302.295381) (xy 79.830297 -302.258544) (xy 79.803994 -302.216948)
			(xy 79.784703 -302.171672) (xy 79.772926 -302.123888) (xy 79.768966 -302.074834) (xy 79.430118 -302.074834)
			(xy 79.429623 -302.099441) (xy 79.421728 -302.148018) (xy 79.406144 -302.194699) (xy 79.383273 -302.238276)
			(xy 79.353708 -302.27762) (xy 79.318215 -302.311712) (xy 79.277712 -302.339668) (xy 79.23325 -302.360766)
			(xy 79.185979 -302.374458) (xy 79.137124 -302.38039) (xy 79.087949 -302.378409) (xy 79.03973 -302.368565)
			(xy 78.993714 -302.351113) (xy 78.951093 -302.326506) (xy 78.912972 -302.295381) (xy 78.880337 -302.258544)
			(xy 78.854034 -302.216948) (xy 78.834743 -302.171672) (xy 78.822966 -302.123888) (xy 78.819006 -302.074834)
			(xy 78.480158 -302.074834) (xy 78.479663 -302.099441) (xy 78.471768 -302.148018) (xy 78.456184 -302.194699)
			(xy 78.433313 -302.238276) (xy 78.403748 -302.27762) (xy 78.368255 -302.311712) (xy 78.327752 -302.339668)
			(xy 78.28329 -302.360766) (xy 78.236019 -302.374458) (xy 78.187164 -302.38039) (xy 78.137989 -302.378409)
			(xy 78.08977 -302.368565) (xy 78.043754 -302.351113) (xy 78.001133 -302.326506) (xy 77.963012 -302.295381)
			(xy 77.930377 -302.258544) (xy 77.904074 -302.216948) (xy 77.884783 -302.171672) (xy 77.873006 -302.123888)
			(xy 77.869046 -302.074834) (xy 77.530198 -302.074834) (xy 77.529703 -302.099441) (xy 77.521808 -302.148018)
			(xy 77.506224 -302.194699) (xy 77.483353 -302.238276) (xy 77.453788 -302.27762) (xy 77.418295 -302.311712)
			(xy 77.377792 -302.339668) (xy 77.33333 -302.360766) (xy 77.286059 -302.374458) (xy 77.237204 -302.38039)
			(xy 77.188029 -302.378409) (xy 77.13981 -302.368565) (xy 77.093794 -302.351113) (xy 77.051173 -302.326506)
			(xy 77.013052 -302.295381) (xy 76.980417 -302.258544) (xy 76.954114 -302.216948) (xy 76.934823 -302.171672)
			(xy 76.923046 -302.123888) (xy 76.919086 -302.074834) (xy 76.580139 -302.074834) (xy 76.577901 -302.11609)
			(xy 76.56723 -302.164564) (xy 76.548858 -302.210673) (xy 76.523268 -302.253203) (xy 76.491135 -302.291033)
			(xy 76.453306 -302.323166) (xy 76.410777 -302.348756) (xy 76.364668 -302.367129) (xy 76.316194 -302.3778)
			(xy 76.266632 -302.380489) (xy 76.217288 -302.375125) (xy 76.169462 -302.361849) (xy 76.124414 -302.341011)
			(xy 76.08333 -302.313159) (xy 76.047293 -302.279028) (xy 76.017252 -302.239517) (xy 75.993999 -302.195666)
			(xy 75.978146 -302.148631) (xy 75.97011 -302.099651) (xy 75.969622 -302.074834) (xy 75.969803 -302.060651)
			(xy 75.972472 -302.032411) (xy 75.974956 -302.018446) (xy 75.977242 -302.006) (xy 75.969876 -301.982378)
			(xy 75.892406 -301.904908) (xy 75.868784 -301.897542) (xy 75.856338 -301.899828) (xy 75.842373 -301.902309)
			(xy 75.814133 -301.904978) (xy 75.79995 -301.905162) (xy 75.774694 -301.904729) (xy 75.724871 -301.896407)
			(xy 75.677097 -301.88) (xy 75.632674 -301.855953) (xy 75.592815 -301.824924) (xy 75.558607 -301.787757)
			(xy 75.530981 -301.745468) (xy 75.510692 -301.699208) (xy 75.498293 -301.650241) (xy 75.494122 -301.5999)
			(xy 49.149254 -301.5999) (xy 49.149254 -302.074834) (xy 49.368976 -302.074834) (xy 49.372936 -302.02578)
			(xy 49.384713 -301.977996) (xy 49.404004 -301.93272) (xy 49.430307 -301.891124) (xy 49.462942 -301.854287)
			(xy 49.501063 -301.823162) (xy 49.543684 -301.798555) (xy 49.5897 -301.781103) (xy 49.637919 -301.771259)
			(xy 49.687094 -301.769278) (xy 49.735949 -301.77521) (xy 49.78322 -301.788902) (xy 49.827682 -301.81)
			(xy 49.868185 -301.837956) (xy 49.903678 -301.872048) (xy 49.933243 -301.911392) (xy 49.956114 -301.954969)
			(xy 49.971698 -302.00165) (xy 49.979593 -302.050227) (xy 49.980088 -302.074834) (xy 50.31919 -302.074834)
			(xy 50.32315 -302.02578) (xy 50.334927 -301.977996) (xy 50.354218 -301.93272) (xy 50.380521 -301.891124)
			(xy 50.413156 -301.854287) (xy 50.451277 -301.823162) (xy 50.493898 -301.798555) (xy 50.539914 -301.781103)
			(xy 50.588133 -301.771259) (xy 50.637308 -301.769278) (xy 50.686163 -301.77521) (xy 50.733434 -301.788902)
			(xy 50.777896 -301.81) (xy 50.818399 -301.837956) (xy 50.853892 -301.872048) (xy 50.883457 -301.911392)
			(xy 50.906328 -301.954969) (xy 50.921912 -302.00165) (xy 50.929807 -302.050227) (xy 50.930302 -302.074834)
			(xy 51.26915 -302.074834) (xy 51.27311 -302.02578) (xy 51.284887 -301.977996) (xy 51.304178 -301.93272)
			(xy 51.330481 -301.891124) (xy 51.363116 -301.854287) (xy 51.401237 -301.823162) (xy 51.443858 -301.798555)
			(xy 51.489874 -301.781103) (xy 51.538093 -301.771259) (xy 51.587268 -301.769278) (xy 51.636123 -301.77521)
			(xy 51.683394 -301.788902) (xy 51.727856 -301.81) (xy 51.768359 -301.837956) (xy 51.803852 -301.872048)
			(xy 51.833417 -301.911392) (xy 51.856288 -301.954969) (xy 51.871872 -302.00165) (xy 51.879767 -302.050227)
			(xy 51.880262 -302.074834) (xy 52.21911 -302.074834) (xy 52.22307 -302.02578) (xy 52.234847 -301.977996)
			(xy 52.254138 -301.93272) (xy 52.280441 -301.891124) (xy 52.313076 -301.854287) (xy 52.351197 -301.823162)
			(xy 52.393818 -301.798555) (xy 52.439834 -301.781103) (xy 52.488053 -301.771259) (xy 52.537228 -301.769278)
			(xy 52.586083 -301.77521) (xy 52.633354 -301.788902) (xy 52.677816 -301.81) (xy 52.718319 -301.837956)
			(xy 52.753812 -301.872048) (xy 52.783377 -301.911392) (xy 52.806248 -301.954969) (xy 52.821832 -302.00165)
			(xy 52.829727 -302.050227) (xy 52.830222 -302.074834) (xy 53.16907 -302.074834) (xy 53.17303 -302.02578)
			(xy 53.184807 -301.977996) (xy 53.204098 -301.93272) (xy 53.230401 -301.891124) (xy 53.263036 -301.854287)
			(xy 53.301157 -301.823162) (xy 53.343778 -301.798555) (xy 53.389794 -301.781103) (xy 53.438013 -301.771259)
			(xy 53.487188 -301.769278) (xy 53.536043 -301.77521) (xy 53.583314 -301.788902) (xy 53.627776 -301.81)
			(xy 53.668279 -301.837956) (xy 53.703772 -301.872048) (xy 53.733337 -301.911392) (xy 53.756208 -301.954969)
			(xy 53.771792 -302.00165) (xy 53.779687 -302.050227) (xy 53.780182 -302.074834) (xy 54.11903 -302.074834)
			(xy 54.12299 -302.02578) (xy 54.134767 -301.977996) (xy 54.154058 -301.93272) (xy 54.180361 -301.891124)
			(xy 54.212996 -301.854287) (xy 54.251117 -301.823162) (xy 54.293738 -301.798555) (xy 54.339754 -301.781103)
			(xy 54.387973 -301.771259) (xy 54.437148 -301.769278) (xy 54.486003 -301.77521) (xy 54.533274 -301.788902)
			(xy 54.577736 -301.81) (xy 54.618239 -301.837956) (xy 54.653732 -301.872048) (xy 54.683297 -301.911392)
			(xy 54.706168 -301.954969) (xy 54.721752 -302.00165) (xy 54.729647 -302.050227) (xy 54.730142 -302.074834)
			(xy 55.06899 -302.074834) (xy 55.07295 -302.02578) (xy 55.084727 -301.977996) (xy 55.104018 -301.93272)
			(xy 55.130321 -301.891124) (xy 55.162956 -301.854287) (xy 55.201077 -301.823162) (xy 55.243698 -301.798555)
			(xy 55.289714 -301.781103) (xy 55.337933 -301.771259) (xy 55.387108 -301.769278) (xy 55.435963 -301.77521)
			(xy 55.483234 -301.788902) (xy 55.527696 -301.81) (xy 55.568199 -301.837956) (xy 55.603692 -301.872048)
			(xy 55.633257 -301.911392) (xy 55.656128 -301.954969) (xy 55.671712 -302.00165) (xy 55.679607 -302.050227)
			(xy 55.680102 -302.074834) (xy 56.01895 -302.074834) (xy 56.02291 -302.02578) (xy 56.034687 -301.977996)
			(xy 56.053978 -301.93272) (xy 56.080281 -301.891124) (xy 56.112916 -301.854287) (xy 56.151037 -301.823162)
			(xy 56.193658 -301.798555) (xy 56.239674 -301.781103) (xy 56.287893 -301.771259) (xy 56.337068 -301.769278)
			(xy 56.385923 -301.77521) (xy 56.433194 -301.788902) (xy 56.477656 -301.81) (xy 56.518159 -301.837956)
			(xy 56.553652 -301.872048) (xy 56.583217 -301.911392) (xy 56.606088 -301.954969) (xy 56.621672 -302.00165)
			(xy 56.629567 -302.050227) (xy 56.630062 -302.074834) (xy 56.969164 -302.074834) (xy 56.973124 -302.02578)
			(xy 56.984901 -301.977996) (xy 57.004192 -301.93272) (xy 57.030495 -301.891124) (xy 57.06313 -301.854287)
			(xy 57.101251 -301.823162) (xy 57.143872 -301.798555) (xy 57.189888 -301.781103) (xy 57.238107 -301.771259)
			(xy 57.287282 -301.769278) (xy 57.336137 -301.77521) (xy 57.383408 -301.788902) (xy 57.42787 -301.81)
			(xy 57.468373 -301.837956) (xy 57.503866 -301.872048) (xy 57.533431 -301.911392) (xy 57.556302 -301.954969)
			(xy 57.571886 -302.00165) (xy 57.579781 -302.050227) (xy 57.580276 -302.074834) (xy 57.919124 -302.074834)
			(xy 57.923084 -302.02578) (xy 57.934861 -301.977996) (xy 57.954152 -301.93272) (xy 57.980455 -301.891124)
			(xy 58.01309 -301.854287) (xy 58.051211 -301.823162) (xy 58.093832 -301.798555) (xy 58.139848 -301.781103)
			(xy 58.188067 -301.771259) (xy 58.237242 -301.769278) (xy 58.286097 -301.77521) (xy 58.333368 -301.788902)
			(xy 58.37783 -301.81) (xy 58.418333 -301.837956) (xy 58.453826 -301.872048) (xy 58.483391 -301.911392)
			(xy 58.506262 -301.954969) (xy 58.521846 -302.00165) (xy 58.529741 -302.050227) (xy 58.530236 -302.074834)
			(xy 59.819044 -302.074834) (xy 59.823004 -302.02578) (xy 59.834781 -301.977996) (xy 59.854072 -301.93272)
			(xy 59.880375 -301.891124) (xy 59.91301 -301.854287) (xy 59.951131 -301.823162) (xy 59.993752 -301.798555)
			(xy 60.039768 -301.781103) (xy 60.087987 -301.771259) (xy 60.137162 -301.769278) (xy 60.186017 -301.77521)
			(xy 60.233288 -301.788902) (xy 60.27775 -301.81) (xy 60.318253 -301.837956) (xy 60.353746 -301.872048)
			(xy 60.383311 -301.911392) (xy 60.406182 -301.954969) (xy 60.421766 -302.00165) (xy 60.429661 -302.050227)
			(xy 60.430156 -302.074834) (xy 60.769004 -302.074834) (xy 60.772964 -302.02578) (xy 60.784741 -301.977996)
			(xy 60.804032 -301.93272) (xy 60.830335 -301.891124) (xy 60.86297 -301.854287) (xy 60.901091 -301.823162)
			(xy 60.943712 -301.798555) (xy 60.989728 -301.781103) (xy 61.037947 -301.771259) (xy 61.087122 -301.769278)
			(xy 61.135977 -301.77521) (xy 61.183248 -301.788902) (xy 61.22771 -301.81) (xy 61.268213 -301.837956)
			(xy 61.303706 -301.872048) (xy 61.333271 -301.911392) (xy 61.356142 -301.954969) (xy 61.371726 -302.00165)
			(xy 61.379621 -302.050227) (xy 61.380116 -302.074834) (xy 61.718964 -302.074834) (xy 61.722924 -302.02578)
			(xy 61.734701 -301.977996) (xy 61.753992 -301.93272) (xy 61.780295 -301.891124) (xy 61.81293 -301.854287)
			(xy 61.851051 -301.823162) (xy 61.893672 -301.798555) (xy 61.939688 -301.781103) (xy 61.987907 -301.771259)
			(xy 62.037082 -301.769278) (xy 62.085937 -301.77521) (xy 62.133208 -301.788902) (xy 62.17767 -301.81)
			(xy 62.218173 -301.837956) (xy 62.253666 -301.872048) (xy 62.283231 -301.911392) (xy 62.306102 -301.954969)
			(xy 62.321686 -302.00165) (xy 62.329581 -302.050227) (xy 62.330076 -302.074834) (xy 62.669178 -302.074834)
			(xy 62.673138 -302.02578) (xy 62.684915 -301.977996) (xy 62.704206 -301.93272) (xy 62.730509 -301.891124)
			(xy 62.763144 -301.854287) (xy 62.801265 -301.823162) (xy 62.843886 -301.798555) (xy 62.889902 -301.781103)
			(xy 62.938121 -301.771259) (xy 62.987296 -301.769278) (xy 63.036151 -301.77521) (xy 63.083422 -301.788902)
			(xy 63.127884 -301.81) (xy 63.168387 -301.837956) (xy 63.20388 -301.872048) (xy 63.233445 -301.911392)
			(xy 63.256316 -301.954969) (xy 63.2719 -302.00165) (xy 63.279795 -302.050227) (xy 63.28029 -302.074834)
			(xy 63.619138 -302.074834) (xy 63.623098 -302.02578) (xy 63.634875 -301.977996) (xy 63.654166 -301.93272)
			(xy 63.680469 -301.891124) (xy 63.713104 -301.854287) (xy 63.751225 -301.823162) (xy 63.793846 -301.798555)
			(xy 63.839862 -301.781103) (xy 63.888081 -301.771259) (xy 63.937256 -301.769278) (xy 63.986111 -301.77521)
			(xy 64.033382 -301.788902) (xy 64.077844 -301.81) (xy 64.118347 -301.837956) (xy 64.15384 -301.872048)
			(xy 64.183405 -301.911392) (xy 64.206276 -301.954969) (xy 64.22186 -302.00165) (xy 64.229755 -302.050227)
			(xy 64.23025 -302.074834) (xy 64.569098 -302.074834) (xy 64.573058 -302.02578) (xy 64.584835 -301.977996)
			(xy 64.604126 -301.93272) (xy 64.630429 -301.891124) (xy 64.663064 -301.854287) (xy 64.701185 -301.823162)
			(xy 64.743806 -301.798555) (xy 64.789822 -301.781103) (xy 64.838041 -301.771259) (xy 64.887216 -301.769278)
			(xy 64.936071 -301.77521) (xy 64.983342 -301.788902) (xy 65.027804 -301.81) (xy 65.068307 -301.837956)
			(xy 65.1038 -301.872048) (xy 65.133365 -301.911392) (xy 65.156236 -301.954969) (xy 65.17182 -302.00165)
			(xy 65.179715 -302.050227) (xy 65.18021 -302.074834) (xy 65.519058 -302.074834) (xy 65.523018 -302.02578)
			(xy 65.534795 -301.977996) (xy 65.554086 -301.93272) (xy 65.580389 -301.891124) (xy 65.613024 -301.854287)
			(xy 65.651145 -301.823162) (xy 65.693766 -301.798555) (xy 65.739782 -301.781103) (xy 65.788001 -301.771259)
			(xy 65.837176 -301.769278) (xy 65.886031 -301.77521) (xy 65.933302 -301.788902) (xy 65.977764 -301.81)
			(xy 66.018267 -301.837956) (xy 66.05376 -301.872048) (xy 66.083325 -301.911392) (xy 66.106196 -301.954969)
			(xy 66.12178 -302.00165) (xy 66.129675 -302.050227) (xy 66.13017 -302.074834) (xy 66.469018 -302.074834)
			(xy 66.472978 -302.02578) (xy 66.484755 -301.977996) (xy 66.504046 -301.93272) (xy 66.530349 -301.891124)
			(xy 66.562984 -301.854287) (xy 66.601105 -301.823162) (xy 66.643726 -301.798555) (xy 66.689742 -301.781103)
			(xy 66.737961 -301.771259) (xy 66.787136 -301.769278) (xy 66.835991 -301.77521) (xy 66.883262 -301.788902)
			(xy 66.927724 -301.81) (xy 66.968227 -301.837956) (xy 67.00372 -301.872048) (xy 67.033285 -301.911392)
			(xy 67.056156 -301.954969) (xy 67.07174 -302.00165) (xy 67.079635 -302.050227) (xy 67.08013 -302.074834)
			(xy 67.418978 -302.074834) (xy 67.422938 -302.02578) (xy 67.434715 -301.977996) (xy 67.454006 -301.93272)
			(xy 67.480309 -301.891124) (xy 67.512944 -301.854287) (xy 67.551065 -301.823162) (xy 67.593686 -301.798555)
			(xy 67.639702 -301.781103) (xy 67.687921 -301.771259) (xy 67.737096 -301.769278) (xy 67.785951 -301.77521)
			(xy 67.833222 -301.788902) (xy 67.877684 -301.81) (xy 67.918187 -301.837956) (xy 67.95368 -301.872048)
			(xy 67.983245 -301.911392) (xy 68.006116 -301.954969) (xy 68.0217 -302.00165) (xy 68.029595 -302.050227)
			(xy 68.03009 -302.074834) (xy 68.368938 -302.074834) (xy 68.372898 -302.02578) (xy 68.384675 -301.977996)
			(xy 68.403966 -301.93272) (xy 68.430269 -301.891124) (xy 68.462904 -301.854287) (xy 68.501025 -301.823162)
			(xy 68.543646 -301.798555) (xy 68.589662 -301.781103) (xy 68.637881 -301.771259) (xy 68.687056 -301.769278)
			(xy 68.735911 -301.77521) (xy 68.783182 -301.788902) (xy 68.827644 -301.81) (xy 68.868147 -301.837956)
			(xy 68.90364 -301.872048) (xy 68.933205 -301.911392) (xy 68.956076 -301.954969) (xy 68.97166 -302.00165)
			(xy 68.979555 -302.050227) (xy 68.98005 -302.074834) (xy 69.319152 -302.074834) (xy 69.323112 -302.02578)
			(xy 69.334889 -301.977996) (xy 69.35418 -301.93272) (xy 69.380483 -301.891124) (xy 69.413118 -301.854287)
			(xy 69.451239 -301.823162) (xy 69.49386 -301.798555) (xy 69.539876 -301.781103) (xy 69.588095 -301.771259)
			(xy 69.63727 -301.769278) (xy 69.686125 -301.77521) (xy 69.733396 -301.788902) (xy 69.777858 -301.81)
			(xy 69.818361 -301.837956) (xy 69.853854 -301.872048) (xy 69.883419 -301.911392) (xy 69.90629 -301.954969)
			(xy 69.921874 -302.00165) (xy 69.929769 -302.050227) (xy 69.930264 -302.074834) (xy 70.269112 -302.074834)
			(xy 70.273072 -302.02578) (xy 70.284849 -301.977996) (xy 70.30414 -301.93272) (xy 70.330443 -301.891124)
			(xy 70.363078 -301.854287) (xy 70.401199 -301.823162) (xy 70.44382 -301.798555) (xy 70.489836 -301.781103)
			(xy 70.538055 -301.771259) (xy 70.58723 -301.769278) (xy 70.636085 -301.77521) (xy 70.683356 -301.788902)
			(xy 70.727818 -301.81) (xy 70.768321 -301.837956) (xy 70.803814 -301.872048) (xy 70.833379 -301.911392)
			(xy 70.85625 -301.954969) (xy 70.871834 -302.00165) (xy 70.879729 -302.050227) (xy 70.880224 -302.074834)
			(xy 71.219072 -302.074834) (xy 71.223032 -302.02578) (xy 71.234809 -301.977996) (xy 71.2541 -301.93272)
			(xy 71.280403 -301.891124) (xy 71.313038 -301.854287) (xy 71.351159 -301.823162) (xy 71.39378 -301.798555)
			(xy 71.439796 -301.781103) (xy 71.488015 -301.771259) (xy 71.53719 -301.769278) (xy 71.586045 -301.77521)
			(xy 71.633316 -301.788902) (xy 71.677778 -301.81) (xy 71.718281 -301.837956) (xy 71.753774 -301.872048)
			(xy 71.783339 -301.911392) (xy 71.80621 -301.954969) (xy 71.821794 -302.00165) (xy 71.829689 -302.050227)
			(xy 71.830184 -302.074834) (xy 72.169032 -302.074834) (xy 72.172992 -302.02578) (xy 72.184769 -301.977996)
			(xy 72.20406 -301.93272) (xy 72.230363 -301.891124) (xy 72.262998 -301.854287) (xy 72.301119 -301.823162)
			(xy 72.34374 -301.798555) (xy 72.389756 -301.781103) (xy 72.437975 -301.771259) (xy 72.48715 -301.769278)
			(xy 72.536005 -301.77521) (xy 72.583276 -301.788902) (xy 72.627738 -301.81) (xy 72.668241 -301.837956)
			(xy 72.703734 -301.872048) (xy 72.733299 -301.911392) (xy 72.75617 -301.954969) (xy 72.771754 -302.00165)
			(xy 72.779649 -302.050227) (xy 72.780144 -302.074834) (xy 72.779978 -302.083068) (xy 73.119085 -302.083068)
			(xy 73.121775 -302.033499) (xy 73.132449 -301.985018) (xy 73.150826 -301.938902) (xy 73.176421 -301.896368)
			(xy 73.208561 -301.858534) (xy 73.246398 -301.826399) (xy 73.288936 -301.800809) (xy 73.335054 -301.782438)
			(xy 73.383536 -301.77177) (xy 73.433106 -301.769086) (xy 73.482456 -301.774457) (xy 73.530288 -301.787742)
			(xy 73.57534 -301.80859) (xy 73.616426 -301.836452) (xy 73.652462 -301.870594) (xy 73.682501 -301.910117)
			(xy 73.705749 -301.953979) (xy 73.721595 -302.001024) (xy 73.729621 -302.050013) (xy 73.730104 -302.074834)
			(xy 73.729932 -302.089017) (xy 73.727257 -302.117257) (xy 73.72477 -302.131222) (xy 73.722484 -302.143668)
			(xy 73.72985 -302.16729) (xy 73.80732 -302.24476) (xy 73.830942 -302.252126) (xy 73.843388 -302.24984)
			(xy 73.857355 -302.247369) (xy 73.885594 -302.244694) (xy 73.899776 -302.244506) (xy 73.913959 -302.244686)
			(xy 73.942199 -302.247356) (xy 73.956164 -302.24984) (xy 73.96861 -302.252126) (xy 73.992232 -302.24476)
			(xy 74.069702 -302.16729) (xy 74.077068 -302.143668) (xy 74.074782 -302.131222) (xy 74.072299 -302.117257)
			(xy 74.069631 -302.089017) (xy 74.069448 -302.074834) (xy 74.069941 -302.050009) (xy 74.077969 -302.001012)
			(xy 74.093818 -301.95396) (xy 74.11707 -301.910092) (xy 74.147114 -301.870563) (xy 74.183158 -301.836417)
			(xy 74.224251 -301.808551) (xy 74.269311 -301.787702) (xy 74.31715 -301.774417) (xy 74.366509 -301.769047)
			(xy 74.416086 -301.771734) (xy 74.464575 -301.782407) (xy 74.510699 -301.800784) (xy 74.553242 -301.826381)
			(xy 74.591083 -301.858524) (xy 74.623225 -301.896366) (xy 74.648821 -301.93891) (xy 74.667196 -301.985034)
			(xy 74.677867 -302.033524) (xy 74.680552 -302.083101) (xy 74.675181 -302.13246) (xy 74.661895 -302.180299)
			(xy 74.641044 -302.225358) (xy 74.613177 -302.26645) (xy 74.579029 -302.302492) (xy 74.5395 -302.332535)
			(xy 74.495631 -302.355786) (xy 74.448578 -302.371634) (xy 74.399581 -302.379659) (xy 74.374756 -302.380142)
			(xy 74.360573 -302.379957) (xy 74.332333 -302.37729) (xy 74.318368 -302.374808) (xy 74.305922 -302.372522)
			(xy 74.2823 -302.379888) (xy 74.20483 -302.457358) (xy 74.197464 -302.48098) (xy 74.19975 -302.493426)
			(xy 74.202226 -302.507392) (xy 74.204898 -302.535632) (xy 74.205084 -302.549814) (xy 74.204562 -302.575069)
			(xy 74.196249 -302.624891) (xy 74.179848 -302.672665) (xy 74.155807 -302.717088) (xy 74.124783 -302.756948)
			(xy 74.087621 -302.791158) (xy 74.045335 -302.818784) (xy 73.999079 -302.839074) (xy 73.950114 -302.851474)
			(xy 73.899776 -302.855645) (xy 73.849438 -302.851474) (xy 73.800473 -302.839074) (xy 73.754217 -302.818784)
			(xy 73.711931 -302.791158) (xy 73.674769 -302.756948) (xy 73.643745 -302.717088) (xy 73.619704 -302.672665)
			(xy 73.603303 -302.624891) (xy 73.59499 -302.575069) (xy 73.594468 -302.549814) (xy 73.594647 -302.535631)
			(xy 73.597318 -302.507391) (xy 73.599802 -302.493426) (xy 73.602088 -302.48098) (xy 73.594722 -302.457358)
			(xy 73.517252 -302.379888) (xy 73.49363 -302.372522) (xy 73.481184 -302.374808) (xy 73.467218 -302.377283)
			(xy 73.438978 -302.379956) (xy 73.424796 -302.380142) (xy 73.399975 -302.379618) (xy 73.350987 -302.371586)
			(xy 73.303944 -302.355734) (xy 73.260085 -302.33248) (xy 73.220566 -302.302437) (xy 73.186428 -302.266396)
			(xy 73.158571 -302.225307) (xy 73.137729 -302.180252) (xy 73.12445 -302.132419) (xy 73.119085 -302.083068)
			(xy 72.779978 -302.083068) (xy 72.779649 -302.099441) (xy 72.771754 -302.148018) (xy 72.75617 -302.194699)
			(xy 72.733299 -302.238276) (xy 72.703734 -302.27762) (xy 72.668241 -302.311712) (xy 72.627738 -302.339668)
			(xy 72.583276 -302.360766) (xy 72.536005 -302.374458) (xy 72.48715 -302.38039) (xy 72.437975 -302.378409)
			(xy 72.389756 -302.368565) (xy 72.34374 -302.351113) (xy 72.301119 -302.326506) (xy 72.262998 -302.295381)
			(xy 72.230363 -302.258544) (xy 72.20406 -302.216948) (xy 72.184769 -302.171672) (xy 72.172992 -302.123888)
			(xy 72.169032 -302.074834) (xy 71.830184 -302.074834) (xy 71.829689 -302.099441) (xy 71.821794 -302.148018)
			(xy 71.80621 -302.194699) (xy 71.783339 -302.238276) (xy 71.753774 -302.27762) (xy 71.718281 -302.311712)
			(xy 71.677778 -302.339668) (xy 71.633316 -302.360766) (xy 71.586045 -302.374458) (xy 71.53719 -302.38039)
			(xy 71.488015 -302.378409) (xy 71.439796 -302.368565) (xy 71.39378 -302.351113) (xy 71.351159 -302.326506)
			(xy 71.313038 -302.295381) (xy 71.280403 -302.258544) (xy 71.2541 -302.216948) (xy 71.234809 -302.171672)
			(xy 71.223032 -302.123888) (xy 71.219072 -302.074834) (xy 70.880224 -302.074834) (xy 70.879729 -302.099441)
			(xy 70.871834 -302.148018) (xy 70.85625 -302.194699) (xy 70.833379 -302.238276) (xy 70.803814 -302.27762)
			(xy 70.768321 -302.311712) (xy 70.727818 -302.339668) (xy 70.683356 -302.360766) (xy 70.636085 -302.374458)
			(xy 70.58723 -302.38039) (xy 70.538055 -302.378409) (xy 70.489836 -302.368565) (xy 70.44382 -302.351113)
			(xy 70.401199 -302.326506) (xy 70.363078 -302.295381) (xy 70.330443 -302.258544) (xy 70.30414 -302.216948)
			(xy 70.284849 -302.171672) (xy 70.273072 -302.123888) (xy 70.269112 -302.074834) (xy 69.930264 -302.074834)
			(xy 69.929769 -302.099441) (xy 69.921874 -302.148018) (xy 69.90629 -302.194699) (xy 69.883419 -302.238276)
			(xy 69.853854 -302.27762) (xy 69.818361 -302.311712) (xy 69.777858 -302.339668) (xy 69.733396 -302.360766)
			(xy 69.686125 -302.374458) (xy 69.63727 -302.38039) (xy 69.588095 -302.378409) (xy 69.539876 -302.368565)
			(xy 69.49386 -302.351113) (xy 69.451239 -302.326506) (xy 69.413118 -302.295381) (xy 69.380483 -302.258544)
			(xy 69.35418 -302.216948) (xy 69.334889 -302.171672) (xy 69.323112 -302.123888) (xy 69.319152 -302.074834)
			(xy 68.98005 -302.074834) (xy 68.979555 -302.099441) (xy 68.97166 -302.148018) (xy 68.956076 -302.194699)
			(xy 68.933205 -302.238276) (xy 68.90364 -302.27762) (xy 68.868147 -302.311712) (xy 68.827644 -302.339668)
			(xy 68.783182 -302.360766) (xy 68.735911 -302.374458) (xy 68.687056 -302.38039) (xy 68.637881 -302.378409)
			(xy 68.589662 -302.368565) (xy 68.543646 -302.351113) (xy 68.501025 -302.326506) (xy 68.462904 -302.295381)
			(xy 68.430269 -302.258544) (xy 68.403966 -302.216948) (xy 68.384675 -302.171672) (xy 68.372898 -302.123888)
			(xy 68.368938 -302.074834) (xy 68.03009 -302.074834) (xy 68.029595 -302.099441) (xy 68.0217 -302.148018)
			(xy 68.006116 -302.194699) (xy 67.983245 -302.238276) (xy 67.95368 -302.27762) (xy 67.918187 -302.311712)
			(xy 67.877684 -302.339668) (xy 67.833222 -302.360766) (xy 67.785951 -302.374458) (xy 67.737096 -302.38039)
			(xy 67.687921 -302.378409) (xy 67.639702 -302.368565) (xy 67.593686 -302.351113) (xy 67.551065 -302.326506)
			(xy 67.512944 -302.295381) (xy 67.480309 -302.258544) (xy 67.454006 -302.216948) (xy 67.434715 -302.171672)
			(xy 67.422938 -302.123888) (xy 67.418978 -302.074834) (xy 67.08013 -302.074834) (xy 67.079635 -302.099441)
			(xy 67.07174 -302.148018) (xy 67.056156 -302.194699) (xy 67.033285 -302.238276) (xy 67.00372 -302.27762)
			(xy 66.968227 -302.311712) (xy 66.927724 -302.339668) (xy 66.883262 -302.360766) (xy 66.835991 -302.374458)
			(xy 66.787136 -302.38039) (xy 66.737961 -302.378409) (xy 66.689742 -302.368565) (xy 66.643726 -302.351113)
			(xy 66.601105 -302.326506) (xy 66.562984 -302.295381) (xy 66.530349 -302.258544) (xy 66.504046 -302.216948)
			(xy 66.484755 -302.171672) (xy 66.472978 -302.123888) (xy 66.469018 -302.074834) (xy 66.13017 -302.074834)
			(xy 66.129675 -302.099441) (xy 66.12178 -302.148018) (xy 66.106196 -302.194699) (xy 66.083325 -302.238276)
			(xy 66.05376 -302.27762) (xy 66.018267 -302.311712) (xy 65.977764 -302.339668) (xy 65.933302 -302.360766)
			(xy 65.886031 -302.374458) (xy 65.837176 -302.38039) (xy 65.788001 -302.378409) (xy 65.739782 -302.368565)
			(xy 65.693766 -302.351113) (xy 65.651145 -302.326506) (xy 65.613024 -302.295381) (xy 65.580389 -302.258544)
			(xy 65.554086 -302.216948) (xy 65.534795 -302.171672) (xy 65.523018 -302.123888) (xy 65.519058 -302.074834)
			(xy 65.18021 -302.074834) (xy 65.179715 -302.099441) (xy 65.17182 -302.148018) (xy 65.156236 -302.194699)
			(xy 65.133365 -302.238276) (xy 65.1038 -302.27762) (xy 65.068307 -302.311712) (xy 65.027804 -302.339668)
			(xy 64.983342 -302.360766) (xy 64.936071 -302.374458) (xy 64.887216 -302.38039) (xy 64.838041 -302.378409)
			(xy 64.789822 -302.368565) (xy 64.743806 -302.351113) (xy 64.701185 -302.326506) (xy 64.663064 -302.295381)
			(xy 64.630429 -302.258544) (xy 64.604126 -302.216948) (xy 64.584835 -302.171672) (xy 64.573058 -302.123888)
			(xy 64.569098 -302.074834) (xy 64.23025 -302.074834) (xy 64.229755 -302.099441) (xy 64.22186 -302.148018)
			(xy 64.206276 -302.194699) (xy 64.183405 -302.238276) (xy 64.15384 -302.27762) (xy 64.118347 -302.311712)
			(xy 64.077844 -302.339668) (xy 64.033382 -302.360766) (xy 63.986111 -302.374458) (xy 63.937256 -302.38039)
			(xy 63.888081 -302.378409) (xy 63.839862 -302.368565) (xy 63.793846 -302.351113) (xy 63.751225 -302.326506)
			(xy 63.713104 -302.295381) (xy 63.680469 -302.258544) (xy 63.654166 -302.216948) (xy 63.634875 -302.171672)
			(xy 63.623098 -302.123888) (xy 63.619138 -302.074834) (xy 63.28029 -302.074834) (xy 63.279795 -302.099441)
			(xy 63.2719 -302.148018) (xy 63.256316 -302.194699) (xy 63.233445 -302.238276) (xy 63.20388 -302.27762)
			(xy 63.168387 -302.311712) (xy 63.127884 -302.339668) (xy 63.083422 -302.360766) (xy 63.036151 -302.374458)
			(xy 62.987296 -302.38039) (xy 62.938121 -302.378409) (xy 62.889902 -302.368565) (xy 62.843886 -302.351113)
			(xy 62.801265 -302.326506) (xy 62.763144 -302.295381) (xy 62.730509 -302.258544) (xy 62.704206 -302.216948)
			(xy 62.684915 -302.171672) (xy 62.673138 -302.123888) (xy 62.669178 -302.074834) (xy 62.330076 -302.074834)
			(xy 62.329581 -302.099441) (xy 62.321686 -302.148018) (xy 62.306102 -302.194699) (xy 62.283231 -302.238276)
			(xy 62.253666 -302.27762) (xy 62.218173 -302.311712) (xy 62.17767 -302.339668) (xy 62.133208 -302.360766)
			(xy 62.085937 -302.374458) (xy 62.037082 -302.38039) (xy 61.987907 -302.378409) (xy 61.939688 -302.368565)
			(xy 61.893672 -302.351113) (xy 61.851051 -302.326506) (xy 61.81293 -302.295381) (xy 61.780295 -302.258544)
			(xy 61.753992 -302.216948) (xy 61.734701 -302.171672) (xy 61.722924 -302.123888) (xy 61.718964 -302.074834)
			(xy 61.380116 -302.074834) (xy 61.379621 -302.099441) (xy 61.371726 -302.148018) (xy 61.356142 -302.194699)
			(xy 61.333271 -302.238276) (xy 61.303706 -302.27762) (xy 61.268213 -302.311712) (xy 61.22771 -302.339668)
			(xy 61.183248 -302.360766) (xy 61.135977 -302.374458) (xy 61.087122 -302.38039) (xy 61.037947 -302.378409)
			(xy 60.989728 -302.368565) (xy 60.943712 -302.351113) (xy 60.901091 -302.326506) (xy 60.86297 -302.295381)
			(xy 60.830335 -302.258544) (xy 60.804032 -302.216948) (xy 60.784741 -302.171672) (xy 60.772964 -302.123888)
			(xy 60.769004 -302.074834) (xy 60.430156 -302.074834) (xy 60.429661 -302.099441) (xy 60.421766 -302.148018)
			(xy 60.406182 -302.194699) (xy 60.383311 -302.238276) (xy 60.353746 -302.27762) (xy 60.318253 -302.311712)
			(xy 60.27775 -302.339668) (xy 60.233288 -302.360766) (xy 60.186017 -302.374458) (xy 60.137162 -302.38039)
			(xy 60.087987 -302.378409) (xy 60.039768 -302.368565) (xy 59.993752 -302.351113) (xy 59.951131 -302.326506)
			(xy 59.91301 -302.295381) (xy 59.880375 -302.258544) (xy 59.854072 -302.216948) (xy 59.834781 -302.171672)
			(xy 59.823004 -302.123888) (xy 59.819044 -302.074834) (xy 58.530236 -302.074834) (xy 58.529741 -302.099441)
			(xy 58.521846 -302.148018) (xy 58.506262 -302.194699) (xy 58.483391 -302.238276) (xy 58.453826 -302.27762)
			(xy 58.418333 -302.311712) (xy 58.37783 -302.339668) (xy 58.333368 -302.360766) (xy 58.286097 -302.374458)
			(xy 58.237242 -302.38039) (xy 58.188067 -302.378409) (xy 58.139848 -302.368565) (xy 58.093832 -302.351113)
			(xy 58.051211 -302.326506) (xy 58.01309 -302.295381) (xy 57.980455 -302.258544) (xy 57.954152 -302.216948)
			(xy 57.934861 -302.171672) (xy 57.923084 -302.123888) (xy 57.919124 -302.074834) (xy 57.580276 -302.074834)
			(xy 57.579781 -302.099441) (xy 57.571886 -302.148018) (xy 57.556302 -302.194699) (xy 57.533431 -302.238276)
			(xy 57.503866 -302.27762) (xy 57.468373 -302.311712) (xy 57.42787 -302.339668) (xy 57.383408 -302.360766)
			(xy 57.336137 -302.374458) (xy 57.287282 -302.38039) (xy 57.238107 -302.378409) (xy 57.189888 -302.368565)
			(xy 57.143872 -302.351113) (xy 57.101251 -302.326506) (xy 57.06313 -302.295381) (xy 57.030495 -302.258544)
			(xy 57.004192 -302.216948) (xy 56.984901 -302.171672) (xy 56.973124 -302.123888) (xy 56.969164 -302.074834)
			(xy 56.630062 -302.074834) (xy 56.629567 -302.099441) (xy 56.621672 -302.148018) (xy 56.606088 -302.194699)
			(xy 56.583217 -302.238276) (xy 56.553652 -302.27762) (xy 56.518159 -302.311712) (xy 56.477656 -302.339668)
			(xy 56.433194 -302.360766) (xy 56.385923 -302.374458) (xy 56.337068 -302.38039) (xy 56.287893 -302.378409)
			(xy 56.239674 -302.368565) (xy 56.193658 -302.351113) (xy 56.151037 -302.326506) (xy 56.112916 -302.295381)
			(xy 56.080281 -302.258544) (xy 56.053978 -302.216948) (xy 56.034687 -302.171672) (xy 56.02291 -302.123888)
			(xy 56.01895 -302.074834) (xy 55.680102 -302.074834) (xy 55.679607 -302.099441) (xy 55.671712 -302.148018)
			(xy 55.656128 -302.194699) (xy 55.633257 -302.238276) (xy 55.603692 -302.27762) (xy 55.568199 -302.311712)
			(xy 55.527696 -302.339668) (xy 55.483234 -302.360766) (xy 55.435963 -302.374458) (xy 55.387108 -302.38039)
			(xy 55.337933 -302.378409) (xy 55.289714 -302.368565) (xy 55.243698 -302.351113) (xy 55.201077 -302.326506)
			(xy 55.162956 -302.295381) (xy 55.130321 -302.258544) (xy 55.104018 -302.216948) (xy 55.084727 -302.171672)
			(xy 55.07295 -302.123888) (xy 55.06899 -302.074834) (xy 54.730142 -302.074834) (xy 54.729647 -302.099441)
			(xy 54.721752 -302.148018) (xy 54.706168 -302.194699) (xy 54.683297 -302.238276) (xy 54.653732 -302.27762)
			(xy 54.618239 -302.311712) (xy 54.577736 -302.339668) (xy 54.533274 -302.360766) (xy 54.486003 -302.374458)
			(xy 54.437148 -302.38039) (xy 54.387973 -302.378409) (xy 54.339754 -302.368565) (xy 54.293738 -302.351113)
			(xy 54.251117 -302.326506) (xy 54.212996 -302.295381) (xy 54.180361 -302.258544) (xy 54.154058 -302.216948)
			(xy 54.134767 -302.171672) (xy 54.12299 -302.123888) (xy 54.11903 -302.074834) (xy 53.780182 -302.074834)
			(xy 53.779687 -302.099441) (xy 53.771792 -302.148018) (xy 53.756208 -302.194699) (xy 53.733337 -302.238276)
			(xy 53.703772 -302.27762) (xy 53.668279 -302.311712) (xy 53.627776 -302.339668) (xy 53.583314 -302.360766)
			(xy 53.536043 -302.374458) (xy 53.487188 -302.38039) (xy 53.438013 -302.378409) (xy 53.389794 -302.368565)
			(xy 53.343778 -302.351113) (xy 53.301157 -302.326506) (xy 53.263036 -302.295381) (xy 53.230401 -302.258544)
			(xy 53.204098 -302.216948) (xy 53.184807 -302.171672) (xy 53.17303 -302.123888) (xy 53.16907 -302.074834)
			(xy 52.830222 -302.074834) (xy 52.829727 -302.099441) (xy 52.821832 -302.148018) (xy 52.806248 -302.194699)
			(xy 52.783377 -302.238276) (xy 52.753812 -302.27762) (xy 52.718319 -302.311712) (xy 52.677816 -302.339668)
			(xy 52.633354 -302.360766) (xy 52.586083 -302.374458) (xy 52.537228 -302.38039) (xy 52.488053 -302.378409)
			(xy 52.439834 -302.368565) (xy 52.393818 -302.351113) (xy 52.351197 -302.326506) (xy 52.313076 -302.295381)
			(xy 52.280441 -302.258544) (xy 52.254138 -302.216948) (xy 52.234847 -302.171672) (xy 52.22307 -302.123888)
			(xy 52.21911 -302.074834) (xy 51.880262 -302.074834) (xy 51.879767 -302.099441) (xy 51.871872 -302.148018)
			(xy 51.856288 -302.194699) (xy 51.833417 -302.238276) (xy 51.803852 -302.27762) (xy 51.768359 -302.311712)
			(xy 51.727856 -302.339668) (xy 51.683394 -302.360766) (xy 51.636123 -302.374458) (xy 51.587268 -302.38039)
			(xy 51.538093 -302.378409) (xy 51.489874 -302.368565) (xy 51.443858 -302.351113) (xy 51.401237 -302.326506)
			(xy 51.363116 -302.295381) (xy 51.330481 -302.258544) (xy 51.304178 -302.216948) (xy 51.284887 -302.171672)
			(xy 51.27311 -302.123888) (xy 51.26915 -302.074834) (xy 50.930302 -302.074834) (xy 50.929807 -302.099441)
			(xy 50.921912 -302.148018) (xy 50.906328 -302.194699) (xy 50.883457 -302.238276) (xy 50.853892 -302.27762)
			(xy 50.818399 -302.311712) (xy 50.777896 -302.339668) (xy 50.733434 -302.360766) (xy 50.686163 -302.374458)
			(xy 50.637308 -302.38039) (xy 50.588133 -302.378409) (xy 50.539914 -302.368565) (xy 50.493898 -302.351113)
			(xy 50.451277 -302.326506) (xy 50.413156 -302.295381) (xy 50.380521 -302.258544) (xy 50.354218 -302.216948)
			(xy 50.334927 -302.171672) (xy 50.32315 -302.123888) (xy 50.31919 -302.074834) (xy 49.980088 -302.074834)
			(xy 49.979593 -302.099441) (xy 49.971698 -302.148018) (xy 49.956114 -302.194699) (xy 49.933243 -302.238276)
			(xy 49.903678 -302.27762) (xy 49.868185 -302.311712) (xy 49.827682 -302.339668) (xy 49.78322 -302.360766)
			(xy 49.735949 -302.374458) (xy 49.687094 -302.38039) (xy 49.637919 -302.378409) (xy 49.5897 -302.368565)
			(xy 49.543684 -302.351113) (xy 49.501063 -302.326506) (xy 49.462942 -302.295381) (xy 49.430307 -302.258544)
			(xy 49.404004 -302.216948) (xy 49.384713 -302.171672) (xy 49.372936 -302.123888) (xy 49.368976 -302.074834)
			(xy 49.149254 -302.074834) (xy 49.149254 -303.024794) (xy 49.368976 -303.024794) (xy 49.372936 -302.97574)
			(xy 49.384713 -302.927956) (xy 49.404004 -302.88268) (xy 49.430307 -302.841084) (xy 49.462942 -302.804247)
			(xy 49.501063 -302.773122) (xy 49.543684 -302.748515) (xy 49.5897 -302.731063) (xy 49.637919 -302.721219)
			(xy 49.687094 -302.719238) (xy 49.735949 -302.72517) (xy 49.78322 -302.738862) (xy 49.827682 -302.75996)
			(xy 49.868185 -302.787916) (xy 49.903678 -302.822008) (xy 49.933243 -302.861352) (xy 49.956114 -302.904929)
			(xy 49.971698 -302.95161) (xy 49.979593 -303.000187) (xy 49.980088 -303.024794) (xy 50.31919 -303.024794)
			(xy 50.32315 -302.97574) (xy 50.334927 -302.927956) (xy 50.354218 -302.88268) (xy 50.380521 -302.841084)
			(xy 50.413156 -302.804247) (xy 50.451277 -302.773122) (xy 50.493898 -302.748515) (xy 50.539914 -302.731063)
			(xy 50.588133 -302.721219) (xy 50.637308 -302.719238) (xy 50.686163 -302.72517) (xy 50.733434 -302.738862)
			(xy 50.777896 -302.75996) (xy 50.818399 -302.787916) (xy 50.853892 -302.822008) (xy 50.883457 -302.861352)
			(xy 50.906328 -302.904929) (xy 50.921912 -302.95161) (xy 50.929807 -303.000187) (xy 50.930302 -303.024794)
			(xy 51.26915 -303.024794) (xy 51.27311 -302.97574) (xy 51.284887 -302.927956) (xy 51.304178 -302.88268)
			(xy 51.330481 -302.841084) (xy 51.363116 -302.804247) (xy 51.401237 -302.773122) (xy 51.443858 -302.748515)
			(xy 51.489874 -302.731063) (xy 51.538093 -302.721219) (xy 51.587268 -302.719238) (xy 51.636123 -302.72517)
			(xy 51.683394 -302.738862) (xy 51.727856 -302.75996) (xy 51.768359 -302.787916) (xy 51.803852 -302.822008)
			(xy 51.833417 -302.861352) (xy 51.856288 -302.904929) (xy 51.871872 -302.95161) (xy 51.879767 -303.000187)
			(xy 51.880262 -303.024794) (xy 52.21911 -303.024794) (xy 52.22307 -302.97574) (xy 52.234847 -302.927956)
			(xy 52.254138 -302.88268) (xy 52.280441 -302.841084) (xy 52.313076 -302.804247) (xy 52.351197 -302.773122)
			(xy 52.393818 -302.748515) (xy 52.439834 -302.731063) (xy 52.488053 -302.721219) (xy 52.537228 -302.719238)
			(xy 52.586083 -302.72517) (xy 52.633354 -302.738862) (xy 52.677816 -302.75996) (xy 52.718319 -302.787916)
			(xy 52.753812 -302.822008) (xy 52.783377 -302.861352) (xy 52.806248 -302.904929) (xy 52.821832 -302.95161)
			(xy 52.829727 -303.000187) (xy 52.830222 -303.024794) (xy 53.16907 -303.024794) (xy 53.17303 -302.97574)
			(xy 53.184807 -302.927956) (xy 53.204098 -302.88268) (xy 53.230401 -302.841084) (xy 53.263036 -302.804247)
			(xy 53.301157 -302.773122) (xy 53.343778 -302.748515) (xy 53.389794 -302.731063) (xy 53.438013 -302.721219)
			(xy 53.487188 -302.719238) (xy 53.536043 -302.72517) (xy 53.583314 -302.738862) (xy 53.627776 -302.75996)
			(xy 53.668279 -302.787916) (xy 53.703772 -302.822008) (xy 53.733337 -302.861352) (xy 53.756208 -302.904929)
			(xy 53.771792 -302.95161) (xy 53.779687 -303.000187) (xy 53.780182 -303.024794) (xy 54.11903 -303.024794)
			(xy 54.12299 -302.97574) (xy 54.134767 -302.927956) (xy 54.154058 -302.88268) (xy 54.180361 -302.841084)
			(xy 54.212996 -302.804247) (xy 54.251117 -302.773122) (xy 54.293738 -302.748515) (xy 54.339754 -302.731063)
			(xy 54.387973 -302.721219) (xy 54.437148 -302.719238) (xy 54.486003 -302.72517) (xy 54.533274 -302.738862)
			(xy 54.577736 -302.75996) (xy 54.618239 -302.787916) (xy 54.653732 -302.822008) (xy 54.683297 -302.861352)
			(xy 54.706168 -302.904929) (xy 54.721752 -302.95161) (xy 54.729647 -303.000187) (xy 54.730142 -303.024794)
			(xy 55.06899 -303.024794) (xy 55.07295 -302.97574) (xy 55.084727 -302.927956) (xy 55.104018 -302.88268)
			(xy 55.130321 -302.841084) (xy 55.162956 -302.804247) (xy 55.201077 -302.773122) (xy 55.243698 -302.748515)
			(xy 55.289714 -302.731063) (xy 55.337933 -302.721219) (xy 55.387108 -302.719238) (xy 55.435963 -302.72517)
			(xy 55.483234 -302.738862) (xy 55.527696 -302.75996) (xy 55.568199 -302.787916) (xy 55.603692 -302.822008)
			(xy 55.633257 -302.861352) (xy 55.656128 -302.904929) (xy 55.671712 -302.95161) (xy 55.679607 -303.000187)
			(xy 55.680102 -303.024794) (xy 56.01895 -303.024794) (xy 56.02291 -302.97574) (xy 56.034687 -302.927956)
			(xy 56.053978 -302.88268) (xy 56.080281 -302.841084) (xy 56.112916 -302.804247) (xy 56.151037 -302.773122)
			(xy 56.193658 -302.748515) (xy 56.239674 -302.731063) (xy 56.287893 -302.721219) (xy 56.337068 -302.719238)
			(xy 56.385923 -302.72517) (xy 56.433194 -302.738862) (xy 56.477656 -302.75996) (xy 56.518159 -302.787916)
			(xy 56.553652 -302.822008) (xy 56.583217 -302.861352) (xy 56.606088 -302.904929) (xy 56.621672 -302.95161)
			(xy 56.629567 -303.000187) (xy 56.630062 -303.024794) (xy 56.969164 -303.024794) (xy 56.973124 -302.97574)
			(xy 56.984901 -302.927956) (xy 57.004192 -302.88268) (xy 57.030495 -302.841084) (xy 57.06313 -302.804247)
			(xy 57.101251 -302.773122) (xy 57.143872 -302.748515) (xy 57.189888 -302.731063) (xy 57.238107 -302.721219)
			(xy 57.287282 -302.719238) (xy 57.336137 -302.72517) (xy 57.383408 -302.738862) (xy 57.42787 -302.75996)
			(xy 57.468373 -302.787916) (xy 57.503866 -302.822008) (xy 57.533431 -302.861352) (xy 57.556302 -302.904929)
			(xy 57.571886 -302.95161) (xy 57.579781 -303.000187) (xy 57.580276 -303.024794) (xy 57.919124 -303.024794)
			(xy 57.923084 -302.97574) (xy 57.934861 -302.927956) (xy 57.954152 -302.88268) (xy 57.980455 -302.841084)
			(xy 58.01309 -302.804247) (xy 58.051211 -302.773122) (xy 58.093832 -302.748515) (xy 58.139848 -302.731063)
			(xy 58.188067 -302.721219) (xy 58.237242 -302.719238) (xy 58.286097 -302.72517) (xy 58.333368 -302.738862)
			(xy 58.37783 -302.75996) (xy 58.418333 -302.787916) (xy 58.453826 -302.822008) (xy 58.483391 -302.861352)
			(xy 58.506262 -302.904929) (xy 58.521846 -302.95161) (xy 58.529741 -303.000187) (xy 58.530236 -303.024794)
			(xy 59.819044 -303.024794) (xy 59.823004 -302.97574) (xy 59.834781 -302.927956) (xy 59.854072 -302.88268)
			(xy 59.880375 -302.841084) (xy 59.91301 -302.804247) (xy 59.951131 -302.773122) (xy 59.993752 -302.748515)
			(xy 60.039768 -302.731063) (xy 60.087987 -302.721219) (xy 60.137162 -302.719238) (xy 60.186017 -302.72517)
			(xy 60.233288 -302.738862) (xy 60.27775 -302.75996) (xy 60.318253 -302.787916) (xy 60.353746 -302.822008)
			(xy 60.383311 -302.861352) (xy 60.406182 -302.904929) (xy 60.421766 -302.95161) (xy 60.429661 -303.000187)
			(xy 60.430156 -303.024794) (xy 60.769004 -303.024794) (xy 60.772964 -302.97574) (xy 60.784741 -302.927956)
			(xy 60.804032 -302.88268) (xy 60.830335 -302.841084) (xy 60.86297 -302.804247) (xy 60.901091 -302.773122)
			(xy 60.943712 -302.748515) (xy 60.989728 -302.731063) (xy 61.037947 -302.721219) (xy 61.087122 -302.719238)
			(xy 61.135977 -302.72517) (xy 61.183248 -302.738862) (xy 61.22771 -302.75996) (xy 61.268213 -302.787916)
			(xy 61.303706 -302.822008) (xy 61.333271 -302.861352) (xy 61.356142 -302.904929) (xy 61.371726 -302.95161)
			(xy 61.379621 -303.000187) (xy 61.380116 -303.024794) (xy 61.718964 -303.024794) (xy 61.722924 -302.97574)
			(xy 61.734701 -302.927956) (xy 61.753992 -302.88268) (xy 61.780295 -302.841084) (xy 61.81293 -302.804247)
			(xy 61.851051 -302.773122) (xy 61.893672 -302.748515) (xy 61.939688 -302.731063) (xy 61.987907 -302.721219)
			(xy 62.037082 -302.719238) (xy 62.085937 -302.72517) (xy 62.133208 -302.738862) (xy 62.17767 -302.75996)
			(xy 62.218173 -302.787916) (xy 62.253666 -302.822008) (xy 62.283231 -302.861352) (xy 62.306102 -302.904929)
			(xy 62.321686 -302.95161) (xy 62.329581 -303.000187) (xy 62.330076 -303.024794) (xy 62.669178 -303.024794)
			(xy 62.673138 -302.97574) (xy 62.684915 -302.927956) (xy 62.704206 -302.88268) (xy 62.730509 -302.841084)
			(xy 62.763144 -302.804247) (xy 62.801265 -302.773122) (xy 62.843886 -302.748515) (xy 62.889902 -302.731063)
			(xy 62.938121 -302.721219) (xy 62.987296 -302.719238) (xy 63.036151 -302.72517) (xy 63.083422 -302.738862)
			(xy 63.127884 -302.75996) (xy 63.168387 -302.787916) (xy 63.20388 -302.822008) (xy 63.233445 -302.861352)
			(xy 63.256316 -302.904929) (xy 63.2719 -302.95161) (xy 63.279795 -303.000187) (xy 63.28029 -303.024794)
			(xy 63.619138 -303.024794) (xy 63.623098 -302.97574) (xy 63.634875 -302.927956) (xy 63.654166 -302.88268)
			(xy 63.680469 -302.841084) (xy 63.713104 -302.804247) (xy 63.751225 -302.773122) (xy 63.793846 -302.748515)
			(xy 63.839862 -302.731063) (xy 63.888081 -302.721219) (xy 63.937256 -302.719238) (xy 63.986111 -302.72517)
			(xy 64.033382 -302.738862) (xy 64.077844 -302.75996) (xy 64.118347 -302.787916) (xy 64.15384 -302.822008)
			(xy 64.183405 -302.861352) (xy 64.206276 -302.904929) (xy 64.22186 -302.95161) (xy 64.229755 -303.000187)
			(xy 64.23025 -303.024794) (xy 64.569098 -303.024794) (xy 64.573058 -302.97574) (xy 64.584835 -302.927956)
			(xy 64.604126 -302.88268) (xy 64.630429 -302.841084) (xy 64.663064 -302.804247) (xy 64.701185 -302.773122)
			(xy 64.743806 -302.748515) (xy 64.789822 -302.731063) (xy 64.838041 -302.721219) (xy 64.887216 -302.719238)
			(xy 64.936071 -302.72517) (xy 64.983342 -302.738862) (xy 65.027804 -302.75996) (xy 65.068307 -302.787916)
			(xy 65.1038 -302.822008) (xy 65.133365 -302.861352) (xy 65.156236 -302.904929) (xy 65.17182 -302.95161)
			(xy 65.179715 -303.000187) (xy 65.18021 -303.024794) (xy 65.519058 -303.024794) (xy 65.523018 -302.97574)
			(xy 65.534795 -302.927956) (xy 65.554086 -302.88268) (xy 65.580389 -302.841084) (xy 65.613024 -302.804247)
			(xy 65.651145 -302.773122) (xy 65.693766 -302.748515) (xy 65.739782 -302.731063) (xy 65.788001 -302.721219)
			(xy 65.837176 -302.719238) (xy 65.886031 -302.72517) (xy 65.933302 -302.738862) (xy 65.977764 -302.75996)
			(xy 66.018267 -302.787916) (xy 66.05376 -302.822008) (xy 66.083325 -302.861352) (xy 66.106196 -302.904929)
			(xy 66.12178 -302.95161) (xy 66.129675 -303.000187) (xy 66.13017 -303.024794) (xy 66.469018 -303.024794)
			(xy 66.472978 -302.97574) (xy 66.484755 -302.927956) (xy 66.504046 -302.88268) (xy 66.530349 -302.841084)
			(xy 66.562984 -302.804247) (xy 66.601105 -302.773122) (xy 66.643726 -302.748515) (xy 66.689742 -302.731063)
			(xy 66.737961 -302.721219) (xy 66.787136 -302.719238) (xy 66.835991 -302.72517) (xy 66.883262 -302.738862)
			(xy 66.927724 -302.75996) (xy 66.968227 -302.787916) (xy 67.00372 -302.822008) (xy 67.033285 -302.861352)
			(xy 67.056156 -302.904929) (xy 67.07174 -302.95161) (xy 67.079635 -303.000187) (xy 67.08013 -303.024794)
			(xy 67.418978 -303.024794) (xy 67.422938 -302.97574) (xy 67.434715 -302.927956) (xy 67.454006 -302.88268)
			(xy 67.480309 -302.841084) (xy 67.512944 -302.804247) (xy 67.551065 -302.773122) (xy 67.593686 -302.748515)
			(xy 67.639702 -302.731063) (xy 67.687921 -302.721219) (xy 67.737096 -302.719238) (xy 67.785951 -302.72517)
			(xy 67.833222 -302.738862) (xy 67.877684 -302.75996) (xy 67.918187 -302.787916) (xy 67.95368 -302.822008)
			(xy 67.983245 -302.861352) (xy 68.006116 -302.904929) (xy 68.0217 -302.95161) (xy 68.029595 -303.000187)
			(xy 68.03009 -303.024794) (xy 68.368938 -303.024794) (xy 68.372898 -302.97574) (xy 68.384675 -302.927956)
			(xy 68.403966 -302.88268) (xy 68.430269 -302.841084) (xy 68.462904 -302.804247) (xy 68.501025 -302.773122)
			(xy 68.543646 -302.748515) (xy 68.589662 -302.731063) (xy 68.637881 -302.721219) (xy 68.687056 -302.719238)
			(xy 68.735911 -302.72517) (xy 68.783182 -302.738862) (xy 68.827644 -302.75996) (xy 68.868147 -302.787916)
			(xy 68.90364 -302.822008) (xy 68.933205 -302.861352) (xy 68.956076 -302.904929) (xy 68.97166 -302.95161)
			(xy 68.979555 -303.000187) (xy 68.98005 -303.024794) (xy 69.319152 -303.024794) (xy 69.323112 -302.97574)
			(xy 69.334889 -302.927956) (xy 69.35418 -302.88268) (xy 69.380483 -302.841084) (xy 69.413118 -302.804247)
			(xy 69.451239 -302.773122) (xy 69.49386 -302.748515) (xy 69.539876 -302.731063) (xy 69.588095 -302.721219)
			(xy 69.63727 -302.719238) (xy 69.686125 -302.72517) (xy 69.733396 -302.738862) (xy 69.777858 -302.75996)
			(xy 69.818361 -302.787916) (xy 69.853854 -302.822008) (xy 69.883419 -302.861352) (xy 69.90629 -302.904929)
			(xy 69.921874 -302.95161) (xy 69.929769 -303.000187) (xy 69.930264 -303.024794) (xy 70.269112 -303.024794)
			(xy 70.273072 -302.97574) (xy 70.284849 -302.927956) (xy 70.30414 -302.88268) (xy 70.330443 -302.841084)
			(xy 70.363078 -302.804247) (xy 70.401199 -302.773122) (xy 70.44382 -302.748515) (xy 70.489836 -302.731063)
			(xy 70.538055 -302.721219) (xy 70.58723 -302.719238) (xy 70.636085 -302.72517) (xy 70.683356 -302.738862)
			(xy 70.727818 -302.75996) (xy 70.768321 -302.787916) (xy 70.803814 -302.822008) (xy 70.833379 -302.861352)
			(xy 70.85625 -302.904929) (xy 70.871834 -302.95161) (xy 70.879729 -303.000187) (xy 70.880224 -303.024794)
			(xy 71.219072 -303.024794) (xy 71.223032 -302.97574) (xy 71.234809 -302.927956) (xy 71.2541 -302.88268)
			(xy 71.280403 -302.841084) (xy 71.313038 -302.804247) (xy 71.351159 -302.773122) (xy 71.39378 -302.748515)
			(xy 71.439796 -302.731063) (xy 71.488015 -302.721219) (xy 71.53719 -302.719238) (xy 71.586045 -302.72517)
			(xy 71.633316 -302.738862) (xy 71.677778 -302.75996) (xy 71.718281 -302.787916) (xy 71.753774 -302.822008)
			(xy 71.783339 -302.861352) (xy 71.80621 -302.904929) (xy 71.821794 -302.95161) (xy 71.829689 -303.000187)
			(xy 71.830184 -303.024794) (xy 72.169032 -303.024794) (xy 72.172992 -302.97574) (xy 72.184769 -302.927956)
			(xy 72.20406 -302.88268) (xy 72.230363 -302.841084) (xy 72.262998 -302.804247) (xy 72.301119 -302.773122)
			(xy 72.34374 -302.748515) (xy 72.389756 -302.731063) (xy 72.437975 -302.721219) (xy 72.48715 -302.719238)
			(xy 72.536005 -302.72517) (xy 72.583276 -302.738862) (xy 72.627738 -302.75996) (xy 72.668241 -302.787916)
			(xy 72.703734 -302.822008) (xy 72.733299 -302.861352) (xy 72.75617 -302.904929) (xy 72.771754 -302.95161)
			(xy 72.779649 -303.000187) (xy 72.780144 -303.024794) (xy 76.919086 -303.024794) (xy 76.923046 -302.97574)
			(xy 76.934823 -302.927956) (xy 76.954114 -302.88268) (xy 76.980417 -302.841084) (xy 77.013052 -302.804247)
			(xy 77.051173 -302.773122) (xy 77.093794 -302.748515) (xy 77.13981 -302.731063) (xy 77.188029 -302.721219)
			(xy 77.237204 -302.719238) (xy 77.286059 -302.72517) (xy 77.33333 -302.738862) (xy 77.377792 -302.75996)
			(xy 77.418295 -302.787916) (xy 77.453788 -302.822008) (xy 77.483353 -302.861352) (xy 77.506224 -302.904929)
			(xy 77.521808 -302.95161) (xy 77.529703 -303.000187) (xy 77.530198 -303.024794) (xy 77.869046 -303.024794)
			(xy 77.873006 -302.97574) (xy 77.884783 -302.927956) (xy 77.904074 -302.88268) (xy 77.930377 -302.841084)
			(xy 77.963012 -302.804247) (xy 78.001133 -302.773122) (xy 78.043754 -302.748515) (xy 78.08977 -302.731063)
			(xy 78.137989 -302.721219) (xy 78.187164 -302.719238) (xy 78.236019 -302.72517) (xy 78.28329 -302.738862)
			(xy 78.327752 -302.75996) (xy 78.368255 -302.787916) (xy 78.403748 -302.822008) (xy 78.433313 -302.861352)
			(xy 78.456184 -302.904929) (xy 78.471768 -302.95161) (xy 78.479663 -303.000187) (xy 78.480158 -303.024794)
			(xy 78.819006 -303.024794) (xy 78.822966 -302.97574) (xy 78.834743 -302.927956) (xy 78.854034 -302.88268)
			(xy 78.880337 -302.841084) (xy 78.912972 -302.804247) (xy 78.951093 -302.773122) (xy 78.993714 -302.748515)
			(xy 79.03973 -302.731063) (xy 79.087949 -302.721219) (xy 79.137124 -302.719238) (xy 79.185979 -302.72517)
			(xy 79.23325 -302.738862) (xy 79.277712 -302.75996) (xy 79.318215 -302.787916) (xy 79.353708 -302.822008)
			(xy 79.383273 -302.861352) (xy 79.406144 -302.904929) (xy 79.421728 -302.95161) (xy 79.429623 -303.000187)
			(xy 79.430118 -303.024794) (xy 79.768966 -303.024794) (xy 79.772926 -302.97574) (xy 79.784703 -302.927956)
			(xy 79.803994 -302.88268) (xy 79.830297 -302.841084) (xy 79.862932 -302.804247) (xy 79.901053 -302.773122)
			(xy 79.943674 -302.748515) (xy 79.98969 -302.731063) (xy 80.037909 -302.721219) (xy 80.087084 -302.719238)
			(xy 80.135939 -302.72517) (xy 80.18321 -302.738862) (xy 80.227672 -302.75996) (xy 80.268175 -302.787916)
			(xy 80.303668 -302.822008) (xy 80.333233 -302.861352) (xy 80.356104 -302.904929) (xy 80.371688 -302.95161)
			(xy 80.379583 -303.000187) (xy 80.380078 -303.024794) (xy 80.71918 -303.024794) (xy 80.72314 -302.97574)
			(xy 80.734917 -302.927956) (xy 80.754208 -302.88268) (xy 80.780511 -302.841084) (xy 80.813146 -302.804247)
			(xy 80.851267 -302.773122) (xy 80.893888 -302.748515) (xy 80.939904 -302.731063) (xy 80.988123 -302.721219)
			(xy 81.037298 -302.719238) (xy 81.086153 -302.72517) (xy 81.133424 -302.738862) (xy 81.177886 -302.75996)
			(xy 81.218389 -302.787916) (xy 81.253882 -302.822008) (xy 81.283447 -302.861352) (xy 81.306318 -302.904929)
			(xy 81.321902 -302.95161) (xy 81.329797 -303.000187) (xy 81.330292 -303.024794) (xy 81.66914 -303.024794)
			(xy 81.6731 -302.97574) (xy 81.684877 -302.927956) (xy 81.704168 -302.88268) (xy 81.730471 -302.841084)
			(xy 81.763106 -302.804247) (xy 81.801227 -302.773122) (xy 81.843848 -302.748515) (xy 81.889864 -302.731063)
			(xy 81.938083 -302.721219) (xy 81.987258 -302.719238) (xy 82.036113 -302.72517) (xy 82.083384 -302.738862)
			(xy 82.127846 -302.75996) (xy 82.168349 -302.787916) (xy 82.203842 -302.822008) (xy 82.233407 -302.861352)
			(xy 82.256278 -302.904929) (xy 82.271862 -302.95161) (xy 82.279757 -303.000187) (xy 82.280252 -303.024794)
			(xy 82.60386 -303.024794) (xy 82.60782 -302.97574) (xy 82.619597 -302.927956) (xy 82.638888 -302.88268)
			(xy 82.665191 -302.841084) (xy 82.697826 -302.804247) (xy 82.735947 -302.773122) (xy 82.778568 -302.748515)
			(xy 82.824584 -302.731063) (xy 82.872803 -302.721219) (xy 82.921978 -302.719238) (xy 82.970833 -302.72517)
			(xy 83.018104 -302.738862) (xy 83.062566 -302.75996) (xy 83.103069 -302.787916) (xy 83.138562 -302.822008)
			(xy 83.168127 -302.861352) (xy 83.190998 -302.904929) (xy 83.206582 -302.95161) (xy 83.210441 -302.975356)
			(xy 90.372341 -302.975356) (xy 90.372341 -302.920844) (xy 90.380099 -302.866888) (xy 90.395458 -302.814585)
			(xy 90.418104 -302.765001) (xy 90.447577 -302.719144) (xy 90.483276 -302.677949) (xy 90.524474 -302.642254)
			(xy 90.570334 -302.612786) (xy 90.619921 -302.590144) (xy 90.672225 -302.574791) (xy 90.726182 -302.567038)
			(xy 90.753438 -302.566578) (xy 90.781901 -302.567128) (xy 90.838198 -302.575574) (xy 90.892616 -302.592287)
			(xy 90.943949 -302.616897) (xy 90.991056 -302.648858) (xy 91.032895 -302.687461) (xy 91.051126 -302.709326)
			(xy 91.060886 -302.72061) (xy 91.08546 -302.737501) (xy 91.113865 -302.746574) (xy 91.143679 -302.747054)
			(xy 91.172362 -302.738902) (xy 91.197467 -302.722812) (xy 91.216854 -302.700155) (xy 91.223338 -302.68672)
			(xy 91.234826 -302.661582) (xy 91.264054 -302.614673) (xy 91.299745 -302.572473) (xy 91.341152 -302.535864)
			(xy 91.387408 -302.505615) (xy 91.437546 -302.482357) (xy 91.490515 -302.466578) (xy 91.545207 -302.458608)
			(xy 91.572842 -302.45812) (xy 91.600093 -302.458553) (xy 91.65404 -302.466315) (xy 91.706334 -302.481675)
			(xy 91.75591 -302.50432) (xy 91.801758 -302.533789) (xy 91.842946 -302.569483) (xy 91.878636 -302.610676)
			(xy 91.9081 -302.656527) (xy 91.93074 -302.706105) (xy 91.946094 -302.758401) (xy 91.95385 -302.812349)
			(xy 91.95385 -302.866851) (xy 91.946094 -302.920799) (xy 91.93074 -302.973095) (xy 91.9081 -303.022673)
			(xy 91.878636 -303.068524) (xy 91.842946 -303.109717) (xy 91.806116 -303.141634) (xy 116.784372 -303.141634)
			(xy 116.788443 -303.086012) (xy 116.800569 -303.031575) (xy 116.820492 -302.979484) (xy 116.847788 -302.930849)
			(xy 116.881874 -302.886706) (xy 116.922023 -302.847997) (xy 116.967381 -302.815546) (xy 117.016981 -302.790045)
			(xy 117.069765 -302.772038) (xy 117.124608 -302.761908) (xy 117.180342 -302.759871) (xy 117.235779 -302.765971)
			(xy 117.289736 -302.780077) (xy 117.341065 -302.801889) (xy 117.388671 -302.830943) (xy 117.431539 -302.866618)
			(xy 117.468756 -302.908155) (xy 117.499529 -302.954668) (xy 117.523201 -303.005165) (xy 117.539269 -303.058572)
			(xy 117.547389 -303.113748) (xy 117.547898 -303.141634) (xy 117.547389 -303.16952) (xy 117.539269 -303.224696)
			(xy 117.523201 -303.278103) (xy 117.499529 -303.3286) (xy 117.468756 -303.375113) (xy 117.431539 -303.41665)
			(xy 117.388671 -303.452325) (xy 117.341065 -303.481379) (xy 117.289736 -303.503191) (xy 117.235779 -303.517297)
			(xy 117.180342 -303.523397) (xy 117.124608 -303.52136) (xy 117.069765 -303.51123) (xy 117.016981 -303.493223)
			(xy 116.967381 -303.467722) (xy 116.922023 -303.435271) (xy 116.881874 -303.396562) (xy 116.847788 -303.352419)
			(xy 116.820492 -303.303784) (xy 116.800569 -303.251693) (xy 116.788443 -303.197256) (xy 116.784372 -303.141634)
			(xy 91.806116 -303.141634) (xy 91.801758 -303.145411) (xy 91.75591 -303.17488) (xy 91.706334 -303.197525)
			(xy 91.65404 -303.212885) (xy 91.600093 -303.220647) (xy 91.572842 -303.221136) (xy 91.544378 -303.220595)
			(xy 91.488081 -303.212146) (xy 91.433663 -303.195431) (xy 91.382331 -303.170819) (xy 91.335224 -303.138857)
			(xy 91.293385 -303.100253) (xy 91.275154 -303.078388) (xy 91.26542 -303.067078) (xy 91.240841 -303.050185)
			(xy 91.212429 -303.041113) (xy 91.182608 -303.040635) (xy 91.15392 -303.048793) (xy 91.128812 -303.06489)
			(xy 91.109425 -303.087554) (xy 91.102942 -303.100994) (xy 91.091476 -303.126143) (xy 91.062245 -303.173052)
			(xy 91.026551 -303.215252) (xy 90.985141 -303.251859) (xy 90.938881 -303.282108) (xy 90.88874 -303.305364)
			(xy 90.835768 -303.32114) (xy 90.781074 -303.329108) (xy 90.753438 -303.329594) (xy 90.726182 -303.329162)
			(xy 90.672225 -303.321409) (xy 90.619921 -303.306056) (xy 90.570334 -303.283414) (xy 90.524474 -303.253946)
			(xy 90.483276 -303.218251) (xy 90.447577 -303.177056) (xy 90.418104 -303.131199) (xy 90.395458 -303.081615)
			(xy 90.380099 -303.029312) (xy 90.372341 -302.975356) (xy 83.210441 -302.975356) (xy 83.214477 -303.000187)
			(xy 83.214972 -303.024794) (xy 83.214477 -303.049401) (xy 83.206582 -303.097978) (xy 83.190998 -303.144659)
			(xy 83.168127 -303.188236) (xy 83.138562 -303.22758) (xy 83.103069 -303.261672) (xy 83.062566 -303.289628)
			(xy 83.018104 -303.310726) (xy 82.970833 -303.324418) (xy 82.921978 -303.33035) (xy 82.872803 -303.328369)
			(xy 82.824584 -303.318525) (xy 82.778568 -303.301073) (xy 82.735947 -303.276466) (xy 82.697826 -303.245341)
			(xy 82.665191 -303.208504) (xy 82.638888 -303.166908) (xy 82.619597 -303.121632) (xy 82.60782 -303.073848)
			(xy 82.60386 -303.024794) (xy 82.280252 -303.024794) (xy 82.279757 -303.049401) (xy 82.271862 -303.097978)
			(xy 82.256278 -303.144659) (xy 82.233407 -303.188236) (xy 82.203842 -303.22758) (xy 82.168349 -303.261672)
			(xy 82.127846 -303.289628) (xy 82.083384 -303.310726) (xy 82.036113 -303.324418) (xy 81.987258 -303.33035)
			(xy 81.938083 -303.328369) (xy 81.889864 -303.318525) (xy 81.843848 -303.301073) (xy 81.801227 -303.276466)
			(xy 81.763106 -303.245341) (xy 81.730471 -303.208504) (xy 81.704168 -303.166908) (xy 81.684877 -303.121632)
			(xy 81.6731 -303.073848) (xy 81.66914 -303.024794) (xy 81.330292 -303.024794) (xy 81.329797 -303.049401)
			(xy 81.321902 -303.097978) (xy 81.306318 -303.144659) (xy 81.283447 -303.188236) (xy 81.253882 -303.22758)
			(xy 81.218389 -303.261672) (xy 81.177886 -303.289628) (xy 81.133424 -303.310726) (xy 81.086153 -303.324418)
			(xy 81.037298 -303.33035) (xy 80.988123 -303.328369) (xy 80.939904 -303.318525) (xy 80.893888 -303.301073)
			(xy 80.851267 -303.276466) (xy 80.813146 -303.245341) (xy 80.780511 -303.208504) (xy 80.754208 -303.166908)
			(xy 80.734917 -303.121632) (xy 80.72314 -303.073848) (xy 80.71918 -303.024794) (xy 80.380078 -303.024794)
			(xy 80.379583 -303.049401) (xy 80.371688 -303.097978) (xy 80.356104 -303.144659) (xy 80.333233 -303.188236)
			(xy 80.303668 -303.22758) (xy 80.268175 -303.261672) (xy 80.227672 -303.289628) (xy 80.18321 -303.310726)
			(xy 80.135939 -303.324418) (xy 80.087084 -303.33035) (xy 80.037909 -303.328369) (xy 79.98969 -303.318525)
			(xy 79.943674 -303.301073) (xy 79.901053 -303.276466) (xy 79.862932 -303.245341) (xy 79.830297 -303.208504)
			(xy 79.803994 -303.166908) (xy 79.784703 -303.121632) (xy 79.772926 -303.073848) (xy 79.768966 -303.024794)
			(xy 79.430118 -303.024794) (xy 79.429623 -303.049401) (xy 79.421728 -303.097978) (xy 79.406144 -303.144659)
			(xy 79.383273 -303.188236) (xy 79.353708 -303.22758) (xy 79.318215 -303.261672) (xy 79.277712 -303.289628)
			(xy 79.23325 -303.310726) (xy 79.185979 -303.324418) (xy 79.137124 -303.33035) (xy 79.087949 -303.328369)
			(xy 79.03973 -303.318525) (xy 78.993714 -303.301073) (xy 78.951093 -303.276466) (xy 78.912972 -303.245341)
			(xy 78.880337 -303.208504) (xy 78.854034 -303.166908) (xy 78.834743 -303.121632) (xy 78.822966 -303.073848)
			(xy 78.819006 -303.024794) (xy 78.480158 -303.024794) (xy 78.479663 -303.049401) (xy 78.471768 -303.097978)
			(xy 78.456184 -303.144659) (xy 78.433313 -303.188236) (xy 78.403748 -303.22758) (xy 78.368255 -303.261672)
			(xy 78.327752 -303.289628) (xy 78.28329 -303.310726) (xy 78.236019 -303.324418) (xy 78.187164 -303.33035)
			(xy 78.137989 -303.328369) (xy 78.08977 -303.318525) (xy 78.043754 -303.301073) (xy 78.001133 -303.276466)
			(xy 77.963012 -303.245341) (xy 77.930377 -303.208504) (xy 77.904074 -303.166908) (xy 77.884783 -303.121632)
			(xy 77.873006 -303.073848) (xy 77.869046 -303.024794) (xy 77.530198 -303.024794) (xy 77.529703 -303.049401)
			(xy 77.521808 -303.097978) (xy 77.506224 -303.144659) (xy 77.483353 -303.188236) (xy 77.453788 -303.22758)
			(xy 77.418295 -303.261672) (xy 77.377792 -303.289628) (xy 77.33333 -303.310726) (xy 77.286059 -303.324418)
			(xy 77.237204 -303.33035) (xy 77.188029 -303.328369) (xy 77.13981 -303.318525) (xy 77.093794 -303.301073)
			(xy 77.051173 -303.276466) (xy 77.013052 -303.245341) (xy 76.980417 -303.208504) (xy 76.954114 -303.166908)
			(xy 76.934823 -303.121632) (xy 76.923046 -303.073848) (xy 76.919086 -303.024794) (xy 72.780144 -303.024794)
			(xy 72.779649 -303.049401) (xy 72.771754 -303.097978) (xy 72.75617 -303.144659) (xy 72.733299 -303.188236)
			(xy 72.703734 -303.22758) (xy 72.668241 -303.261672) (xy 72.627738 -303.289628) (xy 72.583276 -303.310726)
			(xy 72.536005 -303.324418) (xy 72.48715 -303.33035) (xy 72.437975 -303.328369) (xy 72.389756 -303.318525)
			(xy 72.34374 -303.301073) (xy 72.301119 -303.276466) (xy 72.262998 -303.245341) (xy 72.230363 -303.208504)
			(xy 72.20406 -303.166908) (xy 72.184769 -303.121632) (xy 72.172992 -303.073848) (xy 72.169032 -303.024794)
			(xy 71.830184 -303.024794) (xy 71.829689 -303.049401) (xy 71.821794 -303.097978) (xy 71.80621 -303.144659)
			(xy 71.783339 -303.188236) (xy 71.753774 -303.22758) (xy 71.718281 -303.261672) (xy 71.677778 -303.289628)
			(xy 71.633316 -303.310726) (xy 71.586045 -303.324418) (xy 71.53719 -303.33035) (xy 71.488015 -303.328369)
			(xy 71.439796 -303.318525) (xy 71.39378 -303.301073) (xy 71.351159 -303.276466) (xy 71.313038 -303.245341)
			(xy 71.280403 -303.208504) (xy 71.2541 -303.166908) (xy 71.234809 -303.121632) (xy 71.223032 -303.073848)
			(xy 71.219072 -303.024794) (xy 70.880224 -303.024794) (xy 70.879729 -303.049401) (xy 70.871834 -303.097978)
			(xy 70.85625 -303.144659) (xy 70.833379 -303.188236) (xy 70.803814 -303.22758) (xy 70.768321 -303.261672)
			(xy 70.727818 -303.289628) (xy 70.683356 -303.310726) (xy 70.636085 -303.324418) (xy 70.58723 -303.33035)
			(xy 70.538055 -303.328369) (xy 70.489836 -303.318525) (xy 70.44382 -303.301073) (xy 70.401199 -303.276466)
			(xy 70.363078 -303.245341) (xy 70.330443 -303.208504) (xy 70.30414 -303.166908) (xy 70.284849 -303.121632)
			(xy 70.273072 -303.073848) (xy 70.269112 -303.024794) (xy 69.930264 -303.024794) (xy 69.929769 -303.049401)
			(xy 69.921874 -303.097978) (xy 69.90629 -303.144659) (xy 69.883419 -303.188236) (xy 69.853854 -303.22758)
			(xy 69.818361 -303.261672) (xy 69.777858 -303.289628) (xy 69.733396 -303.310726) (xy 69.686125 -303.324418)
			(xy 69.63727 -303.33035) (xy 69.588095 -303.328369) (xy 69.539876 -303.318525) (xy 69.49386 -303.301073)
			(xy 69.451239 -303.276466) (xy 69.413118 -303.245341) (xy 69.380483 -303.208504) (xy 69.35418 -303.166908)
			(xy 69.334889 -303.121632) (xy 69.323112 -303.073848) (xy 69.319152 -303.024794) (xy 68.98005 -303.024794)
			(xy 68.979555 -303.049401) (xy 68.97166 -303.097978) (xy 68.956076 -303.144659) (xy 68.933205 -303.188236)
			(xy 68.90364 -303.22758) (xy 68.868147 -303.261672) (xy 68.827644 -303.289628) (xy 68.783182 -303.310726)
			(xy 68.735911 -303.324418) (xy 68.687056 -303.33035) (xy 68.637881 -303.328369) (xy 68.589662 -303.318525)
			(xy 68.543646 -303.301073) (xy 68.501025 -303.276466) (xy 68.462904 -303.245341) (xy 68.430269 -303.208504)
			(xy 68.403966 -303.166908) (xy 68.384675 -303.121632) (xy 68.372898 -303.073848) (xy 68.368938 -303.024794)
			(xy 68.03009 -303.024794) (xy 68.029595 -303.049401) (xy 68.0217 -303.097978) (xy 68.006116 -303.144659)
			(xy 67.983245 -303.188236) (xy 67.95368 -303.22758) (xy 67.918187 -303.261672) (xy 67.877684 -303.289628)
			(xy 67.833222 -303.310726) (xy 67.785951 -303.324418) (xy 67.737096 -303.33035) (xy 67.687921 -303.328369)
			(xy 67.639702 -303.318525) (xy 67.593686 -303.301073) (xy 67.551065 -303.276466) (xy 67.512944 -303.245341)
			(xy 67.480309 -303.208504) (xy 67.454006 -303.166908) (xy 67.434715 -303.121632) (xy 67.422938 -303.073848)
			(xy 67.418978 -303.024794) (xy 67.08013 -303.024794) (xy 67.079635 -303.049401) (xy 67.07174 -303.097978)
			(xy 67.056156 -303.144659) (xy 67.033285 -303.188236) (xy 67.00372 -303.22758) (xy 66.968227 -303.261672)
			(xy 66.927724 -303.289628) (xy 66.883262 -303.310726) (xy 66.835991 -303.324418) (xy 66.787136 -303.33035)
			(xy 66.737961 -303.328369) (xy 66.689742 -303.318525) (xy 66.643726 -303.301073) (xy 66.601105 -303.276466)
			(xy 66.562984 -303.245341) (xy 66.530349 -303.208504) (xy 66.504046 -303.166908) (xy 66.484755 -303.121632)
			(xy 66.472978 -303.073848) (xy 66.469018 -303.024794) (xy 66.13017 -303.024794) (xy 66.129675 -303.049401)
			(xy 66.12178 -303.097978) (xy 66.106196 -303.144659) (xy 66.083325 -303.188236) (xy 66.05376 -303.22758)
			(xy 66.018267 -303.261672) (xy 65.977764 -303.289628) (xy 65.933302 -303.310726) (xy 65.886031 -303.324418)
			(xy 65.837176 -303.33035) (xy 65.788001 -303.328369) (xy 65.739782 -303.318525) (xy 65.693766 -303.301073)
			(xy 65.651145 -303.276466) (xy 65.613024 -303.245341) (xy 65.580389 -303.208504) (xy 65.554086 -303.166908)
			(xy 65.534795 -303.121632) (xy 65.523018 -303.073848) (xy 65.519058 -303.024794) (xy 65.18021 -303.024794)
			(xy 65.179715 -303.049401) (xy 65.17182 -303.097978) (xy 65.156236 -303.144659) (xy 65.133365 -303.188236)
			(xy 65.1038 -303.22758) (xy 65.068307 -303.261672) (xy 65.027804 -303.289628) (xy 64.983342 -303.310726)
			(xy 64.936071 -303.324418) (xy 64.887216 -303.33035) (xy 64.838041 -303.328369) (xy 64.789822 -303.318525)
			(xy 64.743806 -303.301073) (xy 64.701185 -303.276466) (xy 64.663064 -303.245341) (xy 64.630429 -303.208504)
			(xy 64.604126 -303.166908) (xy 64.584835 -303.121632) (xy 64.573058 -303.073848) (xy 64.569098 -303.024794)
			(xy 64.23025 -303.024794) (xy 64.229755 -303.049401) (xy 64.22186 -303.097978) (xy 64.206276 -303.144659)
			(xy 64.183405 -303.188236) (xy 64.15384 -303.22758) (xy 64.118347 -303.261672) (xy 64.077844 -303.289628)
			(xy 64.033382 -303.310726) (xy 63.986111 -303.324418) (xy 63.937256 -303.33035) (xy 63.888081 -303.328369)
			(xy 63.839862 -303.318525) (xy 63.793846 -303.301073) (xy 63.751225 -303.276466) (xy 63.713104 -303.245341)
			(xy 63.680469 -303.208504) (xy 63.654166 -303.166908) (xy 63.634875 -303.121632) (xy 63.623098 -303.073848)
			(xy 63.619138 -303.024794) (xy 63.28029 -303.024794) (xy 63.279795 -303.049401) (xy 63.2719 -303.097978)
			(xy 63.256316 -303.144659) (xy 63.233445 -303.188236) (xy 63.20388 -303.22758) (xy 63.168387 -303.261672)
			(xy 63.127884 -303.289628) (xy 63.083422 -303.310726) (xy 63.036151 -303.324418) (xy 62.987296 -303.33035)
			(xy 62.938121 -303.328369) (xy 62.889902 -303.318525) (xy 62.843886 -303.301073) (xy 62.801265 -303.276466)
			(xy 62.763144 -303.245341) (xy 62.730509 -303.208504) (xy 62.704206 -303.166908) (xy 62.684915 -303.121632)
			(xy 62.673138 -303.073848) (xy 62.669178 -303.024794) (xy 62.330076 -303.024794) (xy 62.329581 -303.049401)
			(xy 62.321686 -303.097978) (xy 62.306102 -303.144659) (xy 62.283231 -303.188236) (xy 62.253666 -303.22758)
			(xy 62.218173 -303.261672) (xy 62.17767 -303.289628) (xy 62.133208 -303.310726) (xy 62.085937 -303.324418)
			(xy 62.037082 -303.33035) (xy 61.987907 -303.328369) (xy 61.939688 -303.318525) (xy 61.893672 -303.301073)
			(xy 61.851051 -303.276466) (xy 61.81293 -303.245341) (xy 61.780295 -303.208504) (xy 61.753992 -303.166908)
			(xy 61.734701 -303.121632) (xy 61.722924 -303.073848) (xy 61.718964 -303.024794) (xy 61.380116 -303.024794)
			(xy 61.379621 -303.049401) (xy 61.371726 -303.097978) (xy 61.356142 -303.144659) (xy 61.333271 -303.188236)
			(xy 61.303706 -303.22758) (xy 61.268213 -303.261672) (xy 61.22771 -303.289628) (xy 61.183248 -303.310726)
			(xy 61.135977 -303.324418) (xy 61.087122 -303.33035) (xy 61.037947 -303.328369) (xy 60.989728 -303.318525)
			(xy 60.943712 -303.301073) (xy 60.901091 -303.276466) (xy 60.86297 -303.245341) (xy 60.830335 -303.208504)
			(xy 60.804032 -303.166908) (xy 60.784741 -303.121632) (xy 60.772964 -303.073848) (xy 60.769004 -303.024794)
			(xy 60.430156 -303.024794) (xy 60.429661 -303.049401) (xy 60.421766 -303.097978) (xy 60.406182 -303.144659)
			(xy 60.383311 -303.188236) (xy 60.353746 -303.22758) (xy 60.318253 -303.261672) (xy 60.27775 -303.289628)
			(xy 60.233288 -303.310726) (xy 60.186017 -303.324418) (xy 60.137162 -303.33035) (xy 60.087987 -303.328369)
			(xy 60.039768 -303.318525) (xy 59.993752 -303.301073) (xy 59.951131 -303.276466) (xy 59.91301 -303.245341)
			(xy 59.880375 -303.208504) (xy 59.854072 -303.166908) (xy 59.834781 -303.121632) (xy 59.823004 -303.073848)
			(xy 59.819044 -303.024794) (xy 58.530236 -303.024794) (xy 58.529741 -303.049401) (xy 58.521846 -303.097978)
			(xy 58.506262 -303.144659) (xy 58.483391 -303.188236) (xy 58.453826 -303.22758) (xy 58.418333 -303.261672)
			(xy 58.37783 -303.289628) (xy 58.333368 -303.310726) (xy 58.286097 -303.324418) (xy 58.237242 -303.33035)
			(xy 58.188067 -303.328369) (xy 58.139848 -303.318525) (xy 58.093832 -303.301073) (xy 58.051211 -303.276466)
			(xy 58.01309 -303.245341) (xy 57.980455 -303.208504) (xy 57.954152 -303.166908) (xy 57.934861 -303.121632)
			(xy 57.923084 -303.073848) (xy 57.919124 -303.024794) (xy 57.580276 -303.024794) (xy 57.579781 -303.049401)
			(xy 57.571886 -303.097978) (xy 57.556302 -303.144659) (xy 57.533431 -303.188236) (xy 57.503866 -303.22758)
			(xy 57.468373 -303.261672) (xy 57.42787 -303.289628) (xy 57.383408 -303.310726) (xy 57.336137 -303.324418)
			(xy 57.287282 -303.33035) (xy 57.238107 -303.328369) (xy 57.189888 -303.318525) (xy 57.143872 -303.301073)
			(xy 57.101251 -303.276466) (xy 57.06313 -303.245341) (xy 57.030495 -303.208504) (xy 57.004192 -303.166908)
			(xy 56.984901 -303.121632) (xy 56.973124 -303.073848) (xy 56.969164 -303.024794) (xy 56.630062 -303.024794)
			(xy 56.629567 -303.049401) (xy 56.621672 -303.097978) (xy 56.606088 -303.144659) (xy 56.583217 -303.188236)
			(xy 56.553652 -303.22758) (xy 56.518159 -303.261672) (xy 56.477656 -303.289628) (xy 56.433194 -303.310726)
			(xy 56.385923 -303.324418) (xy 56.337068 -303.33035) (xy 56.287893 -303.328369) (xy 56.239674 -303.318525)
			(xy 56.193658 -303.301073) (xy 56.151037 -303.276466) (xy 56.112916 -303.245341) (xy 56.080281 -303.208504)
			(xy 56.053978 -303.166908) (xy 56.034687 -303.121632) (xy 56.02291 -303.073848) (xy 56.01895 -303.024794)
			(xy 55.680102 -303.024794) (xy 55.679607 -303.049401) (xy 55.671712 -303.097978) (xy 55.656128 -303.144659)
			(xy 55.633257 -303.188236) (xy 55.603692 -303.22758) (xy 55.568199 -303.261672) (xy 55.527696 -303.289628)
			(xy 55.483234 -303.310726) (xy 55.435963 -303.324418) (xy 55.387108 -303.33035) (xy 55.337933 -303.328369)
			(xy 55.289714 -303.318525) (xy 55.243698 -303.301073) (xy 55.201077 -303.276466) (xy 55.162956 -303.245341)
			(xy 55.130321 -303.208504) (xy 55.104018 -303.166908) (xy 55.084727 -303.121632) (xy 55.07295 -303.073848)
			(xy 55.06899 -303.024794) (xy 54.730142 -303.024794) (xy 54.729647 -303.049401) (xy 54.721752 -303.097978)
			(xy 54.706168 -303.144659) (xy 54.683297 -303.188236) (xy 54.653732 -303.22758) (xy 54.618239 -303.261672)
			(xy 54.577736 -303.289628) (xy 54.533274 -303.310726) (xy 54.486003 -303.324418) (xy 54.437148 -303.33035)
			(xy 54.387973 -303.328369) (xy 54.339754 -303.318525) (xy 54.293738 -303.301073) (xy 54.251117 -303.276466)
			(xy 54.212996 -303.245341) (xy 54.180361 -303.208504) (xy 54.154058 -303.166908) (xy 54.134767 -303.121632)
			(xy 54.12299 -303.073848) (xy 54.11903 -303.024794) (xy 53.780182 -303.024794) (xy 53.779687 -303.049401)
			(xy 53.771792 -303.097978) (xy 53.756208 -303.144659) (xy 53.733337 -303.188236) (xy 53.703772 -303.22758)
			(xy 53.668279 -303.261672) (xy 53.627776 -303.289628) (xy 53.583314 -303.310726) (xy 53.536043 -303.324418)
			(xy 53.487188 -303.33035) (xy 53.438013 -303.328369) (xy 53.389794 -303.318525) (xy 53.343778 -303.301073)
			(xy 53.301157 -303.276466) (xy 53.263036 -303.245341) (xy 53.230401 -303.208504) (xy 53.204098 -303.166908)
			(xy 53.184807 -303.121632) (xy 53.17303 -303.073848) (xy 53.16907 -303.024794) (xy 52.830222 -303.024794)
			(xy 52.829727 -303.049401) (xy 52.821832 -303.097978) (xy 52.806248 -303.144659) (xy 52.783377 -303.188236)
			(xy 52.753812 -303.22758) (xy 52.718319 -303.261672) (xy 52.677816 -303.289628) (xy 52.633354 -303.310726)
			(xy 52.586083 -303.324418) (xy 52.537228 -303.33035) (xy 52.488053 -303.328369) (xy 52.439834 -303.318525)
			(xy 52.393818 -303.301073) (xy 52.351197 -303.276466) (xy 52.313076 -303.245341) (xy 52.280441 -303.208504)
			(xy 52.254138 -303.166908) (xy 52.234847 -303.121632) (xy 52.22307 -303.073848) (xy 52.21911 -303.024794)
			(xy 51.880262 -303.024794) (xy 51.879767 -303.049401) (xy 51.871872 -303.097978) (xy 51.856288 -303.144659)
			(xy 51.833417 -303.188236) (xy 51.803852 -303.22758) (xy 51.768359 -303.261672) (xy 51.727856 -303.289628)
			(xy 51.683394 -303.310726) (xy 51.636123 -303.324418) (xy 51.587268 -303.33035) (xy 51.538093 -303.328369)
			(xy 51.489874 -303.318525) (xy 51.443858 -303.301073) (xy 51.401237 -303.276466) (xy 51.363116 -303.245341)
			(xy 51.330481 -303.208504) (xy 51.304178 -303.166908) (xy 51.284887 -303.121632) (xy 51.27311 -303.073848)
			(xy 51.26915 -303.024794) (xy 50.930302 -303.024794) (xy 50.929807 -303.049401) (xy 50.921912 -303.097978)
			(xy 50.906328 -303.144659) (xy 50.883457 -303.188236) (xy 50.853892 -303.22758) (xy 50.818399 -303.261672)
			(xy 50.777896 -303.289628) (xy 50.733434 -303.310726) (xy 50.686163 -303.324418) (xy 50.637308 -303.33035)
			(xy 50.588133 -303.328369) (xy 50.539914 -303.318525) (xy 50.493898 -303.301073) (xy 50.451277 -303.276466)
			(xy 50.413156 -303.245341) (xy 50.380521 -303.208504) (xy 50.354218 -303.166908) (xy 50.334927 -303.121632)
			(xy 50.32315 -303.073848) (xy 50.31919 -303.024794) (xy 49.980088 -303.024794) (xy 49.979593 -303.049401)
			(xy 49.971698 -303.097978) (xy 49.956114 -303.144659) (xy 49.933243 -303.188236) (xy 49.903678 -303.22758)
			(xy 49.868185 -303.261672) (xy 49.827682 -303.289628) (xy 49.78322 -303.310726) (xy 49.735949 -303.324418)
			(xy 49.687094 -303.33035) (xy 49.637919 -303.328369) (xy 49.5897 -303.318525) (xy 49.543684 -303.301073)
			(xy 49.501063 -303.276466) (xy 49.462942 -303.245341) (xy 49.430307 -303.208504) (xy 49.404004 -303.166908)
			(xy 49.384713 -303.121632) (xy 49.372936 -303.073848) (xy 49.368976 -303.024794) (xy 49.149254 -303.024794)
			(xy 49.149254 -303.499774) (xy 73.593972 -303.499774) (xy 73.597932 -303.45072) (xy 73.609709 -303.402936)
			(xy 73.629 -303.35766) (xy 73.655303 -303.316064) (xy 73.687938 -303.279227) (xy 73.726059 -303.248102)
			(xy 73.76868 -303.223495) (xy 73.814696 -303.206043) (xy 73.862915 -303.196199) (xy 73.91209 -303.194218)
			(xy 73.960945 -303.20015) (xy 74.008216 -303.213842) (xy 74.052678 -303.23494) (xy 74.093181 -303.262896)
			(xy 74.128674 -303.296988) (xy 74.158239 -303.336332) (xy 74.18111 -303.379909) (xy 74.196694 -303.42659)
			(xy 74.204589 -303.475167) (xy 74.205084 -303.499774) (xy 74.544186 -303.499774) (xy 74.548146 -303.45072)
			(xy 74.559923 -303.402936) (xy 74.579214 -303.35766) (xy 74.605517 -303.316064) (xy 74.638152 -303.279227)
			(xy 74.676273 -303.248102) (xy 74.718894 -303.223495) (xy 74.76491 -303.206043) (xy 74.813129 -303.196199)
			(xy 74.862304 -303.194218) (xy 74.911159 -303.20015) (xy 74.95843 -303.213842) (xy 75.002892 -303.23494)
			(xy 75.043395 -303.262896) (xy 75.078888 -303.296988) (xy 75.108453 -303.336332) (xy 75.131324 -303.379909)
			(xy 75.146908 -303.42659) (xy 75.154803 -303.475167) (xy 75.155298 -303.499774) (xy 75.494146 -303.499774)
			(xy 75.498106 -303.45072) (xy 75.509883 -303.402936) (xy 75.529174 -303.35766) (xy 75.555477 -303.316064)
			(xy 75.588112 -303.279227) (xy 75.626233 -303.248102) (xy 75.668854 -303.223495) (xy 75.71487 -303.206043)
			(xy 75.763089 -303.196199) (xy 75.812264 -303.194218) (xy 75.861119 -303.20015) (xy 75.90839 -303.213842)
			(xy 75.952852 -303.23494) (xy 75.993355 -303.262896) (xy 76.028848 -303.296988) (xy 76.058413 -303.336332)
			(xy 76.081284 -303.379909) (xy 76.096868 -303.42659) (xy 76.104763 -303.475167) (xy 76.105258 -303.499774)
			(xy 76.104763 -303.524381) (xy 76.096868 -303.572958) (xy 76.081284 -303.619639) (xy 76.058413 -303.663216)
			(xy 76.028848 -303.70256) (xy 75.993355 -303.736652) (xy 75.952852 -303.764608) (xy 75.90839 -303.785706)
			(xy 75.861119 -303.799398) (xy 75.812264 -303.80533) (xy 75.763089 -303.803349) (xy 75.71487 -303.793505)
			(xy 75.668854 -303.776053) (xy 75.626233 -303.751446) (xy 75.588112 -303.720321) (xy 75.555477 -303.683484)
			(xy 75.529174 -303.641888) (xy 75.509883 -303.596612) (xy 75.498106 -303.548828) (xy 75.494146 -303.499774)
			(xy 75.155298 -303.499774) (xy 75.154803 -303.524381) (xy 75.146908 -303.572958) (xy 75.131324 -303.619639)
			(xy 75.108453 -303.663216) (xy 75.078888 -303.70256) (xy 75.043395 -303.736652) (xy 75.002892 -303.764608)
			(xy 74.95843 -303.785706) (xy 74.911159 -303.799398) (xy 74.862304 -303.80533) (xy 74.813129 -303.803349)
			(xy 74.76491 -303.793505) (xy 74.718894 -303.776053) (xy 74.676273 -303.751446) (xy 74.638152 -303.720321)
			(xy 74.605517 -303.683484) (xy 74.579214 -303.641888) (xy 74.559923 -303.596612) (xy 74.548146 -303.548828)
			(xy 74.544186 -303.499774) (xy 74.205084 -303.499774) (xy 74.204589 -303.524381) (xy 74.196694 -303.572958)
			(xy 74.18111 -303.619639) (xy 74.158239 -303.663216) (xy 74.128674 -303.70256) (xy 74.093181 -303.736652)
			(xy 74.052678 -303.764608) (xy 74.008216 -303.785706) (xy 73.960945 -303.799398) (xy 73.91209 -303.80533)
			(xy 73.862915 -303.803349) (xy 73.814696 -303.793505) (xy 73.76868 -303.776053) (xy 73.726059 -303.751446)
			(xy 73.687938 -303.720321) (xy 73.655303 -303.683484) (xy 73.629 -303.641888) (xy 73.609709 -303.596612)
			(xy 73.597932 -303.548828) (xy 73.593972 -303.499774) (xy 49.149254 -303.499774) (xy 49.149254 -303.974754)
			(xy 49.368976 -303.974754) (xy 49.372936 -303.9257) (xy 49.384713 -303.877916) (xy 49.404004 -303.83264)
			(xy 49.430307 -303.791044) (xy 49.462942 -303.754207) (xy 49.501063 -303.723082) (xy 49.543684 -303.698475)
			(xy 49.5897 -303.681023) (xy 49.637919 -303.671179) (xy 49.687094 -303.669198) (xy 49.735949 -303.67513)
			(xy 49.78322 -303.688822) (xy 49.827682 -303.70992) (xy 49.868185 -303.737876) (xy 49.903678 -303.771968)
			(xy 49.933243 -303.811312) (xy 49.956114 -303.854889) (xy 49.971698 -303.90157) (xy 49.979593 -303.950147)
			(xy 49.980088 -303.974754) (xy 50.31919 -303.974754) (xy 50.32315 -303.9257) (xy 50.334927 -303.877916)
			(xy 50.354218 -303.83264) (xy 50.380521 -303.791044) (xy 50.413156 -303.754207) (xy 50.451277 -303.723082)
			(xy 50.493898 -303.698475) (xy 50.539914 -303.681023) (xy 50.588133 -303.671179) (xy 50.637308 -303.669198)
			(xy 50.686163 -303.67513) (xy 50.733434 -303.688822) (xy 50.777896 -303.70992) (xy 50.818399 -303.737876)
			(xy 50.853892 -303.771968) (xy 50.883457 -303.811312) (xy 50.906328 -303.854889) (xy 50.921912 -303.90157)
			(xy 50.929807 -303.950147) (xy 50.930302 -303.974754) (xy 51.26915 -303.974754) (xy 51.27311 -303.9257)
			(xy 51.284887 -303.877916) (xy 51.304178 -303.83264) (xy 51.330481 -303.791044) (xy 51.363116 -303.754207)
			(xy 51.401237 -303.723082) (xy 51.443858 -303.698475) (xy 51.489874 -303.681023) (xy 51.538093 -303.671179)
			(xy 51.587268 -303.669198) (xy 51.636123 -303.67513) (xy 51.683394 -303.688822) (xy 51.727856 -303.70992)
			(xy 51.768359 -303.737876) (xy 51.803852 -303.771968) (xy 51.833417 -303.811312) (xy 51.856288 -303.854889)
			(xy 51.871872 -303.90157) (xy 51.879767 -303.950147) (xy 51.880262 -303.974754) (xy 52.21911 -303.974754)
			(xy 52.22307 -303.9257) (xy 52.234847 -303.877916) (xy 52.254138 -303.83264) (xy 52.280441 -303.791044)
			(xy 52.313076 -303.754207) (xy 52.351197 -303.723082) (xy 52.393818 -303.698475) (xy 52.439834 -303.681023)
			(xy 52.488053 -303.671179) (xy 52.537228 -303.669198) (xy 52.586083 -303.67513) (xy 52.633354 -303.688822)
			(xy 52.677816 -303.70992) (xy 52.718319 -303.737876) (xy 52.753812 -303.771968) (xy 52.783377 -303.811312)
			(xy 52.806248 -303.854889) (xy 52.821832 -303.90157) (xy 52.829727 -303.950147) (xy 52.830222 -303.974754)
			(xy 53.16907 -303.974754) (xy 53.17303 -303.9257) (xy 53.184807 -303.877916) (xy 53.204098 -303.83264)
			(xy 53.230401 -303.791044) (xy 53.263036 -303.754207) (xy 53.301157 -303.723082) (xy 53.343778 -303.698475)
			(xy 53.389794 -303.681023) (xy 53.438013 -303.671179) (xy 53.487188 -303.669198) (xy 53.536043 -303.67513)
			(xy 53.583314 -303.688822) (xy 53.627776 -303.70992) (xy 53.668279 -303.737876) (xy 53.703772 -303.771968)
			(xy 53.733337 -303.811312) (xy 53.756208 -303.854889) (xy 53.771792 -303.90157) (xy 53.779687 -303.950147)
			(xy 53.780182 -303.974754) (xy 54.11903 -303.974754) (xy 54.12299 -303.9257) (xy 54.134767 -303.877916)
			(xy 54.154058 -303.83264) (xy 54.180361 -303.791044) (xy 54.212996 -303.754207) (xy 54.251117 -303.723082)
			(xy 54.293738 -303.698475) (xy 54.339754 -303.681023) (xy 54.387973 -303.671179) (xy 54.437148 -303.669198)
			(xy 54.486003 -303.67513) (xy 54.533274 -303.688822) (xy 54.577736 -303.70992) (xy 54.618239 -303.737876)
			(xy 54.653732 -303.771968) (xy 54.683297 -303.811312) (xy 54.706168 -303.854889) (xy 54.721752 -303.90157)
			(xy 54.729647 -303.950147) (xy 54.730142 -303.974754) (xy 55.06899 -303.974754) (xy 55.07295 -303.9257)
			(xy 55.084727 -303.877916) (xy 55.104018 -303.83264) (xy 55.130321 -303.791044) (xy 55.162956 -303.754207)
			(xy 55.201077 -303.723082) (xy 55.243698 -303.698475) (xy 55.289714 -303.681023) (xy 55.337933 -303.671179)
			(xy 55.387108 -303.669198) (xy 55.435963 -303.67513) (xy 55.483234 -303.688822) (xy 55.527696 -303.70992)
			(xy 55.568199 -303.737876) (xy 55.603692 -303.771968) (xy 55.633257 -303.811312) (xy 55.656128 -303.854889)
			(xy 55.671712 -303.90157) (xy 55.679607 -303.950147) (xy 55.680102 -303.974754) (xy 56.01895 -303.974754)
			(xy 56.02291 -303.9257) (xy 56.034687 -303.877916) (xy 56.053978 -303.83264) (xy 56.080281 -303.791044)
			(xy 56.112916 -303.754207) (xy 56.151037 -303.723082) (xy 56.193658 -303.698475) (xy 56.239674 -303.681023)
			(xy 56.287893 -303.671179) (xy 56.337068 -303.669198) (xy 56.385923 -303.67513) (xy 56.433194 -303.688822)
			(xy 56.477656 -303.70992) (xy 56.518159 -303.737876) (xy 56.553652 -303.771968) (xy 56.583217 -303.811312)
			(xy 56.606088 -303.854889) (xy 56.621672 -303.90157) (xy 56.629567 -303.950147) (xy 56.630062 -303.974754)
			(xy 56.969164 -303.974754) (xy 56.973124 -303.9257) (xy 56.984901 -303.877916) (xy 57.004192 -303.83264)
			(xy 57.030495 -303.791044) (xy 57.06313 -303.754207) (xy 57.101251 -303.723082) (xy 57.143872 -303.698475)
			(xy 57.189888 -303.681023) (xy 57.238107 -303.671179) (xy 57.287282 -303.669198) (xy 57.336137 -303.67513)
			(xy 57.383408 -303.688822) (xy 57.42787 -303.70992) (xy 57.468373 -303.737876) (xy 57.503866 -303.771968)
			(xy 57.533431 -303.811312) (xy 57.556302 -303.854889) (xy 57.571886 -303.90157) (xy 57.579781 -303.950147)
			(xy 57.580276 -303.974754) (xy 57.919124 -303.974754) (xy 57.923084 -303.9257) (xy 57.934861 -303.877916)
			(xy 57.954152 -303.83264) (xy 57.980455 -303.791044) (xy 58.01309 -303.754207) (xy 58.051211 -303.723082)
			(xy 58.093832 -303.698475) (xy 58.139848 -303.681023) (xy 58.188067 -303.671179) (xy 58.237242 -303.669198)
			(xy 58.286097 -303.67513) (xy 58.333368 -303.688822) (xy 58.37783 -303.70992) (xy 58.418333 -303.737876)
			(xy 58.453826 -303.771968) (xy 58.483391 -303.811312) (xy 58.506262 -303.854889) (xy 58.521846 -303.90157)
			(xy 58.529741 -303.950147) (xy 58.530236 -303.974754) (xy 59.819044 -303.974754) (xy 59.823004 -303.9257)
			(xy 59.834781 -303.877916) (xy 59.854072 -303.83264) (xy 59.880375 -303.791044) (xy 59.91301 -303.754207)
			(xy 59.951131 -303.723082) (xy 59.993752 -303.698475) (xy 60.039768 -303.681023) (xy 60.087987 -303.671179)
			(xy 60.137162 -303.669198) (xy 60.186017 -303.67513) (xy 60.233288 -303.688822) (xy 60.27775 -303.70992)
			(xy 60.318253 -303.737876) (xy 60.353746 -303.771968) (xy 60.383311 -303.811312) (xy 60.406182 -303.854889)
			(xy 60.421766 -303.90157) (xy 60.429661 -303.950147) (xy 60.430156 -303.974754) (xy 60.769004 -303.974754)
			(xy 60.772964 -303.9257) (xy 60.784741 -303.877916) (xy 60.804032 -303.83264) (xy 60.830335 -303.791044)
			(xy 60.86297 -303.754207) (xy 60.901091 -303.723082) (xy 60.943712 -303.698475) (xy 60.989728 -303.681023)
			(xy 61.037947 -303.671179) (xy 61.087122 -303.669198) (xy 61.135977 -303.67513) (xy 61.183248 -303.688822)
			(xy 61.22771 -303.70992) (xy 61.268213 -303.737876) (xy 61.303706 -303.771968) (xy 61.333271 -303.811312)
			(xy 61.356142 -303.854889) (xy 61.371726 -303.90157) (xy 61.379621 -303.950147) (xy 61.380116 -303.974754)
			(xy 61.718964 -303.974754) (xy 61.722924 -303.9257) (xy 61.734701 -303.877916) (xy 61.753992 -303.83264)
			(xy 61.780295 -303.791044) (xy 61.81293 -303.754207) (xy 61.851051 -303.723082) (xy 61.893672 -303.698475)
			(xy 61.939688 -303.681023) (xy 61.987907 -303.671179) (xy 62.037082 -303.669198) (xy 62.085937 -303.67513)
			(xy 62.133208 -303.688822) (xy 62.17767 -303.70992) (xy 62.218173 -303.737876) (xy 62.253666 -303.771968)
			(xy 62.283231 -303.811312) (xy 62.306102 -303.854889) (xy 62.321686 -303.90157) (xy 62.329581 -303.950147)
			(xy 62.330076 -303.974754) (xy 62.669178 -303.974754) (xy 62.673138 -303.9257) (xy 62.684915 -303.877916)
			(xy 62.704206 -303.83264) (xy 62.730509 -303.791044) (xy 62.763144 -303.754207) (xy 62.801265 -303.723082)
			(xy 62.843886 -303.698475) (xy 62.889902 -303.681023) (xy 62.938121 -303.671179) (xy 62.987296 -303.669198)
			(xy 63.036151 -303.67513) (xy 63.083422 -303.688822) (xy 63.127884 -303.70992) (xy 63.168387 -303.737876)
			(xy 63.20388 -303.771968) (xy 63.233445 -303.811312) (xy 63.256316 -303.854889) (xy 63.2719 -303.90157)
			(xy 63.279795 -303.950147) (xy 63.28029 -303.974754) (xy 63.619138 -303.974754) (xy 63.623098 -303.9257)
			(xy 63.634875 -303.877916) (xy 63.654166 -303.83264) (xy 63.680469 -303.791044) (xy 63.713104 -303.754207)
			(xy 63.751225 -303.723082) (xy 63.793846 -303.698475) (xy 63.839862 -303.681023) (xy 63.888081 -303.671179)
			(xy 63.937256 -303.669198) (xy 63.986111 -303.67513) (xy 64.033382 -303.688822) (xy 64.077844 -303.70992)
			(xy 64.118347 -303.737876) (xy 64.15384 -303.771968) (xy 64.183405 -303.811312) (xy 64.206276 -303.854889)
			(xy 64.22186 -303.90157) (xy 64.229755 -303.950147) (xy 64.23025 -303.974754) (xy 64.569098 -303.974754)
			(xy 64.573058 -303.9257) (xy 64.584835 -303.877916) (xy 64.604126 -303.83264) (xy 64.630429 -303.791044)
			(xy 64.663064 -303.754207) (xy 64.701185 -303.723082) (xy 64.743806 -303.698475) (xy 64.789822 -303.681023)
			(xy 64.838041 -303.671179) (xy 64.887216 -303.669198) (xy 64.936071 -303.67513) (xy 64.983342 -303.688822)
			(xy 65.027804 -303.70992) (xy 65.068307 -303.737876) (xy 65.1038 -303.771968) (xy 65.133365 -303.811312)
			(xy 65.156236 -303.854889) (xy 65.17182 -303.90157) (xy 65.179715 -303.950147) (xy 65.18021 -303.974754)
			(xy 65.519058 -303.974754) (xy 65.523018 -303.9257) (xy 65.534795 -303.877916) (xy 65.554086 -303.83264)
			(xy 65.580389 -303.791044) (xy 65.613024 -303.754207) (xy 65.651145 -303.723082) (xy 65.693766 -303.698475)
			(xy 65.739782 -303.681023) (xy 65.788001 -303.671179) (xy 65.837176 -303.669198) (xy 65.886031 -303.67513)
			(xy 65.933302 -303.688822) (xy 65.977764 -303.70992) (xy 66.018267 -303.737876) (xy 66.05376 -303.771968)
			(xy 66.083325 -303.811312) (xy 66.106196 -303.854889) (xy 66.12178 -303.90157) (xy 66.129675 -303.950147)
			(xy 66.13017 -303.974754) (xy 66.469018 -303.974754) (xy 66.472978 -303.9257) (xy 66.484755 -303.877916)
			(xy 66.504046 -303.83264) (xy 66.530349 -303.791044) (xy 66.562984 -303.754207) (xy 66.601105 -303.723082)
			(xy 66.643726 -303.698475) (xy 66.689742 -303.681023) (xy 66.737961 -303.671179) (xy 66.787136 -303.669198)
			(xy 66.835991 -303.67513) (xy 66.883262 -303.688822) (xy 66.927724 -303.70992) (xy 66.968227 -303.737876)
			(xy 67.00372 -303.771968) (xy 67.033285 -303.811312) (xy 67.056156 -303.854889) (xy 67.07174 -303.90157)
			(xy 67.079635 -303.950147) (xy 67.08013 -303.974754) (xy 67.418978 -303.974754) (xy 67.422938 -303.9257)
			(xy 67.434715 -303.877916) (xy 67.454006 -303.83264) (xy 67.480309 -303.791044) (xy 67.512944 -303.754207)
			(xy 67.551065 -303.723082) (xy 67.593686 -303.698475) (xy 67.639702 -303.681023) (xy 67.687921 -303.671179)
			(xy 67.737096 -303.669198) (xy 67.785951 -303.67513) (xy 67.833222 -303.688822) (xy 67.877684 -303.70992)
			(xy 67.918187 -303.737876) (xy 67.95368 -303.771968) (xy 67.983245 -303.811312) (xy 68.006116 -303.854889)
			(xy 68.0217 -303.90157) (xy 68.029595 -303.950147) (xy 68.029993 -303.969928) (xy 68.374018 -303.969928)
			(xy 68.377978 -303.920874) (xy 68.389755 -303.87309) (xy 68.409046 -303.827814) (xy 68.435349 -303.786218)
			(xy 68.467984 -303.749381) (xy 68.506105 -303.718256) (xy 68.548726 -303.693649) (xy 68.594742 -303.676197)
			(xy 68.642961 -303.666353) (xy 68.692136 -303.664372) (xy 68.740991 -303.670304) (xy 68.788262 -303.683996)
			(xy 68.832724 -303.705094) (xy 68.873227 -303.73305) (xy 68.90872 -303.767142) (xy 68.938285 -303.806486)
			(xy 68.961156 -303.850063) (xy 68.97674 -303.896744) (xy 68.984635 -303.945321) (xy 68.98513 -303.969928)
			(xy 68.985033 -303.974754) (xy 69.319152 -303.974754) (xy 69.323112 -303.9257) (xy 69.334889 -303.877916)
			(xy 69.35418 -303.83264) (xy 69.380483 -303.791044) (xy 69.413118 -303.754207) (xy 69.451239 -303.723082)
			(xy 69.49386 -303.698475) (xy 69.539876 -303.681023) (xy 69.588095 -303.671179) (xy 69.63727 -303.669198)
			(xy 69.686125 -303.67513) (xy 69.733396 -303.688822) (xy 69.777858 -303.70992) (xy 69.818361 -303.737876)
			(xy 69.853854 -303.771968) (xy 69.883419 -303.811312) (xy 69.90629 -303.854889) (xy 69.921874 -303.90157)
			(xy 69.929769 -303.950147) (xy 69.930264 -303.974754) (xy 70.269112 -303.974754) (xy 70.273072 -303.9257)
			(xy 70.284849 -303.877916) (xy 70.30414 -303.83264) (xy 70.330443 -303.791044) (xy 70.363078 -303.754207)
			(xy 70.401199 -303.723082) (xy 70.44382 -303.698475) (xy 70.489836 -303.681023) (xy 70.538055 -303.671179)
			(xy 70.58723 -303.669198) (xy 70.636085 -303.67513) (xy 70.683356 -303.688822) (xy 70.727818 -303.70992)
			(xy 70.768321 -303.737876) (xy 70.803814 -303.771968) (xy 70.833379 -303.811312) (xy 70.85625 -303.854889)
			(xy 70.871834 -303.90157) (xy 70.879729 -303.950147) (xy 70.880224 -303.974754) (xy 71.219072 -303.974754)
			(xy 71.223032 -303.9257) (xy 71.234809 -303.877916) (xy 71.2541 -303.83264) (xy 71.280403 -303.791044)
			(xy 71.313038 -303.754207) (xy 71.351159 -303.723082) (xy 71.39378 -303.698475) (xy 71.439796 -303.681023)
			(xy 71.488015 -303.671179) (xy 71.53719 -303.669198) (xy 71.586045 -303.67513) (xy 71.633316 -303.688822)
			(xy 71.677778 -303.70992) (xy 71.718281 -303.737876) (xy 71.753774 -303.771968) (xy 71.783339 -303.811312)
			(xy 71.80621 -303.854889) (xy 71.821794 -303.90157) (xy 71.829689 -303.950147) (xy 71.830184 -303.974754)
			(xy 72.169032 -303.974754) (xy 72.172992 -303.9257) (xy 72.184769 -303.877916) (xy 72.20406 -303.83264)
			(xy 72.230363 -303.791044) (xy 72.262998 -303.754207) (xy 72.301119 -303.723082) (xy 72.34374 -303.698475)
			(xy 72.389756 -303.681023) (xy 72.437975 -303.671179) (xy 72.48715 -303.669198) (xy 72.536005 -303.67513)
			(xy 72.583276 -303.688822) (xy 72.627738 -303.70992) (xy 72.668241 -303.737876) (xy 72.703734 -303.771968)
			(xy 72.733299 -303.811312) (xy 72.75617 -303.854889) (xy 72.771754 -303.90157) (xy 72.779649 -303.950147)
			(xy 72.780144 -303.974754) (xy 72.779649 -303.999361) (xy 72.771754 -304.047938) (xy 72.75617 -304.094619)
			(xy 72.733299 -304.138196) (xy 72.703734 -304.17754) (xy 72.668241 -304.211632) (xy 72.627738 -304.239588)
			(xy 72.583276 -304.260686) (xy 72.536005 -304.274378) (xy 72.48715 -304.28031) (xy 72.437975 -304.278329)
			(xy 72.389756 -304.268485) (xy 72.34374 -304.251033) (xy 72.301119 -304.226426) (xy 72.262998 -304.195301)
			(xy 72.230363 -304.158464) (xy 72.20406 -304.116868) (xy 72.184769 -304.071592) (xy 72.172992 -304.023808)
			(xy 72.169032 -303.974754) (xy 71.830184 -303.974754) (xy 71.829689 -303.999361) (xy 71.821794 -304.047938)
			(xy 71.80621 -304.094619) (xy 71.783339 -304.138196) (xy 71.753774 -304.17754) (xy 71.718281 -304.211632)
			(xy 71.677778 -304.239588) (xy 71.633316 -304.260686) (xy 71.586045 -304.274378) (xy 71.53719 -304.28031)
			(xy 71.488015 -304.278329) (xy 71.439796 -304.268485) (xy 71.39378 -304.251033) (xy 71.351159 -304.226426)
			(xy 71.313038 -304.195301) (xy 71.280403 -304.158464) (xy 71.2541 -304.116868) (xy 71.234809 -304.071592)
			(xy 71.223032 -304.023808) (xy 71.219072 -303.974754) (xy 70.880224 -303.974754) (xy 70.879729 -303.999361)
			(xy 70.871834 -304.047938) (xy 70.85625 -304.094619) (xy 70.833379 -304.138196) (xy 70.803814 -304.17754)
			(xy 70.768321 -304.211632) (xy 70.727818 -304.239588) (xy 70.683356 -304.260686) (xy 70.636085 -304.274378)
			(xy 70.58723 -304.28031) (xy 70.538055 -304.278329) (xy 70.489836 -304.268485) (xy 70.44382 -304.251033)
			(xy 70.401199 -304.226426) (xy 70.363078 -304.195301) (xy 70.330443 -304.158464) (xy 70.30414 -304.116868)
			(xy 70.284849 -304.071592) (xy 70.273072 -304.023808) (xy 70.269112 -303.974754) (xy 69.930264 -303.974754)
			(xy 69.929769 -303.999361) (xy 69.921874 -304.047938) (xy 69.90629 -304.094619) (xy 69.883419 -304.138196)
			(xy 69.853854 -304.17754) (xy 69.818361 -304.211632) (xy 69.777858 -304.239588) (xy 69.733396 -304.260686)
			(xy 69.686125 -304.274378) (xy 69.63727 -304.28031) (xy 69.588095 -304.278329) (xy 69.539876 -304.268485)
			(xy 69.49386 -304.251033) (xy 69.451239 -304.226426) (xy 69.413118 -304.195301) (xy 69.380483 -304.158464)
			(xy 69.35418 -304.116868) (xy 69.334889 -304.071592) (xy 69.323112 -304.023808) (xy 69.319152 -303.974754)
			(xy 68.985033 -303.974754) (xy 68.984635 -303.994535) (xy 68.97674 -304.043112) (xy 68.961156 -304.089793)
			(xy 68.938285 -304.13337) (xy 68.90872 -304.172714) (xy 68.873227 -304.206806) (xy 68.832724 -304.234762)
			(xy 68.788262 -304.25586) (xy 68.740991 -304.269552) (xy 68.692136 -304.275484) (xy 68.642961 -304.273503)
			(xy 68.594742 -304.263659) (xy 68.548726 -304.246207) (xy 68.506105 -304.2216) (xy 68.467984 -304.190475)
			(xy 68.435349 -304.153638) (xy 68.409046 -304.112042) (xy 68.389755 -304.066766) (xy 68.377978 -304.018982)
			(xy 68.374018 -303.969928) (xy 68.029993 -303.969928) (xy 68.03009 -303.974754) (xy 68.029595 -303.999361)
			(xy 68.0217 -304.047938) (xy 68.006116 -304.094619) (xy 67.983245 -304.138196) (xy 67.95368 -304.17754)
			(xy 67.918187 -304.211632) (xy 67.877684 -304.239588) (xy 67.833222 -304.260686) (xy 67.785951 -304.274378)
			(xy 67.737096 -304.28031) (xy 67.687921 -304.278329) (xy 67.639702 -304.268485) (xy 67.593686 -304.251033)
			(xy 67.551065 -304.226426) (xy 67.512944 -304.195301) (xy 67.480309 -304.158464) (xy 67.454006 -304.116868)
			(xy 67.434715 -304.071592) (xy 67.422938 -304.023808) (xy 67.418978 -303.974754) (xy 67.08013 -303.974754)
			(xy 67.079635 -303.999361) (xy 67.07174 -304.047938) (xy 67.056156 -304.094619) (xy 67.033285 -304.138196)
			(xy 67.00372 -304.17754) (xy 66.968227 -304.211632) (xy 66.927724 -304.239588) (xy 66.883262 -304.260686)
			(xy 66.835991 -304.274378) (xy 66.787136 -304.28031) (xy 66.737961 -304.278329) (xy 66.689742 -304.268485)
			(xy 66.643726 -304.251033) (xy 66.601105 -304.226426) (xy 66.562984 -304.195301) (xy 66.530349 -304.158464)
			(xy 66.504046 -304.116868) (xy 66.484755 -304.071592) (xy 66.472978 -304.023808) (xy 66.469018 -303.974754)
			(xy 66.13017 -303.974754) (xy 66.129675 -303.999361) (xy 66.12178 -304.047938) (xy 66.106196 -304.094619)
			(xy 66.083325 -304.138196) (xy 66.05376 -304.17754) (xy 66.018267 -304.211632) (xy 65.977764 -304.239588)
			(xy 65.933302 -304.260686) (xy 65.886031 -304.274378) (xy 65.837176 -304.28031) (xy 65.788001 -304.278329)
			(xy 65.739782 -304.268485) (xy 65.693766 -304.251033) (xy 65.651145 -304.226426) (xy 65.613024 -304.195301)
			(xy 65.580389 -304.158464) (xy 65.554086 -304.116868) (xy 65.534795 -304.071592) (xy 65.523018 -304.023808)
			(xy 65.519058 -303.974754) (xy 65.18021 -303.974754) (xy 65.179715 -303.999361) (xy 65.17182 -304.047938)
			(xy 65.156236 -304.094619) (xy 65.133365 -304.138196) (xy 65.1038 -304.17754) (xy 65.068307 -304.211632)
			(xy 65.027804 -304.239588) (xy 64.983342 -304.260686) (xy 64.936071 -304.274378) (xy 64.887216 -304.28031)
			(xy 64.838041 -304.278329) (xy 64.789822 -304.268485) (xy 64.743806 -304.251033) (xy 64.701185 -304.226426)
			(xy 64.663064 -304.195301) (xy 64.630429 -304.158464) (xy 64.604126 -304.116868) (xy 64.584835 -304.071592)
			(xy 64.573058 -304.023808) (xy 64.569098 -303.974754) (xy 64.23025 -303.974754) (xy 64.229755 -303.999361)
			(xy 64.22186 -304.047938) (xy 64.206276 -304.094619) (xy 64.183405 -304.138196) (xy 64.15384 -304.17754)
			(xy 64.118347 -304.211632) (xy 64.077844 -304.239588) (xy 64.033382 -304.260686) (xy 63.986111 -304.274378)
			(xy 63.937256 -304.28031) (xy 63.888081 -304.278329) (xy 63.839862 -304.268485) (xy 63.793846 -304.251033)
			(xy 63.751225 -304.226426) (xy 63.713104 -304.195301) (xy 63.680469 -304.158464) (xy 63.654166 -304.116868)
			(xy 63.634875 -304.071592) (xy 63.623098 -304.023808) (xy 63.619138 -303.974754) (xy 63.28029 -303.974754)
			(xy 63.279795 -303.999361) (xy 63.2719 -304.047938) (xy 63.256316 -304.094619) (xy 63.233445 -304.138196)
			(xy 63.20388 -304.17754) (xy 63.168387 -304.211632) (xy 63.127884 -304.239588) (xy 63.083422 -304.260686)
			(xy 63.036151 -304.274378) (xy 62.987296 -304.28031) (xy 62.938121 -304.278329) (xy 62.889902 -304.268485)
			(xy 62.843886 -304.251033) (xy 62.801265 -304.226426) (xy 62.763144 -304.195301) (xy 62.730509 -304.158464)
			(xy 62.704206 -304.116868) (xy 62.684915 -304.071592) (xy 62.673138 -304.023808) (xy 62.669178 -303.974754)
			(xy 62.330076 -303.974754) (xy 62.329581 -303.999361) (xy 62.321686 -304.047938) (xy 62.306102 -304.094619)
			(xy 62.283231 -304.138196) (xy 62.253666 -304.17754) (xy 62.218173 -304.211632) (xy 62.17767 -304.239588)
			(xy 62.133208 -304.260686) (xy 62.085937 -304.274378) (xy 62.037082 -304.28031) (xy 61.987907 -304.278329)
			(xy 61.939688 -304.268485) (xy 61.893672 -304.251033) (xy 61.851051 -304.226426) (xy 61.81293 -304.195301)
			(xy 61.780295 -304.158464) (xy 61.753992 -304.116868) (xy 61.734701 -304.071592) (xy 61.722924 -304.023808)
			(xy 61.718964 -303.974754) (xy 61.380116 -303.974754) (xy 61.379621 -303.999361) (xy 61.371726 -304.047938)
			(xy 61.356142 -304.094619) (xy 61.333271 -304.138196) (xy 61.303706 -304.17754) (xy 61.268213 -304.211632)
			(xy 61.22771 -304.239588) (xy 61.183248 -304.260686) (xy 61.135977 -304.274378) (xy 61.087122 -304.28031)
			(xy 61.037947 -304.278329) (xy 60.989728 -304.268485) (xy 60.943712 -304.251033) (xy 60.901091 -304.226426)
			(xy 60.86297 -304.195301) (xy 60.830335 -304.158464) (xy 60.804032 -304.116868) (xy 60.784741 -304.071592)
			(xy 60.772964 -304.023808) (xy 60.769004 -303.974754) (xy 60.430156 -303.974754) (xy 60.429661 -303.999361)
			(xy 60.421766 -304.047938) (xy 60.406182 -304.094619) (xy 60.383311 -304.138196) (xy 60.353746 -304.17754)
			(xy 60.318253 -304.211632) (xy 60.27775 -304.239588) (xy 60.233288 -304.260686) (xy 60.186017 -304.274378)
			(xy 60.137162 -304.28031) (xy 60.087987 -304.278329) (xy 60.039768 -304.268485) (xy 59.993752 -304.251033)
			(xy 59.951131 -304.226426) (xy 59.91301 -304.195301) (xy 59.880375 -304.158464) (xy 59.854072 -304.116868)
			(xy 59.834781 -304.071592) (xy 59.823004 -304.023808) (xy 59.819044 -303.974754) (xy 58.530236 -303.974754)
			(xy 58.529741 -303.999361) (xy 58.521846 -304.047938) (xy 58.506262 -304.094619) (xy 58.483391 -304.138196)
			(xy 58.453826 -304.17754) (xy 58.418333 -304.211632) (xy 58.37783 -304.239588) (xy 58.333368 -304.260686)
			(xy 58.286097 -304.274378) (xy 58.237242 -304.28031) (xy 58.188067 -304.278329) (xy 58.139848 -304.268485)
			(xy 58.093832 -304.251033) (xy 58.051211 -304.226426) (xy 58.01309 -304.195301) (xy 57.980455 -304.158464)
			(xy 57.954152 -304.116868) (xy 57.934861 -304.071592) (xy 57.923084 -304.023808) (xy 57.919124 -303.974754)
			(xy 57.580276 -303.974754) (xy 57.579781 -303.999361) (xy 57.571886 -304.047938) (xy 57.556302 -304.094619)
			(xy 57.533431 -304.138196) (xy 57.503866 -304.17754) (xy 57.468373 -304.211632) (xy 57.42787 -304.239588)
			(xy 57.383408 -304.260686) (xy 57.336137 -304.274378) (xy 57.287282 -304.28031) (xy 57.238107 -304.278329)
			(xy 57.189888 -304.268485) (xy 57.143872 -304.251033) (xy 57.101251 -304.226426) (xy 57.06313 -304.195301)
			(xy 57.030495 -304.158464) (xy 57.004192 -304.116868) (xy 56.984901 -304.071592) (xy 56.973124 -304.023808)
			(xy 56.969164 -303.974754) (xy 56.630062 -303.974754) (xy 56.629567 -303.999361) (xy 56.621672 -304.047938)
			(xy 56.606088 -304.094619) (xy 56.583217 -304.138196) (xy 56.553652 -304.17754) (xy 56.518159 -304.211632)
			(xy 56.477656 -304.239588) (xy 56.433194 -304.260686) (xy 56.385923 -304.274378) (xy 56.337068 -304.28031)
			(xy 56.287893 -304.278329) (xy 56.239674 -304.268485) (xy 56.193658 -304.251033) (xy 56.151037 -304.226426)
			(xy 56.112916 -304.195301) (xy 56.080281 -304.158464) (xy 56.053978 -304.116868) (xy 56.034687 -304.071592)
			(xy 56.02291 -304.023808) (xy 56.01895 -303.974754) (xy 55.680102 -303.974754) (xy 55.679607 -303.999361)
			(xy 55.671712 -304.047938) (xy 55.656128 -304.094619) (xy 55.633257 -304.138196) (xy 55.603692 -304.17754)
			(xy 55.568199 -304.211632) (xy 55.527696 -304.239588) (xy 55.483234 -304.260686) (xy 55.435963 -304.274378)
			(xy 55.387108 -304.28031) (xy 55.337933 -304.278329) (xy 55.289714 -304.268485) (xy 55.243698 -304.251033)
			(xy 55.201077 -304.226426) (xy 55.162956 -304.195301) (xy 55.130321 -304.158464) (xy 55.104018 -304.116868)
			(xy 55.084727 -304.071592) (xy 55.07295 -304.023808) (xy 55.06899 -303.974754) (xy 54.730142 -303.974754)
			(xy 54.729647 -303.999361) (xy 54.721752 -304.047938) (xy 54.706168 -304.094619) (xy 54.683297 -304.138196)
			(xy 54.653732 -304.17754) (xy 54.618239 -304.211632) (xy 54.577736 -304.239588) (xy 54.533274 -304.260686)
			(xy 54.486003 -304.274378) (xy 54.437148 -304.28031) (xy 54.387973 -304.278329) (xy 54.339754 -304.268485)
			(xy 54.293738 -304.251033) (xy 54.251117 -304.226426) (xy 54.212996 -304.195301) (xy 54.180361 -304.158464)
			(xy 54.154058 -304.116868) (xy 54.134767 -304.071592) (xy 54.12299 -304.023808) (xy 54.11903 -303.974754)
			(xy 53.780182 -303.974754) (xy 53.779687 -303.999361) (xy 53.771792 -304.047938) (xy 53.756208 -304.094619)
			(xy 53.733337 -304.138196) (xy 53.703772 -304.17754) (xy 53.668279 -304.211632) (xy 53.627776 -304.239588)
			(xy 53.583314 -304.260686) (xy 53.536043 -304.274378) (xy 53.487188 -304.28031) (xy 53.438013 -304.278329)
			(xy 53.389794 -304.268485) (xy 53.343778 -304.251033) (xy 53.301157 -304.226426) (xy 53.263036 -304.195301)
			(xy 53.230401 -304.158464) (xy 53.204098 -304.116868) (xy 53.184807 -304.071592) (xy 53.17303 -304.023808)
			(xy 53.16907 -303.974754) (xy 52.830222 -303.974754) (xy 52.829727 -303.999361) (xy 52.821832 -304.047938)
			(xy 52.806248 -304.094619) (xy 52.783377 -304.138196) (xy 52.753812 -304.17754) (xy 52.718319 -304.211632)
			(xy 52.677816 -304.239588) (xy 52.633354 -304.260686) (xy 52.586083 -304.274378) (xy 52.537228 -304.28031)
			(xy 52.488053 -304.278329) (xy 52.439834 -304.268485) (xy 52.393818 -304.251033) (xy 52.351197 -304.226426)
			(xy 52.313076 -304.195301) (xy 52.280441 -304.158464) (xy 52.254138 -304.116868) (xy 52.234847 -304.071592)
			(xy 52.22307 -304.023808) (xy 52.21911 -303.974754) (xy 51.880262 -303.974754) (xy 51.879767 -303.999361)
			(xy 51.871872 -304.047938) (xy 51.856288 -304.094619) (xy 51.833417 -304.138196) (xy 51.803852 -304.17754)
			(xy 51.768359 -304.211632) (xy 51.727856 -304.239588) (xy 51.683394 -304.260686) (xy 51.636123 -304.274378)
			(xy 51.587268 -304.28031) (xy 51.538093 -304.278329) (xy 51.489874 -304.268485) (xy 51.443858 -304.251033)
			(xy 51.401237 -304.226426) (xy 51.363116 -304.195301) (xy 51.330481 -304.158464) (xy 51.304178 -304.116868)
			(xy 51.284887 -304.071592) (xy 51.27311 -304.023808) (xy 51.26915 -303.974754) (xy 50.930302 -303.974754)
			(xy 50.929807 -303.999361) (xy 50.921912 -304.047938) (xy 50.906328 -304.094619) (xy 50.883457 -304.138196)
			(xy 50.853892 -304.17754) (xy 50.818399 -304.211632) (xy 50.777896 -304.239588) (xy 50.733434 -304.260686)
			(xy 50.686163 -304.274378) (xy 50.637308 -304.28031) (xy 50.588133 -304.278329) (xy 50.539914 -304.268485)
			(xy 50.493898 -304.251033) (xy 50.451277 -304.226426) (xy 50.413156 -304.195301) (xy 50.380521 -304.158464)
			(xy 50.354218 -304.116868) (xy 50.334927 -304.071592) (xy 50.32315 -304.023808) (xy 50.31919 -303.974754)
			(xy 49.980088 -303.974754) (xy 49.979593 -303.999361) (xy 49.971698 -304.047938) (xy 49.956114 -304.094619)
			(xy 49.933243 -304.138196) (xy 49.903678 -304.17754) (xy 49.868185 -304.211632) (xy 49.827682 -304.239588)
			(xy 49.78322 -304.260686) (xy 49.735949 -304.274378) (xy 49.687094 -304.28031) (xy 49.637919 -304.278329)
			(xy 49.5897 -304.268485) (xy 49.543684 -304.251033) (xy 49.501063 -304.226426) (xy 49.462942 -304.195301)
			(xy 49.430307 -304.158464) (xy 49.404004 -304.116868) (xy 49.384713 -304.071592) (xy 49.372936 -304.023808)
			(xy 49.368976 -303.974754) (xy 49.149254 -303.974754) (xy 49.149254 -304.449734) (xy 73.593972 -304.449734)
			(xy 73.597932 -304.40068) (xy 73.609709 -304.352896) (xy 73.629 -304.30762) (xy 73.655303 -304.266024)
			(xy 73.687938 -304.229187) (xy 73.726059 -304.198062) (xy 73.76868 -304.173455) (xy 73.814696 -304.156003)
			(xy 73.862915 -304.146159) (xy 73.91209 -304.144178) (xy 73.960945 -304.15011) (xy 74.008216 -304.163802)
			(xy 74.052678 -304.1849) (xy 74.093181 -304.212856) (xy 74.128674 -304.246948) (xy 74.158239 -304.286292)
			(xy 74.18111 -304.329869) (xy 74.196694 -304.37655) (xy 74.204589 -304.425127) (xy 74.205084 -304.449734)
			(xy 74.204589 -304.474341) (xy 74.20441 -304.475442) (xy 74.523342 -304.475442) (xy 74.523342 -304.424026)
			(xy 74.531385 -304.373244) (xy 74.547273 -304.324345) (xy 74.570616 -304.278533) (xy 74.600837 -304.236937)
			(xy 74.637193 -304.200581) (xy 74.678789 -304.17036) (xy 74.724601 -304.147017) (xy 74.7735 -304.131129)
			(xy 74.824282 -304.123086) (xy 74.875698 -304.123086) (xy 74.92648 -304.131129) (xy 74.975379 -304.147017)
			(xy 75.021191 -304.17036) (xy 75.062787 -304.200581) (xy 75.099143 -304.236937) (xy 75.129364 -304.278533)
			(xy 75.152707 -304.324345) (xy 75.168595 -304.373244) (xy 75.176638 -304.424026) (xy 75.177142 -304.449734)
			(xy 75.176638 -304.475442) (xy 75.473302 -304.475442) (xy 75.473302 -304.424026) (xy 75.481345 -304.373244)
			(xy 75.497233 -304.324345) (xy 75.520576 -304.278533) (xy 75.550797 -304.236937) (xy 75.587153 -304.200581)
			(xy 75.628749 -304.17036) (xy 75.674561 -304.147017) (xy 75.72346 -304.131129) (xy 75.774242 -304.123086)
			(xy 75.825658 -304.123086) (xy 75.87644 -304.131129) (xy 75.925339 -304.147017) (xy 75.971151 -304.17036)
			(xy 76.012747 -304.200581) (xy 76.049103 -304.236937) (xy 76.079324 -304.278533) (xy 76.102667 -304.324345)
			(xy 76.118555 -304.373244) (xy 76.126598 -304.424026) (xy 76.127102 -304.449734) (xy 76.444106 -304.449734)
			(xy 76.448066 -304.40068) (xy 76.459843 -304.352896) (xy 76.479134 -304.30762) (xy 76.505437 -304.266024)
			(xy 76.538072 -304.229187) (xy 76.576193 -304.198062) (xy 76.618814 -304.173455) (xy 76.66483 -304.156003)
			(xy 76.713049 -304.146159) (xy 76.762224 -304.144178) (xy 76.811079 -304.15011) (xy 76.85835 -304.163802)
			(xy 76.902812 -304.1849) (xy 76.943315 -304.212856) (xy 76.978808 -304.246948) (xy 77.008373 -304.286292)
			(xy 77.031244 -304.329869) (xy 77.046828 -304.37655) (xy 77.054723 -304.425127) (xy 77.055218 -304.449734)
			(xy 77.394066 -304.449734) (xy 77.398026 -304.40068) (xy 77.409803 -304.352896) (xy 77.429094 -304.30762)
			(xy 77.455397 -304.266024) (xy 77.488032 -304.229187) (xy 77.526153 -304.198062) (xy 77.568774 -304.173455)
			(xy 77.61479 -304.156003) (xy 77.663009 -304.146159) (xy 77.712184 -304.144178) (xy 77.761039 -304.15011)
			(xy 77.80831 -304.163802) (xy 77.852772 -304.1849) (xy 77.893275 -304.212856) (xy 77.928768 -304.246948)
			(xy 77.958333 -304.286292) (xy 77.981204 -304.329869) (xy 77.996788 -304.37655) (xy 78.004683 -304.425127)
			(xy 78.00501 -304.441388) (xy 78.344116 -304.441388) (xy 78.349488 -304.392043) (xy 78.362772 -304.344218)
			(xy 78.383618 -304.299172) (xy 78.411477 -304.258091) (xy 78.445615 -304.222059) (xy 78.485133 -304.192024)
			(xy 78.52899 -304.168779) (xy 78.576029 -304.152935) (xy 78.625012 -304.144909) (xy 78.64983 -304.144426)
			(xy 78.664013 -304.144598) (xy 78.692253 -304.147273) (xy 78.706218 -304.14976) (xy 78.718664 -304.152046)
			(xy 78.742286 -304.14468) (xy 78.819756 -304.06721) (xy 78.827122 -304.043588) (xy 78.824836 -304.031142)
			(xy 78.822356 -304.017177) (xy 78.819686 -303.988937) (xy 78.819502 -303.974754) (xy 78.820024 -303.949499)
			(xy 78.828337 -303.899677) (xy 78.844738 -303.851903) (xy 78.868779 -303.80748) (xy 78.899803 -303.76762)
			(xy 78.936965 -303.73341) (xy 78.979251 -303.705784) (xy 79.025507 -303.685494) (xy 79.074472 -303.673094)
			(xy 79.12481 -303.668923) (xy 79.175148 -303.673094) (xy 79.224113 -303.685494) (xy 79.270369 -303.705784)
			(xy 79.312655 -303.73341) (xy 79.349817 -303.76762) (xy 79.380841 -303.80748) (xy 79.404882 -303.851903)
			(xy 79.421283 -303.899677) (xy 79.423781 -303.914651) (xy 85.191856 -303.914651) (xy 85.191856 -303.860149)
			(xy 85.199611 -303.806202) (xy 85.214965 -303.753908) (xy 85.237604 -303.704331) (xy 85.267068 -303.658481)
			(xy 85.302757 -303.617289) (xy 85.343944 -303.581596) (xy 85.389791 -303.552126) (xy 85.439365 -303.529481)
			(xy 85.491657 -303.514121) (xy 85.545603 -303.506359) (xy 85.572854 -303.50587) (xy 85.599171 -303.506293)
			(xy 85.651305 -303.513523) (xy 85.70195 -303.527852) (xy 85.750144 -303.549008) (xy 85.794972 -303.57659)
			(xy 85.835582 -303.610073) (xy 85.871203 -303.648821) (xy 85.886544 -303.670208) (xy 85.892386 -303.678844)
			(xy 85.908896 -303.689512) (xy 85.999828 -303.706276) (xy 86.019132 -303.702212) (xy 86.027514 -303.69637)
			(xy 86.051436 -303.68057) (xy 86.103046 -303.655608) (xy 86.15781 -303.63865) (xy 86.214495 -303.63008)
			(xy 86.24316 -303.629568) (xy 86.270413 -303.630077) (xy 86.314606 -303.636426) (xy 93.3229 -303.636426)
			(xy 93.326971 -303.580804) (xy 93.339097 -303.526367) (xy 93.35902 -303.474276) (xy 93.386316 -303.425641)
			(xy 93.420402 -303.381498) (xy 93.460551 -303.342789) (xy 93.505909 -303.310338) (xy 93.555509 -303.284837)
			(xy 93.608293 -303.26683) (xy 93.663136 -303.2567) (xy 93.71887 -303.254663) (xy 93.774307 -303.260763)
			(xy 93.828264 -303.274869) (xy 93.879593 -303.296681) (xy 93.927199 -303.325735) (xy 93.970067 -303.36141)
			(xy 94.007284 -303.402947) (xy 94.038057 -303.44946) (xy 94.061729 -303.499957) (xy 94.077797 -303.553364)
			(xy 94.085917 -303.60854) (xy 94.086426 -303.636426) (xy 94.085917 -303.664312) (xy 94.077797 -303.719488)
			(xy 94.061729 -303.772895) (xy 94.038057 -303.823392) (xy 94.007284 -303.869905) (xy 93.970067 -303.911442)
			(xy 93.927199 -303.947117) (xy 93.879593 -303.976171) (xy 93.828264 -303.997983) (xy 93.774307 -304.012089)
			(xy 93.71887 -304.018189) (xy 93.663136 -304.016152) (xy 93.608293 -304.006022) (xy 93.555509 -303.988015)
			(xy 93.505909 -303.962514) (xy 93.460551 -303.930063) (xy 93.420402 -303.891354) (xy 93.386316 -303.847211)
			(xy 93.35902 -303.798576) (xy 93.339097 -303.746485) (xy 93.326971 -303.692048) (xy 93.3229 -303.636426)
			(xy 86.314606 -303.636426) (xy 86.324365 -303.637828) (xy 86.376664 -303.65318) (xy 86.426246 -303.675819)
			(xy 86.472102 -303.705284) (xy 86.513296 -303.740975) (xy 86.548992 -303.782166) (xy 86.578462 -303.828019)
			(xy 86.601106 -303.877598) (xy 86.616463 -303.929896) (xy 86.624221 -303.983847) (xy 86.624221 -304.038353)
			(xy 86.616463 -304.092304) (xy 86.601106 -304.144602) (xy 86.578462 -304.194181) (xy 86.548992 -304.240034)
			(xy 86.513296 -304.281225) (xy 86.472102 -304.316916) (xy 86.426246 -304.346381) (xy 86.376664 -304.36902)
			(xy 86.324365 -304.384372) (xy 86.270413 -304.392123) (xy 86.24316 -304.392584) (xy 86.216845 -304.392128)
			(xy 86.164713 -304.384901) (xy 86.114069 -304.370575) (xy 86.065876 -304.349424) (xy 86.021048 -304.321848)
			(xy 85.980437 -304.288372) (xy 85.944813 -304.24963) (xy 85.92947 -304.228246) (xy 85.923628 -304.21961)
			(xy 85.907118 -304.208942) (xy 85.816186 -304.192178) (xy 85.796882 -304.196242) (xy 85.7885 -304.202084)
			(xy 85.764571 -304.217872) (xy 85.712964 -304.242839) (xy 85.658202 -304.2598) (xy 85.601518 -304.268373)
			(xy 85.572854 -304.268886) (xy 85.545603 -304.268441) (xy 85.491657 -304.260679) (xy 85.439365 -304.245319)
			(xy 85.389791 -304.222674) (xy 85.343944 -304.193204) (xy 85.302757 -304.157511) (xy 85.267068 -304.116319)
			(xy 85.237604 -304.070469) (xy 85.214965 -304.020892) (xy 85.199611 -303.968598) (xy 85.191856 -303.914651)
			(xy 79.423781 -303.914651) (xy 79.429596 -303.949499) (xy 79.430118 -303.974754) (xy 79.429935 -303.988937)
			(xy 79.427267 -304.017177) (xy 79.424784 -304.031142) (xy 79.422498 -304.043588) (xy 79.429864 -304.06721)
			(xy 79.507334 -304.14468) (xy 79.530956 -304.152046) (xy 79.543402 -304.14976) (xy 79.557369 -304.147288)
			(xy 79.585608 -304.144613) (xy 79.59979 -304.144426) (xy 79.624611 -304.144867) (xy 79.6736 -304.152897)
			(xy 79.720645 -304.168746) (xy 79.764505 -304.191997) (xy 79.804027 -304.222038) (xy 79.838167 -304.258076)
			(xy 79.866028 -304.299163) (xy 79.886875 -304.344217) (xy 79.900158 -304.392049) (xy 79.905528 -304.4414)
			(xy 79.905077 -304.449734) (xy 80.243946 -304.449734) (xy 80.247906 -304.40068) (xy 80.259683 -304.352896)
			(xy 80.278974 -304.30762) (xy 80.305277 -304.266024) (xy 80.337912 -304.229187) (xy 80.376033 -304.198062)
			(xy 80.418654 -304.173455) (xy 80.46467 -304.156003) (xy 80.512889 -304.146159) (xy 80.562064 -304.144178)
			(xy 80.610919 -304.15011) (xy 80.65819 -304.163802) (xy 80.702652 -304.1849) (xy 80.743155 -304.212856)
			(xy 80.778648 -304.246948) (xy 80.808213 -304.286292) (xy 80.831084 -304.329869) (xy 80.846668 -304.37655)
			(xy 80.854563 -304.425127) (xy 80.855058 -304.449734) (xy 81.19416 -304.449734) (xy 81.19812 -304.40068)
			(xy 81.209897 -304.352896) (xy 81.229188 -304.30762) (xy 81.255491 -304.266024) (xy 81.288126 -304.229187)
			(xy 81.326247 -304.198062) (xy 81.368868 -304.173455) (xy 81.414884 -304.156003) (xy 81.463103 -304.146159)
			(xy 81.512278 -304.144178) (xy 81.561133 -304.15011) (xy 81.608404 -304.163802) (xy 81.652866 -304.1849)
			(xy 81.693369 -304.212856) (xy 81.728862 -304.246948) (xy 81.758427 -304.286292) (xy 81.781298 -304.329869)
			(xy 81.796882 -304.37655) (xy 81.804777 -304.425127) (xy 81.805272 -304.449734) (xy 82.14412 -304.449734)
			(xy 82.14808 -304.40068) (xy 82.159857 -304.352896) (xy 82.179148 -304.30762) (xy 82.205451 -304.266024)
			(xy 82.238086 -304.229187) (xy 82.276207 -304.198062) (xy 82.318828 -304.173455) (xy 82.364844 -304.156003)
			(xy 82.413063 -304.146159) (xy 82.462238 -304.144178) (xy 82.511093 -304.15011) (xy 82.558364 -304.163802)
			(xy 82.602826 -304.1849) (xy 82.643329 -304.212856) (xy 82.678822 -304.246948) (xy 82.708387 -304.286292)
			(xy 82.731258 -304.329869) (xy 82.746842 -304.37655) (xy 82.754737 -304.425127) (xy 82.755232 -304.449734)
			(xy 83.094334 -304.449734) (xy 83.098294 -304.40068) (xy 83.110071 -304.352896) (xy 83.129362 -304.30762)
			(xy 83.155665 -304.266024) (xy 83.1883 -304.229187) (xy 83.226421 -304.198062) (xy 83.269042 -304.173455)
			(xy 83.315058 -304.156003) (xy 83.363277 -304.146159) (xy 83.412452 -304.144178) (xy 83.461307 -304.15011)
			(xy 83.508578 -304.163802) (xy 83.55304 -304.1849) (xy 83.593543 -304.212856) (xy 83.629036 -304.246948)
			(xy 83.658601 -304.286292) (xy 83.681472 -304.329869) (xy 83.697056 -304.37655) (xy 83.704951 -304.425127)
			(xy 83.705446 -304.449734) (xy 83.704951 -304.474341) (xy 83.697056 -304.522918) (xy 83.681472 -304.569599)
			(xy 83.65973 -304.611024) (xy 87.60028 -304.611024) (xy 87.604351 -304.555402) (xy 87.616477 -304.500965)
			(xy 87.6364 -304.448874) (xy 87.663696 -304.400239) (xy 87.697782 -304.356096) (xy 87.737931 -304.317387)
			(xy 87.783289 -304.284936) (xy 87.832889 -304.259435) (xy 87.885673 -304.241428) (xy 87.940516 -304.231298)
			(xy 87.99625 -304.229261) (xy 88.051687 -304.235361) (xy 88.105644 -304.249467) (xy 88.156973 -304.271279)
			(xy 88.204579 -304.300333) (xy 88.247447 -304.336008) (xy 88.284664 -304.377545) (xy 88.315437 -304.424058)
			(xy 88.339109 -304.474555) (xy 88.355177 -304.527962) (xy 88.363297 -304.583138) (xy 88.363806 -304.611024)
			(xy 88.363297 -304.63891) (xy 88.355177 -304.694086) (xy 88.339109 -304.747493) (xy 88.315437 -304.79799)
			(xy 88.284664 -304.844503) (xy 88.247447 -304.88604) (xy 88.204579 -304.921715) (xy 88.156973 -304.950769)
			(xy 88.105644 -304.972581) (xy 88.051687 -304.986687) (xy 87.99625 -304.992787) (xy 87.940516 -304.99075)
			(xy 87.885673 -304.98062) (xy 87.832889 -304.962613) (xy 87.783289 -304.937112) (xy 87.737931 -304.904661)
			(xy 87.697782 -304.865952) (xy 87.663696 -304.821809) (xy 87.6364 -304.773174) (xy 87.616477 -304.721083)
			(xy 87.604351 -304.666646) (xy 87.60028 -304.611024) (xy 83.65973 -304.611024) (xy 83.658601 -304.613176)
			(xy 83.629036 -304.65252) (xy 83.593543 -304.686612) (xy 83.55304 -304.714568) (xy 83.508578 -304.735666)
			(xy 83.461307 -304.749358) (xy 83.412452 -304.75529) (xy 83.363277 -304.753309) (xy 83.315058 -304.743465)
			(xy 83.269042 -304.726013) (xy 83.226421 -304.701406) (xy 83.1883 -304.670281) (xy 83.155665 -304.633444)
			(xy 83.129362 -304.591848) (xy 83.110071 -304.546572) (xy 83.098294 -304.498788) (xy 83.094334 -304.449734)
			(xy 82.755232 -304.449734) (xy 82.754737 -304.474341) (xy 82.746842 -304.522918) (xy 82.731258 -304.569599)
			(xy 82.708387 -304.613176) (xy 82.678822 -304.65252) (xy 82.643329 -304.686612) (xy 82.602826 -304.714568)
			(xy 82.558364 -304.735666) (xy 82.511093 -304.749358) (xy 82.462238 -304.75529) (xy 82.413063 -304.753309)
			(xy 82.364844 -304.743465) (xy 82.318828 -304.726013) (xy 82.276207 -304.701406) (xy 82.238086 -304.670281)
			(xy 82.205451 -304.633444) (xy 82.179148 -304.591848) (xy 82.159857 -304.546572) (xy 82.14808 -304.498788)
			(xy 82.14412 -304.449734) (xy 81.805272 -304.449734) (xy 81.804777 -304.474341) (xy 81.796882 -304.522918)
			(xy 81.781298 -304.569599) (xy 81.758427 -304.613176) (xy 81.728862 -304.65252) (xy 81.693369 -304.686612)
			(xy 81.652866 -304.714568) (xy 81.608404 -304.735666) (xy 81.561133 -304.749358) (xy 81.512278 -304.75529)
			(xy 81.463103 -304.753309) (xy 81.414884 -304.743465) (xy 81.368868 -304.726013) (xy 81.326247 -304.701406)
			(xy 81.288126 -304.670281) (xy 81.255491 -304.633444) (xy 81.229188 -304.591848) (xy 81.209897 -304.546572)
			(xy 81.19812 -304.498788) (xy 81.19416 -304.449734) (xy 80.855058 -304.449734) (xy 80.854563 -304.474341)
			(xy 80.846668 -304.522918) (xy 80.831084 -304.569599) (xy 80.808213 -304.613176) (xy 80.778648 -304.65252)
			(xy 80.743155 -304.686612) (xy 80.702652 -304.714568) (xy 80.65819 -304.735666) (xy 80.610919 -304.749358)
			(xy 80.562064 -304.75529) (xy 80.512889 -304.753309) (xy 80.46467 -304.743465) (xy 80.418654 -304.726013)
			(xy 80.376033 -304.701406) (xy 80.337912 -304.670281) (xy 80.305277 -304.633444) (xy 80.278974 -304.591848)
			(xy 80.259683 -304.546572) (xy 80.247906 -304.498788) (xy 80.243946 -304.449734) (xy 79.905077 -304.449734)
			(xy 79.902844 -304.49097) (xy 79.892175 -304.539453) (xy 79.873804 -304.58557) (xy 79.848213 -304.628109)
			(xy 79.816078 -304.665947) (xy 79.778245 -304.698087) (xy 79.73571 -304.723684) (xy 79.689595 -304.742062)
			(xy 79.641114 -304.752738) (xy 79.591544 -304.75543) (xy 79.542192 -304.750067) (xy 79.494358 -304.73679)
			(xy 79.449302 -304.71595) (xy 79.408211 -304.688095) (xy 79.372167 -304.653959) (xy 79.342121 -304.614442)
			(xy 79.318863 -304.570585) (xy 79.303007 -304.523543) (xy 79.294971 -304.474555) (xy 79.294482 -304.449734)
			(xy 79.294664 -304.435551) (xy 79.297332 -304.407311) (xy 79.299816 -304.393346) (xy 79.302102 -304.3809)
			(xy 79.294736 -304.357278) (xy 79.217266 -304.279808) (xy 79.193644 -304.272442) (xy 79.181198 -304.274728)
			(xy 79.167232 -304.277201) (xy 79.138992 -304.279875) (xy 79.12481 -304.280062) (xy 79.110627 -304.279885)
			(xy 79.082387 -304.277213) (xy 79.068422 -304.274728) (xy 79.055976 -304.272442) (xy 79.032354 -304.279808)
			(xy 78.954884 -304.357278) (xy 78.947518 -304.3809) (xy 78.949804 -304.393346) (xy 78.952283 -304.407311)
			(xy 78.954953 -304.435551) (xy 78.955138 -304.449734) (xy 78.954585 -304.474552) (xy 78.94655 -304.523533)
			(xy 78.930696 -304.570569) (xy 78.907441 -304.614421) (xy 78.877398 -304.653932) (xy 78.841359 -304.688063)
			(xy 78.800273 -304.715914) (xy 78.755222 -304.736751) (xy 78.707394 -304.750024) (xy 78.658048 -304.755386)
			(xy 78.608485 -304.752693) (xy 78.560011 -304.742018) (xy 78.513902 -304.723641) (xy 78.471374 -304.698046)
			(xy 78.433546 -304.665908) (xy 78.401416 -304.628074) (xy 78.375831 -304.585541) (xy 78.357463 -304.539428)
			(xy 78.346798 -304.490951) (xy 78.344116 -304.441388) (xy 78.00501 -304.441388) (xy 78.005178 -304.449734)
			(xy 78.004683 -304.474341) (xy 77.996788 -304.522918) (xy 77.981204 -304.569599) (xy 77.958333 -304.613176)
			(xy 77.928768 -304.65252) (xy 77.893275 -304.686612) (xy 77.852772 -304.714568) (xy 77.80831 -304.735666)
			(xy 77.761039 -304.749358) (xy 77.712184 -304.75529) (xy 77.663009 -304.753309) (xy 77.61479 -304.743465)
			(xy 77.568774 -304.726013) (xy 77.526153 -304.701406) (xy 77.488032 -304.670281) (xy 77.455397 -304.633444)
			(xy 77.429094 -304.591848) (xy 77.409803 -304.546572) (xy 77.398026 -304.498788) (xy 77.394066 -304.449734)
			(xy 77.055218 -304.449734) (xy 77.054723 -304.474341) (xy 77.046828 -304.522918) (xy 77.031244 -304.569599)
			(xy 77.008373 -304.613176) (xy 76.978808 -304.65252) (xy 76.943315 -304.686612) (xy 76.902812 -304.714568)
			(xy 76.85835 -304.735666) (xy 76.811079 -304.749358) (xy 76.762224 -304.75529) (xy 76.713049 -304.753309)
			(xy 76.66483 -304.743465) (xy 76.618814 -304.726013) (xy 76.576193 -304.701406) (xy 76.538072 -304.670281)
			(xy 76.505437 -304.633444) (xy 76.479134 -304.591848) (xy 76.459843 -304.546572) (xy 76.448066 -304.498788)
			(xy 76.444106 -304.449734) (xy 76.127102 -304.449734) (xy 76.126598 -304.475442) (xy 76.118555 -304.526224)
			(xy 76.102667 -304.575123) (xy 76.079324 -304.620935) (xy 76.049103 -304.662531) (xy 76.012747 -304.698887)
			(xy 75.971151 -304.729108) (xy 75.925339 -304.752451) (xy 75.87644 -304.768339) (xy 75.825658 -304.776382)
			(xy 75.774242 -304.776382) (xy 75.72346 -304.768339) (xy 75.674561 -304.752451) (xy 75.628749 -304.729108)
			(xy 75.587153 -304.698887) (xy 75.550797 -304.662531) (xy 75.520576 -304.620935) (xy 75.497233 -304.575123)
			(xy 75.481345 -304.526224) (xy 75.473302 -304.475442) (xy 75.176638 -304.475442) (xy 75.168595 -304.526224)
			(xy 75.152707 -304.575123) (xy 75.129364 -304.620935) (xy 75.099143 -304.662531) (xy 75.062787 -304.698887)
			(xy 75.021191 -304.729108) (xy 74.975379 -304.752451) (xy 74.92648 -304.768339) (xy 74.875698 -304.776382)
			(xy 74.824282 -304.776382) (xy 74.7735 -304.768339) (xy 74.724601 -304.752451) (xy 74.678789 -304.729108)
			(xy 74.637193 -304.698887) (xy 74.600837 -304.662531) (xy 74.570616 -304.620935) (xy 74.547273 -304.575123)
			(xy 74.531385 -304.526224) (xy 74.523342 -304.475442) (xy 74.20441 -304.475442) (xy 74.196694 -304.522918)
			(xy 74.18111 -304.569599) (xy 74.158239 -304.613176) (xy 74.128674 -304.65252) (xy 74.093181 -304.686612)
			(xy 74.052678 -304.714568) (xy 74.008216 -304.735666) (xy 73.960945 -304.749358) (xy 73.91209 -304.75529)
			(xy 73.862915 -304.753309) (xy 73.814696 -304.743465) (xy 73.76868 -304.726013) (xy 73.726059 -304.701406)
			(xy 73.687938 -304.670281) (xy 73.655303 -304.633444) (xy 73.629 -304.591848) (xy 73.609709 -304.546572)
			(xy 73.597932 -304.498788) (xy 73.593972 -304.449734) (xy 49.149254 -304.449734) (xy 49.149254 -304.924714)
			(xy 49.368976 -304.924714) (xy 49.372936 -304.87566) (xy 49.384713 -304.827876) (xy 49.404004 -304.7826)
			(xy 49.430307 -304.741004) (xy 49.462942 -304.704167) (xy 49.501063 -304.673042) (xy 49.543684 -304.648435)
			(xy 49.5897 -304.630983) (xy 49.637919 -304.621139) (xy 49.687094 -304.619158) (xy 49.735949 -304.62509)
			(xy 49.78322 -304.638782) (xy 49.827682 -304.65988) (xy 49.868185 -304.687836) (xy 49.903678 -304.721928)
			(xy 49.933243 -304.761272) (xy 49.956114 -304.804849) (xy 49.971698 -304.85153) (xy 49.979593 -304.900107)
			(xy 49.980088 -304.924714) (xy 50.31919 -304.924714) (xy 50.32315 -304.87566) (xy 50.334927 -304.827876)
			(xy 50.354218 -304.7826) (xy 50.380521 -304.741004) (xy 50.413156 -304.704167) (xy 50.451277 -304.673042)
			(xy 50.493898 -304.648435) (xy 50.539914 -304.630983) (xy 50.588133 -304.621139) (xy 50.637308 -304.619158)
			(xy 50.686163 -304.62509) (xy 50.733434 -304.638782) (xy 50.777896 -304.65988) (xy 50.818399 -304.687836)
			(xy 50.853892 -304.721928) (xy 50.883457 -304.761272) (xy 50.906328 -304.804849) (xy 50.921912 -304.85153)
			(xy 50.929807 -304.900107) (xy 50.930302 -304.924714) (xy 51.26915 -304.924714) (xy 51.27311 -304.87566)
			(xy 51.284887 -304.827876) (xy 51.304178 -304.7826) (xy 51.330481 -304.741004) (xy 51.363116 -304.704167)
			(xy 51.401237 -304.673042) (xy 51.443858 -304.648435) (xy 51.489874 -304.630983) (xy 51.538093 -304.621139)
			(xy 51.587268 -304.619158) (xy 51.636123 -304.62509) (xy 51.683394 -304.638782) (xy 51.727856 -304.65988)
			(xy 51.768359 -304.687836) (xy 51.803852 -304.721928) (xy 51.833417 -304.761272) (xy 51.856288 -304.804849)
			(xy 51.871872 -304.85153) (xy 51.879767 -304.900107) (xy 51.880262 -304.924714) (xy 52.21911 -304.924714)
			(xy 52.22307 -304.87566) (xy 52.234847 -304.827876) (xy 52.254138 -304.7826) (xy 52.280441 -304.741004)
			(xy 52.313076 -304.704167) (xy 52.351197 -304.673042) (xy 52.393818 -304.648435) (xy 52.439834 -304.630983)
			(xy 52.488053 -304.621139) (xy 52.537228 -304.619158) (xy 52.586083 -304.62509) (xy 52.633354 -304.638782)
			(xy 52.677816 -304.65988) (xy 52.718319 -304.687836) (xy 52.753812 -304.721928) (xy 52.783377 -304.761272)
			(xy 52.806248 -304.804849) (xy 52.821832 -304.85153) (xy 52.829727 -304.900107) (xy 52.830222 -304.924714)
			(xy 53.16907 -304.924714) (xy 53.17303 -304.87566) (xy 53.184807 -304.827876) (xy 53.204098 -304.7826)
			(xy 53.230401 -304.741004) (xy 53.263036 -304.704167) (xy 53.301157 -304.673042) (xy 53.343778 -304.648435)
			(xy 53.389794 -304.630983) (xy 53.438013 -304.621139) (xy 53.487188 -304.619158) (xy 53.536043 -304.62509)
			(xy 53.583314 -304.638782) (xy 53.627776 -304.65988) (xy 53.668279 -304.687836) (xy 53.703772 -304.721928)
			(xy 53.733337 -304.761272) (xy 53.756208 -304.804849) (xy 53.771792 -304.85153) (xy 53.779687 -304.900107)
			(xy 53.780182 -304.924714) (xy 54.11903 -304.924714) (xy 54.12299 -304.87566) (xy 54.134767 -304.827876)
			(xy 54.154058 -304.7826) (xy 54.180361 -304.741004) (xy 54.212996 -304.704167) (xy 54.251117 -304.673042)
			(xy 54.293738 -304.648435) (xy 54.339754 -304.630983) (xy 54.387973 -304.621139) (xy 54.437148 -304.619158)
			(xy 54.486003 -304.62509) (xy 54.533274 -304.638782) (xy 54.577736 -304.65988) (xy 54.618239 -304.687836)
			(xy 54.653732 -304.721928) (xy 54.683297 -304.761272) (xy 54.706168 -304.804849) (xy 54.721752 -304.85153)
			(xy 54.729647 -304.900107) (xy 54.730142 -304.924714) (xy 55.06899 -304.924714) (xy 55.07295 -304.87566)
			(xy 55.084727 -304.827876) (xy 55.104018 -304.7826) (xy 55.130321 -304.741004) (xy 55.162956 -304.704167)
			(xy 55.201077 -304.673042) (xy 55.243698 -304.648435) (xy 55.289714 -304.630983) (xy 55.337933 -304.621139)
			(xy 55.387108 -304.619158) (xy 55.435963 -304.62509) (xy 55.483234 -304.638782) (xy 55.527696 -304.65988)
			(xy 55.568199 -304.687836) (xy 55.603692 -304.721928) (xy 55.633257 -304.761272) (xy 55.656128 -304.804849)
			(xy 55.671712 -304.85153) (xy 55.679607 -304.900107) (xy 55.680102 -304.924714) (xy 56.01895 -304.924714)
			(xy 56.02291 -304.87566) (xy 56.034687 -304.827876) (xy 56.053978 -304.7826) (xy 56.080281 -304.741004)
			(xy 56.112916 -304.704167) (xy 56.151037 -304.673042) (xy 56.193658 -304.648435) (xy 56.239674 -304.630983)
			(xy 56.287893 -304.621139) (xy 56.337068 -304.619158) (xy 56.385923 -304.62509) (xy 56.433194 -304.638782)
			(xy 56.477656 -304.65988) (xy 56.518159 -304.687836) (xy 56.553652 -304.721928) (xy 56.583217 -304.761272)
			(xy 56.606088 -304.804849) (xy 56.621672 -304.85153) (xy 56.629567 -304.900107) (xy 56.630062 -304.924714)
			(xy 56.969164 -304.924714) (xy 56.973124 -304.87566) (xy 56.984901 -304.827876) (xy 57.004192 -304.7826)
			(xy 57.030495 -304.741004) (xy 57.06313 -304.704167) (xy 57.101251 -304.673042) (xy 57.143872 -304.648435)
			(xy 57.189888 -304.630983) (xy 57.238107 -304.621139) (xy 57.287282 -304.619158) (xy 57.336137 -304.62509)
			(xy 57.383408 -304.638782) (xy 57.42787 -304.65988) (xy 57.468373 -304.687836) (xy 57.503866 -304.721928)
			(xy 57.533431 -304.761272) (xy 57.556302 -304.804849) (xy 57.571886 -304.85153) (xy 57.579781 -304.900107)
			(xy 57.580276 -304.924714) (xy 57.919124 -304.924714) (xy 57.923084 -304.87566) (xy 57.934861 -304.827876)
			(xy 57.954152 -304.7826) (xy 57.980455 -304.741004) (xy 58.01309 -304.704167) (xy 58.051211 -304.673042)
			(xy 58.093832 -304.648435) (xy 58.139848 -304.630983) (xy 58.188067 -304.621139) (xy 58.237242 -304.619158)
			(xy 58.286097 -304.62509) (xy 58.333368 -304.638782) (xy 58.37783 -304.65988) (xy 58.418333 -304.687836)
			(xy 58.453826 -304.721928) (xy 58.483391 -304.761272) (xy 58.506262 -304.804849) (xy 58.521846 -304.85153)
			(xy 58.529741 -304.900107) (xy 58.530236 -304.924714) (xy 59.819044 -304.924714) (xy 59.823004 -304.87566)
			(xy 59.834781 -304.827876) (xy 59.854072 -304.7826) (xy 59.880375 -304.741004) (xy 59.91301 -304.704167)
			(xy 59.951131 -304.673042) (xy 59.993752 -304.648435) (xy 60.039768 -304.630983) (xy 60.087987 -304.621139)
			(xy 60.137162 -304.619158) (xy 60.186017 -304.62509) (xy 60.233288 -304.638782) (xy 60.27775 -304.65988)
			(xy 60.318253 -304.687836) (xy 60.353746 -304.721928) (xy 60.383311 -304.761272) (xy 60.406182 -304.804849)
			(xy 60.421766 -304.85153) (xy 60.429661 -304.900107) (xy 60.430156 -304.924714) (xy 60.769004 -304.924714)
			(xy 60.772964 -304.87566) (xy 60.784741 -304.827876) (xy 60.804032 -304.7826) (xy 60.830335 -304.741004)
			(xy 60.86297 -304.704167) (xy 60.901091 -304.673042) (xy 60.943712 -304.648435) (xy 60.989728 -304.630983)
			(xy 61.037947 -304.621139) (xy 61.087122 -304.619158) (xy 61.135977 -304.62509) (xy 61.183248 -304.638782)
			(xy 61.22771 -304.65988) (xy 61.268213 -304.687836) (xy 61.303706 -304.721928) (xy 61.333271 -304.761272)
			(xy 61.356142 -304.804849) (xy 61.371726 -304.85153) (xy 61.379621 -304.900107) (xy 61.380116 -304.924714)
			(xy 61.718964 -304.924714) (xy 61.722924 -304.87566) (xy 61.734701 -304.827876) (xy 61.753992 -304.7826)
			(xy 61.780295 -304.741004) (xy 61.81293 -304.704167) (xy 61.851051 -304.673042) (xy 61.893672 -304.648435)
			(xy 61.939688 -304.630983) (xy 61.987907 -304.621139) (xy 62.037082 -304.619158) (xy 62.085937 -304.62509)
			(xy 62.133208 -304.638782) (xy 62.17767 -304.65988) (xy 62.218173 -304.687836) (xy 62.253666 -304.721928)
			(xy 62.283231 -304.761272) (xy 62.306102 -304.804849) (xy 62.321686 -304.85153) (xy 62.329581 -304.900107)
			(xy 62.330076 -304.924714) (xy 62.669178 -304.924714) (xy 62.673138 -304.87566) (xy 62.684915 -304.827876)
			(xy 62.704206 -304.7826) (xy 62.730509 -304.741004) (xy 62.763144 -304.704167) (xy 62.801265 -304.673042)
			(xy 62.843886 -304.648435) (xy 62.889902 -304.630983) (xy 62.938121 -304.621139) (xy 62.987296 -304.619158)
			(xy 63.036151 -304.62509) (xy 63.083422 -304.638782) (xy 63.127884 -304.65988) (xy 63.168387 -304.687836)
			(xy 63.20388 -304.721928) (xy 63.233445 -304.761272) (xy 63.256316 -304.804849) (xy 63.2719 -304.85153)
			(xy 63.279795 -304.900107) (xy 63.28029 -304.924714) (xy 63.619138 -304.924714) (xy 63.623098 -304.87566)
			(xy 63.634875 -304.827876) (xy 63.654166 -304.7826) (xy 63.680469 -304.741004) (xy 63.713104 -304.704167)
			(xy 63.751225 -304.673042) (xy 63.793846 -304.648435) (xy 63.839862 -304.630983) (xy 63.888081 -304.621139)
			(xy 63.937256 -304.619158) (xy 63.986111 -304.62509) (xy 64.033382 -304.638782) (xy 64.077844 -304.65988)
			(xy 64.118347 -304.687836) (xy 64.15384 -304.721928) (xy 64.183405 -304.761272) (xy 64.206276 -304.804849)
			(xy 64.22186 -304.85153) (xy 64.229755 -304.900107) (xy 64.23025 -304.924714) (xy 64.569098 -304.924714)
			(xy 64.573058 -304.87566) (xy 64.584835 -304.827876) (xy 64.604126 -304.7826) (xy 64.630429 -304.741004)
			(xy 64.663064 -304.704167) (xy 64.701185 -304.673042) (xy 64.743806 -304.648435) (xy 64.789822 -304.630983)
			(xy 64.838041 -304.621139) (xy 64.887216 -304.619158) (xy 64.936071 -304.62509) (xy 64.983342 -304.638782)
			(xy 65.027804 -304.65988) (xy 65.068307 -304.687836) (xy 65.1038 -304.721928) (xy 65.133365 -304.761272)
			(xy 65.156236 -304.804849) (xy 65.17182 -304.85153) (xy 65.179715 -304.900107) (xy 65.18021 -304.924714)
			(xy 65.519058 -304.924714) (xy 65.523018 -304.87566) (xy 65.534795 -304.827876) (xy 65.554086 -304.7826)
			(xy 65.580389 -304.741004) (xy 65.613024 -304.704167) (xy 65.651145 -304.673042) (xy 65.693766 -304.648435)
			(xy 65.739782 -304.630983) (xy 65.788001 -304.621139) (xy 65.837176 -304.619158) (xy 65.886031 -304.62509)
			(xy 65.933302 -304.638782) (xy 65.977764 -304.65988) (xy 66.018267 -304.687836) (xy 66.05376 -304.721928)
			(xy 66.083325 -304.761272) (xy 66.106196 -304.804849) (xy 66.12178 -304.85153) (xy 66.129675 -304.900107)
			(xy 66.13017 -304.924714) (xy 66.469018 -304.924714) (xy 66.472978 -304.87566) (xy 66.484755 -304.827876)
			(xy 66.504046 -304.7826) (xy 66.530349 -304.741004) (xy 66.562984 -304.704167) (xy 66.601105 -304.673042)
			(xy 66.643726 -304.648435) (xy 66.689742 -304.630983) (xy 66.737961 -304.621139) (xy 66.787136 -304.619158)
			(xy 66.835991 -304.62509) (xy 66.883262 -304.638782) (xy 66.927724 -304.65988) (xy 66.968227 -304.687836)
			(xy 67.00372 -304.721928) (xy 67.033285 -304.761272) (xy 67.056156 -304.804849) (xy 67.07174 -304.85153)
			(xy 67.079635 -304.900107) (xy 67.08013 -304.924714) (xy 67.418978 -304.924714) (xy 67.422938 -304.87566)
			(xy 67.434715 -304.827876) (xy 67.454006 -304.7826) (xy 67.480309 -304.741004) (xy 67.512944 -304.704167)
			(xy 67.551065 -304.673042) (xy 67.593686 -304.648435) (xy 67.639702 -304.630983) (xy 67.687921 -304.621139)
			(xy 67.737096 -304.619158) (xy 67.785951 -304.62509) (xy 67.833222 -304.638782) (xy 67.877684 -304.65988)
			(xy 67.918187 -304.687836) (xy 67.95368 -304.721928) (xy 67.983245 -304.761272) (xy 68.006116 -304.804849)
			(xy 68.0217 -304.85153) (xy 68.029595 -304.900107) (xy 68.03009 -304.924714) (xy 68.368938 -304.924714)
			(xy 68.372898 -304.87566) (xy 68.384675 -304.827876) (xy 68.403966 -304.7826) (xy 68.430269 -304.741004)
			(xy 68.462904 -304.704167) (xy 68.501025 -304.673042) (xy 68.543646 -304.648435) (xy 68.589662 -304.630983)
			(xy 68.637881 -304.621139) (xy 68.687056 -304.619158) (xy 68.735911 -304.62509) (xy 68.783182 -304.638782)
			(xy 68.827644 -304.65988) (xy 68.868147 -304.687836) (xy 68.90364 -304.721928) (xy 68.933205 -304.761272)
			(xy 68.956076 -304.804849) (xy 68.97166 -304.85153) (xy 68.979555 -304.900107) (xy 68.98005 -304.924714)
			(xy 69.319152 -304.924714) (xy 69.323112 -304.87566) (xy 69.334889 -304.827876) (xy 69.35418 -304.7826)
			(xy 69.380483 -304.741004) (xy 69.413118 -304.704167) (xy 69.451239 -304.673042) (xy 69.49386 -304.648435)
			(xy 69.539876 -304.630983) (xy 69.588095 -304.621139) (xy 69.63727 -304.619158) (xy 69.686125 -304.62509)
			(xy 69.733396 -304.638782) (xy 69.777858 -304.65988) (xy 69.818361 -304.687836) (xy 69.853854 -304.721928)
			(xy 69.883419 -304.761272) (xy 69.90629 -304.804849) (xy 69.921874 -304.85153) (xy 69.929769 -304.900107)
			(xy 69.930264 -304.924714) (xy 70.269112 -304.924714) (xy 70.273072 -304.87566) (xy 70.284849 -304.827876)
			(xy 70.30414 -304.7826) (xy 70.330443 -304.741004) (xy 70.363078 -304.704167) (xy 70.401199 -304.673042)
			(xy 70.44382 -304.648435) (xy 70.489836 -304.630983) (xy 70.538055 -304.621139) (xy 70.58723 -304.619158)
			(xy 70.636085 -304.62509) (xy 70.683356 -304.638782) (xy 70.727818 -304.65988) (xy 70.768321 -304.687836)
			(xy 70.803814 -304.721928) (xy 70.833379 -304.761272) (xy 70.85625 -304.804849) (xy 70.871834 -304.85153)
			(xy 70.879729 -304.900107) (xy 70.880224 -304.924714) (xy 71.219072 -304.924714) (xy 71.223032 -304.87566)
			(xy 71.234809 -304.827876) (xy 71.2541 -304.7826) (xy 71.280403 -304.741004) (xy 71.313038 -304.704167)
			(xy 71.351159 -304.673042) (xy 71.39378 -304.648435) (xy 71.439796 -304.630983) (xy 71.488015 -304.621139)
			(xy 71.53719 -304.619158) (xy 71.586045 -304.62509) (xy 71.633316 -304.638782) (xy 71.677778 -304.65988)
			(xy 71.718281 -304.687836) (xy 71.753774 -304.721928) (xy 71.783339 -304.761272) (xy 71.80621 -304.804849)
			(xy 71.821794 -304.85153) (xy 71.829689 -304.900107) (xy 71.830184 -304.924714) (xy 72.169032 -304.924714)
			(xy 72.172992 -304.87566) (xy 72.184769 -304.827876) (xy 72.20406 -304.7826) (xy 72.230363 -304.741004)
			(xy 72.262998 -304.704167) (xy 72.301119 -304.673042) (xy 72.34374 -304.648435) (xy 72.389756 -304.630983)
			(xy 72.437975 -304.621139) (xy 72.48715 -304.619158) (xy 72.536005 -304.62509) (xy 72.583276 -304.638782)
			(xy 72.627738 -304.65988) (xy 72.668241 -304.687836) (xy 72.703734 -304.721928) (xy 72.733299 -304.761272)
			(xy 72.75617 -304.804849) (xy 72.771754 -304.85153) (xy 72.779649 -304.900107) (xy 72.780144 -304.924714)
			(xy 72.779649 -304.949321) (xy 72.771754 -304.997898) (xy 72.75617 -305.044579) (xy 72.745493 -305.064922)
			(xy 88.62009 -305.064922) (xy 88.624161 -305.0093) (xy 88.636287 -304.954863) (xy 88.65621 -304.902772)
			(xy 88.683506 -304.854137) (xy 88.717592 -304.809994) (xy 88.757741 -304.771285) (xy 88.803099 -304.738834)
			(xy 88.852699 -304.713333) (xy 88.905483 -304.695326) (xy 88.960326 -304.685196) (xy 89.01606 -304.683159)
			(xy 89.071497 -304.689259) (xy 89.125454 -304.703365) (xy 89.176783 -304.725177) (xy 89.224389 -304.754231)
			(xy 89.267257 -304.789906) (xy 89.304474 -304.831443) (xy 89.335247 -304.877956) (xy 89.358919 -304.928453)
			(xy 89.374987 -304.98186) (xy 89.383107 -305.037036) (xy 89.383616 -305.064922) (xy 89.635074 -305.064922)
			(xy 89.639145 -305.0093) (xy 89.651271 -304.954863) (xy 89.671194 -304.902772) (xy 89.69849 -304.854137)
			(xy 89.732576 -304.809994) (xy 89.772725 -304.771285) (xy 89.818083 -304.738834) (xy 89.867683 -304.713333)
			(xy 89.920467 -304.695326) (xy 89.97531 -304.685196) (xy 90.031044 -304.683159) (xy 90.086481 -304.689259)
			(xy 90.140438 -304.703365) (xy 90.191767 -304.725177) (xy 90.239373 -304.754231) (xy 90.282241 -304.789906)
			(xy 90.319458 -304.831443) (xy 90.350231 -304.877956) (xy 90.373903 -304.928453) (xy 90.389971 -304.98186)
			(xy 90.398091 -305.037036) (xy 90.3986 -305.064922) (xy 90.643454 -305.064922) (xy 90.647525 -305.0093)
			(xy 90.659651 -304.954863) (xy 90.679574 -304.902772) (xy 90.70687 -304.854137) (xy 90.740956 -304.809994)
			(xy 90.781105 -304.771285) (xy 90.826463 -304.738834) (xy 90.876063 -304.713333) (xy 90.928847 -304.695326)
			(xy 90.98369 -304.685196) (xy 91.039424 -304.683159) (xy 91.094861 -304.689259) (xy 91.148818 -304.703365)
			(xy 91.200147 -304.725177) (xy 91.247753 -304.754231) (xy 91.290621 -304.789906) (xy 91.327838 -304.831443)
			(xy 91.358611 -304.877956) (xy 91.382283 -304.928453) (xy 91.398351 -304.98186) (xy 91.406471 -305.037036)
			(xy 91.406961 -305.063906) (xy 91.66809 -305.063906) (xy 91.672161 -305.008284) (xy 91.684287 -304.953847)
			(xy 91.70421 -304.901756) (xy 91.731506 -304.853121) (xy 91.765592 -304.808978) (xy 91.805741 -304.770269)
			(xy 91.851099 -304.737818) (xy 91.900699 -304.712317) (xy 91.953483 -304.69431) (xy 92.008326 -304.68418)
			(xy 92.06406 -304.682143) (xy 92.119497 -304.688243) (xy 92.173454 -304.702349) (xy 92.224783 -304.724161)
			(xy 92.272389 -304.753215) (xy 92.315257 -304.78889) (xy 92.352474 -304.830427) (xy 92.383247 -304.87694)
			(xy 92.406919 -304.927437) (xy 92.422987 -304.980844) (xy 92.431107 -305.03602) (xy 92.431291 -305.046126)
			(xy 92.68409 -305.046126) (xy 92.688161 -304.990504) (xy 92.700287 -304.936067) (xy 92.72021 -304.883976)
			(xy 92.747506 -304.835341) (xy 92.781592 -304.791198) (xy 92.821741 -304.752489) (xy 92.867099 -304.720038)
			(xy 92.916699 -304.694537) (xy 92.969483 -304.67653) (xy 93.024326 -304.6664) (xy 93.08006 -304.664363)
			(xy 93.135497 -304.670463) (xy 93.189454 -304.684569) (xy 93.240783 -304.706381) (xy 93.288389 -304.735435)
			(xy 93.331257 -304.77111) (xy 93.368474 -304.812647) (xy 93.399247 -304.85916) (xy 93.422919 -304.909657)
			(xy 93.438987 -304.963064) (xy 93.445679 -305.008534) (xy 102.235508 -305.008534) (xy 102.235992 -304.981164)
			(xy 102.243805 -304.926986) (xy 102.25929 -304.874483) (xy 102.282128 -304.824736) (xy 102.311849 -304.778768)
			(xy 102.329488 -304.757836) (xy 102.335584 -304.750724) (xy 102.341934 -304.733706) (xy 102.341934 -304.648362)
			(xy 102.335584 -304.631344) (xy 102.329488 -304.624232) (xy 102.311849 -304.6033) (xy 102.282137 -304.557327)
			(xy 102.259302 -304.50758) (xy 102.24381 -304.455079) (xy 102.235982 -304.400903) (xy 102.235508 -304.373534)
			(xy 102.235994 -304.346283) (xy 102.24375 -304.292335) (xy 102.259105 -304.24004) (xy 102.281747 -304.190463)
			(xy 102.311213 -304.144613) (xy 102.346904 -304.103422) (xy 102.388095 -304.067731) (xy 102.433945 -304.038265)
			(xy 102.483522 -304.015623) (xy 102.535817 -304.000268) (xy 102.589765 -303.992512) (xy 102.644267 -303.992512)
			(xy 102.698215 -304.000268) (xy 102.75051 -304.015623) (xy 102.800087 -304.038265) (xy 102.845937 -304.067731)
			(xy 102.887128 -304.103422) (xy 102.922819 -304.144613) (xy 102.952285 -304.190463) (xy 102.974927 -304.24004)
			(xy 102.990282 -304.292335) (xy 102.998038 -304.346283) (xy 102.998524 -304.373534) (xy 102.998096 -304.400906)
			(xy 102.990272 -304.455087) (xy 102.974775 -304.507592) (xy 102.951924 -304.557338) (xy 102.92219 -304.603302)
			(xy 102.904544 -304.624232) (xy 102.898448 -304.631344) (xy 102.892098 -304.648362) (xy 102.892098 -304.733706)
			(xy 102.898448 -304.750724) (xy 102.904544 -304.757836) (xy 102.922174 -304.778775) (xy 102.951886 -304.824747)
			(xy 102.974723 -304.874493) (xy 102.990216 -304.926991) (xy 102.998048 -304.981165) (xy 102.998524 -305.008534)
			(xy 105.655618 -305.008534) (xy 105.6561 -304.981164) (xy 105.663913 -304.926986) (xy 105.679398 -304.874483)
			(xy 105.702237 -304.824735) (xy 105.731958 -304.778768) (xy 105.749598 -304.757836) (xy 105.755694 -304.750724)
			(xy 105.762044 -304.733706) (xy 105.762044 -304.648362) (xy 105.755694 -304.631344) (xy 105.749598 -304.624232)
			(xy 105.73196 -304.603299) (xy 105.702248 -304.557326) (xy 105.679412 -304.507579) (xy 105.663921 -304.455079)
			(xy 105.656092 -304.400903) (xy 105.655618 -304.373534) (xy 105.656104 -304.346283) (xy 105.66386 -304.292335)
			(xy 105.679215 -304.24004) (xy 105.701857 -304.190463) (xy 105.731323 -304.144613) (xy 105.767014 -304.103422)
			(xy 105.808205 -304.067731) (xy 105.854055 -304.038265) (xy 105.903632 -304.015623) (xy 105.955927 -304.000268)
			(xy 106.009875 -303.992512) (xy 106.064377 -303.992512) (xy 106.118325 -304.000268) (xy 106.17062 -304.015623)
			(xy 106.220197 -304.038265) (xy 106.266047 -304.067731) (xy 106.307238 -304.103422) (xy 106.342929 -304.144613)
			(xy 106.372395 -304.190463) (xy 106.395037 -304.24004) (xy 106.410392 -304.292335) (xy 106.418148 -304.346283)
			(xy 106.418634 -304.373534) (xy 106.418204 -304.400906) (xy 106.41038 -304.455087) (xy 106.394883 -304.507591)
			(xy 106.372033 -304.557337) (xy 106.3423 -304.603302) (xy 106.324654 -304.624232) (xy 106.318558 -304.631344)
			(xy 106.312208 -304.648362) (xy 106.312208 -304.733706) (xy 106.318558 -304.750724) (xy 106.324654 -304.757836)
			(xy 106.342269 -304.778787) (xy 106.371986 -304.824754) (xy 106.394828 -304.874497) (xy 106.410324 -304.926993)
			(xy 106.418157 -304.981166) (xy 106.418634 -305.008534) (xy 107.043728 -305.008534) (xy 107.044207 -304.981164)
			(xy 107.052021 -304.926985) (xy 107.067506 -304.874482) (xy 107.090345 -304.824735) (xy 107.120068 -304.778768)
			(xy 107.137708 -304.757836) (xy 107.143804 -304.750724) (xy 107.150154 -304.733706) (xy 107.150154 -304.648362)
			(xy 107.143804 -304.631344) (xy 107.137708 -304.624232) (xy 107.120072 -304.603298) (xy 107.090359 -304.557326)
			(xy 107.067523 -304.507579) (xy 107.052031 -304.455078) (xy 107.044202 -304.400903) (xy 107.043728 -304.373534)
			(xy 107.044214 -304.346283) (xy 107.05197 -304.292335) (xy 107.067325 -304.24004) (xy 107.089967 -304.190463)
			(xy 107.119433 -304.144613) (xy 107.155124 -304.103422) (xy 107.196315 -304.067731) (xy 107.242165 -304.038265)
			(xy 107.291742 -304.015623) (xy 107.344037 -304.000268) (xy 107.397985 -303.992512) (xy 107.452487 -303.992512)
			(xy 107.506435 -304.000268) (xy 107.55873 -304.015623) (xy 107.608307 -304.038265) (xy 107.654157 -304.067731)
			(xy 107.695348 -304.103422) (xy 107.731039 -304.144613) (xy 107.760505 -304.190463) (xy 107.783147 -304.24004)
			(xy 107.798502 -304.292335) (xy 107.806258 -304.346283) (xy 107.806744 -304.373534) (xy 107.806312 -304.400906)
			(xy 107.798488 -304.455087) (xy 107.782992 -304.507591) (xy 107.760142 -304.557337) (xy 107.730409 -304.603302)
			(xy 107.712764 -304.624232) (xy 107.706668 -304.631344) (xy 107.700318 -304.648362) (xy 107.700318 -304.733706)
			(xy 107.706668 -304.750724) (xy 107.712764 -304.757836) (xy 107.730381 -304.778786) (xy 107.760097 -304.824753)
			(xy 107.782938 -304.874496) (xy 107.798434 -304.926993) (xy 107.806267 -304.981166) (xy 107.806744 -305.008534)
			(xy 109.075728 -305.008534) (xy 109.076207 -304.981164) (xy 109.084021 -304.926985) (xy 109.099506 -304.874482)
			(xy 109.122345 -304.824735) (xy 109.152068 -304.778768) (xy 109.169708 -304.757836) (xy 109.175804 -304.750724)
			(xy 109.182154 -304.733706) (xy 109.182154 -304.648362) (xy 109.175804 -304.631344) (xy 109.169708 -304.624232)
			(xy 109.152072 -304.603298) (xy 109.122359 -304.557326) (xy 109.099523 -304.507579) (xy 109.084031 -304.455078)
			(xy 109.076202 -304.400903) (xy 109.075728 -304.373534) (xy 109.076214 -304.346283) (xy 109.08397 -304.292335)
			(xy 109.099325 -304.24004) (xy 109.121967 -304.190463) (xy 109.151433 -304.144613) (xy 109.187124 -304.103422)
			(xy 109.228315 -304.067731) (xy 109.274165 -304.038265) (xy 109.323742 -304.015623) (xy 109.376037 -304.000268)
			(xy 109.429985 -303.992512) (xy 109.484487 -303.992512) (xy 109.538435 -304.000268) (xy 109.59073 -304.015623)
			(xy 109.640307 -304.038265) (xy 109.686157 -304.067731) (xy 109.727348 -304.103422) (xy 109.763039 -304.144613)
			(xy 109.792505 -304.190463) (xy 109.815147 -304.24004) (xy 109.830502 -304.292335) (xy 109.838258 -304.346283)
			(xy 109.838744 -304.373534) (xy 109.838312 -304.400906) (xy 109.830488 -304.455087) (xy 109.814992 -304.507591)
			(xy 109.792142 -304.557337) (xy 109.762409 -304.603302) (xy 109.744764 -304.624232) (xy 109.738668 -304.631344)
			(xy 109.732318 -304.648362) (xy 109.732318 -304.733706) (xy 109.738668 -304.750724) (xy 109.744764 -304.757836)
			(xy 109.762381 -304.778786) (xy 109.792097 -304.824753) (xy 109.814938 -304.874496) (xy 109.830434 -304.926993)
			(xy 109.838267 -304.981166) (xy 109.838744 -305.008534) (xy 113.883948 -305.008534) (xy 113.884422 -304.981164)
			(xy 113.892236 -304.926985) (xy 113.907723 -304.874481) (xy 113.930563 -304.824734) (xy 113.960287 -304.778767)
			(xy 113.977928 -304.757836) (xy 113.984024 -304.750724) (xy 113.990374 -304.733706) (xy 113.990374 -304.648362)
			(xy 113.984024 -304.631344) (xy 113.977928 -304.624232) (xy 113.960295 -304.603295) (xy 113.930581 -304.557324)
			(xy 113.907744 -304.507578) (xy 113.892251 -304.455078) (xy 113.884422 -304.400903) (xy 113.883948 -304.373534)
			(xy 113.884434 -304.346283) (xy 113.89219 -304.292335) (xy 113.907545 -304.24004) (xy 113.930187 -304.190463)
			(xy 113.959653 -304.144613) (xy 113.995344 -304.103422) (xy 114.036535 -304.067731) (xy 114.082385 -304.038265)
			(xy 114.131962 -304.015623) (xy 114.184257 -304.000268) (xy 114.238205 -303.992512) (xy 114.292707 -303.992512)
			(xy 114.346655 -304.000268) (xy 114.39895 -304.015623) (xy 114.448527 -304.038265) (xy 114.494377 -304.067731)
			(xy 114.535568 -304.103422) (xy 114.571259 -304.144613) (xy 114.579627 -304.157634) (xy 116.784372 -304.157634)
			(xy 116.788443 -304.102012) (xy 116.800569 -304.047575) (xy 116.820492 -303.995484) (xy 116.847788 -303.946849)
			(xy 116.881874 -303.902706) (xy 116.922023 -303.863997) (xy 116.967381 -303.831546) (xy 117.016981 -303.806045)
			(xy 117.069765 -303.788038) (xy 117.124608 -303.777908) (xy 117.180342 -303.775871) (xy 117.235779 -303.781971)
			(xy 117.289736 -303.796077) (xy 117.341065 -303.817889) (xy 117.388671 -303.846943) (xy 117.431539 -303.882618)
			(xy 117.468756 -303.924155) (xy 117.499529 -303.970668) (xy 117.523201 -304.021165) (xy 117.539269 -304.074572)
			(xy 117.547389 -304.129748) (xy 117.547898 -304.157634) (xy 117.547389 -304.18552) (xy 117.539269 -304.240696)
			(xy 117.523201 -304.294103) (xy 117.499529 -304.3446) (xy 117.468756 -304.391113) (xy 117.431539 -304.43265)
			(xy 117.388671 -304.468325) (xy 117.341065 -304.497379) (xy 117.289736 -304.519191) (xy 117.235779 -304.533297)
			(xy 117.180342 -304.539397) (xy 117.124608 -304.53736) (xy 117.069765 -304.52723) (xy 117.016981 -304.509223)
			(xy 116.967381 -304.483722) (xy 116.922023 -304.451271) (xy 116.881874 -304.412562) (xy 116.847788 -304.368419)
			(xy 116.820492 -304.319784) (xy 116.800569 -304.267693) (xy 116.788443 -304.213256) (xy 116.784372 -304.157634)
			(xy 114.579627 -304.157634) (xy 114.600725 -304.190463) (xy 114.623367 -304.24004) (xy 114.638722 -304.292335)
			(xy 114.646478 -304.346283) (xy 114.646964 -304.373534) (xy 114.646527 -304.400905) (xy 114.638703 -304.455086)
			(xy 114.623208 -304.50759) (xy 114.60036 -304.557336) (xy 114.570628 -304.603302) (xy 114.552984 -304.624232)
			(xy 114.546888 -304.631344) (xy 114.540538 -304.648362) (xy 114.540538 -304.733706) (xy 114.546888 -304.750724)
			(xy 114.552984 -304.757836) (xy 114.570604 -304.778783) (xy 114.600319 -304.824752) (xy 114.623159 -304.874495)
			(xy 114.638655 -304.926993) (xy 114.646488 -304.981166) (xy 114.646964 -305.008534) (xy 114.646478 -305.035785)
			(xy 114.638722 -305.089733) (xy 114.623367 -305.142028) (xy 114.600725 -305.191605) (xy 114.571259 -305.237455)
			(xy 114.535568 -305.278646) (xy 114.494377 -305.314337) (xy 114.448527 -305.343803) (xy 114.39895 -305.366445)
			(xy 114.346655 -305.3818) (xy 114.292707 -305.389556) (xy 114.238205 -305.389556) (xy 114.184257 -305.3818)
			(xy 114.131962 -305.366445) (xy 114.082385 -305.343803) (xy 114.036535 -305.314337) (xy 113.995344 -305.278646)
			(xy 113.959653 -305.237455) (xy 113.930187 -305.191605) (xy 113.907545 -305.142028) (xy 113.89219 -305.089733)
			(xy 113.884434 -305.035785) (xy 113.883948 -305.008534) (xy 109.838744 -305.008534) (xy 109.838258 -305.035785)
			(xy 109.830502 -305.089733) (xy 109.815147 -305.142028) (xy 109.792505 -305.191605) (xy 109.763039 -305.237455)
			(xy 109.727348 -305.278646) (xy 109.686157 -305.314337) (xy 109.640307 -305.343803) (xy 109.59073 -305.366445)
			(xy 109.538435 -305.3818) (xy 109.484487 -305.389556) (xy 109.429985 -305.389556) (xy 109.376037 -305.3818)
			(xy 109.323742 -305.366445) (xy 109.274165 -305.343803) (xy 109.228315 -305.314337) (xy 109.187124 -305.278646)
			(xy 109.151433 -305.237455) (xy 109.121967 -305.191605) (xy 109.099325 -305.142028) (xy 109.08397 -305.089733)
			(xy 109.076214 -305.035785) (xy 109.075728 -305.008534) (xy 107.806744 -305.008534) (xy 107.806258 -305.035785)
			(xy 107.798502 -305.089733) (xy 107.783147 -305.142028) (xy 107.760505 -305.191605) (xy 107.731039 -305.237455)
			(xy 107.695348 -305.278646) (xy 107.654157 -305.314337) (xy 107.608307 -305.343803) (xy 107.55873 -305.366445)
			(xy 107.506435 -305.3818) (xy 107.452487 -305.389556) (xy 107.397985 -305.389556) (xy 107.344037 -305.3818)
			(xy 107.291742 -305.366445) (xy 107.242165 -305.343803) (xy 107.196315 -305.314337) (xy 107.155124 -305.278646)
			(xy 107.119433 -305.237455) (xy 107.089967 -305.191605) (xy 107.067325 -305.142028) (xy 107.05197 -305.089733)
			(xy 107.044214 -305.035785) (xy 107.043728 -305.008534) (xy 106.418634 -305.008534) (xy 106.418148 -305.035785)
			(xy 106.410392 -305.089733) (xy 106.395037 -305.142028) (xy 106.372395 -305.191605) (xy 106.342929 -305.237455)
			(xy 106.307238 -305.278646) (xy 106.266047 -305.314337) (xy 106.220197 -305.343803) (xy 106.17062 -305.366445)
			(xy 106.118325 -305.3818) (xy 106.064377 -305.389556) (xy 106.009875 -305.389556) (xy 105.955927 -305.3818)
			(xy 105.903632 -305.366445) (xy 105.854055 -305.343803) (xy 105.808205 -305.314337) (xy 105.767014 -305.278646)
			(xy 105.731323 -305.237455) (xy 105.701857 -305.191605) (xy 105.679215 -305.142028) (xy 105.66386 -305.089733)
			(xy 105.656104 -305.035785) (xy 105.655618 -305.008534) (xy 102.998524 -305.008534) (xy 102.998038 -305.035785)
			(xy 102.990282 -305.089733) (xy 102.974927 -305.142028) (xy 102.952285 -305.191605) (xy 102.922819 -305.237455)
			(xy 102.887128 -305.278646) (xy 102.845937 -305.314337) (xy 102.800087 -305.343803) (xy 102.75051 -305.366445)
			(xy 102.698215 -305.3818) (xy 102.644267 -305.389556) (xy 102.589765 -305.389556) (xy 102.535817 -305.3818)
			(xy 102.483522 -305.366445) (xy 102.433945 -305.343803) (xy 102.388095 -305.314337) (xy 102.346904 -305.278646)
			(xy 102.311213 -305.237455) (xy 102.281747 -305.191605) (xy 102.259105 -305.142028) (xy 102.24375 -305.089733)
			(xy 102.235994 -305.035785) (xy 102.235508 -305.008534) (xy 93.445679 -305.008534) (xy 93.447107 -305.01824)
			(xy 93.447616 -305.046126) (xy 93.447107 -305.074012) (xy 93.438987 -305.129188) (xy 93.422919 -305.182595)
			(xy 93.399247 -305.233092) (xy 93.368474 -305.279605) (xy 93.331257 -305.321142) (xy 93.288389 -305.356817)
			(xy 93.240783 -305.385871) (xy 93.189454 -305.407683) (xy 93.135497 -305.421789) (xy 93.08006 -305.427889)
			(xy 93.024326 -305.425852) (xy 92.969483 -305.415722) (xy 92.916699 -305.397715) (xy 92.867099 -305.372214)
			(xy 92.821741 -305.339763) (xy 92.781592 -305.301054) (xy 92.747506 -305.256911) (xy 92.72021 -305.208276)
			(xy 92.700287 -305.156185) (xy 92.688161 -305.101748) (xy 92.68409 -305.046126) (xy 92.431291 -305.046126)
			(xy 92.431616 -305.063906) (xy 92.431107 -305.091792) (xy 92.422987 -305.146968) (xy 92.406919 -305.200375)
			(xy 92.383247 -305.250872) (xy 92.352474 -305.297385) (xy 92.315257 -305.338922) (xy 92.272389 -305.374597)
			(xy 92.224783 -305.403651) (xy 92.173454 -305.425463) (xy 92.119497 -305.439569) (xy 92.06406 -305.445669)
			(xy 92.008326 -305.443632) (xy 91.953483 -305.433502) (xy 91.900699 -305.415495) (xy 91.851099 -305.389994)
			(xy 91.805741 -305.357543) (xy 91.765592 -305.318834) (xy 91.731506 -305.274691) (xy 91.70421 -305.226056)
			(xy 91.684287 -305.173965) (xy 91.672161 -305.119528) (xy 91.66809 -305.063906) (xy 91.406961 -305.063906)
			(xy 91.40698 -305.064922) (xy 91.406471 -305.092808) (xy 91.398351 -305.147984) (xy 91.382283 -305.201391)
			(xy 91.358611 -305.251888) (xy 91.327838 -305.298401) (xy 91.290621 -305.339938) (xy 91.247753 -305.375613)
			(xy 91.200147 -305.404667) (xy 91.148818 -305.426479) (xy 91.094861 -305.440585) (xy 91.039424 -305.446685)
			(xy 90.98369 -305.444648) (xy 90.928847 -305.434518) (xy 90.876063 -305.416511) (xy 90.826463 -305.39101)
			(xy 90.781105 -305.358559) (xy 90.740956 -305.31985) (xy 90.70687 -305.275707) (xy 90.679574 -305.227072)
			(xy 90.659651 -305.174981) (xy 90.647525 -305.120544) (xy 90.643454 -305.064922) (xy 90.3986 -305.064922)
			(xy 90.398091 -305.092808) (xy 90.389971 -305.147984) (xy 90.373903 -305.201391) (xy 90.350231 -305.251888)
			(xy 90.319458 -305.298401) (xy 90.282241 -305.339938) (xy 90.239373 -305.375613) (xy 90.191767 -305.404667)
			(xy 90.140438 -305.426479) (xy 90.086481 -305.440585) (xy 90.031044 -305.446685) (xy 89.97531 -305.444648)
			(xy 89.920467 -305.434518) (xy 89.867683 -305.416511) (xy 89.818083 -305.39101) (xy 89.772725 -305.358559)
			(xy 89.732576 -305.31985) (xy 89.69849 -305.275707) (xy 89.671194 -305.227072) (xy 89.651271 -305.174981)
			(xy 89.639145 -305.120544) (xy 89.635074 -305.064922) (xy 89.383616 -305.064922) (xy 89.383107 -305.092808)
			(xy 89.374987 -305.147984) (xy 89.358919 -305.201391) (xy 89.335247 -305.251888) (xy 89.304474 -305.298401)
			(xy 89.267257 -305.339938) (xy 89.224389 -305.375613) (xy 89.176783 -305.404667) (xy 89.125454 -305.426479)
			(xy 89.071497 -305.440585) (xy 89.01606 -305.446685) (xy 88.960326 -305.444648) (xy 88.905483 -305.434518)
			(xy 88.852699 -305.416511) (xy 88.803099 -305.39101) (xy 88.757741 -305.358559) (xy 88.717592 -305.31985)
			(xy 88.683506 -305.275707) (xy 88.65621 -305.227072) (xy 88.636287 -305.174981) (xy 88.624161 -305.120544)
			(xy 88.62009 -305.064922) (xy 72.745493 -305.064922) (xy 72.733299 -305.088156) (xy 72.703734 -305.1275)
			(xy 72.668241 -305.161592) (xy 72.627738 -305.189548) (xy 72.583276 -305.210646) (xy 72.536005 -305.224338)
			(xy 72.48715 -305.23027) (xy 72.437975 -305.228289) (xy 72.389756 -305.218445) (xy 72.34374 -305.200993)
			(xy 72.301119 -305.176386) (xy 72.262998 -305.145261) (xy 72.230363 -305.108424) (xy 72.20406 -305.066828)
			(xy 72.184769 -305.021552) (xy 72.172992 -304.973768) (xy 72.169032 -304.924714) (xy 71.830184 -304.924714)
			(xy 71.829689 -304.949321) (xy 71.821794 -304.997898) (xy 71.80621 -305.044579) (xy 71.783339 -305.088156)
			(xy 71.753774 -305.1275) (xy 71.718281 -305.161592) (xy 71.677778 -305.189548) (xy 71.633316 -305.210646)
			(xy 71.586045 -305.224338) (xy 71.53719 -305.23027) (xy 71.488015 -305.228289) (xy 71.439796 -305.218445)
			(xy 71.39378 -305.200993) (xy 71.351159 -305.176386) (xy 71.313038 -305.145261) (xy 71.280403 -305.108424)
			(xy 71.2541 -305.066828) (xy 71.234809 -305.021552) (xy 71.223032 -304.973768) (xy 71.219072 -304.924714)
			(xy 70.880224 -304.924714) (xy 70.879729 -304.949321) (xy 70.871834 -304.997898) (xy 70.85625 -305.044579)
			(xy 70.833379 -305.088156) (xy 70.803814 -305.1275) (xy 70.768321 -305.161592) (xy 70.727818 -305.189548)
			(xy 70.683356 -305.210646) (xy 70.636085 -305.224338) (xy 70.58723 -305.23027) (xy 70.538055 -305.228289)
			(xy 70.489836 -305.218445) (xy 70.44382 -305.200993) (xy 70.401199 -305.176386) (xy 70.363078 -305.145261)
			(xy 70.330443 -305.108424) (xy 70.30414 -305.066828) (xy 70.284849 -305.021552) (xy 70.273072 -304.973768)
			(xy 70.269112 -304.924714) (xy 69.930264 -304.924714) (xy 69.929769 -304.949321) (xy 69.921874 -304.997898)
			(xy 69.90629 -305.044579) (xy 69.883419 -305.088156) (xy 69.853854 -305.1275) (xy 69.818361 -305.161592)
			(xy 69.777858 -305.189548) (xy 69.733396 -305.210646) (xy 69.686125 -305.224338) (xy 69.63727 -305.23027)
			(xy 69.588095 -305.228289) (xy 69.539876 -305.218445) (xy 69.49386 -305.200993) (xy 69.451239 -305.176386)
			(xy 69.413118 -305.145261) (xy 69.380483 -305.108424) (xy 69.35418 -305.066828) (xy 69.334889 -305.021552)
			(xy 69.323112 -304.973768) (xy 69.319152 -304.924714) (xy 68.98005 -304.924714) (xy 68.979555 -304.949321)
			(xy 68.97166 -304.997898) (xy 68.956076 -305.044579) (xy 68.933205 -305.088156) (xy 68.90364 -305.1275)
			(xy 68.868147 -305.161592) (xy 68.827644 -305.189548) (xy 68.783182 -305.210646) (xy 68.735911 -305.224338)
			(xy 68.687056 -305.23027) (xy 68.637881 -305.228289) (xy 68.589662 -305.218445) (xy 68.543646 -305.200993)
			(xy 68.501025 -305.176386) (xy 68.462904 -305.145261) (xy 68.430269 -305.108424) (xy 68.403966 -305.066828)
			(xy 68.384675 -305.021552) (xy 68.372898 -304.973768) (xy 68.368938 -304.924714) (xy 68.03009 -304.924714)
			(xy 68.029595 -304.949321) (xy 68.0217 -304.997898) (xy 68.006116 -305.044579) (xy 67.983245 -305.088156)
			(xy 67.95368 -305.1275) (xy 67.918187 -305.161592) (xy 67.877684 -305.189548) (xy 67.833222 -305.210646)
			(xy 67.785951 -305.224338) (xy 67.737096 -305.23027) (xy 67.687921 -305.228289) (xy 67.639702 -305.218445)
			(xy 67.593686 -305.200993) (xy 67.551065 -305.176386) (xy 67.512944 -305.145261) (xy 67.480309 -305.108424)
			(xy 67.454006 -305.066828) (xy 67.434715 -305.021552) (xy 67.422938 -304.973768) (xy 67.418978 -304.924714)
			(xy 67.08013 -304.924714) (xy 67.079635 -304.949321) (xy 67.07174 -304.997898) (xy 67.056156 -305.044579)
			(xy 67.033285 -305.088156) (xy 67.00372 -305.1275) (xy 66.968227 -305.161592) (xy 66.927724 -305.189548)
			(xy 66.883262 -305.210646) (xy 66.835991 -305.224338) (xy 66.787136 -305.23027) (xy 66.737961 -305.228289)
			(xy 66.689742 -305.218445) (xy 66.643726 -305.200993) (xy 66.601105 -305.176386) (xy 66.562984 -305.145261)
			(xy 66.530349 -305.108424) (xy 66.504046 -305.066828) (xy 66.484755 -305.021552) (xy 66.472978 -304.973768)
			(xy 66.469018 -304.924714) (xy 66.13017 -304.924714) (xy 66.129675 -304.949321) (xy 66.12178 -304.997898)
			(xy 66.106196 -305.044579) (xy 66.083325 -305.088156) (xy 66.05376 -305.1275) (xy 66.018267 -305.161592)
			(xy 65.977764 -305.189548) (xy 65.933302 -305.210646) (xy 65.886031 -305.224338) (xy 65.837176 -305.23027)
			(xy 65.788001 -305.228289) (xy 65.739782 -305.218445) (xy 65.693766 -305.200993) (xy 65.651145 -305.176386)
			(xy 65.613024 -305.145261) (xy 65.580389 -305.108424) (xy 65.554086 -305.066828) (xy 65.534795 -305.021552)
			(xy 65.523018 -304.973768) (xy 65.519058 -304.924714) (xy 65.18021 -304.924714) (xy 65.179715 -304.949321)
			(xy 65.17182 -304.997898) (xy 65.156236 -305.044579) (xy 65.133365 -305.088156) (xy 65.1038 -305.1275)
			(xy 65.068307 -305.161592) (xy 65.027804 -305.189548) (xy 64.983342 -305.210646) (xy 64.936071 -305.224338)
			(xy 64.887216 -305.23027) (xy 64.838041 -305.228289) (xy 64.789822 -305.218445) (xy 64.743806 -305.200993)
			(xy 64.701185 -305.176386) (xy 64.663064 -305.145261) (xy 64.630429 -305.108424) (xy 64.604126 -305.066828)
			(xy 64.584835 -305.021552) (xy 64.573058 -304.973768) (xy 64.569098 -304.924714) (xy 64.23025 -304.924714)
			(xy 64.229755 -304.949321) (xy 64.22186 -304.997898) (xy 64.206276 -305.044579) (xy 64.183405 -305.088156)
			(xy 64.15384 -305.1275) (xy 64.118347 -305.161592) (xy 64.077844 -305.189548) (xy 64.033382 -305.210646)
			(xy 63.986111 -305.224338) (xy 63.937256 -305.23027) (xy 63.888081 -305.228289) (xy 63.839862 -305.218445)
			(xy 63.793846 -305.200993) (xy 63.751225 -305.176386) (xy 63.713104 -305.145261) (xy 63.680469 -305.108424)
			(xy 63.654166 -305.066828) (xy 63.634875 -305.021552) (xy 63.623098 -304.973768) (xy 63.619138 -304.924714)
			(xy 63.28029 -304.924714) (xy 63.279795 -304.949321) (xy 63.2719 -304.997898) (xy 63.256316 -305.044579)
			(xy 63.233445 -305.088156) (xy 63.20388 -305.1275) (xy 63.168387 -305.161592) (xy 63.127884 -305.189548)
			(xy 63.083422 -305.210646) (xy 63.036151 -305.224338) (xy 62.987296 -305.23027) (xy 62.938121 -305.228289)
			(xy 62.889902 -305.218445) (xy 62.843886 -305.200993) (xy 62.801265 -305.176386) (xy 62.763144 -305.145261)
			(xy 62.730509 -305.108424) (xy 62.704206 -305.066828) (xy 62.684915 -305.021552) (xy 62.673138 -304.973768)
			(xy 62.669178 -304.924714) (xy 62.330076 -304.924714) (xy 62.329581 -304.949321) (xy 62.321686 -304.997898)
			(xy 62.306102 -305.044579) (xy 62.283231 -305.088156) (xy 62.253666 -305.1275) (xy 62.218173 -305.161592)
			(xy 62.17767 -305.189548) (xy 62.133208 -305.210646) (xy 62.085937 -305.224338) (xy 62.037082 -305.23027)
			(xy 61.987907 -305.228289) (xy 61.939688 -305.218445) (xy 61.893672 -305.200993) (xy 61.851051 -305.176386)
			(xy 61.81293 -305.145261) (xy 61.780295 -305.108424) (xy 61.753992 -305.066828) (xy 61.734701 -305.021552)
			(xy 61.722924 -304.973768) (xy 61.718964 -304.924714) (xy 61.380116 -304.924714) (xy 61.379621 -304.949321)
			(xy 61.371726 -304.997898) (xy 61.356142 -305.044579) (xy 61.333271 -305.088156) (xy 61.303706 -305.1275)
			(xy 61.268213 -305.161592) (xy 61.22771 -305.189548) (xy 61.183248 -305.210646) (xy 61.135977 -305.224338)
			(xy 61.087122 -305.23027) (xy 61.037947 -305.228289) (xy 60.989728 -305.218445) (xy 60.943712 -305.200993)
			(xy 60.901091 -305.176386) (xy 60.86297 -305.145261) (xy 60.830335 -305.108424) (xy 60.804032 -305.066828)
			(xy 60.784741 -305.021552) (xy 60.772964 -304.973768) (xy 60.769004 -304.924714) (xy 60.430156 -304.924714)
			(xy 60.429661 -304.949321) (xy 60.421766 -304.997898) (xy 60.406182 -305.044579) (xy 60.383311 -305.088156)
			(xy 60.353746 -305.1275) (xy 60.318253 -305.161592) (xy 60.27775 -305.189548) (xy 60.233288 -305.210646)
			(xy 60.186017 -305.224338) (xy 60.137162 -305.23027) (xy 60.087987 -305.228289) (xy 60.039768 -305.218445)
			(xy 59.993752 -305.200993) (xy 59.951131 -305.176386) (xy 59.91301 -305.145261) (xy 59.880375 -305.108424)
			(xy 59.854072 -305.066828) (xy 59.834781 -305.021552) (xy 59.823004 -304.973768) (xy 59.819044 -304.924714)
			(xy 58.530236 -304.924714) (xy 58.529741 -304.949321) (xy 58.521846 -304.997898) (xy 58.506262 -305.044579)
			(xy 58.483391 -305.088156) (xy 58.453826 -305.1275) (xy 58.418333 -305.161592) (xy 58.37783 -305.189548)
			(xy 58.333368 -305.210646) (xy 58.286097 -305.224338) (xy 58.237242 -305.23027) (xy 58.188067 -305.228289)
			(xy 58.139848 -305.218445) (xy 58.093832 -305.200993) (xy 58.051211 -305.176386) (xy 58.01309 -305.145261)
			(xy 57.980455 -305.108424) (xy 57.954152 -305.066828) (xy 57.934861 -305.021552) (xy 57.923084 -304.973768)
			(xy 57.919124 -304.924714) (xy 57.580276 -304.924714) (xy 57.579781 -304.949321) (xy 57.571886 -304.997898)
			(xy 57.556302 -305.044579) (xy 57.533431 -305.088156) (xy 57.503866 -305.1275) (xy 57.468373 -305.161592)
			(xy 57.42787 -305.189548) (xy 57.383408 -305.210646) (xy 57.336137 -305.224338) (xy 57.287282 -305.23027)
			(xy 57.238107 -305.228289) (xy 57.189888 -305.218445) (xy 57.143872 -305.200993) (xy 57.101251 -305.176386)
			(xy 57.06313 -305.145261) (xy 57.030495 -305.108424) (xy 57.004192 -305.066828) (xy 56.984901 -305.021552)
			(xy 56.973124 -304.973768) (xy 56.969164 -304.924714) (xy 56.630062 -304.924714) (xy 56.629567 -304.949321)
			(xy 56.621672 -304.997898) (xy 56.606088 -305.044579) (xy 56.583217 -305.088156) (xy 56.553652 -305.1275)
			(xy 56.518159 -305.161592) (xy 56.477656 -305.189548) (xy 56.433194 -305.210646) (xy 56.385923 -305.224338)
			(xy 56.337068 -305.23027) (xy 56.287893 -305.228289) (xy 56.239674 -305.218445) (xy 56.193658 -305.200993)
			(xy 56.151037 -305.176386) (xy 56.112916 -305.145261) (xy 56.080281 -305.108424) (xy 56.053978 -305.066828)
			(xy 56.034687 -305.021552) (xy 56.02291 -304.973768) (xy 56.01895 -304.924714) (xy 55.680102 -304.924714)
			(xy 55.679607 -304.949321) (xy 55.671712 -304.997898) (xy 55.656128 -305.044579) (xy 55.633257 -305.088156)
			(xy 55.603692 -305.1275) (xy 55.568199 -305.161592) (xy 55.527696 -305.189548) (xy 55.483234 -305.210646)
			(xy 55.435963 -305.224338) (xy 55.387108 -305.23027) (xy 55.337933 -305.228289) (xy 55.289714 -305.218445)
			(xy 55.243698 -305.200993) (xy 55.201077 -305.176386) (xy 55.162956 -305.145261) (xy 55.130321 -305.108424)
			(xy 55.104018 -305.066828) (xy 55.084727 -305.021552) (xy 55.07295 -304.973768) (xy 55.06899 -304.924714)
			(xy 54.730142 -304.924714) (xy 54.729647 -304.949321) (xy 54.721752 -304.997898) (xy 54.706168 -305.044579)
			(xy 54.683297 -305.088156) (xy 54.653732 -305.1275) (xy 54.618239 -305.161592) (xy 54.577736 -305.189548)
			(xy 54.533274 -305.210646) (xy 54.486003 -305.224338) (xy 54.437148 -305.23027) (xy 54.387973 -305.228289)
			(xy 54.339754 -305.218445) (xy 54.293738 -305.200993) (xy 54.251117 -305.176386) (xy 54.212996 -305.145261)
			(xy 54.180361 -305.108424) (xy 54.154058 -305.066828) (xy 54.134767 -305.021552) (xy 54.12299 -304.973768)
			(xy 54.11903 -304.924714) (xy 53.780182 -304.924714) (xy 53.779687 -304.949321) (xy 53.771792 -304.997898)
			(xy 53.756208 -305.044579) (xy 53.733337 -305.088156) (xy 53.703772 -305.1275) (xy 53.668279 -305.161592)
			(xy 53.627776 -305.189548) (xy 53.583314 -305.210646) (xy 53.536043 -305.224338) (xy 53.487188 -305.23027)
			(xy 53.438013 -305.228289) (xy 53.389794 -305.218445) (xy 53.343778 -305.200993) (xy 53.301157 -305.176386)
			(xy 53.263036 -305.145261) (xy 53.230401 -305.108424) (xy 53.204098 -305.066828) (xy 53.184807 -305.021552)
			(xy 53.17303 -304.973768) (xy 53.16907 -304.924714) (xy 52.830222 -304.924714) (xy 52.829727 -304.949321)
			(xy 52.821832 -304.997898) (xy 52.806248 -305.044579) (xy 52.783377 -305.088156) (xy 52.753812 -305.1275)
			(xy 52.718319 -305.161592) (xy 52.677816 -305.189548) (xy 52.633354 -305.210646) (xy 52.586083 -305.224338)
			(xy 52.537228 -305.23027) (xy 52.488053 -305.228289) (xy 52.439834 -305.218445) (xy 52.393818 -305.200993)
			(xy 52.351197 -305.176386) (xy 52.313076 -305.145261) (xy 52.280441 -305.108424) (xy 52.254138 -305.066828)
			(xy 52.234847 -305.021552) (xy 52.22307 -304.973768) (xy 52.21911 -304.924714) (xy 51.880262 -304.924714)
			(xy 51.879767 -304.949321) (xy 51.871872 -304.997898) (xy 51.856288 -305.044579) (xy 51.833417 -305.088156)
			(xy 51.803852 -305.1275) (xy 51.768359 -305.161592) (xy 51.727856 -305.189548) (xy 51.683394 -305.210646)
			(xy 51.636123 -305.224338) (xy 51.587268 -305.23027) (xy 51.538093 -305.228289) (xy 51.489874 -305.218445)
			(xy 51.443858 -305.200993) (xy 51.401237 -305.176386) (xy 51.363116 -305.145261) (xy 51.330481 -305.108424)
			(xy 51.304178 -305.066828) (xy 51.284887 -305.021552) (xy 51.27311 -304.973768) (xy 51.26915 -304.924714)
			(xy 50.930302 -304.924714) (xy 50.929807 -304.949321) (xy 50.921912 -304.997898) (xy 50.906328 -305.044579)
			(xy 50.883457 -305.088156) (xy 50.853892 -305.1275) (xy 50.818399 -305.161592) (xy 50.777896 -305.189548)
			(xy 50.733434 -305.210646) (xy 50.686163 -305.224338) (xy 50.637308 -305.23027) (xy 50.588133 -305.228289)
			(xy 50.539914 -305.218445) (xy 50.493898 -305.200993) (xy 50.451277 -305.176386) (xy 50.413156 -305.145261)
			(xy 50.380521 -305.108424) (xy 50.354218 -305.066828) (xy 50.334927 -305.021552) (xy 50.32315 -304.973768)
			(xy 50.31919 -304.924714) (xy 49.980088 -304.924714) (xy 49.979593 -304.949321) (xy 49.971698 -304.997898)
			(xy 49.956114 -305.044579) (xy 49.933243 -305.088156) (xy 49.903678 -305.1275) (xy 49.868185 -305.161592)
			(xy 49.827682 -305.189548) (xy 49.78322 -305.210646) (xy 49.735949 -305.224338) (xy 49.687094 -305.23027)
			(xy 49.637919 -305.228289) (xy 49.5897 -305.218445) (xy 49.543684 -305.200993) (xy 49.501063 -305.176386)
			(xy 49.462942 -305.145261) (xy 49.430307 -305.108424) (xy 49.404004 -305.066828) (xy 49.384713 -305.021552)
			(xy 49.372936 -304.973768) (xy 49.368976 -304.924714) (xy 49.149254 -304.924714) (xy 49.149254 -305.399948)
			(xy 73.593972 -305.399948) (xy 73.597932 -305.350894) (xy 73.609709 -305.30311) (xy 73.629 -305.257834)
			(xy 73.655303 -305.216238) (xy 73.687938 -305.179401) (xy 73.726059 -305.148276) (xy 73.76868 -305.123669)
			(xy 73.814696 -305.106217) (xy 73.862915 -305.096373) (xy 73.91209 -305.094392) (xy 73.960945 -305.100324)
			(xy 74.008216 -305.114016) (xy 74.052678 -305.135114) (xy 74.093181 -305.16307) (xy 74.128674 -305.197162)
			(xy 74.158239 -305.236506) (xy 74.18111 -305.280083) (xy 74.196694 -305.326764) (xy 74.204589 -305.375341)
			(xy 74.205084 -305.399948) (xy 74.544186 -305.399948) (xy 74.548146 -305.350894) (xy 74.559923 -305.30311)
			(xy 74.579214 -305.257834) (xy 74.605517 -305.216238) (xy 74.638152 -305.179401) (xy 74.676273 -305.148276)
			(xy 74.718894 -305.123669) (xy 74.76491 -305.106217) (xy 74.813129 -305.096373) (xy 74.862304 -305.094392)
			(xy 74.911159 -305.100324) (xy 74.95843 -305.114016) (xy 75.002892 -305.135114) (xy 75.043395 -305.16307)
			(xy 75.078888 -305.197162) (xy 75.108453 -305.236506) (xy 75.131324 -305.280083) (xy 75.146908 -305.326764)
			(xy 75.154803 -305.375341) (xy 75.155298 -305.399948) (xy 75.494146 -305.399948) (xy 75.498106 -305.350894)
			(xy 75.509883 -305.30311) (xy 75.529174 -305.257834) (xy 75.555477 -305.216238) (xy 75.588112 -305.179401)
			(xy 75.626233 -305.148276) (xy 75.668854 -305.123669) (xy 75.71487 -305.106217) (xy 75.763089 -305.096373)
			(xy 75.812264 -305.094392) (xy 75.861119 -305.100324) (xy 75.90839 -305.114016) (xy 75.952852 -305.135114)
			(xy 75.993355 -305.16307) (xy 76.028848 -305.197162) (xy 76.058413 -305.236506) (xy 76.081284 -305.280083)
			(xy 76.096868 -305.326764) (xy 76.104763 -305.375341) (xy 76.105258 -305.399948) (xy 76.104763 -305.424555)
			(xy 76.104584 -305.425656) (xy 76.423262 -305.425656) (xy 76.423262 -305.37424) (xy 76.431305 -305.323458)
			(xy 76.447193 -305.274559) (xy 76.470536 -305.228747) (xy 76.500757 -305.187151) (xy 76.537113 -305.150795)
			(xy 76.578709 -305.120574) (xy 76.624521 -305.097231) (xy 76.67342 -305.081343) (xy 76.724202 -305.0733)
			(xy 76.775618 -305.0733) (xy 76.8264 -305.081343) (xy 76.875299 -305.097231) (xy 76.921111 -305.120574)
			(xy 76.962707 -305.150795) (xy 76.999063 -305.187151) (xy 77.029284 -305.228747) (xy 77.052627 -305.274559)
			(xy 77.068515 -305.323458) (xy 77.076558 -305.37424) (xy 77.077062 -305.399948) (xy 77.076558 -305.425656)
			(xy 77.373222 -305.425656) (xy 77.373222 -305.37424) (xy 77.381265 -305.323458) (xy 77.397153 -305.274559)
			(xy 77.420496 -305.228747) (xy 77.450717 -305.187151) (xy 77.487073 -305.150795) (xy 77.528669 -305.120574)
			(xy 77.574481 -305.097231) (xy 77.62338 -305.081343) (xy 77.674162 -305.0733) (xy 77.725578 -305.0733)
			(xy 77.77636 -305.081343) (xy 77.825259 -305.097231) (xy 77.871071 -305.120574) (xy 77.912667 -305.150795)
			(xy 77.949023 -305.187151) (xy 77.979244 -305.228747) (xy 78.002587 -305.274559) (xy 78.018475 -305.323458)
			(xy 78.026518 -305.37424) (xy 78.027022 -305.399948) (xy 78.344026 -305.399948) (xy 78.347986 -305.350894)
			(xy 78.359763 -305.30311) (xy 78.379054 -305.257834) (xy 78.405357 -305.216238) (xy 78.437992 -305.179401)
			(xy 78.476113 -305.148276) (xy 78.518734 -305.123669) (xy 78.56475 -305.106217) (xy 78.612969 -305.096373)
			(xy 78.662144 -305.094392) (xy 78.710999 -305.100324) (xy 78.75827 -305.114016) (xy 78.802732 -305.135114)
			(xy 78.843235 -305.16307) (xy 78.878728 -305.197162) (xy 78.908293 -305.236506) (xy 78.931164 -305.280083)
			(xy 78.946748 -305.326764) (xy 78.954643 -305.375341) (xy 78.955138 -305.399948) (xy 79.293986 -305.399948)
			(xy 79.297946 -305.350894) (xy 79.309723 -305.30311) (xy 79.329014 -305.257834) (xy 79.355317 -305.216238)
			(xy 79.387952 -305.179401) (xy 79.426073 -305.148276) (xy 79.468694 -305.123669) (xy 79.51471 -305.106217)
			(xy 79.562929 -305.096373) (xy 79.612104 -305.094392) (xy 79.660959 -305.100324) (xy 79.70823 -305.114016)
			(xy 79.752692 -305.135114) (xy 79.793195 -305.16307) (xy 79.828688 -305.197162) (xy 79.858253 -305.236506)
			(xy 79.881124 -305.280083) (xy 79.896708 -305.326764) (xy 79.904603 -305.375341) (xy 79.905098 -305.399948)
			(xy 80.243946 -305.399948) (xy 80.247906 -305.350894) (xy 80.259683 -305.30311) (xy 80.278974 -305.257834)
			(xy 80.305277 -305.216238) (xy 80.337912 -305.179401) (xy 80.376033 -305.148276) (xy 80.418654 -305.123669)
			(xy 80.46467 -305.106217) (xy 80.512889 -305.096373) (xy 80.562064 -305.094392) (xy 80.610919 -305.100324)
			(xy 80.65819 -305.114016) (xy 80.702652 -305.135114) (xy 80.743155 -305.16307) (xy 80.778648 -305.197162)
			(xy 80.808213 -305.236506) (xy 80.831084 -305.280083) (xy 80.846668 -305.326764) (xy 80.854563 -305.375341)
			(xy 80.855058 -305.399948) (xy 81.19416 -305.399948) (xy 81.19812 -305.350894) (xy 81.209897 -305.30311)
			(xy 81.229188 -305.257834) (xy 81.255491 -305.216238) (xy 81.288126 -305.179401) (xy 81.326247 -305.148276)
			(xy 81.368868 -305.123669) (xy 81.414884 -305.106217) (xy 81.463103 -305.096373) (xy 81.512278 -305.094392)
			(xy 81.561133 -305.100324) (xy 81.608404 -305.114016) (xy 81.652866 -305.135114) (xy 81.693369 -305.16307)
			(xy 81.728862 -305.197162) (xy 81.758427 -305.236506) (xy 81.781298 -305.280083) (xy 81.796882 -305.326764)
			(xy 81.804777 -305.375341) (xy 81.805272 -305.399948) (xy 82.14412 -305.399948) (xy 82.14808 -305.350894)
			(xy 82.159857 -305.30311) (xy 82.179148 -305.257834) (xy 82.205451 -305.216238) (xy 82.238086 -305.179401)
			(xy 82.276207 -305.148276) (xy 82.318828 -305.123669) (xy 82.364844 -305.106217) (xy 82.413063 -305.096373)
			(xy 82.462238 -305.094392) (xy 82.511093 -305.100324) (xy 82.558364 -305.114016) (xy 82.602826 -305.135114)
			(xy 82.643329 -305.16307) (xy 82.678822 -305.197162) (xy 82.708387 -305.236506) (xy 82.731258 -305.280083)
			(xy 82.746842 -305.326764) (xy 82.754737 -305.375341) (xy 82.755232 -305.399948) (xy 82.754737 -305.424555)
			(xy 82.746842 -305.473132) (xy 82.731258 -305.519813) (xy 82.708387 -305.56339) (xy 82.678822 -305.602734)
			(xy 82.643329 -305.636826) (xy 82.602826 -305.664782) (xy 82.558364 -305.68588) (xy 82.511093 -305.699572)
			(xy 82.462238 -305.705504) (xy 82.413063 -305.703523) (xy 82.364844 -305.693679) (xy 82.318828 -305.676227)
			(xy 82.276207 -305.65162) (xy 82.238086 -305.620495) (xy 82.205451 -305.583658) (xy 82.179148 -305.542062)
			(xy 82.159857 -305.496786) (xy 82.14808 -305.449002) (xy 82.14412 -305.399948) (xy 81.805272 -305.399948)
			(xy 81.804777 -305.424555) (xy 81.796882 -305.473132) (xy 81.781298 -305.519813) (xy 81.758427 -305.56339)
			(xy 81.728862 -305.602734) (xy 81.693369 -305.636826) (xy 81.652866 -305.664782) (xy 81.608404 -305.68588)
			(xy 81.561133 -305.699572) (xy 81.512278 -305.705504) (xy 81.463103 -305.703523) (xy 81.414884 -305.693679)
			(xy 81.368868 -305.676227) (xy 81.326247 -305.65162) (xy 81.288126 -305.620495) (xy 81.255491 -305.583658)
			(xy 81.229188 -305.542062) (xy 81.209897 -305.496786) (xy 81.19812 -305.449002) (xy 81.19416 -305.399948)
			(xy 80.855058 -305.399948) (xy 80.854563 -305.424555) (xy 80.846668 -305.473132) (xy 80.831084 -305.519813)
			(xy 80.808213 -305.56339) (xy 80.778648 -305.602734) (xy 80.743155 -305.636826) (xy 80.702652 -305.664782)
			(xy 80.65819 -305.68588) (xy 80.610919 -305.699572) (xy 80.562064 -305.705504) (xy 80.512889 -305.703523)
			(xy 80.46467 -305.693679) (xy 80.418654 -305.676227) (xy 80.376033 -305.65162) (xy 80.337912 -305.620495)
			(xy 80.305277 -305.583658) (xy 80.278974 -305.542062) (xy 80.259683 -305.496786) (xy 80.247906 -305.449002)
			(xy 80.243946 -305.399948) (xy 79.905098 -305.399948) (xy 79.904603 -305.424555) (xy 79.896708 -305.473132)
			(xy 79.881124 -305.519813) (xy 79.858253 -305.56339) (xy 79.828688 -305.602734) (xy 79.793195 -305.636826)
			(xy 79.752692 -305.664782) (xy 79.70823 -305.68588) (xy 79.660959 -305.699572) (xy 79.612104 -305.705504)
			(xy 79.562929 -305.703523) (xy 79.51471 -305.693679) (xy 79.468694 -305.676227) (xy 79.426073 -305.65162)
			(xy 79.387952 -305.620495) (xy 79.355317 -305.583658) (xy 79.329014 -305.542062) (xy 79.309723 -305.496786)
			(xy 79.297946 -305.449002) (xy 79.293986 -305.399948) (xy 78.955138 -305.399948) (xy 78.954643 -305.424555)
			(xy 78.946748 -305.473132) (xy 78.931164 -305.519813) (xy 78.908293 -305.56339) (xy 78.878728 -305.602734)
			(xy 78.843235 -305.636826) (xy 78.802732 -305.664782) (xy 78.75827 -305.68588) (xy 78.710999 -305.699572)
			(xy 78.662144 -305.705504) (xy 78.612969 -305.703523) (xy 78.56475 -305.693679) (xy 78.518734 -305.676227)
			(xy 78.476113 -305.65162) (xy 78.437992 -305.620495) (xy 78.405357 -305.583658) (xy 78.379054 -305.542062)
			(xy 78.359763 -305.496786) (xy 78.347986 -305.449002) (xy 78.344026 -305.399948) (xy 78.027022 -305.399948)
			(xy 78.026518 -305.425656) (xy 78.018475 -305.476438) (xy 78.002587 -305.525337) (xy 77.979244 -305.571149)
			(xy 77.949023 -305.612745) (xy 77.912667 -305.649101) (xy 77.871071 -305.679322) (xy 77.825259 -305.702665)
			(xy 77.77636 -305.718553) (xy 77.725578 -305.726596) (xy 77.674162 -305.726596) (xy 77.62338 -305.718553)
			(xy 77.574481 -305.702665) (xy 77.528669 -305.679322) (xy 77.487073 -305.649101) (xy 77.450717 -305.612745)
			(xy 77.420496 -305.571149) (xy 77.397153 -305.525337) (xy 77.381265 -305.476438) (xy 77.373222 -305.425656)
			(xy 77.076558 -305.425656) (xy 77.068515 -305.476438) (xy 77.052627 -305.525337) (xy 77.029284 -305.571149)
			(xy 76.999063 -305.612745) (xy 76.962707 -305.649101) (xy 76.921111 -305.679322) (xy 76.875299 -305.702665)
			(xy 76.8264 -305.718553) (xy 76.775618 -305.726596) (xy 76.724202 -305.726596) (xy 76.67342 -305.718553)
			(xy 76.624521 -305.702665) (xy 76.578709 -305.679322) (xy 76.537113 -305.649101) (xy 76.500757 -305.612745)
			(xy 76.470536 -305.571149) (xy 76.447193 -305.525337) (xy 76.431305 -305.476438) (xy 76.423262 -305.425656)
			(xy 76.104584 -305.425656) (xy 76.096868 -305.473132) (xy 76.081284 -305.519813) (xy 76.058413 -305.56339)
			(xy 76.028848 -305.602734) (xy 75.993355 -305.636826) (xy 75.952852 -305.664782) (xy 75.90839 -305.68588)
			(xy 75.861119 -305.699572) (xy 75.812264 -305.705504) (xy 75.763089 -305.703523) (xy 75.71487 -305.693679)
			(xy 75.668854 -305.676227) (xy 75.626233 -305.65162) (xy 75.588112 -305.620495) (xy 75.555477 -305.583658)
			(xy 75.529174 -305.542062) (xy 75.509883 -305.496786) (xy 75.498106 -305.449002) (xy 75.494146 -305.399948)
			(xy 75.155298 -305.399948) (xy 75.154803 -305.424555) (xy 75.146908 -305.473132) (xy 75.131324 -305.519813)
			(xy 75.108453 -305.56339) (xy 75.078888 -305.602734) (xy 75.043395 -305.636826) (xy 75.002892 -305.664782)
			(xy 74.95843 -305.68588) (xy 74.911159 -305.699572) (xy 74.862304 -305.705504) (xy 74.813129 -305.703523)
			(xy 74.76491 -305.693679) (xy 74.718894 -305.676227) (xy 74.676273 -305.65162) (xy 74.638152 -305.620495)
			(xy 74.605517 -305.583658) (xy 74.579214 -305.542062) (xy 74.559923 -305.496786) (xy 74.548146 -305.449002)
			(xy 74.544186 -305.399948) (xy 74.205084 -305.399948) (xy 74.204589 -305.424555) (xy 74.196694 -305.473132)
			(xy 74.18111 -305.519813) (xy 74.158239 -305.56339) (xy 74.128674 -305.602734) (xy 74.093181 -305.636826)
			(xy 74.052678 -305.664782) (xy 74.008216 -305.68588) (xy 73.960945 -305.699572) (xy 73.91209 -305.705504)
			(xy 73.862915 -305.703523) (xy 73.814696 -305.693679) (xy 73.76868 -305.676227) (xy 73.726059 -305.65162)
			(xy 73.687938 -305.620495) (xy 73.655303 -305.583658) (xy 73.629 -305.542062) (xy 73.609709 -305.496786)
			(xy 73.597932 -305.449002) (xy 73.593972 -305.399948) (xy 49.149254 -305.399948) (xy 49.149254 -305.874928)
			(xy 49.368976 -305.874928) (xy 49.372936 -305.825874) (xy 49.384713 -305.77809) (xy 49.404004 -305.732814)
			(xy 49.430307 -305.691218) (xy 49.462942 -305.654381) (xy 49.501063 -305.623256) (xy 49.543684 -305.598649)
			(xy 49.5897 -305.581197) (xy 49.637919 -305.571353) (xy 49.687094 -305.569372) (xy 49.735949 -305.575304)
			(xy 49.78322 -305.588996) (xy 49.827682 -305.610094) (xy 49.868185 -305.63805) (xy 49.903678 -305.672142)
			(xy 49.933243 -305.711486) (xy 49.956114 -305.755063) (xy 49.971698 -305.801744) (xy 49.979593 -305.850321)
			(xy 49.980088 -305.874928) (xy 50.31919 -305.874928) (xy 50.32315 -305.825874) (xy 50.334927 -305.77809)
			(xy 50.354218 -305.732814) (xy 50.380521 -305.691218) (xy 50.413156 -305.654381) (xy 50.451277 -305.623256)
			(xy 50.493898 -305.598649) (xy 50.539914 -305.581197) (xy 50.588133 -305.571353) (xy 50.637308 -305.569372)
			(xy 50.686163 -305.575304) (xy 50.733434 -305.588996) (xy 50.777896 -305.610094) (xy 50.818399 -305.63805)
			(xy 50.853892 -305.672142) (xy 50.883457 -305.711486) (xy 50.906328 -305.755063) (xy 50.921912 -305.801744)
			(xy 50.929807 -305.850321) (xy 50.930302 -305.874928) (xy 51.26915 -305.874928) (xy 51.27311 -305.825874)
			(xy 51.284887 -305.77809) (xy 51.304178 -305.732814) (xy 51.330481 -305.691218) (xy 51.363116 -305.654381)
			(xy 51.401237 -305.623256) (xy 51.443858 -305.598649) (xy 51.489874 -305.581197) (xy 51.538093 -305.571353)
			(xy 51.587268 -305.569372) (xy 51.636123 -305.575304) (xy 51.683394 -305.588996) (xy 51.727856 -305.610094)
			(xy 51.768359 -305.63805) (xy 51.803852 -305.672142) (xy 51.833417 -305.711486) (xy 51.856288 -305.755063)
			(xy 51.871872 -305.801744) (xy 51.879767 -305.850321) (xy 51.880262 -305.874928) (xy 52.21911 -305.874928)
			(xy 52.22307 -305.825874) (xy 52.234847 -305.77809) (xy 52.254138 -305.732814) (xy 52.280441 -305.691218)
			(xy 52.313076 -305.654381) (xy 52.351197 -305.623256) (xy 52.393818 -305.598649) (xy 52.439834 -305.581197)
			(xy 52.488053 -305.571353) (xy 52.537228 -305.569372) (xy 52.586083 -305.575304) (xy 52.633354 -305.588996)
			(xy 52.677816 -305.610094) (xy 52.718319 -305.63805) (xy 52.753812 -305.672142) (xy 52.783377 -305.711486)
			(xy 52.806248 -305.755063) (xy 52.821832 -305.801744) (xy 52.829727 -305.850321) (xy 52.830222 -305.874928)
			(xy 53.16907 -305.874928) (xy 53.17303 -305.825874) (xy 53.184807 -305.77809) (xy 53.204098 -305.732814)
			(xy 53.230401 -305.691218) (xy 53.263036 -305.654381) (xy 53.301157 -305.623256) (xy 53.343778 -305.598649)
			(xy 53.389794 -305.581197) (xy 53.438013 -305.571353) (xy 53.487188 -305.569372) (xy 53.536043 -305.575304)
			(xy 53.583314 -305.588996) (xy 53.627776 -305.610094) (xy 53.668279 -305.63805) (xy 53.703772 -305.672142)
			(xy 53.733337 -305.711486) (xy 53.756208 -305.755063) (xy 53.771792 -305.801744) (xy 53.779687 -305.850321)
			(xy 53.780182 -305.874928) (xy 54.11903 -305.874928) (xy 54.12299 -305.825874) (xy 54.134767 -305.77809)
			(xy 54.154058 -305.732814) (xy 54.180361 -305.691218) (xy 54.212996 -305.654381) (xy 54.251117 -305.623256)
			(xy 54.293738 -305.598649) (xy 54.339754 -305.581197) (xy 54.387973 -305.571353) (xy 54.437148 -305.569372)
			(xy 54.486003 -305.575304) (xy 54.533274 -305.588996) (xy 54.577736 -305.610094) (xy 54.618239 -305.63805)
			(xy 54.653732 -305.672142) (xy 54.683297 -305.711486) (xy 54.706168 -305.755063) (xy 54.721752 -305.801744)
			(xy 54.729647 -305.850321) (xy 54.730142 -305.874928) (xy 55.06899 -305.874928) (xy 55.07295 -305.825874)
			(xy 55.084727 -305.77809) (xy 55.104018 -305.732814) (xy 55.130321 -305.691218) (xy 55.162956 -305.654381)
			(xy 55.201077 -305.623256) (xy 55.243698 -305.598649) (xy 55.289714 -305.581197) (xy 55.337933 -305.571353)
			(xy 55.387108 -305.569372) (xy 55.435963 -305.575304) (xy 55.483234 -305.588996) (xy 55.527696 -305.610094)
			(xy 55.568199 -305.63805) (xy 55.603692 -305.672142) (xy 55.633257 -305.711486) (xy 55.656128 -305.755063)
			(xy 55.671712 -305.801744) (xy 55.679607 -305.850321) (xy 55.680102 -305.874928) (xy 56.01895 -305.874928)
			(xy 56.02291 -305.825874) (xy 56.034687 -305.77809) (xy 56.053978 -305.732814) (xy 56.080281 -305.691218)
			(xy 56.112916 -305.654381) (xy 56.151037 -305.623256) (xy 56.193658 -305.598649) (xy 56.239674 -305.581197)
			(xy 56.287893 -305.571353) (xy 56.337068 -305.569372) (xy 56.385923 -305.575304) (xy 56.433194 -305.588996)
			(xy 56.477656 -305.610094) (xy 56.518159 -305.63805) (xy 56.553652 -305.672142) (xy 56.583217 -305.711486)
			(xy 56.606088 -305.755063) (xy 56.621672 -305.801744) (xy 56.629567 -305.850321) (xy 56.630062 -305.874928)
			(xy 56.969164 -305.874928) (xy 56.973124 -305.825874) (xy 56.984901 -305.77809) (xy 57.004192 -305.732814)
			(xy 57.030495 -305.691218) (xy 57.06313 -305.654381) (xy 57.101251 -305.623256) (xy 57.143872 -305.598649)
			(xy 57.189888 -305.581197) (xy 57.238107 -305.571353) (xy 57.287282 -305.569372) (xy 57.336137 -305.575304)
			(xy 57.383408 -305.588996) (xy 57.42787 -305.610094) (xy 57.468373 -305.63805) (xy 57.503866 -305.672142)
			(xy 57.533431 -305.711486) (xy 57.556302 -305.755063) (xy 57.571886 -305.801744) (xy 57.579781 -305.850321)
			(xy 57.580276 -305.874928) (xy 57.919124 -305.874928) (xy 57.923084 -305.825874) (xy 57.934861 -305.77809)
			(xy 57.954152 -305.732814) (xy 57.980455 -305.691218) (xy 58.01309 -305.654381) (xy 58.051211 -305.623256)
			(xy 58.093832 -305.598649) (xy 58.139848 -305.581197) (xy 58.188067 -305.571353) (xy 58.237242 -305.569372)
			(xy 58.286097 -305.575304) (xy 58.333368 -305.588996) (xy 58.37783 -305.610094) (xy 58.418333 -305.63805)
			(xy 58.453826 -305.672142) (xy 58.483391 -305.711486) (xy 58.506262 -305.755063) (xy 58.521846 -305.801744)
			(xy 58.529741 -305.850321) (xy 58.530236 -305.874928) (xy 59.819044 -305.874928) (xy 59.823004 -305.825874)
			(xy 59.834781 -305.77809) (xy 59.854072 -305.732814) (xy 59.880375 -305.691218) (xy 59.91301 -305.654381)
			(xy 59.951131 -305.623256) (xy 59.993752 -305.598649) (xy 60.039768 -305.581197) (xy 60.087987 -305.571353)
			(xy 60.137162 -305.569372) (xy 60.186017 -305.575304) (xy 60.233288 -305.588996) (xy 60.27775 -305.610094)
			(xy 60.318253 -305.63805) (xy 60.353746 -305.672142) (xy 60.383311 -305.711486) (xy 60.406182 -305.755063)
			(xy 60.421766 -305.801744) (xy 60.429661 -305.850321) (xy 60.430156 -305.874928) (xy 60.769004 -305.874928)
			(xy 60.772964 -305.825874) (xy 60.784741 -305.77809) (xy 60.804032 -305.732814) (xy 60.830335 -305.691218)
			(xy 60.86297 -305.654381) (xy 60.901091 -305.623256) (xy 60.943712 -305.598649) (xy 60.989728 -305.581197)
			(xy 61.037947 -305.571353) (xy 61.087122 -305.569372) (xy 61.135977 -305.575304) (xy 61.183248 -305.588996)
			(xy 61.22771 -305.610094) (xy 61.268213 -305.63805) (xy 61.303706 -305.672142) (xy 61.333271 -305.711486)
			(xy 61.356142 -305.755063) (xy 61.371726 -305.801744) (xy 61.379621 -305.850321) (xy 61.380116 -305.874928)
			(xy 61.718964 -305.874928) (xy 61.722924 -305.825874) (xy 61.734701 -305.77809) (xy 61.753992 -305.732814)
			(xy 61.780295 -305.691218) (xy 61.81293 -305.654381) (xy 61.851051 -305.623256) (xy 61.893672 -305.598649)
			(xy 61.939688 -305.581197) (xy 61.987907 -305.571353) (xy 62.037082 -305.569372) (xy 62.085937 -305.575304)
			(xy 62.133208 -305.588996) (xy 62.17767 -305.610094) (xy 62.218173 -305.63805) (xy 62.253666 -305.672142)
			(xy 62.283231 -305.711486) (xy 62.306102 -305.755063) (xy 62.321686 -305.801744) (xy 62.329581 -305.850321)
			(xy 62.330076 -305.874928) (xy 62.669178 -305.874928) (xy 62.673138 -305.825874) (xy 62.684915 -305.77809)
			(xy 62.704206 -305.732814) (xy 62.730509 -305.691218) (xy 62.763144 -305.654381) (xy 62.801265 -305.623256)
			(xy 62.843886 -305.598649) (xy 62.889902 -305.581197) (xy 62.938121 -305.571353) (xy 62.987296 -305.569372)
			(xy 63.036151 -305.575304) (xy 63.083422 -305.588996) (xy 63.127884 -305.610094) (xy 63.168387 -305.63805)
			(xy 63.20388 -305.672142) (xy 63.233445 -305.711486) (xy 63.256316 -305.755063) (xy 63.2719 -305.801744)
			(xy 63.279795 -305.850321) (xy 63.28029 -305.874928) (xy 63.619138 -305.874928) (xy 63.623098 -305.825874)
			(xy 63.634875 -305.77809) (xy 63.654166 -305.732814) (xy 63.680469 -305.691218) (xy 63.713104 -305.654381)
			(xy 63.751225 -305.623256) (xy 63.793846 -305.598649) (xy 63.839862 -305.581197) (xy 63.888081 -305.571353)
			(xy 63.937256 -305.569372) (xy 63.986111 -305.575304) (xy 64.033382 -305.588996) (xy 64.077844 -305.610094)
			(xy 64.118347 -305.63805) (xy 64.15384 -305.672142) (xy 64.183405 -305.711486) (xy 64.206276 -305.755063)
			(xy 64.22186 -305.801744) (xy 64.229755 -305.850321) (xy 64.23025 -305.874928) (xy 64.569098 -305.874928)
			(xy 64.573058 -305.825874) (xy 64.584835 -305.77809) (xy 64.604126 -305.732814) (xy 64.630429 -305.691218)
			(xy 64.663064 -305.654381) (xy 64.701185 -305.623256) (xy 64.743806 -305.598649) (xy 64.789822 -305.581197)
			(xy 64.838041 -305.571353) (xy 64.887216 -305.569372) (xy 64.936071 -305.575304) (xy 64.983342 -305.588996)
			(xy 65.027804 -305.610094) (xy 65.068307 -305.63805) (xy 65.1038 -305.672142) (xy 65.133365 -305.711486)
			(xy 65.156236 -305.755063) (xy 65.17182 -305.801744) (xy 65.179715 -305.850321) (xy 65.18021 -305.874928)
			(xy 65.519058 -305.874928) (xy 65.523018 -305.825874) (xy 65.534795 -305.77809) (xy 65.554086 -305.732814)
			(xy 65.580389 -305.691218) (xy 65.613024 -305.654381) (xy 65.651145 -305.623256) (xy 65.693766 -305.598649)
			(xy 65.739782 -305.581197) (xy 65.788001 -305.571353) (xy 65.837176 -305.569372) (xy 65.886031 -305.575304)
			(xy 65.933302 -305.588996) (xy 65.977764 -305.610094) (xy 66.018267 -305.63805) (xy 66.05376 -305.672142)
			(xy 66.083325 -305.711486) (xy 66.106196 -305.755063) (xy 66.12178 -305.801744) (xy 66.129675 -305.850321)
			(xy 66.13017 -305.874928) (xy 66.469018 -305.874928) (xy 66.472978 -305.825874) (xy 66.484755 -305.77809)
			(xy 66.504046 -305.732814) (xy 66.530349 -305.691218) (xy 66.562984 -305.654381) (xy 66.601105 -305.623256)
			(xy 66.643726 -305.598649) (xy 66.689742 -305.581197) (xy 66.737961 -305.571353) (xy 66.787136 -305.569372)
			(xy 66.835991 -305.575304) (xy 66.883262 -305.588996) (xy 66.927724 -305.610094) (xy 66.968227 -305.63805)
			(xy 67.00372 -305.672142) (xy 67.033285 -305.711486) (xy 67.056156 -305.755063) (xy 67.07174 -305.801744)
			(xy 67.079635 -305.850321) (xy 67.08013 -305.874928) (xy 67.418978 -305.874928) (xy 67.422938 -305.825874)
			(xy 67.434715 -305.77809) (xy 67.454006 -305.732814) (xy 67.480309 -305.691218) (xy 67.512944 -305.654381)
			(xy 67.551065 -305.623256) (xy 67.593686 -305.598649) (xy 67.639702 -305.581197) (xy 67.687921 -305.571353)
			(xy 67.737096 -305.569372) (xy 67.785951 -305.575304) (xy 67.833222 -305.588996) (xy 67.877684 -305.610094)
			(xy 67.918187 -305.63805) (xy 67.95368 -305.672142) (xy 67.983245 -305.711486) (xy 68.006116 -305.755063)
			(xy 68.0217 -305.801744) (xy 68.029595 -305.850321) (xy 68.03009 -305.874928) (xy 68.368938 -305.874928)
			(xy 68.372898 -305.825874) (xy 68.384675 -305.77809) (xy 68.403966 -305.732814) (xy 68.430269 -305.691218)
			(xy 68.462904 -305.654381) (xy 68.501025 -305.623256) (xy 68.543646 -305.598649) (xy 68.589662 -305.581197)
			(xy 68.637881 -305.571353) (xy 68.687056 -305.569372) (xy 68.735911 -305.575304) (xy 68.783182 -305.588996)
			(xy 68.827644 -305.610094) (xy 68.868147 -305.63805) (xy 68.90364 -305.672142) (xy 68.933205 -305.711486)
			(xy 68.956076 -305.755063) (xy 68.97166 -305.801744) (xy 68.979555 -305.850321) (xy 68.98005 -305.874928)
			(xy 69.319152 -305.874928) (xy 69.323112 -305.825874) (xy 69.334889 -305.77809) (xy 69.35418 -305.732814)
			(xy 69.380483 -305.691218) (xy 69.413118 -305.654381) (xy 69.451239 -305.623256) (xy 69.49386 -305.598649)
			(xy 69.539876 -305.581197) (xy 69.588095 -305.571353) (xy 69.63727 -305.569372) (xy 69.686125 -305.575304)
			(xy 69.733396 -305.588996) (xy 69.777858 -305.610094) (xy 69.818361 -305.63805) (xy 69.853854 -305.672142)
			(xy 69.883419 -305.711486) (xy 69.90629 -305.755063) (xy 69.921874 -305.801744) (xy 69.929769 -305.850321)
			(xy 69.930264 -305.874928) (xy 70.269112 -305.874928) (xy 70.273072 -305.825874) (xy 70.284849 -305.77809)
			(xy 70.30414 -305.732814) (xy 70.330443 -305.691218) (xy 70.363078 -305.654381) (xy 70.401199 -305.623256)
			(xy 70.44382 -305.598649) (xy 70.489836 -305.581197) (xy 70.538055 -305.571353) (xy 70.58723 -305.569372)
			(xy 70.636085 -305.575304) (xy 70.683356 -305.588996) (xy 70.727818 -305.610094) (xy 70.768321 -305.63805)
			(xy 70.803814 -305.672142) (xy 70.833379 -305.711486) (xy 70.85625 -305.755063) (xy 70.871834 -305.801744)
			(xy 70.879729 -305.850321) (xy 70.880224 -305.874928) (xy 71.219072 -305.874928) (xy 71.223032 -305.825874)
			(xy 71.234809 -305.77809) (xy 71.2541 -305.732814) (xy 71.280403 -305.691218) (xy 71.313038 -305.654381)
			(xy 71.351159 -305.623256) (xy 71.39378 -305.598649) (xy 71.439796 -305.581197) (xy 71.488015 -305.571353)
			(xy 71.53719 -305.569372) (xy 71.586045 -305.575304) (xy 71.633316 -305.588996) (xy 71.677778 -305.610094)
			(xy 71.718281 -305.63805) (xy 71.753774 -305.672142) (xy 71.783339 -305.711486) (xy 71.80621 -305.755063)
			(xy 71.821794 -305.801744) (xy 71.829689 -305.850321) (xy 71.830184 -305.874928) (xy 72.169032 -305.874928)
			(xy 72.172992 -305.825874) (xy 72.184769 -305.77809) (xy 72.20406 -305.732814) (xy 72.230363 -305.691218)
			(xy 72.262998 -305.654381) (xy 72.301119 -305.623256) (xy 72.34374 -305.598649) (xy 72.389756 -305.581197)
			(xy 72.437975 -305.571353) (xy 72.48715 -305.569372) (xy 72.536005 -305.575304) (xy 72.583276 -305.588996)
			(xy 72.627738 -305.610094) (xy 72.668241 -305.63805) (xy 72.703734 -305.672142) (xy 72.733299 -305.711486)
			(xy 72.75617 -305.755063) (xy 72.771754 -305.801744) (xy 72.779649 -305.850321) (xy 72.780144 -305.874928)
			(xy 72.779649 -305.899535) (xy 72.771754 -305.948112) (xy 72.75617 -305.994793) (xy 72.733299 -306.03837)
			(xy 72.703734 -306.077714) (xy 72.668241 -306.111806) (xy 72.627738 -306.139762) (xy 72.583276 -306.16086)
			(xy 72.536005 -306.174552) (xy 72.48715 -306.180484) (xy 72.437975 -306.178503) (xy 72.389756 -306.168659)
			(xy 72.34374 -306.151207) (xy 72.301119 -306.1266) (xy 72.262998 -306.095475) (xy 72.230363 -306.058638)
			(xy 72.20406 -306.017042) (xy 72.184769 -305.971766) (xy 72.172992 -305.923982) (xy 72.169032 -305.874928)
			(xy 71.830184 -305.874928) (xy 71.829689 -305.899535) (xy 71.821794 -305.948112) (xy 71.80621 -305.994793)
			(xy 71.783339 -306.03837) (xy 71.753774 -306.077714) (xy 71.718281 -306.111806) (xy 71.677778 -306.139762)
			(xy 71.633316 -306.16086) (xy 71.586045 -306.174552) (xy 71.53719 -306.180484) (xy 71.488015 -306.178503)
			(xy 71.439796 -306.168659) (xy 71.39378 -306.151207) (xy 71.351159 -306.1266) (xy 71.313038 -306.095475)
			(xy 71.280403 -306.058638) (xy 71.2541 -306.017042) (xy 71.234809 -305.971766) (xy 71.223032 -305.923982)
			(xy 71.219072 -305.874928) (xy 70.880224 -305.874928) (xy 70.879729 -305.899535) (xy 70.871834 -305.948112)
			(xy 70.85625 -305.994793) (xy 70.833379 -306.03837) (xy 70.803814 -306.077714) (xy 70.768321 -306.111806)
			(xy 70.727818 -306.139762) (xy 70.683356 -306.16086) (xy 70.636085 -306.174552) (xy 70.58723 -306.180484)
			(xy 70.538055 -306.178503) (xy 70.489836 -306.168659) (xy 70.44382 -306.151207) (xy 70.401199 -306.1266)
			(xy 70.363078 -306.095475) (xy 70.330443 -306.058638) (xy 70.30414 -306.017042) (xy 70.284849 -305.971766)
			(xy 70.273072 -305.923982) (xy 70.269112 -305.874928) (xy 69.930264 -305.874928) (xy 69.929769 -305.899535)
			(xy 69.921874 -305.948112) (xy 69.90629 -305.994793) (xy 69.883419 -306.03837) (xy 69.853854 -306.077714)
			(xy 69.818361 -306.111806) (xy 69.777858 -306.139762) (xy 69.733396 -306.16086) (xy 69.686125 -306.174552)
			(xy 69.63727 -306.180484) (xy 69.588095 -306.178503) (xy 69.539876 -306.168659) (xy 69.49386 -306.151207)
			(xy 69.451239 -306.1266) (xy 69.413118 -306.095475) (xy 69.380483 -306.058638) (xy 69.35418 -306.017042)
			(xy 69.334889 -305.971766) (xy 69.323112 -305.923982) (xy 69.319152 -305.874928) (xy 68.98005 -305.874928)
			(xy 68.979555 -305.899535) (xy 68.97166 -305.948112) (xy 68.956076 -305.994793) (xy 68.933205 -306.03837)
			(xy 68.90364 -306.077714) (xy 68.868147 -306.111806) (xy 68.827644 -306.139762) (xy 68.783182 -306.16086)
			(xy 68.735911 -306.174552) (xy 68.687056 -306.180484) (xy 68.637881 -306.178503) (xy 68.589662 -306.168659)
			(xy 68.543646 -306.151207) (xy 68.501025 -306.1266) (xy 68.462904 -306.095475) (xy 68.430269 -306.058638)
			(xy 68.403966 -306.017042) (xy 68.384675 -305.971766) (xy 68.372898 -305.923982) (xy 68.368938 -305.874928)
			(xy 68.03009 -305.874928) (xy 68.029595 -305.899535) (xy 68.0217 -305.948112) (xy 68.006116 -305.994793)
			(xy 67.983245 -306.03837) (xy 67.95368 -306.077714) (xy 67.918187 -306.111806) (xy 67.877684 -306.139762)
			(xy 67.833222 -306.16086) (xy 67.785951 -306.174552) (xy 67.737096 -306.180484) (xy 67.687921 -306.178503)
			(xy 67.639702 -306.168659) (xy 67.593686 -306.151207) (xy 67.551065 -306.1266) (xy 67.512944 -306.095475)
			(xy 67.480309 -306.058638) (xy 67.454006 -306.017042) (xy 67.434715 -305.971766) (xy 67.422938 -305.923982)
			(xy 67.418978 -305.874928) (xy 67.08013 -305.874928) (xy 67.079635 -305.899535) (xy 67.07174 -305.948112)
			(xy 67.056156 -305.994793) (xy 67.033285 -306.03837) (xy 67.00372 -306.077714) (xy 66.968227 -306.111806)
			(xy 66.927724 -306.139762) (xy 66.883262 -306.16086) (xy 66.835991 -306.174552) (xy 66.787136 -306.180484)
			(xy 66.737961 -306.178503) (xy 66.689742 -306.168659) (xy 66.643726 -306.151207) (xy 66.601105 -306.1266)
			(xy 66.562984 -306.095475) (xy 66.530349 -306.058638) (xy 66.504046 -306.017042) (xy 66.484755 -305.971766)
			(xy 66.472978 -305.923982) (xy 66.469018 -305.874928) (xy 66.13017 -305.874928) (xy 66.129675 -305.899535)
			(xy 66.12178 -305.948112) (xy 66.106196 -305.994793) (xy 66.083325 -306.03837) (xy 66.05376 -306.077714)
			(xy 66.018267 -306.111806) (xy 65.977764 -306.139762) (xy 65.933302 -306.16086) (xy 65.886031 -306.174552)
			(xy 65.837176 -306.180484) (xy 65.788001 -306.178503) (xy 65.739782 -306.168659) (xy 65.693766 -306.151207)
			(xy 65.651145 -306.1266) (xy 65.613024 -306.095475) (xy 65.580389 -306.058638) (xy 65.554086 -306.017042)
			(xy 65.534795 -305.971766) (xy 65.523018 -305.923982) (xy 65.519058 -305.874928) (xy 65.18021 -305.874928)
			(xy 65.179715 -305.899535) (xy 65.17182 -305.948112) (xy 65.156236 -305.994793) (xy 65.133365 -306.03837)
			(xy 65.1038 -306.077714) (xy 65.068307 -306.111806) (xy 65.027804 -306.139762) (xy 64.983342 -306.16086)
			(xy 64.936071 -306.174552) (xy 64.887216 -306.180484) (xy 64.838041 -306.178503) (xy 64.789822 -306.168659)
			(xy 64.743806 -306.151207) (xy 64.701185 -306.1266) (xy 64.663064 -306.095475) (xy 64.630429 -306.058638)
			(xy 64.604126 -306.017042) (xy 64.584835 -305.971766) (xy 64.573058 -305.923982) (xy 64.569098 -305.874928)
			(xy 64.23025 -305.874928) (xy 64.229755 -305.899535) (xy 64.22186 -305.948112) (xy 64.206276 -305.994793)
			(xy 64.183405 -306.03837) (xy 64.15384 -306.077714) (xy 64.118347 -306.111806) (xy 64.077844 -306.139762)
			(xy 64.033382 -306.16086) (xy 63.986111 -306.174552) (xy 63.937256 -306.180484) (xy 63.888081 -306.178503)
			(xy 63.839862 -306.168659) (xy 63.793846 -306.151207) (xy 63.751225 -306.1266) (xy 63.713104 -306.095475)
			(xy 63.680469 -306.058638) (xy 63.654166 -306.017042) (xy 63.634875 -305.971766) (xy 63.623098 -305.923982)
			(xy 63.619138 -305.874928) (xy 63.28029 -305.874928) (xy 63.279795 -305.899535) (xy 63.2719 -305.948112)
			(xy 63.256316 -305.994793) (xy 63.233445 -306.03837) (xy 63.20388 -306.077714) (xy 63.168387 -306.111806)
			(xy 63.127884 -306.139762) (xy 63.083422 -306.16086) (xy 63.036151 -306.174552) (xy 62.987296 -306.180484)
			(xy 62.938121 -306.178503) (xy 62.889902 -306.168659) (xy 62.843886 -306.151207) (xy 62.801265 -306.1266)
			(xy 62.763144 -306.095475) (xy 62.730509 -306.058638) (xy 62.704206 -306.017042) (xy 62.684915 -305.971766)
			(xy 62.673138 -305.923982) (xy 62.669178 -305.874928) (xy 62.330076 -305.874928) (xy 62.329581 -305.899535)
			(xy 62.321686 -305.948112) (xy 62.306102 -305.994793) (xy 62.283231 -306.03837) (xy 62.253666 -306.077714)
			(xy 62.218173 -306.111806) (xy 62.17767 -306.139762) (xy 62.133208 -306.16086) (xy 62.085937 -306.174552)
			(xy 62.037082 -306.180484) (xy 61.987907 -306.178503) (xy 61.939688 -306.168659) (xy 61.893672 -306.151207)
			(xy 61.851051 -306.1266) (xy 61.81293 -306.095475) (xy 61.780295 -306.058638) (xy 61.753992 -306.017042)
			(xy 61.734701 -305.971766) (xy 61.722924 -305.923982) (xy 61.718964 -305.874928) (xy 61.380116 -305.874928)
			(xy 61.379621 -305.899535) (xy 61.371726 -305.948112) (xy 61.356142 -305.994793) (xy 61.333271 -306.03837)
			(xy 61.303706 -306.077714) (xy 61.268213 -306.111806) (xy 61.22771 -306.139762) (xy 61.183248 -306.16086)
			(xy 61.135977 -306.174552) (xy 61.087122 -306.180484) (xy 61.037947 -306.178503) (xy 60.989728 -306.168659)
			(xy 60.943712 -306.151207) (xy 60.901091 -306.1266) (xy 60.86297 -306.095475) (xy 60.830335 -306.058638)
			(xy 60.804032 -306.017042) (xy 60.784741 -305.971766) (xy 60.772964 -305.923982) (xy 60.769004 -305.874928)
			(xy 60.430156 -305.874928) (xy 60.429661 -305.899535) (xy 60.421766 -305.948112) (xy 60.406182 -305.994793)
			(xy 60.383311 -306.03837) (xy 60.353746 -306.077714) (xy 60.318253 -306.111806) (xy 60.27775 -306.139762)
			(xy 60.233288 -306.16086) (xy 60.186017 -306.174552) (xy 60.137162 -306.180484) (xy 60.087987 -306.178503)
			(xy 60.039768 -306.168659) (xy 59.993752 -306.151207) (xy 59.951131 -306.1266) (xy 59.91301 -306.095475)
			(xy 59.880375 -306.058638) (xy 59.854072 -306.017042) (xy 59.834781 -305.971766) (xy 59.823004 -305.923982)
			(xy 59.819044 -305.874928) (xy 58.530236 -305.874928) (xy 58.529741 -305.899535) (xy 58.521846 -305.948112)
			(xy 58.506262 -305.994793) (xy 58.483391 -306.03837) (xy 58.453826 -306.077714) (xy 58.418333 -306.111806)
			(xy 58.37783 -306.139762) (xy 58.333368 -306.16086) (xy 58.286097 -306.174552) (xy 58.237242 -306.180484)
			(xy 58.188067 -306.178503) (xy 58.139848 -306.168659) (xy 58.093832 -306.151207) (xy 58.051211 -306.1266)
			(xy 58.01309 -306.095475) (xy 57.980455 -306.058638) (xy 57.954152 -306.017042) (xy 57.934861 -305.971766)
			(xy 57.923084 -305.923982) (xy 57.919124 -305.874928) (xy 57.580276 -305.874928) (xy 57.579781 -305.899535)
			(xy 57.571886 -305.948112) (xy 57.556302 -305.994793) (xy 57.533431 -306.03837) (xy 57.503866 -306.077714)
			(xy 57.468373 -306.111806) (xy 57.42787 -306.139762) (xy 57.383408 -306.16086) (xy 57.336137 -306.174552)
			(xy 57.287282 -306.180484) (xy 57.238107 -306.178503) (xy 57.189888 -306.168659) (xy 57.143872 -306.151207)
			(xy 57.101251 -306.1266) (xy 57.06313 -306.095475) (xy 57.030495 -306.058638) (xy 57.004192 -306.017042)
			(xy 56.984901 -305.971766) (xy 56.973124 -305.923982) (xy 56.969164 -305.874928) (xy 56.630062 -305.874928)
			(xy 56.629567 -305.899535) (xy 56.621672 -305.948112) (xy 56.606088 -305.994793) (xy 56.583217 -306.03837)
			(xy 56.553652 -306.077714) (xy 56.518159 -306.111806) (xy 56.477656 -306.139762) (xy 56.433194 -306.16086)
			(xy 56.385923 -306.174552) (xy 56.337068 -306.180484) (xy 56.287893 -306.178503) (xy 56.239674 -306.168659)
			(xy 56.193658 -306.151207) (xy 56.151037 -306.1266) (xy 56.112916 -306.095475) (xy 56.080281 -306.058638)
			(xy 56.053978 -306.017042) (xy 56.034687 -305.971766) (xy 56.02291 -305.923982) (xy 56.01895 -305.874928)
			(xy 55.680102 -305.874928) (xy 55.679607 -305.899535) (xy 55.671712 -305.948112) (xy 55.656128 -305.994793)
			(xy 55.633257 -306.03837) (xy 55.603692 -306.077714) (xy 55.568199 -306.111806) (xy 55.527696 -306.139762)
			(xy 55.483234 -306.16086) (xy 55.435963 -306.174552) (xy 55.387108 -306.180484) (xy 55.337933 -306.178503)
			(xy 55.289714 -306.168659) (xy 55.243698 -306.151207) (xy 55.201077 -306.1266) (xy 55.162956 -306.095475)
			(xy 55.130321 -306.058638) (xy 55.104018 -306.017042) (xy 55.084727 -305.971766) (xy 55.07295 -305.923982)
			(xy 55.06899 -305.874928) (xy 54.730142 -305.874928) (xy 54.729647 -305.899535) (xy 54.721752 -305.948112)
			(xy 54.706168 -305.994793) (xy 54.683297 -306.03837) (xy 54.653732 -306.077714) (xy 54.618239 -306.111806)
			(xy 54.577736 -306.139762) (xy 54.533274 -306.16086) (xy 54.486003 -306.174552) (xy 54.437148 -306.180484)
			(xy 54.387973 -306.178503) (xy 54.339754 -306.168659) (xy 54.293738 -306.151207) (xy 54.251117 -306.1266)
			(xy 54.212996 -306.095475) (xy 54.180361 -306.058638) (xy 54.154058 -306.017042) (xy 54.134767 -305.971766)
			(xy 54.12299 -305.923982) (xy 54.11903 -305.874928) (xy 53.780182 -305.874928) (xy 53.779687 -305.899535)
			(xy 53.771792 -305.948112) (xy 53.756208 -305.994793) (xy 53.733337 -306.03837) (xy 53.703772 -306.077714)
			(xy 53.668279 -306.111806) (xy 53.627776 -306.139762) (xy 53.583314 -306.16086) (xy 53.536043 -306.174552)
			(xy 53.487188 -306.180484) (xy 53.438013 -306.178503) (xy 53.389794 -306.168659) (xy 53.343778 -306.151207)
			(xy 53.301157 -306.1266) (xy 53.263036 -306.095475) (xy 53.230401 -306.058638) (xy 53.204098 -306.017042)
			(xy 53.184807 -305.971766) (xy 53.17303 -305.923982) (xy 53.16907 -305.874928) (xy 52.830222 -305.874928)
			(xy 52.829727 -305.899535) (xy 52.821832 -305.948112) (xy 52.806248 -305.994793) (xy 52.783377 -306.03837)
			(xy 52.753812 -306.077714) (xy 52.718319 -306.111806) (xy 52.677816 -306.139762) (xy 52.633354 -306.16086)
			(xy 52.586083 -306.174552) (xy 52.537228 -306.180484) (xy 52.488053 -306.178503) (xy 52.439834 -306.168659)
			(xy 52.393818 -306.151207) (xy 52.351197 -306.1266) (xy 52.313076 -306.095475) (xy 52.280441 -306.058638)
			(xy 52.254138 -306.017042) (xy 52.234847 -305.971766) (xy 52.22307 -305.923982) (xy 52.21911 -305.874928)
			(xy 51.880262 -305.874928) (xy 51.879767 -305.899535) (xy 51.871872 -305.948112) (xy 51.856288 -305.994793)
			(xy 51.833417 -306.03837) (xy 51.803852 -306.077714) (xy 51.768359 -306.111806) (xy 51.727856 -306.139762)
			(xy 51.683394 -306.16086) (xy 51.636123 -306.174552) (xy 51.587268 -306.180484) (xy 51.538093 -306.178503)
			(xy 51.489874 -306.168659) (xy 51.443858 -306.151207) (xy 51.401237 -306.1266) (xy 51.363116 -306.095475)
			(xy 51.330481 -306.058638) (xy 51.304178 -306.017042) (xy 51.284887 -305.971766) (xy 51.27311 -305.923982)
			(xy 51.26915 -305.874928) (xy 50.930302 -305.874928) (xy 50.929807 -305.899535) (xy 50.921912 -305.948112)
			(xy 50.906328 -305.994793) (xy 50.883457 -306.03837) (xy 50.853892 -306.077714) (xy 50.818399 -306.111806)
			(xy 50.777896 -306.139762) (xy 50.733434 -306.16086) (xy 50.686163 -306.174552) (xy 50.637308 -306.180484)
			(xy 50.588133 -306.178503) (xy 50.539914 -306.168659) (xy 50.493898 -306.151207) (xy 50.451277 -306.1266)
			(xy 50.413156 -306.095475) (xy 50.380521 -306.058638) (xy 50.354218 -306.017042) (xy 50.334927 -305.971766)
			(xy 50.32315 -305.923982) (xy 50.31919 -305.874928) (xy 49.980088 -305.874928) (xy 49.979593 -305.899535)
			(xy 49.971698 -305.948112) (xy 49.956114 -305.994793) (xy 49.933243 -306.03837) (xy 49.903678 -306.077714)
			(xy 49.868185 -306.111806) (xy 49.827682 -306.139762) (xy 49.78322 -306.16086) (xy 49.735949 -306.174552)
			(xy 49.687094 -306.180484) (xy 49.637919 -306.178503) (xy 49.5897 -306.168659) (xy 49.543684 -306.151207)
			(xy 49.501063 -306.1266) (xy 49.462942 -306.095475) (xy 49.430307 -306.058638) (xy 49.404004 -306.017042)
			(xy 49.384713 -305.971766) (xy 49.372936 -305.923982) (xy 49.368976 -305.874928) (xy 49.149254 -305.874928)
			(xy 49.149254 -306.349908) (xy 73.593972 -306.349908) (xy 73.597932 -306.300854) (xy 73.609709 -306.25307)
			(xy 73.629 -306.207794) (xy 73.655303 -306.166198) (xy 73.687938 -306.129361) (xy 73.726059 -306.098236)
			(xy 73.76868 -306.073629) (xy 73.814696 -306.056177) (xy 73.862915 -306.046333) (xy 73.91209 -306.044352)
			(xy 73.960945 -306.050284) (xy 74.008216 -306.063976) (xy 74.052678 -306.085074) (xy 74.093181 -306.11303)
			(xy 74.128674 -306.147122) (xy 74.158239 -306.186466) (xy 74.18111 -306.230043) (xy 74.196694 -306.276724)
			(xy 74.204589 -306.325301) (xy 74.205084 -306.349908) (xy 74.204589 -306.374515) (xy 74.20441 -306.375616)
			(xy 74.523342 -306.375616) (xy 74.523342 -306.3242) (xy 74.531385 -306.273418) (xy 74.547273 -306.224519)
			(xy 74.570616 -306.178707) (xy 74.600837 -306.137111) (xy 74.637193 -306.100755) (xy 74.678789 -306.070534)
			(xy 74.724601 -306.047191) (xy 74.7735 -306.031303) (xy 74.824282 -306.02326) (xy 74.875698 -306.02326)
			(xy 74.92648 -306.031303) (xy 74.975379 -306.047191) (xy 75.021191 -306.070534) (xy 75.062787 -306.100755)
			(xy 75.099143 -306.137111) (xy 75.129364 -306.178707) (xy 75.152707 -306.224519) (xy 75.168595 -306.273418)
			(xy 75.176638 -306.3242) (xy 75.177142 -306.349908) (xy 75.176638 -306.375616) (xy 75.473302 -306.375616)
			(xy 75.473302 -306.3242) (xy 75.481345 -306.273418) (xy 75.497233 -306.224519) (xy 75.520576 -306.178707)
			(xy 75.550797 -306.137111) (xy 75.587153 -306.100755) (xy 75.628749 -306.070534) (xy 75.674561 -306.047191)
			(xy 75.72346 -306.031303) (xy 75.774242 -306.02326) (xy 75.825658 -306.02326) (xy 75.87644 -306.031303)
			(xy 75.925339 -306.047191) (xy 75.971151 -306.070534) (xy 76.012747 -306.100755) (xy 76.049103 -306.137111)
			(xy 76.079324 -306.178707) (xy 76.102667 -306.224519) (xy 76.118555 -306.273418) (xy 76.126598 -306.3242)
			(xy 76.127102 -306.349908) (xy 76.444106 -306.349908) (xy 76.448066 -306.300854) (xy 76.459843 -306.25307)
			(xy 76.479134 -306.207794) (xy 76.505437 -306.166198) (xy 76.538072 -306.129361) (xy 76.576193 -306.098236)
			(xy 76.618814 -306.073629) (xy 76.66483 -306.056177) (xy 76.713049 -306.046333) (xy 76.762224 -306.044352)
			(xy 76.811079 -306.050284) (xy 76.85835 -306.063976) (xy 76.902812 -306.085074) (xy 76.943315 -306.11303)
			(xy 76.978808 -306.147122) (xy 77.008373 -306.186466) (xy 77.031244 -306.230043) (xy 77.046828 -306.276724)
			(xy 77.054723 -306.325301) (xy 77.055218 -306.349908) (xy 77.394066 -306.349908) (xy 77.398026 -306.300854)
			(xy 77.409803 -306.25307) (xy 77.429094 -306.207794) (xy 77.455397 -306.166198) (xy 77.488032 -306.129361)
			(xy 77.526153 -306.098236) (xy 77.568774 -306.073629) (xy 77.61479 -306.056177) (xy 77.663009 -306.046333)
			(xy 77.712184 -306.044352) (xy 77.761039 -306.050284) (xy 77.80831 -306.063976) (xy 77.852772 -306.085074)
			(xy 77.893275 -306.11303) (xy 77.928768 -306.147122) (xy 77.958333 -306.186466) (xy 77.981204 -306.230043)
			(xy 77.996788 -306.276724) (xy 78.004683 -306.325301) (xy 78.005178 -306.349908) (xy 78.344026 -306.349908)
			(xy 78.347986 -306.300854) (xy 78.359763 -306.25307) (xy 78.379054 -306.207794) (xy 78.405357 -306.166198)
			(xy 78.437992 -306.129361) (xy 78.476113 -306.098236) (xy 78.518734 -306.073629) (xy 78.56475 -306.056177)
			(xy 78.612969 -306.046333) (xy 78.662144 -306.044352) (xy 78.710999 -306.050284) (xy 78.75827 -306.063976)
			(xy 78.802732 -306.085074) (xy 78.843235 -306.11303) (xy 78.878728 -306.147122) (xy 78.908293 -306.186466)
			(xy 78.931164 -306.230043) (xy 78.946748 -306.276724) (xy 78.954643 -306.325301) (xy 78.955138 -306.349908)
			(xy 79.293986 -306.349908) (xy 79.297946 -306.300854) (xy 79.309723 -306.25307) (xy 79.329014 -306.207794)
			(xy 79.355317 -306.166198) (xy 79.387952 -306.129361) (xy 79.426073 -306.098236) (xy 79.468694 -306.073629)
			(xy 79.51471 -306.056177) (xy 79.562929 -306.046333) (xy 79.612104 -306.044352) (xy 79.660959 -306.050284)
			(xy 79.70823 -306.063976) (xy 79.752692 -306.085074) (xy 79.793195 -306.11303) (xy 79.828688 -306.147122)
			(xy 79.858253 -306.186466) (xy 79.881124 -306.230043) (xy 79.896708 -306.276724) (xy 79.904603 -306.325301)
			(xy 79.905098 -306.349908) (xy 80.243946 -306.349908) (xy 80.247906 -306.300854) (xy 80.259683 -306.25307)
			(xy 80.278974 -306.207794) (xy 80.305277 -306.166198) (xy 80.337912 -306.129361) (xy 80.376033 -306.098236)
			(xy 80.418654 -306.073629) (xy 80.46467 -306.056177) (xy 80.512889 -306.046333) (xy 80.562064 -306.044352)
			(xy 80.610919 -306.050284) (xy 80.65819 -306.063976) (xy 80.702652 -306.085074) (xy 80.743155 -306.11303)
			(xy 80.778648 -306.147122) (xy 80.808213 -306.186466) (xy 80.831084 -306.230043) (xy 80.846668 -306.276724)
			(xy 80.854563 -306.325301) (xy 80.855058 -306.349908) (xy 81.19416 -306.349908) (xy 81.19812 -306.300854)
			(xy 81.209897 -306.25307) (xy 81.229188 -306.207794) (xy 81.255491 -306.166198) (xy 81.288126 -306.129361)
			(xy 81.326247 -306.098236) (xy 81.368868 -306.073629) (xy 81.414884 -306.056177) (xy 81.463103 -306.046333)
			(xy 81.512278 -306.044352) (xy 81.561133 -306.050284) (xy 81.608404 -306.063976) (xy 81.652866 -306.085074)
			(xy 81.693369 -306.11303) (xy 81.728862 -306.147122) (xy 81.758427 -306.186466) (xy 81.781298 -306.230043)
			(xy 81.796882 -306.276724) (xy 81.804777 -306.325301) (xy 81.805272 -306.349908) (xy 82.14412 -306.349908)
			(xy 82.14808 -306.300854) (xy 82.159857 -306.25307) (xy 82.179148 -306.207794) (xy 82.205451 -306.166198)
			(xy 82.238086 -306.129361) (xy 82.276207 -306.098236) (xy 82.318828 -306.073629) (xy 82.364844 -306.056177)
			(xy 82.413063 -306.046333) (xy 82.462238 -306.044352) (xy 82.511093 -306.050284) (xy 82.558364 -306.063976)
			(xy 82.602826 -306.085074) (xy 82.643329 -306.11303) (xy 82.678822 -306.147122) (xy 82.708387 -306.186466)
			(xy 82.731258 -306.230043) (xy 82.746842 -306.276724) (xy 82.754737 -306.325301) (xy 82.755232 -306.349908)
			(xy 83.094334 -306.349908) (xy 83.098294 -306.300854) (xy 83.110071 -306.25307) (xy 83.129362 -306.207794)
			(xy 83.155665 -306.166198) (xy 83.1883 -306.129361) (xy 83.226421 -306.098236) (xy 83.269042 -306.073629)
			(xy 83.315058 -306.056177) (xy 83.363277 -306.046333) (xy 83.412452 -306.044352) (xy 83.461307 -306.050284)
			(xy 83.508578 -306.063976) (xy 83.55304 -306.085074) (xy 83.593543 -306.11303) (xy 83.629036 -306.147122)
			(xy 83.658601 -306.186466) (xy 83.681472 -306.230043) (xy 83.697056 -306.276724) (xy 83.704951 -306.325301)
			(xy 83.705446 -306.349908) (xy 83.704951 -306.374515) (xy 83.697056 -306.423092) (xy 83.681472 -306.469773)
			(xy 83.658601 -306.51335) (xy 83.629036 -306.552694) (xy 83.593543 -306.586786) (xy 83.55304 -306.614742)
			(xy 83.508578 -306.63584) (xy 83.461307 -306.649532) (xy 83.412452 -306.655464) (xy 83.363277 -306.653483)
			(xy 83.315058 -306.643639) (xy 83.269042 -306.626187) (xy 83.226421 -306.60158) (xy 83.1883 -306.570455)
			(xy 83.155665 -306.533618) (xy 83.129362 -306.492022) (xy 83.110071 -306.446746) (xy 83.098294 -306.398962)
			(xy 83.094334 -306.349908) (xy 82.755232 -306.349908) (xy 82.754737 -306.374515) (xy 82.746842 -306.423092)
			(xy 82.731258 -306.469773) (xy 82.708387 -306.51335) (xy 82.678822 -306.552694) (xy 82.643329 -306.586786)
			(xy 82.602826 -306.614742) (xy 82.558364 -306.63584) (xy 82.511093 -306.649532) (xy 82.462238 -306.655464)
			(xy 82.413063 -306.653483) (xy 82.364844 -306.643639) (xy 82.318828 -306.626187) (xy 82.276207 -306.60158)
			(xy 82.238086 -306.570455) (xy 82.205451 -306.533618) (xy 82.179148 -306.492022) (xy 82.159857 -306.446746)
			(xy 82.14808 -306.398962) (xy 82.14412 -306.349908) (xy 81.805272 -306.349908) (xy 81.804777 -306.374515)
			(xy 81.796882 -306.423092) (xy 81.781298 -306.469773) (xy 81.758427 -306.51335) (xy 81.728862 -306.552694)
			(xy 81.693369 -306.586786) (xy 81.652866 -306.614742) (xy 81.608404 -306.63584) (xy 81.561133 -306.649532)
			(xy 81.512278 -306.655464) (xy 81.463103 -306.653483) (xy 81.414884 -306.643639) (xy 81.368868 -306.626187)
			(xy 81.326247 -306.60158) (xy 81.288126 -306.570455) (xy 81.255491 -306.533618) (xy 81.229188 -306.492022)
			(xy 81.209897 -306.446746) (xy 81.19812 -306.398962) (xy 81.19416 -306.349908) (xy 80.855058 -306.349908)
			(xy 80.854563 -306.374515) (xy 80.846668 -306.423092) (xy 80.831084 -306.469773) (xy 80.808213 -306.51335)
			(xy 80.778648 -306.552694) (xy 80.743155 -306.586786) (xy 80.702652 -306.614742) (xy 80.65819 -306.63584)
			(xy 80.610919 -306.649532) (xy 80.562064 -306.655464) (xy 80.512889 -306.653483) (xy 80.46467 -306.643639)
			(xy 80.418654 -306.626187) (xy 80.376033 -306.60158) (xy 80.337912 -306.570455) (xy 80.305277 -306.533618)
			(xy 80.278974 -306.492022) (xy 80.259683 -306.446746) (xy 80.247906 -306.398962) (xy 80.243946 -306.349908)
			(xy 79.905098 -306.349908) (xy 79.904603 -306.374515) (xy 79.896708 -306.423092) (xy 79.881124 -306.469773)
			(xy 79.858253 -306.51335) (xy 79.828688 -306.552694) (xy 79.793195 -306.586786) (xy 79.752692 -306.614742)
			(xy 79.70823 -306.63584) (xy 79.660959 -306.649532) (xy 79.612104 -306.655464) (xy 79.562929 -306.653483)
			(xy 79.51471 -306.643639) (xy 79.468694 -306.626187) (xy 79.426073 -306.60158) (xy 79.387952 -306.570455)
			(xy 79.355317 -306.533618) (xy 79.329014 -306.492022) (xy 79.309723 -306.446746) (xy 79.297946 -306.398962)
			(xy 79.293986 -306.349908) (xy 78.955138 -306.349908) (xy 78.954643 -306.374515) (xy 78.946748 -306.423092)
			(xy 78.931164 -306.469773) (xy 78.908293 -306.51335) (xy 78.878728 -306.552694) (xy 78.843235 -306.586786)
			(xy 78.802732 -306.614742) (xy 78.75827 -306.63584) (xy 78.710999 -306.649532) (xy 78.662144 -306.655464)
			(xy 78.612969 -306.653483) (xy 78.56475 -306.643639) (xy 78.518734 -306.626187) (xy 78.476113 -306.60158)
			(xy 78.437992 -306.570455) (xy 78.405357 -306.533618) (xy 78.379054 -306.492022) (xy 78.359763 -306.446746)
			(xy 78.347986 -306.398962) (xy 78.344026 -306.349908) (xy 78.005178 -306.349908) (xy 78.004683 -306.374515)
			(xy 77.996788 -306.423092) (xy 77.981204 -306.469773) (xy 77.958333 -306.51335) (xy 77.928768 -306.552694)
			(xy 77.893275 -306.586786) (xy 77.852772 -306.614742) (xy 77.80831 -306.63584) (xy 77.761039 -306.649532)
			(xy 77.712184 -306.655464) (xy 77.663009 -306.653483) (xy 77.61479 -306.643639) (xy 77.568774 -306.626187)
			(xy 77.526153 -306.60158) (xy 77.488032 -306.570455) (xy 77.455397 -306.533618) (xy 77.429094 -306.492022)
			(xy 77.409803 -306.446746) (xy 77.398026 -306.398962) (xy 77.394066 -306.349908) (xy 77.055218 -306.349908)
			(xy 77.054723 -306.374515) (xy 77.046828 -306.423092) (xy 77.031244 -306.469773) (xy 77.008373 -306.51335)
			(xy 76.978808 -306.552694) (xy 76.943315 -306.586786) (xy 76.902812 -306.614742) (xy 76.85835 -306.63584)
			(xy 76.811079 -306.649532) (xy 76.762224 -306.655464) (xy 76.713049 -306.653483) (xy 76.66483 -306.643639)
			(xy 76.618814 -306.626187) (xy 76.576193 -306.60158) (xy 76.538072 -306.570455) (xy 76.505437 -306.533618)
			(xy 76.479134 -306.492022) (xy 76.459843 -306.446746) (xy 76.448066 -306.398962) (xy 76.444106 -306.349908)
			(xy 76.127102 -306.349908) (xy 76.126598 -306.375616) (xy 76.118555 -306.426398) (xy 76.102667 -306.475297)
			(xy 76.079324 -306.521109) (xy 76.049103 -306.562705) (xy 76.012747 -306.599061) (xy 75.971151 -306.629282)
			(xy 75.925339 -306.652625) (xy 75.87644 -306.668513) (xy 75.825658 -306.676556) (xy 75.774242 -306.676556)
			(xy 75.72346 -306.668513) (xy 75.674561 -306.652625) (xy 75.628749 -306.629282) (xy 75.587153 -306.599061)
			(xy 75.550797 -306.562705) (xy 75.520576 -306.521109) (xy 75.497233 -306.475297) (xy 75.481345 -306.426398)
			(xy 75.473302 -306.375616) (xy 75.176638 -306.375616) (xy 75.168595 -306.426398) (xy 75.152707 -306.475297)
			(xy 75.129364 -306.521109) (xy 75.099143 -306.562705) (xy 75.062787 -306.599061) (xy 75.021191 -306.629282)
			(xy 74.975379 -306.652625) (xy 74.92648 -306.668513) (xy 74.875698 -306.676556) (xy 74.824282 -306.676556)
			(xy 74.7735 -306.668513) (xy 74.724601 -306.652625) (xy 74.678789 -306.629282) (xy 74.637193 -306.599061)
			(xy 74.600837 -306.562705) (xy 74.570616 -306.521109) (xy 74.547273 -306.475297) (xy 74.531385 -306.426398)
			(xy 74.523342 -306.375616) (xy 74.20441 -306.375616) (xy 74.196694 -306.423092) (xy 74.18111 -306.469773)
			(xy 74.158239 -306.51335) (xy 74.128674 -306.552694) (xy 74.093181 -306.586786) (xy 74.052678 -306.614742)
			(xy 74.008216 -306.63584) (xy 73.960945 -306.649532) (xy 73.91209 -306.655464) (xy 73.862915 -306.653483)
			(xy 73.814696 -306.643639) (xy 73.76868 -306.626187) (xy 73.726059 -306.60158) (xy 73.687938 -306.570455)
			(xy 73.655303 -306.533618) (xy 73.629 -306.492022) (xy 73.609709 -306.446746) (xy 73.597932 -306.398962)
			(xy 73.593972 -306.349908) (xy 49.149254 -306.349908) (xy 49.149254 -306.922678) (xy 49.149693 -306.932741)
			(xy 49.157433 -306.951319) (xy 49.16424 -306.958746) (xy 49.18583 -306.980336) (xy 49.192646 -306.986531)
			(xy 49.209439 -306.994064) (xy 49.218596 -306.995068) (xy 49.228052 -306.995766) (xy 49.246862 -306.998182)
			(xy 49.256188 -306.999894) (xy 49.268634 -307.00218) (xy 49.292256 -306.994814) (xy 49.369726 -306.917344)
			(xy 49.377092 -306.893722) (xy 49.374806 -306.881276) (xy 49.372321 -306.867311) (xy 49.369651 -306.839071)
			(xy 49.369472 -306.824888) (xy 49.369994 -306.799633) (xy 49.378307 -306.749811) (xy 49.394708 -306.702037)
			(xy 49.418749 -306.657614) (xy 49.449773 -306.617754) (xy 49.486935 -306.583544) (xy 49.529221 -306.555918)
			(xy 49.575477 -306.535628) (xy 49.624442 -306.523228) (xy 49.67478 -306.519057) (xy 49.725118 -306.523228)
			(xy 49.774083 -306.535628) (xy 49.820339 -306.555918) (xy 49.862625 -306.583544) (xy 49.899787 -306.617754)
			(xy 49.930811 -306.657614) (xy 49.954852 -306.702037) (xy 49.971253 -306.749811) (xy 49.979566 -306.799633)
			(xy 49.980088 -306.824888) (xy 49.979902 -306.83907) (xy 49.977229 -306.86731) (xy 49.974754 -306.881276)
			(xy 49.972468 -306.893722) (xy 49.979834 -306.917344) (xy 50.057304 -306.994814) (xy 50.080926 -307.00218)
			(xy 50.093372 -306.999894) (xy 50.107337 -306.997407) (xy 50.135577 -306.994732) (xy 50.14976 -306.99456)
			(xy 50.164006 -306.994738) (xy 50.192373 -306.997412) (xy 50.206402 -306.999894) (xy 50.218594 -307.00218)
			(xy 50.242724 -306.994814) (xy 50.31994 -306.917598) (xy 50.327306 -306.893722) (xy 50.32502 -306.881276)
			(xy 50.322535 -306.867311) (xy 50.319864 -306.839071) (xy 50.319686 -306.824888) (xy 50.320173 -306.800067)
			(xy 50.328206 -306.751079) (xy 50.344059 -306.704035) (xy 50.367313 -306.660176) (xy 50.397357 -306.620658)
			(xy 50.433399 -306.58652) (xy 50.474488 -306.558662) (xy 50.519543 -306.53782) (xy 50.567377 -306.524541)
			(xy 50.616728 -306.519175) (xy 50.666298 -306.521864) (xy 50.714779 -306.532537) (xy 50.760895 -306.550913)
			(xy 50.803431 -306.576508) (xy 50.841266 -306.608647) (xy 50.873403 -306.646484) (xy 50.898995 -306.689021)
			(xy 50.917368 -306.735138) (xy 50.928038 -306.78362) (xy 50.930275 -306.824888) (xy 51.26915 -306.824888)
			(xy 51.27311 -306.775834) (xy 51.284887 -306.72805) (xy 51.304178 -306.682774) (xy 51.330481 -306.641178)
			(xy 51.363116 -306.604341) (xy 51.401237 -306.573216) (xy 51.443858 -306.548609) (xy 51.489874 -306.531157)
			(xy 51.538093 -306.521313) (xy 51.587268 -306.519332) (xy 51.636123 -306.525264) (xy 51.683394 -306.538956)
			(xy 51.727856 -306.560054) (xy 51.768359 -306.58801) (xy 51.803852 -306.622102) (xy 51.833417 -306.661446)
			(xy 51.856288 -306.705023) (xy 51.871872 -306.751704) (xy 51.879767 -306.800281) (xy 51.880262 -306.824888)
			(xy 52.21911 -306.824888) (xy 52.22307 -306.775834) (xy 52.234847 -306.72805) (xy 52.254138 -306.682774)
			(xy 52.280441 -306.641178) (xy 52.313076 -306.604341) (xy 52.351197 -306.573216) (xy 52.393818 -306.548609)
			(xy 52.439834 -306.531157) (xy 52.488053 -306.521313) (xy 52.537228 -306.519332) (xy 52.586083 -306.525264)
			(xy 52.633354 -306.538956) (xy 52.677816 -306.560054) (xy 52.718319 -306.58801) (xy 52.753812 -306.622102)
			(xy 52.783377 -306.661446) (xy 52.806248 -306.705023) (xy 52.821832 -306.751704) (xy 52.829727 -306.800281)
			(xy 52.830222 -306.824888) (xy 53.16907 -306.824888) (xy 53.17303 -306.775834) (xy 53.184807 -306.72805)
			(xy 53.204098 -306.682774) (xy 53.230401 -306.641178) (xy 53.263036 -306.604341) (xy 53.301157 -306.573216)
			(xy 53.343778 -306.548609) (xy 53.389794 -306.531157) (xy 53.438013 -306.521313) (xy 53.487188 -306.519332)
			(xy 53.536043 -306.525264) (xy 53.583314 -306.538956) (xy 53.627776 -306.560054) (xy 53.668279 -306.58801)
			(xy 53.703772 -306.622102) (xy 53.733337 -306.661446) (xy 53.756208 -306.705023) (xy 53.771792 -306.751704)
			(xy 53.779687 -306.800281) (xy 53.780182 -306.824888) (xy 54.11903 -306.824888) (xy 54.12299 -306.775834)
			(xy 54.134767 -306.72805) (xy 54.154058 -306.682774) (xy 54.180361 -306.641178) (xy 54.212996 -306.604341)
			(xy 54.251117 -306.573216) (xy 54.293738 -306.548609) (xy 54.339754 -306.531157) (xy 54.387973 -306.521313)
			(xy 54.437148 -306.519332) (xy 54.486003 -306.525264) (xy 54.533274 -306.538956) (xy 54.577736 -306.560054)
			(xy 54.618239 -306.58801) (xy 54.653732 -306.622102) (xy 54.683297 -306.661446) (xy 54.706168 -306.705023)
			(xy 54.721752 -306.751704) (xy 54.729647 -306.800281) (xy 54.730142 -306.824888) (xy 55.06899 -306.824888)
			(xy 55.07295 -306.775834) (xy 55.084727 -306.72805) (xy 55.104018 -306.682774) (xy 55.130321 -306.641178)
			(xy 55.162956 -306.604341) (xy 55.201077 -306.573216) (xy 55.243698 -306.548609) (xy 55.289714 -306.531157)
			(xy 55.337933 -306.521313) (xy 55.387108 -306.519332) (xy 55.435963 -306.525264) (xy 55.483234 -306.538956)
			(xy 55.527696 -306.560054) (xy 55.568199 -306.58801) (xy 55.603692 -306.622102) (xy 55.633257 -306.661446)
			(xy 55.656128 -306.705023) (xy 55.671712 -306.751704) (xy 55.679607 -306.800281) (xy 55.680102 -306.824888)
			(xy 56.01895 -306.824888) (xy 56.02291 -306.775834) (xy 56.034687 -306.72805) (xy 56.053978 -306.682774)
			(xy 56.080281 -306.641178) (xy 56.112916 -306.604341) (xy 56.151037 -306.573216) (xy 56.193658 -306.548609)
			(xy 56.239674 -306.531157) (xy 56.287893 -306.521313) (xy 56.337068 -306.519332) (xy 56.385923 -306.525264)
			(xy 56.433194 -306.538956) (xy 56.477656 -306.560054) (xy 56.518159 -306.58801) (xy 56.553652 -306.622102)
			(xy 56.583217 -306.661446) (xy 56.606088 -306.705023) (xy 56.621672 -306.751704) (xy 56.629567 -306.800281)
			(xy 56.630062 -306.824888) (xy 56.969164 -306.824888) (xy 56.973124 -306.775834) (xy 56.984901 -306.72805)
			(xy 57.004192 -306.682774) (xy 57.030495 -306.641178) (xy 57.06313 -306.604341) (xy 57.101251 -306.573216)
			(xy 57.143872 -306.548609) (xy 57.189888 -306.531157) (xy 57.238107 -306.521313) (xy 57.287282 -306.519332)
			(xy 57.336137 -306.525264) (xy 57.383408 -306.538956) (xy 57.42787 -306.560054) (xy 57.468373 -306.58801)
			(xy 57.503866 -306.622102) (xy 57.533431 -306.661446) (xy 57.556302 -306.705023) (xy 57.571886 -306.751704)
			(xy 57.579781 -306.800281) (xy 57.580276 -306.824888) (xy 57.919124 -306.824888) (xy 57.923084 -306.775834)
			(xy 57.934861 -306.72805) (xy 57.954152 -306.682774) (xy 57.980455 -306.641178) (xy 58.01309 -306.604341)
			(xy 58.051211 -306.573216) (xy 58.093832 -306.548609) (xy 58.139848 -306.531157) (xy 58.188067 -306.521313)
			(xy 58.237242 -306.519332) (xy 58.286097 -306.525264) (xy 58.333368 -306.538956) (xy 58.37783 -306.560054)
			(xy 58.418333 -306.58801) (xy 58.453826 -306.622102) (xy 58.483391 -306.661446) (xy 58.506262 -306.705023)
			(xy 58.521846 -306.751704) (xy 58.529741 -306.800281) (xy 58.530236 -306.824888) (xy 59.819044 -306.824888)
			(xy 59.823004 -306.775834) (xy 59.834781 -306.72805) (xy 59.854072 -306.682774) (xy 59.880375 -306.641178)
			(xy 59.91301 -306.604341) (xy 59.951131 -306.573216) (xy 59.993752 -306.548609) (xy 60.039768 -306.531157)
			(xy 60.087987 -306.521313) (xy 60.137162 -306.519332) (xy 60.186017 -306.525264) (xy 60.233288 -306.538956)
			(xy 60.27775 -306.560054) (xy 60.318253 -306.58801) (xy 60.353746 -306.622102) (xy 60.383311 -306.661446)
			(xy 60.406182 -306.705023) (xy 60.421766 -306.751704) (xy 60.429661 -306.800281) (xy 60.430156 -306.824888)
			(xy 60.769004 -306.824888) (xy 60.772964 -306.775834) (xy 60.784741 -306.72805) (xy 60.804032 -306.682774)
			(xy 60.830335 -306.641178) (xy 60.86297 -306.604341) (xy 60.901091 -306.573216) (xy 60.943712 -306.548609)
			(xy 60.989728 -306.531157) (xy 61.037947 -306.521313) (xy 61.087122 -306.519332) (xy 61.135977 -306.525264)
			(xy 61.183248 -306.538956) (xy 61.22771 -306.560054) (xy 61.268213 -306.58801) (xy 61.303706 -306.622102)
			(xy 61.333271 -306.661446) (xy 61.356142 -306.705023) (xy 61.371726 -306.751704) (xy 61.379621 -306.800281)
			(xy 61.380116 -306.824888) (xy 61.718964 -306.824888) (xy 61.722924 -306.775834) (xy 61.734701 -306.72805)
			(xy 61.753992 -306.682774) (xy 61.780295 -306.641178) (xy 61.81293 -306.604341) (xy 61.851051 -306.573216)
			(xy 61.893672 -306.548609) (xy 61.939688 -306.531157) (xy 61.987907 -306.521313) (xy 62.037082 -306.519332)
			(xy 62.085937 -306.525264) (xy 62.133208 -306.538956) (xy 62.17767 -306.560054) (xy 62.218173 -306.58801)
			(xy 62.253666 -306.622102) (xy 62.283231 -306.661446) (xy 62.306102 -306.705023) (xy 62.321686 -306.751704)
			(xy 62.329581 -306.800281) (xy 62.330076 -306.824888) (xy 62.669178 -306.824888) (xy 62.673138 -306.775834)
			(xy 62.684915 -306.72805) (xy 62.704206 -306.682774) (xy 62.730509 -306.641178) (xy 62.763144 -306.604341)
			(xy 62.801265 -306.573216) (xy 62.843886 -306.548609) (xy 62.889902 -306.531157) (xy 62.938121 -306.521313)
			(xy 62.987296 -306.519332) (xy 63.036151 -306.525264) (xy 63.083422 -306.538956) (xy 63.127884 -306.560054)
			(xy 63.168387 -306.58801) (xy 63.20388 -306.622102) (xy 63.233445 -306.661446) (xy 63.256316 -306.705023)
			(xy 63.2719 -306.751704) (xy 63.279795 -306.800281) (xy 63.28029 -306.824888) (xy 63.619138 -306.824888)
			(xy 63.623098 -306.775834) (xy 63.634875 -306.72805) (xy 63.654166 -306.682774) (xy 63.680469 -306.641178)
			(xy 63.713104 -306.604341) (xy 63.751225 -306.573216) (xy 63.793846 -306.548609) (xy 63.839862 -306.531157)
			(xy 63.888081 -306.521313) (xy 63.937256 -306.519332) (xy 63.986111 -306.525264) (xy 64.033382 -306.538956)
			(xy 64.077844 -306.560054) (xy 64.118347 -306.58801) (xy 64.15384 -306.622102) (xy 64.183405 -306.661446)
			(xy 64.206276 -306.705023) (xy 64.22186 -306.751704) (xy 64.229755 -306.800281) (xy 64.23025 -306.824888)
			(xy 64.569098 -306.824888) (xy 64.573058 -306.775834) (xy 64.584835 -306.72805) (xy 64.604126 -306.682774)
			(xy 64.630429 -306.641178) (xy 64.663064 -306.604341) (xy 64.701185 -306.573216) (xy 64.743806 -306.548609)
			(xy 64.789822 -306.531157) (xy 64.838041 -306.521313) (xy 64.887216 -306.519332) (xy 64.936071 -306.525264)
			(xy 64.983342 -306.538956) (xy 65.027804 -306.560054) (xy 65.068307 -306.58801) (xy 65.1038 -306.622102)
			(xy 65.133365 -306.661446) (xy 65.156236 -306.705023) (xy 65.17182 -306.751704) (xy 65.179715 -306.800281)
			(xy 65.18021 -306.824888) (xy 65.519058 -306.824888) (xy 65.523018 -306.775834) (xy 65.534795 -306.72805)
			(xy 65.554086 -306.682774) (xy 65.580389 -306.641178) (xy 65.613024 -306.604341) (xy 65.651145 -306.573216)
			(xy 65.693766 -306.548609) (xy 65.739782 -306.531157) (xy 65.788001 -306.521313) (xy 65.837176 -306.519332)
			(xy 65.886031 -306.525264) (xy 65.933302 -306.538956) (xy 65.977764 -306.560054) (xy 66.018267 -306.58801)
			(xy 66.05376 -306.622102) (xy 66.083325 -306.661446) (xy 66.106196 -306.705023) (xy 66.12178 -306.751704)
			(xy 66.129675 -306.800281) (xy 66.13017 -306.824888) (xy 66.469018 -306.824888) (xy 66.472978 -306.775834)
			(xy 66.484755 -306.72805) (xy 66.504046 -306.682774) (xy 66.530349 -306.641178) (xy 66.562984 -306.604341)
			(xy 66.601105 -306.573216) (xy 66.643726 -306.548609) (xy 66.689742 -306.531157) (xy 66.737961 -306.521313)
			(xy 66.787136 -306.519332) (xy 66.835991 -306.525264) (xy 66.883262 -306.538956) (xy 66.927724 -306.560054)
			(xy 66.968227 -306.58801) (xy 67.00372 -306.622102) (xy 67.033285 -306.661446) (xy 67.056156 -306.705023)
			(xy 67.07174 -306.751704) (xy 67.079635 -306.800281) (xy 67.08013 -306.824888) (xy 67.418978 -306.824888)
			(xy 67.422938 -306.775834) (xy 67.434715 -306.72805) (xy 67.454006 -306.682774) (xy 67.480309 -306.641178)
			(xy 67.512944 -306.604341) (xy 67.551065 -306.573216) (xy 67.593686 -306.548609) (xy 67.639702 -306.531157)
			(xy 67.687921 -306.521313) (xy 67.737096 -306.519332) (xy 67.785951 -306.525264) (xy 67.833222 -306.538956)
			(xy 67.877684 -306.560054) (xy 67.918187 -306.58801) (xy 67.95368 -306.622102) (xy 67.983245 -306.661446)
			(xy 68.006116 -306.705023) (xy 68.0217 -306.751704) (xy 68.029595 -306.800281) (xy 68.03009 -306.824888)
			(xy 68.368938 -306.824888) (xy 68.372898 -306.775834) (xy 68.384675 -306.72805) (xy 68.403966 -306.682774)
			(xy 68.430269 -306.641178) (xy 68.462904 -306.604341) (xy 68.501025 -306.573216) (xy 68.543646 -306.548609)
			(xy 68.589662 -306.531157) (xy 68.637881 -306.521313) (xy 68.687056 -306.519332) (xy 68.735911 -306.525264)
			(xy 68.783182 -306.538956) (xy 68.827644 -306.560054) (xy 68.868147 -306.58801) (xy 68.90364 -306.622102)
			(xy 68.933205 -306.661446) (xy 68.956076 -306.705023) (xy 68.97166 -306.751704) (xy 68.979555 -306.800281)
			(xy 68.98005 -306.824888) (xy 69.319152 -306.824888) (xy 69.323112 -306.775834) (xy 69.334889 -306.72805)
			(xy 69.35418 -306.682774) (xy 69.380483 -306.641178) (xy 69.413118 -306.604341) (xy 69.451239 -306.573216)
			(xy 69.49386 -306.548609) (xy 69.539876 -306.531157) (xy 69.588095 -306.521313) (xy 69.63727 -306.519332)
			(xy 69.686125 -306.525264) (xy 69.733396 -306.538956) (xy 69.777858 -306.560054) (xy 69.818361 -306.58801)
			(xy 69.853854 -306.622102) (xy 69.883419 -306.661446) (xy 69.90629 -306.705023) (xy 69.921874 -306.751704)
			(xy 69.929769 -306.800281) (xy 69.930264 -306.824888) (xy 70.269112 -306.824888) (xy 70.273072 -306.775834)
			(xy 70.284849 -306.72805) (xy 70.30414 -306.682774) (xy 70.330443 -306.641178) (xy 70.363078 -306.604341)
			(xy 70.401199 -306.573216) (xy 70.44382 -306.548609) (xy 70.489836 -306.531157) (xy 70.538055 -306.521313)
			(xy 70.58723 -306.519332) (xy 70.636085 -306.525264) (xy 70.683356 -306.538956) (xy 70.727818 -306.560054)
			(xy 70.768321 -306.58801) (xy 70.803814 -306.622102) (xy 70.833379 -306.661446) (xy 70.85625 -306.705023)
			(xy 70.871834 -306.751704) (xy 70.879729 -306.800281) (xy 70.880224 -306.824888) (xy 71.219072 -306.824888)
			(xy 71.223032 -306.775834) (xy 71.234809 -306.72805) (xy 71.2541 -306.682774) (xy 71.280403 -306.641178)
			(xy 71.313038 -306.604341) (xy 71.351159 -306.573216) (xy 71.39378 -306.548609) (xy 71.439796 -306.531157)
			(xy 71.488015 -306.521313) (xy 71.53719 -306.519332) (xy 71.586045 -306.525264) (xy 71.633316 -306.538956)
			(xy 71.677778 -306.560054) (xy 71.718281 -306.58801) (xy 71.753774 -306.622102) (xy 71.783339 -306.661446)
			(xy 71.80621 -306.705023) (xy 71.821794 -306.751704) (xy 71.829689 -306.800281) (xy 71.830184 -306.824888)
			(xy 72.169032 -306.824888) (xy 72.172992 -306.775834) (xy 72.184769 -306.72805) (xy 72.20406 -306.682774)
			(xy 72.230363 -306.641178) (xy 72.262998 -306.604341) (xy 72.301119 -306.573216) (xy 72.34374 -306.548609)
			(xy 72.389756 -306.531157) (xy 72.437975 -306.521313) (xy 72.48715 -306.519332) (xy 72.536005 -306.525264)
			(xy 72.583276 -306.538956) (xy 72.627738 -306.560054) (xy 72.668241 -306.58801) (xy 72.703734 -306.622102)
			(xy 72.733299 -306.661446) (xy 72.75617 -306.705023) (xy 72.771754 -306.751704) (xy 72.779649 -306.800281)
			(xy 72.780144 -306.824888) (xy 72.779649 -306.849495) (xy 72.771754 -306.898072) (xy 72.75617 -306.944753)
			(xy 72.733299 -306.98833) (xy 72.703734 -307.027674) (xy 72.668241 -307.061766) (xy 72.627738 -307.089722)
			(xy 72.583276 -307.11082) (xy 72.536005 -307.124512) (xy 72.48715 -307.130444) (xy 72.437975 -307.128463)
			(xy 72.389756 -307.118619) (xy 72.34374 -307.101167) (xy 72.301119 -307.07656) (xy 72.262998 -307.045435)
			(xy 72.230363 -307.008598) (xy 72.20406 -306.967002) (xy 72.184769 -306.921726) (xy 72.172992 -306.873942)
			(xy 72.169032 -306.824888) (xy 71.830184 -306.824888) (xy 71.829689 -306.849495) (xy 71.821794 -306.898072)
			(xy 71.80621 -306.944753) (xy 71.783339 -306.98833) (xy 71.753774 -307.027674) (xy 71.718281 -307.061766)
			(xy 71.677778 -307.089722) (xy 71.633316 -307.11082) (xy 71.586045 -307.124512) (xy 71.53719 -307.130444)
			(xy 71.488015 -307.128463) (xy 71.439796 -307.118619) (xy 71.39378 -307.101167) (xy 71.351159 -307.07656)
			(xy 71.313038 -307.045435) (xy 71.280403 -307.008598) (xy 71.2541 -306.967002) (xy 71.234809 -306.921726)
			(xy 71.223032 -306.873942) (xy 71.219072 -306.824888) (xy 70.880224 -306.824888) (xy 70.879729 -306.849495)
			(xy 70.871834 -306.898072) (xy 70.85625 -306.944753) (xy 70.833379 -306.98833) (xy 70.803814 -307.027674)
			(xy 70.768321 -307.061766) (xy 70.727818 -307.089722) (xy 70.683356 -307.11082) (xy 70.636085 -307.124512)
			(xy 70.58723 -307.130444) (xy 70.538055 -307.128463) (xy 70.489836 -307.118619) (xy 70.44382 -307.101167)
			(xy 70.401199 -307.07656) (xy 70.363078 -307.045435) (xy 70.330443 -307.008598) (xy 70.30414 -306.967002)
			(xy 70.284849 -306.921726) (xy 70.273072 -306.873942) (xy 70.269112 -306.824888) (xy 69.930264 -306.824888)
			(xy 69.929769 -306.849495) (xy 69.921874 -306.898072) (xy 69.90629 -306.944753) (xy 69.883419 -306.98833)
			(xy 69.853854 -307.027674) (xy 69.818361 -307.061766) (xy 69.777858 -307.089722) (xy 69.733396 -307.11082)
			(xy 69.686125 -307.124512) (xy 69.63727 -307.130444) (xy 69.588095 -307.128463) (xy 69.539876 -307.118619)
			(xy 69.49386 -307.101167) (xy 69.451239 -307.07656) (xy 69.413118 -307.045435) (xy 69.380483 -307.008598)
			(xy 69.35418 -306.967002) (xy 69.334889 -306.921726) (xy 69.323112 -306.873942) (xy 69.319152 -306.824888)
			(xy 68.98005 -306.824888) (xy 68.979555 -306.849495) (xy 68.97166 -306.898072) (xy 68.956076 -306.944753)
			(xy 68.933205 -306.98833) (xy 68.90364 -307.027674) (xy 68.868147 -307.061766) (xy 68.827644 -307.089722)
			(xy 68.783182 -307.11082) (xy 68.735911 -307.124512) (xy 68.687056 -307.130444) (xy 68.637881 -307.128463)
			(xy 68.589662 -307.118619) (xy 68.543646 -307.101167) (xy 68.501025 -307.07656) (xy 68.462904 -307.045435)
			(xy 68.430269 -307.008598) (xy 68.403966 -306.967002) (xy 68.384675 -306.921726) (xy 68.372898 -306.873942)
			(xy 68.368938 -306.824888) (xy 68.03009 -306.824888) (xy 68.029595 -306.849495) (xy 68.0217 -306.898072)
			(xy 68.006116 -306.944753) (xy 67.983245 -306.98833) (xy 67.95368 -307.027674) (xy 67.918187 -307.061766)
			(xy 67.877684 -307.089722) (xy 67.833222 -307.11082) (xy 67.785951 -307.124512) (xy 67.737096 -307.130444)
			(xy 67.687921 -307.128463) (xy 67.639702 -307.118619) (xy 67.593686 -307.101167) (xy 67.551065 -307.07656)
			(xy 67.512944 -307.045435) (xy 67.480309 -307.008598) (xy 67.454006 -306.967002) (xy 67.434715 -306.921726)
			(xy 67.422938 -306.873942) (xy 67.418978 -306.824888) (xy 67.08013 -306.824888) (xy 67.079635 -306.849495)
			(xy 67.07174 -306.898072) (xy 67.056156 -306.944753) (xy 67.033285 -306.98833) (xy 67.00372 -307.027674)
			(xy 66.968227 -307.061766) (xy 66.927724 -307.089722) (xy 66.883262 -307.11082) (xy 66.835991 -307.124512)
			(xy 66.787136 -307.130444) (xy 66.737961 -307.128463) (xy 66.689742 -307.118619) (xy 66.643726 -307.101167)
			(xy 66.601105 -307.07656) (xy 66.562984 -307.045435) (xy 66.530349 -307.008598) (xy 66.504046 -306.967002)
			(xy 66.484755 -306.921726) (xy 66.472978 -306.873942) (xy 66.469018 -306.824888) (xy 66.13017 -306.824888)
			(xy 66.129675 -306.849495) (xy 66.12178 -306.898072) (xy 66.106196 -306.944753) (xy 66.083325 -306.98833)
			(xy 66.05376 -307.027674) (xy 66.018267 -307.061766) (xy 65.977764 -307.089722) (xy 65.933302 -307.11082)
			(xy 65.886031 -307.124512) (xy 65.837176 -307.130444) (xy 65.788001 -307.128463) (xy 65.739782 -307.118619)
			(xy 65.693766 -307.101167) (xy 65.651145 -307.07656) (xy 65.613024 -307.045435) (xy 65.580389 -307.008598)
			(xy 65.554086 -306.967002) (xy 65.534795 -306.921726) (xy 65.523018 -306.873942) (xy 65.519058 -306.824888)
			(xy 65.18021 -306.824888) (xy 65.179715 -306.849495) (xy 65.17182 -306.898072) (xy 65.156236 -306.944753)
			(xy 65.133365 -306.98833) (xy 65.1038 -307.027674) (xy 65.068307 -307.061766) (xy 65.027804 -307.089722)
			(xy 64.983342 -307.11082) (xy 64.936071 -307.124512) (xy 64.887216 -307.130444) (xy 64.838041 -307.128463)
			(xy 64.789822 -307.118619) (xy 64.743806 -307.101167) (xy 64.701185 -307.07656) (xy 64.663064 -307.045435)
			(xy 64.630429 -307.008598) (xy 64.604126 -306.967002) (xy 64.584835 -306.921726) (xy 64.573058 -306.873942)
			(xy 64.569098 -306.824888) (xy 64.23025 -306.824888) (xy 64.229755 -306.849495) (xy 64.22186 -306.898072)
			(xy 64.206276 -306.944753) (xy 64.183405 -306.98833) (xy 64.15384 -307.027674) (xy 64.118347 -307.061766)
			(xy 64.077844 -307.089722) (xy 64.033382 -307.11082) (xy 63.986111 -307.124512) (xy 63.937256 -307.130444)
			(xy 63.888081 -307.128463) (xy 63.839862 -307.118619) (xy 63.793846 -307.101167) (xy 63.751225 -307.07656)
			(xy 63.713104 -307.045435) (xy 63.680469 -307.008598) (xy 63.654166 -306.967002) (xy 63.634875 -306.921726)
			(xy 63.623098 -306.873942) (xy 63.619138 -306.824888) (xy 63.28029 -306.824888) (xy 63.279795 -306.849495)
			(xy 63.2719 -306.898072) (xy 63.256316 -306.944753) (xy 63.233445 -306.98833) (xy 63.20388 -307.027674)
			(xy 63.168387 -307.061766) (xy 63.127884 -307.089722) (xy 63.083422 -307.11082) (xy 63.036151 -307.124512)
			(xy 62.987296 -307.130444) (xy 62.938121 -307.128463) (xy 62.889902 -307.118619) (xy 62.843886 -307.101167)
			(xy 62.801265 -307.07656) (xy 62.763144 -307.045435) (xy 62.730509 -307.008598) (xy 62.704206 -306.967002)
			(xy 62.684915 -306.921726) (xy 62.673138 -306.873942) (xy 62.669178 -306.824888) (xy 62.330076 -306.824888)
			(xy 62.329581 -306.849495) (xy 62.321686 -306.898072) (xy 62.306102 -306.944753) (xy 62.283231 -306.98833)
			(xy 62.253666 -307.027674) (xy 62.218173 -307.061766) (xy 62.17767 -307.089722) (xy 62.133208 -307.11082)
			(xy 62.085937 -307.124512) (xy 62.037082 -307.130444) (xy 61.987907 -307.128463) (xy 61.939688 -307.118619)
			(xy 61.893672 -307.101167) (xy 61.851051 -307.07656) (xy 61.81293 -307.045435) (xy 61.780295 -307.008598)
			(xy 61.753992 -306.967002) (xy 61.734701 -306.921726) (xy 61.722924 -306.873942) (xy 61.718964 -306.824888)
			(xy 61.380116 -306.824888) (xy 61.379621 -306.849495) (xy 61.371726 -306.898072) (xy 61.356142 -306.944753)
			(xy 61.333271 -306.98833) (xy 61.303706 -307.027674) (xy 61.268213 -307.061766) (xy 61.22771 -307.089722)
			(xy 61.183248 -307.11082) (xy 61.135977 -307.124512) (xy 61.087122 -307.130444) (xy 61.037947 -307.128463)
			(xy 60.989728 -307.118619) (xy 60.943712 -307.101167) (xy 60.901091 -307.07656) (xy 60.86297 -307.045435)
			(xy 60.830335 -307.008598) (xy 60.804032 -306.967002) (xy 60.784741 -306.921726) (xy 60.772964 -306.873942)
			(xy 60.769004 -306.824888) (xy 60.430156 -306.824888) (xy 60.429661 -306.849495) (xy 60.421766 -306.898072)
			(xy 60.406182 -306.944753) (xy 60.383311 -306.98833) (xy 60.353746 -307.027674) (xy 60.318253 -307.061766)
			(xy 60.27775 -307.089722) (xy 60.233288 -307.11082) (xy 60.186017 -307.124512) (xy 60.137162 -307.130444)
			(xy 60.087987 -307.128463) (xy 60.039768 -307.118619) (xy 59.993752 -307.101167) (xy 59.951131 -307.07656)
			(xy 59.91301 -307.045435) (xy 59.880375 -307.008598) (xy 59.854072 -306.967002) (xy 59.834781 -306.921726)
			(xy 59.823004 -306.873942) (xy 59.819044 -306.824888) (xy 58.530236 -306.824888) (xy 58.529741 -306.849495)
			(xy 58.521846 -306.898072) (xy 58.506262 -306.944753) (xy 58.483391 -306.98833) (xy 58.453826 -307.027674)
			(xy 58.418333 -307.061766) (xy 58.37783 -307.089722) (xy 58.333368 -307.11082) (xy 58.286097 -307.124512)
			(xy 58.237242 -307.130444) (xy 58.188067 -307.128463) (xy 58.139848 -307.118619) (xy 58.093832 -307.101167)
			(xy 58.051211 -307.07656) (xy 58.01309 -307.045435) (xy 57.980455 -307.008598) (xy 57.954152 -306.967002)
			(xy 57.934861 -306.921726) (xy 57.923084 -306.873942) (xy 57.919124 -306.824888) (xy 57.580276 -306.824888)
			(xy 57.579781 -306.849495) (xy 57.571886 -306.898072) (xy 57.556302 -306.944753) (xy 57.533431 -306.98833)
			(xy 57.503866 -307.027674) (xy 57.468373 -307.061766) (xy 57.42787 -307.089722) (xy 57.383408 -307.11082)
			(xy 57.336137 -307.124512) (xy 57.287282 -307.130444) (xy 57.238107 -307.128463) (xy 57.189888 -307.118619)
			(xy 57.143872 -307.101167) (xy 57.101251 -307.07656) (xy 57.06313 -307.045435) (xy 57.030495 -307.008598)
			(xy 57.004192 -306.967002) (xy 56.984901 -306.921726) (xy 56.973124 -306.873942) (xy 56.969164 -306.824888)
			(xy 56.630062 -306.824888) (xy 56.629567 -306.849495) (xy 56.621672 -306.898072) (xy 56.606088 -306.944753)
			(xy 56.583217 -306.98833) (xy 56.553652 -307.027674) (xy 56.518159 -307.061766) (xy 56.477656 -307.089722)
			(xy 56.433194 -307.11082) (xy 56.385923 -307.124512) (xy 56.337068 -307.130444) (xy 56.287893 -307.128463)
			(xy 56.239674 -307.118619) (xy 56.193658 -307.101167) (xy 56.151037 -307.07656) (xy 56.112916 -307.045435)
			(xy 56.080281 -307.008598) (xy 56.053978 -306.967002) (xy 56.034687 -306.921726) (xy 56.02291 -306.873942)
			(xy 56.01895 -306.824888) (xy 55.680102 -306.824888) (xy 55.679607 -306.849495) (xy 55.671712 -306.898072)
			(xy 55.656128 -306.944753) (xy 55.633257 -306.98833) (xy 55.603692 -307.027674) (xy 55.568199 -307.061766)
			(xy 55.527696 -307.089722) (xy 55.483234 -307.11082) (xy 55.435963 -307.124512) (xy 55.387108 -307.130444)
			(xy 55.337933 -307.128463) (xy 55.289714 -307.118619) (xy 55.243698 -307.101167) (xy 55.201077 -307.07656)
			(xy 55.162956 -307.045435) (xy 55.130321 -307.008598) (xy 55.104018 -306.967002) (xy 55.084727 -306.921726)
			(xy 55.07295 -306.873942) (xy 55.06899 -306.824888) (xy 54.730142 -306.824888) (xy 54.729647 -306.849495)
			(xy 54.721752 -306.898072) (xy 54.706168 -306.944753) (xy 54.683297 -306.98833) (xy 54.653732 -307.027674)
			(xy 54.618239 -307.061766) (xy 54.577736 -307.089722) (xy 54.533274 -307.11082) (xy 54.486003 -307.124512)
			(xy 54.437148 -307.130444) (xy 54.387973 -307.128463) (xy 54.339754 -307.118619) (xy 54.293738 -307.101167)
			(xy 54.251117 -307.07656) (xy 54.212996 -307.045435) (xy 54.180361 -307.008598) (xy 54.154058 -306.967002)
			(xy 54.134767 -306.921726) (xy 54.12299 -306.873942) (xy 54.11903 -306.824888) (xy 53.780182 -306.824888)
			(xy 53.779687 -306.849495) (xy 53.771792 -306.898072) (xy 53.756208 -306.944753) (xy 53.733337 -306.98833)
			(xy 53.703772 -307.027674) (xy 53.668279 -307.061766) (xy 53.627776 -307.089722) (xy 53.583314 -307.11082)
			(xy 53.536043 -307.124512) (xy 53.487188 -307.130444) (xy 53.438013 -307.128463) (xy 53.389794 -307.118619)
			(xy 53.343778 -307.101167) (xy 53.301157 -307.07656) (xy 53.263036 -307.045435) (xy 53.230401 -307.008598)
			(xy 53.204098 -306.967002) (xy 53.184807 -306.921726) (xy 53.17303 -306.873942) (xy 53.16907 -306.824888)
			(xy 52.830222 -306.824888) (xy 52.829727 -306.849495) (xy 52.821832 -306.898072) (xy 52.806248 -306.944753)
			(xy 52.783377 -306.98833) (xy 52.753812 -307.027674) (xy 52.718319 -307.061766) (xy 52.677816 -307.089722)
			(xy 52.633354 -307.11082) (xy 52.586083 -307.124512) (xy 52.537228 -307.130444) (xy 52.488053 -307.128463)
			(xy 52.439834 -307.118619) (xy 52.393818 -307.101167) (xy 52.351197 -307.07656) (xy 52.313076 -307.045435)
			(xy 52.280441 -307.008598) (xy 52.254138 -306.967002) (xy 52.234847 -306.921726) (xy 52.22307 -306.873942)
			(xy 52.21911 -306.824888) (xy 51.880262 -306.824888) (xy 51.879767 -306.849495) (xy 51.871872 -306.898072)
			(xy 51.856288 -306.944753) (xy 51.833417 -306.98833) (xy 51.803852 -307.027674) (xy 51.768359 -307.061766)
			(xy 51.727856 -307.089722) (xy 51.683394 -307.11082) (xy 51.636123 -307.124512) (xy 51.587268 -307.130444)
			(xy 51.538093 -307.128463) (xy 51.489874 -307.118619) (xy 51.443858 -307.101167) (xy 51.401237 -307.07656)
			(xy 51.363116 -307.045435) (xy 51.330481 -307.008598) (xy 51.304178 -306.967002) (xy 51.284887 -306.921726)
			(xy 51.27311 -306.873942) (xy 51.26915 -306.824888) (xy 50.930275 -306.824888) (xy 50.930725 -306.83319)
			(xy 50.925356 -306.882541) (xy 50.912074 -306.930374) (xy 50.891229 -306.975428) (xy 50.863369 -307.016516)
			(xy 50.829229 -307.052555) (xy 50.789708 -307.082596) (xy 50.745848 -307.105848) (xy 50.698804 -307.121698)
			(xy 50.649815 -307.129729) (xy 50.624994 -307.130196) (xy 50.610748 -307.13002) (xy 50.58238 -307.127352)
			(xy 50.568352 -307.124862) (xy 50.55616 -307.122576) (xy 50.53203 -307.129942) (xy 50.454814 -307.207158)
			(xy 50.447448 -307.231034) (xy 50.449734 -307.24348) (xy 50.452221 -307.257445) (xy 50.454896 -307.285685)
			(xy 50.455068 -307.299868) (xy 73.593972 -307.299868) (xy 73.597932 -307.250814) (xy 73.609709 -307.20303)
			(xy 73.629 -307.157754) (xy 73.655303 -307.116158) (xy 73.687938 -307.079321) (xy 73.726059 -307.048196)
			(xy 73.76868 -307.023589) (xy 73.814696 -307.006137) (xy 73.862915 -306.996293) (xy 73.91209 -306.994312)
			(xy 73.960945 -307.000244) (xy 74.008216 -307.013936) (xy 74.052678 -307.035034) (xy 74.093181 -307.06299)
			(xy 74.128674 -307.097082) (xy 74.158239 -307.136426) (xy 74.18111 -307.180003) (xy 74.196694 -307.226684)
			(xy 74.204589 -307.275261) (xy 74.205084 -307.299868) (xy 74.544186 -307.299868) (xy 74.548146 -307.250814)
			(xy 74.559923 -307.20303) (xy 74.579214 -307.157754) (xy 74.605517 -307.116158) (xy 74.638152 -307.079321)
			(xy 74.676273 -307.048196) (xy 74.718894 -307.023589) (xy 74.76491 -307.006137) (xy 74.813129 -306.996293)
			(xy 74.862304 -306.994312) (xy 74.911159 -307.000244) (xy 74.95843 -307.013936) (xy 75.002892 -307.035034)
			(xy 75.043395 -307.06299) (xy 75.078888 -307.097082) (xy 75.108453 -307.136426) (xy 75.131324 -307.180003)
			(xy 75.146908 -307.226684) (xy 75.154803 -307.275261) (xy 75.155298 -307.299868) (xy 75.494146 -307.299868)
			(xy 75.498106 -307.250814) (xy 75.509883 -307.20303) (xy 75.529174 -307.157754) (xy 75.555477 -307.116158)
			(xy 75.588112 -307.079321) (xy 75.626233 -307.048196) (xy 75.668854 -307.023589) (xy 75.71487 -307.006137)
			(xy 75.763089 -306.996293) (xy 75.812264 -306.994312) (xy 75.861119 -307.000244) (xy 75.90839 -307.013936)
			(xy 75.952852 -307.035034) (xy 75.993355 -307.06299) (xy 76.028848 -307.097082) (xy 76.058413 -307.136426)
			(xy 76.081284 -307.180003) (xy 76.096868 -307.226684) (xy 76.104763 -307.275261) (xy 76.105258 -307.299868)
			(xy 76.104763 -307.324475) (xy 76.104584 -307.325576) (xy 76.423262 -307.325576) (xy 76.423262 -307.27416)
			(xy 76.431305 -307.223378) (xy 76.447193 -307.174479) (xy 76.470536 -307.128667) (xy 76.500757 -307.087071)
			(xy 76.537113 -307.050715) (xy 76.578709 -307.020494) (xy 76.624521 -306.997151) (xy 76.67342 -306.981263)
			(xy 76.724202 -306.97322) (xy 76.775618 -306.97322) (xy 76.8264 -306.981263) (xy 76.875299 -306.997151)
			(xy 76.921111 -307.020494) (xy 76.962707 -307.050715) (xy 76.999063 -307.087071) (xy 77.029284 -307.128667)
			(xy 77.052627 -307.174479) (xy 77.068515 -307.223378) (xy 77.076558 -307.27416) (xy 77.077062 -307.299868)
			(xy 77.076558 -307.325576) (xy 77.373222 -307.325576) (xy 77.373222 -307.27416) (xy 77.381265 -307.223378)
			(xy 77.397153 -307.174479) (xy 77.420496 -307.128667) (xy 77.450717 -307.087071) (xy 77.487073 -307.050715)
			(xy 77.528669 -307.020494) (xy 77.574481 -306.997151) (xy 77.62338 -306.981263) (xy 77.674162 -306.97322)
			(xy 77.725578 -306.97322) (xy 77.77636 -306.981263) (xy 77.825259 -306.997151) (xy 77.871071 -307.020494)
			(xy 77.912667 -307.050715) (xy 77.949023 -307.087071) (xy 77.979244 -307.128667) (xy 78.002587 -307.174479)
			(xy 78.018475 -307.223378) (xy 78.026518 -307.27416) (xy 78.027022 -307.299868) (xy 78.344026 -307.299868)
			(xy 78.347986 -307.250814) (xy 78.359763 -307.20303) (xy 78.379054 -307.157754) (xy 78.405357 -307.116158)
			(xy 78.437992 -307.079321) (xy 78.476113 -307.048196) (xy 78.518734 -307.023589) (xy 78.56475 -307.006137)
			(xy 78.612969 -306.996293) (xy 78.662144 -306.994312) (xy 78.710999 -307.000244) (xy 78.75827 -307.013936)
			(xy 78.802732 -307.035034) (xy 78.843235 -307.06299) (xy 78.878728 -307.097082) (xy 78.908293 -307.136426)
			(xy 78.931164 -307.180003) (xy 78.946748 -307.226684) (xy 78.954643 -307.275261) (xy 78.955138 -307.299868)
			(xy 79.293986 -307.299868) (xy 79.297946 -307.250814) (xy 79.309723 -307.20303) (xy 79.329014 -307.157754)
			(xy 79.355317 -307.116158) (xy 79.387952 -307.079321) (xy 79.426073 -307.048196) (xy 79.468694 -307.023589)
			(xy 79.51471 -307.006137) (xy 79.562929 -306.996293) (xy 79.612104 -306.994312) (xy 79.660959 -307.000244)
			(xy 79.70823 -307.013936) (xy 79.752692 -307.035034) (xy 79.793195 -307.06299) (xy 79.828688 -307.097082)
			(xy 79.858253 -307.136426) (xy 79.881124 -307.180003) (xy 79.896708 -307.226684) (xy 79.904603 -307.275261)
			(xy 79.905098 -307.299868) (xy 80.243946 -307.299868) (xy 80.247906 -307.250814) (xy 80.259683 -307.20303)
			(xy 80.278974 -307.157754) (xy 80.305277 -307.116158) (xy 80.337912 -307.079321) (xy 80.376033 -307.048196)
			(xy 80.418654 -307.023589) (xy 80.46467 -307.006137) (xy 80.512889 -306.996293) (xy 80.562064 -306.994312)
			(xy 80.610919 -307.000244) (xy 80.65819 -307.013936) (xy 80.702652 -307.035034) (xy 80.743155 -307.06299)
			(xy 80.778648 -307.097082) (xy 80.808213 -307.136426) (xy 80.831084 -307.180003) (xy 80.846668 -307.226684)
			(xy 80.854563 -307.275261) (xy 80.855058 -307.299868) (xy 81.19416 -307.299868) (xy 81.19812 -307.250814)
			(xy 81.209897 -307.20303) (xy 81.229188 -307.157754) (xy 81.255491 -307.116158) (xy 81.288126 -307.079321)
			(xy 81.326247 -307.048196) (xy 81.368868 -307.023589) (xy 81.414884 -307.006137) (xy 81.463103 -306.996293)
			(xy 81.512278 -306.994312) (xy 81.561133 -307.000244) (xy 81.608404 -307.013936) (xy 81.652866 -307.035034)
			(xy 81.693369 -307.06299) (xy 81.728862 -307.097082) (xy 81.758427 -307.136426) (xy 81.781298 -307.180003)
			(xy 81.796882 -307.226684) (xy 81.804777 -307.275261) (xy 81.805272 -307.299868) (xy 82.14412 -307.299868)
			(xy 82.14808 -307.250814) (xy 82.159857 -307.20303) (xy 82.179148 -307.157754) (xy 82.205451 -307.116158)
			(xy 82.238086 -307.079321) (xy 82.276207 -307.048196) (xy 82.318828 -307.023589) (xy 82.364844 -307.006137)
			(xy 82.413063 -306.996293) (xy 82.462238 -306.994312) (xy 82.511093 -307.000244) (xy 82.558364 -307.013936)
			(xy 82.602826 -307.035034) (xy 82.643329 -307.06299) (xy 82.678822 -307.097082) (xy 82.708387 -307.136426)
			(xy 82.731258 -307.180003) (xy 82.746842 -307.226684) (xy 82.754737 -307.275261) (xy 82.755232 -307.299868)
			(xy 82.754955 -307.313639) (xy 91.226391 -307.313639) (xy 91.226393 -307.259139) (xy 91.234151 -307.205193)
			(xy 91.249507 -307.152901) (xy 91.272148 -307.103327) (xy 91.301615 -307.057479) (xy 91.337306 -307.016292)
			(xy 91.378495 -306.980603) (xy 91.424344 -306.951139) (xy 91.47392 -306.9285) (xy 91.526213 -306.913147)
			(xy 91.580159 -306.905392) (xy 91.634659 -306.905393) (xy 91.688604 -306.91315) (xy 91.740896 -306.928506)
			(xy 91.790471 -306.951147) (xy 91.836319 -306.980613) (xy 91.877507 -307.016304) (xy 91.913196 -307.057493)
			(xy 91.930373 -307.084222) (xy 92.714316 -307.084222) (xy 92.718387 -307.0286) (xy 92.730513 -306.974163)
			(xy 92.750436 -306.922072) (xy 92.777732 -306.873437) (xy 92.811818 -306.829294) (xy 92.851967 -306.790585)
			(xy 92.897325 -306.758134) (xy 92.946925 -306.732633) (xy 92.999709 -306.714626) (xy 93.054552 -306.704496)
			(xy 93.110286 -306.702459) (xy 93.165723 -306.708559) (xy 93.21968 -306.722665) (xy 93.271009 -306.744477)
			(xy 93.318615 -306.773531) (xy 93.361483 -306.809206) (xy 93.3987 -306.850743) (xy 93.429473 -306.897256)
			(xy 93.453145 -306.947753) (xy 93.469213 -307.00116) (xy 93.477333 -307.056336) (xy 93.477842 -307.084222)
			(xy 93.477333 -307.112108) (xy 93.469213 -307.167284) (xy 93.453145 -307.220691) (xy 93.429473 -307.271188)
			(xy 93.3987 -307.317701) (xy 93.361483 -307.359238) (xy 93.318615 -307.394913) (xy 93.271009 -307.423967)
			(xy 93.21968 -307.445779) (xy 93.165723 -307.459885) (xy 93.110286 -307.465985) (xy 93.054552 -307.463948)
			(xy 92.999709 -307.453818) (xy 92.946925 -307.435811) (xy 92.897325 -307.41031) (xy 92.851967 -307.377859)
			(xy 92.811818 -307.33915) (xy 92.777732 -307.295007) (xy 92.750436 -307.246372) (xy 92.730513 -307.194281)
			(xy 92.718387 -307.139844) (xy 92.714316 -307.084222) (xy 91.930373 -307.084222) (xy 91.94266 -307.103342)
			(xy 91.965299 -307.152918) (xy 91.980653 -307.20521) (xy 91.988408 -307.259156) (xy 91.988894 -307.286406)
			(xy 91.987116 -307.322982) (xy 91.9861 -307.334412) (xy 91.99372 -307.355494) (xy 92.065348 -307.427122)
			(xy 92.086684 -307.434742) (xy 92.098114 -307.433726) (xy 92.13469 -307.431948) (xy 92.161939 -307.432487)
			(xy 92.215882 -307.440241) (xy 92.268173 -307.455593) (xy 92.317748 -307.47823) (xy 92.363596 -307.507691)
			(xy 92.404785 -307.543377) (xy 92.440477 -307.584561) (xy 92.469944 -307.630405) (xy 92.492588 -307.679976)
			(xy 92.507947 -307.732265) (xy 92.515709 -307.786207) (xy 92.516198 -307.813456) (xy 92.516033 -307.82387)
			(xy 102.823518 -307.82387) (xy 102.823962 -307.796499) (xy 102.831785 -307.742319) (xy 102.847279 -307.689815)
			(xy 102.870125 -307.640069) (xy 102.899855 -307.594103) (xy 102.917498 -307.573172) (xy 102.923594 -307.56606)
			(xy 102.929944 -307.549042) (xy 102.929944 -307.463698) (xy 102.923594 -307.44668) (xy 102.917498 -307.439568)
			(xy 102.899829 -307.418658) (xy 102.870108 -307.372686) (xy 102.847266 -307.322936) (xy 102.831773 -307.27043)
			(xy 102.823948 -307.216249) (xy 102.823951 -307.161506) (xy 102.831783 -307.107325) (xy 102.847282 -307.054822)
			(xy 102.87013 -307.005074) (xy 102.899856 -306.959105) (xy 102.917498 -306.938172) (xy 102.923594 -306.93106)
			(xy 102.929944 -306.914042) (xy 102.929944 -306.828698) (xy 102.923594 -306.81168) (xy 102.917498 -306.804568)
			(xy 102.899829 -306.783658) (xy 102.870108 -306.737686) (xy 102.847266 -306.687936) (xy 102.831773 -306.63543)
			(xy 102.823948 -306.581249) (xy 102.823951 -306.526506) (xy 102.831783 -306.472325) (xy 102.847282 -306.419822)
			(xy 102.87013 -306.370074) (xy 102.899856 -306.324105) (xy 102.917498 -306.303172) (xy 102.923594 -306.29606)
			(xy 102.929944 -306.279042) (xy 102.929944 -306.193698) (xy 102.923594 -306.17668) (xy 102.917498 -306.169568)
			(xy 102.899877 -306.148621) (xy 102.870163 -306.102653) (xy 102.847323 -306.052909) (xy 102.831828 -306.000411)
			(xy 102.823995 -305.946238) (xy 102.823518 -305.91887) (xy 102.824004 -305.891619) (xy 102.83176 -305.837671)
			(xy 102.847115 -305.785376) (xy 102.869757 -305.735799) (xy 102.899223 -305.689949) (xy 102.934914 -305.648758)
			(xy 102.976105 -305.613067) (xy 103.021955 -305.583601) (xy 103.071532 -305.560959) (xy 103.123827 -305.545604)
			(xy 103.177775 -305.537848) (xy 103.232277 -305.537848) (xy 103.286225 -305.545604) (xy 103.33852 -305.560959)
			(xy 103.388097 -305.583601) (xy 103.433947 -305.613067) (xy 103.475138 -305.648758) (xy 103.510829 -305.689949)
			(xy 103.540295 -305.735799) (xy 103.562937 -305.785376) (xy 103.578292 -305.837671) (xy 103.586048 -305.891619)
			(xy 103.586534 -305.91887) (xy 103.586066 -305.94624) (xy 103.578251 -306.00042) (xy 103.562764 -306.052924)
			(xy 103.539922 -306.102671) (xy 103.510196 -306.148637) (xy 103.492554 -306.169568) (xy 103.486458 -306.17668)
			(xy 103.480108 -306.193698) (xy 103.480108 -306.279042) (xy 103.486458 -306.29606) (xy 103.492554 -306.303172)
			(xy 103.510166 -306.324128) (xy 103.539894 -306.370091) (xy 103.562742 -306.419834) (xy 103.578241 -306.472332)
			(xy 103.586073 -306.526508) (xy 103.586076 -306.581247) (xy 103.578251 -306.635423) (xy 103.562758 -306.687924)
			(xy 103.539915 -306.737669) (xy 103.510193 -306.783636) (xy 103.492554 -306.804568) (xy 103.486458 -306.81168)
			(xy 103.480108 -306.828698) (xy 103.480108 -306.914042) (xy 103.486458 -306.93106) (xy 103.492554 -306.938172)
			(xy 103.510166 -306.959128) (xy 103.539894 -307.005091) (xy 103.562742 -307.054834) (xy 103.578241 -307.107332)
			(xy 103.586073 -307.161508) (xy 103.586076 -307.216247) (xy 103.578251 -307.270423) (xy 103.562758 -307.322924)
			(xy 103.539915 -307.372669) (xy 103.510193 -307.418636) (xy 103.492554 -307.439568) (xy 103.486458 -307.44668)
			(xy 103.480108 -307.463698) (xy 103.480108 -307.549042) (xy 103.486458 -307.56606) (xy 103.492554 -307.573172)
			(xy 103.510186 -307.59411) (xy 103.539901 -307.64008) (xy 103.562739 -307.689826) (xy 103.578231 -307.742326)
			(xy 103.58606 -307.796501) (xy 103.586534 -307.82387) (xy 103.586048 -307.851121) (xy 103.582224 -307.877718)
			(xy 106.455718 -307.877718) (xy 106.45619 -307.850348) (xy 106.464006 -307.796169) (xy 106.479493 -307.743666)
			(xy 106.502334 -307.693919) (xy 106.532057 -307.647952) (xy 106.549698 -307.62702) (xy 106.555794 -307.619908)
			(xy 106.562144 -307.60289) (xy 106.562144 -307.517546) (xy 106.555794 -307.500528) (xy 106.549698 -307.493416)
			(xy 106.532076 -307.472468) (xy 106.502353 -307.426502) (xy 106.479508 -307.376759) (xy 106.464012 -307.324259)
			(xy 106.456182 -307.270083) (xy 106.45618 -307.215344) (xy 106.464006 -307.161168) (xy 106.479499 -307.108667)
			(xy 106.50234 -307.058921) (xy 106.53206 -307.012953) (xy 106.549698 -306.99202) (xy 106.555794 -306.984908)
			(xy 106.562144 -306.96789) (xy 106.562144 -306.882546) (xy 106.555794 -306.865528) (xy 106.549698 -306.858416)
			(xy 106.532076 -306.837468) (xy 106.502353 -306.791502) (xy 106.479508 -306.741759) (xy 106.464012 -306.689259)
			(xy 106.456182 -306.635083) (xy 106.45618 -306.580344) (xy 106.464006 -306.526168) (xy 106.479499 -306.473667)
			(xy 106.50234 -306.423921) (xy 106.53206 -306.377953) (xy 106.549698 -306.35702) (xy 106.555794 -306.349908)
			(xy 106.562144 -306.33289) (xy 106.562144 -306.247546) (xy 106.555794 -306.230528) (xy 106.549698 -306.223416)
			(xy 106.532053 -306.202489) (xy 106.502342 -306.156515) (xy 106.479507 -306.106766) (xy 106.464018 -306.054264)
			(xy 106.456191 -306.000088) (xy 106.455718 -305.972718) (xy 106.456204 -305.945467) (xy 106.46396 -305.891519)
			(xy 106.479315 -305.839224) (xy 106.501957 -305.789647) (xy 106.531423 -305.743797) (xy 106.567114 -305.702606)
			(xy 106.608305 -305.666915) (xy 106.654155 -305.637449) (xy 106.703732 -305.614807) (xy 106.756027 -305.599452)
			(xy 106.809975 -305.591696) (xy 106.864477 -305.591696) (xy 106.918425 -305.599452) (xy 106.97072 -305.614807)
			(xy 107.020297 -305.637449) (xy 107.066147 -305.666915) (xy 107.107338 -305.702606) (xy 107.143029 -305.743797)
			(xy 107.172495 -305.789647) (xy 107.195137 -305.839224) (xy 107.210492 -305.891519) (xy 107.218248 -305.945467)
			(xy 107.218734 -305.972718) (xy 107.218295 -306.000089) (xy 107.210473 -306.05427) (xy 107.194978 -306.106774)
			(xy 107.17213 -306.156521) (xy 107.142399 -306.202486) (xy 107.124754 -306.223416) (xy 107.118658 -306.230528)
			(xy 107.112308 -306.247546) (xy 107.112308 -306.33289) (xy 107.118658 -306.349908) (xy 107.124754 -306.35702)
			(xy 107.142413 -306.377938) (xy 107.172139 -306.423908) (xy 107.194984 -306.473657) (xy 107.21048 -306.526161)
			(xy 107.218307 -306.580342) (xy 107.218305 -306.635085) (xy 107.210474 -306.689266) (xy 107.194975 -306.741769)
			(xy 107.172126 -306.791516) (xy 107.142397 -306.837484) (xy 107.124754 -306.858416) (xy 107.118658 -306.865528)
			(xy 107.112308 -306.882546) (xy 107.112308 -306.96789) (xy 107.118658 -306.984908) (xy 107.124754 -306.99202)
			(xy 107.142413 -307.012938) (xy 107.172139 -307.058908) (xy 107.194984 -307.108657) (xy 107.21048 -307.161161)
			(xy 107.218307 -307.215342) (xy 107.218305 -307.270085) (xy 107.210474 -307.324266) (xy 107.194975 -307.376769)
			(xy 107.172126 -307.426516) (xy 107.142397 -307.472484) (xy 107.124754 -307.493416) (xy 107.118658 -307.500528)
			(xy 107.112308 -307.517546) (xy 107.112308 -307.60289) (xy 107.118658 -307.619908) (xy 107.124754 -307.62702)
			(xy 107.142362 -307.647977) (xy 107.17208 -307.693942) (xy 107.194923 -307.743683) (xy 107.210421 -307.796179)
			(xy 107.214426 -307.82387) (xy 109.663738 -307.82387) (xy 109.664177 -307.796499) (xy 109.672 -307.742318)
			(xy 109.687495 -307.689814) (xy 109.710343 -307.640068) (xy 109.740074 -307.594103) (xy 109.757718 -307.573172)
			(xy 109.763814 -307.56606) (xy 109.770164 -307.549042) (xy 109.770164 -307.463698) (xy 109.763814 -307.44668)
			(xy 109.757718 -307.439568) (xy 109.740048 -307.418659) (xy 109.710325 -307.372687) (xy 109.687482 -307.322937)
			(xy 109.671989 -307.270431) (xy 109.664163 -307.216249) (xy 109.664166 -307.161506) (xy 109.671998 -307.107325)
			(xy 109.687498 -307.054821) (xy 109.710347 -307.005074) (xy 109.740076 -306.959105) (xy 109.757718 -306.938172)
			(xy 109.763814 -306.93106) (xy 109.770164 -306.914042) (xy 109.770164 -306.828698) (xy 109.763814 -306.81168)
			(xy 109.757718 -306.804568) (xy 109.740048 -306.783659) (xy 109.710325 -306.737687) (xy 109.687482 -306.687937)
			(xy 109.671989 -306.635431) (xy 109.664163 -306.581249) (xy 109.664166 -306.526506) (xy 109.671998 -306.472325)
			(xy 109.687498 -306.419821) (xy 109.710347 -306.370074) (xy 109.740076 -306.324105) (xy 109.757718 -306.303172)
			(xy 109.763814 -306.29606) (xy 109.770164 -306.279042) (xy 109.770164 -306.193698) (xy 109.763814 -306.17668)
			(xy 109.757718 -306.169568) (xy 109.7401 -306.148619) (xy 109.710384 -306.102651) (xy 109.687544 -306.052908)
			(xy 109.672048 -306.000411) (xy 109.664215 -305.946238) (xy 109.663738 -305.91887) (xy 109.664224 -305.891619)
			(xy 109.67198 -305.837671) (xy 109.687335 -305.785376) (xy 109.709977 -305.735799) (xy 109.739443 -305.689949)
			(xy 109.775134 -305.648758) (xy 109.816325 -305.613067) (xy 109.862175 -305.583601) (xy 109.911752 -305.560959)
			(xy 109.964047 -305.545604) (xy 110.017995 -305.537848) (xy 110.072497 -305.537848) (xy 110.126445 -305.545604)
			(xy 110.17874 -305.560959) (xy 110.228317 -305.583601) (xy 110.274167 -305.613067) (xy 110.315358 -305.648758)
			(xy 110.351049 -305.689949) (xy 110.380515 -305.735799) (xy 110.403157 -305.785376) (xy 110.418512 -305.837671)
			(xy 110.426268 -305.891619) (xy 110.426754 -305.91887) (xy 110.426282 -305.94624) (xy 110.418467 -306.000419)
			(xy 110.40298 -306.052923) (xy 110.380139 -306.10267) (xy 110.350415 -306.148637) (xy 110.332774 -306.169568)
			(xy 110.326678 -306.17668) (xy 110.320328 -306.193698) (xy 110.320328 -306.279042) (xy 110.326678 -306.29606)
			(xy 110.332774 -306.303172) (xy 110.350385 -306.324129) (xy 110.380111 -306.370092) (xy 110.402958 -306.419835)
			(xy 110.418457 -306.472333) (xy 110.426288 -306.526508) (xy 110.426291 -306.581247) (xy 110.418466 -306.635423)
			(xy 110.402974 -306.687923) (xy 110.380133 -306.737668) (xy 110.350413 -306.783635) (xy 110.332774 -306.804568)
			(xy 110.326678 -306.81168) (xy 110.320328 -306.828698) (xy 110.320328 -306.914042) (xy 110.326678 -306.93106)
			(xy 110.332774 -306.938172) (xy 110.350385 -306.959129) (xy 110.380111 -307.005092) (xy 110.402958 -307.054835)
			(xy 110.418457 -307.107333) (xy 110.426288 -307.161508) (xy 110.426291 -307.216247) (xy 110.418466 -307.270423)
			(xy 110.402974 -307.322923) (xy 110.380133 -307.372668) (xy 110.350413 -307.418635) (xy 110.332774 -307.439568)
			(xy 110.326678 -307.44668) (xy 110.320328 -307.463698) (xy 110.320328 -307.549042) (xy 110.326678 -307.56606)
			(xy 110.332774 -307.573172) (xy 110.350409 -307.594107) (xy 110.380123 -307.640079) (xy 110.40296 -307.689825)
			(xy 110.418452 -307.742326) (xy 110.42628 -307.796501) (xy 110.426754 -307.82387) (xy 110.426268 -307.851121)
			(xy 110.422444 -307.877718) (xy 113.295938 -307.877718) (xy 113.296405 -307.850348) (xy 113.304221 -307.796168)
			(xy 113.31971 -307.743665) (xy 113.342551 -307.693918) (xy 113.372276 -307.647951) (xy 113.389918 -307.62702)
			(xy 113.396014 -307.619908) (xy 113.402364 -307.60289) (xy 113.402364 -307.517546) (xy 113.396014 -307.500528)
			(xy 113.389918 -307.493416) (xy 113.372295 -307.472469) (xy 113.34257 -307.426503) (xy 113.319725 -307.376759)
			(xy 113.304227 -307.32426) (xy 113.296397 -307.270083) (xy 113.296395 -307.215344) (xy 113.304222 -307.161167)
			(xy 113.319715 -307.108666) (xy 113.342557 -307.05892) (xy 113.372279 -307.012953) (xy 113.389918 -306.99202)
			(xy 113.396014 -306.984908) (xy 113.402364 -306.96789) (xy 113.402364 -306.882546) (xy 113.396014 -306.865528)
			(xy 113.389918 -306.858416) (xy 113.372295 -306.837469) (xy 113.34257 -306.791503) (xy 113.319725 -306.741759)
			(xy 113.304227 -306.68926) (xy 113.296397 -306.635083) (xy 113.296395 -306.580344) (xy 113.304222 -306.526167)
			(xy 113.319715 -306.473666) (xy 113.342557 -306.42392) (xy 113.372279 -306.377953) (xy 113.389918 -306.35702)
			(xy 113.396014 -306.349908) (xy 113.402364 -306.33289) (xy 113.402364 -306.247546) (xy 113.396014 -306.230528)
			(xy 113.389918 -306.223416) (xy 113.372276 -306.202486) (xy 113.342564 -306.156513) (xy 113.319728 -306.106765)
			(xy 113.304238 -306.054264) (xy 113.296411 -306.000087) (xy 113.295938 -305.972718) (xy 113.296424 -305.945467)
			(xy 113.30418 -305.891519) (xy 113.319535 -305.839224) (xy 113.342177 -305.789647) (xy 113.371643 -305.743797)
			(xy 113.407334 -305.702606) (xy 113.448525 -305.666915) (xy 113.494375 -305.637449) (xy 113.543952 -305.614807)
			(xy 113.596247 -305.599452) (xy 113.650195 -305.591696) (xy 113.704697 -305.591696) (xy 113.758645 -305.599452)
			(xy 113.81094 -305.614807) (xy 113.860517 -305.637449) (xy 113.906367 -305.666915) (xy 113.947558 -305.702606)
			(xy 113.983249 -305.743797) (xy 114.012715 -305.789647) (xy 114.035357 -305.839224) (xy 114.050712 -305.891519)
			(xy 114.058468 -305.945467) (xy 114.058954 -305.972718) (xy 114.05851 -306.000089) (xy 114.050688 -306.05427)
			(xy 114.035195 -306.106773) (xy 114.012348 -306.15652) (xy 113.982618 -306.202485) (xy 113.964974 -306.223416)
			(xy 113.958878 -306.230528) (xy 113.952528 -306.247546) (xy 113.952528 -306.33289) (xy 113.958878 -306.349908)
			(xy 113.964974 -306.35702) (xy 113.982632 -306.377938) (xy 114.012356 -306.423909) (xy 114.035201 -306.473657)
			(xy 114.050695 -306.526162) (xy 114.058522 -306.580342) (xy 114.05852 -306.635085) (xy 114.05069 -306.689265)
			(xy 114.035191 -306.741768) (xy 114.012343 -306.791515) (xy 113.982616 -306.837483) (xy 113.964974 -306.858416)
			(xy 113.958878 -306.865528) (xy 113.952528 -306.882546) (xy 113.952528 -306.96789) (xy 113.958878 -306.984908)
			(xy 113.964974 -306.99202) (xy 113.982632 -307.012938) (xy 114.012356 -307.058909) (xy 114.035201 -307.108657)
			(xy 114.050695 -307.161162) (xy 114.058522 -307.215342) (xy 114.05852 -307.270085) (xy 114.05069 -307.324265)
			(xy 114.035191 -307.376768) (xy 114.012343 -307.426515) (xy 113.982616 -307.472483) (xy 113.964974 -307.493416)
			(xy 113.958878 -307.500528) (xy 113.952528 -307.517546) (xy 113.952528 -307.60289) (xy 113.958878 -307.619908)
			(xy 113.964974 -307.62702) (xy 113.982585 -307.647975) (xy 114.012302 -307.693941) (xy 114.035144 -307.743683)
			(xy 114.050641 -307.796178) (xy 114.058476 -307.85035) (xy 114.058954 -307.877718) (xy 114.058468 -307.904969)
			(xy 114.050712 -307.958917) (xy 114.035357 -308.011212) (xy 114.012715 -308.060789) (xy 113.983249 -308.106639)
			(xy 113.947558 -308.14783) (xy 113.906367 -308.183521) (xy 113.860517 -308.212987) (xy 113.81094 -308.235629)
			(xy 113.758645 -308.250984) (xy 113.704697 -308.25874) (xy 113.650195 -308.25874) (xy 113.596247 -308.250984)
			(xy 113.543952 -308.235629) (xy 113.494375 -308.212987) (xy 113.448525 -308.183521) (xy 113.407334 -308.14783)
			(xy 113.371643 -308.106639) (xy 113.342177 -308.060789) (xy 113.319535 -308.011212) (xy 113.30418 -307.958917)
			(xy 113.296424 -307.904969) (xy 113.295938 -307.877718) (xy 110.422444 -307.877718) (xy 110.418512 -307.905069)
			(xy 110.403157 -307.957364) (xy 110.380515 -308.006941) (xy 110.351049 -308.052791) (xy 110.315358 -308.093982)
			(xy 110.274167 -308.129673) (xy 110.228317 -308.159139) (xy 110.17874 -308.181781) (xy 110.126445 -308.197136)
			(xy 110.072497 -308.204892) (xy 110.017995 -308.204892) (xy 109.964047 -308.197136) (xy 109.911752 -308.181781)
			(xy 109.862175 -308.159139) (xy 109.816325 -308.129673) (xy 109.775134 -308.093982) (xy 109.739443 -308.052791)
			(xy 109.709977 -308.006941) (xy 109.687335 -307.957364) (xy 109.67198 -307.905069) (xy 109.664224 -307.851121)
			(xy 109.663738 -307.82387) (xy 107.214426 -307.82387) (xy 107.218256 -307.85035) (xy 107.218734 -307.877718)
			(xy 107.218248 -307.904969) (xy 107.210492 -307.958917) (xy 107.195137 -308.011212) (xy 107.172495 -308.060789)
			(xy 107.143029 -308.106639) (xy 107.107338 -308.14783) (xy 107.066147 -308.183521) (xy 107.020297 -308.212987)
			(xy 106.97072 -308.235629) (xy 106.918425 -308.250984) (xy 106.864477 -308.25874) (xy 106.809975 -308.25874)
			(xy 106.756027 -308.250984) (xy 106.703732 -308.235629) (xy 106.654155 -308.212987) (xy 106.608305 -308.183521)
			(xy 106.567114 -308.14783) (xy 106.531423 -308.106639) (xy 106.501957 -308.060789) (xy 106.479315 -308.011212)
			(xy 106.46396 -307.958917) (xy 106.456204 -307.904969) (xy 106.455718 -307.877718) (xy 103.582224 -307.877718)
			(xy 103.578292 -307.905069) (xy 103.562937 -307.957364) (xy 103.540295 -308.006941) (xy 103.510829 -308.052791)
			(xy 103.475138 -308.093982) (xy 103.433947 -308.129673) (xy 103.388097 -308.159139) (xy 103.33852 -308.181781)
			(xy 103.286225 -308.197136) (xy 103.232277 -308.204892) (xy 103.177775 -308.204892) (xy 103.123827 -308.197136)
			(xy 103.071532 -308.181781) (xy 103.021955 -308.159139) (xy 102.976105 -308.129673) (xy 102.934914 -308.093982)
			(xy 102.899223 -308.052791) (xy 102.869757 -308.006941) (xy 102.847115 -307.957364) (xy 102.83176 -307.905069)
			(xy 102.824004 -307.851121) (xy 102.823518 -307.82387) (xy 92.516033 -307.82387) (xy 92.515841 -307.835962)
			(xy 92.510498 -307.880656) (xy 92.50553 -307.90261) (xy 92.502482 -307.915818) (xy 92.509594 -307.940964)
			(xy 92.589858 -308.021228) (xy 92.615004 -308.02834) (xy 92.628212 -308.025292) (xy 92.650166 -308.020324)
			(xy 92.69486 -308.014981) (xy 92.717366 -308.014624) (xy 92.744621 -308.015018) (xy 92.798578 -308.022771)
			(xy 92.850882 -308.038124) (xy 92.900469 -308.060764) (xy 92.946328 -308.090231) (xy 92.987528 -308.125924)
			(xy 93.023229 -308.167118) (xy 93.052703 -308.212972) (xy 93.075352 -308.262555) (xy 93.090714 -308.314856)
			(xy 93.098477 -308.368811) (xy 93.098481 -308.423322) (xy 93.090728 -308.477279) (xy 93.075376 -308.529583)
			(xy 93.052735 -308.579169) (xy 93.023269 -308.625029) (xy 92.987575 -308.666229) (xy 92.946382 -308.701929)
			(xy 92.900527 -308.731404) (xy 92.850944 -308.754052) (xy 92.798643 -308.769414) (xy 92.744688 -308.777177)
			(xy 92.690177 -308.777181) (xy 92.636221 -308.769428) (xy 92.583917 -308.754075) (xy 92.53433 -308.731435)
			(xy 92.48847 -308.701968) (xy 92.447271 -308.666275) (xy 92.411571 -308.625081) (xy 92.382096 -308.579227)
			(xy 92.359447 -308.529644) (xy 92.344085 -308.477343) (xy 92.336323 -308.423387) (xy 92.335858 -308.396132)
			(xy 92.336212 -308.373626) (xy 92.341557 -308.328931) (xy 92.346526 -308.306978) (xy 92.349574 -308.29377)
			(xy 92.342462 -308.268624) (xy 92.262198 -308.18836) (xy 92.237052 -308.181248) (xy 92.223844 -308.184296)
			(xy 92.201888 -308.189254) (xy 92.157195 -308.194604) (xy 92.13469 -308.194964) (xy 92.107435 -308.194554)
			(xy 92.05348 -308.186795) (xy 92.001178 -308.171435) (xy 91.951595 -308.148788) (xy 91.90574 -308.119315)
			(xy 91.864546 -308.083616) (xy 91.828852 -308.042417) (xy 91.799386 -307.996558) (xy 91.776746 -307.946971)
			(xy 91.761394 -307.894667) (xy 91.753642 -307.840711) (xy 91.753182 -307.813456) (xy 91.75496 -307.77688)
			(xy 91.755976 -307.76545) (xy 91.748356 -307.744368) (xy 91.676728 -307.67274) (xy 91.655392 -307.66512)
			(xy 91.643962 -307.666136) (xy 91.607386 -307.667914) (xy 91.580136 -307.667407) (xy 91.526191 -307.659649)
			(xy 91.473899 -307.644292) (xy 91.424324 -307.62165) (xy 91.378477 -307.592184) (xy 91.33729 -307.556492)
			(xy 91.301601 -307.515303) (xy 91.272137 -307.469453) (xy 91.249499 -307.419877) (xy 91.234146 -307.367584)
			(xy 91.226391 -307.313639) (xy 82.754955 -307.313639) (xy 82.754737 -307.324475) (xy 82.746842 -307.373052)
			(xy 82.731258 -307.419733) (xy 82.708387 -307.46331) (xy 82.678822 -307.502654) (xy 82.643329 -307.536746)
			(xy 82.602826 -307.564702) (xy 82.558364 -307.5858) (xy 82.511093 -307.599492) (xy 82.462238 -307.605424)
			(xy 82.413063 -307.603443) (xy 82.364844 -307.593599) (xy 82.318828 -307.576147) (xy 82.276207 -307.55154)
			(xy 82.238086 -307.520415) (xy 82.205451 -307.483578) (xy 82.179148 -307.441982) (xy 82.159857 -307.396706)
			(xy 82.14808 -307.348922) (xy 82.14412 -307.299868) (xy 81.805272 -307.299868) (xy 81.804777 -307.324475)
			(xy 81.796882 -307.373052) (xy 81.781298 -307.419733) (xy 81.758427 -307.46331) (xy 81.728862 -307.502654)
			(xy 81.693369 -307.536746) (xy 81.652866 -307.564702) (xy 81.608404 -307.5858) (xy 81.561133 -307.599492)
			(xy 81.512278 -307.605424) (xy 81.463103 -307.603443) (xy 81.414884 -307.593599) (xy 81.368868 -307.576147)
			(xy 81.326247 -307.55154) (xy 81.288126 -307.520415) (xy 81.255491 -307.483578) (xy 81.229188 -307.441982)
			(xy 81.209897 -307.396706) (xy 81.19812 -307.348922) (xy 81.19416 -307.299868) (xy 80.855058 -307.299868)
			(xy 80.854563 -307.324475) (xy 80.846668 -307.373052) (xy 80.831084 -307.419733) (xy 80.808213 -307.46331)
			(xy 80.778648 -307.502654) (xy 80.743155 -307.536746) (xy 80.702652 -307.564702) (xy 80.65819 -307.5858)
			(xy 80.610919 -307.599492) (xy 80.562064 -307.605424) (xy 80.512889 -307.603443) (xy 80.46467 -307.593599)
			(xy 80.418654 -307.576147) (xy 80.376033 -307.55154) (xy 80.337912 -307.520415) (xy 80.305277 -307.483578)
			(xy 80.278974 -307.441982) (xy 80.259683 -307.396706) (xy 80.247906 -307.348922) (xy 80.243946 -307.299868)
			(xy 79.905098 -307.299868) (xy 79.904603 -307.324475) (xy 79.896708 -307.373052) (xy 79.881124 -307.419733)
			(xy 79.858253 -307.46331) (xy 79.828688 -307.502654) (xy 79.793195 -307.536746) (xy 79.752692 -307.564702)
			(xy 79.70823 -307.5858) (xy 79.660959 -307.599492) (xy 79.612104 -307.605424) (xy 79.562929 -307.603443)
			(xy 79.51471 -307.593599) (xy 79.468694 -307.576147) (xy 79.426073 -307.55154) (xy 79.387952 -307.520415)
			(xy 79.355317 -307.483578) (xy 79.329014 -307.441982) (xy 79.309723 -307.396706) (xy 79.297946 -307.348922)
			(xy 79.293986 -307.299868) (xy 78.955138 -307.299868) (xy 78.954643 -307.324475) (xy 78.946748 -307.373052)
			(xy 78.931164 -307.419733) (xy 78.908293 -307.46331) (xy 78.878728 -307.502654) (xy 78.843235 -307.536746)
			(xy 78.802732 -307.564702) (xy 78.75827 -307.5858) (xy 78.710999 -307.599492) (xy 78.662144 -307.605424)
			(xy 78.612969 -307.603443) (xy 78.56475 -307.593599) (xy 78.518734 -307.576147) (xy 78.476113 -307.55154)
			(xy 78.437992 -307.520415) (xy 78.405357 -307.483578) (xy 78.379054 -307.441982) (xy 78.359763 -307.396706)
			(xy 78.347986 -307.348922) (xy 78.344026 -307.299868) (xy 78.027022 -307.299868) (xy 78.026518 -307.325576)
			(xy 78.018475 -307.376358) (xy 78.002587 -307.425257) (xy 77.979244 -307.471069) (xy 77.949023 -307.512665)
			(xy 77.912667 -307.549021) (xy 77.871071 -307.579242) (xy 77.825259 -307.602585) (xy 77.77636 -307.618473)
			(xy 77.725578 -307.626516) (xy 77.674162 -307.626516) (xy 77.62338 -307.618473) (xy 77.574481 -307.602585)
			(xy 77.528669 -307.579242) (xy 77.487073 -307.549021) (xy 77.450717 -307.512665) (xy 77.420496 -307.471069)
			(xy 77.397153 -307.425257) (xy 77.381265 -307.376358) (xy 77.373222 -307.325576) (xy 77.076558 -307.325576)
			(xy 77.068515 -307.376358) (xy 77.052627 -307.425257) (xy 77.029284 -307.471069) (xy 76.999063 -307.512665)
			(xy 76.962707 -307.549021) (xy 76.921111 -307.579242) (xy 76.875299 -307.602585) (xy 76.8264 -307.618473)
			(xy 76.775618 -307.626516) (xy 76.724202 -307.626516) (xy 76.67342 -307.618473) (xy 76.624521 -307.602585)
			(xy 76.578709 -307.579242) (xy 76.537113 -307.549021) (xy 76.500757 -307.512665) (xy 76.470536 -307.471069)
			(xy 76.447193 -307.425257) (xy 76.431305 -307.376358) (xy 76.423262 -307.325576) (xy 76.104584 -307.325576)
			(xy 76.096868 -307.373052) (xy 76.081284 -307.419733) (xy 76.058413 -307.46331) (xy 76.028848 -307.502654)
			(xy 75.993355 -307.536746) (xy 75.952852 -307.564702) (xy 75.90839 -307.5858) (xy 75.861119 -307.599492)
			(xy 75.812264 -307.605424) (xy 75.763089 -307.603443) (xy 75.71487 -307.593599) (xy 75.668854 -307.576147)
			(xy 75.626233 -307.55154) (xy 75.588112 -307.520415) (xy 75.555477 -307.483578) (xy 75.529174 -307.441982)
			(xy 75.509883 -307.396706) (xy 75.498106 -307.348922) (xy 75.494146 -307.299868) (xy 75.155298 -307.299868)
			(xy 75.154803 -307.324475) (xy 75.146908 -307.373052) (xy 75.131324 -307.419733) (xy 75.108453 -307.46331)
			(xy 75.078888 -307.502654) (xy 75.043395 -307.536746) (xy 75.002892 -307.564702) (xy 74.95843 -307.5858)
			(xy 74.911159 -307.599492) (xy 74.862304 -307.605424) (xy 74.813129 -307.603443) (xy 74.76491 -307.593599)
			(xy 74.718894 -307.576147) (xy 74.676273 -307.55154) (xy 74.638152 -307.520415) (xy 74.605517 -307.483578)
			(xy 74.579214 -307.441982) (xy 74.559923 -307.396706) (xy 74.548146 -307.348922) (xy 74.544186 -307.299868)
			(xy 74.205084 -307.299868) (xy 74.204589 -307.324475) (xy 74.196694 -307.373052) (xy 74.18111 -307.419733)
			(xy 74.158239 -307.46331) (xy 74.128674 -307.502654) (xy 74.093181 -307.536746) (xy 74.052678 -307.564702)
			(xy 74.008216 -307.5858) (xy 73.960945 -307.599492) (xy 73.91209 -307.605424) (xy 73.862915 -307.603443)
			(xy 73.814696 -307.593599) (xy 73.76868 -307.576147) (xy 73.726059 -307.55154) (xy 73.687938 -307.520415)
			(xy 73.655303 -307.483578) (xy 73.629 -307.441982) (xy 73.609709 -307.396706) (xy 73.597932 -307.348922)
			(xy 73.593972 -307.299868) (xy 50.455068 -307.299868) (xy 50.454546 -307.325123) (xy 50.446233 -307.374945)
			(xy 50.429832 -307.422719) (xy 50.405791 -307.467142) (xy 50.374767 -307.507002) (xy 50.337605 -307.541212)
			(xy 50.295319 -307.568838) (xy 50.249063 -307.589128) (xy 50.200098 -307.601528) (xy 50.14976 -307.605699)
			(xy 50.099422 -307.601528) (xy 50.050457 -307.589128) (xy 50.004201 -307.568838) (xy 49.961915 -307.541212)
			(xy 49.924753 -307.507002) (xy 49.893729 -307.467142) (xy 49.869688 -307.422719) (xy 49.853287 -307.374945)
			(xy 49.844974 -307.325123) (xy 49.844452 -307.299868) (xy 49.844635 -307.285685) (xy 49.847302 -307.257445)
			(xy 49.849786 -307.24348) (xy 49.852072 -307.231034) (xy 49.844706 -307.207412) (xy 49.767236 -307.129942)
			(xy 49.743614 -307.122576) (xy 49.731168 -307.124862) (xy 49.717203 -307.127346) (xy 49.688963 -307.130017)
			(xy 49.67478 -307.130196) (xy 49.660598 -307.130009) (xy 49.632359 -307.127333) (xy 49.618392 -307.124862)
			(xy 49.605946 -307.122576) (xy 49.582324 -307.129942) (xy 49.504854 -307.207412) (xy 49.497488 -307.231034)
			(xy 49.499774 -307.24348) (xy 49.502261 -307.257445) (xy 49.504936 -307.285685) (xy 49.505108 -307.299868)
			(xy 49.50458 -307.325482) (xy 49.496022 -307.37599) (xy 49.479156 -307.424362) (xy 49.454456 -307.469243)
			(xy 49.422614 -307.509373) (xy 49.384523 -307.543627) (xy 49.341251 -307.571047) (xy 49.29401 -307.590862)
			(xy 49.244126 -307.602517) (xy 49.218596 -307.604668) (xy 49.209421 -307.605603) (xy 49.192611 -307.613151)
			(xy 49.18583 -307.6194) (xy 49.16424 -307.64099) (xy 49.157388 -307.648386) (xy 49.149643 -307.666984)
			(xy 49.149254 -307.677058) (xy 49.149254 -307.872638) (xy 49.149686 -307.882704) (xy 49.157416 -307.901293)
			(xy 49.16424 -307.908706) (xy 49.18583 -307.930296) (xy 49.192644 -307.936495) (xy 49.209437 -307.944034)
			(xy 49.218596 -307.945028) (xy 49.244138 -307.94712) (xy 49.294042 -307.958755) (xy 49.341304 -307.97856)
			(xy 49.384594 -308.005979) (xy 49.422699 -308.040242) (xy 49.454547 -308.080387) (xy 49.479244 -308.125286)
			(xy 49.496097 -308.173679) (xy 49.504633 -308.224206) (xy 49.505108 -308.249828) (xy 49.504925 -308.264011)
			(xy 49.502258 -308.292251) (xy 49.499774 -308.306216) (xy 49.497488 -308.318662) (xy 49.504854 -308.342284)
			(xy 49.582324 -308.419754) (xy 49.605946 -308.42712) (xy 49.618392 -308.424834) (xy 49.632357 -308.422348)
			(xy 49.660597 -308.419674) (xy 49.67478 -308.4195) (xy 49.698774 -308.419945) (xy 49.746171 -308.427449)
			(xy 49.791811 -308.442276) (xy 49.83457 -308.46406) (xy 49.873393 -308.492266) (xy 49.907326 -308.526198)
			(xy 49.935533 -308.56502) (xy 49.95732 -308.607778) (xy 49.972148 -308.653417) (xy 49.979654 -308.700814)
			(xy 49.980088 -308.724808) (xy 49.979901 -308.73899) (xy 49.977227 -308.76723) (xy 49.974754 -308.781196)
			(xy 49.972468 -308.793642) (xy 49.979834 -308.817264) (xy 50.057304 -308.894734) (xy 50.080926 -308.9021)
			(xy 50.093372 -308.899814) (xy 50.107337 -308.897327) (xy 50.135577 -308.894651) (xy 50.14976 -308.89448)
			(xy 50.174583 -308.894963) (xy 50.223575 -308.902988) (xy 50.270624 -308.918835) (xy 50.314489 -308.942084)
			(xy 50.354014 -308.972124) (xy 50.388159 -309.008163) (xy 50.416024 -309.049251) (xy 50.436873 -309.094306)
			(xy 50.450159 -309.142141) (xy 50.45553 -309.191495) (xy 50.455528 -309.191539) (xy 50.794269 -309.191539)
			(xy 50.799632 -309.142187) (xy 50.81291 -309.094352) (xy 50.833751 -309.049296) (xy 50.861607 -309.008205)
			(xy 50.895744 -308.972161) (xy 50.935262 -308.942115) (xy 50.979121 -308.918858) (xy 51.026164 -308.903003)
			(xy 51.075152 -308.894968) (xy 51.099974 -308.89448) (xy 51.114157 -308.89466) (xy 51.142397 -308.89733)
			(xy 51.156362 -308.899814) (xy 51.168808 -308.9021) (xy 51.19243 -308.894734) (xy 51.2699 -308.817264)
			(xy 51.277266 -308.793642) (xy 51.27498 -308.781196) (xy 51.272507 -308.76723) (xy 51.269833 -308.73899)
			(xy 51.269646 -308.724808) (xy 51.269825 -308.710625) (xy 51.272495 -308.682385) (xy 51.27498 -308.66842)
			(xy 51.277266 -308.655974) (xy 51.2699 -308.632352) (xy 51.19243 -308.554882) (xy 51.168808 -308.547516)
			(xy 51.156362 -308.549802) (xy 51.142396 -308.55228) (xy 51.114157 -308.554951) (xy 51.099974 -308.555136)
			(xy 51.075155 -308.554594) (xy 51.026172 -308.546559) (xy 50.979134 -308.530706) (xy 50.935281 -308.507452)
			(xy 50.895768 -308.477409) (xy 50.861635 -308.441369) (xy 50.833783 -308.400282) (xy 50.812944 -308.355231)
			(xy 50.799669 -308.307401) (xy 50.794306 -308.258054) (xy 50.796998 -308.20849) (xy 50.807673 -308.160014)
			(xy 50.82605 -308.113903) (xy 50.851644 -308.071373) (xy 50.883782 -308.033544) (xy 50.921617 -308.001413)
			(xy 50.964152 -307.975826) (xy 51.010265 -307.957457) (xy 51.058743 -307.946791) (xy 51.108308 -307.944108)
			(xy 51.157654 -307.949479) (xy 51.205482 -307.962763) (xy 51.25053 -307.983609) (xy 51.291611 -308.011469)
			(xy 51.327645 -308.045608) (xy 51.357681 -308.085127) (xy 51.380927 -308.128984) (xy 51.396772 -308.176025)
			(xy 51.404798 -308.225009) (xy 51.405282 -308.249828) (xy 51.40511 -308.264011) (xy 51.402435 -308.292251)
			(xy 51.399948 -308.306216) (xy 51.397662 -308.318662) (xy 51.405028 -308.342284) (xy 51.482498 -308.419754)
			(xy 51.50612 -308.42712) (xy 51.518566 -308.424834) (xy 51.532531 -308.422353) (xy 51.560771 -308.419684)
			(xy 51.574954 -308.4195) (xy 51.589137 -308.419683) (xy 51.617377 -308.422351) (xy 51.631342 -308.424834)
			(xy 51.643788 -308.42712) (xy 51.66741 -308.419754) (xy 51.74488 -308.342284) (xy 51.752246 -308.318662)
			(xy 51.74996 -308.306216) (xy 51.747477 -308.292251) (xy 51.744809 -308.264011) (xy 51.744626 -308.249828)
			(xy 51.745048 -308.225005) (xy 51.753075 -308.176012) (xy 51.768923 -308.128963) (xy 51.792173 -308.085098)
			(xy 51.822214 -308.045573) (xy 51.858254 -308.011428) (xy 51.899342 -307.983563) (xy 51.944398 -307.962713)
			(xy 51.992233 -307.949426) (xy 52.041588 -307.944054) (xy 52.091161 -307.946737) (xy 52.139647 -307.957404)
			(xy 52.185769 -307.975776) (xy 52.228311 -308.001367) (xy 52.266153 -308.033503) (xy 52.298297 -308.071338)
			(xy 52.323897 -308.113875) (xy 52.342277 -308.159993) (xy 52.352955 -308.208477) (xy 52.3552 -308.2498)
			(xy 52.694097 -308.2498) (xy 52.698268 -308.199467) (xy 52.710666 -308.150507) (xy 52.730953 -308.104256)
			(xy 52.758577 -308.061974) (xy 52.792783 -308.024816) (xy 52.832638 -307.993794) (xy 52.877056 -307.969756)
			(xy 52.924825 -307.953356) (xy 52.974641 -307.945042) (xy 52.999894 -307.94452) (xy 53.014077 -307.944697)
			(xy 53.042317 -307.947369) (xy 53.056282 -307.949854) (xy 53.068728 -307.95214) (xy 53.09235 -307.944774)
			(xy 53.16982 -307.867304) (xy 53.177186 -307.843682) (xy 53.1749 -307.831236) (xy 53.172419 -307.817271)
			(xy 53.16975 -307.789031) (xy 53.169566 -307.774848) (xy 53.170026 -307.750022) (xy 53.178051 -307.701023)
			(xy 53.193899 -307.653967) (xy 53.21715 -307.610096) (xy 53.247194 -307.570565) (xy 53.283237 -307.536415)
			(xy 53.32433 -307.508546) (xy 53.369391 -307.487693) (xy 53.417233 -307.474406) (xy 53.466593 -307.469033)
			(xy 53.516173 -307.471718) (xy 53.564665 -307.482388) (xy 53.610791 -307.500764) (xy 53.653337 -307.52636)
			(xy 53.691182 -307.558503) (xy 53.723327 -307.596345) (xy 53.748926 -307.638889) (xy 53.767305 -307.685014)
			(xy 53.777979 -307.733505) (xy 53.78022 -307.774848) (xy 54.11903 -307.774848) (xy 54.12299 -307.725794)
			(xy 54.134767 -307.67801) (xy 54.154058 -307.632734) (xy 54.180361 -307.591138) (xy 54.212996 -307.554301)
			(xy 54.251117 -307.523176) (xy 54.293738 -307.498569) (xy 54.339754 -307.481117) (xy 54.387973 -307.471273)
			(xy 54.437148 -307.469292) (xy 54.486003 -307.475224) (xy 54.533274 -307.488916) (xy 54.577736 -307.510014)
			(xy 54.618239 -307.53797) (xy 54.653732 -307.572062) (xy 54.683297 -307.611406) (xy 54.706168 -307.654983)
			(xy 54.721752 -307.701664) (xy 54.729647 -307.750241) (xy 54.730142 -307.774848) (xy 55.06899 -307.774848)
			(xy 55.07295 -307.725794) (xy 55.084727 -307.67801) (xy 55.104018 -307.632734) (xy 55.130321 -307.591138)
			(xy 55.162956 -307.554301) (xy 55.201077 -307.523176) (xy 55.243698 -307.498569) (xy 55.289714 -307.481117)
			(xy 55.337933 -307.471273) (xy 55.387108 -307.469292) (xy 55.435963 -307.475224) (xy 55.483234 -307.488916)
			(xy 55.527696 -307.510014) (xy 55.568199 -307.53797) (xy 55.603692 -307.572062) (xy 55.633257 -307.611406)
			(xy 55.656128 -307.654983) (xy 55.671712 -307.701664) (xy 55.679607 -307.750241) (xy 55.680102 -307.774848)
			(xy 56.019204 -307.774848) (xy 56.023164 -307.725794) (xy 56.034941 -307.67801) (xy 56.054232 -307.632734)
			(xy 56.080535 -307.591138) (xy 56.11317 -307.554301) (xy 56.151291 -307.523176) (xy 56.193912 -307.498569)
			(xy 56.239928 -307.481117) (xy 56.288147 -307.471273) (xy 56.337322 -307.469292) (xy 56.386177 -307.475224)
			(xy 56.433448 -307.488916) (xy 56.47791 -307.510014) (xy 56.518413 -307.53797) (xy 56.553906 -307.572062)
			(xy 56.583471 -307.611406) (xy 56.606342 -307.654983) (xy 56.621926 -307.701664) (xy 56.629821 -307.750241)
			(xy 56.630316 -307.774848) (xy 56.969164 -307.774848) (xy 56.973124 -307.725794) (xy 56.984901 -307.67801)
			(xy 57.004192 -307.632734) (xy 57.030495 -307.591138) (xy 57.06313 -307.554301) (xy 57.101251 -307.523176)
			(xy 57.143872 -307.498569) (xy 57.189888 -307.481117) (xy 57.238107 -307.471273) (xy 57.287282 -307.469292)
			(xy 57.336137 -307.475224) (xy 57.383408 -307.488916) (xy 57.42787 -307.510014) (xy 57.468373 -307.53797)
			(xy 57.503866 -307.572062) (xy 57.533431 -307.611406) (xy 57.556302 -307.654983) (xy 57.571886 -307.701664)
			(xy 57.579781 -307.750241) (xy 57.580276 -307.774848) (xy 57.919124 -307.774848) (xy 57.923084 -307.725794)
			(xy 57.934861 -307.67801) (xy 57.954152 -307.632734) (xy 57.980455 -307.591138) (xy 58.01309 -307.554301)
			(xy 58.051211 -307.523176) (xy 58.093832 -307.498569) (xy 58.139848 -307.481117) (xy 58.188067 -307.471273)
			(xy 58.237242 -307.469292) (xy 58.286097 -307.475224) (xy 58.333368 -307.488916) (xy 58.37783 -307.510014)
			(xy 58.418333 -307.53797) (xy 58.453826 -307.572062) (xy 58.483391 -307.611406) (xy 58.506262 -307.654983)
			(xy 58.521846 -307.701664) (xy 58.529741 -307.750241) (xy 58.530236 -307.774848) (xy 59.819044 -307.774848)
			(xy 59.823004 -307.725794) (xy 59.834781 -307.67801) (xy 59.854072 -307.632734) (xy 59.880375 -307.591138)
			(xy 59.91301 -307.554301) (xy 59.951131 -307.523176) (xy 59.993752 -307.498569) (xy 60.039768 -307.481117)
			(xy 60.087987 -307.471273) (xy 60.137162 -307.469292) (xy 60.186017 -307.475224) (xy 60.233288 -307.488916)
			(xy 60.27775 -307.510014) (xy 60.318253 -307.53797) (xy 60.353746 -307.572062) (xy 60.383311 -307.611406)
			(xy 60.406182 -307.654983) (xy 60.421766 -307.701664) (xy 60.429661 -307.750241) (xy 60.430156 -307.774848)
			(xy 60.769004 -307.774848) (xy 60.772964 -307.725794) (xy 60.784741 -307.67801) (xy 60.804032 -307.632734)
			(xy 60.830335 -307.591138) (xy 60.86297 -307.554301) (xy 60.901091 -307.523176) (xy 60.943712 -307.498569)
			(xy 60.989728 -307.481117) (xy 61.037947 -307.471273) (xy 61.087122 -307.469292) (xy 61.135977 -307.475224)
			(xy 61.183248 -307.488916) (xy 61.22771 -307.510014) (xy 61.268213 -307.53797) (xy 61.303706 -307.572062)
			(xy 61.333271 -307.611406) (xy 61.356142 -307.654983) (xy 61.371726 -307.701664) (xy 61.379621 -307.750241)
			(xy 61.380116 -307.774848) (xy 61.718964 -307.774848) (xy 61.722924 -307.725794) (xy 61.734701 -307.67801)
			(xy 61.753992 -307.632734) (xy 61.780295 -307.591138) (xy 61.81293 -307.554301) (xy 61.851051 -307.523176)
			(xy 61.893672 -307.498569) (xy 61.939688 -307.481117) (xy 61.987907 -307.471273) (xy 62.037082 -307.469292)
			(xy 62.085937 -307.475224) (xy 62.133208 -307.488916) (xy 62.17767 -307.510014) (xy 62.218173 -307.53797)
			(xy 62.253666 -307.572062) (xy 62.283231 -307.611406) (xy 62.306102 -307.654983) (xy 62.321686 -307.701664)
			(xy 62.329581 -307.750241) (xy 62.330071 -307.774594) (xy 62.668924 -307.774594) (xy 62.672884 -307.72554)
			(xy 62.684661 -307.677756) (xy 62.703952 -307.63248) (xy 62.730255 -307.590884) (xy 62.76289 -307.554047)
			(xy 62.801011 -307.522922) (xy 62.843632 -307.498315) (xy 62.889648 -307.480863) (xy 62.937867 -307.471019)
			(xy 62.987042 -307.469038) (xy 63.035897 -307.47497) (xy 63.083168 -307.488662) (xy 63.12763 -307.50976)
			(xy 63.168133 -307.537716) (xy 63.203626 -307.571808) (xy 63.233191 -307.611152) (xy 63.256062 -307.654729)
			(xy 63.271646 -307.70141) (xy 63.279541 -307.749987) (xy 63.280036 -307.774594) (xy 63.619138 -307.774594)
			(xy 63.623098 -307.72554) (xy 63.634875 -307.677756) (xy 63.654166 -307.63248) (xy 63.680469 -307.590884)
			(xy 63.713104 -307.554047) (xy 63.751225 -307.522922) (xy 63.793846 -307.498315) (xy 63.839862 -307.480863)
			(xy 63.888081 -307.471019) (xy 63.937256 -307.469038) (xy 63.986111 -307.47497) (xy 64.033382 -307.488662)
			(xy 64.077844 -307.50976) (xy 64.118347 -307.537716) (xy 64.15384 -307.571808) (xy 64.183405 -307.611152)
			(xy 64.206276 -307.654729) (xy 64.22186 -307.70141) (xy 64.229755 -307.749987) (xy 64.23025 -307.774594)
			(xy 64.230245 -307.774848) (xy 64.569098 -307.774848) (xy 64.573058 -307.725794) (xy 64.584835 -307.67801)
			(xy 64.604126 -307.632734) (xy 64.630429 -307.591138) (xy 64.663064 -307.554301) (xy 64.701185 -307.523176)
			(xy 64.743806 -307.498569) (xy 64.789822 -307.481117) (xy 64.838041 -307.471273) (xy 64.887216 -307.469292)
			(xy 64.936071 -307.475224) (xy 64.983342 -307.488916) (xy 65.027804 -307.510014) (xy 65.068307 -307.53797)
			(xy 65.1038 -307.572062) (xy 65.133365 -307.611406) (xy 65.156236 -307.654983) (xy 65.17182 -307.701664)
			(xy 65.179715 -307.750241) (xy 65.18021 -307.774848) (xy 65.519058 -307.774848) (xy 65.523018 -307.725794)
			(xy 65.534795 -307.67801) (xy 65.554086 -307.632734) (xy 65.580389 -307.591138) (xy 65.613024 -307.554301)
			(xy 65.651145 -307.523176) (xy 65.693766 -307.498569) (xy 65.739782 -307.481117) (xy 65.788001 -307.471273)
			(xy 65.837176 -307.469292) (xy 65.886031 -307.475224) (xy 65.933302 -307.488916) (xy 65.977764 -307.510014)
			(xy 66.018267 -307.53797) (xy 66.05376 -307.572062) (xy 66.083325 -307.611406) (xy 66.106196 -307.654983)
			(xy 66.12178 -307.701664) (xy 66.129675 -307.750241) (xy 66.13017 -307.774848) (xy 66.469018 -307.774848)
			(xy 66.472978 -307.725794) (xy 66.484755 -307.67801) (xy 66.504046 -307.632734) (xy 66.530349 -307.591138)
			(xy 66.562984 -307.554301) (xy 66.601105 -307.523176) (xy 66.643726 -307.498569) (xy 66.689742 -307.481117)
			(xy 66.737961 -307.471273) (xy 66.787136 -307.469292) (xy 66.835991 -307.475224) (xy 66.883262 -307.488916)
			(xy 66.927724 -307.510014) (xy 66.968227 -307.53797) (xy 67.00372 -307.572062) (xy 67.033285 -307.611406)
			(xy 67.056156 -307.654983) (xy 67.07174 -307.701664) (xy 67.079635 -307.750241) (xy 67.08013 -307.774848)
			(xy 67.418978 -307.774848) (xy 67.422938 -307.725794) (xy 67.434715 -307.67801) (xy 67.454006 -307.632734)
			(xy 67.480309 -307.591138) (xy 67.512944 -307.554301) (xy 67.551065 -307.523176) (xy 67.593686 -307.498569)
			(xy 67.639702 -307.481117) (xy 67.687921 -307.471273) (xy 67.737096 -307.469292) (xy 67.785951 -307.475224)
			(xy 67.833222 -307.488916) (xy 67.877684 -307.510014) (xy 67.918187 -307.53797) (xy 67.95368 -307.572062)
			(xy 67.983245 -307.611406) (xy 68.006116 -307.654983) (xy 68.0217 -307.701664) (xy 68.029595 -307.750241)
			(xy 68.03009 -307.774848) (xy 68.368938 -307.774848) (xy 68.372898 -307.725794) (xy 68.384675 -307.67801)
			(xy 68.403966 -307.632734) (xy 68.430269 -307.591138) (xy 68.462904 -307.554301) (xy 68.501025 -307.523176)
			(xy 68.543646 -307.498569) (xy 68.589662 -307.481117) (xy 68.637881 -307.471273) (xy 68.687056 -307.469292)
			(xy 68.735911 -307.475224) (xy 68.783182 -307.488916) (xy 68.827644 -307.510014) (xy 68.868147 -307.53797)
			(xy 68.90364 -307.572062) (xy 68.933205 -307.611406) (xy 68.956076 -307.654983) (xy 68.97166 -307.701664)
			(xy 68.979555 -307.750241) (xy 68.98005 -307.774848) (xy 69.319152 -307.774848) (xy 69.323112 -307.725794)
			(xy 69.334889 -307.67801) (xy 69.35418 -307.632734) (xy 69.380483 -307.591138) (xy 69.413118 -307.554301)
			(xy 69.451239 -307.523176) (xy 69.49386 -307.498569) (xy 69.539876 -307.481117) (xy 69.588095 -307.471273)
			(xy 69.63727 -307.469292) (xy 69.686125 -307.475224) (xy 69.733396 -307.488916) (xy 69.777858 -307.510014)
			(xy 69.818361 -307.53797) (xy 69.853854 -307.572062) (xy 69.883419 -307.611406) (xy 69.90629 -307.654983)
			(xy 69.921874 -307.701664) (xy 69.929769 -307.750241) (xy 69.930264 -307.774848) (xy 70.269112 -307.774848)
			(xy 70.273072 -307.725794) (xy 70.284849 -307.67801) (xy 70.30414 -307.632734) (xy 70.330443 -307.591138)
			(xy 70.363078 -307.554301) (xy 70.401199 -307.523176) (xy 70.44382 -307.498569) (xy 70.489836 -307.481117)
			(xy 70.538055 -307.471273) (xy 70.58723 -307.469292) (xy 70.636085 -307.475224) (xy 70.683356 -307.488916)
			(xy 70.727818 -307.510014) (xy 70.768321 -307.53797) (xy 70.803814 -307.572062) (xy 70.833379 -307.611406)
			(xy 70.85625 -307.654983) (xy 70.871834 -307.701664) (xy 70.879729 -307.750241) (xy 70.880224 -307.774848)
			(xy 71.219072 -307.774848) (xy 71.223032 -307.725794) (xy 71.234809 -307.67801) (xy 71.2541 -307.632734)
			(xy 71.280403 -307.591138) (xy 71.313038 -307.554301) (xy 71.351159 -307.523176) (xy 71.39378 -307.498569)
			(xy 71.439796 -307.481117) (xy 71.488015 -307.471273) (xy 71.53719 -307.469292) (xy 71.586045 -307.475224)
			(xy 71.633316 -307.488916) (xy 71.677778 -307.510014) (xy 71.718281 -307.53797) (xy 71.753774 -307.572062)
			(xy 71.783339 -307.611406) (xy 71.80621 -307.654983) (xy 71.821794 -307.701664) (xy 71.829689 -307.750241)
			(xy 71.830184 -307.774848) (xy 72.169032 -307.774848) (xy 72.172992 -307.725794) (xy 72.184769 -307.67801)
			(xy 72.20406 -307.632734) (xy 72.230363 -307.591138) (xy 72.262998 -307.554301) (xy 72.301119 -307.523176)
			(xy 72.34374 -307.498569) (xy 72.389756 -307.481117) (xy 72.437975 -307.471273) (xy 72.48715 -307.469292)
			(xy 72.536005 -307.475224) (xy 72.583276 -307.488916) (xy 72.627738 -307.510014) (xy 72.668241 -307.53797)
			(xy 72.703734 -307.572062) (xy 72.733299 -307.611406) (xy 72.75617 -307.654983) (xy 72.771754 -307.701664)
			(xy 72.779649 -307.750241) (xy 72.780144 -307.774848) (xy 72.779649 -307.799455) (xy 72.771754 -307.848032)
			(xy 72.75617 -307.894713) (xy 72.733299 -307.93829) (xy 72.703734 -307.977634) (xy 72.668241 -308.011726)
			(xy 72.627738 -308.039682) (xy 72.583276 -308.06078) (xy 72.536005 -308.074472) (xy 72.48715 -308.080404)
			(xy 72.437975 -308.078423) (xy 72.389756 -308.068579) (xy 72.34374 -308.051127) (xy 72.301119 -308.02652)
			(xy 72.262998 -307.995395) (xy 72.230363 -307.958558) (xy 72.20406 -307.916962) (xy 72.184769 -307.871686)
			(xy 72.172992 -307.823902) (xy 72.169032 -307.774848) (xy 71.830184 -307.774848) (xy 71.829689 -307.799455)
			(xy 71.821794 -307.848032) (xy 71.80621 -307.894713) (xy 71.783339 -307.93829) (xy 71.753774 -307.977634)
			(xy 71.718281 -308.011726) (xy 71.677778 -308.039682) (xy 71.633316 -308.06078) (xy 71.586045 -308.074472)
			(xy 71.53719 -308.080404) (xy 71.488015 -308.078423) (xy 71.439796 -308.068579) (xy 71.39378 -308.051127)
			(xy 71.351159 -308.02652) (xy 71.313038 -307.995395) (xy 71.280403 -307.958558) (xy 71.2541 -307.916962)
			(xy 71.234809 -307.871686) (xy 71.223032 -307.823902) (xy 71.219072 -307.774848) (xy 70.880224 -307.774848)
			(xy 70.879729 -307.799455) (xy 70.871834 -307.848032) (xy 70.85625 -307.894713) (xy 70.833379 -307.93829)
			(xy 70.803814 -307.977634) (xy 70.768321 -308.011726) (xy 70.727818 -308.039682) (xy 70.683356 -308.06078)
			(xy 70.636085 -308.074472) (xy 70.58723 -308.080404) (xy 70.538055 -308.078423) (xy 70.489836 -308.068579)
			(xy 70.44382 -308.051127) (xy 70.401199 -308.02652) (xy 70.363078 -307.995395) (xy 70.330443 -307.958558)
			(xy 70.30414 -307.916962) (xy 70.284849 -307.871686) (xy 70.273072 -307.823902) (xy 70.269112 -307.774848)
			(xy 69.930264 -307.774848) (xy 69.929769 -307.799455) (xy 69.921874 -307.848032) (xy 69.90629 -307.894713)
			(xy 69.883419 -307.93829) (xy 69.853854 -307.977634) (xy 69.818361 -308.011726) (xy 69.777858 -308.039682)
			(xy 69.733396 -308.06078) (xy 69.686125 -308.074472) (xy 69.63727 -308.080404) (xy 69.588095 -308.078423)
			(xy 69.539876 -308.068579) (xy 69.49386 -308.051127) (xy 69.451239 -308.02652) (xy 69.413118 -307.995395)
			(xy 69.380483 -307.958558) (xy 69.35418 -307.916962) (xy 69.334889 -307.871686) (xy 69.323112 -307.823902)
			(xy 69.319152 -307.774848) (xy 68.98005 -307.774848) (xy 68.979555 -307.799455) (xy 68.97166 -307.848032)
			(xy 68.956076 -307.894713) (xy 68.933205 -307.93829) (xy 68.90364 -307.977634) (xy 68.868147 -308.011726)
			(xy 68.827644 -308.039682) (xy 68.783182 -308.06078) (xy 68.735911 -308.074472) (xy 68.687056 -308.080404)
			(xy 68.637881 -308.078423) (xy 68.589662 -308.068579) (xy 68.543646 -308.051127) (xy 68.501025 -308.02652)
			(xy 68.462904 -307.995395) (xy 68.430269 -307.958558) (xy 68.403966 -307.916962) (xy 68.384675 -307.871686)
			(xy 68.372898 -307.823902) (xy 68.368938 -307.774848) (xy 68.03009 -307.774848) (xy 68.029595 -307.799455)
			(xy 68.0217 -307.848032) (xy 68.006116 -307.894713) (xy 67.983245 -307.93829) (xy 67.95368 -307.977634)
			(xy 67.918187 -308.011726) (xy 67.877684 -308.039682) (xy 67.833222 -308.06078) (xy 67.785951 -308.074472)
			(xy 67.737096 -308.080404) (xy 67.687921 -308.078423) (xy 67.639702 -308.068579) (xy 67.593686 -308.051127)
			(xy 67.551065 -308.02652) (xy 67.512944 -307.995395) (xy 67.480309 -307.958558) (xy 67.454006 -307.916962)
			(xy 67.434715 -307.871686) (xy 67.422938 -307.823902) (xy 67.418978 -307.774848) (xy 67.08013 -307.774848)
			(xy 67.079635 -307.799455) (xy 67.07174 -307.848032) (xy 67.056156 -307.894713) (xy 67.033285 -307.93829)
			(xy 67.00372 -307.977634) (xy 66.968227 -308.011726) (xy 66.927724 -308.039682) (xy 66.883262 -308.06078)
			(xy 66.835991 -308.074472) (xy 66.787136 -308.080404) (xy 66.737961 -308.078423) (xy 66.689742 -308.068579)
			(xy 66.643726 -308.051127) (xy 66.601105 -308.02652) (xy 66.562984 -307.995395) (xy 66.530349 -307.958558)
			(xy 66.504046 -307.916962) (xy 66.484755 -307.871686) (xy 66.472978 -307.823902) (xy 66.469018 -307.774848)
			(xy 66.13017 -307.774848) (xy 66.129675 -307.799455) (xy 66.12178 -307.848032) (xy 66.106196 -307.894713)
			(xy 66.083325 -307.93829) (xy 66.05376 -307.977634) (xy 66.018267 -308.011726) (xy 65.977764 -308.039682)
			(xy 65.933302 -308.06078) (xy 65.886031 -308.074472) (xy 65.837176 -308.080404) (xy 65.788001 -308.078423)
			(xy 65.739782 -308.068579) (xy 65.693766 -308.051127) (xy 65.651145 -308.02652) (xy 65.613024 -307.995395)
			(xy 65.580389 -307.958558) (xy 65.554086 -307.916962) (xy 65.534795 -307.871686) (xy 65.523018 -307.823902)
			(xy 65.519058 -307.774848) (xy 65.18021 -307.774848) (xy 65.179715 -307.799455) (xy 65.17182 -307.848032)
			(xy 65.156236 -307.894713) (xy 65.133365 -307.93829) (xy 65.1038 -307.977634) (xy 65.068307 -308.011726)
			(xy 65.027804 -308.039682) (xy 64.983342 -308.06078) (xy 64.936071 -308.074472) (xy 64.887216 -308.080404)
			(xy 64.838041 -308.078423) (xy 64.789822 -308.068579) (xy 64.743806 -308.051127) (xy 64.701185 -308.02652)
			(xy 64.663064 -307.995395) (xy 64.630429 -307.958558) (xy 64.604126 -307.916962) (xy 64.584835 -307.871686)
			(xy 64.573058 -307.823902) (xy 64.569098 -307.774848) (xy 64.230245 -307.774848) (xy 64.229755 -307.799201)
			(xy 64.22186 -307.847778) (xy 64.206276 -307.894459) (xy 64.183405 -307.938036) (xy 64.15384 -307.97738)
			(xy 64.118347 -308.011472) (xy 64.077844 -308.039428) (xy 64.033382 -308.060526) (xy 63.986111 -308.074218)
			(xy 63.937256 -308.08015) (xy 63.888081 -308.078169) (xy 63.839862 -308.068325) (xy 63.793846 -308.050873)
			(xy 63.751225 -308.026266) (xy 63.713104 -307.995141) (xy 63.680469 -307.958304) (xy 63.654166 -307.916708)
			(xy 63.634875 -307.871432) (xy 63.623098 -307.823648) (xy 63.619138 -307.774594) (xy 63.280036 -307.774594)
			(xy 63.279541 -307.799201) (xy 63.271646 -307.847778) (xy 63.256062 -307.894459) (xy 63.233191 -307.938036)
			(xy 63.203626 -307.97738) (xy 63.168133 -308.011472) (xy 63.12763 -308.039428) (xy 63.083168 -308.060526)
			(xy 63.035897 -308.074218) (xy 62.987042 -308.08015) (xy 62.937867 -308.078169) (xy 62.889648 -308.068325)
			(xy 62.843632 -308.050873) (xy 62.801011 -308.026266) (xy 62.76289 -307.995141) (xy 62.730255 -307.958304)
			(xy 62.703952 -307.916708) (xy 62.684661 -307.871432) (xy 62.672884 -307.823648) (xy 62.668924 -307.774594)
			(xy 62.330071 -307.774594) (xy 62.330076 -307.774848) (xy 62.329581 -307.799455) (xy 62.321686 -307.848032)
			(xy 62.306102 -307.894713) (xy 62.283231 -307.93829) (xy 62.253666 -307.977634) (xy 62.218173 -308.011726)
			(xy 62.17767 -308.039682) (xy 62.133208 -308.06078) (xy 62.085937 -308.074472) (xy 62.037082 -308.080404)
			(xy 61.987907 -308.078423) (xy 61.939688 -308.068579) (xy 61.893672 -308.051127) (xy 61.851051 -308.02652)
			(xy 61.81293 -307.995395) (xy 61.780295 -307.958558) (xy 61.753992 -307.916962) (xy 61.734701 -307.871686)
			(xy 61.722924 -307.823902) (xy 61.718964 -307.774848) (xy 61.380116 -307.774848) (xy 61.379621 -307.799455)
			(xy 61.371726 -307.848032) (xy 61.356142 -307.894713) (xy 61.333271 -307.93829) (xy 61.303706 -307.977634)
			(xy 61.268213 -308.011726) (xy 61.22771 -308.039682) (xy 61.183248 -308.06078) (xy 61.135977 -308.074472)
			(xy 61.087122 -308.080404) (xy 61.037947 -308.078423) (xy 60.989728 -308.068579) (xy 60.943712 -308.051127)
			(xy 60.901091 -308.02652) (xy 60.86297 -307.995395) (xy 60.830335 -307.958558) (xy 60.804032 -307.916962)
			(xy 60.784741 -307.871686) (xy 60.772964 -307.823902) (xy 60.769004 -307.774848) (xy 60.430156 -307.774848)
			(xy 60.429661 -307.799455) (xy 60.421766 -307.848032) (xy 60.406182 -307.894713) (xy 60.383311 -307.93829)
			(xy 60.353746 -307.977634) (xy 60.318253 -308.011726) (xy 60.27775 -308.039682) (xy 60.233288 -308.06078)
			(xy 60.186017 -308.074472) (xy 60.137162 -308.080404) (xy 60.087987 -308.078423) (xy 60.039768 -308.068579)
			(xy 59.993752 -308.051127) (xy 59.951131 -308.02652) (xy 59.91301 -307.995395) (xy 59.880375 -307.958558)
			(xy 59.854072 -307.916962) (xy 59.834781 -307.871686) (xy 59.823004 -307.823902) (xy 59.819044 -307.774848)
			(xy 58.530236 -307.774848) (xy 58.529741 -307.799455) (xy 58.521846 -307.848032) (xy 58.506262 -307.894713)
			(xy 58.483391 -307.93829) (xy 58.453826 -307.977634) (xy 58.418333 -308.011726) (xy 58.37783 -308.039682)
			(xy 58.333368 -308.06078) (xy 58.286097 -308.074472) (xy 58.237242 -308.080404) (xy 58.188067 -308.078423)
			(xy 58.139848 -308.068579) (xy 58.093832 -308.051127) (xy 58.051211 -308.02652) (xy 58.01309 -307.995395)
			(xy 57.980455 -307.958558) (xy 57.954152 -307.916962) (xy 57.934861 -307.871686) (xy 57.923084 -307.823902)
			(xy 57.919124 -307.774848) (xy 57.580276 -307.774848) (xy 57.579781 -307.799455) (xy 57.571886 -307.848032)
			(xy 57.556302 -307.894713) (xy 57.533431 -307.93829) (xy 57.503866 -307.977634) (xy 57.468373 -308.011726)
			(xy 57.42787 -308.039682) (xy 57.383408 -308.06078) (xy 57.336137 -308.074472) (xy 57.287282 -308.080404)
			(xy 57.238107 -308.078423) (xy 57.189888 -308.068579) (xy 57.143872 -308.051127) (xy 57.101251 -308.02652)
			(xy 57.06313 -307.995395) (xy 57.030495 -307.958558) (xy 57.004192 -307.916962) (xy 56.984901 -307.871686)
			(xy 56.973124 -307.823902) (xy 56.969164 -307.774848) (xy 56.630316 -307.774848) (xy 56.629821 -307.799455)
			(xy 56.621926 -307.848032) (xy 56.606342 -307.894713) (xy 56.583471 -307.93829) (xy 56.553906 -307.977634)
			(xy 56.518413 -308.011726) (xy 56.47791 -308.039682) (xy 56.433448 -308.06078) (xy 56.386177 -308.074472)
			(xy 56.337322 -308.080404) (xy 56.288147 -308.078423) (xy 56.239928 -308.068579) (xy 56.193912 -308.051127)
			(xy 56.151291 -308.02652) (xy 56.11317 -307.995395) (xy 56.080535 -307.958558) (xy 56.054232 -307.916962)
			(xy 56.034941 -307.871686) (xy 56.023164 -307.823902) (xy 56.019204 -307.774848) (xy 55.680102 -307.774848)
			(xy 55.679607 -307.799455) (xy 55.671712 -307.848032) (xy 55.656128 -307.894713) (xy 55.633257 -307.93829)
			(xy 55.603692 -307.977634) (xy 55.568199 -308.011726) (xy 55.527696 -308.039682) (xy 55.483234 -308.06078)
			(xy 55.435963 -308.074472) (xy 55.387108 -308.080404) (xy 55.337933 -308.078423) (xy 55.289714 -308.068579)
			(xy 55.243698 -308.051127) (xy 55.201077 -308.02652) (xy 55.162956 -307.995395) (xy 55.130321 -307.958558)
			(xy 55.104018 -307.916962) (xy 55.084727 -307.871686) (xy 55.07295 -307.823902) (xy 55.06899 -307.774848)
			(xy 54.730142 -307.774848) (xy 54.729647 -307.799455) (xy 54.721752 -307.848032) (xy 54.706168 -307.894713)
			(xy 54.683297 -307.93829) (xy 54.653732 -307.977634) (xy 54.618239 -308.011726) (xy 54.577736 -308.039682)
			(xy 54.533274 -308.06078) (xy 54.486003 -308.074472) (xy 54.437148 -308.080404) (xy 54.387973 -308.078423)
			(xy 54.339754 -308.068579) (xy 54.293738 -308.051127) (xy 54.251117 -308.02652) (xy 54.212996 -307.995395)
			(xy 54.180361 -307.958558) (xy 54.154058 -307.916962) (xy 54.134767 -307.871686) (xy 54.12299 -307.823902)
			(xy 54.11903 -307.774848) (xy 53.78022 -307.774848) (xy 53.780667 -307.783085) (xy 53.775298 -307.832446)
			(xy 53.762014 -307.880288) (xy 53.741165 -307.92535) (xy 53.713299 -307.966446) (xy 53.679152 -308.002492)
			(xy 53.639622 -308.032538) (xy 53.595753 -308.055793) (xy 53.548699 -308.071643) (xy 53.4997 -308.079672)
			(xy 53.474874 -308.080156) (xy 53.460691 -308.079984) (xy 53.432451 -308.077309) (xy 53.418486 -308.074822)
			(xy 53.40604 -308.072536) (xy 53.382418 -308.079902) (xy 53.304948 -308.157372) (xy 53.297582 -308.180994)
			(xy 53.299868 -308.19344) (xy 53.302346 -308.207406) (xy 53.305017 -308.235645) (xy 53.305202 -308.249828)
			(xy 73.593972 -308.249828) (xy 73.597932 -308.200774) (xy 73.609709 -308.15299) (xy 73.629 -308.107714)
			(xy 73.655303 -308.066118) (xy 73.687938 -308.029281) (xy 73.726059 -307.998156) (xy 73.76868 -307.973549)
			(xy 73.814696 -307.956097) (xy 73.862915 -307.946253) (xy 73.91209 -307.944272) (xy 73.960945 -307.950204)
			(xy 74.008216 -307.963896) (xy 74.052678 -307.984994) (xy 74.093181 -308.01295) (xy 74.128674 -308.047042)
			(xy 74.158239 -308.086386) (xy 74.18111 -308.129963) (xy 74.196694 -308.176644) (xy 74.204589 -308.225221)
			(xy 74.205084 -308.249828) (xy 74.204589 -308.274435) (xy 74.20441 -308.275536) (xy 74.523342 -308.275536)
			(xy 74.523342 -308.22412) (xy 74.531385 -308.173338) (xy 74.547273 -308.124439) (xy 74.570616 -308.078627)
			(xy 74.600837 -308.037031) (xy 74.637193 -308.000675) (xy 74.678789 -307.970454) (xy 74.724601 -307.947111)
			(xy 74.7735 -307.931223) (xy 74.824282 -307.92318) (xy 74.875698 -307.92318) (xy 74.92648 -307.931223)
			(xy 74.975379 -307.947111) (xy 75.021191 -307.970454) (xy 75.062787 -308.000675) (xy 75.099143 -308.037031)
			(xy 75.129364 -308.078627) (xy 75.152707 -308.124439) (xy 75.168595 -308.173338) (xy 75.176638 -308.22412)
			(xy 75.177142 -308.249828) (xy 75.176638 -308.275536) (xy 75.473302 -308.275536) (xy 75.473302 -308.22412)
			(xy 75.481345 -308.173338) (xy 75.497233 -308.124439) (xy 75.520576 -308.078627) (xy 75.550797 -308.037031)
			(xy 75.587153 -308.000675) (xy 75.628749 -307.970454) (xy 75.674561 -307.947111) (xy 75.72346 -307.931223)
			(xy 75.774242 -307.92318) (xy 75.825658 -307.92318) (xy 75.87644 -307.931223) (xy 75.925339 -307.947111)
			(xy 75.971151 -307.970454) (xy 76.012747 -308.000675) (xy 76.049103 -308.037031) (xy 76.079324 -308.078627)
			(xy 76.102667 -308.124439) (xy 76.118555 -308.173338) (xy 76.126598 -308.22412) (xy 76.127102 -308.249828)
			(xy 76.444106 -308.249828) (xy 76.448066 -308.200774) (xy 76.459843 -308.15299) (xy 76.479134 -308.107714)
			(xy 76.505437 -308.066118) (xy 76.538072 -308.029281) (xy 76.576193 -307.998156) (xy 76.618814 -307.973549)
			(xy 76.66483 -307.956097) (xy 76.713049 -307.946253) (xy 76.762224 -307.944272) (xy 76.811079 -307.950204)
			(xy 76.85835 -307.963896) (xy 76.902812 -307.984994) (xy 76.943315 -308.01295) (xy 76.978808 -308.047042)
			(xy 77.008373 -308.086386) (xy 77.031244 -308.129963) (xy 77.046828 -308.176644) (xy 77.054723 -308.225221)
			(xy 77.055218 -308.249828) (xy 77.394066 -308.249828) (xy 77.398026 -308.200774) (xy 77.409803 -308.15299)
			(xy 77.429094 -308.107714) (xy 77.455397 -308.066118) (xy 77.488032 -308.029281) (xy 77.526153 -307.998156)
			(xy 77.568774 -307.973549) (xy 77.61479 -307.956097) (xy 77.663009 -307.946253) (xy 77.712184 -307.944272)
			(xy 77.761039 -307.950204) (xy 77.80831 -307.963896) (xy 77.852772 -307.984994) (xy 77.893275 -308.01295)
			(xy 77.928768 -308.047042) (xy 77.958333 -308.086386) (xy 77.981204 -308.129963) (xy 77.996788 -308.176644)
			(xy 78.004683 -308.225221) (xy 78.005178 -308.249828) (xy 78.344026 -308.249828) (xy 78.347986 -308.200774)
			(xy 78.359763 -308.15299) (xy 78.379054 -308.107714) (xy 78.405357 -308.066118) (xy 78.437992 -308.029281)
			(xy 78.476113 -307.998156) (xy 78.518734 -307.973549) (xy 78.56475 -307.956097) (xy 78.612969 -307.946253)
			(xy 78.662144 -307.944272) (xy 78.710999 -307.950204) (xy 78.75827 -307.963896) (xy 78.802732 -307.984994)
			(xy 78.843235 -308.01295) (xy 78.878728 -308.047042) (xy 78.908293 -308.086386) (xy 78.931164 -308.129963)
			(xy 78.946748 -308.176644) (xy 78.954643 -308.225221) (xy 78.955138 -308.249828) (xy 79.293986 -308.249828)
			(xy 79.297946 -308.200774) (xy 79.309723 -308.15299) (xy 79.329014 -308.107714) (xy 79.355317 -308.066118)
			(xy 79.387952 -308.029281) (xy 79.426073 -307.998156) (xy 79.468694 -307.973549) (xy 79.51471 -307.956097)
			(xy 79.562929 -307.946253) (xy 79.612104 -307.944272) (xy 79.660959 -307.950204) (xy 79.70823 -307.963896)
			(xy 79.752692 -307.984994) (xy 79.793195 -308.01295) (xy 79.828688 -308.047042) (xy 79.858253 -308.086386)
			(xy 79.881124 -308.129963) (xy 79.896708 -308.176644) (xy 79.904603 -308.225221) (xy 79.905098 -308.249828)
			(xy 80.243946 -308.249828) (xy 80.247906 -308.200774) (xy 80.259683 -308.15299) (xy 80.278974 -308.107714)
			(xy 80.305277 -308.066118) (xy 80.337912 -308.029281) (xy 80.376033 -307.998156) (xy 80.418654 -307.973549)
			(xy 80.46467 -307.956097) (xy 80.512889 -307.946253) (xy 80.562064 -307.944272) (xy 80.610919 -307.950204)
			(xy 80.65819 -307.963896) (xy 80.702652 -307.984994) (xy 80.743155 -308.01295) (xy 80.778648 -308.047042)
			(xy 80.808213 -308.086386) (xy 80.831084 -308.129963) (xy 80.846668 -308.176644) (xy 80.854563 -308.225221)
			(xy 80.855058 -308.249828) (xy 81.19416 -308.249828) (xy 81.19812 -308.200774) (xy 81.209897 -308.15299)
			(xy 81.229188 -308.107714) (xy 81.255491 -308.066118) (xy 81.288126 -308.029281) (xy 81.326247 -307.998156)
			(xy 81.368868 -307.973549) (xy 81.414884 -307.956097) (xy 81.463103 -307.946253) (xy 81.512278 -307.944272)
			(xy 81.561133 -307.950204) (xy 81.608404 -307.963896) (xy 81.652866 -307.984994) (xy 81.693369 -308.01295)
			(xy 81.728862 -308.047042) (xy 81.758427 -308.086386) (xy 81.781298 -308.129963) (xy 81.796882 -308.176644)
			(xy 81.804777 -308.225221) (xy 81.805272 -308.249828) (xy 82.14412 -308.249828) (xy 82.14808 -308.200774)
			(xy 82.159857 -308.15299) (xy 82.179148 -308.107714) (xy 82.205451 -308.066118) (xy 82.238086 -308.029281)
			(xy 82.276207 -307.998156) (xy 82.318828 -307.973549) (xy 82.364844 -307.956097) (xy 82.413063 -307.946253)
			(xy 82.462238 -307.944272) (xy 82.511093 -307.950204) (xy 82.558364 -307.963896) (xy 82.602826 -307.984994)
			(xy 82.643329 -308.01295) (xy 82.678822 -308.047042) (xy 82.708387 -308.086386) (xy 82.731258 -308.129963)
			(xy 82.746842 -308.176644) (xy 82.754737 -308.225221) (xy 82.755232 -308.249828) (xy 83.094334 -308.249828)
			(xy 83.098294 -308.200774) (xy 83.110071 -308.15299) (xy 83.129362 -308.107714) (xy 83.155665 -308.066118)
			(xy 83.1883 -308.029281) (xy 83.226421 -307.998156) (xy 83.269042 -307.973549) (xy 83.315058 -307.956097)
			(xy 83.363277 -307.946253) (xy 83.412452 -307.944272) (xy 83.461307 -307.950204) (xy 83.508578 -307.963896)
			(xy 83.55304 -307.984994) (xy 83.593543 -308.01295) (xy 83.629036 -308.047042) (xy 83.658601 -308.086386)
			(xy 83.681472 -308.129963) (xy 83.697056 -308.176644) (xy 83.704951 -308.225221) (xy 83.705446 -308.249828)
			(xy 83.704951 -308.274435) (xy 83.697056 -308.323012) (xy 83.681472 -308.369693) (xy 83.658601 -308.41327)
			(xy 83.629036 -308.452614) (xy 83.593543 -308.486706) (xy 83.55304 -308.514662) (xy 83.508578 -308.53576)
			(xy 83.461307 -308.549452) (xy 83.412452 -308.555384) (xy 83.363277 -308.553403) (xy 83.315058 -308.543559)
			(xy 83.269042 -308.526107) (xy 83.226421 -308.5015) (xy 83.1883 -308.470375) (xy 83.155665 -308.433538)
			(xy 83.129362 -308.391942) (xy 83.110071 -308.346666) (xy 83.098294 -308.298882) (xy 83.094334 -308.249828)
			(xy 82.755232 -308.249828) (xy 82.754737 -308.274435) (xy 82.746842 -308.323012) (xy 82.731258 -308.369693)
			(xy 82.708387 -308.41327) (xy 82.678822 -308.452614) (xy 82.643329 -308.486706) (xy 82.602826 -308.514662)
			(xy 82.558364 -308.53576) (xy 82.511093 -308.549452) (xy 82.462238 -308.555384) (xy 82.413063 -308.553403)
			(xy 82.364844 -308.543559) (xy 82.318828 -308.526107) (xy 82.276207 -308.5015) (xy 82.238086 -308.470375)
			(xy 82.205451 -308.433538) (xy 82.179148 -308.391942) (xy 82.159857 -308.346666) (xy 82.14808 -308.298882)
			(xy 82.14412 -308.249828) (xy 81.805272 -308.249828) (xy 81.804777 -308.274435) (xy 81.796882 -308.323012)
			(xy 81.781298 -308.369693) (xy 81.758427 -308.41327) (xy 81.728862 -308.452614) (xy 81.693369 -308.486706)
			(xy 81.652866 -308.514662) (xy 81.608404 -308.53576) (xy 81.561133 -308.549452) (xy 81.512278 -308.555384)
			(xy 81.463103 -308.553403) (xy 81.414884 -308.543559) (xy 81.368868 -308.526107) (xy 81.326247 -308.5015)
			(xy 81.288126 -308.470375) (xy 81.255491 -308.433538) (xy 81.229188 -308.391942) (xy 81.209897 -308.346666)
			(xy 81.19812 -308.298882) (xy 81.19416 -308.249828) (xy 80.855058 -308.249828) (xy 80.854563 -308.274435)
			(xy 80.846668 -308.323012) (xy 80.831084 -308.369693) (xy 80.808213 -308.41327) (xy 80.778648 -308.452614)
			(xy 80.743155 -308.486706) (xy 80.702652 -308.514662) (xy 80.65819 -308.53576) (xy 80.610919 -308.549452)
			(xy 80.562064 -308.555384) (xy 80.512889 -308.553403) (xy 80.46467 -308.543559) (xy 80.418654 -308.526107)
			(xy 80.376033 -308.5015) (xy 80.337912 -308.470375) (xy 80.305277 -308.433538) (xy 80.278974 -308.391942)
			(xy 80.259683 -308.346666) (xy 80.247906 -308.298882) (xy 80.243946 -308.249828) (xy 79.905098 -308.249828)
			(xy 79.904603 -308.274435) (xy 79.896708 -308.323012) (xy 79.881124 -308.369693) (xy 79.858253 -308.41327)
			(xy 79.828688 -308.452614) (xy 79.793195 -308.486706) (xy 79.752692 -308.514662) (xy 79.70823 -308.53576)
			(xy 79.660959 -308.549452) (xy 79.612104 -308.555384) (xy 79.562929 -308.553403) (xy 79.51471 -308.543559)
			(xy 79.468694 -308.526107) (xy 79.426073 -308.5015) (xy 79.387952 -308.470375) (xy 79.355317 -308.433538)
			(xy 79.329014 -308.391942) (xy 79.309723 -308.346666) (xy 79.297946 -308.298882) (xy 79.293986 -308.249828)
			(xy 78.955138 -308.249828) (xy 78.954643 -308.274435) (xy 78.946748 -308.323012) (xy 78.931164 -308.369693)
			(xy 78.908293 -308.41327) (xy 78.878728 -308.452614) (xy 78.843235 -308.486706) (xy 78.802732 -308.514662)
			(xy 78.75827 -308.53576) (xy 78.710999 -308.549452) (xy 78.662144 -308.555384) (xy 78.612969 -308.553403)
			(xy 78.56475 -308.543559) (xy 78.518734 -308.526107) (xy 78.476113 -308.5015) (xy 78.437992 -308.470375)
			(xy 78.405357 -308.433538) (xy 78.379054 -308.391942) (xy 78.359763 -308.346666) (xy 78.347986 -308.298882)
			(xy 78.344026 -308.249828) (xy 78.005178 -308.249828) (xy 78.004683 -308.274435) (xy 77.996788 -308.323012)
			(xy 77.981204 -308.369693) (xy 77.958333 -308.41327) (xy 77.928768 -308.452614) (xy 77.893275 -308.486706)
			(xy 77.852772 -308.514662) (xy 77.80831 -308.53576) (xy 77.761039 -308.549452) (xy 77.712184 -308.555384)
			(xy 77.663009 -308.553403) (xy 77.61479 -308.543559) (xy 77.568774 -308.526107) (xy 77.526153 -308.5015)
			(xy 77.488032 -308.470375) (xy 77.455397 -308.433538) (xy 77.429094 -308.391942) (xy 77.409803 -308.346666)
			(xy 77.398026 -308.298882) (xy 77.394066 -308.249828) (xy 77.055218 -308.249828) (xy 77.054723 -308.274435)
			(xy 77.046828 -308.323012) (xy 77.031244 -308.369693) (xy 77.008373 -308.41327) (xy 76.978808 -308.452614)
			(xy 76.943315 -308.486706) (xy 76.902812 -308.514662) (xy 76.85835 -308.53576) (xy 76.811079 -308.549452)
			(xy 76.762224 -308.555384) (xy 76.713049 -308.553403) (xy 76.66483 -308.543559) (xy 76.618814 -308.526107)
			(xy 76.576193 -308.5015) (xy 76.538072 -308.470375) (xy 76.505437 -308.433538) (xy 76.479134 -308.391942)
			(xy 76.459843 -308.346666) (xy 76.448066 -308.298882) (xy 76.444106 -308.249828) (xy 76.127102 -308.249828)
			(xy 76.126598 -308.275536) (xy 76.118555 -308.326318) (xy 76.102667 -308.375217) (xy 76.079324 -308.421029)
			(xy 76.049103 -308.462625) (xy 76.012747 -308.498981) (xy 75.971151 -308.529202) (xy 75.925339 -308.552545)
			(xy 75.87644 -308.568433) (xy 75.825658 -308.576476) (xy 75.774242 -308.576476) (xy 75.72346 -308.568433)
			(xy 75.674561 -308.552545) (xy 75.628749 -308.529202) (xy 75.587153 -308.498981) (xy 75.550797 -308.462625)
			(xy 75.520576 -308.421029) (xy 75.497233 -308.375217) (xy 75.481345 -308.326318) (xy 75.473302 -308.275536)
			(xy 75.176638 -308.275536) (xy 75.168595 -308.326318) (xy 75.152707 -308.375217) (xy 75.129364 -308.421029)
			(xy 75.099143 -308.462625) (xy 75.062787 -308.498981) (xy 75.021191 -308.529202) (xy 74.975379 -308.552545)
			(xy 74.92648 -308.568433) (xy 74.875698 -308.576476) (xy 74.824282 -308.576476) (xy 74.7735 -308.568433)
			(xy 74.724601 -308.552545) (xy 74.678789 -308.529202) (xy 74.637193 -308.498981) (xy 74.600837 -308.462625)
			(xy 74.570616 -308.421029) (xy 74.547273 -308.375217) (xy 74.531385 -308.326318) (xy 74.523342 -308.275536)
			(xy 74.20441 -308.275536) (xy 74.196694 -308.323012) (xy 74.18111 -308.369693) (xy 74.158239 -308.41327)
			(xy 74.128674 -308.452614) (xy 74.093181 -308.486706) (xy 74.052678 -308.514662) (xy 74.008216 -308.53576)
			(xy 73.960945 -308.549452) (xy 73.91209 -308.555384) (xy 73.862915 -308.553403) (xy 73.814696 -308.543559)
			(xy 73.76868 -308.526107) (xy 73.726059 -308.5015) (xy 73.687938 -308.470375) (xy 73.655303 -308.433538)
			(xy 73.629 -308.391942) (xy 73.609709 -308.346666) (xy 73.597932 -308.298882) (xy 73.593972 -308.249828)
			(xy 53.305202 -308.249828) (xy 53.305029 -308.264011) (xy 53.302355 -308.292251) (xy 53.299868 -308.306216)
			(xy 53.297582 -308.318662) (xy 53.304948 -308.342284) (xy 53.382418 -308.419754) (xy 53.40604 -308.42712)
			(xy 53.418486 -308.424834) (xy 53.432453 -308.422364) (xy 53.460692 -308.419688) (xy 53.474874 -308.4195)
			(xy 53.500134 -308.419975) (xy 53.549965 -308.428286) (xy 53.597748 -308.444687) (xy 53.64218 -308.468729)
			(xy 53.682049 -308.499756) (xy 53.716266 -308.536923) (xy 53.743899 -308.579216) (xy 53.764193 -308.62548)
			(xy 53.776596 -308.674453) (xy 53.780768 -308.7248) (xy 53.780767 -308.724808) (xy 54.11903 -308.724808)
			(xy 54.12299 -308.675754) (xy 54.134767 -308.62797) (xy 54.154058 -308.582694) (xy 54.180361 -308.541098)
			(xy 54.212996 -308.504261) (xy 54.251117 -308.473136) (xy 54.293738 -308.448529) (xy 54.339754 -308.431077)
			(xy 54.387973 -308.421233) (xy 54.437148 -308.419252) (xy 54.486003 -308.425184) (xy 54.533274 -308.438876)
			(xy 54.577736 -308.459974) (xy 54.618239 -308.48793) (xy 54.653732 -308.522022) (xy 54.683297 -308.561366)
			(xy 54.706168 -308.604943) (xy 54.721752 -308.651624) (xy 54.729647 -308.700201) (xy 54.730142 -308.724808)
			(xy 54.729976 -308.733075) (xy 55.069087 -308.733075) (xy 55.071776 -308.683507) (xy 55.082448 -308.635027)
			(xy 55.100823 -308.588912) (xy 55.126416 -308.546378) (xy 55.158554 -308.508544) (xy 55.196389 -308.476408)
			(xy 55.238925 -308.450817) (xy 55.28504 -308.432444) (xy 55.333521 -308.421774) (xy 55.383089 -308.419087)
			(xy 55.432439 -308.424456) (xy 55.48027 -308.437737) (xy 55.525322 -308.458582) (xy 55.566408 -308.486441)
			(xy 55.602447 -308.52058) (xy 55.632487 -308.560099) (xy 55.655738 -308.603958) (xy 55.671587 -308.651001)
			(xy 55.679617 -308.699988) (xy 55.680102 -308.724808) (xy 55.679927 -308.738991) (xy 55.677254 -308.767231)
			(xy 55.674768 -308.781196) (xy 55.672482 -308.793642) (xy 55.679848 -308.817264) (xy 55.757318 -308.894734)
			(xy 55.78094 -308.9021) (xy 55.793386 -308.899814) (xy 55.807353 -308.897343) (xy 55.835592 -308.894668)
			(xy 55.849774 -308.89448) (xy 55.864021 -308.894637) (xy 55.892389 -308.897313) (xy 55.906416 -308.899814)
			(xy 55.918608 -308.9021) (xy 55.942738 -308.894734) (xy 56.019954 -308.817518) (xy 56.02732 -308.793642)
			(xy 56.025034 -308.781196) (xy 56.022561 -308.76723) (xy 56.019887 -308.73899) (xy 56.0197 -308.724808)
			(xy 56.020169 -308.699986) (xy 56.028199 -308.650997) (xy 56.044049 -308.603952) (xy 56.067301 -308.560092)
			(xy 56.097343 -308.52057) (xy 56.133383 -308.48643) (xy 56.174471 -308.45857) (xy 56.219525 -308.437724)
			(xy 56.267358 -308.424442) (xy 56.31671 -308.419073) (xy 56.36628 -308.42176) (xy 56.414763 -308.43243)
			(xy 56.460881 -308.450804) (xy 56.503418 -308.476396) (xy 56.541255 -308.508534) (xy 56.573394 -308.546369)
			(xy 56.598989 -308.588905) (xy 56.617365 -308.635022) (xy 56.628038 -308.683504) (xy 56.630279 -308.724808)
			(xy 57.919124 -308.724808) (xy 57.923084 -308.675754) (xy 57.934861 -308.62797) (xy 57.954152 -308.582694)
			(xy 57.980455 -308.541098) (xy 58.01309 -308.504261) (xy 58.051211 -308.473136) (xy 58.093832 -308.448529)
			(xy 58.139848 -308.431077) (xy 58.188067 -308.421233) (xy 58.237242 -308.419252) (xy 58.286097 -308.425184)
			(xy 58.333368 -308.438876) (xy 58.37783 -308.459974) (xy 58.418333 -308.48793) (xy 58.453826 -308.522022)
			(xy 58.483391 -308.561366) (xy 58.506262 -308.604943) (xy 58.521846 -308.651624) (xy 58.529741 -308.700201)
			(xy 58.530236 -308.724808) (xy 58.530069 -308.733113) (xy 59.819033 -308.733113) (xy 59.821717 -308.683534)
			(xy 59.832386 -308.635042) (xy 59.85076 -308.588916) (xy 59.876355 -308.546369) (xy 59.908496 -308.508525)
			(xy 59.946337 -308.476379) (xy 59.98888 -308.450778) (xy 60.035004 -308.432398) (xy 60.083494 -308.421722)
			(xy 60.133073 -308.419032) (xy 60.182433 -308.424399) (xy 60.230275 -308.437681) (xy 60.275338 -308.458528)
			(xy 60.316435 -308.486392) (xy 60.352481 -308.520537) (xy 60.382529 -308.560064) (xy 60.405786 -308.603932)
			(xy 60.421639 -308.650985) (xy 60.429671 -308.699982) (xy 60.430156 -308.724808) (xy 60.429981 -308.738991)
			(xy 60.427308 -308.767231) (xy 60.424822 -308.781196) (xy 60.422536 -308.793642) (xy 60.429902 -308.817264)
			(xy 60.507372 -308.894734) (xy 60.530994 -308.9021) (xy 60.54344 -308.899814) (xy 60.557406 -308.897336)
			(xy 60.585645 -308.894665) (xy 60.599828 -308.89448) (xy 60.614011 -308.894653) (xy 60.642251 -308.897328)
			(xy 60.656216 -308.899814) (xy 60.668662 -308.9021) (xy 60.692284 -308.894734) (xy 60.769754 -308.817264)
			(xy 60.77712 -308.793642) (xy 60.774834 -308.781196) (xy 60.772361 -308.76723) (xy 60.769687 -308.73899)
			(xy 60.7695 -308.724808) (xy 60.770022 -308.699553) (xy 60.778335 -308.649731) (xy 60.794736 -308.601957)
			(xy 60.818777 -308.557534) (xy 60.849801 -308.517674) (xy 60.886963 -308.483464) (xy 60.929249 -308.455838)
			(xy 60.975505 -308.435548) (xy 61.02447 -308.423148) (xy 61.074808 -308.418977) (xy 61.125146 -308.423148)
			(xy 61.174111 -308.435548) (xy 61.220367 -308.455838) (xy 61.262653 -308.483464) (xy 61.299815 -308.517674)
			(xy 61.330839 -308.557534) (xy 61.35488 -308.601957) (xy 61.371281 -308.649731) (xy 61.379594 -308.699553)
			(xy 61.380116 -308.724808) (xy 61.37994 -308.738991) (xy 61.377268 -308.767231) (xy 61.374782 -308.781196)
			(xy 61.372496 -308.793642) (xy 61.379862 -308.817264) (xy 61.457332 -308.894734) (xy 61.480954 -308.9021)
			(xy 61.4934 -308.899814) (xy 61.507367 -308.897342) (xy 61.535606 -308.894667) (xy 61.549788 -308.89448)
			(xy 61.563971 -308.894659) (xy 61.592211 -308.897329) (xy 61.606176 -308.899814) (xy 61.618622 -308.9021)
			(xy 61.642244 -308.894734) (xy 61.719714 -308.817264) (xy 61.72708 -308.793642) (xy 61.724794 -308.781196)
			(xy 61.722321 -308.76723) (xy 61.719647 -308.73899) (xy 61.71946 -308.724808) (xy 61.719969 -308.699986)
			(xy 61.728 -308.650995) (xy 61.743851 -308.603949) (xy 61.767104 -308.560088) (xy 61.797147 -308.520566)
			(xy 61.833188 -308.486425) (xy 61.874279 -308.458565) (xy 61.919335 -308.437721) (xy 61.96717 -308.42444)
			(xy 62.016523 -308.419073) (xy 62.066095 -308.421762) (xy 62.114578 -308.432435) (xy 62.160696 -308.450811)
			(xy 62.203233 -308.476407) (xy 62.241069 -308.508548) (xy 62.273207 -308.546386) (xy 62.298799 -308.588925)
			(xy 62.317172 -308.635045) (xy 62.327842 -308.683529) (xy 62.330063 -308.724554) (xy 62.668924 -308.724554)
			(xy 62.672884 -308.6755) (xy 62.684661 -308.627716) (xy 62.703952 -308.58244) (xy 62.730255 -308.540844)
			(xy 62.76289 -308.504007) (xy 62.801011 -308.472882) (xy 62.843632 -308.448275) (xy 62.889648 -308.430823)
			(xy 62.937867 -308.420979) (xy 62.987042 -308.418998) (xy 63.035897 -308.42493) (xy 63.083168 -308.438622)
			(xy 63.12763 -308.45972) (xy 63.168133 -308.487676) (xy 63.203626 -308.521768) (xy 63.233191 -308.561112)
			(xy 63.256062 -308.604689) (xy 63.271646 -308.65137) (xy 63.279541 -308.699947) (xy 63.280036 -308.724554)
			(xy 63.280031 -308.724808) (xy 63.619138 -308.724808) (xy 63.623098 -308.675754) (xy 63.634875 -308.62797)
			(xy 63.654166 -308.582694) (xy 63.680469 -308.541098) (xy 63.713104 -308.504261) (xy 63.751225 -308.473136)
			(xy 63.793846 -308.448529) (xy 63.839862 -308.431077) (xy 63.888081 -308.421233) (xy 63.937256 -308.419252)
			(xy 63.986111 -308.425184) (xy 64.033382 -308.438876) (xy 64.077844 -308.459974) (xy 64.118347 -308.48793)
			(xy 64.15384 -308.522022) (xy 64.183405 -308.561366) (xy 64.206276 -308.604943) (xy 64.22186 -308.651624)
			(xy 64.229755 -308.700201) (xy 64.23025 -308.724808) (xy 64.569098 -308.724808) (xy 64.573058 -308.675754)
			(xy 64.584835 -308.62797) (xy 64.604126 -308.582694) (xy 64.630429 -308.541098) (xy 64.663064 -308.504261)
			(xy 64.701185 -308.473136) (xy 64.743806 -308.448529) (xy 64.789822 -308.431077) (xy 64.838041 -308.421233)
			(xy 64.887216 -308.419252) (xy 64.936071 -308.425184) (xy 64.983342 -308.438876) (xy 65.027804 -308.459974)
			(xy 65.068307 -308.48793) (xy 65.1038 -308.522022) (xy 65.133365 -308.561366) (xy 65.156236 -308.604943)
			(xy 65.17182 -308.651624) (xy 65.179715 -308.700201) (xy 65.18021 -308.724808) (xy 65.519058 -308.724808)
			(xy 65.523018 -308.675754) (xy 65.534795 -308.62797) (xy 65.554086 -308.582694) (xy 65.580389 -308.541098)
			(xy 65.613024 -308.504261) (xy 65.651145 -308.473136) (xy 65.693766 -308.448529) (xy 65.739782 -308.431077)
			(xy 65.788001 -308.421233) (xy 65.837176 -308.419252) (xy 65.886031 -308.425184) (xy 65.933302 -308.438876)
			(xy 65.977764 -308.459974) (xy 66.018267 -308.48793) (xy 66.05376 -308.522022) (xy 66.083325 -308.561366)
			(xy 66.106196 -308.604943) (xy 66.12178 -308.651624) (xy 66.129675 -308.700201) (xy 66.13017 -308.724808)
			(xy 66.469018 -308.724808) (xy 66.472978 -308.675754) (xy 66.484755 -308.62797) (xy 66.504046 -308.582694)
			(xy 66.530349 -308.541098) (xy 66.562984 -308.504261) (xy 66.601105 -308.473136) (xy 66.643726 -308.448529)
			(xy 66.689742 -308.431077) (xy 66.737961 -308.421233) (xy 66.787136 -308.419252) (xy 66.835991 -308.425184)
			(xy 66.883262 -308.438876) (xy 66.927724 -308.459974) (xy 66.968227 -308.48793) (xy 67.00372 -308.522022)
			(xy 67.033285 -308.561366) (xy 67.056156 -308.604943) (xy 67.07174 -308.651624) (xy 67.079635 -308.700201)
			(xy 67.08013 -308.724808) (xy 67.418978 -308.724808) (xy 67.422938 -308.675754) (xy 67.434715 -308.62797)
			(xy 67.454006 -308.582694) (xy 67.480309 -308.541098) (xy 67.512944 -308.504261) (xy 67.551065 -308.473136)
			(xy 67.593686 -308.448529) (xy 67.639702 -308.431077) (xy 67.687921 -308.421233) (xy 67.737096 -308.419252)
			(xy 67.785951 -308.425184) (xy 67.833222 -308.438876) (xy 67.877684 -308.459974) (xy 67.918187 -308.48793)
			(xy 67.95368 -308.522022) (xy 67.983245 -308.561366) (xy 68.006116 -308.604943) (xy 68.0217 -308.651624)
			(xy 68.029595 -308.700201) (xy 68.03009 -308.724808) (xy 68.369192 -308.724808) (xy 68.373152 -308.675754)
			(xy 68.384929 -308.62797) (xy 68.40422 -308.582694) (xy 68.430523 -308.541098) (xy 68.463158 -308.504261)
			(xy 68.501279 -308.473136) (xy 68.5439 -308.448529) (xy 68.589916 -308.431077) (xy 68.638135 -308.421233)
			(xy 68.68731 -308.419252) (xy 68.736165 -308.425184) (xy 68.783436 -308.438876) (xy 68.827898 -308.459974)
			(xy 68.868401 -308.48793) (xy 68.903894 -308.522022) (xy 68.933459 -308.561366) (xy 68.95633 -308.604943)
			(xy 68.971914 -308.651624) (xy 68.979809 -308.700201) (xy 68.980304 -308.724808) (xy 69.319152 -308.724808)
			(xy 69.323112 -308.675754) (xy 69.334889 -308.62797) (xy 69.35418 -308.582694) (xy 69.380483 -308.541098)
			(xy 69.413118 -308.504261) (xy 69.451239 -308.473136) (xy 69.49386 -308.448529) (xy 69.539876 -308.431077)
			(xy 69.588095 -308.421233) (xy 69.63727 -308.419252) (xy 69.686125 -308.425184) (xy 69.733396 -308.438876)
			(xy 69.777858 -308.459974) (xy 69.818361 -308.48793) (xy 69.853854 -308.522022) (xy 69.883419 -308.561366)
			(xy 69.90629 -308.604943) (xy 69.921874 -308.651624) (xy 69.929769 -308.700201) (xy 69.930264 -308.724808)
			(xy 70.269112 -308.724808) (xy 70.273072 -308.675754) (xy 70.284849 -308.62797) (xy 70.30414 -308.582694)
			(xy 70.330443 -308.541098) (xy 70.363078 -308.504261) (xy 70.401199 -308.473136) (xy 70.44382 -308.448529)
			(xy 70.489836 -308.431077) (xy 70.538055 -308.421233) (xy 70.58723 -308.419252) (xy 70.636085 -308.425184)
			(xy 70.683356 -308.438876) (xy 70.727818 -308.459974) (xy 70.768321 -308.48793) (xy 70.803814 -308.522022)
			(xy 70.833379 -308.561366) (xy 70.85625 -308.604943) (xy 70.871834 -308.651624) (xy 70.879729 -308.700201)
			(xy 70.880224 -308.724808) (xy 71.219072 -308.724808) (xy 71.223032 -308.675754) (xy 71.234809 -308.62797)
			(xy 71.2541 -308.582694) (xy 71.280403 -308.541098) (xy 71.313038 -308.504261) (xy 71.351159 -308.473136)
			(xy 71.39378 -308.448529) (xy 71.439796 -308.431077) (xy 71.488015 -308.421233) (xy 71.53719 -308.419252)
			(xy 71.586045 -308.425184) (xy 71.633316 -308.438876) (xy 71.677778 -308.459974) (xy 71.718281 -308.48793)
			(xy 71.753774 -308.522022) (xy 71.783339 -308.561366) (xy 71.80621 -308.604943) (xy 71.821794 -308.651624)
			(xy 71.829689 -308.700201) (xy 71.830184 -308.724808) (xy 72.169032 -308.724808) (xy 72.172992 -308.675754)
			(xy 72.184769 -308.62797) (xy 72.20406 -308.582694) (xy 72.230363 -308.541098) (xy 72.262998 -308.504261)
			(xy 72.301119 -308.473136) (xy 72.34374 -308.448529) (xy 72.389756 -308.431077) (xy 72.437975 -308.421233)
			(xy 72.48715 -308.419252) (xy 72.536005 -308.425184) (xy 72.583276 -308.438876) (xy 72.627738 -308.459974)
			(xy 72.668241 -308.48793) (xy 72.703734 -308.522022) (xy 72.733299 -308.561366) (xy 72.75617 -308.604943)
			(xy 72.771754 -308.651624) (xy 72.779649 -308.700201) (xy 72.780144 -308.724808) (xy 72.779649 -308.749415)
			(xy 72.771754 -308.797992) (xy 72.75617 -308.844673) (xy 72.733299 -308.88825) (xy 72.703734 -308.927594)
			(xy 72.668241 -308.961686) (xy 72.627738 -308.989642) (xy 72.583276 -309.01074) (xy 72.536005 -309.024432)
			(xy 72.48715 -309.030364) (xy 72.437975 -309.028383) (xy 72.389756 -309.018539) (xy 72.34374 -309.001087)
			(xy 72.301119 -308.97648) (xy 72.262998 -308.945355) (xy 72.230363 -308.908518) (xy 72.20406 -308.866922)
			(xy 72.184769 -308.821646) (xy 72.172992 -308.773862) (xy 72.169032 -308.724808) (xy 71.830184 -308.724808)
			(xy 71.829689 -308.749415) (xy 71.821794 -308.797992) (xy 71.80621 -308.844673) (xy 71.783339 -308.88825)
			(xy 71.753774 -308.927594) (xy 71.718281 -308.961686) (xy 71.677778 -308.989642) (xy 71.633316 -309.01074)
			(xy 71.586045 -309.024432) (xy 71.53719 -309.030364) (xy 71.488015 -309.028383) (xy 71.439796 -309.018539)
			(xy 71.39378 -309.001087) (xy 71.351159 -308.97648) (xy 71.313038 -308.945355) (xy 71.280403 -308.908518)
			(xy 71.2541 -308.866922) (xy 71.234809 -308.821646) (xy 71.223032 -308.773862) (xy 71.219072 -308.724808)
			(xy 70.880224 -308.724808) (xy 70.879729 -308.749415) (xy 70.871834 -308.797992) (xy 70.85625 -308.844673)
			(xy 70.833379 -308.88825) (xy 70.803814 -308.927594) (xy 70.768321 -308.961686) (xy 70.727818 -308.989642)
			(xy 70.683356 -309.01074) (xy 70.636085 -309.024432) (xy 70.58723 -309.030364) (xy 70.538055 -309.028383)
			(xy 70.489836 -309.018539) (xy 70.44382 -309.001087) (xy 70.401199 -308.97648) (xy 70.363078 -308.945355)
			(xy 70.330443 -308.908518) (xy 70.30414 -308.866922) (xy 70.284849 -308.821646) (xy 70.273072 -308.773862)
			(xy 70.269112 -308.724808) (xy 69.930264 -308.724808) (xy 69.929769 -308.749415) (xy 69.921874 -308.797992)
			(xy 69.90629 -308.844673) (xy 69.883419 -308.88825) (xy 69.853854 -308.927594) (xy 69.818361 -308.961686)
			(xy 69.777858 -308.989642) (xy 69.733396 -309.01074) (xy 69.686125 -309.024432) (xy 69.63727 -309.030364)
			(xy 69.588095 -309.028383) (xy 69.539876 -309.018539) (xy 69.49386 -309.001087) (xy 69.451239 -308.97648)
			(xy 69.413118 -308.945355) (xy 69.380483 -308.908518) (xy 69.35418 -308.866922) (xy 69.334889 -308.821646)
			(xy 69.323112 -308.773862) (xy 69.319152 -308.724808) (xy 68.980304 -308.724808) (xy 68.979809 -308.749415)
			(xy 68.971914 -308.797992) (xy 68.95633 -308.844673) (xy 68.933459 -308.88825) (xy 68.903894 -308.927594)
			(xy 68.868401 -308.961686) (xy 68.827898 -308.989642) (xy 68.783436 -309.01074) (xy 68.736165 -309.024432)
			(xy 68.68731 -309.030364) (xy 68.638135 -309.028383) (xy 68.589916 -309.018539) (xy 68.5439 -309.001087)
			(xy 68.501279 -308.97648) (xy 68.463158 -308.945355) (xy 68.430523 -308.908518) (xy 68.40422 -308.866922)
			(xy 68.384929 -308.821646) (xy 68.373152 -308.773862) (xy 68.369192 -308.724808) (xy 68.03009 -308.724808)
			(xy 68.029595 -308.749415) (xy 68.0217 -308.797992) (xy 68.006116 -308.844673) (xy 67.983245 -308.88825)
			(xy 67.95368 -308.927594) (xy 67.918187 -308.961686) (xy 67.877684 -308.989642) (xy 67.833222 -309.01074)
			(xy 67.785951 -309.024432) (xy 67.737096 -309.030364) (xy 67.687921 -309.028383) (xy 67.639702 -309.018539)
			(xy 67.593686 -309.001087) (xy 67.551065 -308.97648) (xy 67.512944 -308.945355) (xy 67.480309 -308.908518)
			(xy 67.454006 -308.866922) (xy 67.434715 -308.821646) (xy 67.422938 -308.773862) (xy 67.418978 -308.724808)
			(xy 67.08013 -308.724808) (xy 67.079635 -308.749415) (xy 67.07174 -308.797992) (xy 67.056156 -308.844673)
			(xy 67.033285 -308.88825) (xy 67.00372 -308.927594) (xy 66.968227 -308.961686) (xy 66.927724 -308.989642)
			(xy 66.883262 -309.01074) (xy 66.835991 -309.024432) (xy 66.787136 -309.030364) (xy 66.737961 -309.028383)
			(xy 66.689742 -309.018539) (xy 66.643726 -309.001087) (xy 66.601105 -308.97648) (xy 66.562984 -308.945355)
			(xy 66.530349 -308.908518) (xy 66.504046 -308.866922) (xy 66.484755 -308.821646) (xy 66.472978 -308.773862)
			(xy 66.469018 -308.724808) (xy 66.13017 -308.724808) (xy 66.129675 -308.749415) (xy 66.12178 -308.797992)
			(xy 66.106196 -308.844673) (xy 66.083325 -308.88825) (xy 66.05376 -308.927594) (xy 66.018267 -308.961686)
			(xy 65.977764 -308.989642) (xy 65.933302 -309.01074) (xy 65.886031 -309.024432) (xy 65.837176 -309.030364)
			(xy 65.788001 -309.028383) (xy 65.739782 -309.018539) (xy 65.693766 -309.001087) (xy 65.651145 -308.97648)
			(xy 65.613024 -308.945355) (xy 65.580389 -308.908518) (xy 65.554086 -308.866922) (xy 65.534795 -308.821646)
			(xy 65.523018 -308.773862) (xy 65.519058 -308.724808) (xy 65.18021 -308.724808) (xy 65.179715 -308.749415)
			(xy 65.17182 -308.797992) (xy 65.156236 -308.844673) (xy 65.133365 -308.88825) (xy 65.1038 -308.927594)
			(xy 65.068307 -308.961686) (xy 65.027804 -308.989642) (xy 64.983342 -309.01074) (xy 64.936071 -309.024432)
			(xy 64.887216 -309.030364) (xy 64.838041 -309.028383) (xy 64.789822 -309.018539) (xy 64.743806 -309.001087)
			(xy 64.701185 -308.97648) (xy 64.663064 -308.945355) (xy 64.630429 -308.908518) (xy 64.604126 -308.866922)
			(xy 64.584835 -308.821646) (xy 64.573058 -308.773862) (xy 64.569098 -308.724808) (xy 64.23025 -308.724808)
			(xy 64.229755 -308.749415) (xy 64.22186 -308.797992) (xy 64.206276 -308.844673) (xy 64.183405 -308.88825)
			(xy 64.15384 -308.927594) (xy 64.118347 -308.961686) (xy 64.077844 -308.989642) (xy 64.033382 -309.01074)
			(xy 63.986111 -309.024432) (xy 63.937256 -309.030364) (xy 63.888081 -309.028383) (xy 63.839862 -309.018539)
			(xy 63.793846 -309.001087) (xy 63.751225 -308.97648) (xy 63.713104 -308.945355) (xy 63.680469 -308.908518)
			(xy 63.654166 -308.866922) (xy 63.634875 -308.821646) (xy 63.623098 -308.773862) (xy 63.619138 -308.724808)
			(xy 63.280031 -308.724808) (xy 63.279541 -308.749161) (xy 63.271646 -308.797738) (xy 63.256062 -308.844419)
			(xy 63.233191 -308.887996) (xy 63.203626 -308.92734) (xy 63.168133 -308.961432) (xy 63.12763 -308.989388)
			(xy 63.083168 -309.010486) (xy 63.035897 -309.024178) (xy 62.987042 -309.03011) (xy 62.937867 -309.028129)
			(xy 62.889648 -309.018285) (xy 62.843632 -309.000833) (xy 62.801011 -308.976226) (xy 62.76289 -308.945101)
			(xy 62.730255 -308.908264) (xy 62.703952 -308.866668) (xy 62.684661 -308.821392) (xy 62.672884 -308.773608)
			(xy 62.668924 -308.724554) (xy 62.330063 -308.724554) (xy 62.330526 -308.733101) (xy 62.325156 -308.782454)
			(xy 62.311871 -308.830288) (xy 62.291023 -308.875342) (xy 62.26316 -308.91643) (xy 62.229016 -308.952469)
			(xy 62.189492 -308.982509) (xy 62.145629 -309.005759) (xy 62.098581 -309.021606) (xy 62.04959 -309.029633)
			(xy 62.024768 -309.030116) (xy 62.010585 -309.029944) (xy 61.982345 -309.027269) (xy 61.96838 -309.024782)
			(xy 61.955934 -309.022496) (xy 61.932312 -309.029862) (xy 61.854842 -309.107332) (xy 61.847476 -309.130954)
			(xy 61.849762 -309.1434) (xy 61.852234 -309.157367) (xy 61.854909 -309.185606) (xy 61.855096 -309.199788)
			(xy 73.593972 -309.199788) (xy 73.597932 -309.150734) (xy 73.609709 -309.10295) (xy 73.629 -309.057674)
			(xy 73.655303 -309.016078) (xy 73.687938 -308.979241) (xy 73.726059 -308.948116) (xy 73.76868 -308.923509)
			(xy 73.814696 -308.906057) (xy 73.862915 -308.896213) (xy 73.91209 -308.894232) (xy 73.960945 -308.900164)
			(xy 74.008216 -308.913856) (xy 74.052678 -308.934954) (xy 74.093181 -308.96291) (xy 74.128674 -308.997002)
			(xy 74.158239 -309.036346) (xy 74.18111 -309.079923) (xy 74.196694 -309.126604) (xy 74.204589 -309.175181)
			(xy 74.205084 -309.199788) (xy 74.544186 -309.199788) (xy 74.548146 -309.150734) (xy 74.559923 -309.10295)
			(xy 74.579214 -309.057674) (xy 74.605517 -309.016078) (xy 74.638152 -308.979241) (xy 74.676273 -308.948116)
			(xy 74.718894 -308.923509) (xy 74.76491 -308.906057) (xy 74.813129 -308.896213) (xy 74.862304 -308.894232)
			(xy 74.911159 -308.900164) (xy 74.95843 -308.913856) (xy 75.002892 -308.934954) (xy 75.043395 -308.96291)
			(xy 75.078888 -308.997002) (xy 75.108453 -309.036346) (xy 75.131324 -309.079923) (xy 75.146908 -309.126604)
			(xy 75.154803 -309.175181) (xy 75.155298 -309.199788) (xy 75.494146 -309.199788) (xy 75.498106 -309.150734)
			(xy 75.509883 -309.10295) (xy 75.529174 -309.057674) (xy 75.555477 -309.016078) (xy 75.588112 -308.979241)
			(xy 75.626233 -308.948116) (xy 75.668854 -308.923509) (xy 75.71487 -308.906057) (xy 75.763089 -308.896213)
			(xy 75.812264 -308.894232) (xy 75.861119 -308.900164) (xy 75.90839 -308.913856) (xy 75.952852 -308.934954)
			(xy 75.993355 -308.96291) (xy 76.028848 -308.997002) (xy 76.058413 -309.036346) (xy 76.081284 -309.079923)
			(xy 76.096868 -309.126604) (xy 76.104763 -309.175181) (xy 76.105258 -309.199788) (xy 76.104763 -309.224395)
			(xy 76.104584 -309.225496) (xy 76.423262 -309.225496) (xy 76.423262 -309.17408) (xy 76.431305 -309.123298)
			(xy 76.447193 -309.074399) (xy 76.470536 -309.028587) (xy 76.500757 -308.986991) (xy 76.537113 -308.950635)
			(xy 76.578709 -308.920414) (xy 76.624521 -308.897071) (xy 76.67342 -308.881183) (xy 76.724202 -308.87314)
			(xy 76.775618 -308.87314) (xy 76.8264 -308.881183) (xy 76.875299 -308.897071) (xy 76.921111 -308.920414)
			(xy 76.962707 -308.950635) (xy 76.999063 -308.986991) (xy 77.029284 -309.028587) (xy 77.052627 -309.074399)
			(xy 77.068515 -309.123298) (xy 77.076558 -309.17408) (xy 77.077062 -309.199788) (xy 77.076558 -309.225496)
			(xy 77.373222 -309.225496) (xy 77.373222 -309.17408) (xy 77.381265 -309.123298) (xy 77.397153 -309.074399)
			(xy 77.420496 -309.028587) (xy 77.450717 -308.986991) (xy 77.487073 -308.950635) (xy 77.528669 -308.920414)
			(xy 77.574481 -308.897071) (xy 77.62338 -308.881183) (xy 77.674162 -308.87314) (xy 77.725578 -308.87314)
			(xy 77.77636 -308.881183) (xy 77.825259 -308.897071) (xy 77.871071 -308.920414) (xy 77.912667 -308.950635)
			(xy 77.949023 -308.986991) (xy 77.979244 -309.028587) (xy 78.002587 -309.074399) (xy 78.018475 -309.123298)
			(xy 78.026518 -309.17408) (xy 78.027022 -309.199788) (xy 78.344026 -309.199788) (xy 78.347986 -309.150734)
			(xy 78.359763 -309.10295) (xy 78.379054 -309.057674) (xy 78.405357 -309.016078) (xy 78.437992 -308.979241)
			(xy 78.476113 -308.948116) (xy 78.518734 -308.923509) (xy 78.56475 -308.906057) (xy 78.612969 -308.896213)
			(xy 78.662144 -308.894232) (xy 78.710999 -308.900164) (xy 78.75827 -308.913856) (xy 78.802732 -308.934954)
			(xy 78.843235 -308.96291) (xy 78.878728 -308.997002) (xy 78.908293 -309.036346) (xy 78.931164 -309.079923)
			(xy 78.946748 -309.126604) (xy 78.954643 -309.175181) (xy 78.955138 -309.199788) (xy 79.293986 -309.199788)
			(xy 79.297946 -309.150734) (xy 79.309723 -309.10295) (xy 79.329014 -309.057674) (xy 79.355317 -309.016078)
			(xy 79.387952 -308.979241) (xy 79.426073 -308.948116) (xy 79.468694 -308.923509) (xy 79.51471 -308.906057)
			(xy 79.562929 -308.896213) (xy 79.612104 -308.894232) (xy 79.660959 -308.900164) (xy 79.70823 -308.913856)
			(xy 79.752692 -308.934954) (xy 79.793195 -308.96291) (xy 79.828688 -308.997002) (xy 79.858253 -309.036346)
			(xy 79.881124 -309.079923) (xy 79.896708 -309.126604) (xy 79.904603 -309.175181) (xy 79.905098 -309.199788)
			(xy 80.243946 -309.199788) (xy 80.247906 -309.150734) (xy 80.259683 -309.10295) (xy 80.278974 -309.057674)
			(xy 80.305277 -309.016078) (xy 80.337912 -308.979241) (xy 80.376033 -308.948116) (xy 80.418654 -308.923509)
			(xy 80.46467 -308.906057) (xy 80.512889 -308.896213) (xy 80.562064 -308.894232) (xy 80.610919 -308.900164)
			(xy 80.65819 -308.913856) (xy 80.702652 -308.934954) (xy 80.743155 -308.96291) (xy 80.778648 -308.997002)
			(xy 80.808213 -309.036346) (xy 80.831084 -309.079923) (xy 80.846668 -309.126604) (xy 80.854563 -309.175181)
			(xy 80.855058 -309.199788) (xy 81.19416 -309.199788) (xy 81.19812 -309.150734) (xy 81.209897 -309.10295)
			(xy 81.229188 -309.057674) (xy 81.255491 -309.016078) (xy 81.288126 -308.979241) (xy 81.326247 -308.948116)
			(xy 81.368868 -308.923509) (xy 81.414884 -308.906057) (xy 81.463103 -308.896213) (xy 81.512278 -308.894232)
			(xy 81.561133 -308.900164) (xy 81.608404 -308.913856) (xy 81.652866 -308.934954) (xy 81.693369 -308.96291)
			(xy 81.728862 -308.997002) (xy 81.758427 -309.036346) (xy 81.781298 -309.079923) (xy 81.796882 -309.126604)
			(xy 81.804777 -309.175181) (xy 81.805272 -309.199788) (xy 82.14412 -309.199788) (xy 82.14808 -309.150734)
			(xy 82.159857 -309.10295) (xy 82.179148 -309.057674) (xy 82.205451 -309.016078) (xy 82.238086 -308.979241)
			(xy 82.276207 -308.948116) (xy 82.318828 -308.923509) (xy 82.364844 -308.906057) (xy 82.413063 -308.896213)
			(xy 82.462238 -308.894232) (xy 82.511093 -308.900164) (xy 82.558364 -308.913856) (xy 82.602826 -308.934954)
			(xy 82.643329 -308.96291) (xy 82.678822 -308.997002) (xy 82.708387 -309.036346) (xy 82.731258 -309.079923)
			(xy 82.746842 -309.126604) (xy 82.754737 -309.175181) (xy 82.754752 -309.175912) (xy 88.334086 -309.175912)
			(xy 88.338157 -309.12029) (xy 88.350283 -309.065853) (xy 88.370206 -309.013762) (xy 88.397502 -308.965127)
			(xy 88.431588 -308.920984) (xy 88.471737 -308.882275) (xy 88.517095 -308.849824) (xy 88.566695 -308.824323)
			(xy 88.619479 -308.806316) (xy 88.674322 -308.796186) (xy 88.730056 -308.794149) (xy 88.785493 -308.800249)
			(xy 88.83945 -308.814355) (xy 88.890779 -308.836167) (xy 88.938385 -308.865221) (xy 88.981253 -308.900896)
			(xy 89.01847 -308.942433) (xy 89.049243 -308.988946) (xy 89.072915 -309.039443) (xy 89.088983 -309.09285)
			(xy 89.097103 -309.148026) (xy 89.097612 -309.175912) (xy 89.097103 -309.203798) (xy 89.088983 -309.258974)
			(xy 89.072915 -309.312381) (xy 89.049243 -309.362878) (xy 89.01847 -309.409391) (xy 88.981253 -309.450928)
			(xy 88.938385 -309.486603) (xy 88.890779 -309.515657) (xy 88.83945 -309.537469) (xy 88.785493 -309.551575)
			(xy 88.730056 -309.557675) (xy 88.674322 -309.555638) (xy 88.619479 -309.545508) (xy 88.566695 -309.527501)
			(xy 88.517095 -309.502) (xy 88.471737 -309.469549) (xy 88.431588 -309.43084) (xy 88.397502 -309.386697)
			(xy 88.370206 -309.338062) (xy 88.350283 -309.285971) (xy 88.338157 -309.231534) (xy 88.334086 -309.175912)
			(xy 82.754752 -309.175912) (xy 82.755232 -309.199788) (xy 82.754737 -309.224395) (xy 82.746842 -309.272972)
			(xy 82.731258 -309.319653) (xy 82.708387 -309.36323) (xy 82.678822 -309.402574) (xy 82.643329 -309.436666)
			(xy 82.602826 -309.464622) (xy 82.558364 -309.48572) (xy 82.511093 -309.499412) (xy 82.462238 -309.505344)
			(xy 82.413063 -309.503363) (xy 82.364844 -309.493519) (xy 82.318828 -309.476067) (xy 82.276207 -309.45146)
			(xy 82.238086 -309.420335) (xy 82.205451 -309.383498) (xy 82.179148 -309.341902) (xy 82.159857 -309.296626)
			(xy 82.14808 -309.248842) (xy 82.14412 -309.199788) (xy 81.805272 -309.199788) (xy 81.804777 -309.224395)
			(xy 81.796882 -309.272972) (xy 81.781298 -309.319653) (xy 81.758427 -309.36323) (xy 81.728862 -309.402574)
			(xy 81.693369 -309.436666) (xy 81.652866 -309.464622) (xy 81.608404 -309.48572) (xy 81.561133 -309.499412)
			(xy 81.512278 -309.505344) (xy 81.463103 -309.503363) (xy 81.414884 -309.493519) (xy 81.368868 -309.476067)
			(xy 81.326247 -309.45146) (xy 81.288126 -309.420335) (xy 81.255491 -309.383498) (xy 81.229188 -309.341902)
			(xy 81.209897 -309.296626) (xy 81.19812 -309.248842) (xy 81.19416 -309.199788) (xy 80.855058 -309.199788)
			(xy 80.854563 -309.224395) (xy 80.846668 -309.272972) (xy 80.831084 -309.319653) (xy 80.808213 -309.36323)
			(xy 80.778648 -309.402574) (xy 80.743155 -309.436666) (xy 80.702652 -309.464622) (xy 80.65819 -309.48572)
			(xy 80.610919 -309.499412) (xy 80.562064 -309.505344) (xy 80.512889 -309.503363) (xy 80.46467 -309.493519)
			(xy 80.418654 -309.476067) (xy 80.376033 -309.45146) (xy 80.337912 -309.420335) (xy 80.305277 -309.383498)
			(xy 80.278974 -309.341902) (xy 80.259683 -309.296626) (xy 80.247906 -309.248842) (xy 80.243946 -309.199788)
			(xy 79.905098 -309.199788) (xy 79.904603 -309.224395) (xy 79.896708 -309.272972) (xy 79.881124 -309.319653)
			(xy 79.858253 -309.36323) (xy 79.828688 -309.402574) (xy 79.793195 -309.436666) (xy 79.752692 -309.464622)
			(xy 79.70823 -309.48572) (xy 79.660959 -309.499412) (xy 79.612104 -309.505344) (xy 79.562929 -309.503363)
			(xy 79.51471 -309.493519) (xy 79.468694 -309.476067) (xy 79.426073 -309.45146) (xy 79.387952 -309.420335)
			(xy 79.355317 -309.383498) (xy 79.329014 -309.341902) (xy 79.309723 -309.296626) (xy 79.297946 -309.248842)
			(xy 79.293986 -309.199788) (xy 78.955138 -309.199788) (xy 78.954643 -309.224395) (xy 78.946748 -309.272972)
			(xy 78.931164 -309.319653) (xy 78.908293 -309.36323) (xy 78.878728 -309.402574) (xy 78.843235 -309.436666)
			(xy 78.802732 -309.464622) (xy 78.75827 -309.48572) (xy 78.710999 -309.499412) (xy 78.662144 -309.505344)
			(xy 78.612969 -309.503363) (xy 78.56475 -309.493519) (xy 78.518734 -309.476067) (xy 78.476113 -309.45146)
			(xy 78.437992 -309.420335) (xy 78.405357 -309.383498) (xy 78.379054 -309.341902) (xy 78.359763 -309.296626)
			(xy 78.347986 -309.248842) (xy 78.344026 -309.199788) (xy 78.027022 -309.199788) (xy 78.026518 -309.225496)
			(xy 78.018475 -309.276278) (xy 78.002587 -309.325177) (xy 77.979244 -309.370989) (xy 77.949023 -309.412585)
			(xy 77.912667 -309.448941) (xy 77.871071 -309.479162) (xy 77.825259 -309.502505) (xy 77.77636 -309.518393)
			(xy 77.725578 -309.526436) (xy 77.674162 -309.526436) (xy 77.62338 -309.518393) (xy 77.574481 -309.502505)
			(xy 77.528669 -309.479162) (xy 77.487073 -309.448941) (xy 77.450717 -309.412585) (xy 77.420496 -309.370989)
			(xy 77.397153 -309.325177) (xy 77.381265 -309.276278) (xy 77.373222 -309.225496) (xy 77.076558 -309.225496)
			(xy 77.068515 -309.276278) (xy 77.052627 -309.325177) (xy 77.029284 -309.370989) (xy 76.999063 -309.412585)
			(xy 76.962707 -309.448941) (xy 76.921111 -309.479162) (xy 76.875299 -309.502505) (xy 76.8264 -309.518393)
			(xy 76.775618 -309.526436) (xy 76.724202 -309.526436) (xy 76.67342 -309.518393) (xy 76.624521 -309.502505)
			(xy 76.578709 -309.479162) (xy 76.537113 -309.448941) (xy 76.500757 -309.412585) (xy 76.470536 -309.370989)
			(xy 76.447193 -309.325177) (xy 76.431305 -309.276278) (xy 76.423262 -309.225496) (xy 76.104584 -309.225496)
			(xy 76.096868 -309.272972) (xy 76.081284 -309.319653) (xy 76.058413 -309.36323) (xy 76.028848 -309.402574)
			(xy 75.993355 -309.436666) (xy 75.952852 -309.464622) (xy 75.90839 -309.48572) (xy 75.861119 -309.499412)
			(xy 75.812264 -309.505344) (xy 75.763089 -309.503363) (xy 75.71487 -309.493519) (xy 75.668854 -309.476067)
			(xy 75.626233 -309.45146) (xy 75.588112 -309.420335) (xy 75.555477 -309.383498) (xy 75.529174 -309.341902)
			(xy 75.509883 -309.296626) (xy 75.498106 -309.248842) (xy 75.494146 -309.199788) (xy 75.155298 -309.199788)
			(xy 75.154803 -309.224395) (xy 75.146908 -309.272972) (xy 75.131324 -309.319653) (xy 75.108453 -309.36323)
			(xy 75.078888 -309.402574) (xy 75.043395 -309.436666) (xy 75.002892 -309.464622) (xy 74.95843 -309.48572)
			(xy 74.911159 -309.499412) (xy 74.862304 -309.505344) (xy 74.813129 -309.503363) (xy 74.76491 -309.493519)
			(xy 74.718894 -309.476067) (xy 74.676273 -309.45146) (xy 74.638152 -309.420335) (xy 74.605517 -309.383498)
			(xy 74.579214 -309.341902) (xy 74.559923 -309.296626) (xy 74.548146 -309.248842) (xy 74.544186 -309.199788)
			(xy 74.205084 -309.199788) (xy 74.204589 -309.224395) (xy 74.196694 -309.272972) (xy 74.18111 -309.319653)
			(xy 74.158239 -309.36323) (xy 74.128674 -309.402574) (xy 74.093181 -309.436666) (xy 74.052678 -309.464622)
			(xy 74.008216 -309.48572) (xy 73.960945 -309.499412) (xy 73.91209 -309.505344) (xy 73.862915 -309.503363)
			(xy 73.814696 -309.493519) (xy 73.76868 -309.476067) (xy 73.726059 -309.45146) (xy 73.687938 -309.420335)
			(xy 73.655303 -309.383498) (xy 73.629 -309.341902) (xy 73.609709 -309.296626) (xy 73.597932 -309.248842)
			(xy 73.593972 -309.199788) (xy 61.855096 -309.199788) (xy 61.854574 -309.225043) (xy 61.846261 -309.274865)
			(xy 61.82986 -309.322639) (xy 61.805819 -309.367062) (xy 61.774795 -309.406922) (xy 61.737633 -309.441132)
			(xy 61.695347 -309.468758) (xy 61.649091 -309.489048) (xy 61.600126 -309.501448) (xy 61.549788 -309.505619)
			(xy 61.49945 -309.501448) (xy 61.450485 -309.489048) (xy 61.404229 -309.468758) (xy 61.361943 -309.441132)
			(xy 61.324781 -309.406922) (xy 61.293757 -309.367062) (xy 61.269716 -309.322639) (xy 61.253315 -309.274865)
			(xy 61.245002 -309.225043) (xy 61.24448 -309.199788) (xy 61.244655 -309.185605) (xy 61.247328 -309.157365)
			(xy 61.249814 -309.1434) (xy 61.2521 -309.130954) (xy 61.244734 -309.107332) (xy 61.167264 -309.029862)
			(xy 61.143642 -309.022496) (xy 61.131196 -309.024782) (xy 61.11723 -309.027255) (xy 61.08899 -309.029929)
			(xy 61.074808 -309.030116) (xy 61.060625 -309.029938) (xy 61.032385 -309.027267) (xy 61.01842 -309.024782)
			(xy 61.005974 -309.022496) (xy 60.982352 -309.029862) (xy 60.904882 -309.107332) (xy 60.897516 -309.130954)
			(xy 60.899802 -309.1434) (xy 60.902275 -309.157367) (xy 60.904949 -309.185606) (xy 60.905136 -309.199788)
			(xy 60.904614 -309.225043) (xy 60.896301 -309.274865) (xy 60.8799 -309.322639) (xy 60.855859 -309.367062)
			(xy 60.824835 -309.406922) (xy 60.787673 -309.441132) (xy 60.745387 -309.468758) (xy 60.699131 -309.489048)
			(xy 60.650166 -309.501448) (xy 60.599828 -309.505619) (xy 60.54949 -309.501448) (xy 60.500525 -309.489048)
			(xy 60.454269 -309.468758) (xy 60.411983 -309.441132) (xy 60.374821 -309.406922) (xy 60.343797 -309.367062)
			(xy 60.319756 -309.322639) (xy 60.303355 -309.274865) (xy 60.295042 -309.225043) (xy 60.29452 -309.199788)
			(xy 60.294695 -309.185605) (xy 60.297368 -309.157365) (xy 60.299854 -309.1434) (xy 60.30214 -309.130954)
			(xy 60.294774 -309.107332) (xy 60.217304 -309.029862) (xy 60.193682 -309.022496) (xy 60.181236 -309.024782)
			(xy 60.167271 -309.027263) (xy 60.139031 -309.029932) (xy 60.124848 -309.030116) (xy 60.100022 -309.029674)
			(xy 60.051024 -309.021649) (xy 60.003969 -309.005802) (xy 59.960098 -308.982551) (xy 59.920567 -308.952508)
			(xy 59.886417 -308.916466) (xy 59.858548 -308.875373) (xy 59.837695 -308.830313) (xy 59.824407 -308.782473)
			(xy 59.819033 -308.733113) (xy 58.530069 -308.733113) (xy 58.529741 -308.749415) (xy 58.521846 -308.797992)
			(xy 58.506262 -308.844673) (xy 58.483391 -308.88825) (xy 58.453826 -308.927594) (xy 58.418333 -308.961686)
			(xy 58.37783 -308.989642) (xy 58.333368 -309.01074) (xy 58.286097 -309.024432) (xy 58.237242 -309.030364)
			(xy 58.188067 -309.028383) (xy 58.139848 -309.018539) (xy 58.093832 -309.001087) (xy 58.051211 -308.97648)
			(xy 58.01309 -308.945355) (xy 57.980455 -308.908518) (xy 57.954152 -308.866922) (xy 57.934861 -308.821646)
			(xy 57.923084 -308.773862) (xy 57.919124 -308.724808) (xy 56.630279 -308.724808) (xy 56.630727 -308.733074)
			(xy 56.625361 -308.782426) (xy 56.612081 -308.83026) (xy 56.591238 -308.875315) (xy 56.56338 -308.916405)
			(xy 56.529242 -308.952446) (xy 56.489722 -308.98249) (xy 56.445862 -309.005744) (xy 56.398818 -309.021597)
			(xy 56.349829 -309.029629) (xy 56.325008 -309.030116) (xy 56.310762 -309.029941) (xy 56.282394 -309.027274)
			(xy 56.268366 -309.024782) (xy 56.256174 -309.022496) (xy 56.232044 -309.029862) (xy 56.154828 -309.107078)
			(xy 56.147462 -309.130954) (xy 56.149748 -309.1434) (xy 56.15222 -309.157367) (xy 56.154895 -309.185606)
			(xy 56.155082 -309.199788) (xy 56.15456 -309.225043) (xy 56.146247 -309.274865) (xy 56.129846 -309.322639)
			(xy 56.105805 -309.367062) (xy 56.074781 -309.406922) (xy 56.037619 -309.441132) (xy 55.995333 -309.468758)
			(xy 55.949077 -309.489048) (xy 55.900112 -309.501448) (xy 55.849774 -309.505619) (xy 55.799436 -309.501448)
			(xy 55.750471 -309.489048) (xy 55.704215 -309.468758) (xy 55.661929 -309.441132) (xy 55.624767 -309.406922)
			(xy 55.593743 -309.367062) (xy 55.569702 -309.322639) (xy 55.553301 -309.274865) (xy 55.544988 -309.225043)
			(xy 55.544466 -309.199788) (xy 55.544641 -309.185605) (xy 55.547314 -309.157365) (xy 55.5498 -309.1434)
			(xy 55.552086 -309.130954) (xy 55.54472 -309.107332) (xy 55.46725 -309.029862) (xy 55.443628 -309.022496)
			(xy 55.431182 -309.024782) (xy 55.417216 -309.027257) (xy 55.388976 -309.02993) (xy 55.374794 -309.030116)
			(xy 55.349974 -309.029616) (xy 55.300987 -309.021584) (xy 55.253945 -309.005732) (xy 55.210087 -308.982479)
			(xy 55.170569 -308.952437) (xy 55.136432 -308.916397) (xy 55.108575 -308.87531) (xy 55.087732 -308.830256)
			(xy 55.074453 -308.782425) (xy 55.069087 -308.733075) (xy 54.729976 -308.733075) (xy 54.729647 -308.749415)
			(xy 54.721752 -308.797992) (xy 54.706168 -308.844673) (xy 54.683297 -308.88825) (xy 54.653732 -308.927594)
			(xy 54.618239 -308.961686) (xy 54.577736 -308.989642) (xy 54.533274 -309.01074) (xy 54.486003 -309.024432)
			(xy 54.437148 -309.030364) (xy 54.387973 -309.028383) (xy 54.339754 -309.018539) (xy 54.293738 -309.001087)
			(xy 54.251117 -308.97648) (xy 54.212996 -308.945355) (xy 54.180361 -308.908518) (xy 54.154058 -308.866922)
			(xy 54.134767 -308.821646) (xy 54.12299 -308.773862) (xy 54.11903 -308.724808) (xy 53.780767 -308.724808)
			(xy 53.776596 -308.775147) (xy 53.764193 -308.82412) (xy 53.743899 -308.870384) (xy 53.716266 -308.912677)
			(xy 53.682049 -308.949844) (xy 53.64218 -308.980871) (xy 53.597748 -309.004913) (xy 53.549965 -309.021314)
			(xy 53.500134 -309.029625) (xy 53.474874 -309.030116) (xy 53.460691 -309.029943) (xy 53.432451 -309.027268)
			(xy 53.418486 -309.024782) (xy 53.40604 -309.022496) (xy 53.382418 -309.029862) (xy 53.304948 -309.107332)
			(xy 53.297582 -309.130954) (xy 53.299868 -309.1434) (xy 53.30234 -309.157367) (xy 53.305015 -309.185606)
			(xy 53.305202 -309.199788) (xy 53.304735 -309.22461) (xy 53.296705 -309.2736) (xy 53.280856 -309.320646)
			(xy 53.257604 -309.364508) (xy 53.227562 -309.40403) (xy 53.191522 -309.438171) (xy 53.150433 -309.466032)
			(xy 53.105379 -309.486879) (xy 53.057545 -309.500161) (xy 53.008192 -309.505531) (xy 52.958621 -309.502845)
			(xy 52.910137 -309.492174) (xy 52.864019 -309.4738) (xy 52.82148 -309.448208) (xy 52.783643 -309.41607)
			(xy 52.751503 -309.378234) (xy 52.725908 -309.335697) (xy 52.707531 -309.28958) (xy 52.696858 -309.241097)
			(xy 52.694169 -309.191526) (xy 52.699535 -309.142173) (xy 52.712815 -309.094338) (xy 52.733659 -309.049282)
			(xy 52.761517 -309.008192) (xy 52.795657 -308.97215) (xy 52.835177 -308.942106) (xy 52.879038 -308.918851)
			(xy 52.926082 -308.902999) (xy 52.975072 -308.894966) (xy 52.999894 -308.89448) (xy 53.014077 -308.894658)
			(xy 53.042317 -308.897329) (xy 53.056282 -308.899814) (xy 53.068728 -308.9021) (xy 53.09235 -308.894734)
			(xy 53.16982 -308.817264) (xy 53.177186 -308.793642) (xy 53.1749 -308.781196) (xy 53.172427 -308.76723)
			(xy 53.169753 -308.73899) (xy 53.169566 -308.724808) (xy 53.169744 -308.710625) (xy 53.172415 -308.682385)
			(xy 53.1749 -308.66842) (xy 53.177186 -308.655974) (xy 53.16982 -308.632352) (xy 53.09235 -308.554882)
			(xy 53.068728 -308.547516) (xy 53.056282 -308.549802) (xy 53.042316 -308.552277) (xy 53.014076 -308.55495)
			(xy 52.999894 -308.555136) (xy 52.974641 -308.554558) (xy 52.924825 -308.546244) (xy 52.877056 -308.529844)
			(xy 52.832638 -308.505806) (xy 52.792783 -308.474784) (xy 52.758577 -308.437626) (xy 52.730953 -308.395344)
			(xy 52.710666 -308.349093) (xy 52.698268 -308.300133) (xy 52.694097 -308.2498) (xy 52.3552 -308.2498)
			(xy 52.355648 -308.25805) (xy 52.350285 -308.307406) (xy 52.337009 -308.355244) (xy 52.316168 -308.400304)
			(xy 52.288311 -308.441398) (xy 52.254174 -308.477445) (xy 52.214654 -308.507493) (xy 52.170794 -308.530753)
			(xy 52.123748 -308.54661) (xy 52.074757 -308.554647) (xy 52.049934 -308.555136) (xy 52.035751 -308.554954)
			(xy 52.007511 -308.552285) (xy 51.993546 -308.549802) (xy 51.9811 -308.547516) (xy 51.957478 -308.554882)
			(xy 51.880008 -308.632352) (xy 51.872642 -308.655974) (xy 51.874928 -308.66842) (xy 51.877404 -308.682386)
			(xy 51.880076 -308.710626) (xy 51.880262 -308.724808) (xy 51.879869 -308.748804) (xy 51.87236 -308.796204)
			(xy 51.857527 -308.841846) (xy 51.835737 -308.884605) (xy 51.807525 -308.923428) (xy 51.773587 -308.95736)
			(xy 51.734759 -308.985565) (xy 51.691996 -309.007348) (xy 51.646351 -309.022172) (xy 51.59895 -309.029673)
			(xy 51.574954 -309.030116) (xy 51.560771 -309.029932) (xy 51.532531 -309.027265) (xy 51.518566 -309.024782)
			(xy 51.50612 -309.022496) (xy 51.482498 -309.029862) (xy 51.405028 -309.107332) (xy 51.397662 -309.130954)
			(xy 51.399948 -309.1434) (xy 51.40242 -309.157367) (xy 51.405095 -309.185606) (xy 51.405282 -309.199788)
			(xy 51.404835 -309.22461) (xy 51.396806 -309.273599) (xy 51.380957 -309.320644) (xy 51.357705 -309.364506)
			(xy 51.327664 -309.404028) (xy 51.291625 -309.438169) (xy 51.250537 -309.46603) (xy 51.205484 -309.486877)
			(xy 51.157651 -309.50016) (xy 51.108299 -309.50553) (xy 51.058728 -309.502845) (xy 51.010245 -309.492176)
			(xy 50.964127 -309.473804) (xy 50.921588 -309.448213) (xy 50.88375 -309.416077) (xy 50.851609 -309.378243)
			(xy 50.826013 -309.335708) (xy 50.807635 -309.289591) (xy 50.79696 -309.24111) (xy 50.794269 -309.191539)
			(xy 50.455528 -309.191539) (xy 50.452846 -309.241068) (xy 50.442177 -309.289553) (xy 50.423804 -309.335674)
			(xy 50.398212 -309.378214) (xy 50.366074 -309.416054) (xy 50.328237 -309.448195) (xy 50.285699 -309.473792)
			(xy 50.23958 -309.492169) (xy 50.191096 -309.502842) (xy 50.141523 -309.505531) (xy 50.092169 -309.500164)
			(xy 50.044333 -309.486883) (xy 49.999276 -309.466037) (xy 49.958185 -309.438177) (xy 49.922143 -309.404035)
			(xy 49.892099 -309.364512) (xy 49.868846 -309.32065) (xy 49.852995 -309.273602) (xy 49.844965 -309.224611)
			(xy 49.844452 -309.199788) (xy 49.844639 -309.185606) (xy 49.847313 -309.157366) (xy 49.849786 -309.1434)
			(xy 49.852072 -309.130954) (xy 49.844706 -309.107332) (xy 49.767236 -309.029862) (xy 49.743614 -309.022496)
			(xy 49.731168 -309.024782) (xy 49.717203 -309.027266) (xy 49.688963 -309.029936) (xy 49.67478 -309.030116)
			(xy 49.65079 -309.029644) (xy 49.6034 -309.022135) (xy 49.557768 -309.007306) (xy 49.515017 -308.985522)
			(xy 49.476201 -308.957318) (xy 49.442274 -308.92339) (xy 49.414072 -308.884572) (xy 49.392289 -308.841821)
			(xy 49.377462 -308.796188) (xy 49.369955 -308.748798) (xy 49.369472 -308.724808) (xy 49.369658 -308.710626)
			(xy 49.372331 -308.682386) (xy 49.374806 -308.66842) (xy 49.377092 -308.655974) (xy 49.369726 -308.632352)
			(xy 49.292256 -308.554882) (xy 49.268634 -308.547516) (xy 49.256188 -308.549802) (xy 49.246863 -308.551524)
			(xy 49.228053 -308.553941) (xy 49.218596 -308.554628) (xy 49.209423 -308.555565) (xy 49.192618 -308.563119)
			(xy 49.18583 -308.56936) (xy 49.16424 -308.59095) (xy 49.157397 -308.598349) (xy 49.149675 -308.616948)
			(xy 49.149254 -308.627018) (xy 49.149254 -309.772558) (xy 49.149689 -309.782622) (xy 49.157424 -309.801206)
			(xy 49.16424 -309.808626) (xy 49.18583 -309.830216) (xy 49.192645 -309.836413) (xy 49.209438 -309.843949)
			(xy 49.218596 -309.844948) (xy 49.245638 -309.847196) (xy 49.298353 -309.860044) (xy 49.34796 -309.882023)
			(xy 49.370742 -309.896764) (xy 49.377101 -309.900747) (xy 49.391437 -309.905149) (xy 49.398936 -309.9054)
			(xy 49.950624 -309.9054) (xy 49.958116 -309.905099) (xy 49.972448 -309.900718) (xy 49.978818 -309.896764)
			(xy 50.000615 -309.882699) (xy 50.047881 -309.861338) (xy 50.098077 -309.848271) (xy 50.14976 -309.843873)
			(xy 50.201443 -309.848271) (xy 50.251639 -309.861338) (xy 50.298905 -309.882699) (xy 50.320702 -309.896764)
			(xy 50.327063 -309.900739) (xy 50.3414 -309.905124) (xy 50.348896 -309.9054) (xy 50.900838 -309.9054)
			(xy 50.908329 -309.905097) (xy 50.922659 -309.900712) (xy 50.929032 -309.896764) (xy 50.950829 -309.882699)
			(xy 50.998095 -309.861338) (xy 51.048291 -309.848271) (xy 51.099974 -309.843873) (xy 51.151657 -309.848271)
			(xy 51.201853 -309.861338) (xy 51.249119 -309.882699) (xy 51.270916 -309.896764) (xy 51.277278 -309.900737)
			(xy 51.291614 -309.905118) (xy 51.29911 -309.9054) (xy 51.850798 -309.9054) (xy 51.858286 -309.905089)
			(xy 51.872607 -309.90069) (xy 51.878992 -309.896764) (xy 51.900789 -309.882699) (xy 51.948055 -309.861338)
			(xy 51.998251 -309.848271) (xy 52.049934 -309.843873) (xy 52.101617 -309.848271) (xy 52.151813 -309.861338)
			(xy 52.199079 -309.882699) (xy 52.220876 -309.896764) (xy 52.227236 -309.900742) (xy 52.241573 -309.905135)
			(xy 52.24907 -309.9054) (xy 52.800758 -309.9054) (xy 52.808248 -309.905094) (xy 52.822575 -309.900705)
			(xy 52.828952 -309.896764) (xy 52.850749 -309.882699) (xy 52.898015 -309.861338) (xy 52.948211 -309.848271)
			(xy 52.999894 -309.843873) (xy 53.051577 -309.848271) (xy 53.101773 -309.861338) (xy 53.149039 -309.882699)
			(xy 53.170836 -309.896764) (xy 53.177195 -309.900747) (xy 53.191531 -309.905151) (xy 53.19903 -309.9054)
			(xy 53.750718 -309.9054) (xy 53.75821 -309.9051) (xy 53.772543 -309.90072) (xy 53.778912 -309.896764)
			(xy 53.800709 -309.882699) (xy 53.847975 -309.861338) (xy 53.898171 -309.848271) (xy 53.949854 -309.843873)
			(xy 54.001537 -309.848271) (xy 54.051733 -309.861338) (xy 54.098999 -309.882699) (xy 54.120796 -309.896764)
			(xy 54.127157 -309.90074) (xy 54.141493 -309.905126) (xy 54.14899 -309.9054) (xy 54.700678 -309.9054)
			(xy 54.708167 -309.905091) (xy 54.722491 -309.900698) (xy 54.728872 -309.896764) (xy 54.750669 -309.882699)
			(xy 54.797935 -309.861338) (xy 54.848131 -309.848271) (xy 54.899814 -309.843873) (xy 54.951497 -309.848271)
			(xy 55.001693 -309.861338) (xy 55.048959 -309.882699) (xy 55.070756 -309.896764) (xy 55.077116 -309.900745)
			(xy 55.091452 -309.905143) (xy 55.09895 -309.9054) (xy 55.650638 -309.9054) (xy 55.658129 -309.905097)
			(xy 55.672459 -309.900712) (xy 55.678832 -309.896764) (xy 55.700629 -309.882699) (xy 55.747895 -309.861338)
			(xy 55.798091 -309.848271) (xy 55.849774 -309.843873) (xy 55.901457 -309.848271) (xy 55.951653 -309.861338)
			(xy 55.998919 -309.882699) (xy 56.020716 -309.896764) (xy 56.027078 -309.900737) (xy 56.041414 -309.905118)
			(xy 56.04891 -309.9054) (xy 56.600852 -309.9054) (xy 56.608342 -309.905095) (xy 56.62267 -309.900707)
			(xy 56.629046 -309.896764) (xy 56.650843 -309.882699) (xy 56.698109 -309.861338) (xy 56.748305 -309.848271)
			(xy 56.799988 -309.843873) (xy 56.851671 -309.848271) (xy 56.901867 -309.861338) (xy 56.949133 -309.882699)
			(xy 56.97093 -309.896764) (xy 56.97728 -309.901082) (xy 56.991504 -309.9054) (xy 57.027318 -309.9054)
			(xy 57.037387 -309.905827) (xy 57.055986 -309.913546) (xy 57.063386 -309.920386) (xy 57.084214 -309.941214)
			(xy 57.091068 -309.948609) (xy 57.09881 -309.967208) (xy 57.0992 -309.977282) (xy 57.0992 -310.088788)
			(xy 57.099962 -310.093614) (xy 57.102149 -310.105698) (xy 57.104817 -310.130111) (xy 57.105296 -310.142382)
			(xy 57.105927 -310.152517) (xy 57.114151 -310.171065) (xy 57.128948 -310.184948) (xy 57.138316 -310.188864)
			(xy 57.178151 -310.204158) (xy 57.255225 -310.240788) (xy 57.29224 -310.262016) (xy 57.304686 -310.269128)
			(xy 57.332372 -310.268874) (xy 57.43321 -310.207152) (xy 57.446164 -310.182514) (xy 57.445148 -310.16829)
			(xy 57.44464 -310.149748) (xy 57.445122 -310.124931) (xy 57.453144 -310.07595) (xy 57.468985 -310.028911)
			(xy 57.492227 -309.985056) (xy 57.522258 -309.945538) (xy 57.558286 -309.911399) (xy 57.599363 -309.883538)
			(xy 57.644407 -309.862691) (xy 57.692229 -309.849405) (xy 57.741572 -309.84403) (xy 57.791133 -309.84671)
			(xy 57.839608 -309.857372) (xy 57.88572 -309.875736) (xy 57.928253 -309.901318) (xy 57.966087 -309.933445)
			(xy 57.998226 -309.971269) (xy 58.023821 -310.013794) (xy 58.0422 -310.0599) (xy 58.052877 -310.108372)
			(xy 58.055127 -310.149748) (xy 58.394104 -310.149748) (xy 58.398064 -310.100694) (xy 58.409841 -310.05291)
			(xy 58.429132 -310.007634) (xy 58.455435 -309.966038) (xy 58.48807 -309.929201) (xy 58.526191 -309.898076)
			(xy 58.568812 -309.873469) (xy 58.614828 -309.856017) (xy 58.663047 -309.846173) (xy 58.712222 -309.844192)
			(xy 58.761077 -309.850124) (xy 58.808348 -309.863816) (xy 58.85281 -309.884914) (xy 58.893313 -309.91287)
			(xy 58.928806 -309.946962) (xy 58.958371 -309.986306) (xy 58.981242 -310.029883) (xy 58.996826 -310.076564)
			(xy 59.004721 -310.125141) (xy 59.005216 -310.149748) (xy 59.344064 -310.149748) (xy 59.348024 -310.100694)
			(xy 59.359801 -310.05291) (xy 59.379092 -310.007634) (xy 59.405395 -309.966038) (xy 59.43803 -309.929201)
			(xy 59.476151 -309.898076) (xy 59.518772 -309.873469) (xy 59.564788 -309.856017) (xy 59.613007 -309.846173)
			(xy 59.662182 -309.844192) (xy 59.711037 -309.850124) (xy 59.758308 -309.863816) (xy 59.80277 -309.884914)
			(xy 59.843273 -309.91287) (xy 59.878766 -309.946962) (xy 59.908331 -309.986306) (xy 59.931202 -310.029883)
			(xy 59.946786 -310.076564) (xy 59.954681 -310.125141) (xy 59.955176 -310.149748) (xy 60.294024 -310.149748)
			(xy 60.297984 -310.100694) (xy 60.309761 -310.05291) (xy 60.329052 -310.007634) (xy 60.355355 -309.966038)
			(xy 60.38799 -309.929201) (xy 60.426111 -309.898076) (xy 60.468732 -309.873469) (xy 60.514748 -309.856017)
			(xy 60.562967 -309.846173) (xy 60.612142 -309.844192) (xy 60.660997 -309.850124) (xy 60.708268 -309.863816)
			(xy 60.75273 -309.884914) (xy 60.793233 -309.91287) (xy 60.828726 -309.946962) (xy 60.858291 -309.986306)
			(xy 60.881162 -310.029883) (xy 60.896746 -310.076564) (xy 60.904641 -310.125141) (xy 60.905136 -310.149748)
			(xy 61.243984 -310.149748) (xy 61.247944 -310.100694) (xy 61.259721 -310.05291) (xy 61.279012 -310.007634)
			(xy 61.305315 -309.966038) (xy 61.33795 -309.929201) (xy 61.376071 -309.898076) (xy 61.418692 -309.873469)
			(xy 61.464708 -309.856017) (xy 61.512927 -309.846173) (xy 61.562102 -309.844192) (xy 61.610957 -309.850124)
			(xy 61.658228 -309.863816) (xy 61.70269 -309.884914) (xy 61.743193 -309.91287) (xy 61.778686 -309.946962)
			(xy 61.808251 -309.986306) (xy 61.831122 -310.029883) (xy 61.846706 -310.076564) (xy 61.854601 -310.125141)
			(xy 61.855096 -310.149748) (xy 62.193944 -310.149748) (xy 62.197904 -310.100694) (xy 62.209681 -310.05291)
			(xy 62.228972 -310.007634) (xy 62.255275 -309.966038) (xy 62.28791 -309.929201) (xy 62.326031 -309.898076)
			(xy 62.368652 -309.873469) (xy 62.414668 -309.856017) (xy 62.462887 -309.846173) (xy 62.512062 -309.844192)
			(xy 62.560917 -309.850124) (xy 62.608188 -309.863816) (xy 62.65265 -309.884914) (xy 62.693153 -309.91287)
			(xy 62.728646 -309.946962) (xy 62.758211 -309.986306) (xy 62.781082 -310.029883) (xy 62.796666 -310.076564)
			(xy 62.804561 -310.125141) (xy 62.805056 -310.149748) (xy 63.144158 -310.149748) (xy 63.148118 -310.100694)
			(xy 63.159895 -310.05291) (xy 63.179186 -310.007634) (xy 63.205489 -309.966038) (xy 63.238124 -309.929201)
			(xy 63.276245 -309.898076) (xy 63.318866 -309.873469) (xy 63.364882 -309.856017) (xy 63.413101 -309.846173)
			(xy 63.462276 -309.844192) (xy 63.511131 -309.850124) (xy 63.558402 -309.863816) (xy 63.602864 -309.884914)
			(xy 63.643367 -309.91287) (xy 63.67886 -309.946962) (xy 63.708425 -309.986306) (xy 63.731296 -310.029883)
			(xy 63.74688 -310.076564) (xy 63.754775 -310.125141) (xy 63.75527 -310.149748) (xy 64.094118 -310.149748)
			(xy 64.098078 -310.100694) (xy 64.109855 -310.05291) (xy 64.129146 -310.007634) (xy 64.155449 -309.966038)
			(xy 64.188084 -309.929201) (xy 64.226205 -309.898076) (xy 64.268826 -309.873469) (xy 64.314842 -309.856017)
			(xy 64.363061 -309.846173) (xy 64.412236 -309.844192) (xy 64.461091 -309.850124) (xy 64.508362 -309.863816)
			(xy 64.552824 -309.884914) (xy 64.593327 -309.91287) (xy 64.62882 -309.946962) (xy 64.658385 -309.986306)
			(xy 64.681256 -310.029883) (xy 64.69684 -310.076564) (xy 64.704735 -310.125141) (xy 64.70523 -310.149748)
			(xy 65.044078 -310.149748) (xy 65.048038 -310.100694) (xy 65.059815 -310.05291) (xy 65.079106 -310.007634)
			(xy 65.105409 -309.966038) (xy 65.138044 -309.929201) (xy 65.176165 -309.898076) (xy 65.218786 -309.873469)
			(xy 65.264802 -309.856017) (xy 65.313021 -309.846173) (xy 65.362196 -309.844192) (xy 65.411051 -309.850124)
			(xy 65.458322 -309.863816) (xy 65.502784 -309.884914) (xy 65.543287 -309.91287) (xy 65.57878 -309.946962)
			(xy 65.608345 -309.986306) (xy 65.631216 -310.029883) (xy 65.6468 -310.076564) (xy 65.654695 -310.125141)
			(xy 65.65519 -310.149748) (xy 65.994038 -310.149748) (xy 65.997998 -310.100694) (xy 66.009775 -310.05291)
			(xy 66.029066 -310.007634) (xy 66.055369 -309.966038) (xy 66.088004 -309.929201) (xy 66.126125 -309.898076)
			(xy 66.168746 -309.873469) (xy 66.214762 -309.856017) (xy 66.262981 -309.846173) (xy 66.312156 -309.844192)
			(xy 66.361011 -309.850124) (xy 66.408282 -309.863816) (xy 66.452744 -309.884914) (xy 66.493247 -309.91287)
			(xy 66.52874 -309.946962) (xy 66.558305 -309.986306) (xy 66.581176 -310.029883) (xy 66.59676 -310.076564)
			(xy 66.604655 -310.125141) (xy 66.60515 -310.149748) (xy 66.943998 -310.149748) (xy 66.947958 -310.100694)
			(xy 66.959735 -310.05291) (xy 66.979026 -310.007634) (xy 67.005329 -309.966038) (xy 67.037964 -309.929201)
			(xy 67.076085 -309.898076) (xy 67.118706 -309.873469) (xy 67.164722 -309.856017) (xy 67.212941 -309.846173)
			(xy 67.262116 -309.844192) (xy 67.310971 -309.850124) (xy 67.358242 -309.863816) (xy 67.402704 -309.884914)
			(xy 67.443207 -309.91287) (xy 67.4787 -309.946962) (xy 67.508265 -309.986306) (xy 67.531136 -310.029883)
			(xy 67.54672 -310.076564) (xy 67.554615 -310.125141) (xy 67.55511 -310.149748) (xy 67.893958 -310.149748)
			(xy 67.897918 -310.100694) (xy 67.909695 -310.05291) (xy 67.928986 -310.007634) (xy 67.955289 -309.966038)
			(xy 67.987924 -309.929201) (xy 68.026045 -309.898076) (xy 68.068666 -309.873469) (xy 68.114682 -309.856017)
			(xy 68.162901 -309.846173) (xy 68.212076 -309.844192) (xy 68.260931 -309.850124) (xy 68.308202 -309.863816)
			(xy 68.352664 -309.884914) (xy 68.393167 -309.91287) (xy 68.42866 -309.946962) (xy 68.458225 -309.986306)
			(xy 68.481096 -310.029883) (xy 68.49668 -310.076564) (xy 68.504575 -310.125141) (xy 68.50507 -310.149748)
			(xy 68.844172 -310.149748) (xy 68.848132 -310.100694) (xy 68.859909 -310.05291) (xy 68.8792 -310.007634)
			(xy 68.905503 -309.966038) (xy 68.938138 -309.929201) (xy 68.976259 -309.898076) (xy 69.01888 -309.873469)
			(xy 69.064896 -309.856017) (xy 69.113115 -309.846173) (xy 69.16229 -309.844192) (xy 69.211145 -309.850124)
			(xy 69.258416 -309.863816) (xy 69.302878 -309.884914) (xy 69.343381 -309.91287) (xy 69.378874 -309.946962)
			(xy 69.408439 -309.986306) (xy 69.43131 -310.029883) (xy 69.446894 -310.076564) (xy 69.454789 -310.125141)
			(xy 69.455284 -310.149748) (xy 69.794132 -310.149748) (xy 69.798092 -310.100694) (xy 69.809869 -310.05291)
			(xy 69.82916 -310.007634) (xy 69.855463 -309.966038) (xy 69.888098 -309.929201) (xy 69.926219 -309.898076)
			(xy 69.96884 -309.873469) (xy 70.014856 -309.856017) (xy 70.063075 -309.846173) (xy 70.11225 -309.844192)
			(xy 70.161105 -309.850124) (xy 70.208376 -309.863816) (xy 70.252838 -309.884914) (xy 70.293341 -309.91287)
			(xy 70.328834 -309.946962) (xy 70.358399 -309.986306) (xy 70.38127 -310.029883) (xy 70.396854 -310.076564)
			(xy 70.404749 -310.125141) (xy 70.405244 -310.149748) (xy 70.744092 -310.149748) (xy 70.748052 -310.100694)
			(xy 70.759829 -310.05291) (xy 70.77912 -310.007634) (xy 70.805423 -309.966038) (xy 70.838058 -309.929201)
			(xy 70.876179 -309.898076) (xy 70.9188 -309.873469) (xy 70.964816 -309.856017) (xy 71.013035 -309.846173)
			(xy 71.06221 -309.844192) (xy 71.111065 -309.850124) (xy 71.158336 -309.863816) (xy 71.202798 -309.884914)
			(xy 71.243301 -309.91287) (xy 71.278794 -309.946962) (xy 71.308359 -309.986306) (xy 71.33123 -310.029883)
			(xy 71.346814 -310.076564) (xy 71.354709 -310.125141) (xy 71.355204 -310.149748) (xy 71.694052 -310.149748)
			(xy 71.698012 -310.100694) (xy 71.709789 -310.05291) (xy 71.72908 -310.007634) (xy 71.755383 -309.966038)
			(xy 71.788018 -309.929201) (xy 71.826139 -309.898076) (xy 71.86876 -309.873469) (xy 71.914776 -309.856017)
			(xy 71.962995 -309.846173) (xy 72.01217 -309.844192) (xy 72.061025 -309.850124) (xy 72.108296 -309.863816)
			(xy 72.152758 -309.884914) (xy 72.193261 -309.91287) (xy 72.228754 -309.946962) (xy 72.258319 -309.986306)
			(xy 72.28119 -310.029883) (xy 72.296774 -310.076564) (xy 72.304669 -310.125141) (xy 72.305164 -310.149748)
			(xy 72.644012 -310.149748) (xy 72.647972 -310.100694) (xy 72.659749 -310.05291) (xy 72.67904 -310.007634)
			(xy 72.705343 -309.966038) (xy 72.737978 -309.929201) (xy 72.776099 -309.898076) (xy 72.81872 -309.873469)
			(xy 72.864736 -309.856017) (xy 72.912955 -309.846173) (xy 72.96213 -309.844192) (xy 73.010985 -309.850124)
			(xy 73.058256 -309.863816) (xy 73.102718 -309.884914) (xy 73.143221 -309.91287) (xy 73.178714 -309.946962)
			(xy 73.208279 -309.986306) (xy 73.23115 -310.029883) (xy 73.246734 -310.076564) (xy 73.254629 -310.125141)
			(xy 73.255124 -310.149748) (xy 73.593972 -310.149748) (xy 73.597932 -310.100694) (xy 73.609709 -310.05291)
			(xy 73.629 -310.007634) (xy 73.655303 -309.966038) (xy 73.687938 -309.929201) (xy 73.726059 -309.898076)
			(xy 73.76868 -309.873469) (xy 73.814696 -309.856017) (xy 73.862915 -309.846173) (xy 73.91209 -309.844192)
			(xy 73.960945 -309.850124) (xy 74.008216 -309.863816) (xy 74.052678 -309.884914) (xy 74.093181 -309.91287)
			(xy 74.128674 -309.946962) (xy 74.158239 -309.986306) (xy 74.18111 -310.029883) (xy 74.196694 -310.076564)
			(xy 74.204589 -310.125141) (xy 74.205084 -310.149748) (xy 74.544186 -310.149748) (xy 74.548146 -310.100694)
			(xy 74.559923 -310.05291) (xy 74.579214 -310.007634) (xy 74.605517 -309.966038) (xy 74.638152 -309.929201)
			(xy 74.676273 -309.898076) (xy 74.718894 -309.873469) (xy 74.76491 -309.856017) (xy 74.813129 -309.846173)
			(xy 74.862304 -309.844192) (xy 74.911159 -309.850124) (xy 74.95843 -309.863816) (xy 75.002892 -309.884914)
			(xy 75.043395 -309.91287) (xy 75.078888 -309.946962) (xy 75.108453 -309.986306) (xy 75.131324 -310.029883)
			(xy 75.146908 -310.076564) (xy 75.154803 -310.125141) (xy 75.155298 -310.149748) (xy 75.494146 -310.149748)
			(xy 75.498106 -310.100694) (xy 75.509883 -310.05291) (xy 75.529174 -310.007634) (xy 75.555477 -309.966038)
			(xy 75.588112 -309.929201) (xy 75.626233 -309.898076) (xy 75.668854 -309.873469) (xy 75.71487 -309.856017)
			(xy 75.763089 -309.846173) (xy 75.812264 -309.844192) (xy 75.861119 -309.850124) (xy 75.90839 -309.863816)
			(xy 75.952852 -309.884914) (xy 75.993355 -309.91287) (xy 76.028848 -309.946962) (xy 76.058413 -309.986306)
			(xy 76.081284 -310.029883) (xy 76.096868 -310.076564) (xy 76.104763 -310.125141) (xy 76.105258 -310.149748)
			(xy 76.444106 -310.149748) (xy 76.448066 -310.100694) (xy 76.459843 -310.05291) (xy 76.479134 -310.007634)
			(xy 76.505437 -309.966038) (xy 76.538072 -309.929201) (xy 76.576193 -309.898076) (xy 76.618814 -309.873469)
			(xy 76.66483 -309.856017) (xy 76.713049 -309.846173) (xy 76.762224 -309.844192) (xy 76.811079 -309.850124)
			(xy 76.85835 -309.863816) (xy 76.902812 -309.884914) (xy 76.943315 -309.91287) (xy 76.978808 -309.946962)
			(xy 77.008373 -309.986306) (xy 77.031244 -310.029883) (xy 77.046828 -310.076564) (xy 77.054723 -310.125141)
			(xy 77.055218 -310.149748) (xy 77.394066 -310.149748) (xy 77.398026 -310.100694) (xy 77.409803 -310.05291)
			(xy 77.429094 -310.007634) (xy 77.455397 -309.966038) (xy 77.488032 -309.929201) (xy 77.526153 -309.898076)
			(xy 77.568774 -309.873469) (xy 77.61479 -309.856017) (xy 77.663009 -309.846173) (xy 77.712184 -309.844192)
			(xy 77.761039 -309.850124) (xy 77.80831 -309.863816) (xy 77.852772 -309.884914) (xy 77.893275 -309.91287)
			(xy 77.928768 -309.946962) (xy 77.958333 -309.986306) (xy 77.981204 -310.029883) (xy 77.996788 -310.076564)
			(xy 78.004683 -310.125141) (xy 78.005178 -310.149748) (xy 78.344026 -310.149748) (xy 78.347986 -310.100694)
			(xy 78.359763 -310.05291) (xy 78.379054 -310.007634) (xy 78.405357 -309.966038) (xy 78.437992 -309.929201)
			(xy 78.476113 -309.898076) (xy 78.518734 -309.873469) (xy 78.56475 -309.856017) (xy 78.612969 -309.846173)
			(xy 78.662144 -309.844192) (xy 78.710999 -309.850124) (xy 78.75827 -309.863816) (xy 78.802732 -309.884914)
			(xy 78.843235 -309.91287) (xy 78.878728 -309.946962) (xy 78.908293 -309.986306) (xy 78.931164 -310.029883)
			(xy 78.946748 -310.076564) (xy 78.954643 -310.125141) (xy 78.955138 -310.149748) (xy 79.293986 -310.149748)
			(xy 79.297946 -310.100694) (xy 79.309723 -310.05291) (xy 79.329014 -310.007634) (xy 79.355317 -309.966038)
			(xy 79.387952 -309.929201) (xy 79.426073 -309.898076) (xy 79.468694 -309.873469) (xy 79.51471 -309.856017)
			(xy 79.562929 -309.846173) (xy 79.612104 -309.844192) (xy 79.660959 -309.850124) (xy 79.70823 -309.863816)
			(xy 79.752692 -309.884914) (xy 79.793195 -309.91287) (xy 79.828688 -309.946962) (xy 79.858253 -309.986306)
			(xy 79.881124 -310.029883) (xy 79.896708 -310.076564) (xy 79.904603 -310.125141) (xy 79.905098 -310.149748)
			(xy 80.243946 -310.149748) (xy 80.247906 -310.100694) (xy 80.259683 -310.05291) (xy 80.278974 -310.007634)
			(xy 80.305277 -309.966038) (xy 80.337912 -309.929201) (xy 80.376033 -309.898076) (xy 80.418654 -309.873469)
			(xy 80.46467 -309.856017) (xy 80.512889 -309.846173) (xy 80.562064 -309.844192) (xy 80.610919 -309.850124)
			(xy 80.65819 -309.863816) (xy 80.702652 -309.884914) (xy 80.743155 -309.91287) (xy 80.778648 -309.946962)
			(xy 80.808213 -309.986306) (xy 80.831084 -310.029883) (xy 80.846668 -310.076564) (xy 80.854563 -310.125141)
			(xy 80.855058 -310.149748) (xy 81.19416 -310.149748) (xy 81.19812 -310.100694) (xy 81.209897 -310.05291)
			(xy 81.229188 -310.007634) (xy 81.255491 -309.966038) (xy 81.288126 -309.929201) (xy 81.326247 -309.898076)
			(xy 81.368868 -309.873469) (xy 81.414884 -309.856017) (xy 81.463103 -309.846173) (xy 81.512278 -309.844192)
			(xy 81.561133 -309.850124) (xy 81.608404 -309.863816) (xy 81.652866 -309.884914) (xy 81.693369 -309.91287)
			(xy 81.728862 -309.946962) (xy 81.758427 -309.986306) (xy 81.781298 -310.029883) (xy 81.796882 -310.076564)
			(xy 81.804777 -310.125141) (xy 81.805272 -310.149748) (xy 82.14412 -310.149748) (xy 82.14808 -310.100694)
			(xy 82.159857 -310.05291) (xy 82.179148 -310.007634) (xy 82.205451 -309.966038) (xy 82.238086 -309.929201)
			(xy 82.276207 -309.898076) (xy 82.318828 -309.873469) (xy 82.364844 -309.856017) (xy 82.413063 -309.846173)
			(xy 82.462238 -309.844192) (xy 82.511093 -309.850124) (xy 82.558364 -309.863816) (xy 82.602826 -309.884914)
			(xy 82.643329 -309.91287) (xy 82.678822 -309.946962) (xy 82.708387 -309.986306) (xy 82.731258 -310.029883)
			(xy 82.746842 -310.076564) (xy 82.754737 -310.125141) (xy 82.755232 -310.149748) (xy 83.094334 -310.149748)
			(xy 83.098294 -310.100694) (xy 83.110071 -310.05291) (xy 83.129362 -310.007634) (xy 83.155665 -309.966038)
			(xy 83.1883 -309.929201) (xy 83.226421 -309.898076) (xy 83.269042 -309.873469) (xy 83.315058 -309.856017)
			(xy 83.363277 -309.846173) (xy 83.412452 -309.844192) (xy 83.461307 -309.850124) (xy 83.472376 -309.85333)
			(xy 89.010742 -309.85333) (xy 89.014813 -309.797708) (xy 89.026939 -309.743271) (xy 89.046862 -309.69118)
			(xy 89.074158 -309.642545) (xy 89.108244 -309.598402) (xy 89.148393 -309.559693) (xy 89.193751 -309.527242)
			(xy 89.243351 -309.501741) (xy 89.296135 -309.483734) (xy 89.350978 -309.473604) (xy 89.406712 -309.471567)
			(xy 89.462149 -309.477667) (xy 89.516106 -309.491773) (xy 89.567435 -309.513585) (xy 89.615041 -309.542639)
			(xy 89.657909 -309.578314) (xy 89.68698 -309.61076) (xy 93.557088 -309.61076) (xy 93.561159 -309.555138)
			(xy 93.573285 -309.500701) (xy 93.593208 -309.44861) (xy 93.620504 -309.399975) (xy 93.65459 -309.355832)
			(xy 93.694739 -309.317123) (xy 93.740097 -309.284672) (xy 93.789697 -309.259171) (xy 93.842481 -309.241164)
			(xy 93.897324 -309.231034) (xy 93.953058 -309.228997) (xy 94.008495 -309.235097) (xy 94.062452 -309.249203)
			(xy 94.113781 -309.271015) (xy 94.161387 -309.300069) (xy 94.204255 -309.335744) (xy 94.241472 -309.377281)
			(xy 94.272245 -309.423794) (xy 94.295917 -309.474291) (xy 94.311985 -309.527698) (xy 94.320105 -309.582874)
			(xy 94.320614 -309.61076) (xy 94.320105 -309.638646) (xy 94.311985 -309.693822) (xy 94.295917 -309.747229)
			(xy 94.272245 -309.797726) (xy 94.241472 -309.844239) (xy 94.204255 -309.885776) (xy 94.161387 -309.921451)
			(xy 94.113781 -309.950505) (xy 94.062452 -309.972317) (xy 94.008495 -309.986423) (xy 93.953058 -309.992523)
			(xy 93.897324 -309.990486) (xy 93.842481 -309.980356) (xy 93.789697 -309.962349) (xy 93.740097 -309.936848)
			(xy 93.694739 -309.904397) (xy 93.65459 -309.865688) (xy 93.620504 -309.821545) (xy 93.593208 -309.77291)
			(xy 93.573285 -309.720819) (xy 93.561159 -309.666382) (xy 93.557088 -309.61076) (xy 89.68698 -309.61076)
			(xy 89.695126 -309.619851) (xy 89.725899 -309.666364) (xy 89.749571 -309.716861) (xy 89.765639 -309.770268)
			(xy 89.773759 -309.825444) (xy 89.774268 -309.85333) (xy 89.773759 -309.881216) (xy 89.765639 -309.936392)
			(xy 89.749571 -309.989799) (xy 89.725899 -310.040296) (xy 89.695126 -310.086809) (xy 89.657909 -310.128346)
			(xy 89.615041 -310.164021) (xy 89.567435 -310.193075) (xy 89.516106 -310.214887) (xy 89.462149 -310.228993)
			(xy 89.406712 -310.235093) (xy 89.350978 -310.233056) (xy 89.296135 -310.222926) (xy 89.243351 -310.204919)
			(xy 89.193751 -310.179418) (xy 89.148393 -310.146967) (xy 89.108244 -310.108258) (xy 89.074158 -310.064115)
			(xy 89.046862 -310.01548) (xy 89.026939 -309.963389) (xy 89.014813 -309.908952) (xy 89.010742 -309.85333)
			(xy 83.472376 -309.85333) (xy 83.508578 -309.863816) (xy 83.55304 -309.884914) (xy 83.593543 -309.91287)
			(xy 83.629036 -309.946962) (xy 83.658601 -309.986306) (xy 83.681472 -310.029883) (xy 83.697056 -310.076564)
			(xy 83.704951 -310.125141) (xy 83.705446 -310.149748) (xy 83.704951 -310.174355) (xy 83.697056 -310.222932)
			(xy 83.681472 -310.269613) (xy 83.658601 -310.31319) (xy 83.629036 -310.352534) (xy 83.593543 -310.386626)
			(xy 83.55304 -310.414582) (xy 83.508578 -310.43568) (xy 83.461307 -310.449372) (xy 83.412452 -310.455304)
			(xy 83.363277 -310.453323) (xy 83.315058 -310.443479) (xy 83.269042 -310.426027) (xy 83.226421 -310.40142)
			(xy 83.1883 -310.370295) (xy 83.155665 -310.333458) (xy 83.129362 -310.291862) (xy 83.110071 -310.246586)
			(xy 83.098294 -310.198802) (xy 83.094334 -310.149748) (xy 82.755232 -310.149748) (xy 82.754737 -310.174355)
			(xy 82.746842 -310.222932) (xy 82.731258 -310.269613) (xy 82.708387 -310.31319) (xy 82.678822 -310.352534)
			(xy 82.643329 -310.386626) (xy 82.602826 -310.414582) (xy 82.558364 -310.43568) (xy 82.511093 -310.449372)
			(xy 82.462238 -310.455304) (xy 82.413063 -310.453323) (xy 82.364844 -310.443479) (xy 82.318828 -310.426027)
			(xy 82.276207 -310.40142) (xy 82.238086 -310.370295) (xy 82.205451 -310.333458) (xy 82.179148 -310.291862)
			(xy 82.159857 -310.246586) (xy 82.14808 -310.198802) (xy 82.14412 -310.149748) (xy 81.805272 -310.149748)
			(xy 81.804777 -310.174355) (xy 81.796882 -310.222932) (xy 81.781298 -310.269613) (xy 81.758427 -310.31319)
			(xy 81.728862 -310.352534) (xy 81.693369 -310.386626) (xy 81.652866 -310.414582) (xy 81.608404 -310.43568)
			(xy 81.561133 -310.449372) (xy 81.512278 -310.455304) (xy 81.463103 -310.453323) (xy 81.414884 -310.443479)
			(xy 81.368868 -310.426027) (xy 81.326247 -310.40142) (xy 81.288126 -310.370295) (xy 81.255491 -310.333458)
			(xy 81.229188 -310.291862) (xy 81.209897 -310.246586) (xy 81.19812 -310.198802) (xy 81.19416 -310.149748)
			(xy 80.855058 -310.149748) (xy 80.854563 -310.174355) (xy 80.846668 -310.222932) (xy 80.831084 -310.269613)
			(xy 80.808213 -310.31319) (xy 80.778648 -310.352534) (xy 80.743155 -310.386626) (xy 80.702652 -310.414582)
			(xy 80.65819 -310.43568) (xy 80.610919 -310.449372) (xy 80.562064 -310.455304) (xy 80.512889 -310.453323)
			(xy 80.46467 -310.443479) (xy 80.418654 -310.426027) (xy 80.376033 -310.40142) (xy 80.337912 -310.370295)
			(xy 80.305277 -310.333458) (xy 80.278974 -310.291862) (xy 80.259683 -310.246586) (xy 80.247906 -310.198802)
			(xy 80.243946 -310.149748) (xy 79.905098 -310.149748) (xy 79.904603 -310.174355) (xy 79.896708 -310.222932)
			(xy 79.881124 -310.269613) (xy 79.858253 -310.31319) (xy 79.828688 -310.352534) (xy 79.793195 -310.386626)
			(xy 79.752692 -310.414582) (xy 79.70823 -310.43568) (xy 79.660959 -310.449372) (xy 79.612104 -310.455304)
			(xy 79.562929 -310.453323) (xy 79.51471 -310.443479) (xy 79.468694 -310.426027) (xy 79.426073 -310.40142)
			(xy 79.387952 -310.370295) (xy 79.355317 -310.333458) (xy 79.329014 -310.291862) (xy 79.309723 -310.246586)
			(xy 79.297946 -310.198802) (xy 79.293986 -310.149748) (xy 78.955138 -310.149748) (xy 78.954643 -310.174355)
			(xy 78.946748 -310.222932) (xy 78.931164 -310.269613) (xy 78.908293 -310.31319) (xy 78.878728 -310.352534)
			(xy 78.843235 -310.386626) (xy 78.802732 -310.414582) (xy 78.75827 -310.43568) (xy 78.710999 -310.449372)
			(xy 78.662144 -310.455304) (xy 78.612969 -310.453323) (xy 78.56475 -310.443479) (xy 78.518734 -310.426027)
			(xy 78.476113 -310.40142) (xy 78.437992 -310.370295) (xy 78.405357 -310.333458) (xy 78.379054 -310.291862)
			(xy 78.359763 -310.246586) (xy 78.347986 -310.198802) (xy 78.344026 -310.149748) (xy 78.005178 -310.149748)
			(xy 78.004683 -310.174355) (xy 77.996788 -310.222932) (xy 77.981204 -310.269613) (xy 77.958333 -310.31319)
			(xy 77.928768 -310.352534) (xy 77.893275 -310.386626) (xy 77.852772 -310.414582) (xy 77.80831 -310.43568)
			(xy 77.761039 -310.449372) (xy 77.712184 -310.455304) (xy 77.663009 -310.453323) (xy 77.61479 -310.443479)
			(xy 77.568774 -310.426027) (xy 77.526153 -310.40142) (xy 77.488032 -310.370295) (xy 77.455397 -310.333458)
			(xy 77.429094 -310.291862) (xy 77.409803 -310.246586) (xy 77.398026 -310.198802) (xy 77.394066 -310.149748)
			(xy 77.055218 -310.149748) (xy 77.054723 -310.174355) (xy 77.046828 -310.222932) (xy 77.031244 -310.269613)
			(xy 77.008373 -310.31319) (xy 76.978808 -310.352534) (xy 76.943315 -310.386626) (xy 76.902812 -310.414582)
			(xy 76.85835 -310.43568) (xy 76.811079 -310.449372) (xy 76.762224 -310.455304) (xy 76.713049 -310.453323)
			(xy 76.66483 -310.443479) (xy 76.618814 -310.426027) (xy 76.576193 -310.40142) (xy 76.538072 -310.370295)
			(xy 76.505437 -310.333458) (xy 76.479134 -310.291862) (xy 76.459843 -310.246586) (xy 76.448066 -310.198802)
			(xy 76.444106 -310.149748) (xy 76.105258 -310.149748) (xy 76.104763 -310.174355) (xy 76.096868 -310.222932)
			(xy 76.081284 -310.269613) (xy 76.058413 -310.31319) (xy 76.028848 -310.352534) (xy 75.993355 -310.386626)
			(xy 75.952852 -310.414582) (xy 75.90839 -310.43568) (xy 75.861119 -310.449372) (xy 75.812264 -310.455304)
			(xy 75.763089 -310.453323) (xy 75.71487 -310.443479) (xy 75.668854 -310.426027) (xy 75.626233 -310.40142)
			(xy 75.588112 -310.370295) (xy 75.555477 -310.333458) (xy 75.529174 -310.291862) (xy 75.509883 -310.246586)
			(xy 75.498106 -310.198802) (xy 75.494146 -310.149748) (xy 75.155298 -310.149748) (xy 75.154803 -310.174355)
			(xy 75.146908 -310.222932) (xy 75.131324 -310.269613) (xy 75.108453 -310.31319) (xy 75.078888 -310.352534)
			(xy 75.043395 -310.386626) (xy 75.002892 -310.414582) (xy 74.95843 -310.43568) (xy 74.911159 -310.449372)
			(xy 74.862304 -310.455304) (xy 74.813129 -310.453323) (xy 74.76491 -310.443479) (xy 74.718894 -310.426027)
			(xy 74.676273 -310.40142) (xy 74.638152 -310.370295) (xy 74.605517 -310.333458) (xy 74.579214 -310.291862)
			(xy 74.559923 -310.246586) (xy 74.548146 -310.198802) (xy 74.544186 -310.149748) (xy 74.205084 -310.149748)
			(xy 74.204589 -310.174355) (xy 74.196694 -310.222932) (xy 74.18111 -310.269613) (xy 74.158239 -310.31319)
			(xy 74.128674 -310.352534) (xy 74.093181 -310.386626) (xy 74.052678 -310.414582) (xy 74.008216 -310.43568)
			(xy 73.960945 -310.449372) (xy 73.91209 -310.455304) (xy 73.862915 -310.453323) (xy 73.814696 -310.443479)
			(xy 73.76868 -310.426027) (xy 73.726059 -310.40142) (xy 73.687938 -310.370295) (xy 73.655303 -310.333458)
			(xy 73.629 -310.291862) (xy 73.609709 -310.246586) (xy 73.597932 -310.198802) (xy 73.593972 -310.149748)
			(xy 73.255124 -310.149748) (xy 73.254629 -310.174355) (xy 73.246734 -310.222932) (xy 73.23115 -310.269613)
			(xy 73.208279 -310.31319) (xy 73.178714 -310.352534) (xy 73.143221 -310.386626) (xy 73.102718 -310.414582)
			(xy 73.058256 -310.43568) (xy 73.010985 -310.449372) (xy 72.96213 -310.455304) (xy 72.912955 -310.453323)
			(xy 72.864736 -310.443479) (xy 72.81872 -310.426027) (xy 72.776099 -310.40142) (xy 72.737978 -310.370295)
			(xy 72.705343 -310.333458) (xy 72.67904 -310.291862) (xy 72.659749 -310.246586) (xy 72.647972 -310.198802)
			(xy 72.644012 -310.149748) (xy 72.305164 -310.149748) (xy 72.304669 -310.174355) (xy 72.296774 -310.222932)
			(xy 72.28119 -310.269613) (xy 72.258319 -310.31319) (xy 72.228754 -310.352534) (xy 72.193261 -310.386626)
			(xy 72.152758 -310.414582) (xy 72.108296 -310.43568) (xy 72.061025 -310.449372) (xy 72.01217 -310.455304)
			(xy 71.962995 -310.453323) (xy 71.914776 -310.443479) (xy 71.86876 -310.426027) (xy 71.826139 -310.40142)
			(xy 71.788018 -310.370295) (xy 71.755383 -310.333458) (xy 71.72908 -310.291862) (xy 71.709789 -310.246586)
			(xy 71.698012 -310.198802) (xy 71.694052 -310.149748) (xy 71.355204 -310.149748) (xy 71.354709 -310.174355)
			(xy 71.346814 -310.222932) (xy 71.33123 -310.269613) (xy 71.308359 -310.31319) (xy 71.278794 -310.352534)
			(xy 71.243301 -310.386626) (xy 71.202798 -310.414582) (xy 71.158336 -310.43568) (xy 71.111065 -310.449372)
			(xy 71.06221 -310.455304) (xy 71.013035 -310.453323) (xy 70.964816 -310.443479) (xy 70.9188 -310.426027)
			(xy 70.876179 -310.40142) (xy 70.838058 -310.370295) (xy 70.805423 -310.333458) (xy 70.77912 -310.291862)
			(xy 70.759829 -310.246586) (xy 70.748052 -310.198802) (xy 70.744092 -310.149748) (xy 70.405244 -310.149748)
			(xy 70.404749 -310.174355) (xy 70.396854 -310.222932) (xy 70.38127 -310.269613) (xy 70.358399 -310.31319)
			(xy 70.328834 -310.352534) (xy 70.293341 -310.386626) (xy 70.252838 -310.414582) (xy 70.208376 -310.43568)
			(xy 70.161105 -310.449372) (xy 70.11225 -310.455304) (xy 70.063075 -310.453323) (xy 70.014856 -310.443479)
			(xy 69.96884 -310.426027) (xy 69.926219 -310.40142) (xy 69.888098 -310.370295) (xy 69.855463 -310.333458)
			(xy 69.82916 -310.291862) (xy 69.809869 -310.246586) (xy 69.798092 -310.198802) (xy 69.794132 -310.149748)
			(xy 69.455284 -310.149748) (xy 69.454789 -310.174355) (xy 69.446894 -310.222932) (xy 69.43131 -310.269613)
			(xy 69.408439 -310.31319) (xy 69.378874 -310.352534) (xy 69.343381 -310.386626) (xy 69.302878 -310.414582)
			(xy 69.258416 -310.43568) (xy 69.211145 -310.449372) (xy 69.16229 -310.455304) (xy 69.113115 -310.453323)
			(xy 69.064896 -310.443479) (xy 69.01888 -310.426027) (xy 68.976259 -310.40142) (xy 68.938138 -310.370295)
			(xy 68.905503 -310.333458) (xy 68.8792 -310.291862) (xy 68.859909 -310.246586) (xy 68.848132 -310.198802)
			(xy 68.844172 -310.149748) (xy 68.50507 -310.149748) (xy 68.504575 -310.174355) (xy 68.49668 -310.222932)
			(xy 68.481096 -310.269613) (xy 68.458225 -310.31319) (xy 68.42866 -310.352534) (xy 68.393167 -310.386626)
			(xy 68.352664 -310.414582) (xy 68.308202 -310.43568) (xy 68.260931 -310.449372) (xy 68.212076 -310.455304)
			(xy 68.162901 -310.453323) (xy 68.114682 -310.443479) (xy 68.068666 -310.426027) (xy 68.026045 -310.40142)
			(xy 67.987924 -310.370295) (xy 67.955289 -310.333458) (xy 67.928986 -310.291862) (xy 67.909695 -310.246586)
			(xy 67.897918 -310.198802) (xy 67.893958 -310.149748) (xy 67.55511 -310.149748) (xy 67.554615 -310.174355)
			(xy 67.54672 -310.222932) (xy 67.531136 -310.269613) (xy 67.508265 -310.31319) (xy 67.4787 -310.352534)
			(xy 67.443207 -310.386626) (xy 67.402704 -310.414582) (xy 67.358242 -310.43568) (xy 67.310971 -310.449372)
			(xy 67.262116 -310.455304) (xy 67.212941 -310.453323) (xy 67.164722 -310.443479) (xy 67.118706 -310.426027)
			(xy 67.076085 -310.40142) (xy 67.037964 -310.370295) (xy 67.005329 -310.333458) (xy 66.979026 -310.291862)
			(xy 66.959735 -310.246586) (xy 66.947958 -310.198802) (xy 66.943998 -310.149748) (xy 66.60515 -310.149748)
			(xy 66.604655 -310.174355) (xy 66.59676 -310.222932) (xy 66.581176 -310.269613) (xy 66.558305 -310.31319)
			(xy 66.52874 -310.352534) (xy 66.493247 -310.386626) (xy 66.452744 -310.414582) (xy 66.408282 -310.43568)
			(xy 66.361011 -310.449372) (xy 66.312156 -310.455304) (xy 66.262981 -310.453323) (xy 66.214762 -310.443479)
			(xy 66.168746 -310.426027) (xy 66.126125 -310.40142) (xy 66.088004 -310.370295) (xy 66.055369 -310.333458)
			(xy 66.029066 -310.291862) (xy 66.009775 -310.246586) (xy 65.997998 -310.198802) (xy 65.994038 -310.149748)
			(xy 65.65519 -310.149748) (xy 65.654695 -310.174355) (xy 65.6468 -310.222932) (xy 65.631216 -310.269613)
			(xy 65.608345 -310.31319) (xy 65.57878 -310.352534) (xy 65.543287 -310.386626) (xy 65.502784 -310.414582)
			(xy 65.458322 -310.43568) (xy 65.411051 -310.449372) (xy 65.362196 -310.455304) (xy 65.313021 -310.453323)
			(xy 65.264802 -310.443479) (xy 65.218786 -310.426027) (xy 65.176165 -310.40142) (xy 65.138044 -310.370295)
			(xy 65.105409 -310.333458) (xy 65.079106 -310.291862) (xy 65.059815 -310.246586) (xy 65.048038 -310.198802)
			(xy 65.044078 -310.149748) (xy 64.70523 -310.149748) (xy 64.704735 -310.174355) (xy 64.69684 -310.222932)
			(xy 64.681256 -310.269613) (xy 64.658385 -310.31319) (xy 64.62882 -310.352534) (xy 64.593327 -310.386626)
			(xy 64.552824 -310.414582) (xy 64.508362 -310.43568) (xy 64.461091 -310.449372) (xy 64.412236 -310.455304)
			(xy 64.363061 -310.453323) (xy 64.314842 -310.443479) (xy 64.268826 -310.426027) (xy 64.226205 -310.40142)
			(xy 64.188084 -310.370295) (xy 64.155449 -310.333458) (xy 64.129146 -310.291862) (xy 64.109855 -310.246586)
			(xy 64.098078 -310.198802) (xy 64.094118 -310.149748) (xy 63.75527 -310.149748) (xy 63.754775 -310.174355)
			(xy 63.74688 -310.222932) (xy 63.731296 -310.269613) (xy 63.708425 -310.31319) (xy 63.67886 -310.352534)
			(xy 63.643367 -310.386626) (xy 63.602864 -310.414582) (xy 63.558402 -310.43568) (xy 63.511131 -310.449372)
			(xy 63.462276 -310.455304) (xy 63.413101 -310.453323) (xy 63.364882 -310.443479) (xy 63.318866 -310.426027)
			(xy 63.276245 -310.40142) (xy 63.238124 -310.370295) (xy 63.205489 -310.333458) (xy 63.179186 -310.291862)
			(xy 63.159895 -310.246586) (xy 63.148118 -310.198802) (xy 63.144158 -310.149748) (xy 62.805056 -310.149748)
			(xy 62.804561 -310.174355) (xy 62.796666 -310.222932) (xy 62.781082 -310.269613) (xy 62.758211 -310.31319)
			(xy 62.728646 -310.352534) (xy 62.693153 -310.386626) (xy 62.65265 -310.414582) (xy 62.608188 -310.43568)
			(xy 62.560917 -310.449372) (xy 62.512062 -310.455304) (xy 62.462887 -310.453323) (xy 62.414668 -310.443479)
			(xy 62.368652 -310.426027) (xy 62.326031 -310.40142) (xy 62.28791 -310.370295) (xy 62.255275 -310.333458)
			(xy 62.228972 -310.291862) (xy 62.209681 -310.246586) (xy 62.197904 -310.198802) (xy 62.193944 -310.149748)
			(xy 61.855096 -310.149748) (xy 61.854601 -310.174355) (xy 61.846706 -310.222932) (xy 61.831122 -310.269613)
			(xy 61.808251 -310.31319) (xy 61.778686 -310.352534) (xy 61.743193 -310.386626) (xy 61.70269 -310.414582)
			(xy 61.658228 -310.43568) (xy 61.610957 -310.449372) (xy 61.562102 -310.455304) (xy 61.512927 -310.453323)
			(xy 61.464708 -310.443479) (xy 61.418692 -310.426027) (xy 61.376071 -310.40142) (xy 61.33795 -310.370295)
			(xy 61.305315 -310.333458) (xy 61.279012 -310.291862) (xy 61.259721 -310.246586) (xy 61.247944 -310.198802)
			(xy 61.243984 -310.149748) (xy 60.905136 -310.149748) (xy 60.904641 -310.174355) (xy 60.896746 -310.222932)
			(xy 60.881162 -310.269613) (xy 60.858291 -310.31319) (xy 60.828726 -310.352534) (xy 60.793233 -310.386626)
			(xy 60.75273 -310.414582) (xy 60.708268 -310.43568) (xy 60.660997 -310.449372) (xy 60.612142 -310.455304)
			(xy 60.562967 -310.453323) (xy 60.514748 -310.443479) (xy 60.468732 -310.426027) (xy 60.426111 -310.40142)
			(xy 60.38799 -310.370295) (xy 60.355355 -310.333458) (xy 60.329052 -310.291862) (xy 60.309761 -310.246586)
			(xy 60.297984 -310.198802) (xy 60.294024 -310.149748) (xy 59.955176 -310.149748) (xy 59.954681 -310.174355)
			(xy 59.946786 -310.222932) (xy 59.931202 -310.269613) (xy 59.908331 -310.31319) (xy 59.878766 -310.352534)
			(xy 59.843273 -310.386626) (xy 59.80277 -310.414582) (xy 59.758308 -310.43568) (xy 59.711037 -310.449372)
			(xy 59.662182 -310.455304) (xy 59.613007 -310.453323) (xy 59.564788 -310.443479) (xy 59.518772 -310.426027)
			(xy 59.476151 -310.40142) (xy 59.43803 -310.370295) (xy 59.405395 -310.333458) (xy 59.379092 -310.291862)
			(xy 59.359801 -310.246586) (xy 59.348024 -310.198802) (xy 59.344064 -310.149748) (xy 59.005216 -310.149748)
			(xy 59.004721 -310.174355) (xy 58.996826 -310.222932) (xy 58.981242 -310.269613) (xy 58.958371 -310.31319)
			(xy 58.928806 -310.352534) (xy 58.893313 -310.386626) (xy 58.85281 -310.414582) (xy 58.808348 -310.43568)
			(xy 58.761077 -310.449372) (xy 58.712222 -310.455304) (xy 58.663047 -310.453323) (xy 58.614828 -310.443479)
			(xy 58.568812 -310.426027) (xy 58.526191 -310.40142) (xy 58.48807 -310.370295) (xy 58.455435 -310.333458)
			(xy 58.429132 -310.291862) (xy 58.409841 -310.246586) (xy 58.398064 -310.198802) (xy 58.394104 -310.149748)
			(xy 58.055127 -310.149748) (xy 58.055572 -310.157932) (xy 58.050214 -310.207276) (xy 58.036943 -310.255103)
			(xy 58.016109 -310.300153) (xy 57.988261 -310.341239) (xy 57.954134 -310.377278) (xy 57.914625 -310.407321)
			(xy 57.870777 -310.430577) (xy 57.823744 -310.446433) (xy 57.774765 -310.45447) (xy 57.749948 -310.455056)
			(xy 57.73166 -310.454548) (xy 57.717436 -310.453532) (xy 57.692544 -310.466486) (xy 57.630822 -310.567324)
			(xy 57.630568 -310.59501) (xy 57.637934 -310.607456) (xy 57.659159 -310.644538) (xy 57.67844 -310.68518)
			(xy 89.842592 -310.68518) (xy 89.846663 -310.629558) (xy 89.858789 -310.575121) (xy 89.878712 -310.52303)
			(xy 89.906008 -310.474395) (xy 89.940094 -310.430252) (xy 89.980243 -310.391543) (xy 90.025601 -310.359092)
			(xy 90.075201 -310.333591) (xy 90.127985 -310.315584) (xy 90.182828 -310.305454) (xy 90.238562 -310.303417)
			(xy 90.293999 -310.309517) (xy 90.347956 -310.323623) (xy 90.399285 -310.345435) (xy 90.446891 -310.374489)
			(xy 90.489759 -310.410164) (xy 90.526976 -310.451701) (xy 90.557749 -310.498214) (xy 90.581421 -310.548711)
			(xy 90.597489 -310.602118) (xy 90.605609 -310.657294) (xy 90.606118 -310.68518) (xy 90.605609 -310.713066)
			(xy 90.597489 -310.768242) (xy 90.581421 -310.821649) (xy 90.557749 -310.872146) (xy 90.526976 -310.918659)
			(xy 90.489759 -310.960196) (xy 90.446891 -310.995871) (xy 90.399285 -311.024925) (xy 90.347956 -311.046737)
			(xy 90.293999 -311.060843) (xy 90.238562 -311.066943) (xy 90.182828 -311.064906) (xy 90.127985 -311.054776)
			(xy 90.075201 -311.036769) (xy 90.025601 -311.011268) (xy 89.980243 -310.978817) (xy 89.940094 -310.940108)
			(xy 89.906008 -310.895965) (xy 89.878712 -310.84733) (xy 89.858789 -310.795239) (xy 89.846663 -310.740802)
			(xy 89.842592 -310.68518) (xy 57.67844 -310.68518) (xy 57.695785 -310.72174) (xy 57.711086 -310.761634)
			(xy 57.715059 -310.770964) (xy 57.728948 -310.785718) (xy 57.74745 -310.793977) (xy 57.757568 -310.794654)
			(xy 57.781166 -310.795681) (xy 57.82764 -310.804111) (xy 57.87226 -310.8196) (xy 57.913962 -310.841777)
			(xy 57.951751 -310.870112) (xy 57.984723 -310.903931) (xy 58.012093 -310.942425) (xy 58.033207 -310.984675)
			(xy 58.04756 -311.029673) (xy 58.054811 -311.076346) (xy 58.055256 -311.099962) (xy 58.054723 -311.12567)
			(xy 58.37326 -311.12567) (xy 58.37326 -311.074254) (xy 58.381303 -311.023472) (xy 58.397191 -310.974573)
			(xy 58.420534 -310.928761) (xy 58.450755 -310.887165) (xy 58.487111 -310.850809) (xy 58.528707 -310.820588)
			(xy 58.574519 -310.797245) (xy 58.623418 -310.781357) (xy 58.6742 -310.773314) (xy 58.725616 -310.773314)
			(xy 58.776398 -310.781357) (xy 58.825297 -310.797245) (xy 58.871109 -310.820588) (xy 58.912705 -310.850809)
			(xy 58.949061 -310.887165) (xy 58.979282 -310.928761) (xy 59.002625 -310.974573) (xy 59.018513 -311.023472)
			(xy 59.026556 -311.074254) (xy 59.02706 -311.099962) (xy 59.344064 -311.099962) (xy 59.348024 -311.050908)
			(xy 59.359801 -311.003124) (xy 59.379092 -310.957848) (xy 59.405395 -310.916252) (xy 59.43803 -310.879415)
			(xy 59.476151 -310.84829) (xy 59.518772 -310.823683) (xy 59.564788 -310.806231) (xy 59.613007 -310.796387)
			(xy 59.662182 -310.794406) (xy 59.711037 -310.800338) (xy 59.758308 -310.81403) (xy 59.80277 -310.835128)
			(xy 59.843273 -310.863084) (xy 59.878766 -310.897176) (xy 59.908331 -310.93652) (xy 59.931202 -310.980097)
			(xy 59.946786 -311.026778) (xy 59.954681 -311.075355) (xy 59.955176 -311.099962) (xy 59.954681 -311.124569)
			(xy 59.954502 -311.12567) (xy 60.27318 -311.12567) (xy 60.27318 -311.074254) (xy 60.281223 -311.023472)
			(xy 60.297111 -310.974573) (xy 60.320454 -310.928761) (xy 60.350675 -310.887165) (xy 60.387031 -310.850809)
			(xy 60.428627 -310.820588) (xy 60.474439 -310.797245) (xy 60.523338 -310.781357) (xy 60.57412 -310.773314)
			(xy 60.625536 -310.773314) (xy 60.676318 -310.781357) (xy 60.725217 -310.797245) (xy 60.771029 -310.820588)
			(xy 60.812625 -310.850809) (xy 60.848981 -310.887165) (xy 60.879202 -310.928761) (xy 60.902545 -310.974573)
			(xy 60.918433 -311.023472) (xy 60.926476 -311.074254) (xy 60.92698 -311.099962) (xy 61.243984 -311.099962)
			(xy 61.247944 -311.050908) (xy 61.259721 -311.003124) (xy 61.279012 -310.957848) (xy 61.305315 -310.916252)
			(xy 61.33795 -310.879415) (xy 61.376071 -310.84829) (xy 61.418692 -310.823683) (xy 61.464708 -310.806231)
			(xy 61.512927 -310.796387) (xy 61.562102 -310.794406) (xy 61.610957 -310.800338) (xy 61.658228 -310.81403)
			(xy 61.70269 -310.835128) (xy 61.743193 -310.863084) (xy 61.778686 -310.897176) (xy 61.808251 -310.93652)
			(xy 61.831122 -310.980097) (xy 61.846706 -311.026778) (xy 61.854601 -311.075355) (xy 61.855096 -311.099962)
			(xy 61.854601 -311.124569) (xy 61.854422 -311.12567) (xy 62.1731 -311.12567) (xy 62.1731 -311.074254)
			(xy 62.181143 -311.023472) (xy 62.197031 -310.974573) (xy 62.220374 -310.928761) (xy 62.250595 -310.887165)
			(xy 62.286951 -310.850809) (xy 62.328547 -310.820588) (xy 62.374359 -310.797245) (xy 62.423258 -310.781357)
			(xy 62.47404 -310.773314) (xy 62.525456 -310.773314) (xy 62.576238 -310.781357) (xy 62.625137 -310.797245)
			(xy 62.670949 -310.820588) (xy 62.712545 -310.850809) (xy 62.748901 -310.887165) (xy 62.779122 -310.928761)
			(xy 62.802465 -310.974573) (xy 62.818353 -311.023472) (xy 62.826396 -311.074254) (xy 62.8269 -311.099962)
			(xy 63.144158 -311.099962) (xy 63.148118 -311.050908) (xy 63.159895 -311.003124) (xy 63.179186 -310.957848)
			(xy 63.205489 -310.916252) (xy 63.238124 -310.879415) (xy 63.276245 -310.84829) (xy 63.318866 -310.823683)
			(xy 63.364882 -310.806231) (xy 63.413101 -310.796387) (xy 63.462276 -310.794406) (xy 63.511131 -310.800338)
			(xy 63.558402 -310.81403) (xy 63.602864 -310.835128) (xy 63.643367 -310.863084) (xy 63.67886 -310.897176)
			(xy 63.708425 -310.93652) (xy 63.731296 -310.980097) (xy 63.74688 -311.026778) (xy 63.754775 -311.075355)
			(xy 63.75527 -311.099962) (xy 63.754775 -311.124569) (xy 63.754596 -311.12567) (xy 64.073274 -311.12567)
			(xy 64.073274 -311.074254) (xy 64.081317 -311.023472) (xy 64.097205 -310.974573) (xy 64.120548 -310.928761)
			(xy 64.150769 -310.887165) (xy 64.187125 -310.850809) (xy 64.228721 -310.820588) (xy 64.274533 -310.797245)
			(xy 64.323432 -310.781357) (xy 64.374214 -310.773314) (xy 64.42563 -310.773314) (xy 64.476412 -310.781357)
			(xy 64.525311 -310.797245) (xy 64.571123 -310.820588) (xy 64.612719 -310.850809) (xy 64.649075 -310.887165)
			(xy 64.679296 -310.928761) (xy 64.702639 -310.974573) (xy 64.718527 -311.023472) (xy 64.72657 -311.074254)
			(xy 64.727074 -311.099962) (xy 65.044078 -311.099962) (xy 65.048038 -311.050908) (xy 65.059815 -311.003124)
			(xy 65.079106 -310.957848) (xy 65.105409 -310.916252) (xy 65.138044 -310.879415) (xy 65.176165 -310.84829)
			(xy 65.218786 -310.823683) (xy 65.264802 -310.806231) (xy 65.313021 -310.796387) (xy 65.362196 -310.794406)
			(xy 65.411051 -310.800338) (xy 65.458322 -310.81403) (xy 65.502784 -310.835128) (xy 65.543287 -310.863084)
			(xy 65.57878 -310.897176) (xy 65.608345 -310.93652) (xy 65.631216 -310.980097) (xy 65.6468 -311.026778)
			(xy 65.654695 -311.075355) (xy 65.65519 -311.099962) (xy 65.654695 -311.124569) (xy 65.654516 -311.12567)
			(xy 65.973194 -311.12567) (xy 65.973194 -311.074254) (xy 65.981237 -311.023472) (xy 65.997125 -310.974573)
			(xy 66.020468 -310.928761) (xy 66.050689 -310.887165) (xy 66.087045 -310.850809) (xy 66.128641 -310.820588)
			(xy 66.174453 -310.797245) (xy 66.223352 -310.781357) (xy 66.274134 -310.773314) (xy 66.32555 -310.773314)
			(xy 66.376332 -310.781357) (xy 66.425231 -310.797245) (xy 66.471043 -310.820588) (xy 66.512639 -310.850809)
			(xy 66.548995 -310.887165) (xy 66.579216 -310.928761) (xy 66.602559 -310.974573) (xy 66.618447 -311.023472)
			(xy 66.62649 -311.074254) (xy 66.626994 -311.099962) (xy 66.943998 -311.099962) (xy 66.947958 -311.050908)
			(xy 66.959735 -311.003124) (xy 66.979026 -310.957848) (xy 67.005329 -310.916252) (xy 67.037964 -310.879415)
			(xy 67.076085 -310.84829) (xy 67.118706 -310.823683) (xy 67.164722 -310.806231) (xy 67.212941 -310.796387)
			(xy 67.262116 -310.794406) (xy 67.310971 -310.800338) (xy 67.358242 -310.81403) (xy 67.402704 -310.835128)
			(xy 67.443207 -310.863084) (xy 67.4787 -310.897176) (xy 67.508265 -310.93652) (xy 67.531136 -310.980097)
			(xy 67.54672 -311.026778) (xy 67.554615 -311.075355) (xy 67.55511 -311.099962) (xy 67.554615 -311.124569)
			(xy 67.554436 -311.12567) (xy 67.873114 -311.12567) (xy 67.873114 -311.074254) (xy 67.881157 -311.023472)
			(xy 67.897045 -310.974573) (xy 67.920388 -310.928761) (xy 67.950609 -310.887165) (xy 67.986965 -310.850809)
			(xy 68.028561 -310.820588) (xy 68.074373 -310.797245) (xy 68.123272 -310.781357) (xy 68.174054 -310.773314)
			(xy 68.22547 -310.773314) (xy 68.276252 -310.781357) (xy 68.325151 -310.797245) (xy 68.370963 -310.820588)
			(xy 68.412559 -310.850809) (xy 68.448915 -310.887165) (xy 68.479136 -310.928761) (xy 68.502479 -310.974573)
			(xy 68.518367 -311.023472) (xy 68.52641 -311.074254) (xy 68.526914 -311.099962) (xy 68.844172 -311.099962)
			(xy 68.848132 -311.050908) (xy 68.859909 -311.003124) (xy 68.8792 -310.957848) (xy 68.905503 -310.916252)
			(xy 68.938138 -310.879415) (xy 68.976259 -310.84829) (xy 69.01888 -310.823683) (xy 69.064896 -310.806231)
			(xy 69.113115 -310.796387) (xy 69.16229 -310.794406) (xy 69.211145 -310.800338) (xy 69.258416 -310.81403)
			(xy 69.302878 -310.835128) (xy 69.343381 -310.863084) (xy 69.378874 -310.897176) (xy 69.408439 -310.93652)
			(xy 69.43131 -310.980097) (xy 69.446894 -311.026778) (xy 69.454789 -311.075355) (xy 69.455284 -311.099962)
			(xy 69.454789 -311.124569) (xy 69.45461 -311.12567) (xy 69.773288 -311.12567) (xy 69.773288 -311.074254)
			(xy 69.781331 -311.023472) (xy 69.797219 -310.974573) (xy 69.820562 -310.928761) (xy 69.850783 -310.887165)
			(xy 69.887139 -310.850809) (xy 69.928735 -310.820588) (xy 69.974547 -310.797245) (xy 70.023446 -310.781357)
			(xy 70.074228 -310.773314) (xy 70.125644 -310.773314) (xy 70.176426 -310.781357) (xy 70.225325 -310.797245)
			(xy 70.271137 -310.820588) (xy 70.312733 -310.850809) (xy 70.349089 -310.887165) (xy 70.37931 -310.928761)
			(xy 70.402653 -310.974573) (xy 70.418541 -311.023472) (xy 70.426584 -311.074254) (xy 70.427088 -311.099962)
			(xy 70.744092 -311.099962) (xy 70.748052 -311.050908) (xy 70.759829 -311.003124) (xy 70.77912 -310.957848)
			(xy 70.805423 -310.916252) (xy 70.838058 -310.879415) (xy 70.876179 -310.84829) (xy 70.9188 -310.823683)
			(xy 70.964816 -310.806231) (xy 71.013035 -310.796387) (xy 71.06221 -310.794406) (xy 71.111065 -310.800338)
			(xy 71.158336 -310.81403) (xy 71.202798 -310.835128) (xy 71.243301 -310.863084) (xy 71.278794 -310.897176)
			(xy 71.308359 -310.93652) (xy 71.33123 -310.980097) (xy 71.346814 -311.026778) (xy 71.354709 -311.075355)
			(xy 71.355204 -311.099962) (xy 71.354709 -311.124569) (xy 71.35453 -311.12567) (xy 71.673208 -311.12567)
			(xy 71.673208 -311.074254) (xy 71.681251 -311.023472) (xy 71.697139 -310.974573) (xy 71.720482 -310.928761)
			(xy 71.750703 -310.887165) (xy 71.787059 -310.850809) (xy 71.828655 -310.820588) (xy 71.874467 -310.797245)
			(xy 71.923366 -310.781357) (xy 71.974148 -310.773314) (xy 72.025564 -310.773314) (xy 72.076346 -310.781357)
			(xy 72.125245 -310.797245) (xy 72.171057 -310.820588) (xy 72.212653 -310.850809) (xy 72.249009 -310.887165)
			(xy 72.27923 -310.928761) (xy 72.302573 -310.974573) (xy 72.318461 -311.023472) (xy 72.326504 -311.074254)
			(xy 72.327008 -311.099962) (xy 72.644012 -311.099962) (xy 72.647972 -311.050908) (xy 72.659749 -311.003124)
			(xy 72.67904 -310.957848) (xy 72.705343 -310.916252) (xy 72.737978 -310.879415) (xy 72.776099 -310.84829)
			(xy 72.81872 -310.823683) (xy 72.864736 -310.806231) (xy 72.912955 -310.796387) (xy 72.96213 -310.794406)
			(xy 73.010985 -310.800338) (xy 73.058256 -310.81403) (xy 73.102718 -310.835128) (xy 73.143221 -310.863084)
			(xy 73.178714 -310.897176) (xy 73.208279 -310.93652) (xy 73.23115 -310.980097) (xy 73.246734 -311.026778)
			(xy 73.254629 -311.075355) (xy 73.255124 -311.099962) (xy 73.254629 -311.124569) (xy 73.25445 -311.12567)
			(xy 73.573128 -311.12567) (xy 73.573128 -311.074254) (xy 73.581171 -311.023472) (xy 73.597059 -310.974573)
			(xy 73.620402 -310.928761) (xy 73.650623 -310.887165) (xy 73.686979 -310.850809) (xy 73.728575 -310.820588)
			(xy 73.774387 -310.797245) (xy 73.823286 -310.781357) (xy 73.874068 -310.773314) (xy 73.925484 -310.773314)
			(xy 73.976266 -310.781357) (xy 74.025165 -310.797245) (xy 74.070977 -310.820588) (xy 74.112573 -310.850809)
			(xy 74.148929 -310.887165) (xy 74.17915 -310.928761) (xy 74.202493 -310.974573) (xy 74.218381 -311.023472)
			(xy 74.226424 -311.074254) (xy 74.226928 -311.099962) (xy 74.544186 -311.099962) (xy 74.548146 -311.050908)
			(xy 74.559923 -311.003124) (xy 74.579214 -310.957848) (xy 74.605517 -310.916252) (xy 74.638152 -310.879415)
			(xy 74.676273 -310.84829) (xy 74.718894 -310.823683) (xy 74.76491 -310.806231) (xy 74.813129 -310.796387)
			(xy 74.862304 -310.794406) (xy 74.911159 -310.800338) (xy 74.95843 -310.81403) (xy 75.002892 -310.835128)
			(xy 75.043395 -310.863084) (xy 75.078888 -310.897176) (xy 75.108453 -310.93652) (xy 75.131324 -310.980097)
			(xy 75.146908 -311.026778) (xy 75.154803 -311.075355) (xy 75.155298 -311.099962) (xy 75.154803 -311.124569)
			(xy 75.154624 -311.12567) (xy 75.473302 -311.12567) (xy 75.473302 -311.074254) (xy 75.481345 -311.023472)
			(xy 75.497233 -310.974573) (xy 75.520576 -310.928761) (xy 75.550797 -310.887165) (xy 75.587153 -310.850809)
			(xy 75.628749 -310.820588) (xy 75.674561 -310.797245) (xy 75.72346 -310.781357) (xy 75.774242 -310.773314)
			(xy 75.825658 -310.773314) (xy 75.87644 -310.781357) (xy 75.925339 -310.797245) (xy 75.971151 -310.820588)
			(xy 76.012747 -310.850809) (xy 76.049103 -310.887165) (xy 76.079324 -310.928761) (xy 76.102667 -310.974573)
			(xy 76.118555 -311.023472) (xy 76.126598 -311.074254) (xy 76.127102 -311.099962) (xy 76.444106 -311.099962)
			(xy 76.448066 -311.050908) (xy 76.459843 -311.003124) (xy 76.479134 -310.957848) (xy 76.505437 -310.916252)
			(xy 76.538072 -310.879415) (xy 76.576193 -310.84829) (xy 76.618814 -310.823683) (xy 76.66483 -310.806231)
			(xy 76.713049 -310.796387) (xy 76.762224 -310.794406) (xy 76.811079 -310.800338) (xy 76.85835 -310.81403)
			(xy 76.902812 -310.835128) (xy 76.943315 -310.863084) (xy 76.978808 -310.897176) (xy 77.008373 -310.93652)
			(xy 77.031244 -310.980097) (xy 77.046828 -311.026778) (xy 77.054723 -311.075355) (xy 77.055218 -311.099962)
			(xy 77.054723 -311.124569) (xy 77.054544 -311.12567) (xy 77.373222 -311.12567) (xy 77.373222 -311.074254)
			(xy 77.381265 -311.023472) (xy 77.397153 -310.974573) (xy 77.420496 -310.928761) (xy 77.450717 -310.887165)
			(xy 77.487073 -310.850809) (xy 77.528669 -310.820588) (xy 77.574481 -310.797245) (xy 77.62338 -310.781357)
			(xy 77.674162 -310.773314) (xy 77.725578 -310.773314) (xy 77.77636 -310.781357) (xy 77.825259 -310.797245)
			(xy 77.871071 -310.820588) (xy 77.912667 -310.850809) (xy 77.949023 -310.887165) (xy 77.979244 -310.928761)
			(xy 78.002587 -310.974573) (xy 78.018475 -311.023472) (xy 78.026518 -311.074254) (xy 78.027022 -311.099962)
			(xy 78.344026 -311.099962) (xy 78.347986 -311.050908) (xy 78.359763 -311.003124) (xy 78.379054 -310.957848)
			(xy 78.405357 -310.916252) (xy 78.437992 -310.879415) (xy 78.476113 -310.84829) (xy 78.518734 -310.823683)
			(xy 78.56475 -310.806231) (xy 78.612969 -310.796387) (xy 78.662144 -310.794406) (xy 78.710999 -310.800338)
			(xy 78.75827 -310.81403) (xy 78.802732 -310.835128) (xy 78.843235 -310.863084) (xy 78.878728 -310.897176)
			(xy 78.908293 -310.93652) (xy 78.931164 -310.980097) (xy 78.946748 -311.026778) (xy 78.954643 -311.075355)
			(xy 78.955138 -311.099962) (xy 78.954643 -311.124569) (xy 78.954464 -311.12567) (xy 79.273142 -311.12567)
			(xy 79.273142 -311.074254) (xy 79.281185 -311.023472) (xy 79.297073 -310.974573) (xy 79.320416 -310.928761)
			(xy 79.350637 -310.887165) (xy 79.386993 -310.850809) (xy 79.428589 -310.820588) (xy 79.474401 -310.797245)
			(xy 79.5233 -310.781357) (xy 79.574082 -310.773314) (xy 79.625498 -310.773314) (xy 79.67628 -310.781357)
			(xy 79.725179 -310.797245) (xy 79.770991 -310.820588) (xy 79.812587 -310.850809) (xy 79.848943 -310.887165)
			(xy 79.879164 -310.928761) (xy 79.902507 -310.974573) (xy 79.918395 -311.023472) (xy 79.926438 -311.074254)
			(xy 79.926942 -311.099962) (xy 80.243946 -311.099962) (xy 80.247906 -311.050908) (xy 80.259683 -311.003124)
			(xy 80.278974 -310.957848) (xy 80.305277 -310.916252) (xy 80.337912 -310.879415) (xy 80.376033 -310.84829)
			(xy 80.418654 -310.823683) (xy 80.46467 -310.806231) (xy 80.512889 -310.796387) (xy 80.562064 -310.794406)
			(xy 80.610919 -310.800338) (xy 80.65819 -310.81403) (xy 80.702652 -310.835128) (xy 80.743155 -310.863084)
			(xy 80.778648 -310.897176) (xy 80.808213 -310.93652) (xy 80.831084 -310.980097) (xy 80.846668 -311.026778)
			(xy 80.854563 -311.075355) (xy 80.855058 -311.099962) (xy 81.19416 -311.099962) (xy 81.19812 -311.050908)
			(xy 81.209897 -311.003124) (xy 81.229188 -310.957848) (xy 81.255491 -310.916252) (xy 81.288126 -310.879415)
			(xy 81.326247 -310.84829) (xy 81.368868 -310.823683) (xy 81.414884 -310.806231) (xy 81.463103 -310.796387)
			(xy 81.512278 -310.794406) (xy 81.561133 -310.800338) (xy 81.608404 -310.81403) (xy 81.652866 -310.835128)
			(xy 81.693369 -310.863084) (xy 81.728862 -310.897176) (xy 81.758427 -310.93652) (xy 81.781298 -310.980097)
			(xy 81.796882 -311.026778) (xy 81.804777 -311.075355) (xy 81.805272 -311.099962) (xy 82.14412 -311.099962)
			(xy 82.14808 -311.050908) (xy 82.159857 -311.003124) (xy 82.179148 -310.957848) (xy 82.205451 -310.916252)
			(xy 82.238086 -310.879415) (xy 82.276207 -310.84829) (xy 82.318828 -310.823683) (xy 82.364844 -310.806231)
			(xy 82.413063 -310.796387) (xy 82.462238 -310.794406) (xy 82.511093 -310.800338) (xy 82.558364 -310.81403)
			(xy 82.602826 -310.835128) (xy 82.643329 -310.863084) (xy 82.678822 -310.897176) (xy 82.708387 -310.93652)
			(xy 82.731258 -310.980097) (xy 82.746842 -311.026778) (xy 82.754737 -311.075355) (xy 82.755232 -311.099962)
			(xy 82.754737 -311.124569) (xy 82.746842 -311.173146) (xy 82.731258 -311.219827) (xy 82.708387 -311.263404)
			(xy 82.678822 -311.302748) (xy 82.643329 -311.33684) (xy 82.602826 -311.364796) (xy 82.568916 -311.380887)
			(xy 90.566604 -311.380887) (xy 90.574356 -311.326928) (xy 90.589708 -311.274622) (xy 90.612348 -311.225033)
			(xy 90.641815 -311.17917) (xy 90.677508 -311.137968) (xy 90.718703 -311.102265) (xy 90.764559 -311.072788)
			(xy 90.814143 -311.050137) (xy 90.866446 -311.034774) (xy 90.920404 -311.02701) (xy 90.974917 -311.027004)
			(xy 91.028875 -311.034757) (xy 91.081182 -311.050109) (xy 91.130771 -311.07275) (xy 91.176633 -311.102217)
			(xy 91.217835 -311.137911) (xy 91.253537 -311.179106) (xy 91.283014 -311.224962) (xy 91.305664 -311.274547)
			(xy 91.321027 -311.32685) (xy 91.32879 -311.380808) (xy 91.329256 -311.408064) (xy 91.329059 -311.425112)
			(xy 91.326005 -311.459072) (xy 91.32316 -311.475882) (xy 91.320874 -311.488328) (xy 91.32824 -311.51195)
			(xy 91.405202 -311.588912) (xy 91.428824 -311.596278) (xy 91.44127 -311.593992) (xy 91.458141 -311.591124)
			(xy 91.49223 -311.58807) (xy 91.509342 -311.587896) (xy 91.536594 -311.588339) (xy 91.590544 -311.596101)
			(xy 91.64284 -311.611462) (xy 91.692417 -311.634108) (xy 91.738268 -311.663579) (xy 91.779458 -311.699275)
			(xy 91.815149 -311.740469) (xy 91.844614 -311.786323) (xy 91.867254 -311.835903) (xy 91.882609 -311.888201)
			(xy 91.890365 -311.942151) (xy 91.89085 -311.969404) (xy 91.889834 -311.99836) (xy 91.888818 -312.009536)
			(xy 91.896692 -312.030364) (xy 91.967558 -312.100722) (xy 91.988386 -312.108088) (xy 91.999816 -312.107072)
			(xy 92.032328 -312.105802) (xy 92.059577 -312.106308) (xy 92.113519 -312.114068) (xy 92.165807 -312.129425)
			(xy 92.215378 -312.152067) (xy 92.261223 -312.181533) (xy 92.302407 -312.217224) (xy 92.338093 -312.258412)
			(xy 92.367554 -312.30426) (xy 92.39019 -312.353833) (xy 92.405541 -312.406124) (xy 92.413295 -312.460067)
			(xy 92.413293 -312.514564) (xy 92.405535 -312.568506) (xy 92.39018 -312.620795) (xy 92.367539 -312.670367)
			(xy 92.338074 -312.716212) (xy 92.302385 -312.757398) (xy 92.261198 -312.793085) (xy 92.215351 -312.822548)
			(xy 92.165779 -312.845186) (xy 92.113489 -312.860539) (xy 92.059546 -312.868294) (xy 92.005049 -312.868294)
			(xy 91.951106 -312.860538) (xy 91.898816 -312.845184) (xy 91.849244 -312.822545) (xy 91.803398 -312.793082)
			(xy 91.762211 -312.757394) (xy 91.726523 -312.716208) (xy 91.697058 -312.670363) (xy 91.674419 -312.62079)
			(xy 91.659064 -312.568501) (xy 91.651307 -312.514559) (xy 91.65082 -312.48731) (xy 91.651836 -312.458354)
			(xy 91.652852 -312.447178) (xy 91.644978 -312.42635) (xy 91.574112 -312.355992) (xy 91.553284 -312.348626)
			(xy 91.541854 -312.349642) (xy 91.509342 -312.350912) (xy 91.48209 -312.350406) (xy 91.428141 -312.342654)
			(xy 91.375844 -312.327304) (xy 91.326265 -312.304667) (xy 91.280412 -312.275203) (xy 91.239218 -312.239514)
			(xy 91.203524 -312.198325) (xy 91.174055 -312.152476) (xy 91.151412 -312.102899) (xy 91.136055 -312.050604)
			(xy 91.128298 -311.996656) (xy 91.127834 -311.969404) (xy 91.12804 -311.952356) (xy 91.131088 -311.918397)
			(xy 91.13393 -311.901586) (xy 91.136216 -311.88914) (xy 91.12885 -311.865518) (xy 91.051888 -311.788556)
			(xy 91.028266 -311.78119) (xy 91.01582 -311.783476) (xy 90.998949 -311.786345) (xy 90.964861 -311.789398)
			(xy 90.947748 -311.789572) (xy 90.920491 -311.789196) (xy 90.866532 -311.781445) (xy 90.814226 -311.766094)
			(xy 90.764636 -311.743454) (xy 90.718773 -311.713988) (xy 90.677571 -311.678294) (xy 90.641867 -311.637101)
			(xy 90.61239 -311.591245) (xy 90.589739 -311.541661) (xy 90.574374 -311.489358) (xy 90.56661 -311.4354)
			(xy 90.566604 -311.380887) (xy 82.568916 -311.380887) (xy 82.558364 -311.385894) (xy 82.511093 -311.399586)
			(xy 82.462238 -311.405518) (xy 82.413063 -311.403537) (xy 82.364844 -311.393693) (xy 82.318828 -311.376241)
			(xy 82.276207 -311.351634) (xy 82.238086 -311.320509) (xy 82.205451 -311.283672) (xy 82.179148 -311.242076)
			(xy 82.159857 -311.1968) (xy 82.14808 -311.149016) (xy 82.14412 -311.099962) (xy 81.805272 -311.099962)
			(xy 81.804777 -311.124569) (xy 81.796882 -311.173146) (xy 81.781298 -311.219827) (xy 81.758427 -311.263404)
			(xy 81.728862 -311.302748) (xy 81.693369 -311.33684) (xy 81.652866 -311.364796) (xy 81.608404 -311.385894)
			(xy 81.561133 -311.399586) (xy 81.512278 -311.405518) (xy 81.463103 -311.403537) (xy 81.414884 -311.393693)
			(xy 81.368868 -311.376241) (xy 81.326247 -311.351634) (xy 81.288126 -311.320509) (xy 81.255491 -311.283672)
			(xy 81.229188 -311.242076) (xy 81.209897 -311.1968) (xy 81.19812 -311.149016) (xy 81.19416 -311.099962)
			(xy 80.855058 -311.099962) (xy 80.854563 -311.124569) (xy 80.846668 -311.173146) (xy 80.831084 -311.219827)
			(xy 80.808213 -311.263404) (xy 80.778648 -311.302748) (xy 80.743155 -311.33684) (xy 80.702652 -311.364796)
			(xy 80.65819 -311.385894) (xy 80.610919 -311.399586) (xy 80.562064 -311.405518) (xy 80.512889 -311.403537)
			(xy 80.46467 -311.393693) (xy 80.418654 -311.376241) (xy 80.376033 -311.351634) (xy 80.337912 -311.320509)
			(xy 80.305277 -311.283672) (xy 80.278974 -311.242076) (xy 80.259683 -311.1968) (xy 80.247906 -311.149016)
			(xy 80.243946 -311.099962) (xy 79.926942 -311.099962) (xy 79.926438 -311.12567) (xy 79.918395 -311.176452)
			(xy 79.902507 -311.225351) (xy 79.879164 -311.271163) (xy 79.848943 -311.312759) (xy 79.812587 -311.349115)
			(xy 79.770991 -311.379336) (xy 79.725179 -311.402679) (xy 79.67628 -311.418567) (xy 79.625498 -311.42661)
			(xy 79.574082 -311.42661) (xy 79.5233 -311.418567) (xy 79.474401 -311.402679) (xy 79.428589 -311.379336)
			(xy 79.386993 -311.349115) (xy 79.350637 -311.312759) (xy 79.320416 -311.271163) (xy 79.297073 -311.225351)
			(xy 79.281185 -311.176452) (xy 79.273142 -311.12567) (xy 78.954464 -311.12567) (xy 78.946748 -311.173146)
			(xy 78.931164 -311.219827) (xy 78.908293 -311.263404) (xy 78.878728 -311.302748) (xy 78.843235 -311.33684)
			(xy 78.802732 -311.364796) (xy 78.75827 -311.385894) (xy 78.710999 -311.399586) (xy 78.662144 -311.405518)
			(xy 78.612969 -311.403537) (xy 78.56475 -311.393693) (xy 78.518734 -311.376241) (xy 78.476113 -311.351634)
			(xy 78.437992 -311.320509) (xy 78.405357 -311.283672) (xy 78.379054 -311.242076) (xy 78.359763 -311.1968)
			(xy 78.347986 -311.149016) (xy 78.344026 -311.099962) (xy 78.027022 -311.099962) (xy 78.026518 -311.12567)
			(xy 78.018475 -311.176452) (xy 78.002587 -311.225351) (xy 77.979244 -311.271163) (xy 77.949023 -311.312759)
			(xy 77.912667 -311.349115) (xy 77.871071 -311.379336) (xy 77.825259 -311.402679) (xy 77.77636 -311.418567)
			(xy 77.725578 -311.42661) (xy 77.674162 -311.42661) (xy 77.62338 -311.418567) (xy 77.574481 -311.402679)
			(xy 77.528669 -311.379336) (xy 77.487073 -311.349115) (xy 77.450717 -311.312759) (xy 77.420496 -311.271163)
			(xy 77.397153 -311.225351) (xy 77.381265 -311.176452) (xy 77.373222 -311.12567) (xy 77.054544 -311.12567)
			(xy 77.046828 -311.173146) (xy 77.031244 -311.219827) (xy 77.008373 -311.263404) (xy 76.978808 -311.302748)
			(xy 76.943315 -311.33684) (xy 76.902812 -311.364796) (xy 76.85835 -311.385894) (xy 76.811079 -311.399586)
			(xy 76.762224 -311.405518) (xy 76.713049 -311.403537) (xy 76.66483 -311.393693) (xy 76.618814 -311.376241)
			(xy 76.576193 -311.351634) (xy 76.538072 -311.320509) (xy 76.505437 -311.283672) (xy 76.479134 -311.242076)
			(xy 76.459843 -311.1968) (xy 76.448066 -311.149016) (xy 76.444106 -311.099962) (xy 76.127102 -311.099962)
			(xy 76.126598 -311.12567) (xy 76.118555 -311.176452) (xy 76.102667 -311.225351) (xy 76.079324 -311.271163)
			(xy 76.049103 -311.312759) (xy 76.012747 -311.349115) (xy 75.971151 -311.379336) (xy 75.925339 -311.402679)
			(xy 75.87644 -311.418567) (xy 75.825658 -311.42661) (xy 75.774242 -311.42661) (xy 75.72346 -311.418567)
			(xy 75.674561 -311.402679) (xy 75.628749 -311.379336) (xy 75.587153 -311.349115) (xy 75.550797 -311.312759)
			(xy 75.520576 -311.271163) (xy 75.497233 -311.225351) (xy 75.481345 -311.176452) (xy 75.473302 -311.12567)
			(xy 75.154624 -311.12567) (xy 75.146908 -311.173146) (xy 75.131324 -311.219827) (xy 75.108453 -311.263404)
			(xy 75.078888 -311.302748) (xy 75.043395 -311.33684) (xy 75.002892 -311.364796) (xy 74.95843 -311.385894)
			(xy 74.911159 -311.399586) (xy 74.862304 -311.405518) (xy 74.813129 -311.403537) (xy 74.76491 -311.393693)
			(xy 74.718894 -311.376241) (xy 74.676273 -311.351634) (xy 74.638152 -311.320509) (xy 74.605517 -311.283672)
			(xy 74.579214 -311.242076) (xy 74.559923 -311.1968) (xy 74.548146 -311.149016) (xy 74.544186 -311.099962)
			(xy 74.226928 -311.099962) (xy 74.226424 -311.12567) (xy 74.218381 -311.176452) (xy 74.202493 -311.225351)
			(xy 74.17915 -311.271163) (xy 74.148929 -311.312759) (xy 74.112573 -311.349115) (xy 74.070977 -311.379336)
			(xy 74.025165 -311.402679) (xy 73.976266 -311.418567) (xy 73.925484 -311.42661) (xy 73.874068 -311.42661)
			(xy 73.823286 -311.418567) (xy 73.774387 -311.402679) (xy 73.728575 -311.379336) (xy 73.686979 -311.349115)
			(xy 73.650623 -311.312759) (xy 73.620402 -311.271163) (xy 73.597059 -311.225351) (xy 73.581171 -311.176452)
			(xy 73.573128 -311.12567) (xy 73.25445 -311.12567) (xy 73.246734 -311.173146) (xy 73.23115 -311.219827)
			(xy 73.208279 -311.263404) (xy 73.178714 -311.302748) (xy 73.143221 -311.33684) (xy 73.102718 -311.364796)
			(xy 73.058256 -311.385894) (xy 73.010985 -311.399586) (xy 72.96213 -311.405518) (xy 72.912955 -311.403537)
			(xy 72.864736 -311.393693) (xy 72.81872 -311.376241) (xy 72.776099 -311.351634) (xy 72.737978 -311.320509)
			(xy 72.705343 -311.283672) (xy 72.67904 -311.242076) (xy 72.659749 -311.1968) (xy 72.647972 -311.149016)
			(xy 72.644012 -311.099962) (xy 72.327008 -311.099962) (xy 72.326504 -311.12567) (xy 72.318461 -311.176452)
			(xy 72.302573 -311.225351) (xy 72.27923 -311.271163) (xy 72.249009 -311.312759) (xy 72.212653 -311.349115)
			(xy 72.171057 -311.379336) (xy 72.125245 -311.402679) (xy 72.076346 -311.418567) (xy 72.025564 -311.42661)
			(xy 71.974148 -311.42661) (xy 71.923366 -311.418567) (xy 71.874467 -311.402679) (xy 71.828655 -311.379336)
			(xy 71.787059 -311.349115) (xy 71.750703 -311.312759) (xy 71.720482 -311.271163) (xy 71.697139 -311.225351)
			(xy 71.681251 -311.176452) (xy 71.673208 -311.12567) (xy 71.35453 -311.12567) (xy 71.346814 -311.173146)
			(xy 71.33123 -311.219827) (xy 71.308359 -311.263404) (xy 71.278794 -311.302748) (xy 71.243301 -311.33684)
			(xy 71.202798 -311.364796) (xy 71.158336 -311.385894) (xy 71.111065 -311.399586) (xy 71.06221 -311.405518)
			(xy 71.013035 -311.403537) (xy 70.964816 -311.393693) (xy 70.9188 -311.376241) (xy 70.876179 -311.351634)
			(xy 70.838058 -311.320509) (xy 70.805423 -311.283672) (xy 70.77912 -311.242076) (xy 70.759829 -311.1968)
			(xy 70.748052 -311.149016) (xy 70.744092 -311.099962) (xy 70.427088 -311.099962) (xy 70.426584 -311.12567)
			(xy 70.418541 -311.176452) (xy 70.402653 -311.225351) (xy 70.37931 -311.271163) (xy 70.349089 -311.312759)
			(xy 70.312733 -311.349115) (xy 70.271137 -311.379336) (xy 70.225325 -311.402679) (xy 70.176426 -311.418567)
			(xy 70.125644 -311.42661) (xy 70.074228 -311.42661) (xy 70.023446 -311.418567) (xy 69.974547 -311.402679)
			(xy 69.928735 -311.379336) (xy 69.887139 -311.349115) (xy 69.850783 -311.312759) (xy 69.820562 -311.271163)
			(xy 69.797219 -311.225351) (xy 69.781331 -311.176452) (xy 69.773288 -311.12567) (xy 69.45461 -311.12567)
			(xy 69.446894 -311.173146) (xy 69.43131 -311.219827) (xy 69.408439 -311.263404) (xy 69.378874 -311.302748)
			(xy 69.343381 -311.33684) (xy 69.302878 -311.364796) (xy 69.258416 -311.385894) (xy 69.211145 -311.399586)
			(xy 69.16229 -311.405518) (xy 69.113115 -311.403537) (xy 69.064896 -311.393693) (xy 69.01888 -311.376241)
			(xy 68.976259 -311.351634) (xy 68.938138 -311.320509) (xy 68.905503 -311.283672) (xy 68.8792 -311.242076)
			(xy 68.859909 -311.1968) (xy 68.848132 -311.149016) (xy 68.844172 -311.099962) (xy 68.526914 -311.099962)
			(xy 68.52641 -311.12567) (xy 68.518367 -311.176452) (xy 68.502479 -311.225351) (xy 68.479136 -311.271163)
			(xy 68.448915 -311.312759) (xy 68.412559 -311.349115) (xy 68.370963 -311.379336) (xy 68.325151 -311.402679)
			(xy 68.276252 -311.418567) (xy 68.22547 -311.42661) (xy 68.174054 -311.42661) (xy 68.123272 -311.418567)
			(xy 68.074373 -311.402679) (xy 68.028561 -311.379336) (xy 67.986965 -311.349115) (xy 67.950609 -311.312759)
			(xy 67.920388 -311.271163) (xy 67.897045 -311.225351) (xy 67.881157 -311.176452) (xy 67.873114 -311.12567)
			(xy 67.554436 -311.12567) (xy 67.54672 -311.173146) (xy 67.531136 -311.219827) (xy 67.508265 -311.263404)
			(xy 67.4787 -311.302748) (xy 67.443207 -311.33684) (xy 67.402704 -311.364796) (xy 67.358242 -311.385894)
			(xy 67.310971 -311.399586) (xy 67.262116 -311.405518) (xy 67.212941 -311.403537) (xy 67.164722 -311.393693)
			(xy 67.118706 -311.376241) (xy 67.076085 -311.351634) (xy 67.037964 -311.320509) (xy 67.005329 -311.283672)
			(xy 66.979026 -311.242076) (xy 66.959735 -311.1968) (xy 66.947958 -311.149016) (xy 66.943998 -311.099962)
			(xy 66.626994 -311.099962) (xy 66.62649 -311.12567) (xy 66.618447 -311.176452) (xy 66.602559 -311.225351)
			(xy 66.579216 -311.271163) (xy 66.548995 -311.312759) (xy 66.512639 -311.349115) (xy 66.471043 -311.379336)
			(xy 66.425231 -311.402679) (xy 66.376332 -311.418567) (xy 66.32555 -311.42661) (xy 66.274134 -311.42661)
			(xy 66.223352 -311.418567) (xy 66.174453 -311.402679) (xy 66.128641 -311.379336) (xy 66.087045 -311.349115)
			(xy 66.050689 -311.312759) (xy 66.020468 -311.271163) (xy 65.997125 -311.225351) (xy 65.981237 -311.176452)
			(xy 65.973194 -311.12567) (xy 65.654516 -311.12567) (xy 65.6468 -311.173146) (xy 65.631216 -311.219827)
			(xy 65.608345 -311.263404) (xy 65.57878 -311.302748) (xy 65.543287 -311.33684) (xy 65.502784 -311.364796)
			(xy 65.458322 -311.385894) (xy 65.411051 -311.399586) (xy 65.362196 -311.405518) (xy 65.313021 -311.403537)
			(xy 65.264802 -311.393693) (xy 65.218786 -311.376241) (xy 65.176165 -311.351634) (xy 65.138044 -311.320509)
			(xy 65.105409 -311.283672) (xy 65.079106 -311.242076) (xy 65.059815 -311.1968) (xy 65.048038 -311.149016)
			(xy 65.044078 -311.099962) (xy 64.727074 -311.099962) (xy 64.72657 -311.12567) (xy 64.718527 -311.176452)
			(xy 64.702639 -311.225351) (xy 64.679296 -311.271163) (xy 64.649075 -311.312759) (xy 64.612719 -311.349115)
			(xy 64.571123 -311.379336) (xy 64.525311 -311.402679) (xy 64.476412 -311.418567) (xy 64.42563 -311.42661)
			(xy 64.374214 -311.42661) (xy 64.323432 -311.418567) (xy 64.274533 -311.402679) (xy 64.228721 -311.379336)
			(xy 64.187125 -311.349115) (xy 64.150769 -311.312759) (xy 64.120548 -311.271163) (xy 64.097205 -311.225351)
			(xy 64.081317 -311.176452) (xy 64.073274 -311.12567) (xy 63.754596 -311.12567) (xy 63.74688 -311.173146)
			(xy 63.731296 -311.219827) (xy 63.708425 -311.263404) (xy 63.67886 -311.302748) (xy 63.643367 -311.33684)
			(xy 63.602864 -311.364796) (xy 63.558402 -311.385894) (xy 63.511131 -311.399586) (xy 63.462276 -311.405518)
			(xy 63.413101 -311.403537) (xy 63.364882 -311.393693) (xy 63.318866 -311.376241) (xy 63.276245 -311.351634)
			(xy 63.238124 -311.320509) (xy 63.205489 -311.283672) (xy 63.179186 -311.242076) (xy 63.159895 -311.1968)
			(xy 63.148118 -311.149016) (xy 63.144158 -311.099962) (xy 62.8269 -311.099962) (xy 62.826396 -311.12567)
			(xy 62.818353 -311.176452) (xy 62.802465 -311.225351) (xy 62.779122 -311.271163) (xy 62.748901 -311.312759)
			(xy 62.712545 -311.349115) (xy 62.670949 -311.379336) (xy 62.625137 -311.402679) (xy 62.576238 -311.418567)
			(xy 62.525456 -311.42661) (xy 62.47404 -311.42661) (xy 62.423258 -311.418567) (xy 62.374359 -311.402679)
			(xy 62.328547 -311.379336) (xy 62.286951 -311.349115) (xy 62.250595 -311.312759) (xy 62.220374 -311.271163)
			(xy 62.197031 -311.225351) (xy 62.181143 -311.176452) (xy 62.1731 -311.12567) (xy 61.854422 -311.12567)
			(xy 61.846706 -311.173146) (xy 61.831122 -311.219827) (xy 61.808251 -311.263404) (xy 61.778686 -311.302748)
			(xy 61.743193 -311.33684) (xy 61.70269 -311.364796) (xy 61.658228 -311.385894) (xy 61.610957 -311.399586)
			(xy 61.562102 -311.405518) (xy 61.512927 -311.403537) (xy 61.464708 -311.393693) (xy 61.418692 -311.376241)
			(xy 61.376071 -311.351634) (xy 61.33795 -311.320509) (xy 61.305315 -311.283672) (xy 61.279012 -311.242076)
			(xy 61.259721 -311.1968) (xy 61.247944 -311.149016) (xy 61.243984 -311.099962) (xy 60.92698 -311.099962)
			(xy 60.926476 -311.12567) (xy 60.918433 -311.176452) (xy 60.902545 -311.225351) (xy 60.879202 -311.271163)
			(xy 60.848981 -311.312759) (xy 60.812625 -311.349115) (xy 60.771029 -311.379336) (xy 60.725217 -311.402679)
			(xy 60.676318 -311.418567) (xy 60.625536 -311.42661) (xy 60.57412 -311.42661) (xy 60.523338 -311.418567)
			(xy 60.474439 -311.402679) (xy 60.428627 -311.379336) (xy 60.387031 -311.349115) (xy 60.350675 -311.312759)
			(xy 60.320454 -311.271163) (xy 60.297111 -311.225351) (xy 60.281223 -311.176452) (xy 60.27318 -311.12567)
			(xy 59.954502 -311.12567) (xy 59.946786 -311.173146) (xy 59.931202 -311.219827) (xy 59.908331 -311.263404)
			(xy 59.878766 -311.302748) (xy 59.843273 -311.33684) (xy 59.80277 -311.364796) (xy 59.758308 -311.385894)
			(xy 59.711037 -311.399586) (xy 59.662182 -311.405518) (xy 59.613007 -311.403537) (xy 59.564788 -311.393693)
			(xy 59.518772 -311.376241) (xy 59.476151 -311.351634) (xy 59.43803 -311.320509) (xy 59.405395 -311.283672)
			(xy 59.379092 -311.242076) (xy 59.359801 -311.1968) (xy 59.348024 -311.149016) (xy 59.344064 -311.099962)
			(xy 59.02706 -311.099962) (xy 59.026556 -311.12567) (xy 59.018513 -311.176452) (xy 59.002625 -311.225351)
			(xy 58.979282 -311.271163) (xy 58.949061 -311.312759) (xy 58.912705 -311.349115) (xy 58.871109 -311.379336)
			(xy 58.825297 -311.402679) (xy 58.776398 -311.418567) (xy 58.725616 -311.42661) (xy 58.6742 -311.42661)
			(xy 58.623418 -311.418567) (xy 58.574519 -311.402679) (xy 58.528707 -311.379336) (xy 58.487111 -311.349115)
			(xy 58.450755 -311.312759) (xy 58.420534 -311.271163) (xy 58.397191 -311.225351) (xy 58.381303 -311.176452)
			(xy 58.37326 -311.12567) (xy 58.054723 -311.12567) (xy 58.054714 -311.126119) (xy 58.045794 -311.177666)
			(xy 58.028225 -311.226942) (xy 58.002521 -311.272505) (xy 57.969432 -311.313025) (xy 57.929925 -311.347317)
			(xy 57.885155 -311.37438) (xy 57.83643 -311.393422) (xy 57.810908 -311.399174) (xy 57.80011 -311.401973)
			(xy 57.782214 -311.415249) (xy 57.77158 -311.434829) (xy 57.770268 -311.44591) (xy 57.768345 -311.476054)
			(xy 57.761229 -311.536041) (xy 57.756044 -311.565798) (xy 57.755318 -311.570341) (xy 57.755326 -311.579541)
			(xy 57.756044 -311.584086) (xy 57.761229 -311.613843) (xy 57.768345 -311.67383) (xy 57.770268 -311.703974)
			(xy 57.771496 -311.71508) (xy 57.782128 -311.734701) (xy 57.800078 -311.747962) (xy 57.810908 -311.75071)
			(xy 57.835968 -311.756357) (xy 57.883874 -311.774891) (xy 57.928005 -311.801177) (xy 57.967117 -311.834475)
			(xy 58.000108 -311.873846) (xy 58.026048 -311.918181) (xy 58.044207 -311.966231) (xy 58.054073 -312.016641)
			(xy 58.055256 -312.042302) (xy 58.055889 -312.052437) (xy 58.064114 -312.070984) (xy 58.078907 -312.08487)
			(xy 58.088276 -312.088784) (xy 58.122722 -312.101919) (xy 58.189721 -312.132689) (xy 58.222134 -312.150252)
			(xy 58.234072 -312.15711) (xy 58.26125 -312.156602) (xy 58.36031 -312.096404) (xy 58.373264 -312.072528)
			(xy 58.37301 -312.058812) (xy 58.372756 -312.049922) (xy 58.373258 -312.024234) (xy 58.381291 -311.973489)
			(xy 58.397162 -311.924625) (xy 58.420481 -311.878845) (xy 58.450673 -311.837277) (xy 58.486996 -311.800942)
			(xy 58.528555 -311.770736) (xy 58.574327 -311.747402) (xy 58.623186 -311.731515) (xy 58.673928 -311.723466)
			(xy 58.725304 -311.723453) (xy 58.776051 -311.731476) (xy 58.824917 -311.747338) (xy 58.870702 -311.770648)
			(xy 58.912276 -311.800833) (xy 58.948618 -311.837149) (xy 58.978832 -311.878702) (xy 59.002174 -311.92447)
			(xy 59.01807 -311.973325) (xy 59.026129 -312.024066) (xy 59.026141 -312.049922) (xy 59.344064 -312.049922)
			(xy 59.348024 -312.000868) (xy 59.359801 -311.953084) (xy 59.379092 -311.907808) (xy 59.405395 -311.866212)
			(xy 59.43803 -311.829375) (xy 59.476151 -311.79825) (xy 59.518772 -311.773643) (xy 59.564788 -311.756191)
			(xy 59.613007 -311.746347) (xy 59.662182 -311.744366) (xy 59.711037 -311.750298) (xy 59.758308 -311.76399)
			(xy 59.80277 -311.785088) (xy 59.843273 -311.813044) (xy 59.878766 -311.847136) (xy 59.908331 -311.88648)
			(xy 59.931202 -311.930057) (xy 59.946786 -311.976738) (xy 59.954681 -312.025315) (xy 59.955176 -312.049922)
			(xy 59.954681 -312.074529) (xy 59.954502 -312.07563) (xy 60.27318 -312.07563) (xy 60.27318 -312.024214)
			(xy 60.281223 -311.973432) (xy 60.297111 -311.924533) (xy 60.320454 -311.878721) (xy 60.350675 -311.837125)
			(xy 60.387031 -311.800769) (xy 60.428627 -311.770548) (xy 60.474439 -311.747205) (xy 60.523338 -311.731317)
			(xy 60.57412 -311.723274) (xy 60.625536 -311.723274) (xy 60.676318 -311.731317) (xy 60.725217 -311.747205)
			(xy 60.771029 -311.770548) (xy 60.812625 -311.800769) (xy 60.848981 -311.837125) (xy 60.879202 -311.878721)
			(xy 60.902545 -311.924533) (xy 60.918433 -311.973432) (xy 60.926476 -312.024214) (xy 60.92698 -312.049922)
			(xy 61.243984 -312.049922) (xy 61.247944 -312.000868) (xy 61.259721 -311.953084) (xy 61.279012 -311.907808)
			(xy 61.305315 -311.866212) (xy 61.33795 -311.829375) (xy 61.376071 -311.79825) (xy 61.418692 -311.773643)
			(xy 61.464708 -311.756191) (xy 61.512927 -311.746347) (xy 61.562102 -311.744366) (xy 61.610957 -311.750298)
			(xy 61.658228 -311.76399) (xy 61.70269 -311.785088) (xy 61.743193 -311.813044) (xy 61.778686 -311.847136)
			(xy 61.808251 -311.88648) (xy 61.831122 -311.930057) (xy 61.846706 -311.976738) (xy 61.854601 -312.025315)
			(xy 61.855096 -312.049922) (xy 61.854601 -312.074529) (xy 61.854422 -312.07563) (xy 62.1731 -312.07563)
			(xy 62.1731 -312.024214) (xy 62.181143 -311.973432) (xy 62.197031 -311.924533) (xy 62.220374 -311.878721)
			(xy 62.250595 -311.837125) (xy 62.286951 -311.800769) (xy 62.328547 -311.770548) (xy 62.374359 -311.747205)
			(xy 62.423258 -311.731317) (xy 62.47404 -311.723274) (xy 62.525456 -311.723274) (xy 62.576238 -311.731317)
			(xy 62.625137 -311.747205) (xy 62.670949 -311.770548) (xy 62.712545 -311.800769) (xy 62.748901 -311.837125)
			(xy 62.779122 -311.878721) (xy 62.802465 -311.924533) (xy 62.818353 -311.973432) (xy 62.826396 -312.024214)
			(xy 62.8269 -312.049922) (xy 63.144158 -312.049922) (xy 63.148118 -312.000868) (xy 63.159895 -311.953084)
			(xy 63.179186 -311.907808) (xy 63.205489 -311.866212) (xy 63.238124 -311.829375) (xy 63.276245 -311.79825)
			(xy 63.318866 -311.773643) (xy 63.364882 -311.756191) (xy 63.413101 -311.746347) (xy 63.462276 -311.744366)
			(xy 63.511131 -311.750298) (xy 63.558402 -311.76399) (xy 63.602864 -311.785088) (xy 63.643367 -311.813044)
			(xy 63.67886 -311.847136) (xy 63.708425 -311.88648) (xy 63.731296 -311.930057) (xy 63.74688 -311.976738)
			(xy 63.754775 -312.025315) (xy 63.75527 -312.049922) (xy 63.754775 -312.074529) (xy 63.754596 -312.07563)
			(xy 64.073274 -312.07563) (xy 64.073274 -312.024214) (xy 64.081317 -311.973432) (xy 64.097205 -311.924533)
			(xy 64.120548 -311.878721) (xy 64.150769 -311.837125) (xy 64.187125 -311.800769) (xy 64.228721 -311.770548)
			(xy 64.274533 -311.747205) (xy 64.323432 -311.731317) (xy 64.374214 -311.723274) (xy 64.42563 -311.723274)
			(xy 64.476412 -311.731317) (xy 64.525311 -311.747205) (xy 64.571123 -311.770548) (xy 64.612719 -311.800769)
			(xy 64.649075 -311.837125) (xy 64.679296 -311.878721) (xy 64.702639 -311.924533) (xy 64.718527 -311.973432)
			(xy 64.72657 -312.024214) (xy 64.727074 -312.049922) (xy 65.044078 -312.049922) (xy 65.048038 -312.000868)
			(xy 65.059815 -311.953084) (xy 65.079106 -311.907808) (xy 65.105409 -311.866212) (xy 65.138044 -311.829375)
			(xy 65.176165 -311.79825) (xy 65.218786 -311.773643) (xy 65.264802 -311.756191) (xy 65.313021 -311.746347)
			(xy 65.362196 -311.744366) (xy 65.411051 -311.750298) (xy 65.458322 -311.76399) (xy 65.502784 -311.785088)
			(xy 65.543287 -311.813044) (xy 65.57878 -311.847136) (xy 65.608345 -311.88648) (xy 65.631216 -311.930057)
			(xy 65.6468 -311.976738) (xy 65.654695 -312.025315) (xy 65.65519 -312.049922) (xy 65.654695 -312.074529)
			(xy 65.654516 -312.07563) (xy 65.973194 -312.07563) (xy 65.973194 -312.024214) (xy 65.981237 -311.973432)
			(xy 65.997125 -311.924533) (xy 66.020468 -311.878721) (xy 66.050689 -311.837125) (xy 66.087045 -311.800769)
			(xy 66.128641 -311.770548) (xy 66.174453 -311.747205) (xy 66.223352 -311.731317) (xy 66.274134 -311.723274)
			(xy 66.32555 -311.723274) (xy 66.376332 -311.731317) (xy 66.425231 -311.747205) (xy 66.471043 -311.770548)
			(xy 66.512639 -311.800769) (xy 66.548995 -311.837125) (xy 66.579216 -311.878721) (xy 66.602559 -311.924533)
			(xy 66.618447 -311.973432) (xy 66.62649 -312.024214) (xy 66.626994 -312.049922) (xy 66.943998 -312.049922)
			(xy 66.947958 -312.000868) (xy 66.959735 -311.953084) (xy 66.979026 -311.907808) (xy 67.005329 -311.866212)
			(xy 67.037964 -311.829375) (xy 67.076085 -311.79825) (xy 67.118706 -311.773643) (xy 67.164722 -311.756191)
			(xy 67.212941 -311.746347) (xy 67.262116 -311.744366) (xy 67.310971 -311.750298) (xy 67.358242 -311.76399)
			(xy 67.402704 -311.785088) (xy 67.443207 -311.813044) (xy 67.4787 -311.847136) (xy 67.508265 -311.88648)
			(xy 67.531136 -311.930057) (xy 67.54672 -311.976738) (xy 67.554615 -312.025315) (xy 67.55511 -312.049922)
			(xy 67.554615 -312.074529) (xy 67.554436 -312.07563) (xy 67.873114 -312.07563) (xy 67.873114 -312.024214)
			(xy 67.881157 -311.973432) (xy 67.897045 -311.924533) (xy 67.920388 -311.878721) (xy 67.950609 -311.837125)
			(xy 67.986965 -311.800769) (xy 68.028561 -311.770548) (xy 68.074373 -311.747205) (xy 68.123272 -311.731317)
			(xy 68.174054 -311.723274) (xy 68.22547 -311.723274) (xy 68.276252 -311.731317) (xy 68.325151 -311.747205)
			(xy 68.370963 -311.770548) (xy 68.412559 -311.800769) (xy 68.448915 -311.837125) (xy 68.479136 -311.878721)
			(xy 68.502479 -311.924533) (xy 68.518367 -311.973432) (xy 68.52641 -312.024214) (xy 68.526914 -312.049922)
			(xy 68.844172 -312.049922) (xy 68.848132 -312.000868) (xy 68.859909 -311.953084) (xy 68.8792 -311.907808)
			(xy 68.905503 -311.866212) (xy 68.938138 -311.829375) (xy 68.976259 -311.79825) (xy 69.01888 -311.773643)
			(xy 69.064896 -311.756191) (xy 69.113115 -311.746347) (xy 69.16229 -311.744366) (xy 69.211145 -311.750298)
			(xy 69.258416 -311.76399) (xy 69.302878 -311.785088) (xy 69.343381 -311.813044) (xy 69.378874 -311.847136)
			(xy 69.408439 -311.88648) (xy 69.43131 -311.930057) (xy 69.446894 -311.976738) (xy 69.454789 -312.025315)
			(xy 69.455284 -312.049922) (xy 69.454789 -312.074529) (xy 69.45461 -312.07563) (xy 69.773288 -312.07563)
			(xy 69.773288 -312.024214) (xy 69.781331 -311.973432) (xy 69.797219 -311.924533) (xy 69.820562 -311.878721)
			(xy 69.850783 -311.837125) (xy 69.887139 -311.800769) (xy 69.928735 -311.770548) (xy 69.974547 -311.747205)
			(xy 70.023446 -311.731317) (xy 70.074228 -311.723274) (xy 70.125644 -311.723274) (xy 70.176426 -311.731317)
			(xy 70.225325 -311.747205) (xy 70.271137 -311.770548) (xy 70.312733 -311.800769) (xy 70.349089 -311.837125)
			(xy 70.37931 -311.878721) (xy 70.402653 -311.924533) (xy 70.418541 -311.973432) (xy 70.426584 -312.024214)
			(xy 70.427088 -312.049922) (xy 70.744092 -312.049922) (xy 70.748052 -312.000868) (xy 70.759829 -311.953084)
			(xy 70.77912 -311.907808) (xy 70.805423 -311.866212) (xy 70.838058 -311.829375) (xy 70.876179 -311.79825)
			(xy 70.9188 -311.773643) (xy 70.964816 -311.756191) (xy 71.013035 -311.746347) (xy 71.06221 -311.744366)
			(xy 71.111065 -311.750298) (xy 71.158336 -311.76399) (xy 71.202798 -311.785088) (xy 71.243301 -311.813044)
			(xy 71.278794 -311.847136) (xy 71.308359 -311.88648) (xy 71.33123 -311.930057) (xy 71.346814 -311.976738)
			(xy 71.354709 -312.025315) (xy 71.355204 -312.049922) (xy 71.354709 -312.074529) (xy 71.35453 -312.07563)
			(xy 71.673208 -312.07563) (xy 71.673208 -312.024214) (xy 71.681251 -311.973432) (xy 71.697139 -311.924533)
			(xy 71.720482 -311.878721) (xy 71.750703 -311.837125) (xy 71.787059 -311.800769) (xy 71.828655 -311.770548)
			(xy 71.874467 -311.747205) (xy 71.923366 -311.731317) (xy 71.974148 -311.723274) (xy 72.025564 -311.723274)
			(xy 72.076346 -311.731317) (xy 72.125245 -311.747205) (xy 72.171057 -311.770548) (xy 72.212653 -311.800769)
			(xy 72.249009 -311.837125) (xy 72.27923 -311.878721) (xy 72.302573 -311.924533) (xy 72.318461 -311.973432)
			(xy 72.326504 -312.024214) (xy 72.327008 -312.049922) (xy 72.644012 -312.049922) (xy 72.647972 -312.000868)
			(xy 72.659749 -311.953084) (xy 72.67904 -311.907808) (xy 72.705343 -311.866212) (xy 72.737978 -311.829375)
			(xy 72.776099 -311.79825) (xy 72.81872 -311.773643) (xy 72.864736 -311.756191) (xy 72.912955 -311.746347)
			(xy 72.96213 -311.744366) (xy 73.010985 -311.750298) (xy 73.058256 -311.76399) (xy 73.102718 -311.785088)
			(xy 73.143221 -311.813044) (xy 73.178714 -311.847136) (xy 73.208279 -311.88648) (xy 73.23115 -311.930057)
			(xy 73.246734 -311.976738) (xy 73.254629 -312.025315) (xy 73.255124 -312.049922) (xy 73.254629 -312.074529)
			(xy 73.25445 -312.07563) (xy 73.573128 -312.07563) (xy 73.573128 -312.024214) (xy 73.581171 -311.973432)
			(xy 73.597059 -311.924533) (xy 73.620402 -311.878721) (xy 73.650623 -311.837125) (xy 73.686979 -311.800769)
			(xy 73.728575 -311.770548) (xy 73.774387 -311.747205) (xy 73.823286 -311.731317) (xy 73.874068 -311.723274)
			(xy 73.925484 -311.723274) (xy 73.976266 -311.731317) (xy 74.025165 -311.747205) (xy 74.070977 -311.770548)
			(xy 74.112573 -311.800769) (xy 74.148929 -311.837125) (xy 74.17915 -311.878721) (xy 74.202493 -311.924533)
			(xy 74.218381 -311.973432) (xy 74.226424 -312.024214) (xy 74.226928 -312.049922) (xy 74.544186 -312.049922)
			(xy 74.548146 -312.000868) (xy 74.559923 -311.953084) (xy 74.579214 -311.907808) (xy 74.605517 -311.866212)
			(xy 74.638152 -311.829375) (xy 74.676273 -311.79825) (xy 74.718894 -311.773643) (xy 74.76491 -311.756191)
			(xy 74.813129 -311.746347) (xy 74.862304 -311.744366) (xy 74.911159 -311.750298) (xy 74.95843 -311.76399)
			(xy 75.002892 -311.785088) (xy 75.043395 -311.813044) (xy 75.078888 -311.847136) (xy 75.108453 -311.88648)
			(xy 75.131324 -311.930057) (xy 75.146908 -311.976738) (xy 75.154803 -312.025315) (xy 75.155298 -312.049922)
			(xy 75.154803 -312.074529) (xy 75.154624 -312.07563) (xy 75.473302 -312.07563) (xy 75.473302 -312.024214)
			(xy 75.481345 -311.973432) (xy 75.497233 -311.924533) (xy 75.520576 -311.878721) (xy 75.550797 -311.837125)
			(xy 75.587153 -311.800769) (xy 75.628749 -311.770548) (xy 75.674561 -311.747205) (xy 75.72346 -311.731317)
			(xy 75.774242 -311.723274) (xy 75.825658 -311.723274) (xy 75.87644 -311.731317) (xy 75.925339 -311.747205)
			(xy 75.971151 -311.770548) (xy 76.012747 -311.800769) (xy 76.049103 -311.837125) (xy 76.079324 -311.878721)
			(xy 76.102667 -311.924533) (xy 76.118555 -311.973432) (xy 76.126598 -312.024214) (xy 76.127102 -312.049922)
			(xy 76.444106 -312.049922) (xy 76.448066 -312.000868) (xy 76.459843 -311.953084) (xy 76.479134 -311.907808)
			(xy 76.505437 -311.866212) (xy 76.538072 -311.829375) (xy 76.576193 -311.79825) (xy 76.618814 -311.773643)
			(xy 76.66483 -311.756191) (xy 76.713049 -311.746347) (xy 76.762224 -311.744366) (xy 76.811079 -311.750298)
			(xy 76.85835 -311.76399) (xy 76.902812 -311.785088) (xy 76.943315 -311.813044) (xy 76.978808 -311.847136)
			(xy 77.008373 -311.88648) (xy 77.031244 -311.930057) (xy 77.046828 -311.976738) (xy 77.054723 -312.025315)
			(xy 77.055218 -312.049922) (xy 77.054723 -312.074529) (xy 77.054544 -312.07563) (xy 77.373222 -312.07563)
			(xy 77.373222 -312.024214) (xy 77.381265 -311.973432) (xy 77.397153 -311.924533) (xy 77.420496 -311.878721)
			(xy 77.450717 -311.837125) (xy 77.487073 -311.800769) (xy 77.528669 -311.770548) (xy 77.574481 -311.747205)
			(xy 77.62338 -311.731317) (xy 77.674162 -311.723274) (xy 77.725578 -311.723274) (xy 77.77636 -311.731317)
			(xy 77.825259 -311.747205) (xy 77.871071 -311.770548) (xy 77.912667 -311.800769) (xy 77.949023 -311.837125)
			(xy 77.979244 -311.878721) (xy 78.002587 -311.924533) (xy 78.018475 -311.973432) (xy 78.026518 -312.024214)
			(xy 78.027022 -312.049922) (xy 78.344026 -312.049922) (xy 78.347986 -312.000868) (xy 78.359763 -311.953084)
			(xy 78.379054 -311.907808) (xy 78.405357 -311.866212) (xy 78.437992 -311.829375) (xy 78.476113 -311.79825)
			(xy 78.518734 -311.773643) (xy 78.56475 -311.756191) (xy 78.612969 -311.746347) (xy 78.662144 -311.744366)
			(xy 78.710999 -311.750298) (xy 78.75827 -311.76399) (xy 78.802732 -311.785088) (xy 78.843235 -311.813044)
			(xy 78.878728 -311.847136) (xy 78.908293 -311.88648) (xy 78.931164 -311.930057) (xy 78.946748 -311.976738)
			(xy 78.954643 -312.025315) (xy 78.955138 -312.049922) (xy 78.954643 -312.074529) (xy 78.954464 -312.07563)
			(xy 79.273142 -312.07563) (xy 79.273142 -312.024214) (xy 79.281185 -311.973432) (xy 79.297073 -311.924533)
			(xy 79.320416 -311.878721) (xy 79.350637 -311.837125) (xy 79.386993 -311.800769) (xy 79.428589 -311.770548)
			(xy 79.474401 -311.747205) (xy 79.5233 -311.731317) (xy 79.574082 -311.723274) (xy 79.625498 -311.723274)
			(xy 79.67628 -311.731317) (xy 79.725179 -311.747205) (xy 79.770991 -311.770548) (xy 79.812587 -311.800769)
			(xy 79.848943 -311.837125) (xy 79.879164 -311.878721) (xy 79.902507 -311.924533) (xy 79.918395 -311.973432)
			(xy 79.926438 -312.024214) (xy 79.926942 -312.049922) (xy 80.243946 -312.049922) (xy 80.247906 -312.000868)
			(xy 80.259683 -311.953084) (xy 80.278974 -311.907808) (xy 80.305277 -311.866212) (xy 80.337912 -311.829375)
			(xy 80.376033 -311.79825) (xy 80.418654 -311.773643) (xy 80.46467 -311.756191) (xy 80.512889 -311.746347)
			(xy 80.562064 -311.744366) (xy 80.610919 -311.750298) (xy 80.65819 -311.76399) (xy 80.702652 -311.785088)
			(xy 80.743155 -311.813044) (xy 80.778648 -311.847136) (xy 80.808213 -311.88648) (xy 80.831084 -311.930057)
			(xy 80.846668 -311.976738) (xy 80.854563 -312.025315) (xy 80.855058 -312.049922) (xy 80.854563 -312.074529)
			(xy 80.854384 -312.07563) (xy 81.173316 -312.07563) (xy 81.173316 -312.024214) (xy 81.181359 -311.973432)
			(xy 81.197247 -311.924533) (xy 81.22059 -311.878721) (xy 81.250811 -311.837125) (xy 81.287167 -311.800769)
			(xy 81.328763 -311.770548) (xy 81.374575 -311.747205) (xy 81.423474 -311.731317) (xy 81.474256 -311.723274)
			(xy 81.525672 -311.723274) (xy 81.576454 -311.731317) (xy 81.625353 -311.747205) (xy 81.671165 -311.770548)
			(xy 81.712761 -311.800769) (xy 81.749117 -311.837125) (xy 81.779338 -311.878721) (xy 81.802681 -311.924533)
			(xy 81.818569 -311.973432) (xy 81.826612 -312.024214) (xy 81.827116 -312.049922) (xy 81.826612 -312.07563)
			(xy 82.123276 -312.07563) (xy 82.123276 -312.024214) (xy 82.131319 -311.973432) (xy 82.147207 -311.924533)
			(xy 82.17055 -311.878721) (xy 82.200771 -311.837125) (xy 82.237127 -311.800769) (xy 82.278723 -311.770548)
			(xy 82.324535 -311.747205) (xy 82.373434 -311.731317) (xy 82.424216 -311.723274) (xy 82.475632 -311.723274)
			(xy 82.526414 -311.731317) (xy 82.575313 -311.747205) (xy 82.621125 -311.770548) (xy 82.662721 -311.800769)
			(xy 82.699077 -311.837125) (xy 82.729298 -311.878721) (xy 82.752641 -311.924533) (xy 82.768529 -311.973432)
			(xy 82.776572 -312.024214) (xy 82.777076 -312.049922) (xy 83.094334 -312.049922) (xy 83.098294 -312.000868)
			(xy 83.110071 -311.953084) (xy 83.129362 -311.907808) (xy 83.155665 -311.866212) (xy 83.1883 -311.829375)
			(xy 83.226421 -311.79825) (xy 83.269042 -311.773643) (xy 83.315058 -311.756191) (xy 83.363277 -311.746347)
			(xy 83.412452 -311.744366) (xy 83.461307 -311.750298) (xy 83.508578 -311.76399) (xy 83.55304 -311.785088)
			(xy 83.593543 -311.813044) (xy 83.629036 -311.847136) (xy 83.658601 -311.88648) (xy 83.681472 -311.930057)
			(xy 83.697056 -311.976738) (xy 83.704951 -312.025315) (xy 83.705446 -312.049922) (xy 83.704951 -312.074529)
			(xy 83.697056 -312.123106) (xy 83.681472 -312.169787) (xy 83.658601 -312.213364) (xy 83.629036 -312.252708)
			(xy 83.593543 -312.2868) (xy 83.55304 -312.314756) (xy 83.508578 -312.335854) (xy 83.461307 -312.349546)
			(xy 83.412452 -312.355478) (xy 83.363277 -312.353497) (xy 83.315058 -312.343653) (xy 83.269042 -312.326201)
			(xy 83.226421 -312.301594) (xy 83.1883 -312.270469) (xy 83.155665 -312.233632) (xy 83.129362 -312.192036)
			(xy 83.110071 -312.14676) (xy 83.098294 -312.098976) (xy 83.094334 -312.049922) (xy 82.777076 -312.049922)
			(xy 82.776572 -312.07563) (xy 82.768529 -312.126412) (xy 82.752641 -312.175311) (xy 82.729298 -312.221123)
			(xy 82.699077 -312.262719) (xy 82.662721 -312.299075) (xy 82.621125 -312.329296) (xy 82.575313 -312.352639)
			(xy 82.526414 -312.368527) (xy 82.475632 -312.37657) (xy 82.424216 -312.37657) (xy 82.373434 -312.368527)
			(xy 82.324535 -312.352639) (xy 82.278723 -312.329296) (xy 82.237127 -312.299075) (xy 82.200771 -312.262719)
			(xy 82.17055 -312.221123) (xy 82.147207 -312.175311) (xy 82.131319 -312.126412) (xy 82.123276 -312.07563)
			(xy 81.826612 -312.07563) (xy 81.818569 -312.126412) (xy 81.802681 -312.175311) (xy 81.779338 -312.221123)
			(xy 81.749117 -312.262719) (xy 81.712761 -312.299075) (xy 81.671165 -312.329296) (xy 81.625353 -312.352639)
			(xy 81.576454 -312.368527) (xy 81.525672 -312.37657) (xy 81.474256 -312.37657) (xy 81.423474 -312.368527)
			(xy 81.374575 -312.352639) (xy 81.328763 -312.329296) (xy 81.287167 -312.299075) (xy 81.250811 -312.262719)
			(xy 81.22059 -312.221123) (xy 81.197247 -312.175311) (xy 81.181359 -312.126412) (xy 81.173316 -312.07563)
			(xy 80.854384 -312.07563) (xy 80.846668 -312.123106) (xy 80.831084 -312.169787) (xy 80.808213 -312.213364)
			(xy 80.778648 -312.252708) (xy 80.743155 -312.2868) (xy 80.702652 -312.314756) (xy 80.65819 -312.335854)
			(xy 80.610919 -312.349546) (xy 80.562064 -312.355478) (xy 80.512889 -312.353497) (xy 80.46467 -312.343653)
			(xy 80.418654 -312.326201) (xy 80.376033 -312.301594) (xy 80.337912 -312.270469) (xy 80.305277 -312.233632)
			(xy 80.278974 -312.192036) (xy 80.259683 -312.14676) (xy 80.247906 -312.098976) (xy 80.243946 -312.049922)
			(xy 79.926942 -312.049922) (xy 79.926438 -312.07563) (xy 79.918395 -312.126412) (xy 79.902507 -312.175311)
			(xy 79.879164 -312.221123) (xy 79.848943 -312.262719) (xy 79.812587 -312.299075) (xy 79.770991 -312.329296)
			(xy 79.725179 -312.352639) (xy 79.67628 -312.368527) (xy 79.625498 -312.37657) (xy 79.574082 -312.37657)
			(xy 79.5233 -312.368527) (xy 79.474401 -312.352639) (xy 79.428589 -312.329296) (xy 79.386993 -312.299075)
			(xy 79.350637 -312.262719) (xy 79.320416 -312.221123) (xy 79.297073 -312.175311) (xy 79.281185 -312.126412)
			(xy 79.273142 -312.07563) (xy 78.954464 -312.07563) (xy 78.946748 -312.123106) (xy 78.931164 -312.169787)
			(xy 78.908293 -312.213364) (xy 78.878728 -312.252708) (xy 78.843235 -312.2868) (xy 78.802732 -312.314756)
			(xy 78.75827 -312.335854) (xy 78.710999 -312.349546) (xy 78.662144 -312.355478) (xy 78.612969 -312.353497)
			(xy 78.56475 -312.343653) (xy 78.518734 -312.326201) (xy 78.476113 -312.301594) (xy 78.437992 -312.270469)
			(xy 78.405357 -312.233632) (xy 78.379054 -312.192036) (xy 78.359763 -312.14676) (xy 78.347986 -312.098976)
			(xy 78.344026 -312.049922) (xy 78.027022 -312.049922) (xy 78.026518 -312.07563) (xy 78.018475 -312.126412)
			(xy 78.002587 -312.175311) (xy 77.979244 -312.221123) (xy 77.949023 -312.262719) (xy 77.912667 -312.299075)
			(xy 77.871071 -312.329296) (xy 77.825259 -312.352639) (xy 77.77636 -312.368527) (xy 77.725578 -312.37657)
			(xy 77.674162 -312.37657) (xy 77.62338 -312.368527) (xy 77.574481 -312.352639) (xy 77.528669 -312.329296)
			(xy 77.487073 -312.299075) (xy 77.450717 -312.262719) (xy 77.420496 -312.221123) (xy 77.397153 -312.175311)
			(xy 77.381265 -312.126412) (xy 77.373222 -312.07563) (xy 77.054544 -312.07563) (xy 77.046828 -312.123106)
			(xy 77.031244 -312.169787) (xy 77.008373 -312.213364) (xy 76.978808 -312.252708) (xy 76.943315 -312.2868)
			(xy 76.902812 -312.314756) (xy 76.85835 -312.335854) (xy 76.811079 -312.349546) (xy 76.762224 -312.355478)
			(xy 76.713049 -312.353497) (xy 76.66483 -312.343653) (xy 76.618814 -312.326201) (xy 76.576193 -312.301594)
			(xy 76.538072 -312.270469) (xy 76.505437 -312.233632) (xy 76.479134 -312.192036) (xy 76.459843 -312.14676)
			(xy 76.448066 -312.098976) (xy 76.444106 -312.049922) (xy 76.127102 -312.049922) (xy 76.126598 -312.07563)
			(xy 76.118555 -312.126412) (xy 76.102667 -312.175311) (xy 76.079324 -312.221123) (xy 76.049103 -312.262719)
			(xy 76.012747 -312.299075) (xy 75.971151 -312.329296) (xy 75.925339 -312.352639) (xy 75.87644 -312.368527)
			(xy 75.825658 -312.37657) (xy 75.774242 -312.37657) (xy 75.72346 -312.368527) (xy 75.674561 -312.352639)
			(xy 75.628749 -312.329296) (xy 75.587153 -312.299075) (xy 75.550797 -312.262719) (xy 75.520576 -312.221123)
			(xy 75.497233 -312.175311) (xy 75.481345 -312.126412) (xy 75.473302 -312.07563) (xy 75.154624 -312.07563)
			(xy 75.146908 -312.123106) (xy 75.131324 -312.169787) (xy 75.108453 -312.213364) (xy 75.078888 -312.252708)
			(xy 75.043395 -312.2868) (xy 75.002892 -312.314756) (xy 74.95843 -312.335854) (xy 74.911159 -312.349546)
			(xy 74.862304 -312.355478) (xy 74.813129 -312.353497) (xy 74.76491 -312.343653) (xy 74.718894 -312.326201)
			(xy 74.676273 -312.301594) (xy 74.638152 -312.270469) (xy 74.605517 -312.233632) (xy 74.579214 -312.192036)
			(xy 74.559923 -312.14676) (xy 74.548146 -312.098976) (xy 74.544186 -312.049922) (xy 74.226928 -312.049922)
			(xy 74.226424 -312.07563) (xy 74.218381 -312.126412) (xy 74.202493 -312.175311) (xy 74.17915 -312.221123)
			(xy 74.148929 -312.262719) (xy 74.112573 -312.299075) (xy 74.070977 -312.329296) (xy 74.025165 -312.352639)
			(xy 73.976266 -312.368527) (xy 73.925484 -312.37657) (xy 73.874068 -312.37657) (xy 73.823286 -312.368527)
			(xy 73.774387 -312.352639) (xy 73.728575 -312.329296) (xy 73.686979 -312.299075) (xy 73.650623 -312.262719)
			(xy 73.620402 -312.221123) (xy 73.597059 -312.175311) (xy 73.581171 -312.126412) (xy 73.573128 -312.07563)
			(xy 73.25445 -312.07563) (xy 73.246734 -312.123106) (xy 73.23115 -312.169787) (xy 73.208279 -312.213364)
			(xy 73.178714 -312.252708) (xy 73.143221 -312.2868) (xy 73.102718 -312.314756) (xy 73.058256 -312.335854)
			(xy 73.010985 -312.349546) (xy 72.96213 -312.355478) (xy 72.912955 -312.353497) (xy 72.864736 -312.343653)
			(xy 72.81872 -312.326201) (xy 72.776099 -312.301594) (xy 72.737978 -312.270469) (xy 72.705343 -312.233632)
			(xy 72.67904 -312.192036) (xy 72.659749 -312.14676) (xy 72.647972 -312.098976) (xy 72.644012 -312.049922)
			(xy 72.327008 -312.049922) (xy 72.326504 -312.07563) (xy 72.318461 -312.126412) (xy 72.302573 -312.175311)
			(xy 72.27923 -312.221123) (xy 72.249009 -312.262719) (xy 72.212653 -312.299075) (xy 72.171057 -312.329296)
			(xy 72.125245 -312.352639) (xy 72.076346 -312.368527) (xy 72.025564 -312.37657) (xy 71.974148 -312.37657)
			(xy 71.923366 -312.368527) (xy 71.874467 -312.352639) (xy 71.828655 -312.329296) (xy 71.787059 -312.299075)
			(xy 71.750703 -312.262719) (xy 71.720482 -312.221123) (xy 71.697139 -312.175311) (xy 71.681251 -312.126412)
			(xy 71.673208 -312.07563) (xy 71.35453 -312.07563) (xy 71.346814 -312.123106) (xy 71.33123 -312.169787)
			(xy 71.308359 -312.213364) (xy 71.278794 -312.252708) (xy 71.243301 -312.2868) (xy 71.202798 -312.314756)
			(xy 71.158336 -312.335854) (xy 71.111065 -312.349546) (xy 71.06221 -312.355478) (xy 71.013035 -312.353497)
			(xy 70.964816 -312.343653) (xy 70.9188 -312.326201) (xy 70.876179 -312.301594) (xy 70.838058 -312.270469)
			(xy 70.805423 -312.233632) (xy 70.77912 -312.192036) (xy 70.759829 -312.14676) (xy 70.748052 -312.098976)
			(xy 70.744092 -312.049922) (xy 70.427088 -312.049922) (xy 70.426584 -312.07563) (xy 70.418541 -312.126412)
			(xy 70.402653 -312.175311) (xy 70.37931 -312.221123) (xy 70.349089 -312.262719) (xy 70.312733 -312.299075)
			(xy 70.271137 -312.329296) (xy 70.225325 -312.352639) (xy 70.176426 -312.368527) (xy 70.125644 -312.37657)
			(xy 70.074228 -312.37657) (xy 70.023446 -312.368527) (xy 69.974547 -312.352639) (xy 69.928735 -312.329296)
			(xy 69.887139 -312.299075) (xy 69.850783 -312.262719) (xy 69.820562 -312.221123) (xy 69.797219 -312.175311)
			(xy 69.781331 -312.126412) (xy 69.773288 -312.07563) (xy 69.45461 -312.07563) (xy 69.446894 -312.123106)
			(xy 69.43131 -312.169787) (xy 69.408439 -312.213364) (xy 69.378874 -312.252708) (xy 69.343381 -312.2868)
			(xy 69.302878 -312.314756) (xy 69.258416 -312.335854) (xy 69.211145 -312.349546) (xy 69.16229 -312.355478)
			(xy 69.113115 -312.353497) (xy 69.064896 -312.343653) (xy 69.01888 -312.326201) (xy 68.976259 -312.301594)
			(xy 68.938138 -312.270469) (xy 68.905503 -312.233632) (xy 68.8792 -312.192036) (xy 68.859909 -312.14676)
			(xy 68.848132 -312.098976) (xy 68.844172 -312.049922) (xy 68.526914 -312.049922) (xy 68.52641 -312.07563)
			(xy 68.518367 -312.126412) (xy 68.502479 -312.175311) (xy 68.479136 -312.221123) (xy 68.448915 -312.262719)
			(xy 68.412559 -312.299075) (xy 68.370963 -312.329296) (xy 68.325151 -312.352639) (xy 68.276252 -312.368527)
			(xy 68.22547 -312.37657) (xy 68.174054 -312.37657) (xy 68.123272 -312.368527) (xy 68.074373 -312.352639)
			(xy 68.028561 -312.329296) (xy 67.986965 -312.299075) (xy 67.950609 -312.262719) (xy 67.920388 -312.221123)
			(xy 67.897045 -312.175311) (xy 67.881157 -312.126412) (xy 67.873114 -312.07563) (xy 67.554436 -312.07563)
			(xy 67.54672 -312.123106) (xy 67.531136 -312.169787) (xy 67.508265 -312.213364) (xy 67.4787 -312.252708)
			(xy 67.443207 -312.2868) (xy 67.402704 -312.314756) (xy 67.358242 -312.335854) (xy 67.310971 -312.349546)
			(xy 67.262116 -312.355478) (xy 67.212941 -312.353497) (xy 67.164722 -312.343653) (xy 67.118706 -312.326201)
			(xy 67.076085 -312.301594) (xy 67.037964 -312.270469) (xy 67.005329 -312.233632) (xy 66.979026 -312.192036)
			(xy 66.959735 -312.14676) (xy 66.947958 -312.098976) (xy 66.943998 -312.049922) (xy 66.626994 -312.049922)
			(xy 66.62649 -312.07563) (xy 66.618447 -312.126412) (xy 66.602559 -312.175311) (xy 66.579216 -312.221123)
			(xy 66.548995 -312.262719) (xy 66.512639 -312.299075) (xy 66.471043 -312.329296) (xy 66.425231 -312.352639)
			(xy 66.376332 -312.368527) (xy 66.32555 -312.37657) (xy 66.274134 -312.37657) (xy 66.223352 -312.368527)
			(xy 66.174453 -312.352639) (xy 66.128641 -312.329296) (xy 66.087045 -312.299075) (xy 66.050689 -312.262719)
			(xy 66.020468 -312.221123) (xy 65.997125 -312.175311) (xy 65.981237 -312.126412) (xy 65.973194 -312.07563)
			(xy 65.654516 -312.07563) (xy 65.6468 -312.123106) (xy 65.631216 -312.169787) (xy 65.608345 -312.213364)
			(xy 65.57878 -312.252708) (xy 65.543287 -312.2868) (xy 65.502784 -312.314756) (xy 65.458322 -312.335854)
			(xy 65.411051 -312.349546) (xy 65.362196 -312.355478) (xy 65.313021 -312.353497) (xy 65.264802 -312.343653)
			(xy 65.218786 -312.326201) (xy 65.176165 -312.301594) (xy 65.138044 -312.270469) (xy 65.105409 -312.233632)
			(xy 65.079106 -312.192036) (xy 65.059815 -312.14676) (xy 65.048038 -312.098976) (xy 65.044078 -312.049922)
			(xy 64.727074 -312.049922) (xy 64.72657 -312.07563) (xy 64.718527 -312.126412) (xy 64.702639 -312.175311)
			(xy 64.679296 -312.221123) (xy 64.649075 -312.262719) (xy 64.612719 -312.299075) (xy 64.571123 -312.329296)
			(xy 64.525311 -312.352639) (xy 64.476412 -312.368527) (xy 64.42563 -312.37657) (xy 64.374214 -312.37657)
			(xy 64.323432 -312.368527) (xy 64.274533 -312.352639) (xy 64.228721 -312.329296) (xy 64.187125 -312.299075)
			(xy 64.150769 -312.262719) (xy 64.120548 -312.221123) (xy 64.097205 -312.175311) (xy 64.081317 -312.126412)
			(xy 64.073274 -312.07563) (xy 63.754596 -312.07563) (xy 63.74688 -312.123106) (xy 63.731296 -312.169787)
			(xy 63.708425 -312.213364) (xy 63.67886 -312.252708) (xy 63.643367 -312.2868) (xy 63.602864 -312.314756)
			(xy 63.558402 -312.335854) (xy 63.511131 -312.349546) (xy 63.462276 -312.355478) (xy 63.413101 -312.353497)
			(xy 63.364882 -312.343653) (xy 63.318866 -312.326201) (xy 63.276245 -312.301594) (xy 63.238124 -312.270469)
			(xy 63.205489 -312.233632) (xy 63.179186 -312.192036) (xy 63.159895 -312.14676) (xy 63.148118 -312.098976)
			(xy 63.144158 -312.049922) (xy 62.8269 -312.049922) (xy 62.826396 -312.07563) (xy 62.818353 -312.126412)
			(xy 62.802465 -312.175311) (xy 62.779122 -312.221123) (xy 62.748901 -312.262719) (xy 62.712545 -312.299075)
			(xy 62.670949 -312.329296) (xy 62.625137 -312.352639) (xy 62.576238 -312.368527) (xy 62.525456 -312.37657)
			(xy 62.47404 -312.37657) (xy 62.423258 -312.368527) (xy 62.374359 -312.352639) (xy 62.328547 -312.329296)
			(xy 62.286951 -312.299075) (xy 62.250595 -312.262719) (xy 62.220374 -312.221123) (xy 62.197031 -312.175311)
			(xy 62.181143 -312.126412) (xy 62.1731 -312.07563) (xy 61.854422 -312.07563) (xy 61.846706 -312.123106)
			(xy 61.831122 -312.169787) (xy 61.808251 -312.213364) (xy 61.778686 -312.252708) (xy 61.743193 -312.2868)
			(xy 61.70269 -312.314756) (xy 61.658228 -312.335854) (xy 61.610957 -312.349546) (xy 61.562102 -312.355478)
			(xy 61.512927 -312.353497) (xy 61.464708 -312.343653) (xy 61.418692 -312.326201) (xy 61.376071 -312.301594)
			(xy 61.33795 -312.270469) (xy 61.305315 -312.233632) (xy 61.279012 -312.192036) (xy 61.259721 -312.14676)
			(xy 61.247944 -312.098976) (xy 61.243984 -312.049922) (xy 60.92698 -312.049922) (xy 60.926476 -312.07563)
			(xy 60.918433 -312.126412) (xy 60.902545 -312.175311) (xy 60.879202 -312.221123) (xy 60.848981 -312.262719)
			(xy 60.812625 -312.299075) (xy 60.771029 -312.329296) (xy 60.725217 -312.352639) (xy 60.676318 -312.368527)
			(xy 60.625536 -312.37657) (xy 60.57412 -312.37657) (xy 60.523338 -312.368527) (xy 60.474439 -312.352639)
			(xy 60.428627 -312.329296) (xy 60.387031 -312.299075) (xy 60.350675 -312.262719) (xy 60.320454 -312.221123)
			(xy 60.297111 -312.175311) (xy 60.281223 -312.126412) (xy 60.27318 -312.07563) (xy 59.954502 -312.07563)
			(xy 59.946786 -312.123106) (xy 59.931202 -312.169787) (xy 59.908331 -312.213364) (xy 59.878766 -312.252708)
			(xy 59.843273 -312.2868) (xy 59.80277 -312.314756) (xy 59.758308 -312.335854) (xy 59.711037 -312.349546)
			(xy 59.662182 -312.355478) (xy 59.613007 -312.353497) (xy 59.564788 -312.343653) (xy 59.518772 -312.326201)
			(xy 59.476151 -312.301594) (xy 59.43803 -312.270469) (xy 59.405395 -312.233632) (xy 59.379092 -312.192036)
			(xy 59.359801 -312.14676) (xy 59.348024 -312.098976) (xy 59.344064 -312.049922) (xy 59.026141 -312.049922)
			(xy 59.026152 -312.075443) (xy 59.018138 -312.12619) (xy 59.002286 -312.17506) (xy 58.978984 -312.220849)
			(xy 58.948808 -312.262429) (xy 58.912499 -312.298777) (xy 58.870951 -312.328999) (xy 58.825188 -312.35235)
			(xy 58.776335 -312.368256) (xy 58.725596 -312.376324) (xy 58.699908 -312.37682) (xy 58.691018 -312.37682)
			(xy 58.677302 -312.376566) (xy 58.653426 -312.38952) (xy 58.593228 -312.48858) (xy 58.59272 -312.515758)
			(xy 58.599578 -312.527696) (xy 58.617161 -312.560099) (xy 58.647929 -312.627101) (xy 58.661046 -312.661554)
			(xy 58.665019 -312.670886) (xy 58.678907 -312.685644) (xy 58.697409 -312.693914) (xy 58.707528 -312.694574)
			(xy 58.731127 -312.695598) (xy 58.777605 -312.704024) (xy 58.822229 -312.719509) (xy 58.863935 -312.741684)
			(xy 58.901727 -312.77002) (xy 58.934703 -312.803839) (xy 58.962075 -312.842335) (xy 58.983189 -312.884588)
			(xy 58.997542 -312.929589) (xy 59.004791 -312.976264) (xy 59.005216 -312.999882) (xy 59.004682 -313.02559)
			(xy 59.32322 -313.02559) (xy 59.32322 -312.974174) (xy 59.331263 -312.923392) (xy 59.347151 -312.874493)
			(xy 59.370494 -312.828681) (xy 59.400715 -312.787085) (xy 59.437071 -312.750729) (xy 59.478667 -312.720508)
			(xy 59.524479 -312.697165) (xy 59.573378 -312.681277) (xy 59.62416 -312.673234) (xy 59.675576 -312.673234)
			(xy 59.726358 -312.681277) (xy 59.775257 -312.697165) (xy 59.821069 -312.720508) (xy 59.862665 -312.750729)
			(xy 59.899021 -312.787085) (xy 59.929242 -312.828681) (xy 59.952585 -312.874493) (xy 59.968473 -312.923392)
			(xy 59.976516 -312.974174) (xy 59.97702 -312.999882) (xy 60.294024 -312.999882) (xy 60.297984 -312.950828)
			(xy 60.309761 -312.903044) (xy 60.329052 -312.857768) (xy 60.355355 -312.816172) (xy 60.38799 -312.779335)
			(xy 60.426111 -312.74821) (xy 60.468732 -312.723603) (xy 60.514748 -312.706151) (xy 60.562967 -312.696307)
			(xy 60.612142 -312.694326) (xy 60.660997 -312.700258) (xy 60.708268 -312.71395) (xy 60.75273 -312.735048)
			(xy 60.793233 -312.763004) (xy 60.828726 -312.797096) (xy 60.858291 -312.83644) (xy 60.881162 -312.880017)
			(xy 60.896746 -312.926698) (xy 60.904641 -312.975275) (xy 60.905136 -312.999882) (xy 60.904641 -313.024489)
			(xy 60.904462 -313.02559) (xy 61.22314 -313.02559) (xy 61.22314 -312.974174) (xy 61.231183 -312.923392)
			(xy 61.247071 -312.874493) (xy 61.270414 -312.828681) (xy 61.300635 -312.787085) (xy 61.336991 -312.750729)
			(xy 61.378587 -312.720508) (xy 61.424399 -312.697165) (xy 61.473298 -312.681277) (xy 61.52408 -312.673234)
			(xy 61.575496 -312.673234) (xy 61.626278 -312.681277) (xy 61.675177 -312.697165) (xy 61.720989 -312.720508)
			(xy 61.762585 -312.750729) (xy 61.798941 -312.787085) (xy 61.829162 -312.828681) (xy 61.852505 -312.874493)
			(xy 61.868393 -312.923392) (xy 61.876436 -312.974174) (xy 61.87694 -312.999882) (xy 62.193944 -312.999882)
			(xy 62.197904 -312.950828) (xy 62.209681 -312.903044) (xy 62.228972 -312.857768) (xy 62.255275 -312.816172)
			(xy 62.28791 -312.779335) (xy 62.326031 -312.74821) (xy 62.368652 -312.723603) (xy 62.414668 -312.706151)
			(xy 62.462887 -312.696307) (xy 62.512062 -312.694326) (xy 62.560917 -312.700258) (xy 62.608188 -312.71395)
			(xy 62.65265 -312.735048) (xy 62.693153 -312.763004) (xy 62.728646 -312.797096) (xy 62.758211 -312.83644)
			(xy 62.781082 -312.880017) (xy 62.796666 -312.926698) (xy 62.804561 -312.975275) (xy 62.805056 -312.999882)
			(xy 62.804561 -313.024489) (xy 62.804382 -313.02559) (xy 63.123314 -313.02559) (xy 63.123314 -312.974174)
			(xy 63.131357 -312.923392) (xy 63.147245 -312.874493) (xy 63.170588 -312.828681) (xy 63.200809 -312.787085)
			(xy 63.237165 -312.750729) (xy 63.278761 -312.720508) (xy 63.324573 -312.697165) (xy 63.373472 -312.681277)
			(xy 63.424254 -312.673234) (xy 63.47567 -312.673234) (xy 63.526452 -312.681277) (xy 63.575351 -312.697165)
			(xy 63.621163 -312.720508) (xy 63.662759 -312.750729) (xy 63.699115 -312.787085) (xy 63.729336 -312.828681)
			(xy 63.752679 -312.874493) (xy 63.768567 -312.923392) (xy 63.77661 -312.974174) (xy 63.777114 -312.999882)
			(xy 64.094118 -312.999882) (xy 64.098078 -312.950828) (xy 64.109855 -312.903044) (xy 64.129146 -312.857768)
			(xy 64.155449 -312.816172) (xy 64.188084 -312.779335) (xy 64.226205 -312.74821) (xy 64.268826 -312.723603)
			(xy 64.314842 -312.706151) (xy 64.363061 -312.696307) (xy 64.412236 -312.694326) (xy 64.461091 -312.700258)
			(xy 64.508362 -312.71395) (xy 64.552824 -312.735048) (xy 64.593327 -312.763004) (xy 64.62882 -312.797096)
			(xy 64.658385 -312.83644) (xy 64.681256 -312.880017) (xy 64.69684 -312.926698) (xy 64.704735 -312.975275)
			(xy 64.70523 -312.999882) (xy 64.704735 -313.024489) (xy 64.704556 -313.02559) (xy 65.023234 -313.02559)
			(xy 65.023234 -312.974174) (xy 65.031277 -312.923392) (xy 65.047165 -312.874493) (xy 65.070508 -312.828681)
			(xy 65.100729 -312.787085) (xy 65.137085 -312.750729) (xy 65.178681 -312.720508) (xy 65.224493 -312.697165)
			(xy 65.273392 -312.681277) (xy 65.324174 -312.673234) (xy 65.37559 -312.673234) (xy 65.426372 -312.681277)
			(xy 65.475271 -312.697165) (xy 65.521083 -312.720508) (xy 65.562679 -312.750729) (xy 65.599035 -312.787085)
			(xy 65.629256 -312.828681) (xy 65.652599 -312.874493) (xy 65.668487 -312.923392) (xy 65.67653 -312.974174)
			(xy 65.677034 -312.999882) (xy 65.994038 -312.999882) (xy 65.997998 -312.950828) (xy 66.009775 -312.903044)
			(xy 66.029066 -312.857768) (xy 66.055369 -312.816172) (xy 66.088004 -312.779335) (xy 66.126125 -312.74821)
			(xy 66.168746 -312.723603) (xy 66.214762 -312.706151) (xy 66.262981 -312.696307) (xy 66.312156 -312.694326)
			(xy 66.361011 -312.700258) (xy 66.408282 -312.71395) (xy 66.452744 -312.735048) (xy 66.493247 -312.763004)
			(xy 66.52874 -312.797096) (xy 66.558305 -312.83644) (xy 66.581176 -312.880017) (xy 66.59676 -312.926698)
			(xy 66.604655 -312.975275) (xy 66.60515 -312.999882) (xy 66.604655 -313.024489) (xy 66.604476 -313.02559)
			(xy 66.923154 -313.02559) (xy 66.923154 -312.974174) (xy 66.931197 -312.923392) (xy 66.947085 -312.874493)
			(xy 66.970428 -312.828681) (xy 67.000649 -312.787085) (xy 67.037005 -312.750729) (xy 67.078601 -312.720508)
			(xy 67.124413 -312.697165) (xy 67.173312 -312.681277) (xy 67.224094 -312.673234) (xy 67.27551 -312.673234)
			(xy 67.326292 -312.681277) (xy 67.375191 -312.697165) (xy 67.421003 -312.720508) (xy 67.462599 -312.750729)
			(xy 67.498955 -312.787085) (xy 67.529176 -312.828681) (xy 67.552519 -312.874493) (xy 67.568407 -312.923392)
			(xy 67.57645 -312.974174) (xy 67.576954 -312.999882) (xy 67.893958 -312.999882) (xy 67.897918 -312.950828)
			(xy 67.909695 -312.903044) (xy 67.928986 -312.857768) (xy 67.955289 -312.816172) (xy 67.987924 -312.779335)
			(xy 68.026045 -312.74821) (xy 68.068666 -312.723603) (xy 68.114682 -312.706151) (xy 68.162901 -312.696307)
			(xy 68.212076 -312.694326) (xy 68.260931 -312.700258) (xy 68.308202 -312.71395) (xy 68.352664 -312.735048)
			(xy 68.393167 -312.763004) (xy 68.42866 -312.797096) (xy 68.458225 -312.83644) (xy 68.481096 -312.880017)
			(xy 68.49668 -312.926698) (xy 68.504575 -312.975275) (xy 68.50507 -312.999882) (xy 68.504575 -313.024489)
			(xy 68.504396 -313.02559) (xy 68.823328 -313.02559) (xy 68.823328 -312.974174) (xy 68.831371 -312.923392)
			(xy 68.847259 -312.874493) (xy 68.870602 -312.828681) (xy 68.900823 -312.787085) (xy 68.937179 -312.750729)
			(xy 68.978775 -312.720508) (xy 69.024587 -312.697165) (xy 69.073486 -312.681277) (xy 69.124268 -312.673234)
			(xy 69.175684 -312.673234) (xy 69.226466 -312.681277) (xy 69.275365 -312.697165) (xy 69.321177 -312.720508)
			(xy 69.362773 -312.750729) (xy 69.399129 -312.787085) (xy 69.42935 -312.828681) (xy 69.452693 -312.874493)
			(xy 69.468581 -312.923392) (xy 69.476624 -312.974174) (xy 69.477128 -312.999882) (xy 69.794132 -312.999882)
			(xy 69.798092 -312.950828) (xy 69.809869 -312.903044) (xy 69.82916 -312.857768) (xy 69.855463 -312.816172)
			(xy 69.888098 -312.779335) (xy 69.926219 -312.74821) (xy 69.96884 -312.723603) (xy 70.014856 -312.706151)
			(xy 70.063075 -312.696307) (xy 70.11225 -312.694326) (xy 70.161105 -312.700258) (xy 70.208376 -312.71395)
			(xy 70.252838 -312.735048) (xy 70.293341 -312.763004) (xy 70.328834 -312.797096) (xy 70.358399 -312.83644)
			(xy 70.38127 -312.880017) (xy 70.396854 -312.926698) (xy 70.404749 -312.975275) (xy 70.405244 -312.999882)
			(xy 70.404749 -313.024489) (xy 70.40457 -313.02559) (xy 70.723248 -313.02559) (xy 70.723248 -312.974174)
			(xy 70.731291 -312.923392) (xy 70.747179 -312.874493) (xy 70.770522 -312.828681) (xy 70.800743 -312.787085)
			(xy 70.837099 -312.750729) (xy 70.878695 -312.720508) (xy 70.924507 -312.697165) (xy 70.973406 -312.681277)
			(xy 71.024188 -312.673234) (xy 71.075604 -312.673234) (xy 71.126386 -312.681277) (xy 71.175285 -312.697165)
			(xy 71.221097 -312.720508) (xy 71.262693 -312.750729) (xy 71.299049 -312.787085) (xy 71.32927 -312.828681)
			(xy 71.352613 -312.874493) (xy 71.368501 -312.923392) (xy 71.376544 -312.974174) (xy 71.377048 -312.999882)
			(xy 71.694052 -312.999882) (xy 71.698012 -312.950828) (xy 71.709789 -312.903044) (xy 71.72908 -312.857768)
			(xy 71.755383 -312.816172) (xy 71.788018 -312.779335) (xy 71.826139 -312.74821) (xy 71.86876 -312.723603)
			(xy 71.914776 -312.706151) (xy 71.962995 -312.696307) (xy 72.01217 -312.694326) (xy 72.061025 -312.700258)
			(xy 72.108296 -312.71395) (xy 72.152758 -312.735048) (xy 72.193261 -312.763004) (xy 72.228754 -312.797096)
			(xy 72.258319 -312.83644) (xy 72.28119 -312.880017) (xy 72.296774 -312.926698) (xy 72.304669 -312.975275)
			(xy 72.305164 -312.999882) (xy 72.304669 -313.024489) (xy 72.30449 -313.02559) (xy 72.623168 -313.02559)
			(xy 72.623168 -312.974174) (xy 72.631211 -312.923392) (xy 72.647099 -312.874493) (xy 72.670442 -312.828681)
			(xy 72.700663 -312.787085) (xy 72.737019 -312.750729) (xy 72.778615 -312.720508) (xy 72.824427 -312.697165)
			(xy 72.873326 -312.681277) (xy 72.924108 -312.673234) (xy 72.975524 -312.673234) (xy 73.026306 -312.681277)
			(xy 73.075205 -312.697165) (xy 73.121017 -312.720508) (xy 73.162613 -312.750729) (xy 73.198969 -312.787085)
			(xy 73.22919 -312.828681) (xy 73.252533 -312.874493) (xy 73.268421 -312.923392) (xy 73.276464 -312.974174)
			(xy 73.276968 -312.999882) (xy 73.593972 -312.999882) (xy 73.597932 -312.950828) (xy 73.609709 -312.903044)
			(xy 73.629 -312.857768) (xy 73.655303 -312.816172) (xy 73.687938 -312.779335) (xy 73.726059 -312.74821)
			(xy 73.76868 -312.723603) (xy 73.814696 -312.706151) (xy 73.862915 -312.696307) (xy 73.91209 -312.694326)
			(xy 73.960945 -312.700258) (xy 74.008216 -312.71395) (xy 74.052678 -312.735048) (xy 74.093181 -312.763004)
			(xy 74.128674 -312.797096) (xy 74.158239 -312.83644) (xy 74.18111 -312.880017) (xy 74.196694 -312.926698)
			(xy 74.204589 -312.975275) (xy 74.205084 -312.999882) (xy 74.204589 -313.024489) (xy 74.20441 -313.02559)
			(xy 74.523342 -313.02559) (xy 74.523342 -312.974174) (xy 74.531385 -312.923392) (xy 74.547273 -312.874493)
			(xy 74.570616 -312.828681) (xy 74.600837 -312.787085) (xy 74.637193 -312.750729) (xy 74.678789 -312.720508)
			(xy 74.724601 -312.697165) (xy 74.7735 -312.681277) (xy 74.824282 -312.673234) (xy 74.875698 -312.673234)
			(xy 74.92648 -312.681277) (xy 74.975379 -312.697165) (xy 75.021191 -312.720508) (xy 75.062787 -312.750729)
			(xy 75.099143 -312.787085) (xy 75.129364 -312.828681) (xy 75.152707 -312.874493) (xy 75.168595 -312.923392)
			(xy 75.176638 -312.974174) (xy 75.177142 -312.999882) (xy 75.494146 -312.999882) (xy 75.498106 -312.950828)
			(xy 75.509883 -312.903044) (xy 75.529174 -312.857768) (xy 75.555477 -312.816172) (xy 75.588112 -312.779335)
			(xy 75.626233 -312.74821) (xy 75.668854 -312.723603) (xy 75.71487 -312.706151) (xy 75.763089 -312.696307)
			(xy 75.812264 -312.694326) (xy 75.861119 -312.700258) (xy 75.90839 -312.71395) (xy 75.952852 -312.735048)
			(xy 75.993355 -312.763004) (xy 76.028848 -312.797096) (xy 76.058413 -312.83644) (xy 76.081284 -312.880017)
			(xy 76.096868 -312.926698) (xy 76.104763 -312.975275) (xy 76.105258 -312.999882) (xy 76.104763 -313.024489)
			(xy 76.104584 -313.02559) (xy 76.423262 -313.02559) (xy 76.423262 -312.974174) (xy 76.431305 -312.923392)
			(xy 76.447193 -312.874493) (xy 76.470536 -312.828681) (xy 76.500757 -312.787085) (xy 76.537113 -312.750729)
			(xy 76.578709 -312.720508) (xy 76.624521 -312.697165) (xy 76.67342 -312.681277) (xy 76.724202 -312.673234)
			(xy 76.775618 -312.673234) (xy 76.8264 -312.681277) (xy 76.875299 -312.697165) (xy 76.921111 -312.720508)
			(xy 76.962707 -312.750729) (xy 76.999063 -312.787085) (xy 77.029284 -312.828681) (xy 77.052627 -312.874493)
			(xy 77.068515 -312.923392) (xy 77.076558 -312.974174) (xy 77.077062 -312.999882) (xy 77.394066 -312.999882)
			(xy 77.398026 -312.950828) (xy 77.409803 -312.903044) (xy 77.429094 -312.857768) (xy 77.455397 -312.816172)
			(xy 77.488032 -312.779335) (xy 77.526153 -312.74821) (xy 77.568774 -312.723603) (xy 77.61479 -312.706151)
			(xy 77.663009 -312.696307) (xy 77.712184 -312.694326) (xy 77.761039 -312.700258) (xy 77.80831 -312.71395)
			(xy 77.852772 -312.735048) (xy 77.893275 -312.763004) (xy 77.928768 -312.797096) (xy 77.958333 -312.83644)
			(xy 77.981204 -312.880017) (xy 77.996788 -312.926698) (xy 78.004683 -312.975275) (xy 78.005178 -312.999882)
			(xy 78.004683 -313.024489) (xy 78.004504 -313.02559) (xy 78.323182 -313.02559) (xy 78.323182 -312.974174)
			(xy 78.331225 -312.923392) (xy 78.347113 -312.874493) (xy 78.370456 -312.828681) (xy 78.400677 -312.787085)
			(xy 78.437033 -312.750729) (xy 78.478629 -312.720508) (xy 78.524441 -312.697165) (xy 78.57334 -312.681277)
			(xy 78.624122 -312.673234) (xy 78.675538 -312.673234) (xy 78.72632 -312.681277) (xy 78.775219 -312.697165)
			(xy 78.821031 -312.720508) (xy 78.862627 -312.750729) (xy 78.898983 -312.787085) (xy 78.929204 -312.828681)
			(xy 78.952547 -312.874493) (xy 78.968435 -312.923392) (xy 78.976478 -312.974174) (xy 78.976982 -312.999882)
			(xy 79.293986 -312.999882) (xy 79.297946 -312.950828) (xy 79.309723 -312.903044) (xy 79.329014 -312.857768)
			(xy 79.355317 -312.816172) (xy 79.387952 -312.779335) (xy 79.426073 -312.74821) (xy 79.468694 -312.723603)
			(xy 79.51471 -312.706151) (xy 79.562929 -312.696307) (xy 79.612104 -312.694326) (xy 79.660959 -312.700258)
			(xy 79.70823 -312.71395) (xy 79.752692 -312.735048) (xy 79.793195 -312.763004) (xy 79.828688 -312.797096)
			(xy 79.858253 -312.83644) (xy 79.881124 -312.880017) (xy 79.896708 -312.926698) (xy 79.904603 -312.975275)
			(xy 79.905098 -312.999882) (xy 79.904603 -313.024489) (xy 79.904424 -313.02559) (xy 80.223102 -313.02559)
			(xy 80.223102 -312.974174) (xy 80.231145 -312.923392) (xy 80.247033 -312.874493) (xy 80.270376 -312.828681)
			(xy 80.300597 -312.787085) (xy 80.336953 -312.750729) (xy 80.378549 -312.720508) (xy 80.424361 -312.697165)
			(xy 80.47326 -312.681277) (xy 80.524042 -312.673234) (xy 80.575458 -312.673234) (xy 80.62624 -312.681277)
			(xy 80.675139 -312.697165) (xy 80.720951 -312.720508) (xy 80.762547 -312.750729) (xy 80.798903 -312.787085)
			(xy 80.829124 -312.828681) (xy 80.852467 -312.874493) (xy 80.868355 -312.923392) (xy 80.876398 -312.974174)
			(xy 80.876902 -312.999882) (xy 81.19416 -312.999882) (xy 81.19812 -312.950828) (xy 81.209897 -312.903044)
			(xy 81.229188 -312.857768) (xy 81.255491 -312.816172) (xy 81.288126 -312.779335) (xy 81.326247 -312.74821)
			(xy 81.368868 -312.723603) (xy 81.414884 -312.706151) (xy 81.463103 -312.696307) (xy 81.512278 -312.694326)
			(xy 81.561133 -312.700258) (xy 81.608404 -312.71395) (xy 81.652866 -312.735048) (xy 81.693369 -312.763004)
			(xy 81.728862 -312.797096) (xy 81.758427 -312.83644) (xy 81.781298 -312.880017) (xy 81.796882 -312.926698)
			(xy 81.804777 -312.975275) (xy 81.805272 -312.999882) (xy 82.14412 -312.999882) (xy 82.14808 -312.950828)
			(xy 82.159857 -312.903044) (xy 82.179148 -312.857768) (xy 82.205451 -312.816172) (xy 82.238086 -312.779335)
			(xy 82.276207 -312.74821) (xy 82.318828 -312.723603) (xy 82.364844 -312.706151) (xy 82.413063 -312.696307)
			(xy 82.462238 -312.694326) (xy 82.511093 -312.700258) (xy 82.558364 -312.71395) (xy 82.602826 -312.735048)
			(xy 82.643329 -312.763004) (xy 82.678822 -312.797096) (xy 82.708387 -312.83644) (xy 82.731258 -312.880017)
			(xy 82.746842 -312.926698) (xy 82.754737 -312.975275) (xy 82.755232 -312.999882) (xy 82.754737 -313.024489)
			(xy 82.746842 -313.073066) (xy 82.731258 -313.119747) (xy 82.708387 -313.163324) (xy 82.678822 -313.202668)
			(xy 82.643329 -313.23676) (xy 82.602826 -313.264716) (xy 82.558364 -313.285814) (xy 82.511093 -313.299506)
			(xy 82.462238 -313.305438) (xy 82.413063 -313.303457) (xy 82.364844 -313.293613) (xy 82.318828 -313.276161)
			(xy 82.276207 -313.251554) (xy 82.238086 -313.220429) (xy 82.205451 -313.183592) (xy 82.179148 -313.141996)
			(xy 82.159857 -313.09672) (xy 82.14808 -313.048936) (xy 82.14412 -312.999882) (xy 81.805272 -312.999882)
			(xy 81.804777 -313.024489) (xy 81.796882 -313.073066) (xy 81.781298 -313.119747) (xy 81.758427 -313.163324)
			(xy 81.728862 -313.202668) (xy 81.693369 -313.23676) (xy 81.652866 -313.264716) (xy 81.608404 -313.285814)
			(xy 81.561133 -313.299506) (xy 81.512278 -313.305438) (xy 81.463103 -313.303457) (xy 81.414884 -313.293613)
			(xy 81.368868 -313.276161) (xy 81.326247 -313.251554) (xy 81.288126 -313.220429) (xy 81.255491 -313.183592)
			(xy 81.229188 -313.141996) (xy 81.209897 -313.09672) (xy 81.19812 -313.048936) (xy 81.19416 -312.999882)
			(xy 80.876902 -312.999882) (xy 80.876398 -313.02559) (xy 80.868355 -313.076372) (xy 80.852467 -313.125271)
			(xy 80.829124 -313.171083) (xy 80.798903 -313.212679) (xy 80.762547 -313.249035) (xy 80.720951 -313.279256)
			(xy 80.675139 -313.302599) (xy 80.62624 -313.318487) (xy 80.575458 -313.32653) (xy 80.524042 -313.32653)
			(xy 80.47326 -313.318487) (xy 80.424361 -313.302599) (xy 80.378549 -313.279256) (xy 80.336953 -313.249035)
			(xy 80.300597 -313.212679) (xy 80.270376 -313.171083) (xy 80.247033 -313.125271) (xy 80.231145 -313.076372)
			(xy 80.223102 -313.02559) (xy 79.904424 -313.02559) (xy 79.896708 -313.073066) (xy 79.881124 -313.119747)
			(xy 79.858253 -313.163324) (xy 79.828688 -313.202668) (xy 79.793195 -313.23676) (xy 79.752692 -313.264716)
			(xy 79.70823 -313.285814) (xy 79.660959 -313.299506) (xy 79.612104 -313.305438) (xy 79.562929 -313.303457)
			(xy 79.51471 -313.293613) (xy 79.468694 -313.276161) (xy 79.426073 -313.251554) (xy 79.387952 -313.220429)
			(xy 79.355317 -313.183592) (xy 79.329014 -313.141996) (xy 79.309723 -313.09672) (xy 79.297946 -313.048936)
			(xy 79.293986 -312.999882) (xy 78.976982 -312.999882) (xy 78.976478 -313.02559) (xy 78.968435 -313.076372)
			(xy 78.952547 -313.125271) (xy 78.929204 -313.171083) (xy 78.898983 -313.212679) (xy 78.862627 -313.249035)
			(xy 78.821031 -313.279256) (xy 78.775219 -313.302599) (xy 78.72632 -313.318487) (xy 78.675538 -313.32653)
			(xy 78.624122 -313.32653) (xy 78.57334 -313.318487) (xy 78.524441 -313.302599) (xy 78.478629 -313.279256)
			(xy 78.437033 -313.249035) (xy 78.400677 -313.212679) (xy 78.370456 -313.171083) (xy 78.347113 -313.125271)
			(xy 78.331225 -313.076372) (xy 78.323182 -313.02559) (xy 78.004504 -313.02559) (xy 77.996788 -313.073066)
			(xy 77.981204 -313.119747) (xy 77.958333 -313.163324) (xy 77.928768 -313.202668) (xy 77.893275 -313.23676)
			(xy 77.852772 -313.264716) (xy 77.80831 -313.285814) (xy 77.761039 -313.299506) (xy 77.712184 -313.305438)
			(xy 77.663009 -313.303457) (xy 77.61479 -313.293613) (xy 77.568774 -313.276161) (xy 77.526153 -313.251554)
			(xy 77.488032 -313.220429) (xy 77.455397 -313.183592) (xy 77.429094 -313.141996) (xy 77.409803 -313.09672)
			(xy 77.398026 -313.048936) (xy 77.394066 -312.999882) (xy 77.077062 -312.999882) (xy 77.076558 -313.02559)
			(xy 77.068515 -313.076372) (xy 77.052627 -313.125271) (xy 77.029284 -313.171083) (xy 76.999063 -313.212679)
			(xy 76.962707 -313.249035) (xy 76.921111 -313.279256) (xy 76.875299 -313.302599) (xy 76.8264 -313.318487)
			(xy 76.775618 -313.32653) (xy 76.724202 -313.32653) (xy 76.67342 -313.318487) (xy 76.624521 -313.302599)
			(xy 76.578709 -313.279256) (xy 76.537113 -313.249035) (xy 76.500757 -313.212679) (xy 76.470536 -313.171083)
			(xy 76.447193 -313.125271) (xy 76.431305 -313.076372) (xy 76.423262 -313.02559) (xy 76.104584 -313.02559)
			(xy 76.096868 -313.073066) (xy 76.081284 -313.119747) (xy 76.058413 -313.163324) (xy 76.028848 -313.202668)
			(xy 75.993355 -313.23676) (xy 75.952852 -313.264716) (xy 75.90839 -313.285814) (xy 75.861119 -313.299506)
			(xy 75.812264 -313.305438) (xy 75.763089 -313.303457) (xy 75.71487 -313.293613) (xy 75.668854 -313.276161)
			(xy 75.626233 -313.251554) (xy 75.588112 -313.220429) (xy 75.555477 -313.183592) (xy 75.529174 -313.141996)
			(xy 75.509883 -313.09672) (xy 75.498106 -313.048936) (xy 75.494146 -312.999882) (xy 75.177142 -312.999882)
			(xy 75.176638 -313.02559) (xy 75.168595 -313.076372) (xy 75.152707 -313.125271) (xy 75.129364 -313.171083)
			(xy 75.099143 -313.212679) (xy 75.062787 -313.249035) (xy 75.021191 -313.279256) (xy 74.975379 -313.302599)
			(xy 74.92648 -313.318487) (xy 74.875698 -313.32653) (xy 74.824282 -313.32653) (xy 74.7735 -313.318487)
			(xy 74.724601 -313.302599) (xy 74.678789 -313.279256) (xy 74.637193 -313.249035) (xy 74.600837 -313.212679)
			(xy 74.570616 -313.171083) (xy 74.547273 -313.125271) (xy 74.531385 -313.076372) (xy 74.523342 -313.02559)
			(xy 74.20441 -313.02559) (xy 74.196694 -313.073066) (xy 74.18111 -313.119747) (xy 74.158239 -313.163324)
			(xy 74.128674 -313.202668) (xy 74.093181 -313.23676) (xy 74.052678 -313.264716) (xy 74.008216 -313.285814)
			(xy 73.960945 -313.299506) (xy 73.91209 -313.305438) (xy 73.862915 -313.303457) (xy 73.814696 -313.293613)
			(xy 73.76868 -313.276161) (xy 73.726059 -313.251554) (xy 73.687938 -313.220429) (xy 73.655303 -313.183592)
			(xy 73.629 -313.141996) (xy 73.609709 -313.09672) (xy 73.597932 -313.048936) (xy 73.593972 -312.999882)
			(xy 73.276968 -312.999882) (xy 73.276464 -313.02559) (xy 73.268421 -313.076372) (xy 73.252533 -313.125271)
			(xy 73.22919 -313.171083) (xy 73.198969 -313.212679) (xy 73.162613 -313.249035) (xy 73.121017 -313.279256)
			(xy 73.075205 -313.302599) (xy 73.026306 -313.318487) (xy 72.975524 -313.32653) (xy 72.924108 -313.32653)
			(xy 72.873326 -313.318487) (xy 72.824427 -313.302599) (xy 72.778615 -313.279256) (xy 72.737019 -313.249035)
			(xy 72.700663 -313.212679) (xy 72.670442 -313.171083) (xy 72.647099 -313.125271) (xy 72.631211 -313.076372)
			(xy 72.623168 -313.02559) (xy 72.30449 -313.02559) (xy 72.296774 -313.073066) (xy 72.28119 -313.119747)
			(xy 72.258319 -313.163324) (xy 72.228754 -313.202668) (xy 72.193261 -313.23676) (xy 72.152758 -313.264716)
			(xy 72.108296 -313.285814) (xy 72.061025 -313.299506) (xy 72.01217 -313.305438) (xy 71.962995 -313.303457)
			(xy 71.914776 -313.293613) (xy 71.86876 -313.276161) (xy 71.826139 -313.251554) (xy 71.788018 -313.220429)
			(xy 71.755383 -313.183592) (xy 71.72908 -313.141996) (xy 71.709789 -313.09672) (xy 71.698012 -313.048936)
			(xy 71.694052 -312.999882) (xy 71.377048 -312.999882) (xy 71.376544 -313.02559) (xy 71.368501 -313.076372)
			(xy 71.352613 -313.125271) (xy 71.32927 -313.171083) (xy 71.299049 -313.212679) (xy 71.262693 -313.249035)
			(xy 71.221097 -313.279256) (xy 71.175285 -313.302599) (xy 71.126386 -313.318487) (xy 71.075604 -313.32653)
			(xy 71.024188 -313.32653) (xy 70.973406 -313.318487) (xy 70.924507 -313.302599) (xy 70.878695 -313.279256)
			(xy 70.837099 -313.249035) (xy 70.800743 -313.212679) (xy 70.770522 -313.171083) (xy 70.747179 -313.125271)
			(xy 70.731291 -313.076372) (xy 70.723248 -313.02559) (xy 70.40457 -313.02559) (xy 70.396854 -313.073066)
			(xy 70.38127 -313.119747) (xy 70.358399 -313.163324) (xy 70.328834 -313.202668) (xy 70.293341 -313.23676)
			(xy 70.252838 -313.264716) (xy 70.208376 -313.285814) (xy 70.161105 -313.299506) (xy 70.11225 -313.305438)
			(xy 70.063075 -313.303457) (xy 70.014856 -313.293613) (xy 69.96884 -313.276161) (xy 69.926219 -313.251554)
			(xy 69.888098 -313.220429) (xy 69.855463 -313.183592) (xy 69.82916 -313.141996) (xy 69.809869 -313.09672)
			(xy 69.798092 -313.048936) (xy 69.794132 -312.999882) (xy 69.477128 -312.999882) (xy 69.476624 -313.02559)
			(xy 69.468581 -313.076372) (xy 69.452693 -313.125271) (xy 69.42935 -313.171083) (xy 69.399129 -313.212679)
			(xy 69.362773 -313.249035) (xy 69.321177 -313.279256) (xy 69.275365 -313.302599) (xy 69.226466 -313.318487)
			(xy 69.175684 -313.32653) (xy 69.124268 -313.32653) (xy 69.073486 -313.318487) (xy 69.024587 -313.302599)
			(xy 68.978775 -313.279256) (xy 68.937179 -313.249035) (xy 68.900823 -313.212679) (xy 68.870602 -313.171083)
			(xy 68.847259 -313.125271) (xy 68.831371 -313.076372) (xy 68.823328 -313.02559) (xy 68.504396 -313.02559)
			(xy 68.49668 -313.073066) (xy 68.481096 -313.119747) (xy 68.458225 -313.163324) (xy 68.42866 -313.202668)
			(xy 68.393167 -313.23676) (xy 68.352664 -313.264716) (xy 68.308202 -313.285814) (xy 68.260931 -313.299506)
			(xy 68.212076 -313.305438) (xy 68.162901 -313.303457) (xy 68.114682 -313.293613) (xy 68.068666 -313.276161)
			(xy 68.026045 -313.251554) (xy 67.987924 -313.220429) (xy 67.955289 -313.183592) (xy 67.928986 -313.141996)
			(xy 67.909695 -313.09672) (xy 67.897918 -313.048936) (xy 67.893958 -312.999882) (xy 67.576954 -312.999882)
			(xy 67.57645 -313.02559) (xy 67.568407 -313.076372) (xy 67.552519 -313.125271) (xy 67.529176 -313.171083)
			(xy 67.498955 -313.212679) (xy 67.462599 -313.249035) (xy 67.421003 -313.279256) (xy 67.375191 -313.302599)
			(xy 67.326292 -313.318487) (xy 67.27551 -313.32653) (xy 67.224094 -313.32653) (xy 67.173312 -313.318487)
			(xy 67.124413 -313.302599) (xy 67.078601 -313.279256) (xy 67.037005 -313.249035) (xy 67.000649 -313.212679)
			(xy 66.970428 -313.171083) (xy 66.947085 -313.125271) (xy 66.931197 -313.076372) (xy 66.923154 -313.02559)
			(xy 66.604476 -313.02559) (xy 66.59676 -313.073066) (xy 66.581176 -313.119747) (xy 66.558305 -313.163324)
			(xy 66.52874 -313.202668) (xy 66.493247 -313.23676) (xy 66.452744 -313.264716) (xy 66.408282 -313.285814)
			(xy 66.361011 -313.299506) (xy 66.312156 -313.305438) (xy 66.262981 -313.303457) (xy 66.214762 -313.293613)
			(xy 66.168746 -313.276161) (xy 66.126125 -313.251554) (xy 66.088004 -313.220429) (xy 66.055369 -313.183592)
			(xy 66.029066 -313.141996) (xy 66.009775 -313.09672) (xy 65.997998 -313.048936) (xy 65.994038 -312.999882)
			(xy 65.677034 -312.999882) (xy 65.67653 -313.02559) (xy 65.668487 -313.076372) (xy 65.652599 -313.125271)
			(xy 65.629256 -313.171083) (xy 65.599035 -313.212679) (xy 65.562679 -313.249035) (xy 65.521083 -313.279256)
			(xy 65.475271 -313.302599) (xy 65.426372 -313.318487) (xy 65.37559 -313.32653) (xy 65.324174 -313.32653)
			(xy 65.273392 -313.318487) (xy 65.224493 -313.302599) (xy 65.178681 -313.279256) (xy 65.137085 -313.249035)
			(xy 65.100729 -313.212679) (xy 65.070508 -313.171083) (xy 65.047165 -313.125271) (xy 65.031277 -313.076372)
			(xy 65.023234 -313.02559) (xy 64.704556 -313.02559) (xy 64.69684 -313.073066) (xy 64.681256 -313.119747)
			(xy 64.658385 -313.163324) (xy 64.62882 -313.202668) (xy 64.593327 -313.23676) (xy 64.552824 -313.264716)
			(xy 64.508362 -313.285814) (xy 64.461091 -313.299506) (xy 64.412236 -313.305438) (xy 64.363061 -313.303457)
			(xy 64.314842 -313.293613) (xy 64.268826 -313.276161) (xy 64.226205 -313.251554) (xy 64.188084 -313.220429)
			(xy 64.155449 -313.183592) (xy 64.129146 -313.141996) (xy 64.109855 -313.09672) (xy 64.098078 -313.048936)
			(xy 64.094118 -312.999882) (xy 63.777114 -312.999882) (xy 63.77661 -313.02559) (xy 63.768567 -313.076372)
			(xy 63.752679 -313.125271) (xy 63.729336 -313.171083) (xy 63.699115 -313.212679) (xy 63.662759 -313.249035)
			(xy 63.621163 -313.279256) (xy 63.575351 -313.302599) (xy 63.526452 -313.318487) (xy 63.47567 -313.32653)
			(xy 63.424254 -313.32653) (xy 63.373472 -313.318487) (xy 63.324573 -313.302599) (xy 63.278761 -313.279256)
			(xy 63.237165 -313.249035) (xy 63.200809 -313.212679) (xy 63.170588 -313.171083) (xy 63.147245 -313.125271)
			(xy 63.131357 -313.076372) (xy 63.123314 -313.02559) (xy 62.804382 -313.02559) (xy 62.796666 -313.073066)
			(xy 62.781082 -313.119747) (xy 62.758211 -313.163324) (xy 62.728646 -313.202668) (xy 62.693153 -313.23676)
			(xy 62.65265 -313.264716) (xy 62.608188 -313.285814) (xy 62.560917 -313.299506) (xy 62.512062 -313.305438)
			(xy 62.462887 -313.303457) (xy 62.414668 -313.293613) (xy 62.368652 -313.276161) (xy 62.326031 -313.251554)
			(xy 62.28791 -313.220429) (xy 62.255275 -313.183592) (xy 62.228972 -313.141996) (xy 62.209681 -313.09672)
			(xy 62.197904 -313.048936) (xy 62.193944 -312.999882) (xy 61.87694 -312.999882) (xy 61.876436 -313.02559)
			(xy 61.868393 -313.076372) (xy 61.852505 -313.125271) (xy 61.829162 -313.171083) (xy 61.798941 -313.212679)
			(xy 61.762585 -313.249035) (xy 61.720989 -313.279256) (xy 61.675177 -313.302599) (xy 61.626278 -313.318487)
			(xy 61.575496 -313.32653) (xy 61.52408 -313.32653) (xy 61.473298 -313.318487) (xy 61.424399 -313.302599)
			(xy 61.378587 -313.279256) (xy 61.336991 -313.249035) (xy 61.300635 -313.212679) (xy 61.270414 -313.171083)
			(xy 61.247071 -313.125271) (xy 61.231183 -313.076372) (xy 61.22314 -313.02559) (xy 60.904462 -313.02559)
			(xy 60.896746 -313.073066) (xy 60.881162 -313.119747) (xy 60.858291 -313.163324) (xy 60.828726 -313.202668)
			(xy 60.793233 -313.23676) (xy 60.75273 -313.264716) (xy 60.708268 -313.285814) (xy 60.660997 -313.299506)
			(xy 60.612142 -313.305438) (xy 60.562967 -313.303457) (xy 60.514748 -313.293613) (xy 60.468732 -313.276161)
			(xy 60.426111 -313.251554) (xy 60.38799 -313.220429) (xy 60.355355 -313.183592) (xy 60.329052 -313.141996)
			(xy 60.309761 -313.09672) (xy 60.297984 -313.048936) (xy 60.294024 -312.999882) (xy 59.97702 -312.999882)
			(xy 59.976516 -313.02559) (xy 59.968473 -313.076372) (xy 59.952585 -313.125271) (xy 59.929242 -313.171083)
			(xy 59.899021 -313.212679) (xy 59.862665 -313.249035) (xy 59.821069 -313.279256) (xy 59.775257 -313.302599)
			(xy 59.726358 -313.318487) (xy 59.675576 -313.32653) (xy 59.62416 -313.32653) (xy 59.573378 -313.318487)
			(xy 59.524479 -313.302599) (xy 59.478667 -313.279256) (xy 59.437071 -313.249035) (xy 59.400715 -313.212679)
			(xy 59.370494 -313.171083) (xy 59.347151 -313.125271) (xy 59.331263 -313.076372) (xy 59.32322 -313.02559)
			(xy 59.004682 -313.02559) (xy 59.004673 -313.026037) (xy 58.995749 -313.07758) (xy 58.978177 -313.12685)
			(xy 58.95247 -313.172407) (xy 58.91938 -313.212921) (xy 58.879872 -313.247206) (xy 58.835102 -313.274261)
			(xy 58.786379 -313.293296) (xy 58.760868 -313.299094) (xy 58.750053 -313.30188) (xy 58.732116 -313.315144)
			(xy 58.721438 -313.334731) (xy 58.720228 -313.34583) (xy 58.718304 -313.375974) (xy 58.711187 -313.435961)
			(xy 58.706004 -313.465718) (xy 58.70527 -313.470261) (xy 58.705264 -313.479464) (xy 58.706004 -313.484006)
			(xy 58.711188 -313.513763) (xy 58.718303 -313.57375) (xy 58.720228 -313.603894) (xy 58.721461 -313.614993)
			(xy 58.732102 -313.634595) (xy 58.750054 -313.647831) (xy 58.760868 -313.65063) (xy 58.786395 -313.656374)
			(xy 58.835135 -313.675396) (xy 58.879918 -313.702448) (xy 58.919434 -313.736739) (xy 58.952527 -313.777264)
			(xy 58.978226 -313.822837) (xy 58.99578 -313.872124) (xy 59.004675 -313.923682) (xy 59.005216 -313.949842)
			(xy 59.004773 -313.973456) (xy 59.004447 -313.97555) (xy 59.32322 -313.97555) (xy 59.32322 -313.924134)
			(xy 59.331263 -313.873352) (xy 59.347151 -313.824453) (xy 59.370494 -313.778641) (xy 59.400715 -313.737045)
			(xy 59.437071 -313.700689) (xy 59.478667 -313.670468) (xy 59.524479 -313.647125) (xy 59.573378 -313.631237)
			(xy 59.62416 -313.623194) (xy 59.675576 -313.623194) (xy 59.726358 -313.631237) (xy 59.775257 -313.647125)
			(xy 59.821069 -313.670468) (xy 59.862665 -313.700689) (xy 59.899021 -313.737045) (xy 59.929242 -313.778641)
			(xy 59.952585 -313.824453) (xy 59.968473 -313.873352) (xy 59.976516 -313.924134) (xy 59.97702 -313.949842)
			(xy 60.294024 -313.949842) (xy 60.297984 -313.900788) (xy 60.309761 -313.853004) (xy 60.329052 -313.807728)
			(xy 60.355355 -313.766132) (xy 60.38799 -313.729295) (xy 60.426111 -313.69817) (xy 60.468732 -313.673563)
			(xy 60.514748 -313.656111) (xy 60.562967 -313.646267) (xy 60.612142 -313.644286) (xy 60.660997 -313.650218)
			(xy 60.708268 -313.66391) (xy 60.75273 -313.685008) (xy 60.793233 -313.712964) (xy 60.828726 -313.747056)
			(xy 60.858291 -313.7864) (xy 60.881162 -313.829977) (xy 60.896746 -313.876658) (xy 60.904641 -313.925235)
			(xy 60.905136 -313.949842) (xy 60.904641 -313.974449) (xy 60.904462 -313.97555) (xy 61.22314 -313.97555)
			(xy 61.22314 -313.924134) (xy 61.231183 -313.873352) (xy 61.247071 -313.824453) (xy 61.270414 -313.778641)
			(xy 61.300635 -313.737045) (xy 61.336991 -313.700689) (xy 61.378587 -313.670468) (xy 61.424399 -313.647125)
			(xy 61.473298 -313.631237) (xy 61.52408 -313.623194) (xy 61.575496 -313.623194) (xy 61.626278 -313.631237)
			(xy 61.675177 -313.647125) (xy 61.720989 -313.670468) (xy 61.762585 -313.700689) (xy 61.798941 -313.737045)
			(xy 61.829162 -313.778641) (xy 61.852505 -313.824453) (xy 61.868393 -313.873352) (xy 61.876436 -313.924134)
			(xy 61.87694 -313.949842) (xy 62.193944 -313.949842) (xy 62.197904 -313.900788) (xy 62.209681 -313.853004)
			(xy 62.228972 -313.807728) (xy 62.255275 -313.766132) (xy 62.28791 -313.729295) (xy 62.326031 -313.69817)
			(xy 62.368652 -313.673563) (xy 62.414668 -313.656111) (xy 62.462887 -313.646267) (xy 62.512062 -313.644286)
			(xy 62.560917 -313.650218) (xy 62.608188 -313.66391) (xy 62.65265 -313.685008) (xy 62.693153 -313.712964)
			(xy 62.728646 -313.747056) (xy 62.758211 -313.7864) (xy 62.781082 -313.829977) (xy 62.796666 -313.876658)
			(xy 62.804561 -313.925235) (xy 62.805056 -313.949842) (xy 62.804561 -313.974449) (xy 62.804382 -313.97555)
			(xy 63.123314 -313.97555) (xy 63.123314 -313.924134) (xy 63.131357 -313.873352) (xy 63.147245 -313.824453)
			(xy 63.170588 -313.778641) (xy 63.200809 -313.737045) (xy 63.237165 -313.700689) (xy 63.278761 -313.670468)
			(xy 63.324573 -313.647125) (xy 63.373472 -313.631237) (xy 63.424254 -313.623194) (xy 63.47567 -313.623194)
			(xy 63.526452 -313.631237) (xy 63.575351 -313.647125) (xy 63.621163 -313.670468) (xy 63.662759 -313.700689)
			(xy 63.699115 -313.737045) (xy 63.729336 -313.778641) (xy 63.752679 -313.824453) (xy 63.768567 -313.873352)
			(xy 63.77661 -313.924134) (xy 63.777114 -313.949842) (xy 64.094118 -313.949842) (xy 64.098078 -313.900788)
			(xy 64.109855 -313.853004) (xy 64.129146 -313.807728) (xy 64.155449 -313.766132) (xy 64.188084 -313.729295)
			(xy 64.226205 -313.69817) (xy 64.268826 -313.673563) (xy 64.314842 -313.656111) (xy 64.363061 -313.646267)
			(xy 64.412236 -313.644286) (xy 64.461091 -313.650218) (xy 64.508362 -313.66391) (xy 64.552824 -313.685008)
			(xy 64.593327 -313.712964) (xy 64.62882 -313.747056) (xy 64.658385 -313.7864) (xy 64.681256 -313.829977)
			(xy 64.69684 -313.876658) (xy 64.704735 -313.925235) (xy 64.70523 -313.949842) (xy 64.704735 -313.974449)
			(xy 64.704556 -313.97555) (xy 65.023234 -313.97555) (xy 65.023234 -313.924134) (xy 65.031277 -313.873352)
			(xy 65.047165 -313.824453) (xy 65.070508 -313.778641) (xy 65.100729 -313.737045) (xy 65.137085 -313.700689)
			(xy 65.178681 -313.670468) (xy 65.224493 -313.647125) (xy 65.273392 -313.631237) (xy 65.324174 -313.623194)
			(xy 65.37559 -313.623194) (xy 65.426372 -313.631237) (xy 65.475271 -313.647125) (xy 65.521083 -313.670468)
			(xy 65.562679 -313.700689) (xy 65.599035 -313.737045) (xy 65.629256 -313.778641) (xy 65.652599 -313.824453)
			(xy 65.668487 -313.873352) (xy 65.67653 -313.924134) (xy 65.677034 -313.949842) (xy 65.994038 -313.949842)
			(xy 65.997998 -313.900788) (xy 66.009775 -313.853004) (xy 66.029066 -313.807728) (xy 66.055369 -313.766132)
			(xy 66.088004 -313.729295) (xy 66.126125 -313.69817) (xy 66.168746 -313.673563) (xy 66.214762 -313.656111)
			(xy 66.262981 -313.646267) (xy 66.312156 -313.644286) (xy 66.361011 -313.650218) (xy 66.408282 -313.66391)
			(xy 66.452744 -313.685008) (xy 66.493247 -313.712964) (xy 66.52874 -313.747056) (xy 66.558305 -313.7864)
			(xy 66.581176 -313.829977) (xy 66.59676 -313.876658) (xy 66.604655 -313.925235) (xy 66.60515 -313.949842)
			(xy 66.604655 -313.974449) (xy 66.604476 -313.97555) (xy 66.923154 -313.97555) (xy 66.923154 -313.924134)
			(xy 66.931197 -313.873352) (xy 66.947085 -313.824453) (xy 66.970428 -313.778641) (xy 67.000649 -313.737045)
			(xy 67.037005 -313.700689) (xy 67.078601 -313.670468) (xy 67.124413 -313.647125) (xy 67.173312 -313.631237)
			(xy 67.224094 -313.623194) (xy 67.27551 -313.623194) (xy 67.326292 -313.631237) (xy 67.375191 -313.647125)
			(xy 67.421003 -313.670468) (xy 67.462599 -313.700689) (xy 67.498955 -313.737045) (xy 67.529176 -313.778641)
			(xy 67.552519 -313.824453) (xy 67.568407 -313.873352) (xy 67.57645 -313.924134) (xy 67.576954 -313.949842)
			(xy 67.893958 -313.949842) (xy 67.897918 -313.900788) (xy 67.909695 -313.853004) (xy 67.928986 -313.807728)
			(xy 67.955289 -313.766132) (xy 67.987924 -313.729295) (xy 68.026045 -313.69817) (xy 68.068666 -313.673563)
			(xy 68.114682 -313.656111) (xy 68.162901 -313.646267) (xy 68.212076 -313.644286) (xy 68.260931 -313.650218)
			(xy 68.308202 -313.66391) (xy 68.352664 -313.685008) (xy 68.393167 -313.712964) (xy 68.42866 -313.747056)
			(xy 68.458225 -313.7864) (xy 68.481096 -313.829977) (xy 68.49668 -313.876658) (xy 68.504575 -313.925235)
			(xy 68.50507 -313.949842) (xy 68.504575 -313.974449) (xy 68.504396 -313.97555) (xy 68.823328 -313.97555)
			(xy 68.823328 -313.924134) (xy 68.831371 -313.873352) (xy 68.847259 -313.824453) (xy 68.870602 -313.778641)
			(xy 68.900823 -313.737045) (xy 68.937179 -313.700689) (xy 68.978775 -313.670468) (xy 69.024587 -313.647125)
			(xy 69.073486 -313.631237) (xy 69.124268 -313.623194) (xy 69.175684 -313.623194) (xy 69.226466 -313.631237)
			(xy 69.275365 -313.647125) (xy 69.321177 -313.670468) (xy 69.362773 -313.700689) (xy 69.399129 -313.737045)
			(xy 69.42935 -313.778641) (xy 69.452693 -313.824453) (xy 69.468581 -313.873352) (xy 69.476624 -313.924134)
			(xy 69.477128 -313.949842) (xy 69.794132 -313.949842) (xy 69.798092 -313.900788) (xy 69.809869 -313.853004)
			(xy 69.82916 -313.807728) (xy 69.855463 -313.766132) (xy 69.888098 -313.729295) (xy 69.926219 -313.69817)
			(xy 69.96884 -313.673563) (xy 70.014856 -313.656111) (xy 70.063075 -313.646267) (xy 70.11225 -313.644286)
			(xy 70.161105 -313.650218) (xy 70.208376 -313.66391) (xy 70.252838 -313.685008) (xy 70.293341 -313.712964)
			(xy 70.328834 -313.747056) (xy 70.358399 -313.7864) (xy 70.38127 -313.829977) (xy 70.396854 -313.876658)
			(xy 70.404749 -313.925235) (xy 70.405244 -313.949842) (xy 70.404749 -313.974449) (xy 70.40457 -313.97555)
			(xy 70.723248 -313.97555) (xy 70.723248 -313.924134) (xy 70.731291 -313.873352) (xy 70.747179 -313.824453)
			(xy 70.770522 -313.778641) (xy 70.800743 -313.737045) (xy 70.837099 -313.700689) (xy 70.878695 -313.670468)
			(xy 70.924507 -313.647125) (xy 70.973406 -313.631237) (xy 71.024188 -313.623194) (xy 71.075604 -313.623194)
			(xy 71.126386 -313.631237) (xy 71.175285 -313.647125) (xy 71.221097 -313.670468) (xy 71.262693 -313.700689)
			(xy 71.299049 -313.737045) (xy 71.32927 -313.778641) (xy 71.352613 -313.824453) (xy 71.368501 -313.873352)
			(xy 71.376544 -313.924134) (xy 71.377048 -313.949842) (xy 71.694052 -313.949842) (xy 71.698012 -313.900788)
			(xy 71.709789 -313.853004) (xy 71.72908 -313.807728) (xy 71.755383 -313.766132) (xy 71.788018 -313.729295)
			(xy 71.826139 -313.69817) (xy 71.86876 -313.673563) (xy 71.914776 -313.656111) (xy 71.962995 -313.646267)
			(xy 72.01217 -313.644286) (xy 72.061025 -313.650218) (xy 72.108296 -313.66391) (xy 72.152758 -313.685008)
			(xy 72.193261 -313.712964) (xy 72.228754 -313.747056) (xy 72.258319 -313.7864) (xy 72.28119 -313.829977)
			(xy 72.296774 -313.876658) (xy 72.304669 -313.925235) (xy 72.305164 -313.949842) (xy 72.304669 -313.974449)
			(xy 72.30449 -313.97555) (xy 72.623168 -313.97555) (xy 72.623168 -313.924134) (xy 72.631211 -313.873352)
			(xy 72.647099 -313.824453) (xy 72.670442 -313.778641) (xy 72.700663 -313.737045) (xy 72.737019 -313.700689)
			(xy 72.778615 -313.670468) (xy 72.824427 -313.647125) (xy 72.873326 -313.631237) (xy 72.924108 -313.623194)
			(xy 72.975524 -313.623194) (xy 73.026306 -313.631237) (xy 73.075205 -313.647125) (xy 73.121017 -313.670468)
			(xy 73.162613 -313.700689) (xy 73.198969 -313.737045) (xy 73.22919 -313.778641) (xy 73.252533 -313.824453)
			(xy 73.268421 -313.873352) (xy 73.276464 -313.924134) (xy 73.276968 -313.949842) (xy 73.593972 -313.949842)
			(xy 73.597932 -313.900788) (xy 73.609709 -313.853004) (xy 73.629 -313.807728) (xy 73.655303 -313.766132)
			(xy 73.687938 -313.729295) (xy 73.726059 -313.69817) (xy 73.76868 -313.673563) (xy 73.814696 -313.656111)
			(xy 73.862915 -313.646267) (xy 73.91209 -313.644286) (xy 73.960945 -313.650218) (xy 74.008216 -313.66391)
			(xy 74.052678 -313.685008) (xy 74.093181 -313.712964) (xy 74.128674 -313.747056) (xy 74.158239 -313.7864)
			(xy 74.18111 -313.829977) (xy 74.196694 -313.876658) (xy 74.204589 -313.925235) (xy 74.205084 -313.949842)
			(xy 74.204589 -313.974449) (xy 74.20441 -313.97555) (xy 74.523342 -313.97555) (xy 74.523342 -313.924134)
			(xy 74.531385 -313.873352) (xy 74.547273 -313.824453) (xy 74.570616 -313.778641) (xy 74.600837 -313.737045)
			(xy 74.637193 -313.700689) (xy 74.678789 -313.670468) (xy 74.724601 -313.647125) (xy 74.7735 -313.631237)
			(xy 74.824282 -313.623194) (xy 74.875698 -313.623194) (xy 74.92648 -313.631237) (xy 74.975379 -313.647125)
			(xy 75.021191 -313.670468) (xy 75.062787 -313.700689) (xy 75.099143 -313.737045) (xy 75.129364 -313.778641)
			(xy 75.152707 -313.824453) (xy 75.168595 -313.873352) (xy 75.176638 -313.924134) (xy 75.177142 -313.949842)
			(xy 75.494146 -313.949842) (xy 75.498106 -313.900788) (xy 75.509883 -313.853004) (xy 75.529174 -313.807728)
			(xy 75.555477 -313.766132) (xy 75.588112 -313.729295) (xy 75.626233 -313.69817) (xy 75.668854 -313.673563)
			(xy 75.71487 -313.656111) (xy 75.763089 -313.646267) (xy 75.812264 -313.644286) (xy 75.861119 -313.650218)
			(xy 75.90839 -313.66391) (xy 75.952852 -313.685008) (xy 75.993355 -313.712964) (xy 76.028848 -313.747056)
			(xy 76.058413 -313.7864) (xy 76.081284 -313.829977) (xy 76.096868 -313.876658) (xy 76.104763 -313.925235)
			(xy 76.105258 -313.949842) (xy 76.104763 -313.974449) (xy 76.104584 -313.97555) (xy 76.423262 -313.97555)
			(xy 76.423262 -313.924134) (xy 76.431305 -313.873352) (xy 76.447193 -313.824453) (xy 76.470536 -313.778641)
			(xy 76.500757 -313.737045) (xy 76.537113 -313.700689) (xy 76.578709 -313.670468) (xy 76.624521 -313.647125)
			(xy 76.67342 -313.631237) (xy 76.724202 -313.623194) (xy 76.775618 -313.623194) (xy 76.8264 -313.631237)
			(xy 76.875299 -313.647125) (xy 76.921111 -313.670468) (xy 76.962707 -313.700689) (xy 76.999063 -313.737045)
			(xy 77.029284 -313.778641) (xy 77.052627 -313.824453) (xy 77.068515 -313.873352) (xy 77.076558 -313.924134)
			(xy 77.077062 -313.949842) (xy 77.394066 -313.949842) (xy 77.398026 -313.900788) (xy 77.409803 -313.853004)
			(xy 77.429094 -313.807728) (xy 77.455397 -313.766132) (xy 77.488032 -313.729295) (xy 77.526153 -313.69817)
			(xy 77.568774 -313.673563) (xy 77.61479 -313.656111) (xy 77.663009 -313.646267) (xy 77.712184 -313.644286)
			(xy 77.761039 -313.650218) (xy 77.80831 -313.66391) (xy 77.852772 -313.685008) (xy 77.893275 -313.712964)
			(xy 77.928768 -313.747056) (xy 77.958333 -313.7864) (xy 77.981204 -313.829977) (xy 77.996788 -313.876658)
			(xy 78.004683 -313.925235) (xy 78.005178 -313.949842) (xy 78.004683 -313.974449) (xy 78.004504 -313.97555)
			(xy 78.323182 -313.97555) (xy 78.323182 -313.924134) (xy 78.331225 -313.873352) (xy 78.347113 -313.824453)
			(xy 78.370456 -313.778641) (xy 78.400677 -313.737045) (xy 78.437033 -313.700689) (xy 78.478629 -313.670468)
			(xy 78.524441 -313.647125) (xy 78.57334 -313.631237) (xy 78.624122 -313.623194) (xy 78.675538 -313.623194)
			(xy 78.72632 -313.631237) (xy 78.775219 -313.647125) (xy 78.821031 -313.670468) (xy 78.862627 -313.700689)
			(xy 78.898983 -313.737045) (xy 78.929204 -313.778641) (xy 78.952547 -313.824453) (xy 78.968435 -313.873352)
			(xy 78.976478 -313.924134) (xy 78.976982 -313.949842) (xy 79.293986 -313.949842) (xy 79.297946 -313.900788)
			(xy 79.309723 -313.853004) (xy 79.329014 -313.807728) (xy 79.355317 -313.766132) (xy 79.387952 -313.729295)
			(xy 79.426073 -313.69817) (xy 79.468694 -313.673563) (xy 79.51471 -313.656111) (xy 79.562929 -313.646267)
			(xy 79.612104 -313.644286) (xy 79.660959 -313.650218) (xy 79.70823 -313.66391) (xy 79.752692 -313.685008)
			(xy 79.793195 -313.712964) (xy 79.828688 -313.747056) (xy 79.858253 -313.7864) (xy 79.881124 -313.829977)
			(xy 79.896708 -313.876658) (xy 79.904603 -313.925235) (xy 79.905098 -313.949842) (xy 79.904603 -313.974449)
			(xy 79.904424 -313.97555) (xy 80.223102 -313.97555) (xy 80.223102 -313.924134) (xy 80.231145 -313.873352)
			(xy 80.247033 -313.824453) (xy 80.270376 -313.778641) (xy 80.300597 -313.737045) (xy 80.336953 -313.700689)
			(xy 80.378549 -313.670468) (xy 80.424361 -313.647125) (xy 80.47326 -313.631237) (xy 80.524042 -313.623194)
			(xy 80.575458 -313.623194) (xy 80.62624 -313.631237) (xy 80.675139 -313.647125) (xy 80.720951 -313.670468)
			(xy 80.762547 -313.700689) (xy 80.798903 -313.737045) (xy 80.829124 -313.778641) (xy 80.852467 -313.824453)
			(xy 80.868355 -313.873352) (xy 80.876398 -313.924134) (xy 80.876902 -313.949842) (xy 81.19416 -313.949842)
			(xy 81.19812 -313.900788) (xy 81.209897 -313.853004) (xy 81.229188 -313.807728) (xy 81.255491 -313.766132)
			(xy 81.288126 -313.729295) (xy 81.326247 -313.69817) (xy 81.368868 -313.673563) (xy 81.414884 -313.656111)
			(xy 81.463103 -313.646267) (xy 81.512278 -313.644286) (xy 81.561133 -313.650218) (xy 81.608404 -313.66391)
			(xy 81.652866 -313.685008) (xy 81.693369 -313.712964) (xy 81.728862 -313.747056) (xy 81.758427 -313.7864)
			(xy 81.781298 -313.829977) (xy 81.796882 -313.876658) (xy 81.804777 -313.925235) (xy 81.805272 -313.949842)
			(xy 82.14412 -313.949842) (xy 82.14808 -313.900788) (xy 82.159857 -313.853004) (xy 82.179148 -313.807728)
			(xy 82.205451 -313.766132) (xy 82.238086 -313.729295) (xy 82.276207 -313.69817) (xy 82.318828 -313.673563)
			(xy 82.364844 -313.656111) (xy 82.413063 -313.646267) (xy 82.462238 -313.644286) (xy 82.511093 -313.650218)
			(xy 82.558364 -313.66391) (xy 82.602826 -313.685008) (xy 82.643329 -313.712964) (xy 82.678822 -313.747056)
			(xy 82.708387 -313.7864) (xy 82.731258 -313.829977) (xy 82.746842 -313.876658) (xy 82.754737 -313.925235)
			(xy 82.755232 -313.949842) (xy 82.754737 -313.974449) (xy 82.746842 -314.023026) (xy 82.731258 -314.069707)
			(xy 82.708387 -314.113284) (xy 82.678822 -314.152628) (xy 82.643329 -314.18672) (xy 82.602826 -314.214676)
			(xy 82.558364 -314.235774) (xy 82.511093 -314.249466) (xy 82.462238 -314.255398) (xy 82.413063 -314.253417)
			(xy 82.364844 -314.243573) (xy 82.318828 -314.226121) (xy 82.276207 -314.201514) (xy 82.238086 -314.170389)
			(xy 82.205451 -314.133552) (xy 82.179148 -314.091956) (xy 82.159857 -314.04668) (xy 82.14808 -313.998896)
			(xy 82.14412 -313.949842) (xy 81.805272 -313.949842) (xy 81.804777 -313.974449) (xy 81.796882 -314.023026)
			(xy 81.781298 -314.069707) (xy 81.758427 -314.113284) (xy 81.728862 -314.152628) (xy 81.693369 -314.18672)
			(xy 81.652866 -314.214676) (xy 81.608404 -314.235774) (xy 81.561133 -314.249466) (xy 81.512278 -314.255398)
			(xy 81.463103 -314.253417) (xy 81.414884 -314.243573) (xy 81.368868 -314.226121) (xy 81.326247 -314.201514)
			(xy 81.288126 -314.170389) (xy 81.255491 -314.133552) (xy 81.229188 -314.091956) (xy 81.209897 -314.04668)
			(xy 81.19812 -313.998896) (xy 81.19416 -313.949842) (xy 80.876902 -313.949842) (xy 80.876398 -313.97555)
			(xy 80.868355 -314.026332) (xy 80.852467 -314.075231) (xy 80.829124 -314.121043) (xy 80.798903 -314.162639)
			(xy 80.762547 -314.198995) (xy 80.720951 -314.229216) (xy 80.675139 -314.252559) (xy 80.62624 -314.268447)
			(xy 80.575458 -314.27649) (xy 80.524042 -314.27649) (xy 80.47326 -314.268447) (xy 80.424361 -314.252559)
			(xy 80.378549 -314.229216) (xy 80.336953 -314.198995) (xy 80.300597 -314.162639) (xy 80.270376 -314.121043)
			(xy 80.247033 -314.075231) (xy 80.231145 -314.026332) (xy 80.223102 -313.97555) (xy 79.904424 -313.97555)
			(xy 79.896708 -314.023026) (xy 79.881124 -314.069707) (xy 79.858253 -314.113284) (xy 79.828688 -314.152628)
			(xy 79.793195 -314.18672) (xy 79.752692 -314.214676) (xy 79.70823 -314.235774) (xy 79.660959 -314.249466)
			(xy 79.612104 -314.255398) (xy 79.562929 -314.253417) (xy 79.51471 -314.243573) (xy 79.468694 -314.226121)
			(xy 79.426073 -314.201514) (xy 79.387952 -314.170389) (xy 79.355317 -314.133552) (xy 79.329014 -314.091956)
			(xy 79.309723 -314.04668) (xy 79.297946 -313.998896) (xy 79.293986 -313.949842) (xy 78.976982 -313.949842)
			(xy 78.976478 -313.97555) (xy 78.968435 -314.026332) (xy 78.952547 -314.075231) (xy 78.929204 -314.121043)
			(xy 78.898983 -314.162639) (xy 78.862627 -314.198995) (xy 78.821031 -314.229216) (xy 78.775219 -314.252559)
			(xy 78.72632 -314.268447) (xy 78.675538 -314.27649) (xy 78.624122 -314.27649) (xy 78.57334 -314.268447)
			(xy 78.524441 -314.252559) (xy 78.478629 -314.229216) (xy 78.437033 -314.198995) (xy 78.400677 -314.162639)
			(xy 78.370456 -314.121043) (xy 78.347113 -314.075231) (xy 78.331225 -314.026332) (xy 78.323182 -313.97555)
			(xy 78.004504 -313.97555) (xy 77.996788 -314.023026) (xy 77.981204 -314.069707) (xy 77.958333 -314.113284)
			(xy 77.928768 -314.152628) (xy 77.893275 -314.18672) (xy 77.852772 -314.214676) (xy 77.80831 -314.235774)
			(xy 77.761039 -314.249466) (xy 77.712184 -314.255398) (xy 77.663009 -314.253417) (xy 77.61479 -314.243573)
			(xy 77.568774 -314.226121) (xy 77.526153 -314.201514) (xy 77.488032 -314.170389) (xy 77.455397 -314.133552)
			(xy 77.429094 -314.091956) (xy 77.409803 -314.04668) (xy 77.398026 -313.998896) (xy 77.394066 -313.949842)
			(xy 77.077062 -313.949842) (xy 77.076558 -313.97555) (xy 77.068515 -314.026332) (xy 77.052627 -314.075231)
			(xy 77.029284 -314.121043) (xy 76.999063 -314.162639) (xy 76.962707 -314.198995) (xy 76.921111 -314.229216)
			(xy 76.875299 -314.252559) (xy 76.8264 -314.268447) (xy 76.775618 -314.27649) (xy 76.724202 -314.27649)
			(xy 76.67342 -314.268447) (xy 76.624521 -314.252559) (xy 76.578709 -314.229216) (xy 76.537113 -314.198995)
			(xy 76.500757 -314.162639) (xy 76.470536 -314.121043) (xy 76.447193 -314.075231) (xy 76.431305 -314.026332)
			(xy 76.423262 -313.97555) (xy 76.104584 -313.97555) (xy 76.096868 -314.023026) (xy 76.081284 -314.069707)
			(xy 76.058413 -314.113284) (xy 76.028848 -314.152628) (xy 75.993355 -314.18672) (xy 75.952852 -314.214676)
			(xy 75.90839 -314.235774) (xy 75.861119 -314.249466) (xy 75.812264 -314.255398) (xy 75.763089 -314.253417)
			(xy 75.71487 -314.243573) (xy 75.668854 -314.226121) (xy 75.626233 -314.201514) (xy 75.588112 -314.170389)
			(xy 75.555477 -314.133552) (xy 75.529174 -314.091956) (xy 75.509883 -314.04668) (xy 75.498106 -313.998896)
			(xy 75.494146 -313.949842) (xy 75.177142 -313.949842) (xy 75.176638 -313.97555) (xy 75.168595 -314.026332)
			(xy 75.152707 -314.075231) (xy 75.129364 -314.121043) (xy 75.099143 -314.162639) (xy 75.062787 -314.198995)
			(xy 75.021191 -314.229216) (xy 74.975379 -314.252559) (xy 74.92648 -314.268447) (xy 74.875698 -314.27649)
			(xy 74.824282 -314.27649) (xy 74.7735 -314.268447) (xy 74.724601 -314.252559) (xy 74.678789 -314.229216)
			(xy 74.637193 -314.198995) (xy 74.600837 -314.162639) (xy 74.570616 -314.121043) (xy 74.547273 -314.075231)
			(xy 74.531385 -314.026332) (xy 74.523342 -313.97555) (xy 74.20441 -313.97555) (xy 74.196694 -314.023026)
			(xy 74.18111 -314.069707) (xy 74.158239 -314.113284) (xy 74.128674 -314.152628) (xy 74.093181 -314.18672)
			(xy 74.052678 -314.214676) (xy 74.008216 -314.235774) (xy 73.960945 -314.249466) (xy 73.91209 -314.255398)
			(xy 73.862915 -314.253417) (xy 73.814696 -314.243573) (xy 73.76868 -314.226121) (xy 73.726059 -314.201514)
			(xy 73.687938 -314.170389) (xy 73.655303 -314.133552) (xy 73.629 -314.091956) (xy 73.609709 -314.04668)
			(xy 73.597932 -313.998896) (xy 73.593972 -313.949842) (xy 73.276968 -313.949842) (xy 73.276464 -313.97555)
			(xy 73.268421 -314.026332) (xy 73.252533 -314.075231) (xy 73.22919 -314.121043) (xy 73.198969 -314.162639)
			(xy 73.162613 -314.198995) (xy 73.121017 -314.229216) (xy 73.075205 -314.252559) (xy 73.026306 -314.268447)
			(xy 72.975524 -314.27649) (xy 72.924108 -314.27649) (xy 72.873326 -314.268447) (xy 72.824427 -314.252559)
			(xy 72.778615 -314.229216) (xy 72.737019 -314.198995) (xy 72.700663 -314.162639) (xy 72.670442 -314.121043)
			(xy 72.647099 -314.075231) (xy 72.631211 -314.026332) (xy 72.623168 -313.97555) (xy 72.30449 -313.97555)
			(xy 72.296774 -314.023026) (xy 72.28119 -314.069707) (xy 72.258319 -314.113284) (xy 72.228754 -314.152628)
			(xy 72.193261 -314.18672) (xy 72.152758 -314.214676) (xy 72.108296 -314.235774) (xy 72.061025 -314.249466)
			(xy 72.01217 -314.255398) (xy 71.962995 -314.253417) (xy 71.914776 -314.243573) (xy 71.86876 -314.226121)
			(xy 71.826139 -314.201514) (xy 71.788018 -314.170389) (xy 71.755383 -314.133552) (xy 71.72908 -314.091956)
			(xy 71.709789 -314.04668) (xy 71.698012 -313.998896) (xy 71.694052 -313.949842) (xy 71.377048 -313.949842)
			(xy 71.376544 -313.97555) (xy 71.368501 -314.026332) (xy 71.352613 -314.075231) (xy 71.32927 -314.121043)
			(xy 71.299049 -314.162639) (xy 71.262693 -314.198995) (xy 71.221097 -314.229216) (xy 71.175285 -314.252559)
			(xy 71.126386 -314.268447) (xy 71.075604 -314.27649) (xy 71.024188 -314.27649) (xy 70.973406 -314.268447)
			(xy 70.924507 -314.252559) (xy 70.878695 -314.229216) (xy 70.837099 -314.198995) (xy 70.800743 -314.162639)
			(xy 70.770522 -314.121043) (xy 70.747179 -314.075231) (xy 70.731291 -314.026332) (xy 70.723248 -313.97555)
			(xy 70.40457 -313.97555) (xy 70.396854 -314.023026) (xy 70.38127 -314.069707) (xy 70.358399 -314.113284)
			(xy 70.328834 -314.152628) (xy 70.293341 -314.18672) (xy 70.252838 -314.214676) (xy 70.208376 -314.235774)
			(xy 70.161105 -314.249466) (xy 70.11225 -314.255398) (xy 70.063075 -314.253417) (xy 70.014856 -314.243573)
			(xy 69.96884 -314.226121) (xy 69.926219 -314.201514) (xy 69.888098 -314.170389) (xy 69.855463 -314.133552)
			(xy 69.82916 -314.091956) (xy 69.809869 -314.04668) (xy 69.798092 -313.998896) (xy 69.794132 -313.949842)
			(xy 69.477128 -313.949842) (xy 69.476624 -313.97555) (xy 69.468581 -314.026332) (xy 69.452693 -314.075231)
			(xy 69.42935 -314.121043) (xy 69.399129 -314.162639) (xy 69.362773 -314.198995) (xy 69.321177 -314.229216)
			(xy 69.275365 -314.252559) (xy 69.226466 -314.268447) (xy 69.175684 -314.27649) (xy 69.124268 -314.27649)
			(xy 69.073486 -314.268447) (xy 69.024587 -314.252559) (xy 68.978775 -314.229216) (xy 68.937179 -314.198995)
			(xy 68.900823 -314.162639) (xy 68.870602 -314.121043) (xy 68.847259 -314.075231) (xy 68.831371 -314.026332)
			(xy 68.823328 -313.97555) (xy 68.504396 -313.97555) (xy 68.49668 -314.023026) (xy 68.481096 -314.069707)
			(xy 68.458225 -314.113284) (xy 68.42866 -314.152628) (xy 68.393167 -314.18672) (xy 68.352664 -314.214676)
			(xy 68.308202 -314.235774) (xy 68.260931 -314.249466) (xy 68.212076 -314.255398) (xy 68.162901 -314.253417)
			(xy 68.114682 -314.243573) (xy 68.068666 -314.226121) (xy 68.026045 -314.201514) (xy 67.987924 -314.170389)
			(xy 67.955289 -314.133552) (xy 67.928986 -314.091956) (xy 67.909695 -314.04668) (xy 67.897918 -313.998896)
			(xy 67.893958 -313.949842) (xy 67.576954 -313.949842) (xy 67.57645 -313.97555) (xy 67.568407 -314.026332)
			(xy 67.552519 -314.075231) (xy 67.529176 -314.121043) (xy 67.498955 -314.162639) (xy 67.462599 -314.198995)
			(xy 67.421003 -314.229216) (xy 67.375191 -314.252559) (xy 67.326292 -314.268447) (xy 67.27551 -314.27649)
			(xy 67.224094 -314.27649) (xy 67.173312 -314.268447) (xy 67.124413 -314.252559) (xy 67.078601 -314.229216)
			(xy 67.037005 -314.198995) (xy 67.000649 -314.162639) (xy 66.970428 -314.121043) (xy 66.947085 -314.075231)
			(xy 66.931197 -314.026332) (xy 66.923154 -313.97555) (xy 66.604476 -313.97555) (xy 66.59676 -314.023026)
			(xy 66.581176 -314.069707) (xy 66.558305 -314.113284) (xy 66.52874 -314.152628) (xy 66.493247 -314.18672)
			(xy 66.452744 -314.214676) (xy 66.408282 -314.235774) (xy 66.361011 -314.249466) (xy 66.312156 -314.255398)
			(xy 66.262981 -314.253417) (xy 66.214762 -314.243573) (xy 66.168746 -314.226121) (xy 66.126125 -314.201514)
			(xy 66.088004 -314.170389) (xy 66.055369 -314.133552) (xy 66.029066 -314.091956) (xy 66.009775 -314.04668)
			(xy 65.997998 -313.998896) (xy 65.994038 -313.949842) (xy 65.677034 -313.949842) (xy 65.67653 -313.97555)
			(xy 65.668487 -314.026332) (xy 65.652599 -314.075231) (xy 65.629256 -314.121043) (xy 65.599035 -314.162639)
			(xy 65.562679 -314.198995) (xy 65.521083 -314.229216) (xy 65.475271 -314.252559) (xy 65.426372 -314.268447)
			(xy 65.37559 -314.27649) (xy 65.324174 -314.27649) (xy 65.273392 -314.268447) (xy 65.224493 -314.252559)
			(xy 65.178681 -314.229216) (xy 65.137085 -314.198995) (xy 65.100729 -314.162639) (xy 65.070508 -314.121043)
			(xy 65.047165 -314.075231) (xy 65.031277 -314.026332) (xy 65.023234 -313.97555) (xy 64.704556 -313.97555)
			(xy 64.69684 -314.023026) (xy 64.681256 -314.069707) (xy 64.658385 -314.113284) (xy 64.62882 -314.152628)
			(xy 64.593327 -314.18672) (xy 64.552824 -314.214676) (xy 64.508362 -314.235774) (xy 64.461091 -314.249466)
			(xy 64.412236 -314.255398) (xy 64.363061 -314.253417) (xy 64.314842 -314.243573) (xy 64.268826 -314.226121)
			(xy 64.226205 -314.201514) (xy 64.188084 -314.170389) (xy 64.155449 -314.133552) (xy 64.129146 -314.091956)
			(xy 64.109855 -314.04668) (xy 64.098078 -313.998896) (xy 64.094118 -313.949842) (xy 63.777114 -313.949842)
			(xy 63.77661 -313.97555) (xy 63.768567 -314.026332) (xy 63.752679 -314.075231) (xy 63.729336 -314.121043)
			(xy 63.699115 -314.162639) (xy 63.662759 -314.198995) (xy 63.621163 -314.229216) (xy 63.575351 -314.252559)
			(xy 63.526452 -314.268447) (xy 63.47567 -314.27649) (xy 63.424254 -314.27649) (xy 63.373472 -314.268447)
			(xy 63.324573 -314.252559) (xy 63.278761 -314.229216) (xy 63.237165 -314.198995) (xy 63.200809 -314.162639)
			(xy 63.170588 -314.121043) (xy 63.147245 -314.075231) (xy 63.131357 -314.026332) (xy 63.123314 -313.97555)
			(xy 62.804382 -313.97555) (xy 62.796666 -314.023026) (xy 62.781082 -314.069707) (xy 62.758211 -314.113284)
			(xy 62.728646 -314.152628) (xy 62.693153 -314.18672) (xy 62.65265 -314.214676) (xy 62.608188 -314.235774)
			(xy 62.560917 -314.249466) (xy 62.512062 -314.255398) (xy 62.462887 -314.253417) (xy 62.414668 -314.243573)
			(xy 62.368652 -314.226121) (xy 62.326031 -314.201514) (xy 62.28791 -314.170389) (xy 62.255275 -314.133552)
			(xy 62.228972 -314.091956) (xy 62.209681 -314.04668) (xy 62.197904 -313.998896) (xy 62.193944 -313.949842)
			(xy 61.87694 -313.949842) (xy 61.876436 -313.97555) (xy 61.868393 -314.026332) (xy 61.852505 -314.075231)
			(xy 61.829162 -314.121043) (xy 61.798941 -314.162639) (xy 61.762585 -314.198995) (xy 61.720989 -314.229216)
			(xy 61.675177 -314.252559) (xy 61.626278 -314.268447) (xy 61.575496 -314.27649) (xy 61.52408 -314.27649)
			(xy 61.473298 -314.268447) (xy 61.424399 -314.252559) (xy 61.378587 -314.229216) (xy 61.336991 -314.198995)
			(xy 61.300635 -314.162639) (xy 61.270414 -314.121043) (xy 61.247071 -314.075231) (xy 61.231183 -314.026332)
			(xy 61.22314 -313.97555) (xy 60.904462 -313.97555) (xy 60.896746 -314.023026) (xy 60.881162 -314.069707)
			(xy 60.858291 -314.113284) (xy 60.828726 -314.152628) (xy 60.793233 -314.18672) (xy 60.75273 -314.214676)
			(xy 60.708268 -314.235774) (xy 60.660997 -314.249466) (xy 60.612142 -314.255398) (xy 60.562967 -314.253417)
			(xy 60.514748 -314.243573) (xy 60.468732 -314.226121) (xy 60.426111 -314.201514) (xy 60.38799 -314.170389)
			(xy 60.355355 -314.133552) (xy 60.329052 -314.091956) (xy 60.309761 -314.04668) (xy 60.297984 -313.998896)
			(xy 60.294024 -313.949842) (xy 59.97702 -313.949842) (xy 59.976516 -313.97555) (xy 59.968473 -314.026332)
			(xy 59.952585 -314.075231) (xy 59.929242 -314.121043) (xy 59.899021 -314.162639) (xy 59.862665 -314.198995)
			(xy 59.821069 -314.229216) (xy 59.775257 -314.252559) (xy 59.726358 -314.268447) (xy 59.675576 -314.27649)
			(xy 59.62416 -314.27649) (xy 59.573378 -314.268447) (xy 59.524479 -314.252559) (xy 59.478667 -314.229216)
			(xy 59.437071 -314.198995) (xy 59.400715 -314.162639) (xy 59.370494 -314.121043) (xy 59.347151 -314.075231)
			(xy 59.331263 -314.026332) (xy 59.32322 -313.97555) (xy 59.004447 -313.97555) (xy 58.997498 -314.020122)
			(xy 58.983129 -314.065112) (xy 58.962008 -314.107355) (xy 58.934637 -314.145845) (xy 58.90167 -314.179664)
			(xy 58.86389 -314.208006) (xy 58.822199 -314.230198) (xy 58.77759 -314.245709) (xy 58.731125 -314.254171)
			(xy 58.707528 -314.25515) (xy 58.697401 -314.255795) (xy 58.678875 -314.264034) (xy 58.665008 -314.278826)
			(xy 58.661046 -314.28817) (xy 58.645754 -314.328006) (xy 58.609127 -314.405082) (xy 58.587894 -314.442094)
			(xy 58.580782 -314.45454) (xy 58.581036 -314.482226) (xy 58.642758 -314.583064) (xy 58.667396 -314.596018)
			(xy 58.68162 -314.595002) (xy 58.699908 -314.594494) (xy 58.723899 -314.594965) (xy 58.771289 -314.602472)
			(xy 58.816922 -314.6173) (xy 58.859674 -314.639084) (xy 58.898491 -314.667288) (xy 58.932418 -314.701217)
			(xy 58.960621 -314.740035) (xy 58.982403 -314.782787) (xy 58.99723 -314.82842) (xy 59.004736 -314.875811)
			(xy 59.005216 -314.899802) (xy 59.344064 -314.899802) (xy 59.348024 -314.850748) (xy 59.359801 -314.802964)
			(xy 59.379092 -314.757688) (xy 59.405395 -314.716092) (xy 59.43803 -314.679255) (xy 59.476151 -314.64813)
			(xy 59.518772 -314.623523) (xy 59.564788 -314.606071) (xy 59.613007 -314.596227) (xy 59.662182 -314.594246)
			(xy 59.711037 -314.600178) (xy 59.758308 -314.61387) (xy 59.80277 -314.634968) (xy 59.843273 -314.662924)
			(xy 59.878766 -314.697016) (xy 59.908331 -314.73636) (xy 59.931202 -314.779937) (xy 59.946786 -314.826618)
			(xy 59.954681 -314.875195) (xy 59.955176 -314.899802) (xy 60.294024 -314.899802) (xy 60.297984 -314.850748)
			(xy 60.309761 -314.802964) (xy 60.329052 -314.757688) (xy 60.355355 -314.716092) (xy 60.38799 -314.679255)
			(xy 60.426111 -314.64813) (xy 60.468732 -314.623523) (xy 60.514748 -314.606071) (xy 60.562967 -314.596227)
			(xy 60.612142 -314.594246) (xy 60.660997 -314.600178) (xy 60.708268 -314.61387) (xy 60.75273 -314.634968)
			(xy 60.793233 -314.662924) (xy 60.828726 -314.697016) (xy 60.858291 -314.73636) (xy 60.881162 -314.779937)
			(xy 60.896746 -314.826618) (xy 60.904641 -314.875195) (xy 60.905136 -314.899802) (xy 61.243984 -314.899802)
			(xy 61.247944 -314.850748) (xy 61.259721 -314.802964) (xy 61.279012 -314.757688) (xy 61.305315 -314.716092)
			(xy 61.33795 -314.679255) (xy 61.376071 -314.64813) (xy 61.418692 -314.623523) (xy 61.464708 -314.606071)
			(xy 61.512927 -314.596227) (xy 61.562102 -314.594246) (xy 61.610957 -314.600178) (xy 61.658228 -314.61387)
			(xy 61.70269 -314.634968) (xy 61.743193 -314.662924) (xy 61.778686 -314.697016) (xy 61.808251 -314.73636)
			(xy 61.831122 -314.779937) (xy 61.846706 -314.826618) (xy 61.854601 -314.875195) (xy 61.855096 -314.899802)
			(xy 62.193944 -314.899802) (xy 62.197904 -314.850748) (xy 62.209681 -314.802964) (xy 62.228972 -314.757688)
			(xy 62.255275 -314.716092) (xy 62.28791 -314.679255) (xy 62.326031 -314.64813) (xy 62.368652 -314.623523)
			(xy 62.414668 -314.606071) (xy 62.462887 -314.596227) (xy 62.512062 -314.594246) (xy 62.560917 -314.600178)
			(xy 62.608188 -314.61387) (xy 62.65265 -314.634968) (xy 62.693153 -314.662924) (xy 62.728646 -314.697016)
			(xy 62.758211 -314.73636) (xy 62.781082 -314.779937) (xy 62.796666 -314.826618) (xy 62.804561 -314.875195)
			(xy 62.805056 -314.899802) (xy 63.144158 -314.899802) (xy 63.148118 -314.850748) (xy 63.159895 -314.802964)
			(xy 63.179186 -314.757688) (xy 63.205489 -314.716092) (xy 63.238124 -314.679255) (xy 63.276245 -314.64813)
			(xy 63.318866 -314.623523) (xy 63.364882 -314.606071) (xy 63.413101 -314.596227) (xy 63.462276 -314.594246)
			(xy 63.511131 -314.600178) (xy 63.558402 -314.61387) (xy 63.602864 -314.634968) (xy 63.643367 -314.662924)
			(xy 63.67886 -314.697016) (xy 63.708425 -314.73636) (xy 63.731296 -314.779937) (xy 63.74688 -314.826618)
			(xy 63.754775 -314.875195) (xy 63.75527 -314.899802) (xy 64.094118 -314.899802) (xy 64.098078 -314.850748)
			(xy 64.109855 -314.802964) (xy 64.129146 -314.757688) (xy 64.155449 -314.716092) (xy 64.188084 -314.679255)
			(xy 64.226205 -314.64813) (xy 64.268826 -314.623523) (xy 64.314842 -314.606071) (xy 64.363061 -314.596227)
			(xy 64.412236 -314.594246) (xy 64.461091 -314.600178) (xy 64.508362 -314.61387) (xy 64.552824 -314.634968)
			(xy 64.593327 -314.662924) (xy 64.62882 -314.697016) (xy 64.658385 -314.73636) (xy 64.681256 -314.779937)
			(xy 64.69684 -314.826618) (xy 64.704735 -314.875195) (xy 64.70523 -314.899802) (xy 65.044078 -314.899802)
			(xy 65.048038 -314.850748) (xy 65.059815 -314.802964) (xy 65.079106 -314.757688) (xy 65.105409 -314.716092)
			(xy 65.138044 -314.679255) (xy 65.176165 -314.64813) (xy 65.218786 -314.623523) (xy 65.264802 -314.606071)
			(xy 65.313021 -314.596227) (xy 65.362196 -314.594246) (xy 65.411051 -314.600178) (xy 65.458322 -314.61387)
			(xy 65.502784 -314.634968) (xy 65.543287 -314.662924) (xy 65.57878 -314.697016) (xy 65.608345 -314.73636)
			(xy 65.631216 -314.779937) (xy 65.6468 -314.826618) (xy 65.654695 -314.875195) (xy 65.65519 -314.899802)
			(xy 65.994038 -314.899802) (xy 65.997998 -314.850748) (xy 66.009775 -314.802964) (xy 66.029066 -314.757688)
			(xy 66.055369 -314.716092) (xy 66.088004 -314.679255) (xy 66.126125 -314.64813) (xy 66.168746 -314.623523)
			(xy 66.214762 -314.606071) (xy 66.262981 -314.596227) (xy 66.312156 -314.594246) (xy 66.361011 -314.600178)
			(xy 66.408282 -314.61387) (xy 66.452744 -314.634968) (xy 66.493247 -314.662924) (xy 66.52874 -314.697016)
			(xy 66.558305 -314.73636) (xy 66.581176 -314.779937) (xy 66.59676 -314.826618) (xy 66.604655 -314.875195)
			(xy 66.60515 -314.899802) (xy 66.943998 -314.899802) (xy 66.947958 -314.850748) (xy 66.959735 -314.802964)
			(xy 66.979026 -314.757688) (xy 67.005329 -314.716092) (xy 67.037964 -314.679255) (xy 67.076085 -314.64813)
			(xy 67.118706 -314.623523) (xy 67.164722 -314.606071) (xy 67.212941 -314.596227) (xy 67.262116 -314.594246)
			(xy 67.310971 -314.600178) (xy 67.358242 -314.61387) (xy 67.402704 -314.634968) (xy 67.443207 -314.662924)
			(xy 67.4787 -314.697016) (xy 67.508265 -314.73636) (xy 67.531136 -314.779937) (xy 67.54672 -314.826618)
			(xy 67.554615 -314.875195) (xy 67.55511 -314.899802) (xy 67.893958 -314.899802) (xy 67.897918 -314.850748)
			(xy 67.909695 -314.802964) (xy 67.928986 -314.757688) (xy 67.955289 -314.716092) (xy 67.987924 -314.679255)
			(xy 68.026045 -314.64813) (xy 68.068666 -314.623523) (xy 68.114682 -314.606071) (xy 68.162901 -314.596227)
			(xy 68.212076 -314.594246) (xy 68.260931 -314.600178) (xy 68.308202 -314.61387) (xy 68.352664 -314.634968)
			(xy 68.393167 -314.662924) (xy 68.42866 -314.697016) (xy 68.458225 -314.73636) (xy 68.481096 -314.779937)
			(xy 68.49668 -314.826618) (xy 68.504575 -314.875195) (xy 68.50507 -314.899802) (xy 68.844172 -314.899802)
			(xy 68.848132 -314.850748) (xy 68.859909 -314.802964) (xy 68.8792 -314.757688) (xy 68.905503 -314.716092)
			(xy 68.938138 -314.679255) (xy 68.976259 -314.64813) (xy 69.01888 -314.623523) (xy 69.064896 -314.606071)
			(xy 69.113115 -314.596227) (xy 69.16229 -314.594246) (xy 69.211145 -314.600178) (xy 69.258416 -314.61387)
			(xy 69.302878 -314.634968) (xy 69.343381 -314.662924) (xy 69.378874 -314.697016) (xy 69.408439 -314.73636)
			(xy 69.43131 -314.779937) (xy 69.446894 -314.826618) (xy 69.454789 -314.875195) (xy 69.455284 -314.899802)
			(xy 69.794132 -314.899802) (xy 69.798092 -314.850748) (xy 69.809869 -314.802964) (xy 69.82916 -314.757688)
			(xy 69.855463 -314.716092) (xy 69.888098 -314.679255) (xy 69.926219 -314.64813) (xy 69.96884 -314.623523)
			(xy 70.014856 -314.606071) (xy 70.063075 -314.596227) (xy 70.11225 -314.594246) (xy 70.161105 -314.600178)
			(xy 70.208376 -314.61387) (xy 70.252838 -314.634968) (xy 70.293341 -314.662924) (xy 70.328834 -314.697016)
			(xy 70.358399 -314.73636) (xy 70.38127 -314.779937) (xy 70.396854 -314.826618) (xy 70.404749 -314.875195)
			(xy 70.405244 -314.899802) (xy 70.744092 -314.899802) (xy 70.748052 -314.850748) (xy 70.759829 -314.802964)
			(xy 70.77912 -314.757688) (xy 70.805423 -314.716092) (xy 70.838058 -314.679255) (xy 70.876179 -314.64813)
			(xy 70.9188 -314.623523) (xy 70.964816 -314.606071) (xy 71.013035 -314.596227) (xy 71.06221 -314.594246)
			(xy 71.111065 -314.600178) (xy 71.158336 -314.61387) (xy 71.202798 -314.634968) (xy 71.243301 -314.662924)
			(xy 71.278794 -314.697016) (xy 71.308359 -314.73636) (xy 71.33123 -314.779937) (xy 71.346814 -314.826618)
			(xy 71.354709 -314.875195) (xy 71.355204 -314.899802) (xy 71.694052 -314.899802) (xy 71.698012 -314.850748)
			(xy 71.709789 -314.802964) (xy 71.72908 -314.757688) (xy 71.755383 -314.716092) (xy 71.788018 -314.679255)
			(xy 71.826139 -314.64813) (xy 71.86876 -314.623523) (xy 71.914776 -314.606071) (xy 71.962995 -314.596227)
			(xy 72.01217 -314.594246) (xy 72.061025 -314.600178) (xy 72.108296 -314.61387) (xy 72.152758 -314.634968)
			(xy 72.193261 -314.662924) (xy 72.228754 -314.697016) (xy 72.258319 -314.73636) (xy 72.28119 -314.779937)
			(xy 72.296774 -314.826618) (xy 72.304669 -314.875195) (xy 72.305164 -314.899802) (xy 72.644012 -314.899802)
			(xy 72.647972 -314.850748) (xy 72.659749 -314.802964) (xy 72.67904 -314.757688) (xy 72.705343 -314.716092)
			(xy 72.737978 -314.679255) (xy 72.776099 -314.64813) (xy 72.81872 -314.623523) (xy 72.864736 -314.606071)
			(xy 72.912955 -314.596227) (xy 72.96213 -314.594246) (xy 73.010985 -314.600178) (xy 73.058256 -314.61387)
			(xy 73.102718 -314.634968) (xy 73.143221 -314.662924) (xy 73.178714 -314.697016) (xy 73.208279 -314.73636)
			(xy 73.23115 -314.779937) (xy 73.246734 -314.826618) (xy 73.254629 -314.875195) (xy 73.255124 -314.899802)
			(xy 73.593972 -314.899802) (xy 73.597932 -314.850748) (xy 73.609709 -314.802964) (xy 73.629 -314.757688)
			(xy 73.655303 -314.716092) (xy 73.687938 -314.679255) (xy 73.726059 -314.64813) (xy 73.76868 -314.623523)
			(xy 73.814696 -314.606071) (xy 73.862915 -314.596227) (xy 73.91209 -314.594246) (xy 73.960945 -314.600178)
			(xy 74.008216 -314.61387) (xy 74.052678 -314.634968) (xy 74.093181 -314.662924) (xy 74.128674 -314.697016)
			(xy 74.158239 -314.73636) (xy 74.18111 -314.779937) (xy 74.196694 -314.826618) (xy 74.204589 -314.875195)
			(xy 74.205084 -314.899802) (xy 74.544186 -314.899802) (xy 74.548146 -314.850748) (xy 74.559923 -314.802964)
			(xy 74.579214 -314.757688) (xy 74.605517 -314.716092) (xy 74.638152 -314.679255) (xy 74.676273 -314.64813)
			(xy 74.718894 -314.623523) (xy 74.76491 -314.606071) (xy 74.813129 -314.596227) (xy 74.862304 -314.594246)
			(xy 74.911159 -314.600178) (xy 74.95843 -314.61387) (xy 75.002892 -314.634968) (xy 75.043395 -314.662924)
			(xy 75.078888 -314.697016) (xy 75.108453 -314.73636) (xy 75.131324 -314.779937) (xy 75.146908 -314.826618)
			(xy 75.154803 -314.875195) (xy 75.155298 -314.899802) (xy 75.494146 -314.899802) (xy 75.498106 -314.850748)
			(xy 75.509883 -314.802964) (xy 75.529174 -314.757688) (xy 75.555477 -314.716092) (xy 75.588112 -314.679255)
			(xy 75.626233 -314.64813) (xy 75.668854 -314.623523) (xy 75.71487 -314.606071) (xy 75.763089 -314.596227)
			(xy 75.812264 -314.594246) (xy 75.861119 -314.600178) (xy 75.90839 -314.61387) (xy 75.952852 -314.634968)
			(xy 75.993355 -314.662924) (xy 76.028848 -314.697016) (xy 76.058413 -314.73636) (xy 76.081284 -314.779937)
			(xy 76.096868 -314.826618) (xy 76.104763 -314.875195) (xy 76.105258 -314.899802) (xy 76.444106 -314.899802)
			(xy 76.448066 -314.850748) (xy 76.459843 -314.802964) (xy 76.479134 -314.757688) (xy 76.505437 -314.716092)
			(xy 76.538072 -314.679255) (xy 76.576193 -314.64813) (xy 76.618814 -314.623523) (xy 76.66483 -314.606071)
			(xy 76.713049 -314.596227) (xy 76.762224 -314.594246) (xy 76.811079 -314.600178) (xy 76.85835 -314.61387)
			(xy 76.902812 -314.634968) (xy 76.943315 -314.662924) (xy 76.978808 -314.697016) (xy 77.008373 -314.73636)
			(xy 77.031244 -314.779937) (xy 77.046828 -314.826618) (xy 77.054723 -314.875195) (xy 77.055218 -314.899802)
			(xy 77.394066 -314.899802) (xy 77.398026 -314.850748) (xy 77.409803 -314.802964) (xy 77.429094 -314.757688)
			(xy 77.455397 -314.716092) (xy 77.488032 -314.679255) (xy 77.526153 -314.64813) (xy 77.568774 -314.623523)
			(xy 77.61479 -314.606071) (xy 77.663009 -314.596227) (xy 77.712184 -314.594246) (xy 77.761039 -314.600178)
			(xy 77.80831 -314.61387) (xy 77.852772 -314.634968) (xy 77.893275 -314.662924) (xy 77.928768 -314.697016)
			(xy 77.958333 -314.73636) (xy 77.981204 -314.779937) (xy 77.996788 -314.826618) (xy 78.004683 -314.875195)
			(xy 78.005178 -314.899802) (xy 78.344026 -314.899802) (xy 78.347986 -314.850748) (xy 78.359763 -314.802964)
			(xy 78.379054 -314.757688) (xy 78.405357 -314.716092) (xy 78.437992 -314.679255) (xy 78.476113 -314.64813)
			(xy 78.518734 -314.623523) (xy 78.56475 -314.606071) (xy 78.612969 -314.596227) (xy 78.662144 -314.594246)
			(xy 78.710999 -314.600178) (xy 78.75827 -314.61387) (xy 78.802732 -314.634968) (xy 78.843235 -314.662924)
			(xy 78.878728 -314.697016) (xy 78.908293 -314.73636) (xy 78.931164 -314.779937) (xy 78.946748 -314.826618)
			(xy 78.954643 -314.875195) (xy 78.955138 -314.899802) (xy 79.293986 -314.899802) (xy 79.297946 -314.850748)
			(xy 79.309723 -314.802964) (xy 79.329014 -314.757688) (xy 79.355317 -314.716092) (xy 79.387952 -314.679255)
			(xy 79.426073 -314.64813) (xy 79.468694 -314.623523) (xy 79.51471 -314.606071) (xy 79.562929 -314.596227)
			(xy 79.612104 -314.594246) (xy 79.660959 -314.600178) (xy 79.70823 -314.61387) (xy 79.752692 -314.634968)
			(xy 79.793195 -314.662924) (xy 79.828688 -314.697016) (xy 79.858253 -314.73636) (xy 79.881124 -314.779937)
			(xy 79.896708 -314.826618) (xy 79.904603 -314.875195) (xy 79.905098 -314.899802) (xy 80.243946 -314.899802)
			(xy 80.247906 -314.850748) (xy 80.259683 -314.802964) (xy 80.278974 -314.757688) (xy 80.305277 -314.716092)
			(xy 80.337912 -314.679255) (xy 80.376033 -314.64813) (xy 80.418654 -314.623523) (xy 80.46467 -314.606071)
			(xy 80.512889 -314.596227) (xy 80.562064 -314.594246) (xy 80.610919 -314.600178) (xy 80.65819 -314.61387)
			(xy 80.702652 -314.634968) (xy 80.743155 -314.662924) (xy 80.778648 -314.697016) (xy 80.808213 -314.73636)
			(xy 80.831084 -314.779937) (xy 80.846668 -314.826618) (xy 80.854563 -314.875195) (xy 80.855058 -314.899802)
			(xy 80.854563 -314.924409) (xy 80.854384 -314.92551) (xy 81.173316 -314.92551) (xy 81.173316 -314.874094)
			(xy 81.181359 -314.823312) (xy 81.197247 -314.774413) (xy 81.22059 -314.728601) (xy 81.250811 -314.687005)
			(xy 81.287167 -314.650649) (xy 81.328763 -314.620428) (xy 81.374575 -314.597085) (xy 81.423474 -314.581197)
			(xy 81.474256 -314.573154) (xy 81.525672 -314.573154) (xy 81.576454 -314.581197) (xy 81.625353 -314.597085)
			(xy 81.671165 -314.620428) (xy 81.712761 -314.650649) (xy 81.749117 -314.687005) (xy 81.779338 -314.728601)
			(xy 81.802681 -314.774413) (xy 81.818569 -314.823312) (xy 81.826612 -314.874094) (xy 81.827116 -314.899802)
			(xy 81.826612 -314.92551) (xy 82.123276 -314.92551) (xy 82.123276 -314.874094) (xy 82.131319 -314.823312)
			(xy 82.147207 -314.774413) (xy 82.17055 -314.728601) (xy 82.200771 -314.687005) (xy 82.237127 -314.650649)
			(xy 82.278723 -314.620428) (xy 82.324535 -314.597085) (xy 82.373434 -314.581197) (xy 82.424216 -314.573154)
			(xy 82.475632 -314.573154) (xy 82.526414 -314.581197) (xy 82.575313 -314.597085) (xy 82.621125 -314.620428)
			(xy 82.662721 -314.650649) (xy 82.699077 -314.687005) (xy 82.729298 -314.728601) (xy 82.752641 -314.774413)
			(xy 82.768529 -314.823312) (xy 82.776572 -314.874094) (xy 82.777071 -314.899548) (xy 83.094334 -314.899548)
			(xy 83.098294 -314.850494) (xy 83.110071 -314.80271) (xy 83.129362 -314.757434) (xy 83.155665 -314.715838)
			(xy 83.1883 -314.679001) (xy 83.226421 -314.647876) (xy 83.269042 -314.623269) (xy 83.315058 -314.605817)
			(xy 83.363277 -314.595973) (xy 83.412452 -314.593992) (xy 83.461307 -314.599924) (xy 83.508578 -314.613616)
			(xy 83.55304 -314.634714) (xy 83.593543 -314.66267) (xy 83.629036 -314.696762) (xy 83.658601 -314.736106)
			(xy 83.681472 -314.779683) (xy 83.697056 -314.826364) (xy 83.704951 -314.874941) (xy 83.705446 -314.899548)
			(xy 83.704951 -314.924155) (xy 83.697056 -314.972732) (xy 83.681472 -315.019413) (xy 83.658601 -315.06299)
			(xy 83.629036 -315.102334) (xy 83.593543 -315.136426) (xy 83.55304 -315.164382) (xy 83.508578 -315.18548)
			(xy 83.461307 -315.199172) (xy 83.412452 -315.205104) (xy 83.363277 -315.203123) (xy 83.315058 -315.193279)
			(xy 83.269042 -315.175827) (xy 83.226421 -315.15122) (xy 83.1883 -315.120095) (xy 83.155665 -315.083258)
			(xy 83.129362 -315.041662) (xy 83.110071 -314.996386) (xy 83.098294 -314.948602) (xy 83.094334 -314.899548)
			(xy 82.777071 -314.899548) (xy 82.777076 -314.899802) (xy 82.776572 -314.92551) (xy 82.768529 -314.976292)
			(xy 82.752641 -315.025191) (xy 82.729298 -315.071003) (xy 82.699077 -315.112599) (xy 82.662721 -315.148955)
			(xy 82.621125 -315.179176) (xy 82.575313 -315.202519) (xy 82.526414 -315.218407) (xy 82.475632 -315.22645)
			(xy 82.424216 -315.22645) (xy 82.373434 -315.218407) (xy 82.324535 -315.202519) (xy 82.278723 -315.179176)
			(xy 82.237127 -315.148955) (xy 82.200771 -315.112599) (xy 82.17055 -315.071003) (xy 82.147207 -315.025191)
			(xy 82.131319 -314.976292) (xy 82.123276 -314.92551) (xy 81.826612 -314.92551) (xy 81.818569 -314.976292)
			(xy 81.802681 -315.025191) (xy 81.779338 -315.071003) (xy 81.749117 -315.112599) (xy 81.712761 -315.148955)
			(xy 81.671165 -315.179176) (xy 81.625353 -315.202519) (xy 81.576454 -315.218407) (xy 81.525672 -315.22645)
			(xy 81.474256 -315.22645) (xy 81.423474 -315.218407) (xy 81.374575 -315.202519) (xy 81.328763 -315.179176)
			(xy 81.287167 -315.148955) (xy 81.250811 -315.112599) (xy 81.22059 -315.071003) (xy 81.197247 -315.025191)
			(xy 81.181359 -314.976292) (xy 81.173316 -314.92551) (xy 80.854384 -314.92551) (xy 80.846668 -314.972986)
			(xy 80.831084 -315.019667) (xy 80.808213 -315.063244) (xy 80.778648 -315.102588) (xy 80.743155 -315.13668)
			(xy 80.702652 -315.164636) (xy 80.65819 -315.185734) (xy 80.610919 -315.199426) (xy 80.562064 -315.205358)
			(xy 80.512889 -315.203377) (xy 80.46467 -315.193533) (xy 80.418654 -315.176081) (xy 80.376033 -315.151474)
			(xy 80.337912 -315.120349) (xy 80.305277 -315.083512) (xy 80.278974 -315.041916) (xy 80.259683 -314.99664)
			(xy 80.247906 -314.948856) (xy 80.243946 -314.899802) (xy 79.905098 -314.899802) (xy 79.904603 -314.924409)
			(xy 79.896708 -314.972986) (xy 79.881124 -315.019667) (xy 79.858253 -315.063244) (xy 79.828688 -315.102588)
			(xy 79.793195 -315.13668) (xy 79.752692 -315.164636) (xy 79.70823 -315.185734) (xy 79.660959 -315.199426)
			(xy 79.612104 -315.205358) (xy 79.562929 -315.203377) (xy 79.51471 -315.193533) (xy 79.468694 -315.176081)
			(xy 79.426073 -315.151474) (xy 79.387952 -315.120349) (xy 79.355317 -315.083512) (xy 79.329014 -315.041916)
			(xy 79.309723 -314.99664) (xy 79.297946 -314.948856) (xy 79.293986 -314.899802) (xy 78.955138 -314.899802)
			(xy 78.954643 -314.924409) (xy 78.946748 -314.972986) (xy 78.931164 -315.019667) (xy 78.908293 -315.063244)
			(xy 78.878728 -315.102588) (xy 78.843235 -315.13668) (xy 78.802732 -315.164636) (xy 78.75827 -315.185734)
			(xy 78.710999 -315.199426) (xy 78.662144 -315.205358) (xy 78.612969 -315.203377) (xy 78.56475 -315.193533)
			(xy 78.518734 -315.176081) (xy 78.476113 -315.151474) (xy 78.437992 -315.120349) (xy 78.405357 -315.083512)
			(xy 78.379054 -315.041916) (xy 78.359763 -314.99664) (xy 78.347986 -314.948856) (xy 78.344026 -314.899802)
			(xy 78.005178 -314.899802) (xy 78.004683 -314.924409) (xy 77.996788 -314.972986) (xy 77.981204 -315.019667)
			(xy 77.958333 -315.063244) (xy 77.928768 -315.102588) (xy 77.893275 -315.13668) (xy 77.852772 -315.164636)
			(xy 77.80831 -315.185734) (xy 77.761039 -315.199426) (xy 77.712184 -315.205358) (xy 77.663009 -315.203377)
			(xy 77.61479 -315.193533) (xy 77.568774 -315.176081) (xy 77.526153 -315.151474) (xy 77.488032 -315.120349)
			(xy 77.455397 -315.083512) (xy 77.429094 -315.041916) (xy 77.409803 -314.99664) (xy 77.398026 -314.948856)
			(xy 77.394066 -314.899802) (xy 77.055218 -314.899802) (xy 77.054723 -314.924409) (xy 77.046828 -314.972986)
			(xy 77.031244 -315.019667) (xy 77.008373 -315.063244) (xy 76.978808 -315.102588) (xy 76.943315 -315.13668)
			(xy 76.902812 -315.164636) (xy 76.85835 -315.185734) (xy 76.811079 -315.199426) (xy 76.762224 -315.205358)
			(xy 76.713049 -315.203377) (xy 76.66483 -315.193533) (xy 76.618814 -315.176081) (xy 76.576193 -315.151474)
			(xy 76.538072 -315.120349) (xy 76.505437 -315.083512) (xy 76.479134 -315.041916) (xy 76.459843 -314.99664)
			(xy 76.448066 -314.948856) (xy 76.444106 -314.899802) (xy 76.105258 -314.899802) (xy 76.104763 -314.924409)
			(xy 76.096868 -314.972986) (xy 76.081284 -315.019667) (xy 76.058413 -315.063244) (xy 76.028848 -315.102588)
			(xy 75.993355 -315.13668) (xy 75.952852 -315.164636) (xy 75.90839 -315.185734) (xy 75.861119 -315.199426)
			(xy 75.812264 -315.205358) (xy 75.763089 -315.203377) (xy 75.71487 -315.193533) (xy 75.668854 -315.176081)
			(xy 75.626233 -315.151474) (xy 75.588112 -315.120349) (xy 75.555477 -315.083512) (xy 75.529174 -315.041916)
			(xy 75.509883 -314.99664) (xy 75.498106 -314.948856) (xy 75.494146 -314.899802) (xy 75.155298 -314.899802)
			(xy 75.154803 -314.924409) (xy 75.146908 -314.972986) (xy 75.131324 -315.019667) (xy 75.108453 -315.063244)
			(xy 75.078888 -315.102588) (xy 75.043395 -315.13668) (xy 75.002892 -315.164636) (xy 74.95843 -315.185734)
			(xy 74.911159 -315.199426) (xy 74.862304 -315.205358) (xy 74.813129 -315.203377) (xy 74.76491 -315.193533)
			(xy 74.718894 -315.176081) (xy 74.676273 -315.151474) (xy 74.638152 -315.120349) (xy 74.605517 -315.083512)
			(xy 74.579214 -315.041916) (xy 74.559923 -314.99664) (xy 74.548146 -314.948856) (xy 74.544186 -314.899802)
			(xy 74.205084 -314.899802) (xy 74.204589 -314.924409) (xy 74.196694 -314.972986) (xy 74.18111 -315.019667)
			(xy 74.158239 -315.063244) (xy 74.128674 -315.102588) (xy 74.093181 -315.13668) (xy 74.052678 -315.164636)
			(xy 74.008216 -315.185734) (xy 73.960945 -315.199426) (xy 73.91209 -315.205358) (xy 73.862915 -315.203377)
			(xy 73.814696 -315.193533) (xy 73.76868 -315.176081) (xy 73.726059 -315.151474) (xy 73.687938 -315.120349)
			(xy 73.655303 -315.083512) (xy 73.629 -315.041916) (xy 73.609709 -314.99664) (xy 73.597932 -314.948856)
			(xy 73.593972 -314.899802) (xy 73.255124 -314.899802) (xy 73.254629 -314.924409) (xy 73.246734 -314.972986)
			(xy 73.23115 -315.019667) (xy 73.208279 -315.063244) (xy 73.178714 -315.102588) (xy 73.143221 -315.13668)
			(xy 73.102718 -315.164636) (xy 73.058256 -315.185734) (xy 73.010985 -315.199426) (xy 72.96213 -315.205358)
			(xy 72.912955 -315.203377) (xy 72.864736 -315.193533) (xy 72.81872 -315.176081) (xy 72.776099 -315.151474)
			(xy 72.737978 -315.120349) (xy 72.705343 -315.083512) (xy 72.67904 -315.041916) (xy 72.659749 -314.99664)
			(xy 72.647972 -314.948856) (xy 72.644012 -314.899802) (xy 72.305164 -314.899802) (xy 72.304669 -314.924409)
			(xy 72.296774 -314.972986) (xy 72.28119 -315.019667) (xy 72.258319 -315.063244) (xy 72.228754 -315.102588)
			(xy 72.193261 -315.13668) (xy 72.152758 -315.164636) (xy 72.108296 -315.185734) (xy 72.061025 -315.199426)
			(xy 72.01217 -315.205358) (xy 71.962995 -315.203377) (xy 71.914776 -315.193533) (xy 71.86876 -315.176081)
			(xy 71.826139 -315.151474) (xy 71.788018 -315.120349) (xy 71.755383 -315.083512) (xy 71.72908 -315.041916)
			(xy 71.709789 -314.99664) (xy 71.698012 -314.948856) (xy 71.694052 -314.899802) (xy 71.355204 -314.899802)
			(xy 71.354709 -314.924409) (xy 71.346814 -314.972986) (xy 71.33123 -315.019667) (xy 71.308359 -315.063244)
			(xy 71.278794 -315.102588) (xy 71.243301 -315.13668) (xy 71.202798 -315.164636) (xy 71.158336 -315.185734)
			(xy 71.111065 -315.199426) (xy 71.06221 -315.205358) (xy 71.013035 -315.203377) (xy 70.964816 -315.193533)
			(xy 70.9188 -315.176081) (xy 70.876179 -315.151474) (xy 70.838058 -315.120349) (xy 70.805423 -315.083512)
			(xy 70.77912 -315.041916) (xy 70.759829 -314.99664) (xy 70.748052 -314.948856) (xy 70.744092 -314.899802)
			(xy 70.405244 -314.899802) (xy 70.404749 -314.924409) (xy 70.396854 -314.972986) (xy 70.38127 -315.019667)
			(xy 70.358399 -315.063244) (xy 70.328834 -315.102588) (xy 70.293341 -315.13668) (xy 70.252838 -315.164636)
			(xy 70.208376 -315.185734) (xy 70.161105 -315.199426) (xy 70.11225 -315.205358) (xy 70.063075 -315.203377)
			(xy 70.014856 -315.193533) (xy 69.96884 -315.176081) (xy 69.926219 -315.151474) (xy 69.888098 -315.120349)
			(xy 69.855463 -315.083512) (xy 69.82916 -315.041916) (xy 69.809869 -314.99664) (xy 69.798092 -314.948856)
			(xy 69.794132 -314.899802) (xy 69.455284 -314.899802) (xy 69.454789 -314.924409) (xy 69.446894 -314.972986)
			(xy 69.43131 -315.019667) (xy 69.408439 -315.063244) (xy 69.378874 -315.102588) (xy 69.343381 -315.13668)
			(xy 69.302878 -315.164636) (xy 69.258416 -315.185734) (xy 69.211145 -315.199426) (xy 69.16229 -315.205358)
			(xy 69.113115 -315.203377) (xy 69.064896 -315.193533) (xy 69.01888 -315.176081) (xy 68.976259 -315.151474)
			(xy 68.938138 -315.120349) (xy 68.905503 -315.083512) (xy 68.8792 -315.041916) (xy 68.859909 -314.99664)
			(xy 68.848132 -314.948856) (xy 68.844172 -314.899802) (xy 68.50507 -314.899802) (xy 68.504575 -314.924409)
			(xy 68.49668 -314.972986) (xy 68.481096 -315.019667) (xy 68.458225 -315.063244) (xy 68.42866 -315.102588)
			(xy 68.393167 -315.13668) (xy 68.352664 -315.164636) (xy 68.308202 -315.185734) (xy 68.260931 -315.199426)
			(xy 68.212076 -315.205358) (xy 68.162901 -315.203377) (xy 68.114682 -315.193533) (xy 68.068666 -315.176081)
			(xy 68.026045 -315.151474) (xy 67.987924 -315.120349) (xy 67.955289 -315.083512) (xy 67.928986 -315.041916)
			(xy 67.909695 -314.99664) (xy 67.897918 -314.948856) (xy 67.893958 -314.899802) (xy 67.55511 -314.899802)
			(xy 67.554615 -314.924409) (xy 67.54672 -314.972986) (xy 67.531136 -315.019667) (xy 67.508265 -315.063244)
			(xy 67.4787 -315.102588) (xy 67.443207 -315.13668) (xy 67.402704 -315.164636) (xy 67.358242 -315.185734)
			(xy 67.310971 -315.199426) (xy 67.262116 -315.205358) (xy 67.212941 -315.203377) (xy 67.164722 -315.193533)
			(xy 67.118706 -315.176081) (xy 67.076085 -315.151474) (xy 67.037964 -315.120349) (xy 67.005329 -315.083512)
			(xy 66.979026 -315.041916) (xy 66.959735 -314.99664) (xy 66.947958 -314.948856) (xy 66.943998 -314.899802)
			(xy 66.60515 -314.899802) (xy 66.604655 -314.924409) (xy 66.59676 -314.972986) (xy 66.581176 -315.019667)
			(xy 66.558305 -315.063244) (xy 66.52874 -315.102588) (xy 66.493247 -315.13668) (xy 66.452744 -315.164636)
			(xy 66.408282 -315.185734) (xy 66.361011 -315.199426) (xy 66.312156 -315.205358) (xy 66.262981 -315.203377)
			(xy 66.214762 -315.193533) (xy 66.168746 -315.176081) (xy 66.126125 -315.151474) (xy 66.088004 -315.120349)
			(xy 66.055369 -315.083512) (xy 66.029066 -315.041916) (xy 66.009775 -314.99664) (xy 65.997998 -314.948856)
			(xy 65.994038 -314.899802) (xy 65.65519 -314.899802) (xy 65.654695 -314.924409) (xy 65.6468 -314.972986)
			(xy 65.631216 -315.019667) (xy 65.608345 -315.063244) (xy 65.57878 -315.102588) (xy 65.543287 -315.13668)
			(xy 65.502784 -315.164636) (xy 65.458322 -315.185734) (xy 65.411051 -315.199426) (xy 65.362196 -315.205358)
			(xy 65.313021 -315.203377) (xy 65.264802 -315.193533) (xy 65.218786 -315.176081) (xy 65.176165 -315.151474)
			(xy 65.138044 -315.120349) (xy 65.105409 -315.083512) (xy 65.079106 -315.041916) (xy 65.059815 -314.99664)
			(xy 65.048038 -314.948856) (xy 65.044078 -314.899802) (xy 64.70523 -314.899802) (xy 64.704735 -314.924409)
			(xy 64.69684 -314.972986) (xy 64.681256 -315.019667) (xy 64.658385 -315.063244) (xy 64.62882 -315.102588)
			(xy 64.593327 -315.13668) (xy 64.552824 -315.164636) (xy 64.508362 -315.185734) (xy 64.461091 -315.199426)
			(xy 64.412236 -315.205358) (xy 64.363061 -315.203377) (xy 64.314842 -315.193533) (xy 64.268826 -315.176081)
			(xy 64.226205 -315.151474) (xy 64.188084 -315.120349) (xy 64.155449 -315.083512) (xy 64.129146 -315.041916)
			(xy 64.109855 -314.99664) (xy 64.098078 -314.948856) (xy 64.094118 -314.899802) (xy 63.75527 -314.899802)
			(xy 63.754775 -314.924409) (xy 63.74688 -314.972986) (xy 63.731296 -315.019667) (xy 63.708425 -315.063244)
			(xy 63.67886 -315.102588) (xy 63.643367 -315.13668) (xy 63.602864 -315.164636) (xy 63.558402 -315.185734)
			(xy 63.511131 -315.199426) (xy 63.462276 -315.205358) (xy 63.413101 -315.203377) (xy 63.364882 -315.193533)
			(xy 63.318866 -315.176081) (xy 63.276245 -315.151474) (xy 63.238124 -315.120349) (xy 63.205489 -315.083512)
			(xy 63.179186 -315.041916) (xy 63.159895 -314.99664) (xy 63.148118 -314.948856) (xy 63.144158 -314.899802)
			(xy 62.805056 -314.899802) (xy 62.804561 -314.924409) (xy 62.796666 -314.972986) (xy 62.781082 -315.019667)
			(xy 62.758211 -315.063244) (xy 62.728646 -315.102588) (xy 62.693153 -315.13668) (xy 62.65265 -315.164636)
			(xy 62.608188 -315.185734) (xy 62.560917 -315.199426) (xy 62.512062 -315.205358) (xy 62.462887 -315.203377)
			(xy 62.414668 -315.193533) (xy 62.368652 -315.176081) (xy 62.326031 -315.151474) (xy 62.28791 -315.120349)
			(xy 62.255275 -315.083512) (xy 62.228972 -315.041916) (xy 62.209681 -314.99664) (xy 62.197904 -314.948856)
			(xy 62.193944 -314.899802) (xy 61.855096 -314.899802) (xy 61.854601 -314.924409) (xy 61.846706 -314.972986)
			(xy 61.831122 -315.019667) (xy 61.808251 -315.063244) (xy 61.778686 -315.102588) (xy 61.743193 -315.13668)
			(xy 61.70269 -315.164636) (xy 61.658228 -315.185734) (xy 61.610957 -315.199426) (xy 61.562102 -315.205358)
			(xy 61.512927 -315.203377) (xy 61.464708 -315.193533) (xy 61.418692 -315.176081) (xy 61.376071 -315.151474)
			(xy 61.33795 -315.120349) (xy 61.305315 -315.083512) (xy 61.279012 -315.041916) (xy 61.259721 -314.99664)
			(xy 61.247944 -314.948856) (xy 61.243984 -314.899802) (xy 60.905136 -314.899802) (xy 60.904641 -314.924409)
			(xy 60.896746 -314.972986) (xy 60.881162 -315.019667) (xy 60.858291 -315.063244) (xy 60.828726 -315.102588)
			(xy 60.793233 -315.13668) (xy 60.75273 -315.164636) (xy 60.708268 -315.185734) (xy 60.660997 -315.199426)
			(xy 60.612142 -315.205358) (xy 60.562967 -315.203377) (xy 60.514748 -315.193533) (xy 60.468732 -315.176081)
			(xy 60.426111 -315.151474) (xy 60.38799 -315.120349) (xy 60.355355 -315.083512) (xy 60.329052 -315.041916)
			(xy 60.309761 -314.99664) (xy 60.297984 -314.948856) (xy 60.294024 -314.899802) (xy 59.955176 -314.899802)
			(xy 59.954681 -314.924409) (xy 59.946786 -314.972986) (xy 59.931202 -315.019667) (xy 59.908331 -315.063244)
			(xy 59.878766 -315.102588) (xy 59.843273 -315.13668) (xy 59.80277 -315.164636) (xy 59.758308 -315.185734)
			(xy 59.711037 -315.199426) (xy 59.662182 -315.205358) (xy 59.613007 -315.203377) (xy 59.564788 -315.193533)
			(xy 59.518772 -315.176081) (xy 59.476151 -315.151474) (xy 59.43803 -315.120349) (xy 59.405395 -315.083512)
			(xy 59.379092 -315.041916) (xy 59.359801 -314.99664) (xy 59.348024 -314.948856) (xy 59.344064 -314.899802)
			(xy 59.005216 -314.899802) (xy 59.004673 -314.925569) (xy 58.99601 -314.97637) (xy 58.978946 -315.024998)
			(xy 58.953965 -315.070073) (xy 58.921776 -315.110319) (xy 58.883291 -315.144593) (xy 58.8396 -315.171924)
			(xy 58.815986 -315.18225) (xy 58.803794 -315.187076) (xy 58.788046 -315.20638) (xy 58.768742 -315.302138)
			(xy 58.766946 -315.314623) (xy 58.774285 -315.338724) (xy 58.782712 -315.348112) (xy 59.02579 -315.59119)
			(xy 59.032639 -315.598587) (xy 59.040379 -315.617185) (xy 59.040776 -315.627258) (xy 59.040776 -315.849762)
			(xy 59.344064 -315.849762) (xy 59.348024 -315.800708) (xy 59.359801 -315.752924) (xy 59.379092 -315.707648)
			(xy 59.405395 -315.666052) (xy 59.43803 -315.629215) (xy 59.476151 -315.59809) (xy 59.518772 -315.573483)
			(xy 59.564788 -315.556031) (xy 59.613007 -315.546187) (xy 59.662182 -315.544206) (xy 59.711037 -315.550138)
			(xy 59.758308 -315.56383) (xy 59.80277 -315.584928) (xy 59.843273 -315.612884) (xy 59.878766 -315.646976)
			(xy 59.908331 -315.68632) (xy 59.931202 -315.729897) (xy 59.946786 -315.776578) (xy 59.954681 -315.825155)
			(xy 59.955176 -315.849762) (xy 59.954681 -315.874369) (xy 59.954502 -315.87547) (xy 60.27318 -315.87547)
			(xy 60.27318 -315.824054) (xy 60.281223 -315.773272) (xy 60.297111 -315.724373) (xy 60.320454 -315.678561)
			(xy 60.350675 -315.636965) (xy 60.387031 -315.600609) (xy 60.428627 -315.570388) (xy 60.474439 -315.547045)
			(xy 60.523338 -315.531157) (xy 60.57412 -315.523114) (xy 60.625536 -315.523114) (xy 60.676318 -315.531157)
			(xy 60.725217 -315.547045) (xy 60.771029 -315.570388) (xy 60.812625 -315.600609) (xy 60.848981 -315.636965)
			(xy 60.879202 -315.678561) (xy 60.902545 -315.724373) (xy 60.918433 -315.773272) (xy 60.926476 -315.824054)
			(xy 60.92698 -315.849762) (xy 61.243984 -315.849762) (xy 61.247944 -315.800708) (xy 61.259721 -315.752924)
			(xy 61.279012 -315.707648) (xy 61.305315 -315.666052) (xy 61.33795 -315.629215) (xy 61.376071 -315.59809)
			(xy 61.418692 -315.573483) (xy 61.464708 -315.556031) (xy 61.512927 -315.546187) (xy 61.562102 -315.544206)
			(xy 61.610957 -315.550138) (xy 61.658228 -315.56383) (xy 61.70269 -315.584928) (xy 61.743193 -315.612884)
			(xy 61.778686 -315.646976) (xy 61.808251 -315.68632) (xy 61.831122 -315.729897) (xy 61.846706 -315.776578)
			(xy 61.854601 -315.825155) (xy 61.855096 -315.849762) (xy 61.854601 -315.874369) (xy 61.854422 -315.87547)
			(xy 62.1731 -315.87547) (xy 62.1731 -315.824054) (xy 62.181143 -315.773272) (xy 62.197031 -315.724373)
			(xy 62.220374 -315.678561) (xy 62.250595 -315.636965) (xy 62.286951 -315.600609) (xy 62.328547 -315.570388)
			(xy 62.374359 -315.547045) (xy 62.423258 -315.531157) (xy 62.47404 -315.523114) (xy 62.525456 -315.523114)
			(xy 62.576238 -315.531157) (xy 62.625137 -315.547045) (xy 62.670949 -315.570388) (xy 62.712545 -315.600609)
			(xy 62.748901 -315.636965) (xy 62.779122 -315.678561) (xy 62.802465 -315.724373) (xy 62.818353 -315.773272)
			(xy 62.826396 -315.824054) (xy 62.8269 -315.849762) (xy 63.144158 -315.849762) (xy 63.148118 -315.800708)
			(xy 63.159895 -315.752924) (xy 63.179186 -315.707648) (xy 63.205489 -315.666052) (xy 63.238124 -315.629215)
			(xy 63.276245 -315.59809) (xy 63.318866 -315.573483) (xy 63.364882 -315.556031) (xy 63.413101 -315.546187)
			(xy 63.462276 -315.544206) (xy 63.511131 -315.550138) (xy 63.558402 -315.56383) (xy 63.602864 -315.584928)
			(xy 63.643367 -315.612884) (xy 63.67886 -315.646976) (xy 63.708425 -315.68632) (xy 63.731296 -315.729897)
			(xy 63.74688 -315.776578) (xy 63.754775 -315.825155) (xy 63.75527 -315.849762) (xy 63.754775 -315.874369)
			(xy 63.754596 -315.87547) (xy 64.073274 -315.87547) (xy 64.073274 -315.824054) (xy 64.081317 -315.773272)
			(xy 64.097205 -315.724373) (xy 64.120548 -315.678561) (xy 64.150769 -315.636965) (xy 64.187125 -315.600609)
			(xy 64.228721 -315.570388) (xy 64.274533 -315.547045) (xy 64.323432 -315.531157) (xy 64.374214 -315.523114)
			(xy 64.42563 -315.523114) (xy 64.476412 -315.531157) (xy 64.525311 -315.547045) (xy 64.571123 -315.570388)
			(xy 64.612719 -315.600609) (xy 64.649075 -315.636965) (xy 64.679296 -315.678561) (xy 64.702639 -315.724373)
			(xy 64.718527 -315.773272) (xy 64.72657 -315.824054) (xy 64.727074 -315.849762) (xy 65.044078 -315.849762)
			(xy 65.048038 -315.800708) (xy 65.059815 -315.752924) (xy 65.079106 -315.707648) (xy 65.105409 -315.666052)
			(xy 65.138044 -315.629215) (xy 65.176165 -315.59809) (xy 65.218786 -315.573483) (xy 65.264802 -315.556031)
			(xy 65.313021 -315.546187) (xy 65.362196 -315.544206) (xy 65.411051 -315.550138) (xy 65.458322 -315.56383)
			(xy 65.502784 -315.584928) (xy 65.543287 -315.612884) (xy 65.57878 -315.646976) (xy 65.608345 -315.68632)
			(xy 65.631216 -315.729897) (xy 65.6468 -315.776578) (xy 65.654695 -315.825155) (xy 65.65519 -315.849762)
			(xy 65.654695 -315.874369) (xy 65.654516 -315.87547) (xy 65.973194 -315.87547) (xy 65.973194 -315.824054)
			(xy 65.981237 -315.773272) (xy 65.997125 -315.724373) (xy 66.020468 -315.678561) (xy 66.050689 -315.636965)
			(xy 66.087045 -315.600609) (xy 66.128641 -315.570388) (xy 66.174453 -315.547045) (xy 66.223352 -315.531157)
			(xy 66.274134 -315.523114) (xy 66.32555 -315.523114) (xy 66.376332 -315.531157) (xy 66.425231 -315.547045)
			(xy 66.471043 -315.570388) (xy 66.512639 -315.600609) (xy 66.548995 -315.636965) (xy 66.579216 -315.678561)
			(xy 66.602559 -315.724373) (xy 66.618447 -315.773272) (xy 66.62649 -315.824054) (xy 66.626994 -315.849762)
			(xy 66.943998 -315.849762) (xy 66.947958 -315.800708) (xy 66.959735 -315.752924) (xy 66.979026 -315.707648)
			(xy 67.005329 -315.666052) (xy 67.037964 -315.629215) (xy 67.076085 -315.59809) (xy 67.118706 -315.573483)
			(xy 67.164722 -315.556031) (xy 67.212941 -315.546187) (xy 67.262116 -315.544206) (xy 67.310971 -315.550138)
			(xy 67.358242 -315.56383) (xy 67.402704 -315.584928) (xy 67.443207 -315.612884) (xy 67.4787 -315.646976)
			(xy 67.508265 -315.68632) (xy 67.531136 -315.729897) (xy 67.54672 -315.776578) (xy 67.554615 -315.825155)
			(xy 67.55511 -315.849762) (xy 67.554615 -315.874369) (xy 67.554436 -315.87547) (xy 67.873114 -315.87547)
			(xy 67.873114 -315.824054) (xy 67.881157 -315.773272) (xy 67.897045 -315.724373) (xy 67.920388 -315.678561)
			(xy 67.950609 -315.636965) (xy 67.986965 -315.600609) (xy 68.028561 -315.570388) (xy 68.074373 -315.547045)
			(xy 68.123272 -315.531157) (xy 68.174054 -315.523114) (xy 68.22547 -315.523114) (xy 68.276252 -315.531157)
			(xy 68.325151 -315.547045) (xy 68.370963 -315.570388) (xy 68.412559 -315.600609) (xy 68.448915 -315.636965)
			(xy 68.479136 -315.678561) (xy 68.502479 -315.724373) (xy 68.518367 -315.773272) (xy 68.52641 -315.824054)
			(xy 68.526914 -315.849762) (xy 68.844172 -315.849762) (xy 68.848132 -315.800708) (xy 68.859909 -315.752924)
			(xy 68.8792 -315.707648) (xy 68.905503 -315.666052) (xy 68.938138 -315.629215) (xy 68.976259 -315.59809)
			(xy 69.01888 -315.573483) (xy 69.064896 -315.556031) (xy 69.113115 -315.546187) (xy 69.16229 -315.544206)
			(xy 69.211145 -315.550138) (xy 69.258416 -315.56383) (xy 69.302878 -315.584928) (xy 69.343381 -315.612884)
			(xy 69.378874 -315.646976) (xy 69.408439 -315.68632) (xy 69.43131 -315.729897) (xy 69.446894 -315.776578)
			(xy 69.454789 -315.825155) (xy 69.455284 -315.849762) (xy 69.454789 -315.874369) (xy 69.45461 -315.87547)
			(xy 69.773288 -315.87547) (xy 69.773288 -315.824054) (xy 69.781331 -315.773272) (xy 69.797219 -315.724373)
			(xy 69.820562 -315.678561) (xy 69.850783 -315.636965) (xy 69.887139 -315.600609) (xy 69.928735 -315.570388)
			(xy 69.974547 -315.547045) (xy 70.023446 -315.531157) (xy 70.074228 -315.523114) (xy 70.125644 -315.523114)
			(xy 70.176426 -315.531157) (xy 70.225325 -315.547045) (xy 70.271137 -315.570388) (xy 70.312733 -315.600609)
			(xy 70.349089 -315.636965) (xy 70.37931 -315.678561) (xy 70.402653 -315.724373) (xy 70.418541 -315.773272)
			(xy 70.426584 -315.824054) (xy 70.427088 -315.849762) (xy 70.744092 -315.849762) (xy 70.748052 -315.800708)
			(xy 70.759829 -315.752924) (xy 70.77912 -315.707648) (xy 70.805423 -315.666052) (xy 70.838058 -315.629215)
			(xy 70.876179 -315.59809) (xy 70.9188 -315.573483) (xy 70.964816 -315.556031) (xy 71.013035 -315.546187)
			(xy 71.06221 -315.544206) (xy 71.111065 -315.550138) (xy 71.158336 -315.56383) (xy 71.202798 -315.584928)
			(xy 71.243301 -315.612884) (xy 71.278794 -315.646976) (xy 71.308359 -315.68632) (xy 71.33123 -315.729897)
			(xy 71.346814 -315.776578) (xy 71.354709 -315.825155) (xy 71.355204 -315.849762) (xy 71.354709 -315.874369)
			(xy 71.35453 -315.87547) (xy 71.673208 -315.87547) (xy 71.673208 -315.824054) (xy 71.681251 -315.773272)
			(xy 71.697139 -315.724373) (xy 71.720482 -315.678561) (xy 71.750703 -315.636965) (xy 71.787059 -315.600609)
			(xy 71.828655 -315.570388) (xy 71.874467 -315.547045) (xy 71.923366 -315.531157) (xy 71.974148 -315.523114)
			(xy 72.025564 -315.523114) (xy 72.076346 -315.531157) (xy 72.125245 -315.547045) (xy 72.171057 -315.570388)
			(xy 72.212653 -315.600609) (xy 72.249009 -315.636965) (xy 72.27923 -315.678561) (xy 72.302573 -315.724373)
			(xy 72.318461 -315.773272) (xy 72.326504 -315.824054) (xy 72.327008 -315.849762) (xy 72.644012 -315.849762)
			(xy 72.647972 -315.800708) (xy 72.659749 -315.752924) (xy 72.67904 -315.707648) (xy 72.705343 -315.666052)
			(xy 72.737978 -315.629215) (xy 72.776099 -315.59809) (xy 72.81872 -315.573483) (xy 72.864736 -315.556031)
			(xy 72.912955 -315.546187) (xy 72.96213 -315.544206) (xy 73.010985 -315.550138) (xy 73.058256 -315.56383)
			(xy 73.102718 -315.584928) (xy 73.143221 -315.612884) (xy 73.178714 -315.646976) (xy 73.208279 -315.68632)
			(xy 73.23115 -315.729897) (xy 73.246734 -315.776578) (xy 73.254629 -315.825155) (xy 73.255124 -315.849762)
			(xy 73.593972 -315.849762) (xy 73.597932 -315.800708) (xy 73.609709 -315.752924) (xy 73.629 -315.707648)
			(xy 73.655303 -315.666052) (xy 73.687938 -315.629215) (xy 73.726059 -315.59809) (xy 73.76868 -315.573483)
			(xy 73.814696 -315.556031) (xy 73.862915 -315.546187) (xy 73.91209 -315.544206) (xy 73.960945 -315.550138)
			(xy 74.008216 -315.56383) (xy 74.052678 -315.584928) (xy 74.093181 -315.612884) (xy 74.128674 -315.646976)
			(xy 74.158239 -315.68632) (xy 74.18111 -315.729897) (xy 74.196694 -315.776578) (xy 74.204589 -315.825155)
			(xy 74.205084 -315.849762) (xy 74.544186 -315.849762) (xy 74.548146 -315.800708) (xy 74.559923 -315.752924)
			(xy 74.579214 -315.707648) (xy 74.605517 -315.666052) (xy 74.638152 -315.629215) (xy 74.676273 -315.59809)
			(xy 74.718894 -315.573483) (xy 74.76491 -315.556031) (xy 74.813129 -315.546187) (xy 74.862304 -315.544206)
			(xy 74.911159 -315.550138) (xy 74.95843 -315.56383) (xy 75.002892 -315.584928) (xy 75.043395 -315.612884)
			(xy 75.078888 -315.646976) (xy 75.108453 -315.68632) (xy 75.131324 -315.729897) (xy 75.146908 -315.776578)
			(xy 75.154803 -315.825155) (xy 75.155298 -315.849762) (xy 75.494146 -315.849762) (xy 75.498106 -315.800708)
			(xy 75.509883 -315.752924) (xy 75.529174 -315.707648) (xy 75.555477 -315.666052) (xy 75.588112 -315.629215)
			(xy 75.626233 -315.59809) (xy 75.668854 -315.573483) (xy 75.71487 -315.556031) (xy 75.763089 -315.546187)
			(xy 75.812264 -315.544206) (xy 75.861119 -315.550138) (xy 75.90839 -315.56383) (xy 75.952852 -315.584928)
			(xy 75.993355 -315.612884) (xy 76.028848 -315.646976) (xy 76.058413 -315.68632) (xy 76.081284 -315.729897)
			(xy 76.096868 -315.776578) (xy 76.104763 -315.825155) (xy 76.105258 -315.849762) (xy 76.444106 -315.849762)
			(xy 76.448066 -315.800708) (xy 76.459843 -315.752924) (xy 76.479134 -315.707648) (xy 76.505437 -315.666052)
			(xy 76.538072 -315.629215) (xy 76.576193 -315.59809) (xy 76.618814 -315.573483) (xy 76.66483 -315.556031)
			(xy 76.713049 -315.546187) (xy 76.762224 -315.544206) (xy 76.811079 -315.550138) (xy 76.85835 -315.56383)
			(xy 76.902812 -315.584928) (xy 76.943315 -315.612884) (xy 76.978808 -315.646976) (xy 77.008373 -315.68632)
			(xy 77.031244 -315.729897) (xy 77.046828 -315.776578) (xy 77.054723 -315.825155) (xy 77.055218 -315.849762)
			(xy 77.394066 -315.849762) (xy 77.398026 -315.800708) (xy 77.409803 -315.752924) (xy 77.429094 -315.707648)
			(xy 77.455397 -315.666052) (xy 77.488032 -315.629215) (xy 77.526153 -315.59809) (xy 77.568774 -315.573483)
			(xy 77.61479 -315.556031) (xy 77.663009 -315.546187) (xy 77.712184 -315.544206) (xy 77.761039 -315.550138)
			(xy 77.80831 -315.56383) (xy 77.852772 -315.584928) (xy 77.893275 -315.612884) (xy 77.928768 -315.646976)
			(xy 77.958333 -315.68632) (xy 77.981204 -315.729897) (xy 77.996788 -315.776578) (xy 78.004683 -315.825155)
			(xy 78.005178 -315.849762) (xy 78.344026 -315.849762) (xy 78.347986 -315.800708) (xy 78.359763 -315.752924)
			(xy 78.379054 -315.707648) (xy 78.405357 -315.666052) (xy 78.437992 -315.629215) (xy 78.476113 -315.59809)
			(xy 78.518734 -315.573483) (xy 78.56475 -315.556031) (xy 78.612969 -315.546187) (xy 78.662144 -315.544206)
			(xy 78.710999 -315.550138) (xy 78.75827 -315.56383) (xy 78.802732 -315.584928) (xy 78.843235 -315.612884)
			(xy 78.878728 -315.646976) (xy 78.908293 -315.68632) (xy 78.931164 -315.729897) (xy 78.946748 -315.776578)
			(xy 78.954643 -315.825155) (xy 78.955138 -315.849762) (xy 79.293986 -315.849762) (xy 79.297946 -315.800708)
			(xy 79.309723 -315.752924) (xy 79.329014 -315.707648) (xy 79.355317 -315.666052) (xy 79.387952 -315.629215)
			(xy 79.426073 -315.59809) (xy 79.468694 -315.573483) (xy 79.51471 -315.556031) (xy 79.562929 -315.546187)
			(xy 79.612104 -315.544206) (xy 79.660959 -315.550138) (xy 79.70823 -315.56383) (xy 79.752692 -315.584928)
			(xy 79.793195 -315.612884) (xy 79.828688 -315.646976) (xy 79.858253 -315.68632) (xy 79.881124 -315.729897)
			(xy 79.896708 -315.776578) (xy 79.904603 -315.825155) (xy 79.905098 -315.849762) (xy 80.243946 -315.849762)
			(xy 80.247906 -315.800708) (xy 80.259683 -315.752924) (xy 80.278974 -315.707648) (xy 80.305277 -315.666052)
			(xy 80.337912 -315.629215) (xy 80.376033 -315.59809) (xy 80.418654 -315.573483) (xy 80.46467 -315.556031)
			(xy 80.512889 -315.546187) (xy 80.562064 -315.544206) (xy 80.610919 -315.550138) (xy 80.65819 -315.56383)
			(xy 80.702652 -315.584928) (xy 80.743155 -315.612884) (xy 80.778648 -315.646976) (xy 80.808213 -315.68632)
			(xy 80.831084 -315.729897) (xy 80.846668 -315.776578) (xy 80.854563 -315.825155) (xy 80.855058 -315.849762)
			(xy 81.19416 -315.849762) (xy 81.19812 -315.800708) (xy 81.209897 -315.752924) (xy 81.229188 -315.707648)
			(xy 81.255491 -315.666052) (xy 81.288126 -315.629215) (xy 81.326247 -315.59809) (xy 81.368868 -315.573483)
			(xy 81.414884 -315.556031) (xy 81.463103 -315.546187) (xy 81.512278 -315.544206) (xy 81.561133 -315.550138)
			(xy 81.608404 -315.56383) (xy 81.652866 -315.584928) (xy 81.693369 -315.612884) (xy 81.728862 -315.646976)
			(xy 81.758427 -315.68632) (xy 81.781298 -315.729897) (xy 81.796882 -315.776578) (xy 81.804777 -315.825155)
			(xy 81.805272 -315.849762) (xy 82.14412 -315.849762) (xy 82.14808 -315.800708) (xy 82.159857 -315.752924)
			(xy 82.179148 -315.707648) (xy 82.205451 -315.666052) (xy 82.238086 -315.629215) (xy 82.276207 -315.59809)
			(xy 82.318828 -315.573483) (xy 82.364844 -315.556031) (xy 82.413063 -315.546187) (xy 82.462238 -315.544206)
			(xy 82.511093 -315.550138) (xy 82.558364 -315.56383) (xy 82.602826 -315.584928) (xy 82.643329 -315.612884)
			(xy 82.678822 -315.646976) (xy 82.708387 -315.68632) (xy 82.731258 -315.729897) (xy 82.746842 -315.776578)
			(xy 82.754737 -315.825155) (xy 82.755232 -315.849762) (xy 82.754737 -315.874369) (xy 82.746842 -315.922946)
			(xy 82.731258 -315.969627) (xy 82.708387 -316.013204) (xy 82.678822 -316.052548) (xy 82.643329 -316.08664)
			(xy 82.602826 -316.114596) (xy 82.558364 -316.135694) (xy 82.511093 -316.149386) (xy 82.462238 -316.155318)
			(xy 82.413063 -316.153337) (xy 82.364844 -316.143493) (xy 82.318828 -316.126041) (xy 82.276207 -316.101434)
			(xy 82.238086 -316.070309) (xy 82.205451 -316.033472) (xy 82.179148 -315.991876) (xy 82.159857 -315.9466)
			(xy 82.14808 -315.898816) (xy 82.14412 -315.849762) (xy 81.805272 -315.849762) (xy 81.804777 -315.874369)
			(xy 81.796882 -315.922946) (xy 81.781298 -315.969627) (xy 81.758427 -316.013204) (xy 81.728862 -316.052548)
			(xy 81.693369 -316.08664) (xy 81.652866 -316.114596) (xy 81.608404 -316.135694) (xy 81.561133 -316.149386)
			(xy 81.512278 -316.155318) (xy 81.463103 -316.153337) (xy 81.414884 -316.143493) (xy 81.368868 -316.126041)
			(xy 81.326247 -316.101434) (xy 81.288126 -316.070309) (xy 81.255491 -316.033472) (xy 81.229188 -315.991876)
			(xy 81.209897 -315.9466) (xy 81.19812 -315.898816) (xy 81.19416 -315.849762) (xy 80.855058 -315.849762)
			(xy 80.854563 -315.874369) (xy 80.846668 -315.922946) (xy 80.831084 -315.969627) (xy 80.808213 -316.013204)
			(xy 80.778648 -316.052548) (xy 80.743155 -316.08664) (xy 80.702652 -316.114596) (xy 80.65819 -316.135694)
			(xy 80.610919 -316.149386) (xy 80.562064 -316.155318) (xy 80.512889 -316.153337) (xy 80.46467 -316.143493)
			(xy 80.418654 -316.126041) (xy 80.376033 -316.101434) (xy 80.337912 -316.070309) (xy 80.305277 -316.033472)
			(xy 80.278974 -315.991876) (xy 80.259683 -315.9466) (xy 80.247906 -315.898816) (xy 80.243946 -315.849762)
			(xy 79.905098 -315.849762) (xy 79.904603 -315.874369) (xy 79.896708 -315.922946) (xy 79.881124 -315.969627)
			(xy 79.858253 -316.013204) (xy 79.828688 -316.052548) (xy 79.793195 -316.08664) (xy 79.752692 -316.114596)
			(xy 79.70823 -316.135694) (xy 79.660959 -316.149386) (xy 79.612104 -316.155318) (xy 79.562929 -316.153337)
			(xy 79.51471 -316.143493) (xy 79.468694 -316.126041) (xy 79.426073 -316.101434) (xy 79.387952 -316.070309)
			(xy 79.355317 -316.033472) (xy 79.329014 -315.991876) (xy 79.309723 -315.9466) (xy 79.297946 -315.898816)
			(xy 79.293986 -315.849762) (xy 78.955138 -315.849762) (xy 78.954643 -315.874369) (xy 78.946748 -315.922946)
			(xy 78.931164 -315.969627) (xy 78.908293 -316.013204) (xy 78.878728 -316.052548) (xy 78.843235 -316.08664)
			(xy 78.802732 -316.114596) (xy 78.75827 -316.135694) (xy 78.710999 -316.149386) (xy 78.662144 -316.155318)
			(xy 78.612969 -316.153337) (xy 78.56475 -316.143493) (xy 78.518734 -316.126041) (xy 78.476113 -316.101434)
			(xy 78.437992 -316.070309) (xy 78.405357 -316.033472) (xy 78.379054 -315.991876) (xy 78.359763 -315.9466)
			(xy 78.347986 -315.898816) (xy 78.344026 -315.849762) (xy 78.005178 -315.849762) (xy 78.004683 -315.874369)
			(xy 77.996788 -315.922946) (xy 77.981204 -315.969627) (xy 77.958333 -316.013204) (xy 77.928768 -316.052548)
			(xy 77.893275 -316.08664) (xy 77.852772 -316.114596) (xy 77.80831 -316.135694) (xy 77.761039 -316.149386)
			(xy 77.712184 -316.155318) (xy 77.663009 -316.153337) (xy 77.61479 -316.143493) (xy 77.568774 -316.126041)
			(xy 77.526153 -316.101434) (xy 77.488032 -316.070309) (xy 77.455397 -316.033472) (xy 77.429094 -315.991876)
			(xy 77.409803 -315.9466) (xy 77.398026 -315.898816) (xy 77.394066 -315.849762) (xy 77.055218 -315.849762)
			(xy 77.054723 -315.874369) (xy 77.046828 -315.922946) (xy 77.031244 -315.969627) (xy 77.008373 -316.013204)
			(xy 76.978808 -316.052548) (xy 76.943315 -316.08664) (xy 76.902812 -316.114596) (xy 76.85835 -316.135694)
			(xy 76.811079 -316.149386) (xy 76.762224 -316.155318) (xy 76.713049 -316.153337) (xy 76.66483 -316.143493)
			(xy 76.618814 -316.126041) (xy 76.576193 -316.101434) (xy 76.538072 -316.070309) (xy 76.505437 -316.033472)
			(xy 76.479134 -315.991876) (xy 76.459843 -315.9466) (xy 76.448066 -315.898816) (xy 76.444106 -315.849762)
			(xy 76.105258 -315.849762) (xy 76.104763 -315.874369) (xy 76.096868 -315.922946) (xy 76.081284 -315.969627)
			(xy 76.058413 -316.013204) (xy 76.028848 -316.052548) (xy 75.993355 -316.08664) (xy 75.952852 -316.114596)
			(xy 75.90839 -316.135694) (xy 75.861119 -316.149386) (xy 75.812264 -316.155318) (xy 75.763089 -316.153337)
			(xy 75.71487 -316.143493) (xy 75.668854 -316.126041) (xy 75.626233 -316.101434) (xy 75.588112 -316.070309)
			(xy 75.555477 -316.033472) (xy 75.529174 -315.991876) (xy 75.509883 -315.9466) (xy 75.498106 -315.898816)
			(xy 75.494146 -315.849762) (xy 75.155298 -315.849762) (xy 75.154803 -315.874369) (xy 75.146908 -315.922946)
			(xy 75.131324 -315.969627) (xy 75.108453 -316.013204) (xy 75.078888 -316.052548) (xy 75.043395 -316.08664)
			(xy 75.002892 -316.114596) (xy 74.95843 -316.135694) (xy 74.911159 -316.149386) (xy 74.862304 -316.155318)
			(xy 74.813129 -316.153337) (xy 74.76491 -316.143493) (xy 74.718894 -316.126041) (xy 74.676273 -316.101434)
			(xy 74.638152 -316.070309) (xy 74.605517 -316.033472) (xy 74.579214 -315.991876) (xy 74.559923 -315.9466)
			(xy 74.548146 -315.898816) (xy 74.544186 -315.849762) (xy 74.205084 -315.849762) (xy 74.204589 -315.874369)
			(xy 74.196694 -315.922946) (xy 74.18111 -315.969627) (xy 74.158239 -316.013204) (xy 74.128674 -316.052548)
			(xy 74.093181 -316.08664) (xy 74.052678 -316.114596) (xy 74.008216 -316.135694) (xy 73.960945 -316.149386)
			(xy 73.91209 -316.155318) (xy 73.862915 -316.153337) (xy 73.814696 -316.143493) (xy 73.76868 -316.126041)
			(xy 73.726059 -316.101434) (xy 73.687938 -316.070309) (xy 73.655303 -316.033472) (xy 73.629 -315.991876)
			(xy 73.609709 -315.9466) (xy 73.597932 -315.898816) (xy 73.593972 -315.849762) (xy 73.255124 -315.849762)
			(xy 73.254629 -315.874369) (xy 73.246734 -315.922946) (xy 73.23115 -315.969627) (xy 73.208279 -316.013204)
			(xy 73.178714 -316.052548) (xy 73.143221 -316.08664) (xy 73.102718 -316.114596) (xy 73.058256 -316.135694)
			(xy 73.010985 -316.149386) (xy 72.96213 -316.155318) (xy 72.912955 -316.153337) (xy 72.864736 -316.143493)
			(xy 72.81872 -316.126041) (xy 72.776099 -316.101434) (xy 72.737978 -316.070309) (xy 72.705343 -316.033472)
			(xy 72.67904 -315.991876) (xy 72.659749 -315.9466) (xy 72.647972 -315.898816) (xy 72.644012 -315.849762)
			(xy 72.327008 -315.849762) (xy 72.326504 -315.87547) (xy 72.318461 -315.926252) (xy 72.302573 -315.975151)
			(xy 72.27923 -316.020963) (xy 72.249009 -316.062559) (xy 72.212653 -316.098915) (xy 72.171057 -316.129136)
			(xy 72.125245 -316.152479) (xy 72.076346 -316.168367) (xy 72.025564 -316.17641) (xy 71.974148 -316.17641)
			(xy 71.923366 -316.168367) (xy 71.874467 -316.152479) (xy 71.828655 -316.129136) (xy 71.787059 -316.098915)
			(xy 71.750703 -316.062559) (xy 71.720482 -316.020963) (xy 71.697139 -315.975151) (xy 71.681251 -315.926252)
			(xy 71.673208 -315.87547) (xy 71.35453 -315.87547) (xy 71.346814 -315.922946) (xy 71.33123 -315.969627)
			(xy 71.308359 -316.013204) (xy 71.278794 -316.052548) (xy 71.243301 -316.08664) (xy 71.202798 -316.114596)
			(xy 71.158336 -316.135694) (xy 71.111065 -316.149386) (xy 71.06221 -316.155318) (xy 71.013035 -316.153337)
			(xy 70.964816 -316.143493) (xy 70.9188 -316.126041) (xy 70.876179 -316.101434) (xy 70.838058 -316.070309)
			(xy 70.805423 -316.033472) (xy 70.77912 -315.991876) (xy 70.759829 -315.9466) (xy 70.748052 -315.898816)
			(xy 70.744092 -315.849762) (xy 70.427088 -315.849762) (xy 70.426584 -315.87547) (xy 70.418541 -315.926252)
			(xy 70.402653 -315.975151) (xy 70.37931 -316.020963) (xy 70.349089 -316.062559) (xy 70.312733 -316.098915)
			(xy 70.271137 -316.129136) (xy 70.225325 -316.152479) (xy 70.176426 -316.168367) (xy 70.125644 -316.17641)
			(xy 70.074228 -316.17641) (xy 70.023446 -316.168367) (xy 69.974547 -316.152479) (xy 69.928735 -316.129136)
			(xy 69.887139 -316.098915) (xy 69.850783 -316.062559) (xy 69.820562 -316.020963) (xy 69.797219 -315.975151)
			(xy 69.781331 -315.926252) (xy 69.773288 -315.87547) (xy 69.45461 -315.87547) (xy 69.446894 -315.922946)
			(xy 69.43131 -315.969627) (xy 69.408439 -316.013204) (xy 69.378874 -316.052548) (xy 69.343381 -316.08664)
			(xy 69.302878 -316.114596) (xy 69.258416 -316.135694) (xy 69.211145 -316.149386) (xy 69.16229 -316.155318)
			(xy 69.113115 -316.153337) (xy 69.064896 -316.143493) (xy 69.01888 -316.126041) (xy 68.976259 -316.101434)
			(xy 68.938138 -316.070309) (xy 68.905503 -316.033472) (xy 68.8792 -315.991876) (xy 68.859909 -315.9466)
			(xy 68.848132 -315.898816) (xy 68.844172 -315.849762) (xy 68.526914 -315.849762) (xy 68.52641 -315.87547)
			(xy 68.518367 -315.926252) (xy 68.502479 -315.975151) (xy 68.479136 -316.020963) (xy 68.448915 -316.062559)
			(xy 68.412559 -316.098915) (xy 68.370963 -316.129136) (xy 68.325151 -316.152479) (xy 68.276252 -316.168367)
			(xy 68.22547 -316.17641) (xy 68.174054 -316.17641) (xy 68.123272 -316.168367) (xy 68.074373 -316.152479)
			(xy 68.028561 -316.129136) (xy 67.986965 -316.098915) (xy 67.950609 -316.062559) (xy 67.920388 -316.020963)
			(xy 67.897045 -315.975151) (xy 67.881157 -315.926252) (xy 67.873114 -315.87547) (xy 67.554436 -315.87547)
			(xy 67.54672 -315.922946) (xy 67.531136 -315.969627) (xy 67.508265 -316.013204) (xy 67.4787 -316.052548)
			(xy 67.443207 -316.08664) (xy 67.402704 -316.114596) (xy 67.358242 -316.135694) (xy 67.310971 -316.149386)
			(xy 67.262116 -316.155318) (xy 67.212941 -316.153337) (xy 67.164722 -316.143493) (xy 67.118706 -316.126041)
			(xy 67.076085 -316.101434) (xy 67.037964 -316.070309) (xy 67.005329 -316.033472) (xy 66.979026 -315.991876)
			(xy 66.959735 -315.9466) (xy 66.947958 -315.898816) (xy 66.943998 -315.849762) (xy 66.626994 -315.849762)
			(xy 66.62649 -315.87547) (xy 66.618447 -315.926252) (xy 66.602559 -315.975151) (xy 66.579216 -316.020963)
			(xy 66.548995 -316.062559) (xy 66.512639 -316.098915) (xy 66.471043 -316.129136) (xy 66.425231 -316.152479)
			(xy 66.376332 -316.168367) (xy 66.32555 -316.17641) (xy 66.274134 -316.17641) (xy 66.223352 -316.168367)
			(xy 66.174453 -316.152479) (xy 66.128641 -316.129136) (xy 66.087045 -316.098915) (xy 66.050689 -316.062559)
			(xy 66.020468 -316.020963) (xy 65.997125 -315.975151) (xy 65.981237 -315.926252) (xy 65.973194 -315.87547)
			(xy 65.654516 -315.87547) (xy 65.6468 -315.922946) (xy 65.631216 -315.969627) (xy 65.608345 -316.013204)
			(xy 65.57878 -316.052548) (xy 65.543287 -316.08664) (xy 65.502784 -316.114596) (xy 65.458322 -316.135694)
			(xy 65.411051 -316.149386) (xy 65.362196 -316.155318) (xy 65.313021 -316.153337) (xy 65.264802 -316.143493)
			(xy 65.218786 -316.126041) (xy 65.176165 -316.101434) (xy 65.138044 -316.070309) (xy 65.105409 -316.033472)
			(xy 65.079106 -315.991876) (xy 65.059815 -315.9466) (xy 65.048038 -315.898816) (xy 65.044078 -315.849762)
			(xy 64.727074 -315.849762) (xy 64.72657 -315.87547) (xy 64.718527 -315.926252) (xy 64.702639 -315.975151)
			(xy 64.679296 -316.020963) (xy 64.649075 -316.062559) (xy 64.612719 -316.098915) (xy 64.571123 -316.129136)
			(xy 64.525311 -316.152479) (xy 64.476412 -316.168367) (xy 64.42563 -316.17641) (xy 64.374214 -316.17641)
			(xy 64.323432 -316.168367) (xy 64.274533 -316.152479) (xy 64.228721 -316.129136) (xy 64.187125 -316.098915)
			(xy 64.150769 -316.062559) (xy 64.120548 -316.020963) (xy 64.097205 -315.975151) (xy 64.081317 -315.926252)
			(xy 64.073274 -315.87547) (xy 63.754596 -315.87547) (xy 63.74688 -315.922946) (xy 63.731296 -315.969627)
			(xy 63.708425 -316.013204) (xy 63.67886 -316.052548) (xy 63.643367 -316.08664) (xy 63.602864 -316.114596)
			(xy 63.558402 -316.135694) (xy 63.511131 -316.149386) (xy 63.462276 -316.155318) (xy 63.413101 -316.153337)
			(xy 63.364882 -316.143493) (xy 63.318866 -316.126041) (xy 63.276245 -316.101434) (xy 63.238124 -316.070309)
			(xy 63.205489 -316.033472) (xy 63.179186 -315.991876) (xy 63.159895 -315.9466) (xy 63.148118 -315.898816)
			(xy 63.144158 -315.849762) (xy 62.8269 -315.849762) (xy 62.826396 -315.87547) (xy 62.818353 -315.926252)
			(xy 62.802465 -315.975151) (xy 62.779122 -316.020963) (xy 62.748901 -316.062559) (xy 62.712545 -316.098915)
			(xy 62.670949 -316.129136) (xy 62.625137 -316.152479) (xy 62.576238 -316.168367) (xy 62.525456 -316.17641)
			(xy 62.47404 -316.17641) (xy 62.423258 -316.168367) (xy 62.374359 -316.152479) (xy 62.328547 -316.129136)
			(xy 62.286951 -316.098915) (xy 62.250595 -316.062559) (xy 62.220374 -316.020963) (xy 62.197031 -315.975151)
			(xy 62.181143 -315.926252) (xy 62.1731 -315.87547) (xy 61.854422 -315.87547) (xy 61.846706 -315.922946)
			(xy 61.831122 -315.969627) (xy 61.808251 -316.013204) (xy 61.778686 -316.052548) (xy 61.743193 -316.08664)
			(xy 61.70269 -316.114596) (xy 61.658228 -316.135694) (xy 61.610957 -316.149386) (xy 61.562102 -316.155318)
			(xy 61.512927 -316.153337) (xy 61.464708 -316.143493) (xy 61.418692 -316.126041) (xy 61.376071 -316.101434)
			(xy 61.33795 -316.070309) (xy 61.305315 -316.033472) (xy 61.279012 -315.991876) (xy 61.259721 -315.9466)
			(xy 61.247944 -315.898816) (xy 61.243984 -315.849762) (xy 60.92698 -315.849762) (xy 60.926476 -315.87547)
			(xy 60.918433 -315.926252) (xy 60.902545 -315.975151) (xy 60.879202 -316.020963) (xy 60.848981 -316.062559)
			(xy 60.812625 -316.098915) (xy 60.771029 -316.129136) (xy 60.725217 -316.152479) (xy 60.676318 -316.168367)
			(xy 60.625536 -316.17641) (xy 60.57412 -316.17641) (xy 60.523338 -316.168367) (xy 60.474439 -316.152479)
			(xy 60.428627 -316.129136) (xy 60.387031 -316.098915) (xy 60.350675 -316.062559) (xy 60.320454 -316.020963)
			(xy 60.297111 -315.975151) (xy 60.281223 -315.926252) (xy 60.27318 -315.87547) (xy 59.954502 -315.87547)
			(xy 59.946786 -315.922946) (xy 59.931202 -315.969627) (xy 59.908331 -316.013204) (xy 59.878766 -316.052548)
			(xy 59.843273 -316.08664) (xy 59.80277 -316.114596) (xy 59.758308 -316.135694) (xy 59.711037 -316.149386)
			(xy 59.662182 -316.155318) (xy 59.613007 -316.153337) (xy 59.564788 -316.143493) (xy 59.518772 -316.126041)
			(xy 59.476151 -316.101434) (xy 59.43803 -316.070309) (xy 59.405395 -316.033472) (xy 59.379092 -315.991876)
			(xy 59.359801 -315.9466) (xy 59.348024 -315.898816) (xy 59.344064 -315.849762) (xy 59.040776 -315.849762)
			(xy 59.040776 -316.799722) (xy 59.344064 -316.799722) (xy 59.348024 -316.750668) (xy 59.359801 -316.702884)
			(xy 59.379092 -316.657608) (xy 59.405395 -316.616012) (xy 59.43803 -316.579175) (xy 59.476151 -316.54805)
			(xy 59.518772 -316.523443) (xy 59.564788 -316.505991) (xy 59.613007 -316.496147) (xy 59.662182 -316.494166)
			(xy 59.711037 -316.500098) (xy 59.758308 -316.51379) (xy 59.80277 -316.534888) (xy 59.843273 -316.562844)
			(xy 59.878766 -316.596936) (xy 59.908331 -316.63628) (xy 59.931202 -316.679857) (xy 59.946786 -316.726538)
			(xy 59.954681 -316.775115) (xy 59.955176 -316.799722) (xy 59.954681 -316.824329) (xy 59.954502 -316.82543)
			(xy 60.27318 -316.82543) (xy 60.27318 -316.774014) (xy 60.281223 -316.723232) (xy 60.297111 -316.674333)
			(xy 60.320454 -316.628521) (xy 60.350675 -316.586925) (xy 60.387031 -316.550569) (xy 60.428627 -316.520348)
			(xy 60.474439 -316.497005) (xy 60.523338 -316.481117) (xy 60.57412 -316.473074) (xy 60.625536 -316.473074)
			(xy 60.676318 -316.481117) (xy 60.725217 -316.497005) (xy 60.771029 -316.520348) (xy 60.812625 -316.550569)
			(xy 60.848981 -316.586925) (xy 60.879202 -316.628521) (xy 60.902545 -316.674333) (xy 60.918433 -316.723232)
			(xy 60.926476 -316.774014) (xy 60.92698 -316.799722) (xy 61.243984 -316.799722) (xy 61.247944 -316.750668)
			(xy 61.259721 -316.702884) (xy 61.279012 -316.657608) (xy 61.305315 -316.616012) (xy 61.33795 -316.579175)
			(xy 61.376071 -316.54805) (xy 61.418692 -316.523443) (xy 61.464708 -316.505991) (xy 61.512927 -316.496147)
			(xy 61.562102 -316.494166) (xy 61.610957 -316.500098) (xy 61.658228 -316.51379) (xy 61.70269 -316.534888)
			(xy 61.743193 -316.562844) (xy 61.778686 -316.596936) (xy 61.808251 -316.63628) (xy 61.831122 -316.679857)
			(xy 61.846706 -316.726538) (xy 61.854601 -316.775115) (xy 61.855096 -316.799722) (xy 61.854601 -316.824329)
			(xy 61.854422 -316.82543) (xy 62.1731 -316.82543) (xy 62.1731 -316.774014) (xy 62.181143 -316.723232)
			(xy 62.197031 -316.674333) (xy 62.220374 -316.628521) (xy 62.250595 -316.586925) (xy 62.286951 -316.550569)
			(xy 62.328547 -316.520348) (xy 62.374359 -316.497005) (xy 62.423258 -316.481117) (xy 62.47404 -316.473074)
			(xy 62.525456 -316.473074) (xy 62.576238 -316.481117) (xy 62.625137 -316.497005) (xy 62.670949 -316.520348)
			(xy 62.712545 -316.550569) (xy 62.748901 -316.586925) (xy 62.779122 -316.628521) (xy 62.802465 -316.674333)
			(xy 62.818353 -316.723232) (xy 62.826396 -316.774014) (xy 62.8269 -316.799722) (xy 63.144158 -316.799722)
			(xy 63.148118 -316.750668) (xy 63.159895 -316.702884) (xy 63.179186 -316.657608) (xy 63.205489 -316.616012)
			(xy 63.238124 -316.579175) (xy 63.276245 -316.54805) (xy 63.318866 -316.523443) (xy 63.364882 -316.505991)
			(xy 63.413101 -316.496147) (xy 63.462276 -316.494166) (xy 63.511131 -316.500098) (xy 63.558402 -316.51379)
			(xy 63.602864 -316.534888) (xy 63.643367 -316.562844) (xy 63.67886 -316.596936) (xy 63.708425 -316.63628)
			(xy 63.731296 -316.679857) (xy 63.74688 -316.726538) (xy 63.754775 -316.775115) (xy 63.75527 -316.799722)
			(xy 63.754775 -316.824329) (xy 63.754596 -316.82543) (xy 64.073274 -316.82543) (xy 64.073274 -316.774014)
			(xy 64.081317 -316.723232) (xy 64.097205 -316.674333) (xy 64.120548 -316.628521) (xy 64.150769 -316.586925)
			(xy 64.187125 -316.550569) (xy 64.228721 -316.520348) (xy 64.274533 -316.497005) (xy 64.323432 -316.481117)
			(xy 64.374214 -316.473074) (xy 64.42563 -316.473074) (xy 64.476412 -316.481117) (xy 64.525311 -316.497005)
			(xy 64.571123 -316.520348) (xy 64.612719 -316.550569) (xy 64.649075 -316.586925) (xy 64.679296 -316.628521)
			(xy 64.702639 -316.674333) (xy 64.718527 -316.723232) (xy 64.72657 -316.774014) (xy 64.727074 -316.799722)
			(xy 65.044078 -316.799722) (xy 65.048038 -316.750668) (xy 65.059815 -316.702884) (xy 65.079106 -316.657608)
			(xy 65.105409 -316.616012) (xy 65.138044 -316.579175) (xy 65.176165 -316.54805) (xy 65.218786 -316.523443)
			(xy 65.264802 -316.505991) (xy 65.313021 -316.496147) (xy 65.362196 -316.494166) (xy 65.411051 -316.500098)
			(xy 65.458322 -316.51379) (xy 65.502784 -316.534888) (xy 65.543287 -316.562844) (xy 65.57878 -316.596936)
			(xy 65.608345 -316.63628) (xy 65.631216 -316.679857) (xy 65.6468 -316.726538) (xy 65.654695 -316.775115)
			(xy 65.65519 -316.799722) (xy 65.654695 -316.824329) (xy 65.654516 -316.82543) (xy 65.973194 -316.82543)
			(xy 65.973194 -316.774014) (xy 65.981237 -316.723232) (xy 65.997125 -316.674333) (xy 66.020468 -316.628521)
			(xy 66.050689 -316.586925) (xy 66.087045 -316.550569) (xy 66.128641 -316.520348) (xy 66.174453 -316.497005)
			(xy 66.223352 -316.481117) (xy 66.274134 -316.473074) (xy 66.32555 -316.473074) (xy 66.376332 -316.481117)
			(xy 66.425231 -316.497005) (xy 66.471043 -316.520348) (xy 66.512639 -316.550569) (xy 66.548995 -316.586925)
			(xy 66.579216 -316.628521) (xy 66.602559 -316.674333) (xy 66.618447 -316.723232) (xy 66.62649 -316.774014)
			(xy 66.626994 -316.799722) (xy 66.943998 -316.799722) (xy 66.947958 -316.750668) (xy 66.959735 -316.702884)
			(xy 66.979026 -316.657608) (xy 67.005329 -316.616012) (xy 67.037964 -316.579175) (xy 67.076085 -316.54805)
			(xy 67.118706 -316.523443) (xy 67.164722 -316.505991) (xy 67.212941 -316.496147) (xy 67.262116 -316.494166)
			(xy 67.310971 -316.500098) (xy 67.358242 -316.51379) (xy 67.402704 -316.534888) (xy 67.443207 -316.562844)
			(xy 67.4787 -316.596936) (xy 67.508265 -316.63628) (xy 67.531136 -316.679857) (xy 67.54672 -316.726538)
			(xy 67.554615 -316.775115) (xy 67.55511 -316.799722) (xy 67.554615 -316.824329) (xy 67.554436 -316.82543)
			(xy 67.873114 -316.82543) (xy 67.873114 -316.774014) (xy 67.881157 -316.723232) (xy 67.897045 -316.674333)
			(xy 67.920388 -316.628521) (xy 67.950609 -316.586925) (xy 67.986965 -316.550569) (xy 68.028561 -316.520348)
			(xy 68.074373 -316.497005) (xy 68.123272 -316.481117) (xy 68.174054 -316.473074) (xy 68.22547 -316.473074)
			(xy 68.276252 -316.481117) (xy 68.325151 -316.497005) (xy 68.370963 -316.520348) (xy 68.412559 -316.550569)
			(xy 68.448915 -316.586925) (xy 68.479136 -316.628521) (xy 68.502479 -316.674333) (xy 68.518367 -316.723232)
			(xy 68.52641 -316.774014) (xy 68.526914 -316.799722) (xy 68.844172 -316.799722) (xy 68.848132 -316.750668)
			(xy 68.859909 -316.702884) (xy 68.8792 -316.657608) (xy 68.905503 -316.616012) (xy 68.938138 -316.579175)
			(xy 68.976259 -316.54805) (xy 69.01888 -316.523443) (xy 69.064896 -316.505991) (xy 69.113115 -316.496147)
			(xy 69.16229 -316.494166) (xy 69.211145 -316.500098) (xy 69.258416 -316.51379) (xy 69.302878 -316.534888)
			(xy 69.343381 -316.562844) (xy 69.378874 -316.596936) (xy 69.408439 -316.63628) (xy 69.43131 -316.679857)
			(xy 69.446894 -316.726538) (xy 69.454789 -316.775115) (xy 69.455284 -316.799722) (xy 69.454789 -316.824329)
			(xy 69.45461 -316.82543) (xy 69.773288 -316.82543) (xy 69.773288 -316.774014) (xy 69.781331 -316.723232)
			(xy 69.797219 -316.674333) (xy 69.820562 -316.628521) (xy 69.850783 -316.586925) (xy 69.887139 -316.550569)
			(xy 69.928735 -316.520348) (xy 69.974547 -316.497005) (xy 70.023446 -316.481117) (xy 70.074228 -316.473074)
			(xy 70.125644 -316.473074) (xy 70.176426 -316.481117) (xy 70.225325 -316.497005) (xy 70.271137 -316.520348)
			(xy 70.312733 -316.550569) (xy 70.349089 -316.586925) (xy 70.37931 -316.628521) (xy 70.402653 -316.674333)
			(xy 70.418541 -316.723232) (xy 70.426584 -316.774014) (xy 70.427088 -316.799722) (xy 70.744092 -316.799722)
			(xy 70.748052 -316.750668) (xy 70.759829 -316.702884) (xy 70.77912 -316.657608) (xy 70.805423 -316.616012)
			(xy 70.838058 -316.579175) (xy 70.876179 -316.54805) (xy 70.9188 -316.523443) (xy 70.964816 -316.505991)
			(xy 71.013035 -316.496147) (xy 71.06221 -316.494166) (xy 71.111065 -316.500098) (xy 71.158336 -316.51379)
			(xy 71.202798 -316.534888) (xy 71.243301 -316.562844) (xy 71.278794 -316.596936) (xy 71.308359 -316.63628)
			(xy 71.33123 -316.679857) (xy 71.346814 -316.726538) (xy 71.354709 -316.775115) (xy 71.355204 -316.799722)
			(xy 71.354709 -316.824329) (xy 71.35453 -316.82543) (xy 71.673208 -316.82543) (xy 71.673208 -316.774014)
			(xy 71.681251 -316.723232) (xy 71.697139 -316.674333) (xy 71.720482 -316.628521) (xy 71.750703 -316.586925)
			(xy 71.787059 -316.550569) (xy 71.828655 -316.520348) (xy 71.874467 -316.497005) (xy 71.923366 -316.481117)
			(xy 71.974148 -316.473074) (xy 72.025564 -316.473074) (xy 72.076346 -316.481117) (xy 72.125245 -316.497005)
			(xy 72.171057 -316.520348) (xy 72.212653 -316.550569) (xy 72.249009 -316.586925) (xy 72.27923 -316.628521)
			(xy 72.302573 -316.674333) (xy 72.318461 -316.723232) (xy 72.326504 -316.774014) (xy 72.327008 -316.799722)
			(xy 72.644012 -316.799722) (xy 72.647972 -316.750668) (xy 72.659749 -316.702884) (xy 72.67904 -316.657608)
			(xy 72.705343 -316.616012) (xy 72.737978 -316.579175) (xy 72.776099 -316.54805) (xy 72.81872 -316.523443)
			(xy 72.864736 -316.505991) (xy 72.912955 -316.496147) (xy 72.96213 -316.494166) (xy 73.010985 -316.500098)
			(xy 73.058256 -316.51379) (xy 73.102718 -316.534888) (xy 73.143221 -316.562844) (xy 73.178714 -316.596936)
			(xy 73.208279 -316.63628) (xy 73.23115 -316.679857) (xy 73.246734 -316.726538) (xy 73.254629 -316.775115)
			(xy 73.255124 -316.799722) (xy 73.593972 -316.799722) (xy 73.597932 -316.750668) (xy 73.609709 -316.702884)
			(xy 73.629 -316.657608) (xy 73.655303 -316.616012) (xy 73.687938 -316.579175) (xy 73.726059 -316.54805)
			(xy 73.76868 -316.523443) (xy 73.814696 -316.505991) (xy 73.862915 -316.496147) (xy 73.91209 -316.494166)
			(xy 73.960945 -316.500098) (xy 74.008216 -316.51379) (xy 74.052678 -316.534888) (xy 74.093181 -316.562844)
			(xy 74.128674 -316.596936) (xy 74.158239 -316.63628) (xy 74.18111 -316.679857) (xy 74.196694 -316.726538)
			(xy 74.204589 -316.775115) (xy 74.205084 -316.799722) (xy 74.544186 -316.799722) (xy 74.548146 -316.750668)
			(xy 74.559923 -316.702884) (xy 74.579214 -316.657608) (xy 74.605517 -316.616012) (xy 74.638152 -316.579175)
			(xy 74.676273 -316.54805) (xy 74.718894 -316.523443) (xy 74.76491 -316.505991) (xy 74.813129 -316.496147)
			(xy 74.862304 -316.494166) (xy 74.911159 -316.500098) (xy 74.95843 -316.51379) (xy 75.002892 -316.534888)
			(xy 75.043395 -316.562844) (xy 75.078888 -316.596936) (xy 75.108453 -316.63628) (xy 75.131324 -316.679857)
			(xy 75.146908 -316.726538) (xy 75.154803 -316.775115) (xy 75.155298 -316.799722) (xy 75.494146 -316.799722)
			(xy 75.498106 -316.750668) (xy 75.509883 -316.702884) (xy 75.529174 -316.657608) (xy 75.555477 -316.616012)
			(xy 75.588112 -316.579175) (xy 75.626233 -316.54805) (xy 75.668854 -316.523443) (xy 75.71487 -316.505991)
			(xy 75.763089 -316.496147) (xy 75.812264 -316.494166) (xy 75.861119 -316.500098) (xy 75.90839 -316.51379)
			(xy 75.952852 -316.534888) (xy 75.993355 -316.562844) (xy 76.028848 -316.596936) (xy 76.058413 -316.63628)
			(xy 76.081284 -316.679857) (xy 76.096868 -316.726538) (xy 76.104763 -316.775115) (xy 76.105258 -316.799722)
			(xy 76.444106 -316.799722) (xy 76.448066 -316.750668) (xy 76.459843 -316.702884) (xy 76.479134 -316.657608)
			(xy 76.505437 -316.616012) (xy 76.538072 -316.579175) (xy 76.576193 -316.54805) (xy 76.618814 -316.523443)
			(xy 76.66483 -316.505991) (xy 76.713049 -316.496147) (xy 76.762224 -316.494166) (xy 76.811079 -316.500098)
			(xy 76.85835 -316.51379) (xy 76.902812 -316.534888) (xy 76.943315 -316.562844) (xy 76.978808 -316.596936)
			(xy 77.008373 -316.63628) (xy 77.031244 -316.679857) (xy 77.046828 -316.726538) (xy 77.054723 -316.775115)
			(xy 77.055218 -316.799722) (xy 77.394066 -316.799722) (xy 77.398026 -316.750668) (xy 77.409803 -316.702884)
			(xy 77.429094 -316.657608) (xy 77.455397 -316.616012) (xy 77.488032 -316.579175) (xy 77.526153 -316.54805)
			(xy 77.568774 -316.523443) (xy 77.61479 -316.505991) (xy 77.663009 -316.496147) (xy 77.712184 -316.494166)
			(xy 77.761039 -316.500098) (xy 77.80831 -316.51379) (xy 77.852772 -316.534888) (xy 77.893275 -316.562844)
			(xy 77.928768 -316.596936) (xy 77.958333 -316.63628) (xy 77.981204 -316.679857) (xy 77.996788 -316.726538)
			(xy 78.004683 -316.775115) (xy 78.005178 -316.799722) (xy 78.344026 -316.799722) (xy 78.347986 -316.750668)
			(xy 78.359763 -316.702884) (xy 78.379054 -316.657608) (xy 78.405357 -316.616012) (xy 78.437992 -316.579175)
			(xy 78.476113 -316.54805) (xy 78.518734 -316.523443) (xy 78.56475 -316.505991) (xy 78.612969 -316.496147)
			(xy 78.662144 -316.494166) (xy 78.710999 -316.500098) (xy 78.75827 -316.51379) (xy 78.802732 -316.534888)
			(xy 78.843235 -316.562844) (xy 78.878728 -316.596936) (xy 78.908293 -316.63628) (xy 78.931164 -316.679857)
			(xy 78.946748 -316.726538) (xy 78.954643 -316.775115) (xy 78.955138 -316.799722) (xy 79.293986 -316.799722)
			(xy 79.297946 -316.750668) (xy 79.309723 -316.702884) (xy 79.329014 -316.657608) (xy 79.355317 -316.616012)
			(xy 79.387952 -316.579175) (xy 79.426073 -316.54805) (xy 79.468694 -316.523443) (xy 79.51471 -316.505991)
			(xy 79.562929 -316.496147) (xy 79.612104 -316.494166) (xy 79.660959 -316.500098) (xy 79.70823 -316.51379)
			(xy 79.752692 -316.534888) (xy 79.793195 -316.562844) (xy 79.828688 -316.596936) (xy 79.858253 -316.63628)
			(xy 79.881124 -316.679857) (xy 79.896708 -316.726538) (xy 79.904603 -316.775115) (xy 79.905098 -316.799722)
			(xy 80.243946 -316.799722) (xy 80.247906 -316.750668) (xy 80.259683 -316.702884) (xy 80.278974 -316.657608)
			(xy 80.305277 -316.616012) (xy 80.337912 -316.579175) (xy 80.376033 -316.54805) (xy 80.418654 -316.523443)
			(xy 80.46467 -316.505991) (xy 80.512889 -316.496147) (xy 80.562064 -316.494166) (xy 80.610919 -316.500098)
			(xy 80.65819 -316.51379) (xy 80.702652 -316.534888) (xy 80.743155 -316.562844) (xy 80.778648 -316.596936)
			(xy 80.808213 -316.63628) (xy 80.831084 -316.679857) (xy 80.846668 -316.726538) (xy 80.854563 -316.775115)
			(xy 80.855058 -316.799722) (xy 81.19416 -316.799722) (xy 81.19812 -316.750668) (xy 81.209897 -316.702884)
			(xy 81.229188 -316.657608) (xy 81.255491 -316.616012) (xy 81.288126 -316.579175) (xy 81.326247 -316.54805)
			(xy 81.368868 -316.523443) (xy 81.414884 -316.505991) (xy 81.463103 -316.496147) (xy 81.512278 -316.494166)
			(xy 81.561133 -316.500098) (xy 81.608404 -316.51379) (xy 81.652866 -316.534888) (xy 81.693369 -316.562844)
			(xy 81.728862 -316.596936) (xy 81.758427 -316.63628) (xy 81.781298 -316.679857) (xy 81.796882 -316.726538)
			(xy 81.804777 -316.775115) (xy 81.805272 -316.799722) (xy 82.14412 -316.799722) (xy 82.14808 -316.750668)
			(xy 82.159857 -316.702884) (xy 82.179148 -316.657608) (xy 82.205451 -316.616012) (xy 82.238086 -316.579175)
			(xy 82.276207 -316.54805) (xy 82.318828 -316.523443) (xy 82.364844 -316.505991) (xy 82.413063 -316.496147)
			(xy 82.462238 -316.494166) (xy 82.511093 -316.500098) (xy 82.558364 -316.51379) (xy 82.602826 -316.534888)
			(xy 82.643329 -316.562844) (xy 82.678822 -316.596936) (xy 82.708387 -316.63628) (xy 82.731258 -316.679857)
			(xy 82.746842 -316.726538) (xy 82.754737 -316.775115) (xy 82.755232 -316.799722) (xy 83.094334 -316.799722)
			(xy 83.098294 -316.750668) (xy 83.110071 -316.702884) (xy 83.129362 -316.657608) (xy 83.155665 -316.616012)
			(xy 83.1883 -316.579175) (xy 83.226421 -316.54805) (xy 83.269042 -316.523443) (xy 83.315058 -316.505991)
			(xy 83.363277 -316.496147) (xy 83.412452 -316.494166) (xy 83.461307 -316.500098) (xy 83.508578 -316.51379)
			(xy 83.55304 -316.534888) (xy 83.593543 -316.562844) (xy 83.629036 -316.596936) (xy 83.658601 -316.63628)
			(xy 83.681472 -316.679857) (xy 83.697056 -316.726538) (xy 83.704951 -316.775115) (xy 83.705446 -316.799722)
			(xy 83.704951 -316.824329) (xy 83.697056 -316.872906) (xy 83.681472 -316.919587) (xy 83.658601 -316.963164)
			(xy 83.629036 -317.002508) (xy 83.593543 -317.0366) (xy 83.55304 -317.064556) (xy 83.508578 -317.085654)
			(xy 83.461307 -317.099346) (xy 83.412452 -317.105278) (xy 83.363277 -317.103297) (xy 83.315058 -317.093453)
			(xy 83.269042 -317.076001) (xy 83.226421 -317.051394) (xy 83.1883 -317.020269) (xy 83.155665 -316.983432)
			(xy 83.129362 -316.941836) (xy 83.110071 -316.89656) (xy 83.098294 -316.848776) (xy 83.094334 -316.799722)
			(xy 82.755232 -316.799722) (xy 82.754737 -316.824329) (xy 82.746842 -316.872906) (xy 82.731258 -316.919587)
			(xy 82.708387 -316.963164) (xy 82.678822 -317.002508) (xy 82.643329 -317.0366) (xy 82.602826 -317.064556)
			(xy 82.558364 -317.085654) (xy 82.511093 -317.099346) (xy 82.462238 -317.105278) (xy 82.413063 -317.103297)
			(xy 82.364844 -317.093453) (xy 82.318828 -317.076001) (xy 82.276207 -317.051394) (xy 82.238086 -317.020269)
			(xy 82.205451 -316.983432) (xy 82.179148 -316.941836) (xy 82.159857 -316.89656) (xy 82.14808 -316.848776)
			(xy 82.14412 -316.799722) (xy 81.805272 -316.799722) (xy 81.804777 -316.824329) (xy 81.796882 -316.872906)
			(xy 81.781298 -316.919587) (xy 81.758427 -316.963164) (xy 81.728862 -317.002508) (xy 81.693369 -317.0366)
			(xy 81.652866 -317.064556) (xy 81.608404 -317.085654) (xy 81.561133 -317.099346) (xy 81.512278 -317.105278)
			(xy 81.463103 -317.103297) (xy 81.414884 -317.093453) (xy 81.368868 -317.076001) (xy 81.326247 -317.051394)
			(xy 81.288126 -317.020269) (xy 81.255491 -316.983432) (xy 81.229188 -316.941836) (xy 81.209897 -316.89656)
			(xy 81.19812 -316.848776) (xy 81.19416 -316.799722) (xy 80.855058 -316.799722) (xy 80.854563 -316.824329)
			(xy 80.846668 -316.872906) (xy 80.831084 -316.919587) (xy 80.808213 -316.963164) (xy 80.778648 -317.002508)
			(xy 80.743155 -317.0366) (xy 80.702652 -317.064556) (xy 80.65819 -317.085654) (xy 80.610919 -317.099346)
			(xy 80.562064 -317.105278) (xy 80.512889 -317.103297) (xy 80.46467 -317.093453) (xy 80.418654 -317.076001)
			(xy 80.376033 -317.051394) (xy 80.337912 -317.020269) (xy 80.305277 -316.983432) (xy 80.278974 -316.941836)
			(xy 80.259683 -316.89656) (xy 80.247906 -316.848776) (xy 80.243946 -316.799722) (xy 79.905098 -316.799722)
			(xy 79.904603 -316.824329) (xy 79.896708 -316.872906) (xy 79.881124 -316.919587) (xy 79.858253 -316.963164)
			(xy 79.828688 -317.002508) (xy 79.793195 -317.0366) (xy 79.752692 -317.064556) (xy 79.70823 -317.085654)
			(xy 79.660959 -317.099346) (xy 79.612104 -317.105278) (xy 79.562929 -317.103297) (xy 79.51471 -317.093453)
			(xy 79.468694 -317.076001) (xy 79.426073 -317.051394) (xy 79.387952 -317.020269) (xy 79.355317 -316.983432)
			(xy 79.329014 -316.941836) (xy 79.309723 -316.89656) (xy 79.297946 -316.848776) (xy 79.293986 -316.799722)
			(xy 78.955138 -316.799722) (xy 78.954643 -316.824329) (xy 78.946748 -316.872906) (xy 78.931164 -316.919587)
			(xy 78.908293 -316.963164) (xy 78.878728 -317.002508) (xy 78.843235 -317.0366) (xy 78.802732 -317.064556)
			(xy 78.75827 -317.085654) (xy 78.710999 -317.099346) (xy 78.662144 -317.105278) (xy 78.612969 -317.103297)
			(xy 78.56475 -317.093453) (xy 78.518734 -317.076001) (xy 78.476113 -317.051394) (xy 78.437992 -317.020269)
			(xy 78.405357 -316.983432) (xy 78.379054 -316.941836) (xy 78.359763 -316.89656) (xy 78.347986 -316.848776)
			(xy 78.344026 -316.799722) (xy 78.005178 -316.799722) (xy 78.004683 -316.824329) (xy 77.996788 -316.872906)
			(xy 77.981204 -316.919587) (xy 77.958333 -316.963164) (xy 77.928768 -317.002508) (xy 77.893275 -317.0366)
			(xy 77.852772 -317.064556) (xy 77.80831 -317.085654) (xy 77.761039 -317.099346) (xy 77.712184 -317.105278)
			(xy 77.663009 -317.103297) (xy 77.61479 -317.093453) (xy 77.568774 -317.076001) (xy 77.526153 -317.051394)
			(xy 77.488032 -317.020269) (xy 77.455397 -316.983432) (xy 77.429094 -316.941836) (xy 77.409803 -316.89656)
			(xy 77.398026 -316.848776) (xy 77.394066 -316.799722) (xy 77.055218 -316.799722) (xy 77.054723 -316.824329)
			(xy 77.046828 -316.872906) (xy 77.031244 -316.919587) (xy 77.008373 -316.963164) (xy 76.978808 -317.002508)
			(xy 76.943315 -317.0366) (xy 76.902812 -317.064556) (xy 76.85835 -317.085654) (xy 76.811079 -317.099346)
			(xy 76.762224 -317.105278) (xy 76.713049 -317.103297) (xy 76.66483 -317.093453) (xy 76.618814 -317.076001)
			(xy 76.576193 -317.051394) (xy 76.538072 -317.020269) (xy 76.505437 -316.983432) (xy 76.479134 -316.941836)
			(xy 76.459843 -316.89656) (xy 76.448066 -316.848776) (xy 76.444106 -316.799722) (xy 76.105258 -316.799722)
			(xy 76.104763 -316.824329) (xy 76.096868 -316.872906) (xy 76.081284 -316.919587) (xy 76.058413 -316.963164)
			(xy 76.028848 -317.002508) (xy 75.993355 -317.0366) (xy 75.952852 -317.064556) (xy 75.90839 -317.085654)
			(xy 75.861119 -317.099346) (xy 75.812264 -317.105278) (xy 75.763089 -317.103297) (xy 75.71487 -317.093453)
			(xy 75.668854 -317.076001) (xy 75.626233 -317.051394) (xy 75.588112 -317.020269) (xy 75.555477 -316.983432)
			(xy 75.529174 -316.941836) (xy 75.509883 -316.89656) (xy 75.498106 -316.848776) (xy 75.494146 -316.799722)
			(xy 75.155298 -316.799722) (xy 75.154803 -316.824329) (xy 75.146908 -316.872906) (xy 75.131324 -316.919587)
			(xy 75.108453 -316.963164) (xy 75.078888 -317.002508) (xy 75.043395 -317.0366) (xy 75.002892 -317.064556)
			(xy 74.95843 -317.085654) (xy 74.911159 -317.099346) (xy 74.862304 -317.105278) (xy 74.813129 -317.103297)
			(xy 74.76491 -317.093453) (xy 74.718894 -317.076001) (xy 74.676273 -317.051394) (xy 74.638152 -317.020269)
			(xy 74.605517 -316.983432) (xy 74.579214 -316.941836) (xy 74.559923 -316.89656) (xy 74.548146 -316.848776)
			(xy 74.544186 -316.799722) (xy 74.205084 -316.799722) (xy 74.204589 -316.824329) (xy 74.196694 -316.872906)
			(xy 74.18111 -316.919587) (xy 74.158239 -316.963164) (xy 74.128674 -317.002508) (xy 74.093181 -317.0366)
			(xy 74.052678 -317.064556) (xy 74.008216 -317.085654) (xy 73.960945 -317.099346) (xy 73.91209 -317.105278)
			(xy 73.862915 -317.103297) (xy 73.814696 -317.093453) (xy 73.76868 -317.076001) (xy 73.726059 -317.051394)
			(xy 73.687938 -317.020269) (xy 73.655303 -316.983432) (xy 73.629 -316.941836) (xy 73.609709 -316.89656)
			(xy 73.597932 -316.848776) (xy 73.593972 -316.799722) (xy 73.255124 -316.799722) (xy 73.254629 -316.824329)
			(xy 73.246734 -316.872906) (xy 73.23115 -316.919587) (xy 73.208279 -316.963164) (xy 73.178714 -317.002508)
			(xy 73.143221 -317.0366) (xy 73.102718 -317.064556) (xy 73.058256 -317.085654) (xy 73.010985 -317.099346)
			(xy 72.96213 -317.105278) (xy 72.912955 -317.103297) (xy 72.864736 -317.093453) (xy 72.81872 -317.076001)
			(xy 72.776099 -317.051394) (xy 72.737978 -317.020269) (xy 72.705343 -316.983432) (xy 72.67904 -316.941836)
			(xy 72.659749 -316.89656) (xy 72.647972 -316.848776) (xy 72.644012 -316.799722) (xy 72.327008 -316.799722)
			(xy 72.326504 -316.82543) (xy 72.318461 -316.876212) (xy 72.302573 -316.925111) (xy 72.27923 -316.970923)
			(xy 72.249009 -317.012519) (xy 72.212653 -317.048875) (xy 72.171057 -317.079096) (xy 72.125245 -317.102439)
			(xy 72.076346 -317.118327) (xy 72.025564 -317.12637) (xy 71.974148 -317.12637) (xy 71.923366 -317.118327)
			(xy 71.874467 -317.102439) (xy 71.828655 -317.079096) (xy 71.787059 -317.048875) (xy 71.750703 -317.012519)
			(xy 71.720482 -316.970923) (xy 71.697139 -316.925111) (xy 71.681251 -316.876212) (xy 71.673208 -316.82543)
			(xy 71.35453 -316.82543) (xy 71.346814 -316.872906) (xy 71.33123 -316.919587) (xy 71.308359 -316.963164)
			(xy 71.278794 -317.002508) (xy 71.243301 -317.0366) (xy 71.202798 -317.064556) (xy 71.158336 -317.085654)
			(xy 71.111065 -317.099346) (xy 71.06221 -317.105278) (xy 71.013035 -317.103297) (xy 70.964816 -317.093453)
			(xy 70.9188 -317.076001) (xy 70.876179 -317.051394) (xy 70.838058 -317.020269) (xy 70.805423 -316.983432)
			(xy 70.77912 -316.941836) (xy 70.759829 -316.89656) (xy 70.748052 -316.848776) (xy 70.744092 -316.799722)
			(xy 70.427088 -316.799722) (xy 70.426584 -316.82543) (xy 70.418541 -316.876212) (xy 70.402653 -316.925111)
			(xy 70.37931 -316.970923) (xy 70.349089 -317.012519) (xy 70.312733 -317.048875) (xy 70.271137 -317.079096)
			(xy 70.225325 -317.102439) (xy 70.176426 -317.118327) (xy 70.125644 -317.12637) (xy 70.074228 -317.12637)
			(xy 70.023446 -317.118327) (xy 69.974547 -317.102439) (xy 69.928735 -317.079096) (xy 69.887139 -317.048875)
			(xy 69.850783 -317.012519) (xy 69.820562 -316.970923) (xy 69.797219 -316.925111) (xy 69.781331 -316.876212)
			(xy 69.773288 -316.82543) (xy 69.45461 -316.82543) (xy 69.446894 -316.872906) (xy 69.43131 -316.919587)
			(xy 69.408439 -316.963164) (xy 69.378874 -317.002508) (xy 69.343381 -317.0366) (xy 69.302878 -317.064556)
			(xy 69.258416 -317.085654) (xy 69.211145 -317.099346) (xy 69.16229 -317.105278) (xy 69.113115 -317.103297)
			(xy 69.064896 -317.093453) (xy 69.01888 -317.076001) (xy 68.976259 -317.051394) (xy 68.938138 -317.020269)
			(xy 68.905503 -316.983432) (xy 68.8792 -316.941836) (xy 68.859909 -316.89656) (xy 68.848132 -316.848776)
			(xy 68.844172 -316.799722) (xy 68.526914 -316.799722) (xy 68.52641 -316.82543) (xy 68.518367 -316.876212)
			(xy 68.502479 -316.925111) (xy 68.479136 -316.970923) (xy 68.448915 -317.012519) (xy 68.412559 -317.048875)
			(xy 68.370963 -317.079096) (xy 68.325151 -317.102439) (xy 68.276252 -317.118327) (xy 68.22547 -317.12637)
			(xy 68.174054 -317.12637) (xy 68.123272 -317.118327) (xy 68.074373 -317.102439) (xy 68.028561 -317.079096)
			(xy 67.986965 -317.048875) (xy 67.950609 -317.012519) (xy 67.920388 -316.970923) (xy 67.897045 -316.925111)
			(xy 67.881157 -316.876212) (xy 67.873114 -316.82543) (xy 67.554436 -316.82543) (xy 67.54672 -316.872906)
			(xy 67.531136 -316.919587) (xy 67.508265 -316.963164) (xy 67.4787 -317.002508) (xy 67.443207 -317.0366)
			(xy 67.402704 -317.064556) (xy 67.358242 -317.085654) (xy 67.310971 -317.099346) (xy 67.262116 -317.105278)
			(xy 67.212941 -317.103297) (xy 67.164722 -317.093453) (xy 67.118706 -317.076001) (xy 67.076085 -317.051394)
			(xy 67.037964 -317.020269) (xy 67.005329 -316.983432) (xy 66.979026 -316.941836) (xy 66.959735 -316.89656)
			(xy 66.947958 -316.848776) (xy 66.943998 -316.799722) (xy 66.626994 -316.799722) (xy 66.62649 -316.82543)
			(xy 66.618447 -316.876212) (xy 66.602559 -316.925111) (xy 66.579216 -316.970923) (xy 66.548995 -317.012519)
			(xy 66.512639 -317.048875) (xy 66.471043 -317.079096) (xy 66.425231 -317.102439) (xy 66.376332 -317.118327)
			(xy 66.32555 -317.12637) (xy 66.274134 -317.12637) (xy 66.223352 -317.118327) (xy 66.174453 -317.102439)
			(xy 66.128641 -317.079096) (xy 66.087045 -317.048875) (xy 66.050689 -317.012519) (xy 66.020468 -316.970923)
			(xy 65.997125 -316.925111) (xy 65.981237 -316.876212) (xy 65.973194 -316.82543) (xy 65.654516 -316.82543)
			(xy 65.6468 -316.872906) (xy 65.631216 -316.919587) (xy 65.608345 -316.963164) (xy 65.57878 -317.002508)
			(xy 65.543287 -317.0366) (xy 65.502784 -317.064556) (xy 65.458322 -317.085654) (xy 65.411051 -317.099346)
			(xy 65.362196 -317.105278) (xy 65.313021 -317.103297) (xy 65.264802 -317.093453) (xy 65.218786 -317.076001)
			(xy 65.176165 -317.051394) (xy 65.138044 -317.020269) (xy 65.105409 -316.983432) (xy 65.079106 -316.941836)
			(xy 65.059815 -316.89656) (xy 65.048038 -316.848776) (xy 65.044078 -316.799722) (xy 64.727074 -316.799722)
			(xy 64.72657 -316.82543) (xy 64.718527 -316.876212) (xy 64.702639 -316.925111) (xy 64.679296 -316.970923)
			(xy 64.649075 -317.012519) (xy 64.612719 -317.048875) (xy 64.571123 -317.079096) (xy 64.525311 -317.102439)
			(xy 64.476412 -317.118327) (xy 64.42563 -317.12637) (xy 64.374214 -317.12637) (xy 64.323432 -317.118327)
			(xy 64.274533 -317.102439) (xy 64.228721 -317.079096) (xy 64.187125 -317.048875) (xy 64.150769 -317.012519)
			(xy 64.120548 -316.970923) (xy 64.097205 -316.925111) (xy 64.081317 -316.876212) (xy 64.073274 -316.82543)
			(xy 63.754596 -316.82543) (xy 63.74688 -316.872906) (xy 63.731296 -316.919587) (xy 63.708425 -316.963164)
			(xy 63.67886 -317.002508) (xy 63.643367 -317.0366) (xy 63.602864 -317.064556) (xy 63.558402 -317.085654)
			(xy 63.511131 -317.099346) (xy 63.462276 -317.105278) (xy 63.413101 -317.103297) (xy 63.364882 -317.093453)
			(xy 63.318866 -317.076001) (xy 63.276245 -317.051394) (xy 63.238124 -317.020269) (xy 63.205489 -316.983432)
			(xy 63.179186 -316.941836) (xy 63.159895 -316.89656) (xy 63.148118 -316.848776) (xy 63.144158 -316.799722)
			(xy 62.8269 -316.799722) (xy 62.826396 -316.82543) (xy 62.818353 -316.876212) (xy 62.802465 -316.925111)
			(xy 62.779122 -316.970923) (xy 62.748901 -317.012519) (xy 62.712545 -317.048875) (xy 62.670949 -317.079096)
			(xy 62.625137 -317.102439) (xy 62.576238 -317.118327) (xy 62.525456 -317.12637) (xy 62.47404 -317.12637)
			(xy 62.423258 -317.118327) (xy 62.374359 -317.102439) (xy 62.328547 -317.079096) (xy 62.286951 -317.048875)
			(xy 62.250595 -317.012519) (xy 62.220374 -316.970923) (xy 62.197031 -316.925111) (xy 62.181143 -316.876212)
			(xy 62.1731 -316.82543) (xy 61.854422 -316.82543) (xy 61.846706 -316.872906) (xy 61.831122 -316.919587)
			(xy 61.808251 -316.963164) (xy 61.778686 -317.002508) (xy 61.743193 -317.0366) (xy 61.70269 -317.064556)
			(xy 61.658228 -317.085654) (xy 61.610957 -317.099346) (xy 61.562102 -317.105278) (xy 61.512927 -317.103297)
			(xy 61.464708 -317.093453) (xy 61.418692 -317.076001) (xy 61.376071 -317.051394) (xy 61.33795 -317.020269)
			(xy 61.305315 -316.983432) (xy 61.279012 -316.941836) (xy 61.259721 -316.89656) (xy 61.247944 -316.848776)
			(xy 61.243984 -316.799722) (xy 60.92698 -316.799722) (xy 60.926476 -316.82543) (xy 60.918433 -316.876212)
			(xy 60.902545 -316.925111) (xy 60.879202 -316.970923) (xy 60.848981 -317.012519) (xy 60.812625 -317.048875)
			(xy 60.771029 -317.079096) (xy 60.725217 -317.102439) (xy 60.676318 -317.118327) (xy 60.625536 -317.12637)
			(xy 60.57412 -317.12637) (xy 60.523338 -317.118327) (xy 60.474439 -317.102439) (xy 60.428627 -317.079096)
			(xy 60.387031 -317.048875) (xy 60.350675 -317.012519) (xy 60.320454 -316.970923) (xy 60.297111 -316.925111)
			(xy 60.281223 -316.876212) (xy 60.27318 -316.82543) (xy 59.954502 -316.82543) (xy 59.946786 -316.872906)
			(xy 59.931202 -316.919587) (xy 59.908331 -316.963164) (xy 59.878766 -317.002508) (xy 59.843273 -317.0366)
			(xy 59.80277 -317.064556) (xy 59.758308 -317.085654) (xy 59.711037 -317.099346) (xy 59.662182 -317.105278)
			(xy 59.613007 -317.103297) (xy 59.564788 -317.093453) (xy 59.518772 -317.076001) (xy 59.476151 -317.051394)
			(xy 59.43803 -317.020269) (xy 59.405395 -316.983432) (xy 59.379092 -316.941836) (xy 59.359801 -316.89656)
			(xy 59.348024 -316.848776) (xy 59.344064 -316.799722) (xy 59.040776 -316.799722) (xy 59.040776 -317.775644)
			(xy 59.32322 -317.775644) (xy 59.32322 -317.724228) (xy 59.331263 -317.673446) (xy 59.347151 -317.624547)
			(xy 59.370494 -317.578735) (xy 59.400715 -317.537139) (xy 59.437071 -317.500783) (xy 59.478667 -317.470562)
			(xy 59.524479 -317.447219) (xy 59.573378 -317.431331) (xy 59.62416 -317.423288) (xy 59.675576 -317.423288)
			(xy 59.726358 -317.431331) (xy 59.775257 -317.447219) (xy 59.821069 -317.470562) (xy 59.862665 -317.500783)
			(xy 59.899021 -317.537139) (xy 59.929242 -317.578735) (xy 59.952585 -317.624547) (xy 59.968473 -317.673446)
			(xy 59.976516 -317.724228) (xy 59.97702 -317.749936) (xy 60.294024 -317.749936) (xy 60.297984 -317.700882)
			(xy 60.309761 -317.653098) (xy 60.329052 -317.607822) (xy 60.355355 -317.566226) (xy 60.38799 -317.529389)
			(xy 60.426111 -317.498264) (xy 60.468732 -317.473657) (xy 60.514748 -317.456205) (xy 60.562967 -317.446361)
			(xy 60.612142 -317.44438) (xy 60.660997 -317.450312) (xy 60.708268 -317.464004) (xy 60.75273 -317.485102)
			(xy 60.793233 -317.513058) (xy 60.828726 -317.54715) (xy 60.858291 -317.586494) (xy 60.881162 -317.630071)
			(xy 60.896746 -317.676752) (xy 60.904641 -317.725329) (xy 60.905136 -317.749936) (xy 60.904641 -317.774543)
			(xy 60.904462 -317.775644) (xy 61.22314 -317.775644) (xy 61.22314 -317.724228) (xy 61.231183 -317.673446)
			(xy 61.247071 -317.624547) (xy 61.270414 -317.578735) (xy 61.300635 -317.537139) (xy 61.336991 -317.500783)
			(xy 61.378587 -317.470562) (xy 61.424399 -317.447219) (xy 61.473298 -317.431331) (xy 61.52408 -317.423288)
			(xy 61.575496 -317.423288) (xy 61.626278 -317.431331) (xy 61.675177 -317.447219) (xy 61.720989 -317.470562)
			(xy 61.762585 -317.500783) (xy 61.798941 -317.537139) (xy 61.829162 -317.578735) (xy 61.852505 -317.624547)
			(xy 61.868393 -317.673446) (xy 61.876436 -317.724228) (xy 61.87694 -317.749936) (xy 62.193944 -317.749936)
			(xy 62.197904 -317.700882) (xy 62.209681 -317.653098) (xy 62.228972 -317.607822) (xy 62.255275 -317.566226)
			(xy 62.28791 -317.529389) (xy 62.326031 -317.498264) (xy 62.368652 -317.473657) (xy 62.414668 -317.456205)
			(xy 62.462887 -317.446361) (xy 62.512062 -317.44438) (xy 62.560917 -317.450312) (xy 62.608188 -317.464004)
			(xy 62.65265 -317.485102) (xy 62.693153 -317.513058) (xy 62.728646 -317.54715) (xy 62.758211 -317.586494)
			(xy 62.781082 -317.630071) (xy 62.796666 -317.676752) (xy 62.804561 -317.725329) (xy 62.805056 -317.749936)
			(xy 62.804561 -317.774543) (xy 62.804382 -317.775644) (xy 63.123314 -317.775644) (xy 63.123314 -317.724228)
			(xy 63.131357 -317.673446) (xy 63.147245 -317.624547) (xy 63.170588 -317.578735) (xy 63.200809 -317.537139)
			(xy 63.237165 -317.500783) (xy 63.278761 -317.470562) (xy 63.324573 -317.447219) (xy 63.373472 -317.431331)
			(xy 63.424254 -317.423288) (xy 63.47567 -317.423288) (xy 63.526452 -317.431331) (xy 63.575351 -317.447219)
			(xy 63.621163 -317.470562) (xy 63.662759 -317.500783) (xy 63.699115 -317.537139) (xy 63.729336 -317.578735)
			(xy 63.752679 -317.624547) (xy 63.768567 -317.673446) (xy 63.77661 -317.724228) (xy 63.777114 -317.749936)
			(xy 64.094118 -317.749936) (xy 64.098078 -317.700882) (xy 64.109855 -317.653098) (xy 64.129146 -317.607822)
			(xy 64.155449 -317.566226) (xy 64.188084 -317.529389) (xy 64.226205 -317.498264) (xy 64.268826 -317.473657)
			(xy 64.314842 -317.456205) (xy 64.363061 -317.446361) (xy 64.412236 -317.44438) (xy 64.461091 -317.450312)
			(xy 64.508362 -317.464004) (xy 64.552824 -317.485102) (xy 64.593327 -317.513058) (xy 64.62882 -317.54715)
			(xy 64.658385 -317.586494) (xy 64.681256 -317.630071) (xy 64.69684 -317.676752) (xy 64.704735 -317.725329)
			(xy 64.70523 -317.749936) (xy 64.704735 -317.774543) (xy 64.704556 -317.775644) (xy 65.023234 -317.775644)
			(xy 65.023234 -317.724228) (xy 65.031277 -317.673446) (xy 65.047165 -317.624547) (xy 65.070508 -317.578735)
			(xy 65.100729 -317.537139) (xy 65.137085 -317.500783) (xy 65.178681 -317.470562) (xy 65.224493 -317.447219)
			(xy 65.273392 -317.431331) (xy 65.324174 -317.423288) (xy 65.37559 -317.423288) (xy 65.426372 -317.431331)
			(xy 65.475271 -317.447219) (xy 65.521083 -317.470562) (xy 65.562679 -317.500783) (xy 65.599035 -317.537139)
			(xy 65.629256 -317.578735) (xy 65.652599 -317.624547) (xy 65.668487 -317.673446) (xy 65.67653 -317.724228)
			(xy 65.677034 -317.749936) (xy 65.994038 -317.749936) (xy 65.997998 -317.700882) (xy 66.009775 -317.653098)
			(xy 66.029066 -317.607822) (xy 66.055369 -317.566226) (xy 66.088004 -317.529389) (xy 66.126125 -317.498264)
			(xy 66.168746 -317.473657) (xy 66.214762 -317.456205) (xy 66.262981 -317.446361) (xy 66.312156 -317.44438)
			(xy 66.361011 -317.450312) (xy 66.408282 -317.464004) (xy 66.452744 -317.485102) (xy 66.493247 -317.513058)
			(xy 66.52874 -317.54715) (xy 66.558305 -317.586494) (xy 66.581176 -317.630071) (xy 66.59676 -317.676752)
			(xy 66.604655 -317.725329) (xy 66.60515 -317.749936) (xy 66.604655 -317.774543) (xy 66.604476 -317.775644)
			(xy 66.923154 -317.775644) (xy 66.923154 -317.724228) (xy 66.931197 -317.673446) (xy 66.947085 -317.624547)
			(xy 66.970428 -317.578735) (xy 67.000649 -317.537139) (xy 67.037005 -317.500783) (xy 67.078601 -317.470562)
			(xy 67.124413 -317.447219) (xy 67.173312 -317.431331) (xy 67.224094 -317.423288) (xy 67.27551 -317.423288)
			(xy 67.326292 -317.431331) (xy 67.375191 -317.447219) (xy 67.421003 -317.470562) (xy 67.462599 -317.500783)
			(xy 67.498955 -317.537139) (xy 67.529176 -317.578735) (xy 67.552519 -317.624547) (xy 67.568407 -317.673446)
			(xy 67.57645 -317.724228) (xy 67.576954 -317.749936) (xy 67.893958 -317.749936) (xy 67.897918 -317.700882)
			(xy 67.909695 -317.653098) (xy 67.928986 -317.607822) (xy 67.955289 -317.566226) (xy 67.987924 -317.529389)
			(xy 68.026045 -317.498264) (xy 68.068666 -317.473657) (xy 68.114682 -317.456205) (xy 68.162901 -317.446361)
			(xy 68.212076 -317.44438) (xy 68.260931 -317.450312) (xy 68.308202 -317.464004) (xy 68.352664 -317.485102)
			(xy 68.393167 -317.513058) (xy 68.42866 -317.54715) (xy 68.458225 -317.586494) (xy 68.481096 -317.630071)
			(xy 68.49668 -317.676752) (xy 68.504575 -317.725329) (xy 68.50507 -317.749936) (xy 68.504575 -317.774543)
			(xy 68.504396 -317.775644) (xy 68.823328 -317.775644) (xy 68.823328 -317.724228) (xy 68.831371 -317.673446)
			(xy 68.847259 -317.624547) (xy 68.870602 -317.578735) (xy 68.900823 -317.537139) (xy 68.937179 -317.500783)
			(xy 68.978775 -317.470562) (xy 69.024587 -317.447219) (xy 69.073486 -317.431331) (xy 69.124268 -317.423288)
			(xy 69.175684 -317.423288) (xy 69.226466 -317.431331) (xy 69.275365 -317.447219) (xy 69.321177 -317.470562)
			(xy 69.362773 -317.500783) (xy 69.399129 -317.537139) (xy 69.42935 -317.578735) (xy 69.452693 -317.624547)
			(xy 69.468581 -317.673446) (xy 69.476624 -317.724228) (xy 69.477128 -317.749936) (xy 69.794132 -317.749936)
			(xy 69.798092 -317.700882) (xy 69.809869 -317.653098) (xy 69.82916 -317.607822) (xy 69.855463 -317.566226)
			(xy 69.888098 -317.529389) (xy 69.926219 -317.498264) (xy 69.96884 -317.473657) (xy 70.014856 -317.456205)
			(xy 70.063075 -317.446361) (xy 70.11225 -317.44438) (xy 70.161105 -317.450312) (xy 70.208376 -317.464004)
			(xy 70.252838 -317.485102) (xy 70.293341 -317.513058) (xy 70.328834 -317.54715) (xy 70.358399 -317.586494)
			(xy 70.38127 -317.630071) (xy 70.396854 -317.676752) (xy 70.404749 -317.725329) (xy 70.405244 -317.749936)
			(xy 70.404749 -317.774543) (xy 70.40457 -317.775644) (xy 70.723248 -317.775644) (xy 70.723248 -317.724228)
			(xy 70.731291 -317.673446) (xy 70.747179 -317.624547) (xy 70.770522 -317.578735) (xy 70.800743 -317.537139)
			(xy 70.837099 -317.500783) (xy 70.878695 -317.470562) (xy 70.924507 -317.447219) (xy 70.973406 -317.431331)
			(xy 71.024188 -317.423288) (xy 71.075604 -317.423288) (xy 71.126386 -317.431331) (xy 71.175285 -317.447219)
			(xy 71.221097 -317.470562) (xy 71.262693 -317.500783) (xy 71.299049 -317.537139) (xy 71.32927 -317.578735)
			(xy 71.352613 -317.624547) (xy 71.368501 -317.673446) (xy 71.376544 -317.724228) (xy 71.377048 -317.749936)
			(xy 71.694052 -317.749936) (xy 71.698012 -317.700882) (xy 71.709789 -317.653098) (xy 71.72908 -317.607822)
			(xy 71.755383 -317.566226) (xy 71.788018 -317.529389) (xy 71.826139 -317.498264) (xy 71.86876 -317.473657)
			(xy 71.914776 -317.456205) (xy 71.962995 -317.446361) (xy 72.01217 -317.44438) (xy 72.061025 -317.450312)
			(xy 72.108296 -317.464004) (xy 72.152758 -317.485102) (xy 72.193261 -317.513058) (xy 72.228754 -317.54715)
			(xy 72.258319 -317.586494) (xy 72.28119 -317.630071) (xy 72.296774 -317.676752) (xy 72.304669 -317.725329)
			(xy 72.305164 -317.749936) (xy 72.304669 -317.774543) (xy 72.30449 -317.775644) (xy 72.623168 -317.775644)
			(xy 72.623168 -317.724228) (xy 72.631211 -317.673446) (xy 72.647099 -317.624547) (xy 72.670442 -317.578735)
			(xy 72.700663 -317.537139) (xy 72.737019 -317.500783) (xy 72.778615 -317.470562) (xy 72.824427 -317.447219)
			(xy 72.873326 -317.431331) (xy 72.924108 -317.423288) (xy 72.975524 -317.423288) (xy 73.026306 -317.431331)
			(xy 73.075205 -317.447219) (xy 73.121017 -317.470562) (xy 73.162613 -317.500783) (xy 73.198969 -317.537139)
			(xy 73.22919 -317.578735) (xy 73.252533 -317.624547) (xy 73.268421 -317.673446) (xy 73.276464 -317.724228)
			(xy 73.276968 -317.749936) (xy 73.593972 -317.749936) (xy 73.597932 -317.700882) (xy 73.609709 -317.653098)
			(xy 73.629 -317.607822) (xy 73.655303 -317.566226) (xy 73.687938 -317.529389) (xy 73.726059 -317.498264)
			(xy 73.76868 -317.473657) (xy 73.814696 -317.456205) (xy 73.862915 -317.446361) (xy 73.91209 -317.44438)
			(xy 73.960945 -317.450312) (xy 74.008216 -317.464004) (xy 74.052678 -317.485102) (xy 74.093181 -317.513058)
			(xy 74.128674 -317.54715) (xy 74.158239 -317.586494) (xy 74.18111 -317.630071) (xy 74.196694 -317.676752)
			(xy 74.204589 -317.725329) (xy 74.205084 -317.749936) (xy 74.544186 -317.749936) (xy 74.548146 -317.700882)
			(xy 74.559923 -317.653098) (xy 74.579214 -317.607822) (xy 74.605517 -317.566226) (xy 74.638152 -317.529389)
			(xy 74.676273 -317.498264) (xy 74.718894 -317.473657) (xy 74.76491 -317.456205) (xy 74.813129 -317.446361)
			(xy 74.862304 -317.44438) (xy 74.911159 -317.450312) (xy 74.95843 -317.464004) (xy 75.002892 -317.485102)
			(xy 75.043395 -317.513058) (xy 75.078888 -317.54715) (xy 75.108453 -317.586494) (xy 75.131324 -317.630071)
			(xy 75.146908 -317.676752) (xy 75.154803 -317.725329) (xy 75.155298 -317.749936) (xy 75.494146 -317.749936)
			(xy 75.498106 -317.700882) (xy 75.509883 -317.653098) (xy 75.529174 -317.607822) (xy 75.555477 -317.566226)
			(xy 75.588112 -317.529389) (xy 75.626233 -317.498264) (xy 75.668854 -317.473657) (xy 75.71487 -317.456205)
			(xy 75.763089 -317.446361) (xy 75.812264 -317.44438) (xy 75.861119 -317.450312) (xy 75.90839 -317.464004)
			(xy 75.952852 -317.485102) (xy 75.993355 -317.513058) (xy 76.028848 -317.54715) (xy 76.058413 -317.586494)
			(xy 76.081284 -317.630071) (xy 76.096868 -317.676752) (xy 76.104763 -317.725329) (xy 76.105258 -317.749936)
			(xy 76.444106 -317.749936) (xy 76.448066 -317.700882) (xy 76.459843 -317.653098) (xy 76.479134 -317.607822)
			(xy 76.505437 -317.566226) (xy 76.538072 -317.529389) (xy 76.576193 -317.498264) (xy 76.618814 -317.473657)
			(xy 76.66483 -317.456205) (xy 76.713049 -317.446361) (xy 76.762224 -317.44438) (xy 76.811079 -317.450312)
			(xy 76.85835 -317.464004) (xy 76.902812 -317.485102) (xy 76.943315 -317.513058) (xy 76.978808 -317.54715)
			(xy 77.008373 -317.586494) (xy 77.031244 -317.630071) (xy 77.046828 -317.676752) (xy 77.054723 -317.725329)
			(xy 77.055218 -317.749936) (xy 77.394066 -317.749936) (xy 77.398026 -317.700882) (xy 77.409803 -317.653098)
			(xy 77.429094 -317.607822) (xy 77.455397 -317.566226) (xy 77.488032 -317.529389) (xy 77.526153 -317.498264)
			(xy 77.568774 -317.473657) (xy 77.61479 -317.456205) (xy 77.663009 -317.446361) (xy 77.712184 -317.44438)
			(xy 77.761039 -317.450312) (xy 77.80831 -317.464004) (xy 77.852772 -317.485102) (xy 77.893275 -317.513058)
			(xy 77.928768 -317.54715) (xy 77.958333 -317.586494) (xy 77.981204 -317.630071) (xy 77.996788 -317.676752)
			(xy 78.004683 -317.725329) (xy 78.005178 -317.749936) (xy 78.344026 -317.749936) (xy 78.347986 -317.700882)
			(xy 78.359763 -317.653098) (xy 78.379054 -317.607822) (xy 78.405357 -317.566226) (xy 78.437992 -317.529389)
			(xy 78.476113 -317.498264) (xy 78.518734 -317.473657) (xy 78.56475 -317.456205) (xy 78.612969 -317.446361)
			(xy 78.662144 -317.44438) (xy 78.710999 -317.450312) (xy 78.75827 -317.464004) (xy 78.802732 -317.485102)
			(xy 78.843235 -317.513058) (xy 78.878728 -317.54715) (xy 78.908293 -317.586494) (xy 78.931164 -317.630071)
			(xy 78.946748 -317.676752) (xy 78.954643 -317.725329) (xy 78.955138 -317.749936) (xy 79.293986 -317.749936)
			(xy 79.297946 -317.700882) (xy 79.309723 -317.653098) (xy 79.329014 -317.607822) (xy 79.355317 -317.566226)
			(xy 79.387952 -317.529389) (xy 79.426073 -317.498264) (xy 79.468694 -317.473657) (xy 79.51471 -317.456205)
			(xy 79.562929 -317.446361) (xy 79.612104 -317.44438) (xy 79.660959 -317.450312) (xy 79.70823 -317.464004)
			(xy 79.752692 -317.485102) (xy 79.793195 -317.513058) (xy 79.828688 -317.54715) (xy 79.858253 -317.586494)
			(xy 79.881124 -317.630071) (xy 79.896708 -317.676752) (xy 79.904603 -317.725329) (xy 79.905098 -317.749936)
			(xy 80.243946 -317.749936) (xy 80.247906 -317.700882) (xy 80.259683 -317.653098) (xy 80.278974 -317.607822)
			(xy 80.305277 -317.566226) (xy 80.337912 -317.529389) (xy 80.376033 -317.498264) (xy 80.418654 -317.473657)
			(xy 80.46467 -317.456205) (xy 80.512889 -317.446361) (xy 80.562064 -317.44438) (xy 80.610919 -317.450312)
			(xy 80.65819 -317.464004) (xy 80.702652 -317.485102) (xy 80.743155 -317.513058) (xy 80.778648 -317.54715)
			(xy 80.808213 -317.586494) (xy 80.831084 -317.630071) (xy 80.846668 -317.676752) (xy 80.854563 -317.725329)
			(xy 80.855058 -317.749936) (xy 81.19416 -317.749936) (xy 81.19812 -317.700882) (xy 81.209897 -317.653098)
			(xy 81.229188 -317.607822) (xy 81.255491 -317.566226) (xy 81.288126 -317.529389) (xy 81.326247 -317.498264)
			(xy 81.368868 -317.473657) (xy 81.414884 -317.456205) (xy 81.463103 -317.446361) (xy 81.512278 -317.44438)
			(xy 81.561133 -317.450312) (xy 81.608404 -317.464004) (xy 81.652866 -317.485102) (xy 81.693369 -317.513058)
			(xy 81.728862 -317.54715) (xy 81.758427 -317.586494) (xy 81.781298 -317.630071) (xy 81.796882 -317.676752)
			(xy 81.804777 -317.725329) (xy 81.805272 -317.749936) (xy 82.14412 -317.749936) (xy 82.14808 -317.700882)
			(xy 82.159857 -317.653098) (xy 82.179148 -317.607822) (xy 82.205451 -317.566226) (xy 82.238086 -317.529389)
			(xy 82.276207 -317.498264) (xy 82.318828 -317.473657) (xy 82.364844 -317.456205) (xy 82.413063 -317.446361)
			(xy 82.462238 -317.44438) (xy 82.511093 -317.450312) (xy 82.558364 -317.464004) (xy 82.602826 -317.485102)
			(xy 82.643329 -317.513058) (xy 82.678822 -317.54715) (xy 82.708387 -317.586494) (xy 82.731258 -317.630071)
			(xy 82.746842 -317.676752) (xy 82.754737 -317.725329) (xy 82.755232 -317.749936) (xy 82.754737 -317.774543)
			(xy 82.746842 -317.82312) (xy 82.731258 -317.869801) (xy 82.708387 -317.913378) (xy 82.678822 -317.952722)
			(xy 82.643329 -317.986814) (xy 82.602826 -318.01477) (xy 82.558364 -318.035868) (xy 82.511093 -318.04956)
			(xy 82.462238 -318.055492) (xy 82.413063 -318.053511) (xy 82.364844 -318.043667) (xy 82.318828 -318.026215)
			(xy 82.276207 -318.001608) (xy 82.238086 -317.970483) (xy 82.205451 -317.933646) (xy 82.179148 -317.89205)
			(xy 82.159857 -317.846774) (xy 82.14808 -317.79899) (xy 82.14412 -317.749936) (xy 81.805272 -317.749936)
			(xy 81.804777 -317.774543) (xy 81.796882 -317.82312) (xy 81.781298 -317.869801) (xy 81.758427 -317.913378)
			(xy 81.728862 -317.952722) (xy 81.693369 -317.986814) (xy 81.652866 -318.01477) (xy 81.608404 -318.035868)
			(xy 81.561133 -318.04956) (xy 81.512278 -318.055492) (xy 81.463103 -318.053511) (xy 81.414884 -318.043667)
			(xy 81.368868 -318.026215) (xy 81.326247 -318.001608) (xy 81.288126 -317.970483) (xy 81.255491 -317.933646)
			(xy 81.229188 -317.89205) (xy 81.209897 -317.846774) (xy 81.19812 -317.79899) (xy 81.19416 -317.749936)
			(xy 80.855058 -317.749936) (xy 80.854563 -317.774543) (xy 80.846668 -317.82312) (xy 80.831084 -317.869801)
			(xy 80.808213 -317.913378) (xy 80.778648 -317.952722) (xy 80.743155 -317.986814) (xy 80.702652 -318.01477)
			(xy 80.65819 -318.035868) (xy 80.610919 -318.04956) (xy 80.562064 -318.055492) (xy 80.512889 -318.053511)
			(xy 80.46467 -318.043667) (xy 80.418654 -318.026215) (xy 80.376033 -318.001608) (xy 80.337912 -317.970483)
			(xy 80.305277 -317.933646) (xy 80.278974 -317.89205) (xy 80.259683 -317.846774) (xy 80.247906 -317.79899)
			(xy 80.243946 -317.749936) (xy 79.905098 -317.749936) (xy 79.904603 -317.774543) (xy 79.896708 -317.82312)
			(xy 79.881124 -317.869801) (xy 79.858253 -317.913378) (xy 79.828688 -317.952722) (xy 79.793195 -317.986814)
			(xy 79.752692 -318.01477) (xy 79.70823 -318.035868) (xy 79.660959 -318.04956) (xy 79.612104 -318.055492)
			(xy 79.562929 -318.053511) (xy 79.51471 -318.043667) (xy 79.468694 -318.026215) (xy 79.426073 -318.001608)
			(xy 79.387952 -317.970483) (xy 79.355317 -317.933646) (xy 79.329014 -317.89205) (xy 79.309723 -317.846774)
			(xy 79.297946 -317.79899) (xy 79.293986 -317.749936) (xy 78.955138 -317.749936) (xy 78.954643 -317.774543)
			(xy 78.946748 -317.82312) (xy 78.931164 -317.869801) (xy 78.908293 -317.913378) (xy 78.878728 -317.952722)
			(xy 78.843235 -317.986814) (xy 78.802732 -318.01477) (xy 78.75827 -318.035868) (xy 78.710999 -318.04956)
			(xy 78.662144 -318.055492) (xy 78.612969 -318.053511) (xy 78.56475 -318.043667) (xy 78.518734 -318.026215)
			(xy 78.476113 -318.001608) (xy 78.437992 -317.970483) (xy 78.405357 -317.933646) (xy 78.379054 -317.89205)
			(xy 78.359763 -317.846774) (xy 78.347986 -317.79899) (xy 78.344026 -317.749936) (xy 78.005178 -317.749936)
			(xy 78.004683 -317.774543) (xy 77.996788 -317.82312) (xy 77.981204 -317.869801) (xy 77.958333 -317.913378)
			(xy 77.928768 -317.952722) (xy 77.893275 -317.986814) (xy 77.852772 -318.01477) (xy 77.80831 -318.035868)
			(xy 77.761039 -318.04956) (xy 77.712184 -318.055492) (xy 77.663009 -318.053511) (xy 77.61479 -318.043667)
			(xy 77.568774 -318.026215) (xy 77.526153 -318.001608) (xy 77.488032 -317.970483) (xy 77.455397 -317.933646)
			(xy 77.429094 -317.89205) (xy 77.409803 -317.846774) (xy 77.398026 -317.79899) (xy 77.394066 -317.749936)
			(xy 77.055218 -317.749936) (xy 77.054723 -317.774543) (xy 77.046828 -317.82312) (xy 77.031244 -317.869801)
			(xy 77.008373 -317.913378) (xy 76.978808 -317.952722) (xy 76.943315 -317.986814) (xy 76.902812 -318.01477)
			(xy 76.85835 -318.035868) (xy 76.811079 -318.04956) (xy 76.762224 -318.055492) (xy 76.713049 -318.053511)
			(xy 76.66483 -318.043667) (xy 76.618814 -318.026215) (xy 76.576193 -318.001608) (xy 76.538072 -317.970483)
			(xy 76.505437 -317.933646) (xy 76.479134 -317.89205) (xy 76.459843 -317.846774) (xy 76.448066 -317.79899)
			(xy 76.444106 -317.749936) (xy 76.105258 -317.749936) (xy 76.104763 -317.774543) (xy 76.096868 -317.82312)
			(xy 76.081284 -317.869801) (xy 76.058413 -317.913378) (xy 76.028848 -317.952722) (xy 75.993355 -317.986814)
			(xy 75.952852 -318.01477) (xy 75.90839 -318.035868) (xy 75.861119 -318.04956) (xy 75.812264 -318.055492)
			(xy 75.763089 -318.053511) (xy 75.71487 -318.043667) (xy 75.668854 -318.026215) (xy 75.626233 -318.001608)
			(xy 75.588112 -317.970483) (xy 75.555477 -317.933646) (xy 75.529174 -317.89205) (xy 75.509883 -317.846774)
			(xy 75.498106 -317.79899) (xy 75.494146 -317.749936) (xy 75.155298 -317.749936) (xy 75.154803 -317.774543)
			(xy 75.146908 -317.82312) (xy 75.131324 -317.869801) (xy 75.108453 -317.913378) (xy 75.078888 -317.952722)
			(xy 75.043395 -317.986814) (xy 75.002892 -318.01477) (xy 74.95843 -318.035868) (xy 74.911159 -318.04956)
			(xy 74.862304 -318.055492) (xy 74.813129 -318.053511) (xy 74.76491 -318.043667) (xy 74.718894 -318.026215)
			(xy 74.676273 -318.001608) (xy 74.638152 -317.970483) (xy 74.605517 -317.933646) (xy 74.579214 -317.89205)
			(xy 74.559923 -317.846774) (xy 74.548146 -317.79899) (xy 74.544186 -317.749936) (xy 74.205084 -317.749936)
			(xy 74.204589 -317.774543) (xy 74.196694 -317.82312) (xy 74.18111 -317.869801) (xy 74.158239 -317.913378)
			(xy 74.128674 -317.952722) (xy 74.093181 -317.986814) (xy 74.052678 -318.01477) (xy 74.008216 -318.035868)
			(xy 73.960945 -318.04956) (xy 73.91209 -318.055492) (xy 73.862915 -318.053511) (xy 73.814696 -318.043667)
			(xy 73.76868 -318.026215) (xy 73.726059 -318.001608) (xy 73.687938 -317.970483) (xy 73.655303 -317.933646)
			(xy 73.629 -317.89205) (xy 73.609709 -317.846774) (xy 73.597932 -317.79899) (xy 73.593972 -317.749936)
			(xy 73.276968 -317.749936) (xy 73.276464 -317.775644) (xy 73.268421 -317.826426) (xy 73.252533 -317.875325)
			(xy 73.22919 -317.921137) (xy 73.198969 -317.962733) (xy 73.162613 -317.999089) (xy 73.121017 -318.02931)
			(xy 73.075205 -318.052653) (xy 73.026306 -318.068541) (xy 72.975524 -318.076584) (xy 72.924108 -318.076584)
			(xy 72.873326 -318.068541) (xy 72.824427 -318.052653) (xy 72.778615 -318.02931) (xy 72.737019 -317.999089)
			(xy 72.700663 -317.962733) (xy 72.670442 -317.921137) (xy 72.647099 -317.875325) (xy 72.631211 -317.826426)
			(xy 72.623168 -317.775644) (xy 72.30449 -317.775644) (xy 72.296774 -317.82312) (xy 72.28119 -317.869801)
			(xy 72.258319 -317.913378) (xy 72.228754 -317.952722) (xy 72.193261 -317.986814) (xy 72.152758 -318.01477)
			(xy 72.108296 -318.035868) (xy 72.061025 -318.04956) (xy 72.01217 -318.055492) (xy 71.962995 -318.053511)
			(xy 71.914776 -318.043667) (xy 71.86876 -318.026215) (xy 71.826139 -318.001608) (xy 71.788018 -317.970483)
			(xy 71.755383 -317.933646) (xy 71.72908 -317.89205) (xy 71.709789 -317.846774) (xy 71.698012 -317.79899)
			(xy 71.694052 -317.749936) (xy 71.377048 -317.749936) (xy 71.376544 -317.775644) (xy 71.368501 -317.826426)
			(xy 71.352613 -317.875325) (xy 71.32927 -317.921137) (xy 71.299049 -317.962733) (xy 71.262693 -317.999089)
			(xy 71.221097 -318.02931) (xy 71.175285 -318.052653) (xy 71.126386 -318.068541) (xy 71.075604 -318.076584)
			(xy 71.024188 -318.076584) (xy 70.973406 -318.068541) (xy 70.924507 -318.052653) (xy 70.878695 -318.02931)
			(xy 70.837099 -317.999089) (xy 70.800743 -317.962733) (xy 70.770522 -317.921137) (xy 70.747179 -317.875325)
			(xy 70.731291 -317.826426) (xy 70.723248 -317.775644) (xy 70.40457 -317.775644) (xy 70.396854 -317.82312)
			(xy 70.38127 -317.869801) (xy 70.358399 -317.913378) (xy 70.328834 -317.952722) (xy 70.293341 -317.986814)
			(xy 70.252838 -318.01477) (xy 70.208376 -318.035868) (xy 70.161105 -318.04956) (xy 70.11225 -318.055492)
			(xy 70.063075 -318.053511) (xy 70.014856 -318.043667) (xy 69.96884 -318.026215) (xy 69.926219 -318.001608)
			(xy 69.888098 -317.970483) (xy 69.855463 -317.933646) (xy 69.82916 -317.89205) (xy 69.809869 -317.846774)
			(xy 69.798092 -317.79899) (xy 69.794132 -317.749936) (xy 69.477128 -317.749936) (xy 69.476624 -317.775644)
			(xy 69.468581 -317.826426) (xy 69.452693 -317.875325) (xy 69.42935 -317.921137) (xy 69.399129 -317.962733)
			(xy 69.362773 -317.999089) (xy 69.321177 -318.02931) (xy 69.275365 -318.052653) (xy 69.226466 -318.068541)
			(xy 69.175684 -318.076584) (xy 69.124268 -318.076584) (xy 69.073486 -318.068541) (xy 69.024587 -318.052653)
			(xy 68.978775 -318.02931) (xy 68.937179 -317.999089) (xy 68.900823 -317.962733) (xy 68.870602 -317.921137)
			(xy 68.847259 -317.875325) (xy 68.831371 -317.826426) (xy 68.823328 -317.775644) (xy 68.504396 -317.775644)
			(xy 68.49668 -317.82312) (xy 68.481096 -317.869801) (xy 68.458225 -317.913378) (xy 68.42866 -317.952722)
			(xy 68.393167 -317.986814) (xy 68.352664 -318.01477) (xy 68.308202 -318.035868) (xy 68.260931 -318.04956)
			(xy 68.212076 -318.055492) (xy 68.162901 -318.053511) (xy 68.114682 -318.043667) (xy 68.068666 -318.026215)
			(xy 68.026045 -318.001608) (xy 67.987924 -317.970483) (xy 67.955289 -317.933646) (xy 67.928986 -317.89205)
			(xy 67.909695 -317.846774) (xy 67.897918 -317.79899) (xy 67.893958 -317.749936) (xy 67.576954 -317.749936)
			(xy 67.57645 -317.775644) (xy 67.568407 -317.826426) (xy 67.552519 -317.875325) (xy 67.529176 -317.921137)
			(xy 67.498955 -317.962733) (xy 67.462599 -317.999089) (xy 67.421003 -318.02931) (xy 67.375191 -318.052653)
			(xy 67.326292 -318.068541) (xy 67.27551 -318.076584) (xy 67.224094 -318.076584) (xy 67.173312 -318.068541)
			(xy 67.124413 -318.052653) (xy 67.078601 -318.02931) (xy 67.037005 -317.999089) (xy 67.000649 -317.962733)
			(xy 66.970428 -317.921137) (xy 66.947085 -317.875325) (xy 66.931197 -317.826426) (xy 66.923154 -317.775644)
			(xy 66.604476 -317.775644) (xy 66.59676 -317.82312) (xy 66.581176 -317.869801) (xy 66.558305 -317.913378)
			(xy 66.52874 -317.952722) (xy 66.493247 -317.986814) (xy 66.452744 -318.01477) (xy 66.408282 -318.035868)
			(xy 66.361011 -318.04956) (xy 66.312156 -318.055492) (xy 66.262981 -318.053511) (xy 66.214762 -318.043667)
			(xy 66.168746 -318.026215) (xy 66.126125 -318.001608) (xy 66.088004 -317.970483) (xy 66.055369 -317.933646)
			(xy 66.029066 -317.89205) (xy 66.009775 -317.846774) (xy 65.997998 -317.79899) (xy 65.994038 -317.749936)
			(xy 65.677034 -317.749936) (xy 65.67653 -317.775644) (xy 65.668487 -317.826426) (xy 65.652599 -317.875325)
			(xy 65.629256 -317.921137) (xy 65.599035 -317.962733) (xy 65.562679 -317.999089) (xy 65.521083 -318.02931)
			(xy 65.475271 -318.052653) (xy 65.426372 -318.068541) (xy 65.37559 -318.076584) (xy 65.324174 -318.076584)
			(xy 65.273392 -318.068541) (xy 65.224493 -318.052653) (xy 65.178681 -318.02931) (xy 65.137085 -317.999089)
			(xy 65.100729 -317.962733) (xy 65.070508 -317.921137) (xy 65.047165 -317.875325) (xy 65.031277 -317.826426)
			(xy 65.023234 -317.775644) (xy 64.704556 -317.775644) (xy 64.69684 -317.82312) (xy 64.681256 -317.869801)
			(xy 64.658385 -317.913378) (xy 64.62882 -317.952722) (xy 64.593327 -317.986814) (xy 64.552824 -318.01477)
			(xy 64.508362 -318.035868) (xy 64.461091 -318.04956) (xy 64.412236 -318.055492) (xy 64.363061 -318.053511)
			(xy 64.314842 -318.043667) (xy 64.268826 -318.026215) (xy 64.226205 -318.001608) (xy 64.188084 -317.970483)
			(xy 64.155449 -317.933646) (xy 64.129146 -317.89205) (xy 64.109855 -317.846774) (xy 64.098078 -317.79899)
			(xy 64.094118 -317.749936) (xy 63.777114 -317.749936) (xy 63.77661 -317.775644) (xy 63.768567 -317.826426)
			(xy 63.752679 -317.875325) (xy 63.729336 -317.921137) (xy 63.699115 -317.962733) (xy 63.662759 -317.999089)
			(xy 63.621163 -318.02931) (xy 63.575351 -318.052653) (xy 63.526452 -318.068541) (xy 63.47567 -318.076584)
			(xy 63.424254 -318.076584) (xy 63.373472 -318.068541) (xy 63.324573 -318.052653) (xy 63.278761 -318.02931)
			(xy 63.237165 -317.999089) (xy 63.200809 -317.962733) (xy 63.170588 -317.921137) (xy 63.147245 -317.875325)
			(xy 63.131357 -317.826426) (xy 63.123314 -317.775644) (xy 62.804382 -317.775644) (xy 62.796666 -317.82312)
			(xy 62.781082 -317.869801) (xy 62.758211 -317.913378) (xy 62.728646 -317.952722) (xy 62.693153 -317.986814)
			(xy 62.65265 -318.01477) (xy 62.608188 -318.035868) (xy 62.560917 -318.04956) (xy 62.512062 -318.055492)
			(xy 62.462887 -318.053511) (xy 62.414668 -318.043667) (xy 62.368652 -318.026215) (xy 62.326031 -318.001608)
			(xy 62.28791 -317.970483) (xy 62.255275 -317.933646) (xy 62.228972 -317.89205) (xy 62.209681 -317.846774)
			(xy 62.197904 -317.79899) (xy 62.193944 -317.749936) (xy 61.87694 -317.749936) (xy 61.876436 -317.775644)
			(xy 61.868393 -317.826426) (xy 61.852505 -317.875325) (xy 61.829162 -317.921137) (xy 61.798941 -317.962733)
			(xy 61.762585 -317.999089) (xy 61.720989 -318.02931) (xy 61.675177 -318.052653) (xy 61.626278 -318.068541)
			(xy 61.575496 -318.076584) (xy 61.52408 -318.076584) (xy 61.473298 -318.068541) (xy 61.424399 -318.052653)
			(xy 61.378587 -318.02931) (xy 61.336991 -317.999089) (xy 61.300635 -317.962733) (xy 61.270414 -317.921137)
			(xy 61.247071 -317.875325) (xy 61.231183 -317.826426) (xy 61.22314 -317.775644) (xy 60.904462 -317.775644)
			(xy 60.896746 -317.82312) (xy 60.881162 -317.869801) (xy 60.858291 -317.913378) (xy 60.828726 -317.952722)
			(xy 60.793233 -317.986814) (xy 60.75273 -318.01477) (xy 60.708268 -318.035868) (xy 60.660997 -318.04956)
			(xy 60.612142 -318.055492) (xy 60.562967 -318.053511) (xy 60.514748 -318.043667) (xy 60.468732 -318.026215)
			(xy 60.426111 -318.001608) (xy 60.38799 -317.970483) (xy 60.355355 -317.933646) (xy 60.329052 -317.89205)
			(xy 60.309761 -317.846774) (xy 60.297984 -317.79899) (xy 60.294024 -317.749936) (xy 59.97702 -317.749936)
			(xy 59.976516 -317.775644) (xy 59.968473 -317.826426) (xy 59.952585 -317.875325) (xy 59.929242 -317.921137)
			(xy 59.899021 -317.962733) (xy 59.862665 -317.999089) (xy 59.821069 -318.02931) (xy 59.775257 -318.052653)
			(xy 59.726358 -318.068541) (xy 59.675576 -318.076584) (xy 59.62416 -318.076584) (xy 59.573378 -318.068541)
			(xy 59.524479 -318.052653) (xy 59.478667 -318.02931) (xy 59.437071 -317.999089) (xy 59.400715 -317.962733)
			(xy 59.370494 -317.921137) (xy 59.347151 -317.875325) (xy 59.331263 -317.826426) (xy 59.32322 -317.775644)
			(xy 59.040776 -317.775644) (xy 59.040776 -318.725604) (xy 59.32322 -318.725604) (xy 59.32322 -318.674188)
			(xy 59.331263 -318.623406) (xy 59.347151 -318.574507) (xy 59.370494 -318.528695) (xy 59.400715 -318.487099)
			(xy 59.437071 -318.450743) (xy 59.478667 -318.420522) (xy 59.524479 -318.397179) (xy 59.573378 -318.381291)
			(xy 59.62416 -318.373248) (xy 59.675576 -318.373248) (xy 59.726358 -318.381291) (xy 59.775257 -318.397179)
			(xy 59.821069 -318.420522) (xy 59.862665 -318.450743) (xy 59.899021 -318.487099) (xy 59.929242 -318.528695)
			(xy 59.952585 -318.574507) (xy 59.968473 -318.623406) (xy 59.976516 -318.674188) (xy 59.97702 -318.699896)
			(xy 60.294024 -318.699896) (xy 60.297984 -318.650842) (xy 60.309761 -318.603058) (xy 60.329052 -318.557782)
			(xy 60.355355 -318.516186) (xy 60.38799 -318.479349) (xy 60.426111 -318.448224) (xy 60.468732 -318.423617)
			(xy 60.514748 -318.406165) (xy 60.562967 -318.396321) (xy 60.612142 -318.39434) (xy 60.660997 -318.400272)
			(xy 60.708268 -318.413964) (xy 60.75273 -318.435062) (xy 60.793233 -318.463018) (xy 60.828726 -318.49711)
			(xy 60.858291 -318.536454) (xy 60.881162 -318.580031) (xy 60.896746 -318.626712) (xy 60.904641 -318.675289)
			(xy 60.905136 -318.699896) (xy 60.904641 -318.724503) (xy 60.904462 -318.725604) (xy 61.22314 -318.725604)
			(xy 61.22314 -318.674188) (xy 61.231183 -318.623406) (xy 61.247071 -318.574507) (xy 61.270414 -318.528695)
			(xy 61.300635 -318.487099) (xy 61.336991 -318.450743) (xy 61.378587 -318.420522) (xy 61.424399 -318.397179)
			(xy 61.473298 -318.381291) (xy 61.52408 -318.373248) (xy 61.575496 -318.373248) (xy 61.626278 -318.381291)
			(xy 61.675177 -318.397179) (xy 61.720989 -318.420522) (xy 61.762585 -318.450743) (xy 61.798941 -318.487099)
			(xy 61.829162 -318.528695) (xy 61.852505 -318.574507) (xy 61.868393 -318.623406) (xy 61.876436 -318.674188)
			(xy 61.87694 -318.699896) (xy 62.193944 -318.699896) (xy 62.197904 -318.650842) (xy 62.209681 -318.603058)
			(xy 62.228972 -318.557782) (xy 62.255275 -318.516186) (xy 62.28791 -318.479349) (xy 62.326031 -318.448224)
			(xy 62.368652 -318.423617) (xy 62.414668 -318.406165) (xy 62.462887 -318.396321) (xy 62.512062 -318.39434)
			(xy 62.560917 -318.400272) (xy 62.608188 -318.413964) (xy 62.65265 -318.435062) (xy 62.693153 -318.463018)
			(xy 62.728646 -318.49711) (xy 62.758211 -318.536454) (xy 62.781082 -318.580031) (xy 62.796666 -318.626712)
			(xy 62.804561 -318.675289) (xy 62.805056 -318.699896) (xy 62.804561 -318.724503) (xy 62.804382 -318.725604)
			(xy 63.123314 -318.725604) (xy 63.123314 -318.674188) (xy 63.131357 -318.623406) (xy 63.147245 -318.574507)
			(xy 63.170588 -318.528695) (xy 63.200809 -318.487099) (xy 63.237165 -318.450743) (xy 63.278761 -318.420522)
			(xy 63.324573 -318.397179) (xy 63.373472 -318.381291) (xy 63.424254 -318.373248) (xy 63.47567 -318.373248)
			(xy 63.526452 -318.381291) (xy 63.575351 -318.397179) (xy 63.621163 -318.420522) (xy 63.662759 -318.450743)
			(xy 63.699115 -318.487099) (xy 63.729336 -318.528695) (xy 63.752679 -318.574507) (xy 63.768567 -318.623406)
			(xy 63.77661 -318.674188) (xy 63.777114 -318.699896) (xy 64.094118 -318.699896) (xy 64.098078 -318.650842)
			(xy 64.109855 -318.603058) (xy 64.129146 -318.557782) (xy 64.155449 -318.516186) (xy 64.188084 -318.479349)
			(xy 64.226205 -318.448224) (xy 64.268826 -318.423617) (xy 64.314842 -318.406165) (xy 64.363061 -318.396321)
			(xy 64.412236 -318.39434) (xy 64.461091 -318.400272) (xy 64.508362 -318.413964) (xy 64.552824 -318.435062)
			(xy 64.593327 -318.463018) (xy 64.62882 -318.49711) (xy 64.658385 -318.536454) (xy 64.681256 -318.580031)
			(xy 64.69684 -318.626712) (xy 64.704735 -318.675289) (xy 64.70523 -318.699896) (xy 64.704735 -318.724503)
			(xy 64.704556 -318.725604) (xy 65.023234 -318.725604) (xy 65.023234 -318.674188) (xy 65.031277 -318.623406)
			(xy 65.047165 -318.574507) (xy 65.070508 -318.528695) (xy 65.100729 -318.487099) (xy 65.137085 -318.450743)
			(xy 65.178681 -318.420522) (xy 65.224493 -318.397179) (xy 65.273392 -318.381291) (xy 65.324174 -318.373248)
			(xy 65.37559 -318.373248) (xy 65.426372 -318.381291) (xy 65.475271 -318.397179) (xy 65.521083 -318.420522)
			(xy 65.562679 -318.450743) (xy 65.599035 -318.487099) (xy 65.629256 -318.528695) (xy 65.652599 -318.574507)
			(xy 65.668487 -318.623406) (xy 65.67653 -318.674188) (xy 65.677034 -318.699896) (xy 65.994038 -318.699896)
			(xy 65.997998 -318.650842) (xy 66.009775 -318.603058) (xy 66.029066 -318.557782) (xy 66.055369 -318.516186)
			(xy 66.088004 -318.479349) (xy 66.126125 -318.448224) (xy 66.168746 -318.423617) (xy 66.214762 -318.406165)
			(xy 66.262981 -318.396321) (xy 66.312156 -318.39434) (xy 66.361011 -318.400272) (xy 66.408282 -318.413964)
			(xy 66.452744 -318.435062) (xy 66.493247 -318.463018) (xy 66.52874 -318.49711) (xy 66.558305 -318.536454)
			(xy 66.581176 -318.580031) (xy 66.59676 -318.626712) (xy 66.604655 -318.675289) (xy 66.60515 -318.699896)
			(xy 66.604655 -318.724503) (xy 66.604476 -318.725604) (xy 66.923154 -318.725604) (xy 66.923154 -318.674188)
			(xy 66.931197 -318.623406) (xy 66.947085 -318.574507) (xy 66.970428 -318.528695) (xy 67.000649 -318.487099)
			(xy 67.037005 -318.450743) (xy 67.078601 -318.420522) (xy 67.124413 -318.397179) (xy 67.173312 -318.381291)
			(xy 67.224094 -318.373248) (xy 67.27551 -318.373248) (xy 67.326292 -318.381291) (xy 67.375191 -318.397179)
			(xy 67.421003 -318.420522) (xy 67.462599 -318.450743) (xy 67.498955 -318.487099) (xy 67.529176 -318.528695)
			(xy 67.552519 -318.574507) (xy 67.568407 -318.623406) (xy 67.57645 -318.674188) (xy 67.576954 -318.699896)
			(xy 67.893958 -318.699896) (xy 67.897918 -318.650842) (xy 67.909695 -318.603058) (xy 67.928986 -318.557782)
			(xy 67.955289 -318.516186) (xy 67.987924 -318.479349) (xy 68.026045 -318.448224) (xy 68.068666 -318.423617)
			(xy 68.114682 -318.406165) (xy 68.162901 -318.396321) (xy 68.212076 -318.39434) (xy 68.260931 -318.400272)
			(xy 68.308202 -318.413964) (xy 68.352664 -318.435062) (xy 68.393167 -318.463018) (xy 68.42866 -318.49711)
			(xy 68.458225 -318.536454) (xy 68.481096 -318.580031) (xy 68.49668 -318.626712) (xy 68.504575 -318.675289)
			(xy 68.50507 -318.699896) (xy 68.504575 -318.724503) (xy 68.504396 -318.725604) (xy 68.823328 -318.725604)
			(xy 68.823328 -318.674188) (xy 68.831371 -318.623406) (xy 68.847259 -318.574507) (xy 68.870602 -318.528695)
			(xy 68.900823 -318.487099) (xy 68.937179 -318.450743) (xy 68.978775 -318.420522) (xy 69.024587 -318.397179)
			(xy 69.073486 -318.381291) (xy 69.124268 -318.373248) (xy 69.175684 -318.373248) (xy 69.226466 -318.381291)
			(xy 69.275365 -318.397179) (xy 69.321177 -318.420522) (xy 69.362773 -318.450743) (xy 69.399129 -318.487099)
			(xy 69.42935 -318.528695) (xy 69.452693 -318.574507) (xy 69.468581 -318.623406) (xy 69.476624 -318.674188)
			(xy 69.477128 -318.699896) (xy 69.794132 -318.699896) (xy 69.798092 -318.650842) (xy 69.809869 -318.603058)
			(xy 69.82916 -318.557782) (xy 69.855463 -318.516186) (xy 69.888098 -318.479349) (xy 69.926219 -318.448224)
			(xy 69.96884 -318.423617) (xy 70.014856 -318.406165) (xy 70.063075 -318.396321) (xy 70.11225 -318.39434)
			(xy 70.161105 -318.400272) (xy 70.208376 -318.413964) (xy 70.252838 -318.435062) (xy 70.293341 -318.463018)
			(xy 70.328834 -318.49711) (xy 70.358399 -318.536454) (xy 70.38127 -318.580031) (xy 70.396854 -318.626712)
			(xy 70.404749 -318.675289) (xy 70.405244 -318.699896) (xy 70.404749 -318.724503) (xy 70.40457 -318.725604)
			(xy 70.723248 -318.725604) (xy 70.723248 -318.674188) (xy 70.731291 -318.623406) (xy 70.747179 -318.574507)
			(xy 70.770522 -318.528695) (xy 70.800743 -318.487099) (xy 70.837099 -318.450743) (xy 70.878695 -318.420522)
			(xy 70.924507 -318.397179) (xy 70.973406 -318.381291) (xy 71.024188 -318.373248) (xy 71.075604 -318.373248)
			(xy 71.126386 -318.381291) (xy 71.175285 -318.397179) (xy 71.221097 -318.420522) (xy 71.262693 -318.450743)
			(xy 71.299049 -318.487099) (xy 71.32927 -318.528695) (xy 71.352613 -318.574507) (xy 71.368501 -318.623406)
			(xy 71.376544 -318.674188) (xy 71.377048 -318.699896) (xy 71.694052 -318.699896) (xy 71.698012 -318.650842)
			(xy 71.709789 -318.603058) (xy 71.72908 -318.557782) (xy 71.755383 -318.516186) (xy 71.788018 -318.479349)
			(xy 71.826139 -318.448224) (xy 71.86876 -318.423617) (xy 71.914776 -318.406165) (xy 71.962995 -318.396321)
			(xy 72.01217 -318.39434) (xy 72.061025 -318.400272) (xy 72.108296 -318.413964) (xy 72.152758 -318.435062)
			(xy 72.193261 -318.463018) (xy 72.228754 -318.49711) (xy 72.258319 -318.536454) (xy 72.28119 -318.580031)
			(xy 72.296774 -318.626712) (xy 72.304669 -318.675289) (xy 72.305164 -318.699896) (xy 72.304669 -318.724503)
			(xy 72.30449 -318.725604) (xy 72.623168 -318.725604) (xy 72.623168 -318.674188) (xy 72.631211 -318.623406)
			(xy 72.647099 -318.574507) (xy 72.670442 -318.528695) (xy 72.700663 -318.487099) (xy 72.737019 -318.450743)
			(xy 72.778615 -318.420522) (xy 72.824427 -318.397179) (xy 72.873326 -318.381291) (xy 72.924108 -318.373248)
			(xy 72.975524 -318.373248) (xy 73.026306 -318.381291) (xy 73.075205 -318.397179) (xy 73.121017 -318.420522)
			(xy 73.162613 -318.450743) (xy 73.198969 -318.487099) (xy 73.22919 -318.528695) (xy 73.252533 -318.574507)
			(xy 73.268421 -318.623406) (xy 73.276464 -318.674188) (xy 73.276968 -318.699896) (xy 73.593972 -318.699896)
			(xy 73.597932 -318.650842) (xy 73.609709 -318.603058) (xy 73.629 -318.557782) (xy 73.655303 -318.516186)
			(xy 73.687938 -318.479349) (xy 73.726059 -318.448224) (xy 73.76868 -318.423617) (xy 73.814696 -318.406165)
			(xy 73.862915 -318.396321) (xy 73.91209 -318.39434) (xy 73.960945 -318.400272) (xy 74.008216 -318.413964)
			(xy 74.052678 -318.435062) (xy 74.093181 -318.463018) (xy 74.128674 -318.49711) (xy 74.158239 -318.536454)
			(xy 74.18111 -318.580031) (xy 74.196694 -318.626712) (xy 74.204589 -318.675289) (xy 74.205084 -318.699896)
			(xy 74.544186 -318.699896) (xy 74.548146 -318.650842) (xy 74.559923 -318.603058) (xy 74.579214 -318.557782)
			(xy 74.605517 -318.516186) (xy 74.638152 -318.479349) (xy 74.676273 -318.448224) (xy 74.718894 -318.423617)
			(xy 74.76491 -318.406165) (xy 74.813129 -318.396321) (xy 74.862304 -318.39434) (xy 74.911159 -318.400272)
			(xy 74.95843 -318.413964) (xy 75.002892 -318.435062) (xy 75.043395 -318.463018) (xy 75.078888 -318.49711)
			(xy 75.108453 -318.536454) (xy 75.131324 -318.580031) (xy 75.146908 -318.626712) (xy 75.154803 -318.675289)
			(xy 75.155298 -318.699896) (xy 75.494146 -318.699896) (xy 75.498106 -318.650842) (xy 75.509883 -318.603058)
			(xy 75.529174 -318.557782) (xy 75.555477 -318.516186) (xy 75.588112 -318.479349) (xy 75.626233 -318.448224)
			(xy 75.668854 -318.423617) (xy 75.71487 -318.406165) (xy 75.763089 -318.396321) (xy 75.812264 -318.39434)
			(xy 75.861119 -318.400272) (xy 75.90839 -318.413964) (xy 75.952852 -318.435062) (xy 75.993355 -318.463018)
			(xy 76.028848 -318.49711) (xy 76.058413 -318.536454) (xy 76.081284 -318.580031) (xy 76.096868 -318.626712)
			(xy 76.104763 -318.675289) (xy 76.105258 -318.699896) (xy 76.444106 -318.699896) (xy 76.448066 -318.650842)
			(xy 76.459843 -318.603058) (xy 76.479134 -318.557782) (xy 76.505437 -318.516186) (xy 76.538072 -318.479349)
			(xy 76.576193 -318.448224) (xy 76.618814 -318.423617) (xy 76.66483 -318.406165) (xy 76.713049 -318.396321)
			(xy 76.762224 -318.39434) (xy 76.811079 -318.400272) (xy 76.85835 -318.413964) (xy 76.902812 -318.435062)
			(xy 76.943315 -318.463018) (xy 76.978808 -318.49711) (xy 77.008373 -318.536454) (xy 77.031244 -318.580031)
			(xy 77.046828 -318.626712) (xy 77.054723 -318.675289) (xy 77.055218 -318.699896) (xy 77.394066 -318.699896)
			(xy 77.398026 -318.650842) (xy 77.409803 -318.603058) (xy 77.429094 -318.557782) (xy 77.455397 -318.516186)
			(xy 77.488032 -318.479349) (xy 77.526153 -318.448224) (xy 77.568774 -318.423617) (xy 77.61479 -318.406165)
			(xy 77.663009 -318.396321) (xy 77.712184 -318.39434) (xy 77.761039 -318.400272) (xy 77.80831 -318.413964)
			(xy 77.852772 -318.435062) (xy 77.893275 -318.463018) (xy 77.928768 -318.49711) (xy 77.958333 -318.536454)
			(xy 77.981204 -318.580031) (xy 77.996788 -318.626712) (xy 78.004683 -318.675289) (xy 78.005178 -318.699896)
			(xy 78.344026 -318.699896) (xy 78.347986 -318.650842) (xy 78.359763 -318.603058) (xy 78.379054 -318.557782)
			(xy 78.405357 -318.516186) (xy 78.437992 -318.479349) (xy 78.476113 -318.448224) (xy 78.518734 -318.423617)
			(xy 78.56475 -318.406165) (xy 78.612969 -318.396321) (xy 78.662144 -318.39434) (xy 78.710999 -318.400272)
			(xy 78.75827 -318.413964) (xy 78.802732 -318.435062) (xy 78.843235 -318.463018) (xy 78.878728 -318.49711)
			(xy 78.908293 -318.536454) (xy 78.931164 -318.580031) (xy 78.946748 -318.626712) (xy 78.954643 -318.675289)
			(xy 78.955138 -318.699896) (xy 79.293986 -318.699896) (xy 79.297946 -318.650842) (xy 79.309723 -318.603058)
			(xy 79.329014 -318.557782) (xy 79.355317 -318.516186) (xy 79.387952 -318.479349) (xy 79.426073 -318.448224)
			(xy 79.468694 -318.423617) (xy 79.51471 -318.406165) (xy 79.562929 -318.396321) (xy 79.612104 -318.39434)
			(xy 79.660959 -318.400272) (xy 79.70823 -318.413964) (xy 79.752692 -318.435062) (xy 79.793195 -318.463018)
			(xy 79.828688 -318.49711) (xy 79.858253 -318.536454) (xy 79.881124 -318.580031) (xy 79.896708 -318.626712)
			(xy 79.904603 -318.675289) (xy 79.905098 -318.699896) (xy 80.243946 -318.699896) (xy 80.247906 -318.650842)
			(xy 80.259683 -318.603058) (xy 80.278974 -318.557782) (xy 80.305277 -318.516186) (xy 80.337912 -318.479349)
			(xy 80.376033 -318.448224) (xy 80.418654 -318.423617) (xy 80.46467 -318.406165) (xy 80.512889 -318.396321)
			(xy 80.562064 -318.39434) (xy 80.610919 -318.400272) (xy 80.65819 -318.413964) (xy 80.702652 -318.435062)
			(xy 80.743155 -318.463018) (xy 80.778648 -318.49711) (xy 80.808213 -318.536454) (xy 80.831084 -318.580031)
			(xy 80.846668 -318.626712) (xy 80.854563 -318.675289) (xy 80.855058 -318.699896) (xy 81.19416 -318.699896)
			(xy 81.19812 -318.650842) (xy 81.209897 -318.603058) (xy 81.229188 -318.557782) (xy 81.255491 -318.516186)
			(xy 81.288126 -318.479349) (xy 81.326247 -318.448224) (xy 81.368868 -318.423617) (xy 81.414884 -318.406165)
			(xy 81.463103 -318.396321) (xy 81.512278 -318.39434) (xy 81.561133 -318.400272) (xy 81.608404 -318.413964)
			(xy 81.652866 -318.435062) (xy 81.693369 -318.463018) (xy 81.728862 -318.49711) (xy 81.758427 -318.536454)
			(xy 81.781298 -318.580031) (xy 81.796882 -318.626712) (xy 81.804777 -318.675289) (xy 81.805272 -318.699896)
			(xy 81.804777 -318.724503) (xy 81.796882 -318.77308) (xy 81.781298 -318.819761) (xy 81.758427 -318.863338)
			(xy 81.728862 -318.902682) (xy 81.693369 -318.936774) (xy 81.652866 -318.96473) (xy 81.608404 -318.985828)
			(xy 81.561133 -318.99952) (xy 81.512278 -319.005452) (xy 81.463103 -319.003471) (xy 81.414884 -318.993627)
			(xy 81.368868 -318.976175) (xy 81.326247 -318.951568) (xy 81.288126 -318.920443) (xy 81.255491 -318.883606)
			(xy 81.229188 -318.84201) (xy 81.209897 -318.796734) (xy 81.19812 -318.74895) (xy 81.19416 -318.699896)
			(xy 80.855058 -318.699896) (xy 80.854563 -318.724503) (xy 80.846668 -318.77308) (xy 80.831084 -318.819761)
			(xy 80.808213 -318.863338) (xy 80.778648 -318.902682) (xy 80.743155 -318.936774) (xy 80.702652 -318.96473)
			(xy 80.65819 -318.985828) (xy 80.610919 -318.99952) (xy 80.562064 -319.005452) (xy 80.512889 -319.003471)
			(xy 80.46467 -318.993627) (xy 80.418654 -318.976175) (xy 80.376033 -318.951568) (xy 80.337912 -318.920443)
			(xy 80.305277 -318.883606) (xy 80.278974 -318.84201) (xy 80.259683 -318.796734) (xy 80.247906 -318.74895)
			(xy 80.243946 -318.699896) (xy 79.905098 -318.699896) (xy 79.904603 -318.724503) (xy 79.896708 -318.77308)
			(xy 79.881124 -318.819761) (xy 79.858253 -318.863338) (xy 79.828688 -318.902682) (xy 79.793195 -318.936774)
			(xy 79.752692 -318.96473) (xy 79.70823 -318.985828) (xy 79.660959 -318.99952) (xy 79.612104 -319.005452)
			(xy 79.562929 -319.003471) (xy 79.51471 -318.993627) (xy 79.468694 -318.976175) (xy 79.426073 -318.951568)
			(xy 79.387952 -318.920443) (xy 79.355317 -318.883606) (xy 79.329014 -318.84201) (xy 79.309723 -318.796734)
			(xy 79.297946 -318.74895) (xy 79.293986 -318.699896) (xy 78.955138 -318.699896) (xy 78.954643 -318.724503)
			(xy 78.946748 -318.77308) (xy 78.931164 -318.819761) (xy 78.908293 -318.863338) (xy 78.878728 -318.902682)
			(xy 78.843235 -318.936774) (xy 78.802732 -318.96473) (xy 78.75827 -318.985828) (xy 78.710999 -318.99952)
			(xy 78.662144 -319.005452) (xy 78.612969 -319.003471) (xy 78.56475 -318.993627) (xy 78.518734 -318.976175)
			(xy 78.476113 -318.951568) (xy 78.437992 -318.920443) (xy 78.405357 -318.883606) (xy 78.379054 -318.84201)
			(xy 78.359763 -318.796734) (xy 78.347986 -318.74895) (xy 78.344026 -318.699896) (xy 78.005178 -318.699896)
			(xy 78.004683 -318.724503) (xy 77.996788 -318.77308) (xy 77.981204 -318.819761) (xy 77.958333 -318.863338)
			(xy 77.928768 -318.902682) (xy 77.893275 -318.936774) (xy 77.852772 -318.96473) (xy 77.80831 -318.985828)
			(xy 77.761039 -318.99952) (xy 77.712184 -319.005452) (xy 77.663009 -319.003471) (xy 77.61479 -318.993627)
			(xy 77.568774 -318.976175) (xy 77.526153 -318.951568) (xy 77.488032 -318.920443) (xy 77.455397 -318.883606)
			(xy 77.429094 -318.84201) (xy 77.409803 -318.796734) (xy 77.398026 -318.74895) (xy 77.394066 -318.699896)
			(xy 77.055218 -318.699896) (xy 77.054723 -318.724503) (xy 77.046828 -318.77308) (xy 77.031244 -318.819761)
			(xy 77.008373 -318.863338) (xy 76.978808 -318.902682) (xy 76.943315 -318.936774) (xy 76.902812 -318.96473)
			(xy 76.85835 -318.985828) (xy 76.811079 -318.99952) (xy 76.762224 -319.005452) (xy 76.713049 -319.003471)
			(xy 76.66483 -318.993627) (xy 76.618814 -318.976175) (xy 76.576193 -318.951568) (xy 76.538072 -318.920443)
			(xy 76.505437 -318.883606) (xy 76.479134 -318.84201) (xy 76.459843 -318.796734) (xy 76.448066 -318.74895)
			(xy 76.444106 -318.699896) (xy 76.105258 -318.699896) (xy 76.104763 -318.724503) (xy 76.096868 -318.77308)
			(xy 76.081284 -318.819761) (xy 76.058413 -318.863338) (xy 76.028848 -318.902682) (xy 75.993355 -318.936774)
			(xy 75.952852 -318.96473) (xy 75.90839 -318.985828) (xy 75.861119 -318.99952) (xy 75.812264 -319.005452)
			(xy 75.763089 -319.003471) (xy 75.71487 -318.993627) (xy 75.668854 -318.976175) (xy 75.626233 -318.951568)
			(xy 75.588112 -318.920443) (xy 75.555477 -318.883606) (xy 75.529174 -318.84201) (xy 75.509883 -318.796734)
			(xy 75.498106 -318.74895) (xy 75.494146 -318.699896) (xy 75.155298 -318.699896) (xy 75.154803 -318.724503)
			(xy 75.146908 -318.77308) (xy 75.131324 -318.819761) (xy 75.108453 -318.863338) (xy 75.078888 -318.902682)
			(xy 75.043395 -318.936774) (xy 75.002892 -318.96473) (xy 74.95843 -318.985828) (xy 74.911159 -318.99952)
			(xy 74.862304 -319.005452) (xy 74.813129 -319.003471) (xy 74.76491 -318.993627) (xy 74.718894 -318.976175)
			(xy 74.676273 -318.951568) (xy 74.638152 -318.920443) (xy 74.605517 -318.883606) (xy 74.579214 -318.84201)
			(xy 74.559923 -318.796734) (xy 74.548146 -318.74895) (xy 74.544186 -318.699896) (xy 74.205084 -318.699896)
			(xy 74.204589 -318.724503) (xy 74.196694 -318.77308) (xy 74.18111 -318.819761) (xy 74.158239 -318.863338)
			(xy 74.128674 -318.902682) (xy 74.093181 -318.936774) (xy 74.052678 -318.96473) (xy 74.008216 -318.985828)
			(xy 73.960945 -318.99952) (xy 73.91209 -319.005452) (xy 73.862915 -319.003471) (xy 73.814696 -318.993627)
			(xy 73.76868 -318.976175) (xy 73.726059 -318.951568) (xy 73.687938 -318.920443) (xy 73.655303 -318.883606)
			(xy 73.629 -318.84201) (xy 73.609709 -318.796734) (xy 73.597932 -318.74895) (xy 73.593972 -318.699896)
			(xy 73.276968 -318.699896) (xy 73.276464 -318.725604) (xy 73.268421 -318.776386) (xy 73.252533 -318.825285)
			(xy 73.22919 -318.871097) (xy 73.198969 -318.912693) (xy 73.162613 -318.949049) (xy 73.121017 -318.97927)
			(xy 73.075205 -319.002613) (xy 73.026306 -319.018501) (xy 72.975524 -319.026544) (xy 72.924108 -319.026544)
			(xy 72.873326 -319.018501) (xy 72.824427 -319.002613) (xy 72.778615 -318.97927) (xy 72.737019 -318.949049)
			(xy 72.700663 -318.912693) (xy 72.670442 -318.871097) (xy 72.647099 -318.825285) (xy 72.631211 -318.776386)
			(xy 72.623168 -318.725604) (xy 72.30449 -318.725604) (xy 72.296774 -318.77308) (xy 72.28119 -318.819761)
			(xy 72.258319 -318.863338) (xy 72.228754 -318.902682) (xy 72.193261 -318.936774) (xy 72.152758 -318.96473)
			(xy 72.108296 -318.985828) (xy 72.061025 -318.99952) (xy 72.01217 -319.005452) (xy 71.962995 -319.003471)
			(xy 71.914776 -318.993627) (xy 71.86876 -318.976175) (xy 71.826139 -318.951568) (xy 71.788018 -318.920443)
			(xy 71.755383 -318.883606) (xy 71.72908 -318.84201) (xy 71.709789 -318.796734) (xy 71.698012 -318.74895)
			(xy 71.694052 -318.699896) (xy 71.377048 -318.699896) (xy 71.376544 -318.725604) (xy 71.368501 -318.776386)
			(xy 71.352613 -318.825285) (xy 71.32927 -318.871097) (xy 71.299049 -318.912693) (xy 71.262693 -318.949049)
			(xy 71.221097 -318.97927) (xy 71.175285 -319.002613) (xy 71.126386 -319.018501) (xy 71.075604 -319.026544)
			(xy 71.024188 -319.026544) (xy 70.973406 -319.018501) (xy 70.924507 -319.002613) (xy 70.878695 -318.97927)
			(xy 70.837099 -318.949049) (xy 70.800743 -318.912693) (xy 70.770522 -318.871097) (xy 70.747179 -318.825285)
			(xy 70.731291 -318.776386) (xy 70.723248 -318.725604) (xy 70.40457 -318.725604) (xy 70.396854 -318.77308)
			(xy 70.38127 -318.819761) (xy 70.358399 -318.863338) (xy 70.328834 -318.902682) (xy 70.293341 -318.936774)
			(xy 70.252838 -318.96473) (xy 70.208376 -318.985828) (xy 70.161105 -318.99952) (xy 70.11225 -319.005452)
			(xy 70.063075 -319.003471) (xy 70.014856 -318.993627) (xy 69.96884 -318.976175) (xy 69.926219 -318.951568)
			(xy 69.888098 -318.920443) (xy 69.855463 -318.883606) (xy 69.82916 -318.84201) (xy 69.809869 -318.796734)
			(xy 69.798092 -318.74895) (xy 69.794132 -318.699896) (xy 69.477128 -318.699896) (xy 69.476624 -318.725604)
			(xy 69.468581 -318.776386) (xy 69.452693 -318.825285) (xy 69.42935 -318.871097) (xy 69.399129 -318.912693)
			(xy 69.362773 -318.949049) (xy 69.321177 -318.97927) (xy 69.275365 -319.002613) (xy 69.226466 -319.018501)
			(xy 69.175684 -319.026544) (xy 69.124268 -319.026544) (xy 69.073486 -319.018501) (xy 69.024587 -319.002613)
			(xy 68.978775 -318.97927) (xy 68.937179 -318.949049) (xy 68.900823 -318.912693) (xy 68.870602 -318.871097)
			(xy 68.847259 -318.825285) (xy 68.831371 -318.776386) (xy 68.823328 -318.725604) (xy 68.504396 -318.725604)
			(xy 68.49668 -318.77308) (xy 68.481096 -318.819761) (xy 68.458225 -318.863338) (xy 68.42866 -318.902682)
			(xy 68.393167 -318.936774) (xy 68.352664 -318.96473) (xy 68.308202 -318.985828) (xy 68.260931 -318.99952)
			(xy 68.212076 -319.005452) (xy 68.162901 -319.003471) (xy 68.114682 -318.993627) (xy 68.068666 -318.976175)
			(xy 68.026045 -318.951568) (xy 67.987924 -318.920443) (xy 67.955289 -318.883606) (xy 67.928986 -318.84201)
			(xy 67.909695 -318.796734) (xy 67.897918 -318.74895) (xy 67.893958 -318.699896) (xy 67.576954 -318.699896)
			(xy 67.57645 -318.725604) (xy 67.568407 -318.776386) (xy 67.552519 -318.825285) (xy 67.529176 -318.871097)
			(xy 67.498955 -318.912693) (xy 67.462599 -318.949049) (xy 67.421003 -318.97927) (xy 67.375191 -319.002613)
			(xy 67.326292 -319.018501) (xy 67.27551 -319.026544) (xy 67.224094 -319.026544) (xy 67.173312 -319.018501)
			(xy 67.124413 -319.002613) (xy 67.078601 -318.97927) (xy 67.037005 -318.949049) (xy 67.000649 -318.912693)
			(xy 66.970428 -318.871097) (xy 66.947085 -318.825285) (xy 66.931197 -318.776386) (xy 66.923154 -318.725604)
			(xy 66.604476 -318.725604) (xy 66.59676 -318.77308) (xy 66.581176 -318.819761) (xy 66.558305 -318.863338)
			(xy 66.52874 -318.902682) (xy 66.493247 -318.936774) (xy 66.452744 -318.96473) (xy 66.408282 -318.985828)
			(xy 66.361011 -318.99952) (xy 66.312156 -319.005452) (xy 66.262981 -319.003471) (xy 66.214762 -318.993627)
			(xy 66.168746 -318.976175) (xy 66.126125 -318.951568) (xy 66.088004 -318.920443) (xy 66.055369 -318.883606)
			(xy 66.029066 -318.84201) (xy 66.009775 -318.796734) (xy 65.997998 -318.74895) (xy 65.994038 -318.699896)
			(xy 65.677034 -318.699896) (xy 65.67653 -318.725604) (xy 65.668487 -318.776386) (xy 65.652599 -318.825285)
			(xy 65.629256 -318.871097) (xy 65.599035 -318.912693) (xy 65.562679 -318.949049) (xy 65.521083 -318.97927)
			(xy 65.475271 -319.002613) (xy 65.426372 -319.018501) (xy 65.37559 -319.026544) (xy 65.324174 -319.026544)
			(xy 65.273392 -319.018501) (xy 65.224493 -319.002613) (xy 65.178681 -318.97927) (xy 65.137085 -318.949049)
			(xy 65.100729 -318.912693) (xy 65.070508 -318.871097) (xy 65.047165 -318.825285) (xy 65.031277 -318.776386)
			(xy 65.023234 -318.725604) (xy 64.704556 -318.725604) (xy 64.69684 -318.77308) (xy 64.681256 -318.819761)
			(xy 64.658385 -318.863338) (xy 64.62882 -318.902682) (xy 64.593327 -318.936774) (xy 64.552824 -318.96473)
			(xy 64.508362 -318.985828) (xy 64.461091 -318.99952) (xy 64.412236 -319.005452) (xy 64.363061 -319.003471)
			(xy 64.314842 -318.993627) (xy 64.268826 -318.976175) (xy 64.226205 -318.951568) (xy 64.188084 -318.920443)
			(xy 64.155449 -318.883606) (xy 64.129146 -318.84201) (xy 64.109855 -318.796734) (xy 64.098078 -318.74895)
			(xy 64.094118 -318.699896) (xy 63.777114 -318.699896) (xy 63.77661 -318.725604) (xy 63.768567 -318.776386)
			(xy 63.752679 -318.825285) (xy 63.729336 -318.871097) (xy 63.699115 -318.912693) (xy 63.662759 -318.949049)
			(xy 63.621163 -318.97927) (xy 63.575351 -319.002613) (xy 63.526452 -319.018501) (xy 63.47567 -319.026544)
			(xy 63.424254 -319.026544) (xy 63.373472 -319.018501) (xy 63.324573 -319.002613) (xy 63.278761 -318.97927)
			(xy 63.237165 -318.949049) (xy 63.200809 -318.912693) (xy 63.170588 -318.871097) (xy 63.147245 -318.825285)
			(xy 63.131357 -318.776386) (xy 63.123314 -318.725604) (xy 62.804382 -318.725604) (xy 62.796666 -318.77308)
			(xy 62.781082 -318.819761) (xy 62.758211 -318.863338) (xy 62.728646 -318.902682) (xy 62.693153 -318.936774)
			(xy 62.65265 -318.96473) (xy 62.608188 -318.985828) (xy 62.560917 -318.99952) (xy 62.512062 -319.005452)
			(xy 62.462887 -319.003471) (xy 62.414668 -318.993627) (xy 62.368652 -318.976175) (xy 62.326031 -318.951568)
			(xy 62.28791 -318.920443) (xy 62.255275 -318.883606) (xy 62.228972 -318.84201) (xy 62.209681 -318.796734)
			(xy 62.197904 -318.74895) (xy 62.193944 -318.699896) (xy 61.87694 -318.699896) (xy 61.876436 -318.725604)
			(xy 61.868393 -318.776386) (xy 61.852505 -318.825285) (xy 61.829162 -318.871097) (xy 61.798941 -318.912693)
			(xy 61.762585 -318.949049) (xy 61.720989 -318.97927) (xy 61.675177 -319.002613) (xy 61.626278 -319.018501)
			(xy 61.575496 -319.026544) (xy 61.52408 -319.026544) (xy 61.473298 -319.018501) (xy 61.424399 -319.002613)
			(xy 61.378587 -318.97927) (xy 61.336991 -318.949049) (xy 61.300635 -318.912693) (xy 61.270414 -318.871097)
			(xy 61.247071 -318.825285) (xy 61.231183 -318.776386) (xy 61.22314 -318.725604) (xy 60.904462 -318.725604)
			(xy 60.896746 -318.77308) (xy 60.881162 -318.819761) (xy 60.858291 -318.863338) (xy 60.828726 -318.902682)
			(xy 60.793233 -318.936774) (xy 60.75273 -318.96473) (xy 60.708268 -318.985828) (xy 60.660997 -318.99952)
			(xy 60.612142 -319.005452) (xy 60.562967 -319.003471) (xy 60.514748 -318.993627) (xy 60.468732 -318.976175)
			(xy 60.426111 -318.951568) (xy 60.38799 -318.920443) (xy 60.355355 -318.883606) (xy 60.329052 -318.84201)
			(xy 60.309761 -318.796734) (xy 60.297984 -318.74895) (xy 60.294024 -318.699896) (xy 59.97702 -318.699896)
			(xy 59.976516 -318.725604) (xy 59.968473 -318.776386) (xy 59.952585 -318.825285) (xy 59.929242 -318.871097)
			(xy 59.899021 -318.912693) (xy 59.862665 -318.949049) (xy 59.821069 -318.97927) (xy 59.775257 -319.002613)
			(xy 59.726358 -319.018501) (xy 59.675576 -319.026544) (xy 59.62416 -319.026544) (xy 59.573378 -319.018501)
			(xy 59.524479 -319.002613) (xy 59.478667 -318.97927) (xy 59.437071 -318.949049) (xy 59.400715 -318.912693)
			(xy 59.370494 -318.871097) (xy 59.347151 -318.825285) (xy 59.331263 -318.776386) (xy 59.32322 -318.725604)
			(xy 59.040776 -318.725604) (xy 59.040776 -319.65011) (xy 59.344064 -319.65011) (xy 59.348024 -319.601056)
			(xy 59.359801 -319.553272) (xy 59.379092 -319.507996) (xy 59.405395 -319.4664) (xy 59.43803 -319.429563)
			(xy 59.476151 -319.398438) (xy 59.518772 -319.373831) (xy 59.564788 -319.356379) (xy 59.613007 -319.346535)
			(xy 59.662182 -319.344554) (xy 59.711037 -319.350486) (xy 59.758308 -319.364178) (xy 59.80277 -319.385276)
			(xy 59.843273 -319.413232) (xy 59.878766 -319.447324) (xy 59.908331 -319.486668) (xy 59.931202 -319.530245)
			(xy 59.946786 -319.576926) (xy 59.954681 -319.625503) (xy 59.955176 -319.65011) (xy 61.243984 -319.65011)
			(xy 61.247944 -319.601056) (xy 61.259721 -319.553272) (xy 61.279012 -319.507996) (xy 61.305315 -319.4664)
			(xy 61.33795 -319.429563) (xy 61.376071 -319.398438) (xy 61.418692 -319.373831) (xy 61.464708 -319.356379)
			(xy 61.512927 -319.346535) (xy 61.562102 -319.344554) (xy 61.610957 -319.350486) (xy 61.658228 -319.364178)
			(xy 61.70269 -319.385276) (xy 61.743193 -319.413232) (xy 61.778686 -319.447324) (xy 61.808251 -319.486668)
			(xy 61.831122 -319.530245) (xy 61.846706 -319.576926) (xy 61.854601 -319.625503) (xy 61.855096 -319.65011)
			(xy 63.144158 -319.65011) (xy 63.148118 -319.601056) (xy 63.159895 -319.553272) (xy 63.179186 -319.507996)
			(xy 63.205489 -319.4664) (xy 63.238124 -319.429563) (xy 63.276245 -319.398438) (xy 63.318866 -319.373831)
			(xy 63.364882 -319.356379) (xy 63.413101 -319.346535) (xy 63.462276 -319.344554) (xy 63.511131 -319.350486)
			(xy 63.558402 -319.364178) (xy 63.602864 -319.385276) (xy 63.643367 -319.413232) (xy 63.67886 -319.447324)
			(xy 63.708425 -319.486668) (xy 63.731296 -319.530245) (xy 63.74688 -319.576926) (xy 63.754775 -319.625503)
			(xy 63.75527 -319.65011) (xy 65.044078 -319.65011) (xy 65.048038 -319.601056) (xy 65.059815 -319.553272)
			(xy 65.079106 -319.507996) (xy 65.105409 -319.4664) (xy 65.138044 -319.429563) (xy 65.176165 -319.398438)
			(xy 65.218786 -319.373831) (xy 65.264802 -319.356379) (xy 65.313021 -319.346535) (xy 65.362196 -319.344554)
			(xy 65.411051 -319.350486) (xy 65.458322 -319.364178) (xy 65.502784 -319.385276) (xy 65.543287 -319.413232)
			(xy 65.57878 -319.447324) (xy 65.608345 -319.486668) (xy 65.631216 -319.530245) (xy 65.6468 -319.576926)
			(xy 65.654695 -319.625503) (xy 65.65519 -319.65011) (xy 66.943998 -319.65011) (xy 66.947958 -319.601056)
			(xy 66.959735 -319.553272) (xy 66.979026 -319.507996) (xy 67.005329 -319.4664) (xy 67.037964 -319.429563)
			(xy 67.076085 -319.398438) (xy 67.118706 -319.373831) (xy 67.164722 -319.356379) (xy 67.212941 -319.346535)
			(xy 67.262116 -319.344554) (xy 67.310971 -319.350486) (xy 67.358242 -319.364178) (xy 67.402704 -319.385276)
			(xy 67.443207 -319.413232) (xy 67.4787 -319.447324) (xy 67.508265 -319.486668) (xy 67.531136 -319.530245)
			(xy 67.54672 -319.576926) (xy 67.554615 -319.625503) (xy 67.55511 -319.65011) (xy 68.844172 -319.65011)
			(xy 68.848132 -319.601056) (xy 68.859909 -319.553272) (xy 68.8792 -319.507996) (xy 68.905503 -319.4664)
			(xy 68.938138 -319.429563) (xy 68.976259 -319.398438) (xy 69.01888 -319.373831) (xy 69.064896 -319.356379)
			(xy 69.113115 -319.346535) (xy 69.16229 -319.344554) (xy 69.211145 -319.350486) (xy 69.258416 -319.364178)
			(xy 69.302878 -319.385276) (xy 69.343381 -319.413232) (xy 69.378874 -319.447324) (xy 69.408439 -319.486668)
			(xy 69.43131 -319.530245) (xy 69.446894 -319.576926) (xy 69.454789 -319.625503) (xy 69.455284 -319.65011)
			(xy 70.744092 -319.65011) (xy 70.748052 -319.601056) (xy 70.759829 -319.553272) (xy 70.77912 -319.507996)
			(xy 70.805423 -319.4664) (xy 70.838058 -319.429563) (xy 70.876179 -319.398438) (xy 70.9188 -319.373831)
			(xy 70.964816 -319.356379) (xy 71.013035 -319.346535) (xy 71.06221 -319.344554) (xy 71.111065 -319.350486)
			(xy 71.158336 -319.364178) (xy 71.202798 -319.385276) (xy 71.243301 -319.413232) (xy 71.278794 -319.447324)
			(xy 71.308359 -319.486668) (xy 71.33123 -319.530245) (xy 71.346814 -319.576926) (xy 71.354709 -319.625503)
			(xy 71.355204 -319.65011) (xy 72.644012 -319.65011) (xy 72.647972 -319.601056) (xy 72.659749 -319.553272)
			(xy 72.67904 -319.507996) (xy 72.705343 -319.4664) (xy 72.737978 -319.429563) (xy 72.776099 -319.398438)
			(xy 72.81872 -319.373831) (xy 72.864736 -319.356379) (xy 72.912955 -319.346535) (xy 72.96213 -319.344554)
			(xy 73.010985 -319.350486) (xy 73.058256 -319.364178) (xy 73.102718 -319.385276) (xy 73.143221 -319.413232)
			(xy 73.178714 -319.447324) (xy 73.208279 -319.486668) (xy 73.23115 -319.530245) (xy 73.246734 -319.576926)
			(xy 73.254629 -319.625503) (xy 73.255124 -319.65011) (xy 74.544186 -319.65011) (xy 74.548146 -319.601056)
			(xy 74.559923 -319.553272) (xy 74.579214 -319.507996) (xy 74.605517 -319.4664) (xy 74.638152 -319.429563)
			(xy 74.676273 -319.398438) (xy 74.718894 -319.373831) (xy 74.76491 -319.356379) (xy 74.813129 -319.346535)
			(xy 74.862304 -319.344554) (xy 74.911159 -319.350486) (xy 74.95843 -319.364178) (xy 75.002892 -319.385276)
			(xy 75.043395 -319.413232) (xy 75.078888 -319.447324) (xy 75.108453 -319.486668) (xy 75.131324 -319.530245)
			(xy 75.146908 -319.576926) (xy 75.154803 -319.625503) (xy 75.155298 -319.65011) (xy 76.444106 -319.65011)
			(xy 76.448066 -319.601056) (xy 76.459843 -319.553272) (xy 76.479134 -319.507996) (xy 76.505437 -319.4664)
			(xy 76.538072 -319.429563) (xy 76.576193 -319.398438) (xy 76.618814 -319.373831) (xy 76.66483 -319.356379)
			(xy 76.713049 -319.346535) (xy 76.762224 -319.344554) (xy 76.811079 -319.350486) (xy 76.85835 -319.364178)
			(xy 76.902812 -319.385276) (xy 76.943315 -319.413232) (xy 76.978808 -319.447324) (xy 77.008373 -319.486668)
			(xy 77.031244 -319.530245) (xy 77.046828 -319.576926) (xy 77.054723 -319.625503) (xy 77.055218 -319.65011)
			(xy 78.344026 -319.65011) (xy 78.347986 -319.601056) (xy 78.359763 -319.553272) (xy 78.379054 -319.507996)
			(xy 78.405357 -319.4664) (xy 78.437992 -319.429563) (xy 78.476113 -319.398438) (xy 78.518734 -319.373831)
			(xy 78.56475 -319.356379) (xy 78.612969 -319.346535) (xy 78.662144 -319.344554) (xy 78.710999 -319.350486)
			(xy 78.75827 -319.364178) (xy 78.802732 -319.385276) (xy 78.843235 -319.413232) (xy 78.878728 -319.447324)
			(xy 78.908293 -319.486668) (xy 78.931164 -319.530245) (xy 78.946748 -319.576926) (xy 78.954643 -319.625503)
			(xy 78.955138 -319.65011) (xy 80.243946 -319.65011) (xy 80.247906 -319.601056) (xy 80.259683 -319.553272)
			(xy 80.278974 -319.507996) (xy 80.305277 -319.4664) (xy 80.337912 -319.429563) (xy 80.376033 -319.398438)
			(xy 80.418654 -319.373831) (xy 80.46467 -319.356379) (xy 80.512889 -319.346535) (xy 80.562064 -319.344554)
			(xy 80.610919 -319.350486) (xy 80.65819 -319.364178) (xy 80.702652 -319.385276) (xy 80.743155 -319.413232)
			(xy 80.778648 -319.447324) (xy 80.808213 -319.486668) (xy 80.831084 -319.530245) (xy 80.846668 -319.576926)
			(xy 80.854563 -319.625503) (xy 80.855058 -319.65011) (xy 80.854563 -319.674717) (xy 80.846668 -319.723294)
			(xy 80.831084 -319.769975) (xy 80.808213 -319.813552) (xy 80.778648 -319.852896) (xy 80.743155 -319.886988)
			(xy 80.702652 -319.914944) (xy 80.65819 -319.936042) (xy 80.610919 -319.949734) (xy 80.562064 -319.955666)
			(xy 80.512889 -319.953685) (xy 80.46467 -319.943841) (xy 80.418654 -319.926389) (xy 80.376033 -319.901782)
			(xy 80.337912 -319.870657) (xy 80.305277 -319.83382) (xy 80.278974 -319.792224) (xy 80.259683 -319.746948)
			(xy 80.247906 -319.699164) (xy 80.243946 -319.65011) (xy 78.955138 -319.65011) (xy 78.954643 -319.674717)
			(xy 78.946748 -319.723294) (xy 78.931164 -319.769975) (xy 78.908293 -319.813552) (xy 78.878728 -319.852896)
			(xy 78.843235 -319.886988) (xy 78.802732 -319.914944) (xy 78.75827 -319.936042) (xy 78.710999 -319.949734)
			(xy 78.662144 -319.955666) (xy 78.612969 -319.953685) (xy 78.56475 -319.943841) (xy 78.518734 -319.926389)
			(xy 78.476113 -319.901782) (xy 78.437992 -319.870657) (xy 78.405357 -319.83382) (xy 78.379054 -319.792224)
			(xy 78.359763 -319.746948) (xy 78.347986 -319.699164) (xy 78.344026 -319.65011) (xy 77.055218 -319.65011)
			(xy 77.054723 -319.674717) (xy 77.046828 -319.723294) (xy 77.031244 -319.769975) (xy 77.008373 -319.813552)
			(xy 76.978808 -319.852896) (xy 76.943315 -319.886988) (xy 76.902812 -319.914944) (xy 76.85835 -319.936042)
			(xy 76.811079 -319.949734) (xy 76.762224 -319.955666) (xy 76.713049 -319.953685) (xy 76.66483 -319.943841)
			(xy 76.618814 -319.926389) (xy 76.576193 -319.901782) (xy 76.538072 -319.870657) (xy 76.505437 -319.83382)
			(xy 76.479134 -319.792224) (xy 76.459843 -319.746948) (xy 76.448066 -319.699164) (xy 76.444106 -319.65011)
			(xy 75.155298 -319.65011) (xy 75.154803 -319.674717) (xy 75.146908 -319.723294) (xy 75.131324 -319.769975)
			(xy 75.108453 -319.813552) (xy 75.078888 -319.852896) (xy 75.043395 -319.886988) (xy 75.002892 -319.914944)
			(xy 74.95843 -319.936042) (xy 74.911159 -319.949734) (xy 74.862304 -319.955666) (xy 74.813129 -319.953685)
			(xy 74.76491 -319.943841) (xy 74.718894 -319.926389) (xy 74.676273 -319.901782) (xy 74.638152 -319.870657)
			(xy 74.605517 -319.83382) (xy 74.579214 -319.792224) (xy 74.559923 -319.746948) (xy 74.548146 -319.699164)
			(xy 74.544186 -319.65011) (xy 73.255124 -319.65011) (xy 73.254629 -319.674717) (xy 73.246734 -319.723294)
			(xy 73.23115 -319.769975) (xy 73.208279 -319.813552) (xy 73.178714 -319.852896) (xy 73.143221 -319.886988)
			(xy 73.102718 -319.914944) (xy 73.058256 -319.936042) (xy 73.010985 -319.949734) (xy 72.96213 -319.955666)
			(xy 72.912955 -319.953685) (xy 72.864736 -319.943841) (xy 72.81872 -319.926389) (xy 72.776099 -319.901782)
			(xy 72.737978 -319.870657) (xy 72.705343 -319.83382) (xy 72.67904 -319.792224) (xy 72.659749 -319.746948)
			(xy 72.647972 -319.699164) (xy 72.644012 -319.65011) (xy 71.355204 -319.65011) (xy 71.354709 -319.674717)
			(xy 71.346814 -319.723294) (xy 71.33123 -319.769975) (xy 71.308359 -319.813552) (xy 71.278794 -319.852896)
			(xy 71.243301 -319.886988) (xy 71.202798 -319.914944) (xy 71.158336 -319.936042) (xy 71.111065 -319.949734)
			(xy 71.06221 -319.955666) (xy 71.013035 -319.953685) (xy 70.964816 -319.943841) (xy 70.9188 -319.926389)
			(xy 70.876179 -319.901782) (xy 70.838058 -319.870657) (xy 70.805423 -319.83382) (xy 70.77912 -319.792224)
			(xy 70.759829 -319.746948) (xy 70.748052 -319.699164) (xy 70.744092 -319.65011) (xy 69.455284 -319.65011)
			(xy 69.454789 -319.674717) (xy 69.446894 -319.723294) (xy 69.43131 -319.769975) (xy 69.408439 -319.813552)
			(xy 69.378874 -319.852896) (xy 69.343381 -319.886988) (xy 69.302878 -319.914944) (xy 69.258416 -319.936042)
			(xy 69.211145 -319.949734) (xy 69.16229 -319.955666) (xy 69.113115 -319.953685) (xy 69.064896 -319.943841)
			(xy 69.01888 -319.926389) (xy 68.976259 -319.901782) (xy 68.938138 -319.870657) (xy 68.905503 -319.83382)
			(xy 68.8792 -319.792224) (xy 68.859909 -319.746948) (xy 68.848132 -319.699164) (xy 68.844172 -319.65011)
			(xy 67.55511 -319.65011) (xy 67.554615 -319.674717) (xy 67.54672 -319.723294) (xy 67.531136 -319.769975)
			(xy 67.508265 -319.813552) (xy 67.4787 -319.852896) (xy 67.443207 -319.886988) (xy 67.402704 -319.914944)
			(xy 67.358242 -319.936042) (xy 67.310971 -319.949734) (xy 67.262116 -319.955666) (xy 67.212941 -319.953685)
			(xy 67.164722 -319.943841) (xy 67.118706 -319.926389) (xy 67.076085 -319.901782) (xy 67.037964 -319.870657)
			(xy 67.005329 -319.83382) (xy 66.979026 -319.792224) (xy 66.959735 -319.746948) (xy 66.947958 -319.699164)
			(xy 66.943998 -319.65011) (xy 65.65519 -319.65011) (xy 65.654695 -319.674717) (xy 65.6468 -319.723294)
			(xy 65.631216 -319.769975) (xy 65.608345 -319.813552) (xy 65.57878 -319.852896) (xy 65.543287 -319.886988)
			(xy 65.502784 -319.914944) (xy 65.458322 -319.936042) (xy 65.411051 -319.949734) (xy 65.362196 -319.955666)
			(xy 65.313021 -319.953685) (xy 65.264802 -319.943841) (xy 65.218786 -319.926389) (xy 65.176165 -319.901782)
			(xy 65.138044 -319.870657) (xy 65.105409 -319.83382) (xy 65.079106 -319.792224) (xy 65.059815 -319.746948)
			(xy 65.048038 -319.699164) (xy 65.044078 -319.65011) (xy 63.75527 -319.65011) (xy 63.754775 -319.674717)
			(xy 63.74688 -319.723294) (xy 63.731296 -319.769975) (xy 63.708425 -319.813552) (xy 63.67886 -319.852896)
			(xy 63.643367 -319.886988) (xy 63.602864 -319.914944) (xy 63.558402 -319.936042) (xy 63.511131 -319.949734)
			(xy 63.462276 -319.955666) (xy 63.413101 -319.953685) (xy 63.364882 -319.943841) (xy 63.318866 -319.926389)
			(xy 63.276245 -319.901782) (xy 63.238124 -319.870657) (xy 63.205489 -319.83382) (xy 63.179186 -319.792224)
			(xy 63.159895 -319.746948) (xy 63.148118 -319.699164) (xy 63.144158 -319.65011) (xy 61.855096 -319.65011)
			(xy 61.854601 -319.674717) (xy 61.846706 -319.723294) (xy 61.831122 -319.769975) (xy 61.808251 -319.813552)
			(xy 61.778686 -319.852896) (xy 61.743193 -319.886988) (xy 61.70269 -319.914944) (xy 61.658228 -319.936042)
			(xy 61.610957 -319.949734) (xy 61.562102 -319.955666) (xy 61.512927 -319.953685) (xy 61.464708 -319.943841)
			(xy 61.418692 -319.926389) (xy 61.376071 -319.901782) (xy 61.33795 -319.870657) (xy 61.305315 -319.83382)
			(xy 61.279012 -319.792224) (xy 61.259721 -319.746948) (xy 61.247944 -319.699164) (xy 61.243984 -319.65011)
			(xy 59.955176 -319.65011) (xy 59.954681 -319.674717) (xy 59.946786 -319.723294) (xy 59.931202 -319.769975)
			(xy 59.908331 -319.813552) (xy 59.878766 -319.852896) (xy 59.843273 -319.886988) (xy 59.80277 -319.914944)
			(xy 59.758308 -319.936042) (xy 59.711037 -319.949734) (xy 59.662182 -319.955666) (xy 59.613007 -319.953685)
			(xy 59.564788 -319.943841) (xy 59.518772 -319.926389) (xy 59.476151 -319.901782) (xy 59.43803 -319.870657)
			(xy 59.405395 -319.83382) (xy 59.379092 -319.792224) (xy 59.359801 -319.746948) (xy 59.348024 -319.699164)
			(xy 59.344064 -319.65011) (xy 59.040776 -319.65011) (xy 59.040776 -319.947036) (xy 59.041205 -319.957104)
			(xy 59.048926 -319.975701) (xy 59.055762 -319.983104) (xy 59.644788 -320.57213) (xy 59.649614 -320.576448)
			(xy 59.659266 -320.58229) (xy 59.891676 -320.692272) (xy 59.915806 -320.703702) (xy 59.951925 -320.721195)
			(xy 60.021488 -320.761229) (xy 60.087572 -320.806775) (xy 60.149743 -320.857534) (xy 60.17895 -320.885058)
			(xy 60.179712 -320.886074) (xy 60.182252 -320.88836) (xy 60.185127 -320.890983) (xy 60.191505 -320.895442)
			(xy 60.194952 -320.89725) (xy 60.200913 -320.900044) (xy 84.898745 -320.900044) (xy 84.902751 -320.704989)
			(xy 84.914761 -320.510263) (xy 84.934756 -320.316194) (xy 84.962701 -320.12311) (xy 84.99855 -319.931335)
			(xy 85.042242 -319.741195) (xy 85.093703 -319.553008) (xy 85.152847 -319.367093) (xy 85.219574 -319.183762)
			(xy 85.293771 -319.003326) (xy 85.375313 -318.826088) (xy 85.464064 -318.652347) (xy 85.559872 -318.482396)
			(xy 85.662577 -318.316522) (xy 85.772005 -318.155004) (xy 85.887972 -317.998115) (xy 86.010283 -317.84612)
			(xy 86.13873 -317.699274) (xy 86.273098 -317.557825) (xy 86.41316 -317.422012) (xy 86.558679 -317.292063)
			(xy 86.709411 -317.168199) (xy 86.865101 -317.050627) (xy 87.025487 -316.939547) (xy 87.190298 -316.835144)
			(xy 87.359256 -316.737596) (xy 87.532077 -316.647067) (xy 87.708469 -316.563709) (xy 87.888134 -316.487663)
			(xy 88.070769 -316.419058) (xy 88.256068 -316.358008) (xy 88.443716 -316.304618) (xy 88.633398 -316.258976)
			(xy 88.824795 -316.22116) (xy 89.017582 -316.191234) (xy 89.211435 -316.169248) (xy 89.406028 -316.155239)
			(xy 89.601031 -316.149231) (xy 89.796117 -316.151234) (xy 89.990956 -316.161245) (xy 90.18522 -316.179246)
			(xy 90.378581 -316.205208) (xy 90.570714 -316.239086) (xy 90.761293 -316.280823) (xy 90.949998 -316.33035)
			(xy 91.136511 -316.387582) (xy 91.320517 -316.452423) (xy 91.501705 -316.524764) (xy 91.679771 -316.604482)
			(xy 91.854414 -316.691444) (xy 92.02534 -316.785503) (xy 92.192259 -316.886499) (xy 92.354892 -316.994264)
			(xy 92.512963 -317.108614) (xy 92.666206 -317.229357) (xy 92.814363 -317.356291) (xy 92.957184 -317.489199)
			(xy 93.094428 -317.627859) (xy 93.225864 -317.772037) (xy 93.351269 -317.92149) (xy 93.470433 -318.075964)
			(xy 93.583154 -318.235201) (xy 93.689243 -318.398932) (xy 93.788521 -318.566879) (xy 93.880819 -318.738762)
			(xy 93.965984 -318.914288) (xy 94.04387 -319.093163) (xy 94.114347 -319.275085) (xy 94.177295 -319.459747)
			(xy 94.23261 -319.646837) (xy 94.280196 -319.836041) (xy 94.319975 -320.027038) (xy 94.32886 -320.08064)
			(xy 106.2228 -320.08064) (xy 106.223347 -320.051724) (xy 106.23207 -319.994554) (xy 106.249322 -319.939356)
			(xy 106.274709 -319.887394) (xy 106.307647 -319.83986) (xy 106.347383 -319.797841) (xy 106.369866 -319.77965)
			(xy 106.378612 -319.772073) (xy 106.388801 -319.751325) (xy 106.389424 -319.739772) (xy 106.389424 -319.659508)
			(xy 106.388875 -319.647937) (xy 106.378668 -319.627164) (xy 106.369866 -319.61963) (xy 106.34739 -319.601431)
			(xy 106.307656 -319.559412) (xy 106.274717 -319.511878) (xy 106.249328 -319.459919) (xy 106.232069 -319.404723)
			(xy 106.223337 -319.347555) (xy 106.2228 -319.31864) (xy 106.223293 -319.291388) (xy 106.231044 -319.237437)
			(xy 106.246396 -319.18514) (xy 106.269034 -319.135559) (xy 106.298499 -319.089705) (xy 106.334189 -319.048512)
			(xy 106.37538 -319.012818) (xy 106.421231 -318.983349) (xy 106.47081 -318.960707) (xy 106.523106 -318.945351)
			(xy 106.577056 -318.937595) (xy 106.604308 -318.937132) (xy 106.633223 -318.937704) (xy 106.690392 -318.946421)
			(xy 106.74559 -318.963667) (xy 106.797553 -318.989048) (xy 106.845088 -319.021983) (xy 106.887106 -319.061716)
			(xy 106.905298 -319.084198) (xy 106.912865 -319.092954) (xy 106.93362 -319.103141) (xy 106.945176 -319.103756)
			(xy 107.02544 -319.103756) (xy 107.037006 -319.103167) (xy 107.057778 -319.092987) (xy 107.065318 -319.084198)
			(xy 107.082071 -319.063415) (xy 107.120425 -319.026285) (xy 107.163579 -318.994863) (xy 107.210693 -318.969764)
			(xy 107.260845 -318.951478) (xy 107.313056 -318.940361) (xy 107.366308 -318.936631) (xy 107.41956 -318.940361)
			(xy 107.471771 -318.951478) (xy 107.521923 -318.969764) (xy 107.569037 -318.994863) (xy 107.612191 -319.026285)
			(xy 107.650545 -319.063415) (xy 107.667298 -319.084198) (xy 107.674865 -319.092954) (xy 107.69562 -319.103141)
			(xy 107.707176 -319.103756) (xy 107.78744 -319.103756) (xy 107.799006 -319.103167) (xy 107.819778 -319.092987)
			(xy 107.827318 -319.084198) (xy 107.844071 -319.063415) (xy 107.882425 -319.026285) (xy 107.925579 -318.994863)
			(xy 107.972693 -318.969764) (xy 108.022845 -318.951478) (xy 108.075056 -318.940361) (xy 108.128308 -318.936631)
			(xy 108.18156 -318.940361) (xy 108.233771 -318.951478) (xy 108.283923 -318.969764) (xy 108.331037 -318.994863)
			(xy 108.374191 -319.026285) (xy 108.412545 -319.063415) (xy 108.429298 -319.084198) (xy 108.436865 -319.092954)
			(xy 108.45762 -319.103141) (xy 108.469176 -319.103756) (xy 108.54944 -319.103756) (xy 108.561006 -319.103167)
			(xy 108.581778 -319.092987) (xy 108.589318 -319.084198) (xy 108.606071 -319.063415) (xy 108.644425 -319.026285)
			(xy 108.687579 -318.994863) (xy 108.734693 -318.969764) (xy 108.784845 -318.951478) (xy 108.837056 -318.940361)
			(xy 108.890308 -318.936631) (xy 108.94356 -318.940361) (xy 108.995771 -318.951478) (xy 109.045923 -318.969764)
			(xy 109.093037 -318.994863) (xy 109.136191 -319.026285) (xy 109.174545 -319.063415) (xy 109.191298 -319.084198)
			(xy 109.198865 -319.092954) (xy 109.21962 -319.103141) (xy 109.231176 -319.103756) (xy 109.31144 -319.103756)
			(xy 109.323006 -319.103167) (xy 109.343778 -319.092987) (xy 109.351318 -319.084198) (xy 109.368071 -319.063415)
			(xy 109.406425 -319.026285) (xy 109.449579 -318.994863) (xy 109.496693 -318.969764) (xy 109.546845 -318.951478)
			(xy 109.599056 -318.940361) (xy 109.652308 -318.936631) (xy 109.70556 -318.940361) (xy 109.757771 -318.951478)
			(xy 109.807923 -318.969764) (xy 109.855037 -318.994863) (xy 109.898191 -319.026285) (xy 109.936545 -319.063415)
			(xy 109.953298 -319.084198) (xy 109.960865 -319.092954) (xy 109.98162 -319.103141) (xy 109.993176 -319.103756)
			(xy 110.07344 -319.103756) (xy 110.085006 -319.103167) (xy 110.105778 -319.092987) (xy 110.113318 -319.084198)
			(xy 110.130071 -319.063415) (xy 110.168425 -319.026285) (xy 110.211579 -318.994863) (xy 110.258693 -318.969764)
			(xy 110.308845 -318.951478) (xy 110.361056 -318.940361) (xy 110.414308 -318.936631) (xy 110.46756 -318.940361)
			(xy 110.519771 -318.951478) (xy 110.569923 -318.969764) (xy 110.617037 -318.994863) (xy 110.660191 -319.026285)
			(xy 110.698545 -319.063415) (xy 110.715298 -319.084198) (xy 110.722865 -319.092954) (xy 110.74362 -319.103141)
			(xy 110.755176 -319.103756) (xy 110.83544 -319.103756) (xy 110.847006 -319.103167) (xy 110.867778 -319.092987)
			(xy 110.875318 -319.084198) (xy 110.892071 -319.063415) (xy 110.930425 -319.026285) (xy 110.973579 -318.994863)
			(xy 111.020693 -318.969764) (xy 111.070845 -318.951478) (xy 111.123056 -318.940361) (xy 111.176308 -318.936631)
			(xy 111.22956 -318.940361) (xy 111.281771 -318.951478) (xy 111.331923 -318.969764) (xy 111.379037 -318.994863)
			(xy 111.422191 -319.026285) (xy 111.460545 -319.063415) (xy 111.477298 -319.084198) (xy 111.484865 -319.092954)
			(xy 111.50562 -319.103141) (xy 111.517176 -319.103756) (xy 111.59744 -319.103756) (xy 111.609006 -319.103167)
			(xy 111.629778 -319.092987) (xy 111.637318 -319.084198) (xy 111.654071 -319.063415) (xy 111.692425 -319.026285)
			(xy 111.735579 -318.994863) (xy 111.782693 -318.969764) (xy 111.832845 -318.951478) (xy 111.885056 -318.940361)
			(xy 111.938308 -318.936631) (xy 111.99156 -318.940361) (xy 112.043771 -318.951478) (xy 112.093923 -318.969764)
			(xy 112.141037 -318.994863) (xy 112.184191 -319.026285) (xy 112.222545 -319.063415) (xy 112.239298 -319.084198)
			(xy 112.246865 -319.092954) (xy 112.26762 -319.103141) (xy 112.279176 -319.103756) (xy 112.35944 -319.103756)
			(xy 112.371006 -319.103167) (xy 112.391778 -319.092987) (xy 112.399318 -319.084198) (xy 112.416071 -319.063415)
			(xy 112.454425 -319.026285) (xy 112.497579 -318.994863) (xy 112.544693 -318.969764) (xy 112.594845 -318.951478)
			(xy 112.647056 -318.940361) (xy 112.700308 -318.936631) (xy 112.75356 -318.940361) (xy 112.805771 -318.951478)
			(xy 112.855923 -318.969764) (xy 112.903037 -318.994863) (xy 112.946191 -319.026285) (xy 112.984545 -319.063415)
			(xy 113.001298 -319.084198) (xy 113.008865 -319.092954) (xy 113.02962 -319.103141) (xy 113.041176 -319.103756)
			(xy 113.12144 -319.103756) (xy 113.133006 -319.103167) (xy 113.153778 -319.092987) (xy 113.161318 -319.084198)
			(xy 113.178071 -319.063415) (xy 113.216425 -319.026285) (xy 113.259579 -318.994863) (xy 113.306693 -318.969764)
			(xy 113.356845 -318.951478) (xy 113.409056 -318.940361) (xy 113.462308 -318.936631) (xy 113.51556 -318.940361)
			(xy 113.567771 -318.951478) (xy 113.617923 -318.969764) (xy 113.665037 -318.994863) (xy 113.708191 -319.026285)
			(xy 113.746545 -319.063415) (xy 113.763298 -319.084198) (xy 113.770865 -319.092954) (xy 113.79162 -319.103141)
			(xy 113.803176 -319.103756) (xy 113.88344 -319.103756) (xy 113.895006 -319.103167) (xy 113.915778 -319.092987)
			(xy 113.923318 -319.084198) (xy 113.941498 -319.061705) (xy 113.98352 -319.021971) (xy 114.031058 -318.989033)
			(xy 114.083021 -318.963646) (xy 114.13822 -318.946392) (xy 114.195391 -318.937666) (xy 114.224308 -318.937132)
			(xy 114.251563 -318.937548) (xy 114.305518 -318.945307) (xy 114.357819 -318.960666) (xy 114.407402 -318.983313)
			(xy 114.453257 -319.012785) (xy 114.49445 -319.048484) (xy 114.530144 -319.089682) (xy 114.559611 -319.135541)
			(xy 114.582251 -319.185126) (xy 114.597603 -319.237429) (xy 114.605355 -319.291385) (xy 114.605816 -319.31864)
			(xy 114.605286 -319.347557) (xy 114.596564 -319.404729) (xy 114.57931 -319.459929) (xy 114.553921 -319.511891)
			(xy 114.520978 -319.559425) (xy 114.481236 -319.601441) (xy 114.45875 -319.61963) (xy 114.44997 -319.627174)
			(xy 114.439799 -319.647947) (xy 114.439192 -319.659508) (xy 114.439192 -319.739772) (xy 114.439781 -319.751337)
			(xy 114.449963 -319.772108) (xy 114.45875 -319.77965) (xy 114.48122 -319.797857) (xy 114.520954 -319.839875)
			(xy 114.553893 -319.887407) (xy 114.579283 -319.939365) (xy 114.596543 -319.994559) (xy 114.605278 -320.051725)
			(xy 114.605816 -320.08064) (xy 114.605359 -320.107892) (xy 114.597598 -320.16184) (xy 114.582238 -320.214135)
			(xy 114.559593 -320.263712) (xy 114.530123 -320.309562) (xy 114.494429 -320.350751) (xy 114.453236 -320.386442)
			(xy 114.407384 -320.415908) (xy 114.357805 -320.438549) (xy 114.305509 -320.453904) (xy 114.25156 -320.461662)
			(xy 114.224308 -320.462148) (xy 114.19539 -320.461644) (xy 114.138218 -320.452914) (xy 114.083018 -320.435655)
			(xy 114.031056 -320.410261) (xy 113.983522 -320.377314) (xy 113.941507 -320.337569) (xy 113.923318 -320.315082)
			(xy 113.915747 -320.306329) (xy 113.894995 -320.296141) (xy 113.88344 -320.295524) (xy 113.803176 -320.295524)
			(xy 113.791612 -320.296129) (xy 113.77084 -320.306298) (xy 113.763298 -320.315082) (xy 113.746545 -320.335865)
			(xy 113.708191 -320.372995) (xy 113.665037 -320.404417) (xy 113.617923 -320.429516) (xy 113.567771 -320.447802)
			(xy 113.51556 -320.458919) (xy 113.462308 -320.462649) (xy 113.409056 -320.458919) (xy 113.356845 -320.447802)
			(xy 113.306693 -320.429516) (xy 113.259579 -320.404417) (xy 113.216425 -320.372995) (xy 113.178071 -320.335865)
			(xy 113.161318 -320.315082) (xy 113.153747 -320.306329) (xy 113.132995 -320.296141) (xy 113.12144 -320.295524)
			(xy 113.041176 -320.295524) (xy 113.029612 -320.296129) (xy 113.00884 -320.306298) (xy 113.001298 -320.315082)
			(xy 112.984545 -320.335865) (xy 112.946191 -320.372995) (xy 112.903037 -320.404417) (xy 112.855923 -320.429516)
			(xy 112.805771 -320.447802) (xy 112.75356 -320.458919) (xy 112.700308 -320.462649) (xy 112.647056 -320.458919)
			(xy 112.594845 -320.447802) (xy 112.544693 -320.429516) (xy 112.497579 -320.404417) (xy 112.454425 -320.372995)
			(xy 112.416071 -320.335865) (xy 112.399318 -320.315082) (xy 112.391747 -320.306329) (xy 112.370995 -320.296141)
			(xy 112.35944 -320.295524) (xy 112.279176 -320.295524) (xy 112.267612 -320.296129) (xy 112.24684 -320.306298)
			(xy 112.239298 -320.315082) (xy 112.222545 -320.335865) (xy 112.184191 -320.372995) (xy 112.141037 -320.404417)
			(xy 112.093923 -320.429516) (xy 112.043771 -320.447802) (xy 111.99156 -320.458919) (xy 111.938308 -320.462649)
			(xy 111.885056 -320.458919) (xy 111.832845 -320.447802) (xy 111.782693 -320.429516) (xy 111.735579 -320.404417)
			(xy 111.692425 -320.372995) (xy 111.654071 -320.335865) (xy 111.637318 -320.315082) (xy 111.629747 -320.306329)
			(xy 111.608995 -320.296141) (xy 111.59744 -320.295524) (xy 111.517176 -320.295524) (xy 111.505612 -320.296129)
			(xy 111.48484 -320.306298) (xy 111.477298 -320.315082) (xy 111.460545 -320.335865) (xy 111.422191 -320.372995)
			(xy 111.379037 -320.404417) (xy 111.331923 -320.429516) (xy 111.281771 -320.447802) (xy 111.22956 -320.458919)
			(xy 111.176308 -320.462649) (xy 111.123056 -320.458919) (xy 111.070845 -320.447802) (xy 111.020693 -320.429516)
			(xy 110.973579 -320.404417) (xy 110.930425 -320.372995) (xy 110.892071 -320.335865) (xy 110.875318 -320.315082)
			(xy 110.867747 -320.306329) (xy 110.846995 -320.296141) (xy 110.83544 -320.295524) (xy 110.755176 -320.295524)
			(xy 110.743612 -320.296129) (xy 110.72284 -320.306298) (xy 110.715298 -320.315082) (xy 110.698545 -320.335865)
			(xy 110.660191 -320.372995) (xy 110.617037 -320.404417) (xy 110.569923 -320.429516) (xy 110.519771 -320.447802)
			(xy 110.46756 -320.458919) (xy 110.414308 -320.462649) (xy 110.361056 -320.458919) (xy 110.308845 -320.447802)
			(xy 110.258693 -320.429516) (xy 110.211579 -320.404417) (xy 110.168425 -320.372995) (xy 110.130071 -320.335865)
			(xy 110.113318 -320.315082) (xy 110.105747 -320.306329) (xy 110.084995 -320.296141) (xy 110.07344 -320.295524)
			(xy 109.993176 -320.295524) (xy 109.981612 -320.296129) (xy 109.96084 -320.306298) (xy 109.953298 -320.315082)
			(xy 109.936545 -320.335865) (xy 109.898191 -320.372995) (xy 109.855037 -320.404417) (xy 109.807923 -320.429516)
			(xy 109.757771 -320.447802) (xy 109.70556 -320.458919) (xy 109.652308 -320.462649) (xy 109.599056 -320.458919)
			(xy 109.546845 -320.447802) (xy 109.496693 -320.429516) (xy 109.449579 -320.404417) (xy 109.406425 -320.372995)
			(xy 109.368071 -320.335865) (xy 109.351318 -320.315082) (xy 109.343747 -320.306329) (xy 109.322995 -320.296141)
			(xy 109.31144 -320.295524) (xy 109.231176 -320.295524) (xy 109.219612 -320.296129) (xy 109.19884 -320.306298)
			(xy 109.191298 -320.315082) (xy 109.174545 -320.335865) (xy 109.136191 -320.372995) (xy 109.093037 -320.404417)
			(xy 109.045923 -320.429516) (xy 108.995771 -320.447802) (xy 108.94356 -320.458919) (xy 108.890308 -320.462649)
			(xy 108.837056 -320.458919) (xy 108.784845 -320.447802) (xy 108.734693 -320.429516) (xy 108.687579 -320.404417)
			(xy 108.644425 -320.372995) (xy 108.606071 -320.335865) (xy 108.589318 -320.315082) (xy 108.581747 -320.306329)
			(xy 108.560995 -320.296141) (xy 108.54944 -320.295524) (xy 108.469176 -320.295524) (xy 108.457612 -320.296129)
			(xy 108.43684 -320.306298) (xy 108.429298 -320.315082) (xy 108.412545 -320.335865) (xy 108.374191 -320.372995)
			(xy 108.331037 -320.404417) (xy 108.283923 -320.429516) (xy 108.233771 -320.447802) (xy 108.18156 -320.458919)
			(xy 108.128308 -320.462649) (xy 108.075056 -320.458919) (xy 108.022845 -320.447802) (xy 107.972693 -320.429516)
			(xy 107.925579 -320.404417) (xy 107.882425 -320.372995) (xy 107.844071 -320.335865) (xy 107.827318 -320.315082)
			(xy 107.819747 -320.306329) (xy 107.798995 -320.296141) (xy 107.78744 -320.295524) (xy 107.707176 -320.295524)
			(xy 107.695612 -320.296129) (xy 107.67484 -320.306298) (xy 107.667298 -320.315082) (xy 107.650545 -320.335865)
			(xy 107.612191 -320.372995) (xy 107.569037 -320.404417) (xy 107.521923 -320.429516) (xy 107.471771 -320.447802)
			(xy 107.41956 -320.458919) (xy 107.366308 -320.462649) (xy 107.313056 -320.458919) (xy 107.260845 -320.447802)
			(xy 107.210693 -320.429516) (xy 107.163579 -320.404417) (xy 107.120425 -320.372995) (xy 107.082071 -320.335865)
			(xy 107.065318 -320.315082) (xy 107.057747 -320.306329) (xy 107.036995 -320.296141) (xy 107.02544 -320.295524)
			(xy 106.945176 -320.295524) (xy 106.933612 -320.296129) (xy 106.91284 -320.306298) (xy 106.905298 -320.315082)
			(xy 106.887104 -320.337563) (xy 106.845085 -320.377299) (xy 106.797551 -320.410239) (xy 106.74559 -320.435628)
			(xy 106.690393 -320.452884) (xy 106.633224 -320.461613) (xy 106.604308 -320.462148) (xy 106.577059 -320.461615)
			(xy 106.523115 -320.453861) (xy 106.470823 -320.438508) (xy 106.421249 -320.415871) (xy 106.3754 -320.386409)
			(xy 106.334211 -320.350723) (xy 106.298519 -320.309538) (xy 106.269052 -320.263693) (xy 106.246408 -320.214122)
			(xy 106.23105 -320.161832) (xy 106.223289 -320.107889) (xy 106.2228 -320.08064) (xy 94.32886 -320.08064)
			(xy 94.351879 -320.219508) (xy 94.375854 -320.413126) (xy 94.39186 -320.607564) (xy 94.399869 -320.802496)
			(xy 94.40037 -320.900044) (xy 94.399869 -320.997592) (xy 94.39186 -321.192524) (xy 94.375854 -321.386962)
			(xy 94.351879 -321.58058) (xy 94.319975 -321.77305) (xy 94.280196 -321.964047) (xy 94.23261 -322.153251)
			(xy 94.177295 -322.340341) (xy 94.139065 -322.452492) (xy 114.964462 -322.452492) (xy 114.968533 -322.39687)
			(xy 114.980659 -322.342433) (xy 115.000582 -322.290342) (xy 115.027878 -322.241707) (xy 115.061964 -322.197564)
			(xy 115.102113 -322.158855) (xy 115.147471 -322.126404) (xy 115.197071 -322.100903) (xy 115.249855 -322.082896)
			(xy 115.304698 -322.072766) (xy 115.360432 -322.070729) (xy 115.415869 -322.076829) (xy 115.469826 -322.090935)
			(xy 115.521155 -322.112747) (xy 115.568761 -322.141801) (xy 115.611629 -322.177476) (xy 115.648846 -322.219013)
			(xy 115.679619 -322.265526) (xy 115.703291 -322.316023) (xy 115.719359 -322.36943) (xy 115.727479 -322.424606)
			(xy 115.727988 -322.452492) (xy 115.727479 -322.480378) (xy 115.719359 -322.535554) (xy 115.703291 -322.588961)
			(xy 115.679619 -322.639458) (xy 115.648846 -322.685971) (xy 115.611629 -322.727508) (xy 115.568761 -322.763183)
			(xy 115.521155 -322.792237) (xy 115.469826 -322.814049) (xy 115.415869 -322.828155) (xy 115.360432 -322.834255)
			(xy 115.304698 -322.832218) (xy 115.249855 -322.822088) (xy 115.197071 -322.804081) (xy 115.147471 -322.77858)
			(xy 115.102113 -322.746129) (xy 115.061964 -322.70742) (xy 115.027878 -322.663277) (xy 115.000582 -322.614642)
			(xy 114.980659 -322.562551) (xy 114.968533 -322.508114) (xy 114.964462 -322.452492) (xy 94.139065 -322.452492)
			(xy 94.114347 -322.525003) (xy 94.04387 -322.706925) (xy 93.965984 -322.8858) (xy 93.881557 -323.059806)
			(xy 102.316278 -323.059806) (xy 102.320349 -323.004184) (xy 102.332475 -322.949747) (xy 102.352398 -322.897656)
			(xy 102.379694 -322.849021) (xy 102.41378 -322.804878) (xy 102.453929 -322.766169) (xy 102.499287 -322.733718)
			(xy 102.548887 -322.708217) (xy 102.601671 -322.69021) (xy 102.656514 -322.68008) (xy 102.712248 -322.678043)
			(xy 102.767685 -322.684143) (xy 102.821642 -322.698249) (xy 102.872971 -322.720061) (xy 102.920577 -322.749115)
			(xy 102.963445 -322.78479) (xy 103.000662 -322.826327) (xy 103.031435 -322.87284) (xy 103.055107 -322.923337)
			(xy 103.071175 -322.976744) (xy 103.079295 -323.03192) (xy 103.079804 -323.059806) (xy 103.079295 -323.087692)
			(xy 103.071175 -323.142868) (xy 103.055107 -323.196275) (xy 103.031435 -323.246772) (xy 103.000662 -323.293285)
			(xy 102.963445 -323.334822) (xy 102.920577 -323.370497) (xy 102.872971 -323.399551) (xy 102.821642 -323.421363)
			(xy 102.767685 -323.435469) (xy 102.712248 -323.441569) (xy 102.656514 -323.439532) (xy 102.601671 -323.429402)
			(xy 102.548887 -323.411395) (xy 102.499287 -323.385894) (xy 102.453929 -323.353443) (xy 102.41378 -323.314734)
			(xy 102.379694 -323.270591) (xy 102.352398 -323.221956) (xy 102.332475 -323.169865) (xy 102.320349 -323.115428)
			(xy 102.316278 -323.059806) (xy 93.881557 -323.059806) (xy 93.880819 -323.061326) (xy 93.788521 -323.233209)
			(xy 93.689243 -323.401156) (xy 93.583154 -323.564887) (xy 93.470433 -323.724124) (xy 93.351269 -323.878598)
			(xy 93.225864 -324.028051) (xy 93.182329 -324.075806) (xy 102.316278 -324.075806) (xy 102.320349 -324.020184)
			(xy 102.332475 -323.965747) (xy 102.352398 -323.913656) (xy 102.379694 -323.865021) (xy 102.41378 -323.820878)
			(xy 102.453929 -323.782169) (xy 102.499287 -323.749718) (xy 102.548887 -323.724217) (xy 102.601671 -323.70621)
			(xy 102.656514 -323.69608) (xy 102.712248 -323.694043) (xy 102.767685 -323.700143) (xy 102.821642 -323.714249)
			(xy 102.872971 -323.736061) (xy 102.920577 -323.765115) (xy 102.963445 -323.80079) (xy 103.000662 -323.842327)
			(xy 103.031435 -323.88884) (xy 103.055107 -323.939337) (xy 103.071175 -323.992744) (xy 103.079295 -324.04792)
			(xy 103.079804 -324.075806) (xy 103.079295 -324.103692) (xy 103.071175 -324.158868) (xy 103.055107 -324.212275)
			(xy 103.031435 -324.262772) (xy 103.000662 -324.309285) (xy 102.963445 -324.350822) (xy 102.920577 -324.386497)
			(xy 102.872971 -324.415551) (xy 102.821642 -324.437363) (xy 102.767685 -324.451469) (xy 102.712248 -324.457569)
			(xy 102.656514 -324.455532) (xy 102.601671 -324.445402) (xy 102.548887 -324.427395) (xy 102.499287 -324.401894)
			(xy 102.453929 -324.369443) (xy 102.41378 -324.330734) (xy 102.379694 -324.286591) (xy 102.352398 -324.237956)
			(xy 102.332475 -324.185865) (xy 102.320349 -324.131428) (xy 102.316278 -324.075806) (xy 93.182329 -324.075806)
			(xy 93.094428 -324.172229) (xy 92.957184 -324.310889) (xy 92.814363 -324.443797) (xy 92.666206 -324.570731)
			(xy 92.512963 -324.691474) (xy 92.354892 -324.805824) (xy 92.192259 -324.913589) (xy 92.02534 -325.014585)
			(xy 91.854414 -325.108644) (xy 91.679771 -325.195606) (xy 91.501705 -325.275324) (xy 91.320517 -325.347665)
			(xy 91.136511 -325.412506) (xy 90.949998 -325.469738) (xy 90.761293 -325.519265) (xy 90.570714 -325.561002)
			(xy 90.378581 -325.59488) (xy 90.18522 -325.620842) (xy 89.990956 -325.638843) (xy 89.796117 -325.648854)
			(xy 89.601031 -325.650857) (xy 89.406028 -325.644849) (xy 89.211435 -325.63084) (xy 89.017582 -325.608854)
			(xy 88.824795 -325.578928) (xy 88.633398 -325.541112) (xy 88.443716 -325.49547) (xy 88.256068 -325.44208)
			(xy 88.070769 -325.38103) (xy 87.888134 -325.312425) (xy 87.708469 -325.236379) (xy 87.532077 -325.153021)
			(xy 87.359256 -325.062492) (xy 87.190298 -324.964944) (xy 87.025487 -324.860541) (xy 86.865101 -324.749461)
			(xy 86.709411 -324.631889) (xy 86.558679 -324.508025) (xy 86.41316 -324.378076) (xy 86.273098 -324.242263)
			(xy 86.13873 -324.100814) (xy 86.010283 -323.953968) (xy 85.887972 -323.801973) (xy 85.772005 -323.645084)
			(xy 85.662577 -323.483566) (xy 85.559872 -323.317692) (xy 85.464064 -323.147741) (xy 85.375313 -322.974)
			(xy 85.293771 -322.796762) (xy 85.219574 -322.616326) (xy 85.152847 -322.432995) (xy 85.093703 -322.24708)
			(xy 85.042242 -322.058893) (xy 84.99855 -321.868753) (xy 84.962701 -321.676978) (xy 84.934756 -321.483894)
			(xy 84.914761 -321.289825) (xy 84.902751 -321.095099) (xy 84.898745 -320.900044) (xy 60.200913 -320.900044)
			(xy 60.20308 -320.90106) (xy 60.24439 -320.905859) (xy 60.326075 -320.921517) (xy 60.406158 -320.943977)
			(xy 60.484072 -320.973078) (xy 60.52185 -320.990468) (xy 60.921646 -321.179444) (xy 60.963783 -321.199941)
			(xy 61.04436 -321.247781) (xy 61.120046 -321.303033) (xy 61.190163 -321.365202) (xy 61.25408 -321.433729)
			(xy 61.283088 -321.470528) (xy 61.286644 -321.475354) (xy 61.296042 -321.48272) (xy 66.012568 -323.713602)
			(xy 66.014854 -323.714618) (xy 69.408548 -325.120254) (xy 69.431087 -325.129775) (xy 69.475302 -325.150741)
			(xy 69.49694 -325.162164) (xy 70.737329 -325.825104) (xy 104.056178 -325.825104) (xy 104.060249 -325.769482)
			(xy 104.072375 -325.715045) (xy 104.092298 -325.662954) (xy 104.119594 -325.614319) (xy 104.15368 -325.570176)
			(xy 104.193829 -325.531467) (xy 104.239187 -325.499016) (xy 104.288787 -325.473515) (xy 104.341571 -325.455508)
			(xy 104.396414 -325.445378) (xy 104.452148 -325.443341) (xy 104.507585 -325.449441) (xy 104.561542 -325.463547)
			(xy 104.612871 -325.485359) (xy 104.660477 -325.514413) (xy 104.703345 -325.550088) (xy 104.740562 -325.591625)
			(xy 104.771335 -325.638138) (xy 104.795007 -325.688635) (xy 104.811075 -325.742042) (xy 104.819195 -325.797218)
			(xy 104.819704 -325.825104) (xy 104.819195 -325.85299) (xy 104.811075 -325.908166) (xy 104.795007 -325.961573)
			(xy 104.771335 -326.01207) (xy 104.740562 -326.058583) (xy 104.703345 -326.10012) (xy 104.660477 -326.135795)
			(xy 104.612871 -326.164849) (xy 104.561542 -326.186661) (xy 104.507585 -326.200767) (xy 104.452148 -326.206867)
			(xy 104.396414 -326.20483) (xy 104.341571 -326.1947) (xy 104.288787 -326.176693) (xy 104.239187 -326.151192)
			(xy 104.193829 -326.118741) (xy 104.15368 -326.080032) (xy 104.119594 -326.035889) (xy 104.092298 -325.987254)
			(xy 104.072375 -325.935163) (xy 104.060249 -325.880726) (xy 104.056178 -325.825104) (xy 70.737329 -325.825104)
			(xy 72.740012 -326.89546) (xy 72.742298 -326.89673) (xy 72.783112 -326.916034) (xy 100.632512 -326.916034)
			(xy 100.636583 -326.860412) (xy 100.648709 -326.805975) (xy 100.668632 -326.753884) (xy 100.695928 -326.705249)
			(xy 100.730014 -326.661106) (xy 100.770163 -326.622397) (xy 100.815521 -326.589946) (xy 100.865121 -326.564445)
			(xy 100.917905 -326.546438) (xy 100.972748 -326.536308) (xy 101.028482 -326.534271) (xy 101.083919 -326.540371)
			(xy 101.137876 -326.554477) (xy 101.189205 -326.576289) (xy 101.236811 -326.605343) (xy 101.279679 -326.641018)
			(xy 101.316896 -326.682555) (xy 101.337433 -326.713596) (xy 109.961678 -326.713596) (xy 109.965749 -326.657974)
			(xy 109.977875 -326.603537) (xy 109.997798 -326.551446) (xy 110.025094 -326.502811) (xy 110.05918 -326.458668)
			(xy 110.099329 -326.419959) (xy 110.144687 -326.387508) (xy 110.194287 -326.362007) (xy 110.247071 -326.344)
			(xy 110.301914 -326.33387) (xy 110.357648 -326.331833) (xy 110.413085 -326.337933) (xy 110.467042 -326.352039)
			(xy 110.518371 -326.373851) (xy 110.565977 -326.402905) (xy 110.608845 -326.43858) (xy 110.646062 -326.480117)
			(xy 110.676835 -326.52663) (xy 110.700507 -326.577127) (xy 110.716575 -326.630534) (xy 110.724695 -326.68571)
			(xy 110.725204 -326.713596) (xy 110.724695 -326.741482) (xy 110.718706 -326.782176) (xy 110.867696 -326.782176)
			(xy 110.871767 -326.726554) (xy 110.883893 -326.672117) (xy 110.903816 -326.620026) (xy 110.931112 -326.571391)
			(xy 110.965198 -326.527248) (xy 111.005347 -326.488539) (xy 111.050705 -326.456088) (xy 111.100305 -326.430587)
			(xy 111.153089 -326.41258) (xy 111.207932 -326.40245) (xy 111.263666 -326.400413) (xy 111.319103 -326.406513)
			(xy 111.37306 -326.420619) (xy 111.424389 -326.442431) (xy 111.471995 -326.471485) (xy 111.514863 -326.50716)
			(xy 111.55208 -326.548697) (xy 111.582853 -326.59521) (xy 111.606525 -326.645707) (xy 111.622593 -326.699114)
			(xy 111.630713 -326.75429) (xy 111.631222 -326.782176) (xy 111.630713 -326.810062) (xy 111.626145 -326.841104)
			(xy 115.496084 -326.841104) (xy 115.500155 -326.785482) (xy 115.512281 -326.731045) (xy 115.532204 -326.678954)
			(xy 115.5595 -326.630319) (xy 115.593586 -326.586176) (xy 115.633735 -326.547467) (xy 115.679093 -326.515016)
			(xy 115.728693 -326.489515) (xy 115.781477 -326.471508) (xy 115.83632 -326.461378) (xy 115.892054 -326.459341)
			(xy 115.947491 -326.465441) (xy 116.001448 -326.479547) (xy 116.052777 -326.501359) (xy 116.100383 -326.530413)
			(xy 116.143251 -326.566088) (xy 116.180468 -326.607625) (xy 116.211241 -326.654138) (xy 116.234913 -326.704635)
			(xy 116.250981 -326.758042) (xy 116.259101 -326.813218) (xy 116.25961 -326.841104) (xy 116.259101 -326.86899)
			(xy 116.250981 -326.924166) (xy 116.234913 -326.977573) (xy 116.211241 -327.02807) (xy 116.180468 -327.074583)
			(xy 116.143251 -327.11612) (xy 116.100383 -327.151795) (xy 116.052777 -327.180849) (xy 116.001448 -327.202661)
			(xy 115.947491 -327.216767) (xy 115.892054 -327.222867) (xy 115.83632 -327.22083) (xy 115.781477 -327.2107)
			(xy 115.728693 -327.192693) (xy 115.679093 -327.167192) (xy 115.633735 -327.134741) (xy 115.593586 -327.096032)
			(xy 115.5595 -327.051889) (xy 115.532204 -327.003254) (xy 115.512281 -326.951163) (xy 115.500155 -326.896726)
			(xy 115.496084 -326.841104) (xy 111.626145 -326.841104) (xy 111.622593 -326.865238) (xy 111.606525 -326.918645)
			(xy 111.582853 -326.969142) (xy 111.55208 -327.015655) (xy 111.514863 -327.057192) (xy 111.471995 -327.092867)
			(xy 111.424389 -327.121921) (xy 111.37306 -327.143733) (xy 111.319103 -327.157839) (xy 111.263666 -327.163939)
			(xy 111.207932 -327.161902) (xy 111.153089 -327.151772) (xy 111.100305 -327.133765) (xy 111.050705 -327.108264)
			(xy 111.005347 -327.075813) (xy 110.965198 -327.037104) (xy 110.931112 -326.992961) (xy 110.903816 -326.944326)
			(xy 110.883893 -326.892235) (xy 110.871767 -326.837798) (xy 110.867696 -326.782176) (xy 110.718706 -326.782176)
			(xy 110.716575 -326.796658) (xy 110.700507 -326.850065) (xy 110.676835 -326.900562) (xy 110.646062 -326.947075)
			(xy 110.608845 -326.988612) (xy 110.565977 -327.024287) (xy 110.518371 -327.053341) (xy 110.467042 -327.075153)
			(xy 110.413085 -327.089259) (xy 110.357648 -327.095359) (xy 110.301914 -327.093322) (xy 110.247071 -327.083192)
			(xy 110.194287 -327.065185) (xy 110.144687 -327.039684) (xy 110.099329 -327.007233) (xy 110.05918 -326.968524)
			(xy 110.025094 -326.924381) (xy 109.997798 -326.875746) (xy 109.977875 -326.823655) (xy 109.965749 -326.769218)
			(xy 109.961678 -326.713596) (xy 101.337433 -326.713596) (xy 101.347669 -326.729068) (xy 101.371341 -326.779565)
			(xy 101.387409 -326.832972) (xy 101.395529 -326.888148) (xy 101.396038 -326.916034) (xy 101.395529 -326.94392)
			(xy 101.387409 -326.999096) (xy 101.371341 -327.052503) (xy 101.347669 -327.103) (xy 101.316896 -327.149513)
			(xy 101.279679 -327.19105) (xy 101.236811 -327.226725) (xy 101.189205 -327.255779) (xy 101.137876 -327.277591)
			(xy 101.083919 -327.291697) (xy 101.028482 -327.297797) (xy 100.972748 -327.29576) (xy 100.917905 -327.28563)
			(xy 100.865121 -327.267623) (xy 100.815521 -327.242122) (xy 100.770163 -327.209671) (xy 100.730014 -327.170962)
			(xy 100.695928 -327.126819) (xy 100.668632 -327.078184) (xy 100.648709 -327.026093) (xy 100.636583 -326.971656)
			(xy 100.632512 -326.916034) (xy 72.783112 -326.916034) (xy 73.785743 -327.390252) (xy 104.653586 -327.390252)
			(xy 104.657657 -327.33463) (xy 104.669783 -327.280193) (xy 104.689706 -327.228102) (xy 104.717002 -327.179467)
			(xy 104.751088 -327.135324) (xy 104.791237 -327.096615) (xy 104.836595 -327.064164) (xy 104.886195 -327.038663)
			(xy 104.938979 -327.020656) (xy 104.993822 -327.010526) (xy 105.049556 -327.008489) (xy 105.104993 -327.014589)
			(xy 105.15895 -327.028695) (xy 105.210279 -327.050507) (xy 105.257885 -327.079561) (xy 105.300753 -327.115236)
			(xy 105.33797 -327.156773) (xy 105.368743 -327.203286) (xy 105.392415 -327.253783) (xy 105.408483 -327.30719)
			(xy 105.416603 -327.362366) (xy 105.416672 -327.366122) (xy 106.29214 -327.366122) (xy 106.296211 -327.3105)
			(xy 106.308337 -327.256063) (xy 106.32826 -327.203972) (xy 106.355556 -327.155337) (xy 106.389642 -327.111194)
			(xy 106.429791 -327.072485) (xy 106.475149 -327.040034) (xy 106.524749 -327.014533) (xy 106.577533 -326.996526)
			(xy 106.632376 -326.986396) (xy 106.68811 -326.984359) (xy 106.743547 -326.990459) (xy 106.797504 -327.004565)
			(xy 106.848833 -327.026377) (xy 106.896439 -327.055431) (xy 106.939307 -327.091106) (xy 106.976524 -327.132643)
			(xy 107.007297 -327.179156) (xy 107.030969 -327.229653) (xy 107.047037 -327.28306) (xy 107.055157 -327.338236)
			(xy 107.055666 -327.366122) (xy 107.055157 -327.394008) (xy 107.047037 -327.449184) (xy 107.044898 -327.456292)
			(xy 108.97184 -327.456292) (xy 108.975911 -327.40067) (xy 108.988037 -327.346233) (xy 109.00796 -327.294142)
			(xy 109.035256 -327.245507) (xy 109.069342 -327.201364) (xy 109.109491 -327.162655) (xy 109.154849 -327.130204)
			(xy 109.204449 -327.104703) (xy 109.257233 -327.086696) (xy 109.312076 -327.076566) (xy 109.36781 -327.074529)
			(xy 109.423247 -327.080629) (xy 109.477204 -327.094735) (xy 109.528533 -327.116547) (xy 109.576139 -327.145601)
			(xy 109.619007 -327.181276) (xy 109.656224 -327.222813) (xy 109.686997 -327.269326) (xy 109.710669 -327.319823)
			(xy 109.726737 -327.37323) (xy 109.734857 -327.428406) (xy 109.735366 -327.456292) (xy 111.608106 -327.456292)
			(xy 111.612177 -327.40067) (xy 111.624303 -327.346233) (xy 111.644226 -327.294142) (xy 111.671522 -327.245507)
			(xy 111.705608 -327.201364) (xy 111.745757 -327.162655) (xy 111.791115 -327.130204) (xy 111.840715 -327.104703)
			(xy 111.893499 -327.086696) (xy 111.948342 -327.076566) (xy 112.004076 -327.074529) (xy 112.059513 -327.080629)
			(xy 112.11347 -327.094735) (xy 112.164799 -327.116547) (xy 112.212405 -327.145601) (xy 112.255273 -327.181276)
			(xy 112.29249 -327.222813) (xy 112.323263 -327.269326) (xy 112.346935 -327.319823) (xy 112.363003 -327.37323)
			(xy 112.371123 -327.428406) (xy 112.371632 -327.456292) (xy 112.371123 -327.484178) (xy 112.363003 -327.539354)
			(xy 112.346935 -327.592761) (xy 112.323263 -327.643258) (xy 112.29249 -327.689771) (xy 112.255273 -327.731308)
			(xy 112.212405 -327.766983) (xy 112.164799 -327.796037) (xy 112.11347 -327.817849) (xy 112.059513 -327.831955)
			(xy 112.004076 -327.838055) (xy 111.948342 -327.836018) (xy 111.893499 -327.825888) (xy 111.840715 -327.807881)
			(xy 111.791115 -327.78238) (xy 111.745757 -327.749929) (xy 111.705608 -327.71122) (xy 111.671522 -327.667077)
			(xy 111.644226 -327.618442) (xy 111.624303 -327.566351) (xy 111.612177 -327.511914) (xy 111.608106 -327.456292)
			(xy 109.735366 -327.456292) (xy 109.734857 -327.484178) (xy 109.726737 -327.539354) (xy 109.710669 -327.592761)
			(xy 109.686997 -327.643258) (xy 109.656224 -327.689771) (xy 109.619007 -327.731308) (xy 109.576139 -327.766983)
			(xy 109.528533 -327.796037) (xy 109.477204 -327.817849) (xy 109.423247 -327.831955) (xy 109.36781 -327.838055)
			(xy 109.312076 -327.836018) (xy 109.257233 -327.825888) (xy 109.204449 -327.807881) (xy 109.154849 -327.78238)
			(xy 109.109491 -327.749929) (xy 109.069342 -327.71122) (xy 109.035256 -327.667077) (xy 109.00796 -327.618442)
			(xy 108.988037 -327.566351) (xy 108.975911 -327.511914) (xy 108.97184 -327.456292) (xy 107.044898 -327.456292)
			(xy 107.030969 -327.502591) (xy 107.007297 -327.553088) (xy 106.976524 -327.599601) (xy 106.939307 -327.641138)
			(xy 106.896439 -327.676813) (xy 106.848833 -327.705867) (xy 106.797504 -327.727679) (xy 106.743547 -327.741785)
			(xy 106.68811 -327.747885) (xy 106.632376 -327.745848) (xy 106.577533 -327.735718) (xy 106.524749 -327.717711)
			(xy 106.475149 -327.69221) (xy 106.429791 -327.659759) (xy 106.389642 -327.62105) (xy 106.355556 -327.576907)
			(xy 106.32826 -327.528272) (xy 106.308337 -327.476181) (xy 106.296211 -327.421744) (xy 106.29214 -327.366122)
			(xy 105.416672 -327.366122) (xy 105.417112 -327.390252) (xy 105.416603 -327.418138) (xy 105.408483 -327.473314)
			(xy 105.392415 -327.526721) (xy 105.368743 -327.577218) (xy 105.33797 -327.623731) (xy 105.300753 -327.665268)
			(xy 105.257885 -327.700943) (xy 105.210279 -327.729997) (xy 105.15895 -327.751809) (xy 105.104993 -327.765915)
			(xy 105.049556 -327.772015) (xy 104.993822 -327.769978) (xy 104.938979 -327.759848) (xy 104.886195 -327.741841)
			(xy 104.836595 -327.71634) (xy 104.791237 -327.683889) (xy 104.751088 -327.64518) (xy 104.717002 -327.601037)
			(xy 104.689706 -327.552402) (xy 104.669783 -327.500311) (xy 104.657657 -327.445874) (xy 104.653586 -327.390252)
			(xy 73.785743 -327.390252) (xy 75.536455 -328.218292) (xy 103.1908 -328.218292) (xy 103.194871 -328.16267)
			(xy 103.206997 -328.108233) (xy 103.22692 -328.056142) (xy 103.254216 -328.007507) (xy 103.288302 -327.963364)
			(xy 103.328451 -327.924655) (xy 103.373809 -327.892204) (xy 103.423409 -327.866703) (xy 103.476193 -327.848696)
			(xy 103.531036 -327.838566) (xy 103.58677 -327.836529) (xy 103.642207 -327.842629) (xy 103.696164 -327.856735)
			(xy 103.747493 -327.878547) (xy 103.795099 -327.907601) (xy 103.837967 -327.943276) (xy 103.875184 -327.984813)
			(xy 103.905957 -328.031326) (xy 103.929629 -328.081823) (xy 103.945697 -328.13523) (xy 103.953817 -328.190406)
			(xy 103.954326 -328.218292) (xy 103.953817 -328.246178) (xy 103.945697 -328.301354) (xy 103.929629 -328.354761)
			(xy 103.915255 -328.385424) (xy 104.682542 -328.385424) (xy 104.686613 -328.329802) (xy 104.698739 -328.275365)
			(xy 104.718662 -328.223274) (xy 104.745958 -328.174639) (xy 104.780044 -328.130496) (xy 104.820193 -328.091787)
			(xy 104.865551 -328.059336) (xy 104.915151 -328.033835) (xy 104.967935 -328.015828) (xy 105.022778 -328.005698)
			(xy 105.078512 -328.003661) (xy 105.133949 -328.009761) (xy 105.187906 -328.023867) (xy 105.239235 -328.045679)
			(xy 105.286841 -328.074733) (xy 105.320473 -328.102722) (xy 107.71581 -328.102722) (xy 107.719881 -328.0471)
			(xy 107.732007 -327.992663) (xy 107.75193 -327.940572) (xy 107.779226 -327.891937) (xy 107.813312 -327.847794)
			(xy 107.853461 -327.809085) (xy 107.898819 -327.776634) (xy 107.948419 -327.751133) (xy 108.001203 -327.733126)
			(xy 108.056046 -327.722996) (xy 108.11178 -327.720959) (xy 108.167217 -327.727059) (xy 108.221174 -327.741165)
			(xy 108.272503 -327.762977) (xy 108.320109 -327.792031) (xy 108.362977 -327.827706) (xy 108.400194 -327.869243)
			(xy 108.430967 -327.915756) (xy 108.454639 -327.966253) (xy 108.470707 -328.01966) (xy 108.478827 -328.074836)
			(xy 108.479336 -328.102722) (xy 108.478827 -328.130608) (xy 108.470707 -328.185784) (xy 108.454639 -328.239191)
			(xy 108.430967 -328.289688) (xy 108.400194 -328.336201) (xy 108.362977 -328.377738) (xy 108.320109 -328.413413)
			(xy 108.28731 -328.43343) (xy 114.249198 -328.43343) (xy 114.253269 -328.377808) (xy 114.265395 -328.323371)
			(xy 114.285318 -328.27128) (xy 114.312614 -328.222645) (xy 114.3467 -328.178502) (xy 114.386849 -328.139793)
			(xy 114.432207 -328.107342) (xy 114.481807 -328.081841) (xy 114.534591 -328.063834) (xy 114.589434 -328.053704)
			(xy 114.645168 -328.051667) (xy 114.700605 -328.057767) (xy 114.754562 -328.071873) (xy 114.805891 -328.093685)
			(xy 114.853497 -328.122739) (xy 114.896365 -328.158414) (xy 114.933582 -328.199951) (xy 114.964355 -328.246464)
			(xy 114.988027 -328.296961) (xy 115.004095 -328.350368) (xy 115.012215 -328.405544) (xy 115.012724 -328.43343)
			(xy 115.012215 -328.461316) (xy 115.004095 -328.516492) (xy 114.988027 -328.569899) (xy 114.964355 -328.620396)
			(xy 114.933582 -328.666909) (xy 114.896365 -328.708446) (xy 114.853497 -328.744121) (xy 114.805891 -328.773175)
			(xy 114.754562 -328.794987) (xy 114.700605 -328.809093) (xy 114.645168 -328.815193) (xy 114.589434 -328.813156)
			(xy 114.534591 -328.803026) (xy 114.481807 -328.785019) (xy 114.432207 -328.759518) (xy 114.386849 -328.727067)
			(xy 114.3467 -328.688358) (xy 114.312614 -328.644215) (xy 114.285318 -328.59558) (xy 114.265395 -328.543489)
			(xy 114.253269 -328.489052) (xy 114.249198 -328.43343) (xy 108.28731 -328.43343) (xy 108.272503 -328.442467)
			(xy 108.221174 -328.464279) (xy 108.167217 -328.478385) (xy 108.11178 -328.484485) (xy 108.056046 -328.482448)
			(xy 108.001203 -328.472318) (xy 107.948419 -328.454311) (xy 107.898819 -328.42881) (xy 107.853461 -328.396359)
			(xy 107.813312 -328.35765) (xy 107.779226 -328.313507) (xy 107.75193 -328.264872) (xy 107.732007 -328.212781)
			(xy 107.719881 -328.158344) (xy 107.71581 -328.102722) (xy 105.320473 -328.102722) (xy 105.329709 -328.110408)
			(xy 105.366926 -328.151945) (xy 105.397699 -328.198458) (xy 105.421371 -328.248955) (xy 105.437439 -328.302362)
			(xy 105.445559 -328.357538) (xy 105.446068 -328.385424) (xy 105.445559 -328.41331) (xy 105.437439 -328.468486)
			(xy 105.421371 -328.521893) (xy 105.397699 -328.57239) (xy 105.366926 -328.618903) (xy 105.329709 -328.66044)
			(xy 105.286841 -328.696115) (xy 105.239235 -328.725169) (xy 105.187906 -328.746981) (xy 105.133949 -328.761087)
			(xy 105.078512 -328.767187) (xy 105.022778 -328.76515) (xy 104.967935 -328.75502) (xy 104.915151 -328.737013)
			(xy 104.865551 -328.711512) (xy 104.820193 -328.679061) (xy 104.780044 -328.640352) (xy 104.745958 -328.596209)
			(xy 104.718662 -328.547574) (xy 104.698739 -328.495483) (xy 104.686613 -328.441046) (xy 104.682542 -328.385424)
			(xy 103.915255 -328.385424) (xy 103.905957 -328.405258) (xy 103.875184 -328.451771) (xy 103.837967 -328.493308)
			(xy 103.795099 -328.528983) (xy 103.747493 -328.558037) (xy 103.696164 -328.579849) (xy 103.642207 -328.593955)
			(xy 103.58677 -328.600055) (xy 103.531036 -328.598018) (xy 103.476193 -328.587888) (xy 103.423409 -328.569881)
			(xy 103.373809 -328.54438) (xy 103.328451 -328.511929) (xy 103.288302 -328.47322) (xy 103.254216 -328.429077)
			(xy 103.22692 -328.380442) (xy 103.206997 -328.328351) (xy 103.194871 -328.273914) (xy 103.1908 -328.218292)
			(xy 75.536455 -328.218292) (xy 79.588868 -330.134976) (xy 97.304352 -330.134976) (xy 97.314378 -330.134564)
			(xy 97.332907 -330.126902) (xy 97.347088 -330.112727) (xy 97.354759 -330.094202) (xy 97.355152 -330.084176)
			(xy 97.355152 -329.553062) (xy 97.355641 -329.523133) (xy 97.363445 -329.463784) (xy 97.378915 -329.405959)
			(xy 97.401788 -329.350642) (xy 97.431673 -329.298777) (xy 97.468061 -329.251248) (xy 97.510331 -329.208865)
			(xy 97.557764 -329.172351) (xy 97.609549 -329.142328) (xy 97.664805 -329.119308) (xy 97.722589 -329.103684)
			(xy 97.781916 -329.095722) (xy 97.811844 -329.0951) (xy 97.820734 -329.095354) (xy 97.857128 -329.096627)
			(xy 97.928841 -329.109268) (xy 97.963482 -329.1205) (xy 97.982024 -329.127104) (xy 97.986596 -329.128882)
			(xy 98.005138 -329.137518) (xy 98.039428 -329.155044) (xy 98.04781 -329.15987) (xy 98.057462 -329.16114)
			(xy 98.06215 -329.161793) (xy 98.07161 -329.161531) (xy 98.076258 -329.160632) (xy 98.097086 -329.155806)
			(xy 98.106484 -329.153774) (xy 98.136456 -329.133708) (xy 98.14179 -329.126596) (xy 98.159941 -329.103327)
			(xy 98.202203 -329.062139) (xy 98.250295 -329.027941) (xy 98.303075 -329.001545) (xy 98.359287 -328.98358)
			(xy 98.417592 -328.974474) (xy 98.447098 -328.973942) (xy 98.462592 -328.973942) (xy 98.476308 -328.974958)
			(xy 98.504708 -328.977664) (xy 98.516144 -328.980292) (xy 101.145846 -328.980292) (xy 101.149917 -328.92467)
			(xy 101.162043 -328.870233) (xy 101.181966 -328.818142) (xy 101.209262 -328.769507) (xy 101.243348 -328.725364)
			(xy 101.283497 -328.686655) (xy 101.328855 -328.654204) (xy 101.378455 -328.628703) (xy 101.431239 -328.610696)
			(xy 101.486082 -328.600566) (xy 101.541816 -328.598529) (xy 101.597253 -328.604629) (xy 101.65121 -328.618735)
			(xy 101.702539 -328.640547) (xy 101.750145 -328.669601) (xy 101.793013 -328.705276) (xy 101.83023 -328.746813)
			(xy 101.861003 -328.793326) (xy 101.884675 -328.843823) (xy 101.900743 -328.89723) (xy 101.908863 -328.952406)
			(xy 101.909372 -328.980292) (xy 101.908863 -329.008178) (xy 101.904444 -329.038204) (xy 102.152194 -329.038204)
			(xy 102.156265 -328.982582) (xy 102.168391 -328.928145) (xy 102.188314 -328.876054) (xy 102.21561 -328.827419)
			(xy 102.249696 -328.783276) (xy 102.289845 -328.744567) (xy 102.335203 -328.712116) (xy 102.384803 -328.686615)
			(xy 102.437587 -328.668608) (xy 102.49243 -328.658478) (xy 102.548164 -328.656441) (xy 102.603601 -328.662541)
			(xy 102.657558 -328.676647) (xy 102.708887 -328.698459) (xy 102.756493 -328.727513) (xy 102.799361 -328.763188)
			(xy 102.836578 -328.804725) (xy 102.867351 -328.851238) (xy 102.891023 -328.901735) (xy 102.907091 -328.955142)
			(xy 102.915211 -329.010318) (xy 102.91572 -329.038204) (xy 102.915211 -329.06609) (xy 102.907091 -329.121266)
			(xy 102.891023 -329.174673) (xy 102.867351 -329.22517) (xy 102.836578 -329.271683) (xy 102.799361 -329.31322)
			(xy 102.756493 -329.348895) (xy 102.708887 -329.377949) (xy 102.657558 -329.399761) (xy 102.603601 -329.413867)
			(xy 102.548164 -329.419967) (xy 102.49243 -329.41793) (xy 102.437587 -329.4078) (xy 102.384803 -329.389793)
			(xy 102.335203 -329.364292) (xy 102.289845 -329.331841) (xy 102.249696 -329.293132) (xy 102.21561 -329.248989)
			(xy 102.188314 -329.200354) (xy 102.168391 -329.148263) (xy 102.156265 -329.093826) (xy 102.152194 -329.038204)
			(xy 101.904444 -329.038204) (xy 101.900743 -329.063354) (xy 101.884675 -329.116761) (xy 101.861003 -329.167258)
			(xy 101.83023 -329.213771) (xy 101.793013 -329.255308) (xy 101.750145 -329.290983) (xy 101.702539 -329.320037)
			(xy 101.65121 -329.341849) (xy 101.597253 -329.355955) (xy 101.541816 -329.362055) (xy 101.486082 -329.360018)
			(xy 101.431239 -329.349888) (xy 101.378455 -329.331881) (xy 101.328855 -329.30638) (xy 101.283497 -329.273929)
			(xy 101.243348 -329.23522) (xy 101.209262 -329.191077) (xy 101.181966 -329.142442) (xy 101.162043 -329.090351)
			(xy 101.149917 -329.035914) (xy 101.145846 -328.980292) (xy 98.516144 -328.980292) (xy 98.560306 -328.99044)
			(xy 98.613381 -329.011353) (xy 98.66275 -329.039937) (xy 98.707312 -329.075554) (xy 98.746072 -329.117411)
			(xy 98.778167 -329.164573) (xy 98.80288 -329.215989) (xy 98.81966 -329.270512) (xy 98.828134 -329.326926)
			(xy 98.828606 -329.35545) (xy 98.828146 -329.382705) (xy 98.820395 -329.436661) (xy 98.805043 -329.488965)
			(xy 98.782403 -329.538551) (xy 98.752937 -329.584411) (xy 98.717243 -329.625609) (xy 98.676049 -329.661308)
			(xy 98.630194 -329.69078) (xy 98.58061 -329.713426) (xy 98.528308 -329.728785) (xy 98.474353 -329.736543)
			(xy 98.447098 -329.736958) (xy 98.432305 -329.736816) (xy 98.402808 -329.73453) (xy 98.38817 -329.732386)
			(xy 98.377248 -329.730608) (xy 98.355912 -329.736704) (xy 98.288856 -329.793854) (xy 98.28083 -329.801426)
			(xy 98.2716 -329.821442) (xy 98.271076 -329.832462) (xy 98.271076 -330.084176) (xy 98.271559 -330.094189)
			(xy 98.279214 -330.112693) (xy 98.293367 -330.126859) (xy 98.311864 -330.134531) (xy 98.321876 -330.134976)
			(xy 100.353622 -330.134976) (xy 100.359718 -330.135484) (xy 100.362512 -330.135992) (xy 100.37445 -330.13777)
			(xy 100.382832 -330.138532) (xy 104.606852 -330.138532)
		)
		(stroke
			(width 0)
			(type solid)
		)
		(fill yes)
		(layer "In13.Cu")
		(net "P0V8_PEX0")
	)
	(gr_poly
		(pts
			(xy 138.072368 -184.52719) (xy 138.072876 -184.52719) (xy 138.080035 -184.525486) (xy 138.093062 -184.518654)
			(xy 138.09853 -184.513728) (xy 139.181332 -183.430926) (xy 139.185966 -183.425943) (xy 139.192648 -183.414095)
			(xy 139.19454 -183.407558) (xy 139.196328 -183.399052) (xy 139.194715 -183.381758) (xy 139.18742 -183.365994)
			(xy 139.181586 -183.359552) (xy 135.938514 -180.116734) (xy 135.920961 -180.098518) (xy 135.891228 -180.057594)
			(xy 135.868269 -180.01252) (xy 135.852649 -179.964407) (xy 135.844753 -179.914443) (xy 135.84428 -179.88915)
			(xy 135.84428 -178.626262) (xy 135.842756 -178.614578) (xy 135.836914 -178.59375) (xy 135.834882 -178.58994)
			(xy 135.82293 -178.56825) (xy 135.804115 -178.52244) (xy 135.791392 -178.474578) (xy 135.784976 -178.425472)
			(xy 135.78459 -178.40071) (xy 135.78459 -178.400456) (xy 135.785076 -178.373205) (xy 135.792832 -178.319257)
			(xy 135.808187 -178.266962) (xy 135.830829 -178.217385) (xy 135.860295 -178.171535) (xy 135.895986 -178.130344)
			(xy 135.937177 -178.094653) (xy 135.983027 -178.065187) (xy 136.032604 -178.042545) (xy 136.084899 -178.02719)
			(xy 136.138847 -178.019434) (xy 136.193349 -178.019434) (xy 136.247297 -178.02719) (xy 136.299592 -178.042545)
			(xy 136.349169 -178.065187) (xy 136.395019 -178.094653) (xy 136.43621 -178.130344) (xy 136.471901 -178.171535)
			(xy 136.501367 -178.217385) (xy 136.524009 -178.266962) (xy 136.539364 -178.319257) (xy 136.54712 -178.373205)
			(xy 136.547606 -178.400456) (xy 136.547606 -178.40071) (xy 136.547195 -178.42547) (xy 136.540763 -178.474571)
			(xy 136.528046 -178.52243) (xy 136.509258 -178.568248) (xy 136.497314 -178.58994) (xy 136.495282 -178.59375)
			(xy 136.48944 -178.614578) (xy 136.487916 -178.626262) (xy 136.487916 -179.734718) (xy 136.489186 -179.745894)
			(xy 136.490986 -179.752692) (xy 136.497694 -179.765045) (xy 136.502394 -179.770278) (xy 139.6365 -182.904384)
			(xy 139.642908 -182.910259) (xy 139.658623 -182.917668) (xy 139.667234 -182.918862) (xy 139.67714 -182.918862)
			(xy 139.68476 -182.917592) (xy 139.689924 -182.916069) (xy 139.699521 -182.911196) (xy 139.70381 -182.90794)
			(xy 139.706604 -182.9054) (xy 139.707874 -182.904384) (xy 140.629386 -181.982872) (xy 140.63437 -181.977444)
			(xy 140.641223 -181.964405) (xy 140.642848 -181.957218) (xy 140.642848 -181.95671) (xy 140.643864 -181.947312)
			(xy 140.643864 -175.1711) (xy 140.643691 -175.165092) (xy 140.640855 -175.153416) (xy 140.638276 -175.147986)
			(xy 140.636436 -175.144512) (xy 140.631841 -175.138134) (xy 140.629132 -175.135286) (xy 140.551408 -175.057562)
			(xy 140.548558 -175.054855) (xy 140.542181 -175.050259) (xy 140.538708 -175.048418) (xy 140.53328 -175.045839)
			(xy 140.521601 -175.043026) (xy 140.515594 -175.04283) (xy 139.694158 -175.04283) (xy 139.686538 -175.043338)
			(xy 139.678616 -175.044817) (xy 139.664229 -175.052058) (xy 139.658344 -175.057562) (xy 138.28141 -176.435004)
			(xy 138.279632 -176.43729) (xy 138.279632 -177.286666) (xy 138.279801 -177.292819) (xy 138.282754 -177.304766)
			(xy 138.285474 -177.310288) (xy 138.299312 -177.33786) (xy 138.318886 -177.396359) (xy 138.328803 -177.457244)
			(xy 138.329416 -177.488088) (xy 138.329416 -177.489612) (xy 138.328908 -177.504598) (xy 138.327207 -177.532321)
			(xy 138.316785 -177.586876) (xy 138.298565 -177.639344) (xy 138.272932 -177.688616) (xy 138.240426 -177.733652)
			(xy 138.201735 -177.7735) (xy 138.157677 -177.807318) (xy 138.109181 -177.834392) (xy 138.057273 -177.854149)
			(xy 138.003048 -177.866173) (xy 137.947654 -177.87021) (xy 137.89226 -177.866173) (xy 137.838035 -177.854149)
			(xy 137.786127 -177.834392) (xy 137.737631 -177.807318) (xy 137.693573 -177.7735) (xy 137.654882 -177.733652)
			(xy 137.622376 -177.688616) (xy 137.596743 -177.639344) (xy 137.578523 -177.586876) (xy 137.568101 -177.532321)
			(xy 137.5664 -177.504598) (xy 137.565892 -177.489612) (xy 137.565892 -177.488088) (xy 137.566485 -177.457244)
			(xy 137.57641 -177.396358) (xy 137.595999 -177.337862) (xy 137.609834 -177.310288) (xy 137.612525 -177.304756)
			(xy 137.61547 -177.292815) (xy 137.615676 -177.286666) (xy 137.615676 -176.542446) (xy 137.615422 -176.53635)
			(xy 137.613303 -176.524029) (xy 137.59905 -176.503524) (xy 137.588244 -176.497234) (xy 137.557002 -176.484534)
			(xy 137.551414 -176.487328) (xy 137.540492 -176.495202) (xy 137.285222 -176.750726) (xy 137.267005 -176.768276)
			(xy 137.226079 -176.798004) (xy 137.181005 -176.820959) (xy 137.132893 -176.836575) (xy 137.08293 -176.844467)
			(xy 137.057638 -176.84496) (xy 136.548114 -176.84496) (xy 136.542105 -176.845131) (xy 136.530426 -176.84796)
			(xy 136.525 -176.850548) (xy 136.521526 -176.852388) (xy 136.515149 -176.856983) (xy 136.5123 -176.859692)
			(xy 135.986774 -177.385218) (xy 135.967993 -177.403331) (xy 135.925796 -177.434016) (xy 135.879315 -177.457717)
			(xy 135.829697 -177.473849) (xy 135.778165 -177.482014) (xy 135.752078 -177.4825) (xy 134.949692 -177.4825)
			(xy 134.937716 -177.48315) (xy 134.916381 -177.494033) (xy 134.908798 -177.503328) (xy 134.860792 -177.57648)
			(xy 134.857475 -177.581933) (xy 134.853365 -177.594012) (xy 134.852664 -177.600356) (xy 134.851648 -177.612802)
			(xy 134.855458 -177.621946) (xy 134.866525 -177.647736) (xy 134.882127 -177.701644) (xy 134.890016 -177.757208)
			(xy 134.89051 -177.785268) (xy 134.89051 -177.785776) (xy 134.889961 -177.816025) (xy 134.880856 -177.875835)
			(xy 134.862835 -177.933587) (xy 134.83631 -177.98796) (xy 134.801888 -178.037711) (xy 134.760356 -178.081702)
			(xy 134.73684 -178.100736) (xy 134.733792 -178.103022) (xy 134.722108 -178.115468) (xy 134.719803 -178.119121)
			(xy 134.716356 -178.12704) (xy 134.71525 -178.131216) (xy 134.713726 -178.143154) (xy 134.713726 -178.162712)
			(xy 134.713892 -178.168087) (xy 134.716205 -178.178586) (xy 134.718298 -178.18354) (xy 134.722616 -178.193192)
			(xy 134.730744 -178.200558) (xy 134.749062 -178.217528) (xy 134.781244 -178.255708) (xy 134.807783 -178.298006)
			(xy 134.82816 -178.343593) (xy 134.841976 -178.391578) (xy 134.848959 -178.441021) (xy 134.849362 -178.465988)
			(xy 134.848842 -178.493973) (xy 134.840088 -178.549253) (xy 134.822792 -178.602483) (xy 134.797382 -178.652351)
			(xy 134.764483 -178.697631) (xy 134.724905 -178.737205) (xy 134.679622 -178.7701) (xy 134.629751 -178.795505)
			(xy 134.57652 -178.812796) (xy 134.521239 -178.821545) (xy 134.493254 -178.822096) (xy 134.476578 -178.821865)
			(xy 134.443376 -178.818686) (xy 134.42696 -178.815746) (xy 134.422134 -178.814984) (xy 134.417308 -178.814984)
			(xy 134.407298 -178.81547) (xy 134.388801 -178.823128) (xy 134.374641 -178.837281) (xy 134.366975 -178.855774)
			(xy 134.366508 -178.865784) (xy 134.366508 -178.91633) (xy 134.366595 -178.920741) (xy 134.368127 -178.929428)
			(xy 134.369556 -178.933602) (xy 134.372604 -178.941984) (xy 134.391654 -178.96459) (xy 134.408926 -178.985164)
			(xy 134.412263 -178.988553) (xy 134.419929 -178.99418) (xy 134.424166 -178.99634) (xy 134.433818 -179.000912)
			(xy 134.44474 -179.001166) (xy 134.464167 -179.00188) (xy 134.502728 -179.00684) (xy 134.521702 -179.011072)
			(xy 134.527798 -179.012088) (xy 134.554702 -179.015704) (xy 134.607144 -179.029714) (xy 134.657002 -179.051181)
			(xy 134.70322 -179.079649) (xy 134.744822 -179.114518) (xy 134.780929 -179.155049) (xy 134.810777 -179.200388)
			(xy 134.833737 -179.249576) (xy 134.849322 -179.301572) (xy 134.857204 -179.355279) (xy 134.857744 -179.38242)
			(xy 134.857268 -179.409036) (xy 134.84969 -179.461726) (xy 134.834691 -179.512801) (xy 134.812577 -179.561222)
			(xy 134.783797 -179.606003) (xy 134.748938 -179.646234) (xy 134.708708 -179.681094) (xy 134.663927 -179.709874)
			(xy 134.615507 -179.731989) (xy 134.564432 -179.746989) (xy 134.511742 -179.754568) (xy 134.485126 -179.755038)
			(xy 134.460234 -179.754276) (xy 134.453122 -179.754784) (xy 134.439302 -179.756781) (xy 134.411459 -179.758942)
			(xy 134.397496 -179.759102) (xy 134.396988 -179.759102) (xy 134.3708 -179.758659) (xy 134.31894 -179.751332)
			(xy 134.268614 -179.736825) (xy 134.220811 -179.715421) (xy 134.176472 -179.687543) (xy 134.156196 -179.670964)
			(xy 134.149592 -179.665376) (xy 134.123684 -179.655724) (xy 134.119666 -179.654513) (xy 134.111371 -179.653241)
			(xy 134.107174 -179.653184) (xy 134.097014 -179.653692) (xy 134.085076 -179.6542) (xy 134.066534 -179.66309)
			(xy 134.059676 -179.67071) (xy 134.041927 -179.689917) (xy 134.001978 -179.723668) (xy 133.957705 -179.751505)
			(xy 133.909976 -179.772883) (xy 133.859729 -179.787382) (xy 133.807948 -179.794717) (xy 133.7818 -179.79517)
			(xy 133.781546 -179.79517) (xy 133.7681 -179.79507) (xy 133.741277 -179.793161) (xy 133.727952 -179.79136)
			(xy 133.722364 -179.790852) (xy 133.721094 -179.790852) (xy 133.684772 -179.78755) (xy 133.658059 -179.783389)
			(xy 133.606125 -179.768371) (xy 133.5569 -179.746021) (xy 133.511411 -179.716807) (xy 133.490716 -179.699412)
			(xy 133.48335 -179.693062) (xy 133.475476 -179.690014) (xy 133.471309 -179.68853) (xy 133.462624 -179.686862)
			(xy 133.458204 -179.686712) (xy 133.423406 -179.68722) (xy 133.389116 -179.687728) (xy 133.384363 -179.687826)
			(xy 133.375027 -179.689618) (xy 133.370574 -179.691284) (xy 133.362446 -179.694586) (xy 133.355334 -179.70119)
			(xy 133.35508 -179.701444) (xy 133.334293 -179.719999) (xy 133.288243 -179.751365) (xy 133.238037 -179.775527)
			(xy 133.184794 -179.791948) (xy 133.129701 -179.800262) (xy 133.101842 -179.800758) (xy 133.101588 -179.800758)
			(xy 133.083554 -179.80025) (xy 133.081522 -179.80025) (xy 133.063018 -179.799005) (xy 133.026373 -179.793276)
			(xy 133.00837 -179.78882) (xy 133.005576 -179.788058) (xy 133.003798 -179.787804) (xy 133.00329 -179.787804)
			(xy 133.002274 -179.78755) (xy 132.972424 -179.780732) (xy 132.915316 -179.758661) (xy 132.862594 -179.727535)
			(xy 132.815682 -179.688194) (xy 132.795264 -179.665376) (xy 132.780278 -179.64785) (xy 132.777738 -179.647596)
			(xy 132.749798 -179.64785) (xy 132.743929 -179.647996) (xy 132.732502 -179.650681) (xy 132.727192 -179.653184)
			(xy 132.696966 -179.668678) (xy 132.694934 -179.671472) (xy 132.678524 -179.693144) (xy 132.640834 -179.732317)
			(xy 132.598245 -179.7661) (xy 132.551522 -179.793885) (xy 132.501504 -179.815174) (xy 132.449088 -179.829584)
			(xy 132.395216 -179.836857) (xy 132.368036 -179.837334) (xy 132.339859 -179.836847) (xy 132.284049 -179.829039)
			(xy 132.229857 -179.813583) (xy 132.178325 -179.790777) (xy 132.130445 -179.761058) (xy 132.087138 -179.724999)
			(xy 132.067808 -179.704492) (xy 132.060696 -179.696618) (xy 132.03301 -179.684172) (xy 132.028062 -179.682064)
			(xy 132.017558 -179.67976) (xy 132.012182 -179.6796) (xy 131.994148 -179.6796) (xy 131.990338 -179.679854)
			(xy 131.98983 -179.679854) (xy 131.985845 -179.680279) (xy 131.978066 -179.682198) (xy 131.974336 -179.683664)
			(xy 131.965192 -179.687728) (xy 131.95808 -179.695094) (xy 131.936866 -179.716092) (xy 131.88899 -179.751733)
			(xy 131.836046 -179.77929) (xy 131.779387 -179.798057) (xy 131.720461 -179.807556) (xy 131.690618 -179.808124)
			(xy 131.662668 -179.807632) (xy 131.607393 -179.799295) (xy 131.553985 -179.78279) (xy 131.503643 -179.758489)
			(xy 131.480306 -179.7431) (xy 131.478274 -179.741576) (xy 131.452366 -179.724304) (xy 131.433164 -179.709946)
			(xy 131.398255 -179.677078) (xy 131.38277 -179.658772) (xy 131.382516 -179.658518) (xy 131.370578 -179.644294)
			(xy 131.364736 -179.642516) (xy 131.315968 -179.63642) (xy 131.285996 -179.63261) (xy 131.284218 -179.63261)
			(xy 131.266438 -179.654708) (xy 131.24865 -179.676225) (xy 131.207731 -179.714202) (xy 131.161607 -179.745654)
			(xy 131.11131 -179.769877) (xy 131.057963 -179.78633) (xy 131.002759 -179.794645) (xy 130.974846 -179.79517)
			(xy 130.948227 -179.794721) (xy 130.895531 -179.78715) (xy 130.844449 -179.772155) (xy 130.796021 -179.750042)
			(xy 130.751234 -179.721261) (xy 130.711 -179.686399) (xy 130.676138 -179.646164) (xy 130.647357 -179.601377)
			(xy 130.625244 -179.552949) (xy 130.61025 -179.501867) (xy 130.602679 -179.449171) (xy 130.602228 -179.422552)
			(xy 130.60264 -179.397379) (xy 130.609415 -179.347492) (xy 130.622847 -179.298972) (xy 130.642693 -179.252704)
			(xy 130.66859 -179.20953) (xy 130.684016 -179.189634) (xy 130.685032 -179.188364) (xy 130.686048 -179.18684)
			(xy 130.69062 -179.179474) (xy 130.691636 -179.177696) (xy 130.705521 -179.152068) (xy 130.740022 -179.105092)
			(xy 130.78141 -179.064055) (xy 130.828678 -179.029956) (xy 130.880676 -179.003626) (xy 130.936137 -178.985705)
			(xy 130.99371 -178.97663) (xy 131.022852 -178.97602) (xy 131.044781 -178.976368) (xy 131.088329 -178.981593)
			(xy 131.10972 -178.986434) (xy 131.110482 -178.986434) (xy 131.116784 -178.987712) (xy 131.129636 -178.987457)
			(xy 131.135882 -178.985926) (xy 131.141724 -178.984148) (xy 131.147058 -178.9811) (xy 131.157218 -178.973226)
			(xy 131.16052 -178.969924) (xy 131.166416 -178.962448) (xy 131.172666 -178.944477) (xy 131.171895 -178.925466)
			(xy 131.164213 -178.908059) (xy 131.157726 -178.90109) (xy 131.155186 -178.89855) (xy 131.138507 -178.88128)
			(xy 131.110246 -178.842471) (xy 131.08841 -178.799715) (xy 131.073538 -178.754068) (xy 131.065997 -178.706654)
			(xy 131.065524 -178.68265) (xy 131.065524 -178.61661) (xy 131.06527 -178.612546) (xy 131.06527 -178.612038)
			(xy 131.064075 -178.60322) (xy 131.056536 -178.587116) (xy 131.050538 -178.580542) (xy 130.99669 -178.529234)
			(xy 130.992726 -178.525691) (xy 130.983631 -178.520187) (xy 130.978656 -178.518312) (xy 130.969004 -178.514756)
			(xy 130.95859 -178.515264) (xy 130.938016 -178.515772) (xy 130.910132 -178.515278) (xy 130.854986 -178.506968)
			(xy 130.801695 -178.490532) (xy 130.751449 -178.466337) (xy 130.705371 -178.434923) (xy 130.664489 -178.396992)
			(xy 130.629717 -178.353391) (xy 130.601832 -178.305095) (xy 130.581458 -178.253182) (xy 130.569048 -178.198812)
			(xy 130.56488 -178.1432) (xy 130.569048 -178.087588) (xy 130.581458 -178.033218) (xy 130.601832 -177.981305)
			(xy 130.629717 -177.933009) (xy 130.664489 -177.889408) (xy 130.705371 -177.851477) (xy 130.751449 -177.820063)
			(xy 130.801695 -177.795868) (xy 130.854986 -177.779432) (xy 130.910132 -177.771122) (xy 130.938016 -177.770536)
			(xy 130.95859 -177.771044) (xy 130.968496 -177.771552) (xy 130.977894 -177.76825) (xy 130.978656 -177.767996)
			(xy 130.983625 -177.76611) (xy 130.99271 -177.760597) (xy 130.99669 -177.757074) (xy 131.050538 -177.705766)
			(xy 131.056614 -177.699248) (xy 131.064143 -177.683111) (xy 131.06527 -177.67427) (xy 131.06527 -177.673762)
			(xy 131.065524 -177.669698) (xy 131.065524 -177.195226) (xy 131.06499 -177.184864) (xy 131.056744 -177.165844)
			(xy 131.049522 -177.158396) (xy 131.03606 -177.145696) (xy 130.995674 -177.10785) (xy 130.99542 -177.10785)
			(xy 130.988185 -177.101596) (xy 130.97043 -177.094534) (xy 130.960876 -177.094134) (xy 130.95732 -177.094134)
			(xy 130.932936 -177.094896) (xy 130.906317 -177.094446) (xy 130.853621 -177.086874) (xy 130.802538 -177.071879)
			(xy 130.75411 -177.049766) (xy 130.709323 -177.020985) (xy 130.669087 -176.986123) (xy 130.634224 -176.945889)
			(xy 130.605441 -176.901102) (xy 130.583326 -176.852675) (xy 130.568329 -176.801593) (xy 130.560755 -176.748897)
			(xy 130.560318 -176.722278) (xy 130.560759 -176.696164) (xy 130.568056 -176.644448) (xy 130.582504 -176.594258)
			(xy 130.60382 -176.546577) (xy 130.631586 -176.502341) (xy 130.665258 -176.462416) (xy 130.704175 -176.427585)
			(xy 130.747576 -176.39853) (xy 130.770884 -176.386744) (xy 130.777234 -176.383696) (xy 130.787394 -176.374806)
			(xy 130.791458 -176.36871) (xy 130.794793 -176.363335) (xy 130.798908 -176.351377) (xy 130.799586 -176.345088)
			(xy 130.801618 -176.29124) (xy 130.803142 -176.253394) (xy 130.8032 -176.248675) (xy 130.801803 -176.239342)
			(xy 130.800348 -176.234852) (xy 130.798316 -176.229772) (xy 130.794787 -176.222885) (xy 130.784315 -176.211503)
			(xy 130.777742 -176.20742) (xy 130.774694 -176.205642) (xy 130.752344 -176.191932) (xy 130.711563 -176.15898)
			(xy 130.676054 -176.120405) (xy 130.646584 -176.077041) (xy 130.62379 -176.029824) (xy 130.608165 -175.979776)
			(xy 130.600046 -175.927978) (xy 130.599609 -175.875549) (xy 130.606864 -175.823623) (xy 130.621653 -175.773321)
			(xy 130.643657 -175.725732) (xy 130.6724 -175.681882) (xy 130.707262 -175.642721) (xy 130.747488 -175.609093)
			(xy 130.769614 -175.595026) (xy 130.79003 -175.582986) (xy 130.833382 -175.563823) (xy 130.878892 -175.550581)
			(xy 130.925757 -175.543495) (xy 130.949446 -175.542702) (xy 130.95605 -175.542702) (xy 130.983917 -175.543268)
			(xy 131.038964 -175.551998) (xy 131.091982 -175.569191) (xy 131.141676 -175.594427) (xy 131.186836 -175.627091)
			(xy 131.207002 -175.646334) (xy 131.20751 -175.646842) (xy 131.210855 -175.650119) (xy 131.218526 -175.655489)
			(xy 131.22275 -175.65751) (xy 131.226306 -175.65878) (xy 131.22783 -175.659542) (xy 131.228338 -175.659542)
			(xy 131.2418 -175.665638) (xy 131.247642 -175.667416) (xy 131.248658 -175.667416) (xy 131.252153 -175.668237)
			(xy 131.259292 -175.669007) (xy 131.262882 -175.66894) (xy 131.27482 -175.668178) (xy 131.275074 -175.668178)
			(xy 131.300474 -175.6537) (xy 131.3053 -175.65116) (xy 131.314444 -175.645826) (xy 131.315714 -175.643794)
			(xy 131.315968 -175.64354) (xy 131.331939 -175.620531) (xy 131.36929 -175.578796) (xy 131.412102 -175.542683)
			(xy 131.459537 -175.512901) (xy 131.510665 -175.490034) (xy 131.564484 -175.474528) (xy 131.619942 -175.466687)
			(xy 131.647946 -175.466248) (xy 131.6482 -175.466248) (xy 131.676887 -175.46676) (xy 131.733665 -175.475008)
			(xy 131.788677 -175.491303) (xy 131.840787 -175.515311) (xy 131.88892 -175.546537) (xy 131.910836 -175.565054)
			(xy 131.91617 -175.569372) (xy 131.941062 -175.579024) (xy 131.945526 -175.580651) (xy 131.954855 -175.58244)
			(xy 131.959604 -175.58258) (xy 131.971288 -175.58258) (xy 131.976041 -175.582482) (xy 131.985377 -175.58069)
			(xy 131.98983 -175.579024) (xy 132.014722 -175.569372) (xy 132.020056 -175.565054) (xy 132.041974 -175.546542)
			(xy 132.090116 -175.515336) (xy 132.142227 -175.491337) (xy 132.197234 -175.475038) (xy 132.254007 -175.466775)
			(xy 132.282692 -175.466248) (xy 132.282946 -175.466248) (xy 132.311464 -175.46676) (xy 132.367919 -175.474883)
			(xy 132.422644 -175.490958) (xy 132.474523 -175.514658) (xy 132.522502 -175.545499) (xy 132.565603 -175.582855)
			(xy 132.60295 -175.625964) (xy 132.633782 -175.673949) (xy 132.65747 -175.725833) (xy 132.673534 -175.780561)
			(xy 132.681646 -175.837018) (xy 132.682234 -175.865536) (xy 132.682234 -175.866044) (xy 132.682078 -175.881602)
			(xy 132.679659 -175.912625) (xy 132.677408 -175.92802) (xy 132.6769 -175.935894) (xy 132.67724 -175.945428)
			(xy 132.684163 -175.963187) (xy 132.690362 -175.970438) (xy 132.696204 -175.976788) (xy 132.702554 -175.983646)
			(xy 132.710005 -175.990865) (xy 132.729022 -175.999106) (xy 132.739384 -175.999648) (xy 132.765546 -175.999648)
			(xy 132.77234 -175.999234) (xy 132.785349 -175.995249) (xy 132.7912 -175.991774) (xy 132.800598 -175.9839)
			(xy 132.808218 -175.975772) (xy 132.812028 -175.971962) (xy 132.817708 -175.965288) (xy 132.82459 -175.949184)
			(xy 132.82549 -175.940466) (xy 132.82549 -175.937164) (xy 132.825236 -175.930814) (xy 132.824982 -175.92929)
			(xy 132.823579 -175.917274) (xy 132.822054 -175.893127) (xy 132.821934 -175.88103) (xy 132.821934 -175.880522)
			(xy 132.822417 -175.851999) (xy 132.830533 -175.795532) (xy 132.846603 -175.740795) (xy 132.8703 -175.688903)
			(xy 132.901141 -175.640912) (xy 132.938499 -175.597799) (xy 132.981612 -175.560441) (xy 133.029603 -175.5296)
			(xy 133.081495 -175.505903) (xy 133.136232 -175.489833) (xy 133.192699 -175.481717) (xy 133.221222 -175.481234)
			(xy 133.221476 -175.481234) (xy 133.249295 -175.481721) (xy 133.304392 -175.489459) (xy 133.357881 -175.504773)
			(xy 133.408725 -175.527367) (xy 133.455938 -175.556803) (xy 133.498606 -175.592511) (xy 133.51764 -175.612806)
			(xy 133.52018 -175.615854) (xy 133.524498 -175.62068) (xy 133.549644 -175.63211) (xy 133.554724 -175.633888)
			(xy 133.574028 -175.638206) (xy 133.57479 -175.638206) (xy 133.579474 -175.638045) (xy 133.588672 -175.636248)
			(xy 133.593078 -175.63465) (xy 133.60146 -175.631348) (xy 133.609842 -175.62322) (xy 133.626963 -175.607351)
			(xy 133.664623 -175.579764) (xy 133.705562 -175.55733) (xy 133.72719 -175.548544) (xy 133.737096 -175.544734)
			(xy 134.101332 -175.180244) (xy 134.118256 -175.163917) (xy 134.156018 -175.135894) (xy 134.197467 -175.113686)
			(xy 134.219442 -175.105314) (xy 134.228936 -175.101999) (xy 134.248253 -175.096407) (xy 134.25805 -175.094138)
			(xy 134.26186 -175.093122) (xy 134.278431 -175.089864) (xy 134.312029 -175.086425) (xy 134.328916 -175.086264)
			(xy 135.75792 -175.086264) (xy 135.767763 -175.085817) (xy 135.785998 -175.078399) (xy 135.80007 -175.064634)
			(xy 135.804402 -175.055784) (xy 135.821166 -175.011334) (xy 135.839962 -174.96155) (xy 135.841868 -174.954715)
			(xy 135.842264 -174.940536) (xy 135.840724 -174.93361) (xy 135.8392 -174.926752) (xy 135.831326 -174.913798)
			(xy 135.830818 -174.91329) (xy 135.828278 -174.911258) (xy 135.82523 -174.908464) (xy 135.805844 -174.890793)
			(xy 135.771615 -174.851045) (xy 135.743146 -174.806988) (xy 135.720972 -174.759451) (xy 135.70551 -174.709326)
			(xy 135.697051 -174.657558) (xy 135.695944 -174.63135) (xy 135.695944 -174.622206) (xy 135.696378 -174.595784)
			(xy 135.703638 -174.543443) (xy 135.718047 -174.492603) (xy 135.739331 -174.444236) (xy 135.767082 -174.399267)
			(xy 135.783574 -174.37862) (xy 135.784082 -174.378112) (xy 135.787384 -174.374048) (xy 135.792373 -174.365958)
			(xy 135.796546 -174.347428) (xy 135.795512 -174.33798) (xy 135.77189 -174.248572) (xy 135.770074 -174.243767)
			(xy 135.764829 -174.234937) (xy 135.761476 -174.231046) (xy 135.757412 -174.226728) (xy 135.747506 -174.220124)
			(xy 135.741664 -174.217838) (xy 135.714707 -174.207205) (xy 135.664102 -174.178978) (xy 135.61834 -174.14343)
			(xy 135.578474 -174.101378) (xy 135.545418 -174.053786) (xy 135.519929 -174.001747) (xy 135.502594 -173.946455)
			(xy 135.49381 -173.889179) (xy 135.493252 -173.860206) (xy 135.493737 -173.832953) (xy 135.501493 -173.779003)
			(xy 135.516847 -173.726705) (xy 135.539487 -173.677125) (xy 135.568953 -173.631271) (xy 135.604644 -173.590076)
			(xy 135.645834 -173.55438) (xy 135.691684 -173.524909) (xy 135.741262 -173.502263) (xy 135.793558 -173.486903)
			(xy 135.847507 -173.479141) (xy 135.87476 -173.478698) (xy 135.901598 -173.479158) (xy 135.954744 -173.486687)
			(xy 136.006312 -173.501586) (xy 136.055283 -173.523564) (xy 136.100692 -173.552185) (xy 136.141644 -173.586886)
			(xy 136.17733 -173.626982) (xy 136.207047 -173.671682) (xy 136.230208 -173.720105) (xy 136.246357 -173.771295)
			(xy 136.255175 -173.824242) (xy 136.256268 -173.851062) (xy 136.256268 -173.860206) (xy 136.255833 -173.886627)
			(xy 136.248572 -173.938968) (xy 136.234162 -173.989808) (xy 136.212878 -174.038174) (xy 136.185126 -174.083142)
			(xy 136.168638 -174.103792) (xy 136.16813 -174.1043) (xy 136.164828 -174.108364) (xy 136.15984 -174.116454)
			(xy 136.155671 -174.134983) (xy 136.1567 -174.144432) (xy 136.180322 -174.23384) (xy 136.182139 -174.238644)
			(xy 136.187387 -174.247472) (xy 136.190736 -174.251366) (xy 136.1948 -174.255684) (xy 136.204706 -174.262288)
			(xy 136.210548 -174.264574) (xy 136.240605 -174.276487) (xy 136.29653 -174.308921) (xy 136.3218 -174.32909)
			(xy 136.329166 -174.335186) (xy 136.338056 -174.338234) (xy 136.342435 -174.339581) (xy 136.351508 -174.340853)
			(xy 136.35609 -174.340774) (xy 136.377172 -174.339758) (xy 136.37768 -174.339758) (xy 136.420098 -174.337218)
			(xy 136.431274 -174.334424) (xy 136.459468 -174.321724) (xy 136.466072 -174.315374) (xy 136.47928 -174.302928)
			(xy 136.479788 -174.30242) (xy 136.500773 -174.284572) (xy 136.546912 -174.254472) (xy 136.596901 -174.231322)
			(xy 136.649701 -174.215604) (xy 136.704212 -174.207645) (xy 136.731756 -174.20717) (xy 136.740138 -174.20717)
			(xy 136.772902 -174.208526) (xy 136.837266 -174.221049) (xy 136.868154 -174.232062) (xy 136.894918 -174.242798)
			(xy 136.94512 -174.271166) (xy 136.990476 -174.306774) (xy 137.029949 -174.348809) (xy 137.046716 -174.37227)
			(xy 137.050018 -174.377096) (xy 137.058654 -174.385224) (xy 137.063226 -174.387764) (xy 137.067508 -174.39005)
			(xy 137.076717 -174.393118) (xy 137.081514 -174.39386) (xy 137.11555 -174.397162) (xy 137.116058 -174.397162)
			(xy 137.165334 -174.40148) (xy 137.174521 -174.401269) (xy 137.191832 -174.395145) (xy 137.199116 -174.389542)
			(xy 140.048742 -171.539916) (xy 140.065661 -171.523582) (xy 140.103416 -171.495543) (xy 140.144861 -171.473319)
			(xy 140.166852 -171.464986) (xy 140.176346 -171.461671) (xy 140.195664 -171.45608) (xy 140.20546 -171.45381)
			(xy 140.20927 -171.452794) (xy 140.225841 -171.449536) (xy 140.259439 -171.446099) (xy 140.276326 -171.445936)
			(xy 140.3604 -171.445936) (xy 140.36421 -171.445682) (xy 140.364718 -171.445682) (xy 140.373943 -171.444472)
			(xy 140.390679 -171.436381) (xy 140.403444 -171.422866) (xy 140.40739 -171.41444) (xy 140.407644 -171.413932)
			(xy 140.408914 -171.41063) (xy 140.408914 -171.410376) (xy 140.40993 -171.40809) (xy 140.410438 -171.406566)
			(xy 140.411962 -171.392342) (xy 140.410438 -171.38523) (xy 140.40891 -171.378636) (xy 140.402854 -171.366537)
			(xy 140.3985 -171.361354) (xy 140.172186 -171.135294) (xy 140.032232 -170.99534) (xy 140.024826 -170.988646)
			(xy 140.00639 -170.981046) (xy 139.996418 -170.980608) (xy 137.140188 -170.980608) (xy 137.134177 -170.980771)
			(xy 137.122491 -170.983587) (xy 137.117074 -170.986196) (xy 137.1136 -170.988036) (xy 137.107222 -170.99263)
			(xy 137.104374 -170.99534) (xy 135.009128 -173.090586) (xy 136.552176 -173.090586) (xy 136.556247 -173.034964)
			(xy 136.568373 -172.980527) (xy 136.588296 -172.928436) (xy 136.615592 -172.879801) (xy 136.649678 -172.835658)
			(xy 136.689827 -172.796949) (xy 136.735185 -172.764498) (xy 136.784785 -172.738997) (xy 136.837569 -172.72099)
			(xy 136.892412 -172.71086) (xy 136.948146 -172.708823) (xy 137.003583 -172.714923) (xy 137.05754 -172.729029)
			(xy 137.108869 -172.750841) (xy 137.156475 -172.779895) (xy 137.199343 -172.81557) (xy 137.23656 -172.857107)
			(xy 137.267333 -172.90362) (xy 137.291005 -172.954117) (xy 137.307073 -173.007524) (xy 137.315193 -173.0627)
			(xy 137.315702 -173.090586) (xy 137.315193 -173.118472) (xy 137.307073 -173.173648) (xy 137.291005 -173.227055)
			(xy 137.267333 -173.277552) (xy 137.23656 -173.324065) (xy 137.199343 -173.365602) (xy 137.156475 -173.401277)
			(xy 137.108869 -173.430331) (xy 137.05754 -173.452143) (xy 137.003583 -173.466249) (xy 136.948146 -173.472349)
			(xy 136.892412 -173.470312) (xy 136.837569 -173.460182) (xy 136.784785 -173.442175) (xy 136.735185 -173.416674)
			(xy 136.689827 -173.384223) (xy 136.649678 -173.345514) (xy 136.615592 -173.301371) (xy 136.588296 -173.252736)
			(xy 136.568373 -173.200645) (xy 136.556247 -173.146208) (xy 136.552176 -173.090586) (xy 135.009128 -173.090586)
			(xy 133.002782 -175.096932) (xy 132.984012 -175.114964) (xy 132.941895 -175.145544) (xy 132.895519 -175.169169)
			(xy 132.846021 -175.185259) (xy 132.794617 -175.19342) (xy 132.768594 -175.19396) (xy 129.791714 -175.19396)
			(xy 129.765691 -175.19343) (xy 129.714291 -175.185258) (xy 129.664797 -175.16916) (xy 129.618424 -175.145531)
			(xy 129.576309 -175.114951) (xy 129.557526 -175.096932) (xy 127.06477 -172.604176) (xy 127.063246 -172.602652)
			(xy 127.061214 -172.601128) (xy 127.05314 -172.594987) (xy 127.033748 -172.589094) (xy 127.023622 -172.589698)
			(xy 126.938024 -172.60316) (xy 126.927094 -172.605943) (xy 126.909029 -172.619397) (xy 126.903226 -172.629068)
			(xy 126.902972 -172.629322) (xy 126.902972 -172.629576) (xy 126.896635 -172.64143) (xy 126.882526 -172.664312)
			(xy 126.874778 -172.675296) (xy 126.874778 -172.67555) (xy 126.851664 -172.70476) (xy 126.850648 -172.705776)
			(xy 126.846145 -172.711737) (xy 126.840468 -172.725549) (xy 126.839472 -172.732954) (xy 126.839218 -172.73778)
			(xy 126.839218 -172.805344) (xy 126.839472 -172.81017) (xy 126.840434 -172.817585) (xy 126.846104 -172.831412)
			(xy 126.850648 -172.837348) (xy 126.851664 -172.838364) (xy 126.869304 -172.859296) (xy 126.899025 -172.905263)
			(xy 126.921862 -172.95501) (xy 126.937345 -173.007514) (xy 126.945155 -173.061692) (xy 126.945644 -173.089062)
			(xy 126.945158 -173.116313) (xy 126.937402 -173.170261) (xy 126.922047 -173.222556) (xy 126.899405 -173.272133)
			(xy 126.869939 -173.317983) (xy 126.834248 -173.359174) (xy 126.793057 -173.394865) (xy 126.747207 -173.424331)
			(xy 126.69763 -173.446973) (xy 126.645335 -173.462328) (xy 126.591387 -173.470084) (xy 126.536885 -173.470084)
			(xy 126.482937 -173.462328) (xy 126.430642 -173.446973) (xy 126.381065 -173.424331) (xy 126.335215 -173.394865)
			(xy 126.294024 -173.359174) (xy 126.258333 -173.317983) (xy 126.228867 -173.272133) (xy 126.206225 -173.222556)
			(xy 126.19087 -173.170261) (xy 126.183114 -173.116313) (xy 126.182628 -173.089062) (xy 126.183094 -173.063019)
			(xy 126.190223 -173.011423) (xy 126.204302 -172.961276) (xy 126.22507 -172.91351) (xy 126.252141 -172.869011)
			(xy 126.268226 -172.848524) (xy 126.268734 -172.847508) (xy 126.27102 -172.844714) (xy 126.276608 -172.828712)
			(xy 126.276608 -172.78731) (xy 126.289054 -172.78731) (xy 126.289054 -172.73778) (xy 126.2888 -172.732954)
			(xy 126.287827 -172.725544) (xy 126.282138 -172.711733) (xy 126.277624 -172.705776) (xy 126.276608 -172.70476)
			(xy 126.258968 -172.683828) (xy 126.229246 -172.637861) (xy 126.206408 -172.588114) (xy 126.190923 -172.53561)
			(xy 126.18311 -172.481432) (xy 126.182628 -172.454062) (xy 126.183078 -172.427934) (xy 126.190243 -172.376172)
			(xy 126.204395 -172.325869) (xy 126.225268 -172.277963) (xy 126.238508 -172.255434) (xy 126.238762 -172.254926)
			(xy 126.24207 -172.249095) (xy 126.245795 -172.236222) (xy 126.246128 -172.229526) (xy 126.246382 -172.216318)
			(xy 126.195836 -172.126656) (xy 126.191114 -172.119014) (xy 126.177447 -172.107374) (xy 126.160614 -172.101132)
			(xy 126.15164 -172.100748) (xy 125.817122 -172.100748) (xy 125.791099 -172.100219) (xy 125.739698 -172.092048)
			(xy 125.690204 -172.07595) (xy 125.64383 -172.052321) (xy 125.601716 -172.02174) (xy 125.582934 -172.00372)
			(xy 123.911614 -170.3324) (xy 123.893498 -170.313621) (xy 123.862806 -170.271425) (xy 123.8391 -170.224945)
			(xy 123.822962 -170.175326) (xy 123.814793 -170.123793) (xy 123.814332 -170.097704) (xy 123.814332 -169.675556)
			(xy 123.814078 -169.671492) (xy 123.813664 -169.667238) (xy 123.811626 -169.65894) (xy 123.810014 -169.654982)
			(xy 123.80849 -169.652188) (xy 123.794715 -169.624688) (xy 123.775236 -169.566353) (xy 123.765368 -169.505647)
			(xy 123.764802 -169.474896) (xy 123.765266 -169.447644) (xy 123.773023 -169.393694) (xy 123.78838 -169.341397)
			(xy 123.811022 -169.291818) (xy 123.840491 -169.245966) (xy 123.876185 -169.204775) (xy 123.917377 -169.169082)
			(xy 123.96323 -169.139616) (xy 124.01281 -169.116975) (xy 124.065107 -169.10162) (xy 124.119058 -169.093865)
			(xy 124.14631 -169.093388) (xy 124.175498 -169.093944) (xy 124.233194 -169.102836) (xy 124.288862 -169.120412)
			(xy 124.341203 -169.146261) (xy 124.388997 -169.17978) (xy 124.41047 -169.19956) (xy 124.417582 -169.206418)
			(xy 124.425964 -169.209974) (xy 124.430293 -169.211639) (xy 124.439366 -169.213553) (xy 124.443998 -169.213784)
			(xy 124.463048 -169.214292) (xy 124.514864 -169.215816) (xy 124.523777 -169.21535) (xy 124.540438 -169.208983)
			(xy 124.547376 -169.20337) (xy 124.568242 -169.18602) (xy 124.613958 -169.156783) (xy 124.663358 -169.134325)
			(xy 124.715444 -169.119101) (xy 124.769163 -169.111418) (xy 124.796296 -169.110914) (xy 124.823547 -169.111377)
			(xy 124.877496 -169.119133) (xy 124.929791 -169.134488) (xy 124.979369 -169.157129) (xy 124.980575 -169.157904)
			(xy 125.619762 -169.157904) (xy 125.623833 -169.102282) (xy 125.635959 -169.047845) (xy 125.655882 -168.995754)
			(xy 125.683178 -168.947119) (xy 125.717264 -168.902976) (xy 125.757413 -168.864267) (xy 125.802771 -168.831816)
			(xy 125.852371 -168.806315) (xy 125.905155 -168.788308) (xy 125.959998 -168.778178) (xy 126.015732 -168.776141)
			(xy 126.071169 -168.782241) (xy 126.125126 -168.796347) (xy 126.176455 -168.818159) (xy 126.224061 -168.847213)
			(xy 126.266929 -168.882888) (xy 126.304146 -168.924425) (xy 126.334919 -168.970938) (xy 126.358591 -169.021435)
			(xy 126.374659 -169.074842) (xy 126.382779 -169.130018) (xy 126.383288 -169.157904) (xy 126.382779 -169.18579)
			(xy 126.374659 -169.240966) (xy 126.358591 -169.294373) (xy 126.334919 -169.34487) (xy 126.304146 -169.391383)
			(xy 126.266929 -169.43292) (xy 126.224061 -169.468595) (xy 126.176455 -169.497649) (xy 126.125126 -169.519461)
			(xy 126.071169 -169.533567) (xy 126.015732 -169.539667) (xy 125.959998 -169.53763) (xy 125.905155 -169.5275)
			(xy 125.852371 -169.509493) (xy 125.802771 -169.483992) (xy 125.757413 -169.451541) (xy 125.717264 -169.412832)
			(xy 125.683178 -169.368689) (xy 125.655882 -169.320054) (xy 125.635959 -169.267963) (xy 125.623833 -169.213526)
			(xy 125.619762 -169.157904) (xy 124.980575 -169.157904) (xy 125.02522 -169.186595) (xy 125.066411 -169.222287)
			(xy 125.102103 -169.263477) (xy 125.131569 -169.309328) (xy 125.154211 -169.358905) (xy 125.169566 -169.4112)
			(xy 125.177323 -169.465149) (xy 125.177323 -169.519651) (xy 125.169566 -169.5736) (xy 125.154211 -169.625895)
			(xy 125.131569 -169.675472) (xy 125.102103 -169.721323) (xy 125.066411 -169.762513) (xy 125.02522 -169.798205)
			(xy 124.979369 -169.827671) (xy 124.929791 -169.850312) (xy 124.877496 -169.865667) (xy 124.823547 -169.873423)
			(xy 124.796296 -169.87393) (xy 124.796042 -169.87393) (xy 124.767422 -169.873403) (xy 124.710829 -169.864813)
			(xy 124.656159 -169.84785) (xy 124.63018 -169.83583) (xy 124.619766 -169.832274) (xy 124.602748 -169.82821)
			(xy 124.596083 -169.828411) (xy 124.583216 -169.831899) (xy 124.577348 -169.835068) (xy 124.499878 -169.882566)
			(xy 124.490241 -169.890185) (xy 124.478948 -169.911956) (xy 124.478288 -169.924222) (xy 124.478288 -169.939208)
			(xy 124.478746 -169.949086) (xy 124.486185 -169.967388) (xy 124.492766 -169.974768) (xy 124.970794 -170.452796)
			(xy 125.940566 -171.422822) (xy 125.946466 -171.428162) (xy 125.960696 -171.435265) (xy 125.968506 -171.436792)
			(xy 125.976126 -171.4373) (xy 126.699518 -171.4373) (xy 126.725543 -171.437825) (xy 126.77695 -171.445986)
			(xy 126.826452 -171.462075) (xy 126.872834 -171.485696) (xy 126.914959 -171.51627) (xy 126.933706 -171.534328)
			(xy 127.51308 -172.113702) (xy 132.256782 -172.113702) (xy 132.260853 -172.05808) (xy 132.272979 -172.003643)
			(xy 132.292902 -171.951552) (xy 132.320198 -171.902917) (xy 132.354284 -171.858774) (xy 132.394433 -171.820065)
			(xy 132.439791 -171.787614) (xy 132.489391 -171.762113) (xy 132.542175 -171.744106) (xy 132.597018 -171.733976)
			(xy 132.652752 -171.731939) (xy 132.708189 -171.738039) (xy 132.762146 -171.752145) (xy 132.813475 -171.773957)
			(xy 132.861081 -171.803011) (xy 132.903949 -171.838686) (xy 132.941166 -171.880223) (xy 132.971939 -171.926736)
			(xy 132.995611 -171.977233) (xy 133.011679 -172.03064) (xy 133.019799 -172.085816) (xy 133.020308 -172.113702)
			(xy 133.019799 -172.141588) (xy 133.011679 -172.196764) (xy 132.995611 -172.250171) (xy 132.971939 -172.300668)
			(xy 132.941166 -172.347181) (xy 132.903949 -172.388718) (xy 132.861081 -172.424393) (xy 132.813475 -172.453447)
			(xy 132.762146 -172.475259) (xy 132.708189 -172.489365) (xy 132.652752 -172.495465) (xy 132.597018 -172.493428)
			(xy 132.542175 -172.483298) (xy 132.489391 -172.465291) (xy 132.439791 -172.43979) (xy 132.394433 -172.407339)
			(xy 132.354284 -172.36863) (xy 132.320198 -172.324487) (xy 132.292902 -172.275852) (xy 132.272979 -172.223761)
			(xy 132.260853 -172.169324) (xy 132.256782 -172.113702) (xy 127.51308 -172.113702) (xy 129.559304 -174.159926)
			(xy 129.56792 -174.16772) (xy 129.589878 -174.175243) (xy 129.601468 -174.174404) (xy 129.68097 -174.164752)
			(xy 129.686714 -174.163905) (xy 129.69762 -174.159929) (xy 129.70256 -174.156878) (xy 129.707386 -174.15383)
			(xy 129.71526 -174.145448) (xy 129.718308 -174.140368) (xy 129.733189 -174.116535) (xy 129.768849 -174.073115)
			(xy 129.810493 -174.035397) (xy 129.857219 -174.004196) (xy 129.908017 -173.980187) (xy 129.961787 -173.963889)
			(xy 130.017367 -173.955655) (xy 130.04546 -173.955202) (xy 130.072714 -173.955663) (xy 130.126669 -173.963415)
			(xy 130.178971 -173.978768) (xy 130.228556 -174.001408) (xy 130.274413 -174.030875) (xy 130.31561 -174.066569)
			(xy 130.351307 -174.107763) (xy 130.380778 -174.153618) (xy 130.403422 -174.203201) (xy 130.418779 -174.255501)
			(xy 130.426535 -174.309456) (xy 130.426968 -174.33671) (xy 130.426724 -174.355052) (xy 130.423159 -174.391564)
			(xy 130.419856 -174.409608) (xy 130.419348 -174.41164) (xy 130.418351 -174.42231) (xy 130.424129 -174.442919)
			(xy 130.430524 -174.451518) (xy 130.480562 -174.51197) (xy 130.488164 -174.520252) (xy 130.508455 -174.529869)
			(xy 130.519678 -174.530512) (xy 131.999228 -174.530512) (xy 132.010653 -174.529894) (xy 132.031255 -174.520014)
			(xy 132.038852 -174.511462) (xy 132.065014 -174.47895) (xy 132.088636 -174.449486) (xy 132.092123 -174.444892)
			(xy 132.097131 -174.434504) (xy 132.098542 -174.428912) (xy 132.101082 -174.418244) (xy 132.098542 -174.407068)
			(xy 132.094425 -174.387064) (xy 132.089971 -174.346463) (xy 132.089652 -174.326042) (xy 132.089652 -174.324264)
			(xy 132.089652 -174.320708) (xy 132.090397 -174.294052) (xy 132.098417 -174.241334) (xy 132.113701 -174.190246)
			(xy 132.135951 -174.141785) (xy 132.164733 -174.096895) (xy 132.199487 -174.05645) (xy 132.239534 -174.02124)
			(xy 132.284095 -173.991951) (xy 132.332301 -173.969152) (xy 132.357622 -173.96079) (xy 132.35813 -173.96079)
			(xy 132.363792 -173.958744) (xy 132.374053 -173.952456) (xy 132.37845 -173.948344) (xy 135.746998 -170.58005)
			(xy 135.75366 -170.572584) (xy 135.761184 -170.554066) (xy 135.761094 -170.534077) (xy 135.757666 -170.524678)
			(xy 135.746236 -170.497246) (xy 135.74014 -170.495468) (xy 135.736661 -170.494519) (xy 135.729522 -170.493498)
			(xy 135.725916 -170.493436) (xy 133.415024 -170.493436) (xy 133.390443 -170.492945) (xy 133.341857 -170.485427)
			(xy 133.294975 -170.470623) (xy 133.250883 -170.448875) (xy 133.210602 -170.420687) (xy 133.19252 -170.404028)
			(xy 133.182614 -170.394122) (xy 133.181852 -170.393106) (xy 133.143244 -170.354498) (xy 132.946902 -170.157902)
			(xy 132.482082 -169.693082) (xy 132.477645 -169.688927) (xy 132.467247 -169.682638) (xy 132.461508 -169.680636)
			(xy 132.458968 -169.679874) (xy 132.431006 -169.672079) (xy 132.377662 -169.649194) (xy 132.328401 -169.618491)
			(xy 132.284361 -169.580679) (xy 132.246558 -169.53663) (xy 132.215866 -169.487362) (xy 132.192993 -169.434013)
			(xy 132.185156 -169.406062) (xy 132.184394 -169.403522) (xy 132.182407 -169.397775) (xy 132.17612 -169.387372)
			(xy 132.171948 -169.382948) (xy 132.15239 -169.36339) (xy 132.14509 -169.356791) (xy 132.126947 -169.349214)
			(xy 132.107286 -169.349012) (xy 132.088992 -169.356215) (xy 132.081524 -169.362628) (xy 132.078476 -169.365422)
			(xy 132.076698 -169.367708) (xy 132.058514 -169.389769) (xy 132.016662 -169.428716) (xy 131.969465 -169.460976)
			(xy 131.917979 -169.485829) (xy 131.863361 -169.502716) (xy 131.806833 -169.511258) (xy 131.778248 -169.511726)
			(xy 131.750992 -169.511266) (xy 131.697035 -169.503515) (xy 131.644731 -169.488163) (xy 131.595143 -169.465524)
			(xy 131.549283 -169.436057) (xy 131.508083 -169.400364) (xy 131.472382 -169.35917) (xy 131.442908 -169.313315)
			(xy 131.42026 -169.263731) (xy 131.404899 -169.211429) (xy 131.397138 -169.157474) (xy 131.39674 -169.130218)
			(xy 131.397316 -169.100383) (xy 131.406607 -169.041441) (xy 131.424964 -168.984665) (xy 131.45194 -168.931441)
			(xy 131.486876 -168.883068) (xy 131.507484 -168.861486) (xy 131.507738 -168.861232) (xy 131.513951 -168.854295)
			(xy 131.521372 -168.837232) (xy 131.522216 -168.827958) (xy 131.521962 -168.754044) (xy 131.521476 -168.744082)
			(xy 131.513887 -168.725658) (xy 131.50723 -168.71823) (xy 128.897634 -166.108634) (xy 128.894784 -166.105927)
			(xy 128.888408 -166.10133) (xy 128.884934 -166.09949) (xy 128.879507 -166.09691) (xy 128.867827 -166.094092)
			(xy 128.86182 -166.093902) (xy 126.113286 -166.093902) (xy 126.102175 -166.094458) (xy 126.082011 -166.103801)
			(xy 126.074424 -166.111936) (xy 126.055374 -166.134288) (xy 126.024132 -166.171372) (xy 126.020714 -166.175612)
			(xy 126.015593 -166.185222) (xy 126.013972 -166.190422) (xy 126.011178 -166.200836) (xy 126.012956 -166.212012)
			(xy 126.015327 -166.227396) (xy 126.01787 -166.258423) (xy 126.018036 -166.273988) (xy 126.017536 -166.302091)
			(xy 126.009287 -166.357689) (xy 125.992967 -166.411473) (xy 125.968929 -166.462279) (xy 125.937693 -166.509007)
			(xy 125.899937 -166.550643) (xy 125.856478 -166.586286) (xy 125.832616 -166.60114) (xy 125.832362 -166.601394)
			(xy 125.822714 -166.60792) (xy 125.810136 -166.627496) (xy 125.808232 -166.638986) (xy 125.803152 -166.735252)
			(xy 125.802898 -166.739062) (xy 125.810772 -166.75608) (xy 125.818646 -166.765732) (xy 125.823726 -166.769542)
			(xy 125.846897 -166.787671) (xy 125.8879 -166.829859) (xy 125.921935 -166.877844) (xy 125.948196 -166.930488)
			(xy 125.966057 -166.986541) (xy 125.975097 -167.044673) (xy 125.975618 -167.074088) (xy 125.975296 -167.092122)
			(xy 126.498094 -167.092122) (xy 126.502165 -167.0365) (xy 126.514291 -166.982063) (xy 126.534214 -166.929972)
			(xy 126.56151 -166.881337) (xy 126.595596 -166.837194) (xy 126.635745 -166.798485) (xy 126.681103 -166.766034)
			(xy 126.730703 -166.740533) (xy 126.783487 -166.722526) (xy 126.83833 -166.712396) (xy 126.894064 -166.710359)
			(xy 126.949501 -166.716459) (xy 127.003458 -166.730565) (xy 127.054787 -166.752377) (xy 127.102393 -166.781431)
			(xy 127.145261 -166.817106) (xy 127.182478 -166.858643) (xy 127.213251 -166.905156) (xy 127.236923 -166.955653)
			(xy 127.252991 -167.00906) (xy 127.261111 -167.064236) (xy 127.26162 -167.092122) (xy 127.261111 -167.120008)
			(xy 127.252991 -167.175184) (xy 127.236923 -167.228591) (xy 127.213251 -167.279088) (xy 127.182478 -167.325601)
			(xy 127.145261 -167.367138) (xy 127.102393 -167.402813) (xy 127.054787 -167.431867) (xy 127.003458 -167.453679)
			(xy 126.949501 -167.467785) (xy 126.894064 -167.473885) (xy 126.83833 -167.471848) (xy 126.783487 -167.461718)
			(xy 126.730703 -167.443711) (xy 126.681103 -167.41821) (xy 126.635745 -167.385759) (xy 126.595596 -167.34705)
			(xy 126.56151 -167.302907) (xy 126.534214 -167.254272) (xy 126.514291 -167.202181) (xy 126.502165 -167.147744)
			(xy 126.498094 -167.092122) (xy 125.975296 -167.092122) (xy 125.975132 -167.101339) (xy 125.967376 -167.155287)
			(xy 125.952021 -167.207582) (xy 125.929379 -167.257159) (xy 125.899913 -167.303009) (xy 125.864222 -167.3442)
			(xy 125.823031 -167.379891) (xy 125.777181 -167.409357) (xy 125.727604 -167.431999) (xy 125.675309 -167.447354)
			(xy 125.621361 -167.45511) (xy 125.566859 -167.45511) (xy 125.512911 -167.447354) (xy 125.460616 -167.431999)
			(xy 125.411039 -167.409357) (xy 125.365189 -167.379891) (xy 125.323998 -167.3442) (xy 125.288307 -167.303009)
			(xy 125.258841 -167.257159) (xy 125.236199 -167.207582) (xy 125.220844 -167.155287) (xy 125.213088 -167.101339)
			(xy 125.212602 -167.074088) (xy 125.213104 -167.045985) (xy 125.221354 -166.990388) (xy 125.237675 -166.936604)
			(xy 125.261713 -166.885797) (xy 125.292947 -166.839069) (xy 125.330701 -166.79743) (xy 125.374157 -166.761784)
			(xy 125.398022 -166.746936) (xy 125.398276 -166.746682) (xy 125.407915 -166.74015) (xy 125.420475 -166.720573)
			(xy 125.422406 -166.70909) (xy 125.427486 -166.612824) (xy 125.42774 -166.609014) (xy 125.419866 -166.591996)
			(xy 125.411992 -166.582344) (xy 125.406912 -166.578534) (xy 125.383746 -166.560402) (xy 125.342752 -166.518211)
			(xy 125.308725 -166.470225) (xy 125.282472 -166.417581) (xy 125.264617 -166.36153) (xy 125.255583 -166.303401)
			(xy 125.25502 -166.273988) (xy 125.255173 -166.258422) (xy 125.257715 -166.227395) (xy 125.2601 -166.212012)
			(xy 125.261878 -166.200836) (xy 125.259084 -166.190422) (xy 125.257454 -166.185227) (xy 125.252328 -166.175622)
			(xy 125.248924 -166.171372) (xy 125.183392 -166.093902) (xy 125.171708 -166.093902) (xy 122.98299 -163.905184)
			(xy 122.976136 -163.897789) (xy 122.968393 -163.87919) (xy 122.968004 -163.869116) (xy 122.968004 -160.218628)
			(xy 122.96775 -160.21431) (xy 122.96585 -160.202817) (xy 122.953276 -160.183235) (xy 122.94362 -160.176718)
			(xy 122.920523 -160.163071) (xy 122.878053 -160.130296) (xy 122.840592 -160.091895) (xy 122.808881 -160.048625)
			(xy 122.783543 -160.001339) (xy 122.765079 -159.95097) (xy 122.753854 -159.898511) (xy 122.750087 -159.844997)
			(xy 122.753854 -159.791483) (xy 122.765081 -159.739024) (xy 122.783546 -159.688656) (xy 122.808884 -159.64137)
			(xy 122.840596 -159.598101) (xy 122.878057 -159.5597) (xy 122.920528 -159.526926) (xy 122.94362 -159.51327)
			(xy 122.953251 -159.506733) (xy 122.965795 -159.487154) (xy 122.96775 -159.475678) (xy 122.968004 -159.47136)
			(xy 122.968004 -159.202628) (xy 122.96775 -159.19831) (xy 122.96585 -159.186817) (xy 122.953276 -159.167235)
			(xy 122.94362 -159.160718) (xy 122.920523 -159.147071) (xy 122.878053 -159.114296) (xy 122.840592 -159.075895)
			(xy 122.808881 -159.032625) (xy 122.783543 -158.985339) (xy 122.765079 -158.93497) (xy 122.753854 -158.882511)
			(xy 122.750087 -158.828997) (xy 122.753854 -158.775483) (xy 122.765081 -158.723024) (xy 122.783546 -158.672656)
			(xy 122.808884 -158.62537) (xy 122.840596 -158.582101) (xy 122.878057 -158.5437) (xy 122.920528 -158.510926)
			(xy 122.94362 -158.49727) (xy 122.953251 -158.490733) (xy 122.965795 -158.471154) (xy 122.96775 -158.459678)
			(xy 122.968004 -158.45536) (xy 122.968004 -158.186628) (xy 122.96775 -158.18231) (xy 122.96585 -158.170817)
			(xy 122.953276 -158.151235) (xy 122.94362 -158.144718) (xy 122.920523 -158.131071) (xy 122.878053 -158.098296)
			(xy 122.840592 -158.059895) (xy 122.808881 -158.016625) (xy 122.783543 -157.969339) (xy 122.765079 -157.91897)
			(xy 122.753854 -157.866511) (xy 122.750087 -157.812997) (xy 122.753854 -157.759483) (xy 122.765081 -157.707024)
			(xy 122.783546 -157.656656) (xy 122.808884 -157.60937) (xy 122.840596 -157.566101) (xy 122.878057 -157.5277)
			(xy 122.920528 -157.494926) (xy 122.94362 -157.48127) (xy 122.953251 -157.474733) (xy 122.965795 -157.455154)
			(xy 122.96775 -157.443678) (xy 122.968004 -157.43936) (xy 122.968004 -140.82776) (xy 122.967507 -140.81819)
			(xy 122.960337 -140.800433) (xy 122.954034 -140.793216) (xy 122.947176 -140.78712) (xy 122.90806 -140.762228)
			(xy 122.868436 -140.737336) (xy 122.863197 -140.734766) (xy 122.85191 -140.731813) (xy 122.846084 -140.731494)
			(xy 122.827796 -140.740384) (xy 122.801204 -140.75279) (xy 122.745209 -140.770324) (xy 122.687208 -140.779206)
			(xy 122.65787 -140.779754) (xy 122.630203 -140.779258) (xy 122.575432 -140.771379) (xy 122.522339 -140.755786)
			(xy 122.472006 -140.732797) (xy 122.425457 -140.702878) (xy 122.383639 -140.66664) (xy 122.347404 -140.624819)
			(xy 122.317489 -140.578268) (xy 122.294503 -140.527933) (xy 122.278914 -140.474839) (xy 122.27104 -140.420067)
			(xy 122.27104 -140.364733) (xy 122.278914 -140.309961) (xy 122.294503 -140.256867) (xy 122.317489 -140.206532)
			(xy 122.347404 -140.159981) (xy 122.383639 -140.11816) (xy 122.425457 -140.081922) (xy 122.472006 -140.052003)
			(xy 122.522339 -140.029014) (xy 122.575432 -140.013421) (xy 122.630203 -140.005542) (xy 122.65787 -140.005054)
			(xy 122.687207 -140.005614) (xy 122.745206 -140.014497) (xy 122.801204 -140.03202) (xy 122.827796 -140.044424)
			(xy 122.84583 -140.053314) (xy 122.850677 -140.053031) (xy 122.860137 -140.050848) (xy 122.864626 -140.048996)
			(xy 122.865134 -140.048996) (xy 122.867166 -140.04798) (xy 122.884946 -140.036804) (xy 122.885454 -140.036804)
			(xy 122.944128 -139.99972) (xy 122.950478 -139.995148) (xy 122.955734 -139.990309) (xy 122.963476 -139.978309)
			(xy 122.965718 -139.971526) (xy 122.966751 -139.96793) (xy 122.967894 -139.960535) (xy 122.968004 -139.956794)
			(xy 122.968004 -139.81176) (xy 122.967507 -139.80219) (xy 122.960337 -139.784433) (xy 122.954034 -139.777216)
			(xy 122.947176 -139.77112) (xy 122.90806 -139.746228) (xy 122.868436 -139.721336) (xy 122.863197 -139.718766)
			(xy 122.85191 -139.715813) (xy 122.846084 -139.715494) (xy 122.827796 -139.724384) (xy 122.801204 -139.73679)
			(xy 122.745209 -139.754324) (xy 122.687208 -139.763206) (xy 122.65787 -139.763754) (xy 122.630203 -139.763258)
			(xy 122.575432 -139.755379) (xy 122.522339 -139.739786) (xy 122.472006 -139.716797) (xy 122.425457 -139.686878)
			(xy 122.383639 -139.65064) (xy 122.347404 -139.608819) (xy 122.317489 -139.562268) (xy 122.294503 -139.511933)
			(xy 122.278914 -139.458839) (xy 122.27104 -139.404067) (xy 122.27104 -139.348733) (xy 122.278914 -139.293961)
			(xy 122.294503 -139.240867) (xy 122.317489 -139.190532) (xy 122.347404 -139.143981) (xy 122.383639 -139.10216)
			(xy 122.425457 -139.065922) (xy 122.472006 -139.036003) (xy 122.522339 -139.013014) (xy 122.575432 -138.997421)
			(xy 122.630203 -138.989542) (xy 122.65787 -138.989054) (xy 122.687207 -138.989614) (xy 122.745206 -138.998497)
			(xy 122.801204 -139.01602) (xy 122.827796 -139.028424) (xy 122.84583 -139.037314) (xy 122.850677 -139.037031)
			(xy 122.860137 -139.034848) (xy 122.864626 -139.032996) (xy 122.865134 -139.032996) (xy 122.867166 -139.03198)
			(xy 122.884946 -139.020804) (xy 122.885454 -139.020804) (xy 122.944128 -138.98372) (xy 122.950478 -138.979148)
			(xy 122.955734 -138.974309) (xy 122.963476 -138.962309) (xy 122.965718 -138.955526) (xy 122.966751 -138.95193)
			(xy 122.967894 -138.944535) (xy 122.968004 -138.940794) (xy 122.968004 -138.79576) (xy 122.967507 -138.78619)
			(xy 122.960337 -138.768433) (xy 122.954034 -138.761216) (xy 122.947176 -138.75512) (xy 122.90806 -138.730228)
			(xy 122.868436 -138.705336) (xy 122.863197 -138.702766) (xy 122.85191 -138.699813) (xy 122.846084 -138.699494)
			(xy 122.827796 -138.708384) (xy 122.801204 -138.72079) (xy 122.745209 -138.738324) (xy 122.687208 -138.747206)
			(xy 122.65787 -138.747754) (xy 122.630203 -138.747258) (xy 122.575432 -138.739379) (xy 122.522339 -138.723786)
			(xy 122.472006 -138.700797) (xy 122.425457 -138.670878) (xy 122.383639 -138.63464) (xy 122.347404 -138.592819)
			(xy 122.317489 -138.546268) (xy 122.294503 -138.495933) (xy 122.278914 -138.442839) (xy 122.27104 -138.388067)
			(xy 122.27104 -138.332733) (xy 122.278914 -138.277961) (xy 122.294503 -138.224867) (xy 122.317489 -138.174532)
			(xy 122.347404 -138.127981) (xy 122.383639 -138.08616) (xy 122.425457 -138.049922) (xy 122.472006 -138.020003)
			(xy 122.522339 -137.997014) (xy 122.575432 -137.981421) (xy 122.630203 -137.973542) (xy 122.65787 -137.973054)
			(xy 122.687207 -137.973614) (xy 122.745206 -137.982497) (xy 122.801204 -138.00002) (xy 122.827796 -138.012424)
			(xy 122.84583 -138.021314) (xy 122.850677 -138.021031) (xy 122.860137 -138.018848) (xy 122.864626 -138.016996)
			(xy 122.865134 -138.016996) (xy 122.867166 -138.01598) (xy 122.884946 -138.004804) (xy 122.885454 -138.004804)
			(xy 122.944128 -137.96772) (xy 122.950478 -137.963148) (xy 122.955734 -137.958309) (xy 122.963476 -137.946309)
			(xy 122.965718 -137.939526) (xy 122.966751 -137.93593) (xy 122.967894 -137.928535) (xy 122.968004 -137.924794)
			(xy 122.968004 -137.77976) (xy 122.967507 -137.77019) (xy 122.960337 -137.752433) (xy 122.954034 -137.745216)
			(xy 122.947176 -137.73912) (xy 122.90806 -137.714228) (xy 122.868436 -137.689336) (xy 122.863197 -137.686766)
			(xy 122.85191 -137.683813) (xy 122.846084 -137.683494) (xy 122.827796 -137.692384) (xy 122.801204 -137.70479)
			(xy 122.745209 -137.722324) (xy 122.687208 -137.731206) (xy 122.65787 -137.731754) (xy 122.630203 -137.731258)
			(xy 122.575432 -137.723379) (xy 122.522339 -137.707786) (xy 122.472006 -137.684797) (xy 122.425457 -137.654878)
			(xy 122.383639 -137.61864) (xy 122.347404 -137.576819) (xy 122.317489 -137.530268) (xy 122.294503 -137.479933)
			(xy 122.278914 -137.426839) (xy 122.27104 -137.372067) (xy 122.27104 -137.316733) (xy 122.278914 -137.261961)
			(xy 122.294503 -137.208867) (xy 122.317489 -137.158532) (xy 122.347404 -137.111981) (xy 122.383639 -137.07016)
			(xy 122.425457 -137.033922) (xy 122.472006 -137.004003) (xy 122.522339 -136.981014) (xy 122.575432 -136.965421)
			(xy 122.630203 -136.957542) (xy 122.65787 -136.957054) (xy 122.687207 -136.957614) (xy 122.745206 -136.966497)
			(xy 122.801204 -136.98402) (xy 122.827796 -136.996424) (xy 122.84583 -137.005314) (xy 122.850677 -137.005031)
			(xy 122.860137 -137.002848) (xy 122.864626 -137.000996) (xy 122.865134 -137.000996) (xy 122.867166 -136.99998)
			(xy 122.884946 -136.988804) (xy 122.885454 -136.988804) (xy 122.944128 -136.95172) (xy 122.950478 -136.947148)
			(xy 122.955734 -136.942309) (xy 122.963476 -136.930309) (xy 122.965718 -136.923526) (xy 122.966751 -136.91993)
			(xy 122.967894 -136.912535) (xy 122.968004 -136.908794) (xy 122.968004 -136.86536) (xy 122.967235 -136.853178)
			(xy 122.955958 -136.831569) (xy 122.946414 -136.823958) (xy 122.912124 -136.8044) (xy 122.86742 -136.779)
			(xy 122.860562 -136.775444) (xy 122.855376 -136.773244) (xy 122.844351 -136.770937) (xy 122.838718 -136.770872)
			(xy 122.826018 -136.771126) (xy 122.81535 -136.777476) (xy 122.813572 -136.778492) (xy 122.813318 -136.778746)
			(xy 122.790847 -136.791861) (xy 122.743111 -136.812556) (xy 122.693009 -136.82658) (xy 122.641466 -136.833675)
			(xy 122.615452 -136.834118) (xy 122.591322 -136.834118) (xy 122.583956 -136.83361) (xy 122.561604 -136.830308)
			(xy 122.530148 -136.825199) (xy 122.469422 -136.805883) (xy 122.412755 -136.776736) (xy 122.386852 -136.758172)
			(xy 122.369737 -136.74504) (xy 122.338287 -136.715508) (xy 122.324114 -136.699244) (xy 122.323098 -136.698228)
			(xy 122.313192 -136.68629) (xy 122.310398 -136.682734) (xy 122.30354 -136.673082) (xy 122.30354 -136.672574)
			(xy 122.28578 -136.646385) (xy 122.258277 -136.589402) (xy 122.240568 -136.528658) (xy 122.23623 -136.497314)
			(xy 122.234706 -136.483598) (xy 122.233436 -136.45261) (xy 122.23399 -136.423042) (xy 122.243107 -136.364614)
			(xy 122.261125 -136.30829) (xy 122.287612 -136.255418) (xy 122.321935 -136.207263) (xy 122.363274 -136.164976)
			(xy 122.386598 -136.146794) (xy 122.391678 -136.142984) (xy 122.397926 -136.136461) (xy 122.40574 -136.120189)
			(xy 122.406918 -136.111234) (xy 122.408696 -136.04875) (xy 122.408696 -136.048242) (xy 122.409458 -136.026144)
			(xy 122.409317 -136.021112) (xy 122.40727 -136.011257) (xy 122.405394 -136.006586) (xy 122.400822 -135.996426)
			(xy 122.399044 -135.994902) (xy 122.397774 -135.993886) (xy 122.391932 -135.988806) (xy 122.371438 -135.970599)
			(xy 122.33537 -135.929316) (xy 122.305583 -135.883296) (xy 122.282691 -135.833486) (xy 122.267166 -135.780911)
			(xy 122.259326 -135.726656) (xy 122.258836 -135.699246) (xy 122.259354 -135.670506) (xy 122.267971 -135.613675)
			(xy 122.285017 -135.558781) (xy 122.310107 -135.507065) (xy 122.342671 -135.459699) (xy 122.36196 -135.438388)
			(xy 122.36831 -135.43153) (xy 122.371866 -135.423148) (xy 122.373532 -135.41882) (xy 122.375449 -135.409746)
			(xy 122.375676 -135.405114) (xy 122.376184 -135.389112) (xy 122.376184 -135.388604) (xy 122.377454 -135.33755)
			(xy 122.377485 -135.333097) (xy 122.376202 -135.324287) (xy 122.374914 -135.320024) (xy 122.373547 -135.316301)
			(xy 122.369848 -135.309285) (xy 122.367548 -135.306054) (xy 122.364754 -135.302752) (xy 122.348153 -135.282094)
			(xy 122.32021 -135.237062) (xy 122.298761 -135.1886) (xy 122.284216 -135.137639) (xy 122.276855 -135.085156)
			(xy 122.276362 -135.058658) (xy 122.276362 -135.05434) (xy 122.277116 -135.027372) (xy 122.285285 -134.974045)
			(xy 122.300886 -134.922402) (xy 122.323608 -134.873471) (xy 122.352997 -134.82823) (xy 122.388467 -134.787581)
			(xy 122.42931 -134.752335) (xy 122.474712 -134.723195) (xy 122.523767 -134.700743) (xy 122.575496 -134.685426)
			(xy 122.628867 -134.677551) (xy 122.655838 -134.676896) (xy 122.660156 -134.676896) (xy 122.672348 -134.67715)
			(xy 122.697754 -134.6785) (xy 122.747895 -134.68711) (xy 122.796442 -134.702325) (xy 122.819668 -134.71271)
			(xy 122.82043 -134.713218) (xy 122.820938 -134.713218) (xy 122.822716 -134.714234) (xy 122.82551 -134.715504)
			(xy 122.826526 -134.716012) (xy 122.843798 -134.719314) (xy 122.84916 -134.719198) (xy 122.859661 -134.717025)
			(xy 122.864626 -134.714996) (xy 122.865134 -134.714996) (xy 122.868436 -134.713218) (xy 122.8852 -134.702804)
			(xy 122.944128 -134.66572) (xy 122.950478 -134.661148) (xy 122.955734 -134.656309) (xy 122.963476 -134.644309)
			(xy 122.965718 -134.637526) (xy 122.966751 -134.63393) (xy 122.967894 -134.626535) (xy 122.968004 -134.622794)
			(xy 122.968004 -134.47776) (xy 122.967507 -134.46819) (xy 122.960337 -134.450433) (xy 122.954034 -134.443216)
			(xy 122.947176 -134.43712) (xy 122.90806 -134.412228) (xy 122.868436 -134.387336) (xy 122.863197 -134.384766)
			(xy 122.85191 -134.381813) (xy 122.846084 -134.381494) (xy 122.827796 -134.390384) (xy 122.801204 -134.40279)
			(xy 122.745209 -134.420324) (xy 122.687208 -134.429206) (xy 122.65787 -134.429754) (xy 122.630203 -134.429258)
			(xy 122.575432 -134.421379) (xy 122.522339 -134.405786) (xy 122.472006 -134.382797) (xy 122.425457 -134.352878)
			(xy 122.383639 -134.31664) (xy 122.347404 -134.274819) (xy 122.317489 -134.228268) (xy 122.294503 -134.177933)
			(xy 122.278914 -134.124839) (xy 122.27104 -134.070067) (xy 122.27104 -134.014733) (xy 122.278914 -133.959961)
			(xy 122.294503 -133.906867) (xy 122.317489 -133.856532) (xy 122.347404 -133.809981) (xy 122.383639 -133.76816)
			(xy 122.425457 -133.731922) (xy 122.472006 -133.702003) (xy 122.522339 -133.679014) (xy 122.575432 -133.663421)
			(xy 122.630203 -133.655542) (xy 122.65787 -133.655054) (xy 122.687207 -133.655614) (xy 122.745206 -133.664497)
			(xy 122.801204 -133.68202) (xy 122.827796 -133.694424) (xy 122.84583 -133.703314) (xy 122.850677 -133.703031)
			(xy 122.860137 -133.700848) (xy 122.864626 -133.698996) (xy 122.865134 -133.698996) (xy 122.867166 -133.69798)
			(xy 122.884946 -133.686804) (xy 122.885454 -133.686804) (xy 122.944128 -133.64972) (xy 122.950478 -133.645148)
			(xy 122.955734 -133.640309) (xy 122.963476 -133.628309) (xy 122.965718 -133.621526) (xy 122.966751 -133.61793)
			(xy 122.967894 -133.610535) (xy 122.968004 -133.606794) (xy 122.968004 -114.212116) (xy 122.968443 -114.202053)
			(xy 122.976179 -114.183471) (xy 122.98299 -114.176048) (xy 125.078744 -112.080294) (xy 125.085546 -112.072965)
			(xy 125.093264 -112.054535) (xy 125.093322 -112.034555) (xy 125.085711 -112.016081) (xy 125.078998 -112.008666)
			(xy 125.07849 -112.008158) (xy 125.060664 -111.990147) (xy 125.029441 -111.950234) (xy 125.003778 -111.906538)
			(xy 124.984126 -111.859829) (xy 124.970831 -111.810929) (xy 124.964126 -111.760699) (xy 124.963682 -111.735362)
			(xy 124.96417 -111.708112) (xy 124.971931 -111.654168) (xy 124.98729 -111.601877) (xy 125.009933 -111.552304)
			(xy 125.0394 -111.506458) (xy 125.075091 -111.465271) (xy 125.11628 -111.429583) (xy 125.162129 -111.400119)
			(xy 125.211704 -111.37748) (xy 125.263996 -111.362125) (xy 125.31794 -111.354368) (xy 125.34519 -111.353854)
			(xy 125.370528 -111.354268) (xy 125.420759 -111.360977) (xy 125.469659 -111.374278) (xy 125.516368 -111.393937)
			(xy 125.560061 -111.419608) (xy 125.599971 -111.450838) (xy 125.617986 -111.468662) (xy 125.618494 -111.46917)
			(xy 125.625938 -111.475813) (xy 125.644399 -111.483325) (xy 125.66433 -111.48326) (xy 125.682742 -111.475628)
			(xy 125.690122 -111.468916) (xy 125.960886 -111.198152) (xy 125.968287 -111.191314) (xy 125.986886 -111.183602)
			(xy 125.996954 -111.183166) (xy 137.261092 -111.183166) (xy 137.271161 -111.183589) (xy 137.289762 -111.191309)
			(xy 137.29716 -111.198152) (xy 137.850857 -111.751849) (xy 150.191215 -111.751849) (xy 150.191215 -111.694551)
			(xy 150.199369 -111.637835) (xy 150.215511 -111.582858) (xy 150.239313 -111.530737) (xy 150.270289 -111.482534)
			(xy 150.307811 -111.439229) (xy 150.351113 -111.401705) (xy 150.399314 -111.370725) (xy 150.451433 -111.34692)
			(xy 150.50641 -111.330774) (xy 150.563125 -111.322617) (xy 150.591774 -111.322104) (xy 150.619154 -111.322588)
			(xy 150.673404 -111.330052) (xy 150.726132 -111.344831) (xy 150.776358 -111.36665) (xy 150.823146 -111.395103)
			(xy 150.865626 -111.42966) (xy 150.903006 -111.469678) (xy 150.91918 -111.491776) (xy 150.924755 -111.499025)
			(xy 150.939855 -111.509316) (xy 150.948644 -111.511842) (xy 150.978616 -111.519208) (xy 150.987565 -111.520967)
			(xy 151.005656 -111.518745) (xy 151.013922 -111.51489) (xy 151.038519 -111.502494) (xy 151.090046 -111.483026)
			(xy 151.143536 -111.46988) (xy 151.198217 -111.463244) (xy 151.225758 -111.46282) (xy 151.253299 -111.463244)
			(xy 151.307979 -111.469881) (xy 151.361468 -111.48303) (xy 151.412995 -111.502499) (xy 151.437594 -111.51489)
			(xy 151.445855 -111.518764) (xy 151.46395 -111.520981) (xy 151.4729 -111.519208) (xy 151.502872 -111.511842)
			(xy 151.51165 -111.509288) (xy 151.526753 -111.499014) (xy 151.532336 -111.491776) (xy 151.548472 -111.469647)
			(xy 151.585851 -111.429617) (xy 151.628333 -111.395052) (xy 151.675128 -111.366594) (xy 151.725362 -111.344775)
			(xy 151.778099 -111.330001) (xy 151.832358 -111.322548) (xy 151.859742 -111.322104) (xy 151.888386 -111.322678)
			(xy 151.945091 -111.330836) (xy 152.000057 -111.346981) (xy 152.052167 -111.370783) (xy 152.100359 -111.401759)
			(xy 152.143652 -111.439278) (xy 152.181166 -111.482575) (xy 152.212137 -111.53077) (xy 152.235934 -111.582882)
			(xy 152.252073 -111.63785) (xy 152.260225 -111.694556) (xy 152.260225 -111.751844) (xy 152.252073 -111.80855)
			(xy 152.235934 -111.863518) (xy 152.212137 -111.91563) (xy 152.181166 -111.963825) (xy 152.143652 -112.007122)
			(xy 152.100359 -112.044641) (xy 152.052167 -112.075617) (xy 152.000057 -112.099419) (xy 151.945091 -112.115564)
			(xy 151.888386 -112.123722) (xy 151.859742 -112.124236) (xy 151.844824 -112.124068) (xy 151.815075 -112.121778)
			(xy 151.800306 -112.119664) (xy 151.78913 -112.117886) (xy 151.768048 -112.123982) (xy 151.701246 -112.18164)
			(xy 151.693298 -112.189249) (xy 151.684205 -112.209257) (xy 151.68372 -112.220248) (xy 151.68372 -112.484916)
			(xy 151.684211 -112.495907) (xy 151.693296 -112.515919) (xy 151.701246 -112.523524) (xy 151.768048 -112.581182)
			(xy 151.78913 -112.587278) (xy 151.800306 -112.5855) (xy 151.815075 -112.583389) (xy 151.844824 -112.581102)
			(xy 151.859742 -112.580928) (xy 151.888388 -112.581454) (xy 151.945096 -112.589613) (xy 152.000065 -112.605759)
			(xy 152.052178 -112.629562) (xy 152.100373 -112.66054) (xy 152.143669 -112.698061) (xy 152.181185 -112.741361)
			(xy 152.212158 -112.789559) (xy 152.235956 -112.841674) (xy 152.252096 -112.896645) (xy 152.260249 -112.953354)
			(xy 152.260249 -113.010646) (xy 152.252096 -113.067355) (xy 152.235956 -113.122326) (xy 152.212158 -113.174441)
			(xy 152.181185 -113.222639) (xy 152.161691 -113.245138) (xy 160.769552 -113.245138) (xy 160.773623 -113.189516)
			(xy 160.785749 -113.135079) (xy 160.805672 -113.082988) (xy 160.832968 -113.034353) (xy 160.867054 -112.99021)
			(xy 160.907203 -112.951501) (xy 160.952561 -112.91905) (xy 161.002161 -112.893549) (xy 161.054945 -112.875542)
			(xy 161.109788 -112.865412) (xy 161.165522 -112.863375) (xy 161.220959 -112.869475) (xy 161.274916 -112.883581)
			(xy 161.326245 -112.905393) (xy 161.373851 -112.934447) (xy 161.416719 -112.970122) (xy 161.453936 -113.011659)
			(xy 161.484709 -113.058172) (xy 161.508381 -113.108669) (xy 161.524449 -113.162076) (xy 161.532569 -113.217252)
			(xy 161.533078 -113.245138) (xy 163.190426 -113.245138) (xy 163.194497 -113.189516) (xy 163.206623 -113.135079)
			(xy 163.226546 -113.082988) (xy 163.253842 -113.034353) (xy 163.287928 -112.99021) (xy 163.328077 -112.951501)
			(xy 163.373435 -112.91905) (xy 163.423035 -112.893549) (xy 163.475819 -112.875542) (xy 163.530662 -112.865412)
			(xy 163.586396 -112.863375) (xy 163.641833 -112.869475) (xy 163.69579 -112.883581) (xy 163.747119 -112.905393)
			(xy 163.794725 -112.934447) (xy 163.837593 -112.970122) (xy 163.87481 -113.011659) (xy 163.905583 -113.058172)
			(xy 163.929255 -113.108669) (xy 163.945323 -113.162076) (xy 163.953443 -113.217252) (xy 163.953952 -113.245138)
			(xy 163.953443 -113.273024) (xy 163.945323 -113.3282) (xy 163.929255 -113.381607) (xy 163.905583 -113.432104)
			(xy 163.87481 -113.478617) (xy 163.837593 -113.520154) (xy 163.794725 -113.555829) (xy 163.747119 -113.584883)
			(xy 163.69579 -113.606695) (xy 163.641833 -113.620801) (xy 163.586396 -113.626901) (xy 163.530662 -113.624864)
			(xy 163.475819 -113.614734) (xy 163.423035 -113.596727) (xy 163.373435 -113.571226) (xy 163.328077 -113.538775)
			(xy 163.287928 -113.500066) (xy 163.253842 -113.455923) (xy 163.226546 -113.407288) (xy 163.206623 -113.355197)
			(xy 163.194497 -113.30076) (xy 163.190426 -113.245138) (xy 161.533078 -113.245138) (xy 161.532569 -113.273024)
			(xy 161.524449 -113.3282) (xy 161.508381 -113.381607) (xy 161.484709 -113.432104) (xy 161.453936 -113.478617)
			(xy 161.416719 -113.520154) (xy 161.373851 -113.555829) (xy 161.326245 -113.584883) (xy 161.274916 -113.606695)
			(xy 161.220959 -113.620801) (xy 161.165522 -113.626901) (xy 161.109788 -113.624864) (xy 161.054945 -113.614734)
			(xy 161.002161 -113.596727) (xy 160.952561 -113.571226) (xy 160.907203 -113.538775) (xy 160.867054 -113.500066)
			(xy 160.832968 -113.455923) (xy 160.805672 -113.407288) (xy 160.785749 -113.355197) (xy 160.773623 -113.30076)
			(xy 160.769552 -113.245138) (xy 152.161691 -113.245138) (xy 152.143669 -113.265939) (xy 152.100373 -113.30346)
			(xy 152.052178 -113.334438) (xy 152.000065 -113.358241) (xy 151.945096 -113.374387) (xy 151.888388 -113.382546)
			(xy 151.859742 -113.38306) (xy 151.832361 -113.382612) (xy 151.778111 -113.375138) (xy 151.725383 -113.36035)
			(xy 151.675158 -113.338525) (xy 151.62837 -113.310067) (xy 151.585891 -113.275506) (xy 151.54851 -113.235486)
			(xy 151.532336 -113.213388) (xy 151.526763 -113.206137) (xy 151.511661 -113.195848) (xy 151.502872 -113.193322)
			(xy 151.4729 -113.185956) (xy 151.46395 -113.184209) (xy 151.445861 -113.186424) (xy 151.437594 -113.190274)
			(xy 151.412997 -113.202669) (xy 151.361469 -113.222136) (xy 151.307979 -113.235282) (xy 151.253299 -113.241919)
			(xy 151.225758 -113.242344) (xy 151.198217 -113.241918) (xy 151.143537 -113.235281) (xy 151.090047 -113.222134)
			(xy 151.038521 -113.202665) (xy 151.013922 -113.190274) (xy 151.005659 -113.186407) (xy 150.987565 -113.184186)
			(xy 150.978616 -113.185956) (xy 150.948644 -113.193322) (xy 150.939858 -113.195854) (xy 150.92476 -113.206145)
			(xy 150.91918 -113.213388) (xy 150.903024 -113.235502) (xy 150.865649 -113.275533) (xy 150.823171 -113.310101)
			(xy 150.77638 -113.338561) (xy 150.726149 -113.360383) (xy 150.673414 -113.375159) (xy 150.619157 -113.382615)
			(xy 150.591774 -113.38306) (xy 150.563127 -113.382559) (xy 150.506415 -113.374402) (xy 150.451442 -113.358257)
			(xy 150.399326 -113.334453) (xy 150.351127 -113.303475) (xy 150.307828 -113.265954) (xy 150.270309 -113.222652)
			(xy 150.239334 -113.174451) (xy 150.215534 -113.122334) (xy 150.199393 -113.067359) (xy 150.191239 -113.010647)
			(xy 150.191239 -112.953353) (xy 150.199393 -112.896641) (xy 150.215534 -112.841666) (xy 150.239334 -112.789549)
			(xy 150.270309 -112.741348) (xy 150.307828 -112.698046) (xy 150.351127 -112.660525) (xy 150.399326 -112.629547)
			(xy 150.451442 -112.605743) (xy 150.506415 -112.589598) (xy 150.563127 -112.581441) (xy 150.591774 -112.580928)
			(xy 150.606692 -112.581094) (xy 150.636441 -112.583385) (xy 150.65121 -112.5855) (xy 150.662386 -112.587278)
			(xy 150.683468 -112.581182) (xy 150.75027 -112.523524) (xy 150.758237 -112.515932) (xy 150.767319 -112.495911)
			(xy 150.767796 -112.484916) (xy 150.767796 -112.220248) (xy 150.76732 -112.209256) (xy 150.758224 -112.189244)
			(xy 150.75027 -112.18164) (xy 150.683468 -112.123982) (xy 150.662386 -112.117886) (xy 150.65121 -112.119664)
			(xy 150.636441 -112.121774) (xy 150.606692 -112.124061) (xy 150.591774 -112.124236) (xy 150.563125 -112.123783)
			(xy 150.50641 -112.115626) (xy 150.451433 -112.09948) (xy 150.399314 -112.075675) (xy 150.351113 -112.044695)
			(xy 150.307811 -112.007171) (xy 150.270289 -111.963866) (xy 150.239313 -111.915663) (xy 150.215511 -111.863542)
			(xy 150.199369 -111.808565) (xy 150.191215 -111.751849) (xy 137.850857 -111.751849) (xy 139.87907 -113.780062)
			(xy 165.581328 -113.780062) (xy 165.585399 -113.72444) (xy 165.597525 -113.670003) (xy 165.617448 -113.617912)
			(xy 165.644744 -113.569277) (xy 165.67883 -113.525134) (xy 165.718979 -113.486425) (xy 165.764337 -113.453974)
			(xy 165.813937 -113.428473) (xy 165.866721 -113.410466) (xy 165.921564 -113.400336) (xy 165.977298 -113.398299)
			(xy 166.032735 -113.404399) (xy 166.086692 -113.418505) (xy 166.138021 -113.440317) (xy 166.185627 -113.469371)
			(xy 166.228495 -113.505046) (xy 166.265712 -113.546583) (xy 166.296485 -113.593096) (xy 166.320157 -113.643593)
			(xy 166.336225 -113.697) (xy 166.344345 -113.752176) (xy 166.344854 -113.780062) (xy 166.344345 -113.807948)
			(xy 166.336225 -113.863124) (xy 166.320157 -113.916531) (xy 166.296485 -113.967028) (xy 166.265712 -114.013541)
			(xy 166.228495 -114.055078) (xy 166.185627 -114.090753) (xy 166.138021 -114.119807) (xy 166.086692 -114.141619)
			(xy 166.032735 -114.155725) (xy 165.977298 -114.161825) (xy 165.921564 -114.159788) (xy 165.866721 -114.149658)
			(xy 165.813937 -114.131651) (xy 165.764337 -114.10615) (xy 165.718979 -114.073699) (xy 165.67883 -114.03499)
			(xy 165.644744 -113.990847) (xy 165.617448 -113.942212) (xy 165.597525 -113.890121) (xy 165.585399 -113.835684)
			(xy 165.581328 -113.780062) (xy 139.87907 -113.780062) (xy 140.441426 -114.342418) (xy 140.448278 -114.349814)
			(xy 140.456017 -114.368413) (xy 140.456412 -114.378486) (xy 140.456412 -114.4905) (xy 150.415242 -114.4905)
			(xy 150.419313 -114.434878) (xy 150.431439 -114.380441) (xy 150.451362 -114.32835) (xy 150.478658 -114.279715)
			(xy 150.512744 -114.235572) (xy 150.552893 -114.196863) (xy 150.598251 -114.164412) (xy 150.647851 -114.138911)
			(xy 150.700635 -114.120904) (xy 150.755478 -114.110774) (xy 150.811212 -114.108737) (xy 150.866649 -114.114837)
			(xy 150.920606 -114.128943) (xy 150.971935 -114.150755) (xy 151.019541 -114.179809) (xy 151.062409 -114.215484)
			(xy 151.099626 -114.257021) (xy 151.130399 -114.303534) (xy 151.154071 -114.354031) (xy 151.170139 -114.407438)
			(xy 151.178259 -114.462614) (xy 151.178768 -114.4905) (xy 151.178259 -114.518386) (xy 151.170139 -114.573562)
			(xy 151.154071 -114.626969) (xy 151.130399 -114.677466) (xy 151.099626 -114.723979) (xy 151.062409 -114.765516)
			(xy 151.019541 -114.801191) (xy 150.971935 -114.830245) (xy 150.920606 -114.852057) (xy 150.866649 -114.866163)
			(xy 150.811212 -114.872263) (xy 150.755478 -114.870226) (xy 150.700635 -114.860096) (xy 150.647851 -114.842089)
			(xy 150.598251 -114.816588) (xy 150.552893 -114.784137) (xy 150.512744 -114.745428) (xy 150.478658 -114.701285)
			(xy 150.451362 -114.65265) (xy 150.431439 -114.600559) (xy 150.419313 -114.546122) (xy 150.415242 -114.4905)
			(xy 140.456412 -114.4905) (xy 140.456412 -116.539855) (xy 152.64425 -116.539855) (xy 152.64425 -116.485345)
			(xy 152.652008 -116.431389) (xy 152.667367 -116.379086) (xy 152.690013 -116.329502) (xy 152.719486 -116.283646)
			(xy 152.755185 -116.242451) (xy 152.796384 -116.206757) (xy 152.842244 -116.17729) (xy 152.891831 -116.15465)
			(xy 152.944136 -116.139298) (xy 152.998092 -116.131546) (xy 153.025348 -116.131086) (xy 153.051663 -116.131526)
			(xy 153.103792 -116.138767) (xy 153.154435 -116.153092) (xy 153.202634 -116.174229) (xy 153.247477 -116.20178)
			(xy 153.288116 -116.235223) (xy 153.306272 -116.254276) (xy 153.313805 -116.261664) (xy 153.333076 -116.270197)
			(xy 153.34361 -116.270786) (xy 153.418286 -116.270786) (xy 153.428837 -116.270267) (xy 153.448132 -116.261725)
			(xy 153.455624 -116.254276) (xy 153.472631 -116.236404) (xy 153.510464 -116.204739) (xy 153.552068 -116.178223)
			(xy 153.574242 -116.167408) (xy 153.584402 -116.162582) (xy 153.598626 -116.145818) (xy 153.625042 -116.049044)
			(xy 153.621486 -116.027708) (xy 153.615136 -116.018564) (xy 153.615136 -116.01831) (xy 153.599564 -115.994468)
			(xy 153.57491 -115.943136) (xy 153.558147 -115.888714) (xy 153.549646 -115.832406) (xy 153.549096 -115.803934)
			(xy 153.54963 -115.775041) (xy 153.558312 -115.717911) (xy 153.575514 -115.662745) (xy 153.600841 -115.610805)
			(xy 153.633714 -115.56328) (xy 153.67338 -115.521259) (xy 153.718932 -115.485702) (xy 153.769326 -115.457425)
			(xy 153.82341 -115.437073) (xy 153.879944 -115.425113) (xy 153.90876 -115.422934) (xy 153.919682 -115.422426)
			(xy 153.938986 -115.412266) (xy 153.999692 -115.335304) (xy 154.005026 -115.314222) (xy 154.002994 -115.303554)
			(xy 154.000151 -115.286807) (xy 153.997096 -115.252975) (xy 153.996898 -115.23599) (xy 153.996898 -115.235228)
			(xy 153.997384 -115.207977) (xy 154.00514 -115.154029) (xy 154.020495 -115.101734) (xy 154.043137 -115.052157)
			(xy 154.072603 -115.006307) (xy 154.108294 -114.965116) (xy 154.149485 -114.929425) (xy 154.195335 -114.899959)
			(xy 154.244912 -114.877317) (xy 154.297207 -114.861962) (xy 154.351155 -114.854206) (xy 154.405657 -114.854206)
			(xy 154.459605 -114.861962) (xy 154.5119 -114.877317) (xy 154.561477 -114.899959) (xy 154.607327 -114.929425)
			(xy 154.648518 -114.965116) (xy 154.684209 -115.006307) (xy 154.713675 -115.052157) (xy 154.736317 -115.101734)
			(xy 154.751672 -115.154029) (xy 154.759428 -115.207977) (xy 154.759914 -115.235228) (xy 154.759429 -115.264123)
			(xy 154.750738 -115.321254) (xy 154.733528 -115.37642) (xy 154.708194 -115.42836) (xy 154.675315 -115.475884)
			(xy 154.635644 -115.517904) (xy 154.590088 -115.55346) (xy 154.539691 -115.581737) (xy 154.485604 -115.602088)
			(xy 154.429067 -115.614049) (xy 154.40025 -115.616228) (xy 154.389328 -115.616736) (xy 154.370024 -115.626896)
			(xy 154.309318 -115.703858) (xy 154.303984 -115.72494) (xy 154.306016 -115.735608) (xy 154.306494 -115.738418)
			(xy 159.312604 -115.738418) (xy 159.312604 -115.651518) (xy 159.320622 -115.564989) (xy 159.33659 -115.479569)
			(xy 159.360371 -115.395987) (xy 159.391763 -115.314955) (xy 159.430497 -115.237166) (xy 159.476244 -115.163282)
			(xy 159.528613 -115.093935) (xy 159.587157 -115.029715) (xy 159.651377 -114.971171) (xy 159.720724 -114.918802)
			(xy 159.794608 -114.873055) (xy 159.872397 -114.834321) (xy 159.953429 -114.802929) (xy 160.037011 -114.779148)
			(xy 160.122431 -114.76318) (xy 160.20896 -114.755162) (xy 160.29586 -114.755162) (xy 160.382389 -114.76318)
			(xy 160.467809 -114.779148) (xy 160.551391 -114.802929) (xy 160.632423 -114.834321) (xy 160.710212 -114.873055)
			(xy 160.784096 -114.918802) (xy 160.853443 -114.971171) (xy 160.917663 -115.029715) (xy 160.976207 -115.093935)
			(xy 161.028576 -115.163282) (xy 161.074323 -115.237166) (xy 161.113057 -115.314955) (xy 161.144449 -115.395987)
			(xy 161.16823 -115.479569) (xy 161.184198 -115.564989) (xy 161.192216 -115.651518) (xy 161.192718 -115.694968)
			(xy 161.192216 -115.738418) (xy 161.192213 -115.738451) (xy 162.575462 -115.738451) (xy 162.575462 -115.651549)
			(xy 162.58348 -115.565017) (xy 162.599448 -115.479595) (xy 162.62323 -115.39601) (xy 162.654623 -115.314976)
			(xy 162.693358 -115.237184) (xy 162.739106 -115.163298) (xy 162.791477 -115.093948) (xy 162.850022 -115.029726)
			(xy 162.914244 -114.97118) (xy 162.983593 -114.91881) (xy 163.057479 -114.873061) (xy 163.13527 -114.834325)
			(xy 163.216304 -114.802932) (xy 163.299889 -114.77915) (xy 163.385311 -114.763181) (xy 163.471843 -114.755162)
			(xy 163.515294 -114.75466) (xy 165.369494 -114.75466) (xy 165.412943 -114.75521) (xy 165.499471 -114.763228)
			(xy 165.58489 -114.779195) (xy 165.668472 -114.802975) (xy 165.749502 -114.834366) (xy 165.827291 -114.8731)
			(xy 165.901174 -114.918846) (xy 165.97052 -114.971213) (xy 166.034739 -115.029756) (xy 166.093283 -115.093975)
			(xy 166.145651 -115.163321) (xy 166.191397 -115.237204) (xy 166.230131 -115.314992) (xy 166.261523 -115.396023)
			(xy 166.285304 -115.479604) (xy 166.301272 -115.565023) (xy 166.30929 -115.651551) (xy 166.30929 -115.738418)
			(xy 166.682414 -115.738418) (xy 166.682414 -115.651518) (xy 166.690432 -115.564989) (xy 166.7064 -115.479569)
			(xy 166.730181 -115.395987) (xy 166.761573 -115.314955) (xy 166.800307 -115.237166) (xy 166.846054 -115.163282)
			(xy 166.898423 -115.093935) (xy 166.956967 -115.029715) (xy 167.021187 -114.971171) (xy 167.090534 -114.918802)
			(xy 167.164418 -114.873055) (xy 167.242207 -114.834321) (xy 167.323239 -114.802929) (xy 167.406821 -114.779148)
			(xy 167.492241 -114.76318) (xy 167.57877 -114.755162) (xy 167.66567 -114.755162) (xy 167.752199 -114.76318)
			(xy 167.837619 -114.779148) (xy 167.921201 -114.802929) (xy 168.002233 -114.834321) (xy 168.080022 -114.873055)
			(xy 168.153906 -114.918802) (xy 168.223253 -114.971171) (xy 168.287473 -115.029715) (xy 168.346017 -115.093935)
			(xy 168.398386 -115.163282) (xy 168.444133 -115.237166) (xy 168.482867 -115.314955) (xy 168.514259 -115.395987)
			(xy 168.53804 -115.479569) (xy 168.554008 -115.564989) (xy 168.562026 -115.651518) (xy 168.562528 -115.694968)
			(xy 168.562026 -115.738418) (xy 168.554543 -115.819174) (xy 171.947076 -115.819174) (xy 171.951147 -115.763552)
			(xy 171.963273 -115.709115) (xy 171.983196 -115.657024) (xy 172.010492 -115.608389) (xy 172.044578 -115.564246)
			(xy 172.084727 -115.525537) (xy 172.130085 -115.493086) (xy 172.179685 -115.467585) (xy 172.232469 -115.449578)
			(xy 172.287312 -115.439448) (xy 172.343046 -115.437411) (xy 172.398483 -115.443511) (xy 172.45244 -115.457617)
			(xy 172.503769 -115.479429) (xy 172.551375 -115.508483) (xy 172.594243 -115.544158) (xy 172.63146 -115.585695)
			(xy 172.662233 -115.632208) (xy 172.685905 -115.682705) (xy 172.701973 -115.736112) (xy 172.710093 -115.791288)
			(xy 172.710602 -115.819174) (xy 172.710093 -115.84706) (xy 172.701973 -115.902236) (xy 172.685905 -115.955643)
			(xy 172.662233 -116.00614) (xy 172.63146 -116.052653) (xy 172.594243 -116.09419) (xy 172.551375 -116.129865)
			(xy 172.503769 -116.158919) (xy 172.45244 -116.180731) (xy 172.398483 -116.194837) (xy 172.343046 -116.200937)
			(xy 172.287312 -116.1989) (xy 172.232469 -116.18877) (xy 172.179685 -116.170763) (xy 172.130085 -116.145262)
			(xy 172.084727 -116.112811) (xy 172.044578 -116.074102) (xy 172.010492 -116.029959) (xy 171.983196 -115.981324)
			(xy 171.963273 -115.929233) (xy 171.951147 -115.874796) (xy 171.947076 -115.819174) (xy 168.554543 -115.819174)
			(xy 168.554008 -115.824947) (xy 168.53804 -115.910367) (xy 168.514259 -115.993949) (xy 168.482867 -116.074981)
			(xy 168.444133 -116.15277) (xy 168.398386 -116.226654) (xy 168.346017 -116.296001) (xy 168.287473 -116.360221)
			(xy 168.223253 -116.418765) (xy 168.153906 -116.471134) (xy 168.080022 -116.516881) (xy 168.002233 -116.555615)
			(xy 167.921201 -116.587007) (xy 167.837619 -116.610788) (xy 167.752199 -116.626756) (xy 167.66567 -116.634774)
			(xy 167.57877 -116.634774) (xy 167.492241 -116.626756) (xy 167.406821 -116.610788) (xy 167.323239 -116.587007)
			(xy 167.242207 -116.555615) (xy 167.164418 -116.516881) (xy 167.090534 -116.471134) (xy 167.021187 -116.418765)
			(xy 166.956967 -116.360221) (xy 166.898423 -116.296001) (xy 166.846054 -116.226654) (xy 166.800307 -116.15277)
			(xy 166.761573 -116.074981) (xy 166.730181 -115.993949) (xy 166.7064 -115.910367) (xy 166.690432 -115.824947)
			(xy 166.682414 -115.738418) (xy 166.30929 -115.738418) (xy 166.30929 -115.738449) (xy 166.301272 -115.824977)
			(xy 166.285304 -115.910396) (xy 166.261523 -115.993977) (xy 166.230131 -116.075008) (xy 166.191397 -116.152796)
			(xy 166.145651 -116.226679) (xy 166.093283 -116.296025) (xy 166.034739 -116.360244) (xy 165.97052 -116.418787)
			(xy 165.901174 -116.471154) (xy 165.827291 -116.5169) (xy 165.749502 -116.555634) (xy 165.668472 -116.587025)
			(xy 165.58489 -116.610805) (xy 165.499471 -116.626772) (xy 165.412943 -116.63479) (xy 165.369494 -116.635276)
			(xy 163.515294 -116.635276) (xy 163.471843 -116.634838) (xy 163.385311 -116.626819) (xy 163.299889 -116.61085)
			(xy 163.216304 -116.587068) (xy 163.13527 -116.555675) (xy 163.057479 -116.516939) (xy 162.983593 -116.47119)
			(xy 162.914244 -116.41882) (xy 162.850022 -116.360274) (xy 162.791477 -116.296052) (xy 162.739106 -116.226702)
			(xy 162.693358 -116.152816) (xy 162.654623 -116.075024) (xy 162.62323 -115.99399) (xy 162.599448 -115.910405)
			(xy 162.58348 -115.824983) (xy 162.575462 -115.738451) (xy 161.192213 -115.738451) (xy 161.184198 -115.824947)
			(xy 161.16823 -115.910367) (xy 161.144449 -115.993949) (xy 161.113057 -116.074981) (xy 161.074323 -116.15277)
			(xy 161.028576 -116.226654) (xy 160.976207 -116.296001) (xy 160.917663 -116.360221) (xy 160.853443 -116.418765)
			(xy 160.784096 -116.471134) (xy 160.710212 -116.516881) (xy 160.632423 -116.555615) (xy 160.551391 -116.587007)
			(xy 160.467809 -116.610788) (xy 160.382389 -116.626756) (xy 160.29586 -116.634774) (xy 160.20896 -116.634774)
			(xy 160.122431 -116.626756) (xy 160.037011 -116.610788) (xy 159.953429 -116.587007) (xy 159.872397 -116.555615)
			(xy 159.794608 -116.516881) (xy 159.720724 -116.471134) (xy 159.651377 -116.418765) (xy 159.587157 -116.360221)
			(xy 159.528613 -116.296001) (xy 159.476244 -116.226654) (xy 159.430497 -116.15277) (xy 159.391763 -116.074981)
			(xy 159.360371 -115.993949) (xy 159.33659 -115.910367) (xy 159.320622 -115.824947) (xy 159.312604 -115.738418)
			(xy 154.306494 -115.738418) (xy 154.308867 -115.752353) (xy 154.311917 -115.786187) (xy 154.312112 -115.803172)
			(xy 154.312112 -115.803934) (xy 154.31163 -115.830916) (xy 154.304008 -115.884341) (xy 154.288936 -115.936158)
			(xy 154.266714 -115.985336) (xy 154.237786 -116.030892) (xy 154.202728 -116.071918) (xy 154.162239 -116.107596)
			(xy 154.117128 -116.137214) (xy 154.09291 -116.14912) (xy 154.08275 -116.153946) (xy 154.068526 -116.17071)
			(xy 154.04211 -116.267484) (xy 154.045666 -116.28882) (xy 154.052016 -116.297964) (xy 154.052016 -116.298218)
			(xy 154.067595 -116.322057) (xy 154.092249 -116.373389) (xy 154.10901 -116.427813) (xy 154.117508 -116.484121)
			(xy 154.118056 -116.512594) (xy 154.117517 -116.539843) (xy 154.109762 -116.593786) (xy 154.09441 -116.646077)
			(xy 154.071773 -116.695651) (xy 154.042312 -116.741499) (xy 154.006626 -116.782688) (xy 153.965442 -116.81838)
			(xy 153.919599 -116.847848) (xy 153.870028 -116.870492) (xy 153.817739 -116.885851) (xy 153.763797 -116.893613)
			(xy 153.736548 -116.894102) (xy 153.710233 -116.893669) (xy 153.658103 -116.886427) (xy 153.60746 -116.872101)
			(xy 153.559261 -116.850962) (xy 153.514418 -116.82341) (xy 153.47378 -116.789966) (xy 153.455624 -116.770912)
			(xy 153.448094 -116.763521) (xy 153.42882 -116.75499) (xy 153.418286 -116.754402) (xy 153.34361 -116.754402)
			(xy 153.333059 -116.754923) (xy 153.313764 -116.763464) (xy 153.306272 -116.770912) (xy 153.288125 -116.789976)
			(xy 153.247493 -116.823432) (xy 153.202651 -116.85099) (xy 153.154449 -116.872127) (xy 153.1038 -116.886442)
			(xy 153.051665 -116.893665) (xy 153.025348 -116.894102) (xy 152.998092 -116.893654) (xy 152.944136 -116.885902)
			(xy 152.891831 -116.87055) (xy 152.842244 -116.84791) (xy 152.796384 -116.818443) (xy 152.755185 -116.782749)
			(xy 152.719486 -116.741554) (xy 152.690013 -116.695698) (xy 152.667367 -116.646114) (xy 152.652008 -116.593811)
			(xy 152.64425 -116.539855) (xy 140.456412 -116.539855) (xy 140.456412 -117.7544) (xy 153.187906 -117.7544)
			(xy 153.191977 -117.698778) (xy 153.204103 -117.644341) (xy 153.224026 -117.59225) (xy 153.251322 -117.543615)
			(xy 153.285408 -117.499472) (xy 153.325557 -117.460763) (xy 153.370915 -117.428312) (xy 153.420515 -117.402811)
			(xy 153.473299 -117.384804) (xy 153.528142 -117.374674) (xy 153.583876 -117.372637) (xy 153.639313 -117.378737)
			(xy 153.69327 -117.392843) (xy 153.744599 -117.414655) (xy 153.792205 -117.443709) (xy 153.835073 -117.479384)
			(xy 153.87229 -117.520921) (xy 153.903063 -117.567434) (xy 153.926735 -117.617931) (xy 153.942803 -117.671338)
			(xy 153.950923 -117.726514) (xy 153.951432 -117.7544) (xy 153.950923 -117.782286) (xy 153.942803 -117.837462)
			(xy 153.926735 -117.890869) (xy 153.903063 -117.941366) (xy 153.87229 -117.987879) (xy 153.835073 -118.029416)
			(xy 153.792205 -118.065091) (xy 153.744599 -118.094145) (xy 153.69327 -118.115957) (xy 153.639313 -118.130063)
			(xy 153.583876 -118.136163) (xy 153.528142 -118.134126) (xy 153.473299 -118.123996) (xy 153.420515 -118.105989)
			(xy 153.370915 -118.080488) (xy 153.325557 -118.048037) (xy 153.285408 -118.009328) (xy 153.251322 -117.965185)
			(xy 153.224026 -117.91655) (xy 153.204103 -117.864459) (xy 153.191977 -117.810022) (xy 153.187906 -117.7544)
			(xy 140.456412 -117.7544) (xy 140.456412 -119.055348) (xy 150.191231 -119.055348) (xy 150.191231 -118.998052)
			(xy 150.199384 -118.941339) (xy 150.215526 -118.886363) (xy 150.239327 -118.834244) (xy 150.270302 -118.786043)
			(xy 150.307822 -118.74274) (xy 150.351122 -118.705218) (xy 150.399322 -118.674239) (xy 150.451439 -118.650435)
			(xy 150.506413 -118.63429) (xy 150.563126 -118.626132) (xy 150.591774 -118.62562) (xy 150.619153 -118.626139)
			(xy 150.673399 -118.633602) (xy 150.726125 -118.648377) (xy 150.77635 -118.670192) (xy 150.823138 -118.698638)
			(xy 150.86562 -118.733188) (xy 150.903004 -118.773198) (xy 150.91918 -118.795292) (xy 150.924752 -118.802544)
			(xy 150.939854 -118.812833) (xy 150.948644 -118.815358) (xy 150.978616 -118.822724) (xy 150.987565 -118.824481)
			(xy 151.005656 -118.82226) (xy 151.013922 -118.818406) (xy 151.038519 -118.806011) (xy 151.090046 -118.786543)
			(xy 151.143536 -118.773396) (xy 151.198217 -118.76676) (xy 151.225758 -118.766336) (xy 151.253299 -118.766758)
			(xy 151.307979 -118.773396) (xy 151.361469 -118.786545) (xy 151.412995 -118.806014) (xy 151.437594 -118.818406)
			(xy 151.445854 -118.822281) (xy 151.46395 -118.824497) (xy 151.4729 -118.822724) (xy 151.502872 -118.815358)
			(xy 151.511648 -118.812799) (xy 151.526752 -118.802528) (xy 151.532336 -118.795292) (xy 151.548477 -118.773166)
			(xy 151.585854 -118.733136) (xy 151.628336 -118.69857) (xy 151.675129 -118.670112) (xy 151.725363 -118.648292)
			(xy 151.7781 -118.633518) (xy 151.832358 -118.626064) (xy 151.859742 -118.62562) (xy 151.888387 -118.626162)
			(xy 151.945094 -118.634321) (xy 152.000063 -118.650466) (xy 152.052174 -118.674269) (xy 152.100368 -118.705246)
			(xy 152.143663 -118.742766) (xy 152.154182 -118.754906) (xy 160.769552 -118.754906) (xy 160.773623 -118.699284)
			(xy 160.785749 -118.644847) (xy 160.805672 -118.592756) (xy 160.832968 -118.544121) (xy 160.867054 -118.499978)
			(xy 160.907203 -118.461269) (xy 160.952561 -118.428818) (xy 161.002161 -118.403317) (xy 161.054945 -118.38531)
			(xy 161.109788 -118.37518) (xy 161.165522 -118.373143) (xy 161.220959 -118.379243) (xy 161.274916 -118.393349)
			(xy 161.326245 -118.415161) (xy 161.373851 -118.444215) (xy 161.416719 -118.47989) (xy 161.453936 -118.521427)
			(xy 161.484709 -118.56794) (xy 161.508381 -118.618437) (xy 161.524449 -118.671844) (xy 161.532569 -118.72702)
			(xy 161.533078 -118.754906) (xy 162.750752 -118.754906) (xy 162.754823 -118.699284) (xy 162.766949 -118.644847)
			(xy 162.786872 -118.592756) (xy 162.814168 -118.544121) (xy 162.848254 -118.499978) (xy 162.888403 -118.461269)
			(xy 162.933761 -118.428818) (xy 162.983361 -118.403317) (xy 163.036145 -118.38531) (xy 163.090988 -118.37518)
			(xy 163.146722 -118.373143) (xy 163.202159 -118.379243) (xy 163.256116 -118.393349) (xy 163.307445 -118.415161)
			(xy 163.355051 -118.444215) (xy 163.397919 -118.47989) (xy 163.435136 -118.521427) (xy 163.465909 -118.56794)
			(xy 163.489581 -118.618437) (xy 163.505649 -118.671844) (xy 163.513769 -118.72702) (xy 163.514278 -118.754906)
			(xy 165.369746 -118.754906) (xy 165.373817 -118.699284) (xy 165.385943 -118.644847) (xy 165.405866 -118.592756)
			(xy 165.433162 -118.544121) (xy 165.467248 -118.499978) (xy 165.507397 -118.461269) (xy 165.552755 -118.428818)
			(xy 165.602355 -118.403317) (xy 165.655139 -118.38531) (xy 165.709982 -118.37518) (xy 165.765716 -118.373143)
			(xy 165.821153 -118.379243) (xy 165.87511 -118.393349) (xy 165.926439 -118.415161) (xy 165.974045 -118.444215)
			(xy 166.016913 -118.47989) (xy 166.05413 -118.521427) (xy 166.084903 -118.56794) (xy 166.108575 -118.618437)
			(xy 166.124643 -118.671844) (xy 166.132763 -118.72702) (xy 166.133272 -118.754906) (xy 167.350946 -118.754906)
			(xy 167.355017 -118.699284) (xy 167.367143 -118.644847) (xy 167.387066 -118.592756) (xy 167.414362 -118.544121)
			(xy 167.448448 -118.499978) (xy 167.488597 -118.461269) (xy 167.533955 -118.428818) (xy 167.583555 -118.403317)
			(xy 167.636339 -118.38531) (xy 167.691182 -118.37518) (xy 167.746916 -118.373143) (xy 167.802353 -118.379243)
			(xy 167.85631 -118.393349) (xy 167.907639 -118.415161) (xy 167.955245 -118.444215) (xy 167.998113 -118.47989)
			(xy 168.03533 -118.521427) (xy 168.066103 -118.56794) (xy 168.089775 -118.618437) (xy 168.105843 -118.671844)
			(xy 168.113963 -118.72702) (xy 168.114472 -118.754906) (xy 168.113963 -118.782792) (xy 168.105843 -118.837968)
			(xy 168.089775 -118.891375) (xy 168.066103 -118.941872) (xy 168.03533 -118.988385) (xy 167.998113 -119.029922)
			(xy 167.955245 -119.065597) (xy 167.907639 -119.094651) (xy 167.85631 -119.116463) (xy 167.802353 -119.130569)
			(xy 167.746916 -119.136669) (xy 167.691182 -119.134632) (xy 167.636339 -119.124502) (xy 167.583555 -119.106495)
			(xy 167.533955 -119.080994) (xy 167.488597 -119.048543) (xy 167.448448 -119.009834) (xy 167.414362 -118.965691)
			(xy 167.387066 -118.917056) (xy 167.367143 -118.864965) (xy 167.355017 -118.810528) (xy 167.350946 -118.754906)
			(xy 166.133272 -118.754906) (xy 166.132763 -118.782792) (xy 166.124643 -118.837968) (xy 166.108575 -118.891375)
			(xy 166.084903 -118.941872) (xy 166.05413 -118.988385) (xy 166.016913 -119.029922) (xy 165.974045 -119.065597)
			(xy 165.926439 -119.094651) (xy 165.87511 -119.116463) (xy 165.821153 -119.130569) (xy 165.765716 -119.136669)
			(xy 165.709982 -119.134632) (xy 165.655139 -119.124502) (xy 165.602355 -119.106495) (xy 165.552755 -119.080994)
			(xy 165.507397 -119.048543) (xy 165.467248 -119.009834) (xy 165.433162 -118.965691) (xy 165.405866 -118.917056)
			(xy 165.385943 -118.864965) (xy 165.373817 -118.810528) (xy 165.369746 -118.754906) (xy 163.514278 -118.754906)
			(xy 163.513769 -118.782792) (xy 163.505649 -118.837968) (xy 163.489581 -118.891375) (xy 163.465909 -118.941872)
			(xy 163.435136 -118.988385) (xy 163.397919 -119.029922) (xy 163.355051 -119.065597) (xy 163.307445 -119.094651)
			(xy 163.256116 -119.116463) (xy 163.202159 -119.130569) (xy 163.146722 -119.136669) (xy 163.090988 -119.134632)
			(xy 163.036145 -119.124502) (xy 162.983361 -119.106495) (xy 162.933761 -119.080994) (xy 162.888403 -119.048543)
			(xy 162.848254 -119.009834) (xy 162.814168 -118.965691) (xy 162.786872 -118.917056) (xy 162.766949 -118.864965)
			(xy 162.754823 -118.810528) (xy 162.750752 -118.754906) (xy 161.533078 -118.754906) (xy 161.532569 -118.782792)
			(xy 161.524449 -118.837968) (xy 161.508381 -118.891375) (xy 161.484709 -118.941872) (xy 161.453936 -118.988385)
			(xy 161.416719 -119.029922) (xy 161.373851 -119.065597) (xy 161.326245 -119.094651) (xy 161.274916 -119.116463)
			(xy 161.220959 -119.130569) (xy 161.165522 -119.136669) (xy 161.109788 -119.134632) (xy 161.054945 -119.124502)
			(xy 161.002161 -119.106495) (xy 160.952561 -119.080994) (xy 160.907203 -119.048543) (xy 160.867054 -119.009834)
			(xy 160.832968 -118.965691) (xy 160.805672 -118.917056) (xy 160.785749 -118.864965) (xy 160.773623 -118.810528)
			(xy 160.769552 -118.754906) (xy 152.154182 -118.754906) (xy 152.181179 -118.786065) (xy 152.212151 -118.834263)
			(xy 152.235949 -118.886377) (xy 152.252088 -118.941347) (xy 152.260241 -118.998055) (xy 152.260241 -119.055345)
			(xy 152.252088 -119.112053) (xy 152.235949 -119.167023) (xy 152.212151 -119.219137) (xy 152.181179 -119.267335)
			(xy 152.143663 -119.310634) (xy 152.100368 -119.348154) (xy 152.052174 -119.379131) (xy 152.000063 -119.402934)
			(xy 151.945094 -119.419079) (xy 151.888387 -119.427238) (xy 151.859742 -119.427752) (xy 151.844824 -119.427584)
			(xy 151.815075 -119.425294) (xy 151.800306 -119.42318) (xy 151.78913 -119.421402) (xy 151.768048 -119.427498)
			(xy 151.701246 -119.485156) (xy 151.693291 -119.492759) (xy 151.684202 -119.512771) (xy 151.68372 -119.523764)
			(xy 151.68372 -119.788432) (xy 151.684201 -119.799424) (xy 151.693293 -119.819436) (xy 151.701246 -119.82704)
			(xy 151.768048 -119.884698) (xy 151.78913 -119.890794) (xy 151.800306 -119.889016) (xy 151.815075 -119.886905)
			(xy 151.844824 -119.884618) (xy 151.859742 -119.884444) (xy 151.888389 -119.884938) (xy 151.945099 -119.893097)
			(xy 152.000071 -119.909243) (xy 152.052186 -119.933048) (xy 152.100383 -119.964027) (xy 152.143681 -120.001549)
			(xy 152.181198 -120.044851) (xy 152.206412 -120.084088) (xy 165.050214 -120.084088) (xy 165.054285 -120.028466)
			(xy 165.066411 -119.974029) (xy 165.086334 -119.921938) (xy 165.11363 -119.873303) (xy 165.147716 -119.82916)
			(xy 165.187865 -119.790451) (xy 165.233223 -119.758) (xy 165.282823 -119.732499) (xy 165.335607 -119.714492)
			(xy 165.39045 -119.704362) (xy 165.446184 -119.702325) (xy 165.501621 -119.708425) (xy 165.555578 -119.722531)
			(xy 165.606907 -119.744343) (xy 165.654513 -119.773397) (xy 165.697381 -119.809072) (xy 165.734598 -119.850609)
			(xy 165.765371 -119.897122) (xy 165.789043 -119.947619) (xy 165.805111 -120.001026) (xy 165.813231 -120.056202)
			(xy 165.81374 -120.084088) (xy 165.813231 -120.111974) (xy 165.805111 -120.16715) (xy 165.789043 -120.220557)
			(xy 165.765371 -120.271054) (xy 165.734598 -120.317567) (xy 165.697381 -120.359104) (xy 165.654513 -120.394779)
			(xy 165.606907 -120.423833) (xy 165.555578 -120.445645) (xy 165.501621 -120.459751) (xy 165.446184 -120.465851)
			(xy 165.39045 -120.463814) (xy 165.335607 -120.453684) (xy 165.282823 -120.435677) (xy 165.233223 -120.410176)
			(xy 165.187865 -120.377725) (xy 165.147716 -120.339016) (xy 165.11363 -120.294873) (xy 165.086334 -120.246238)
			(xy 165.066411 -120.194147) (xy 165.054285 -120.13971) (xy 165.050214 -120.084088) (xy 152.206412 -120.084088)
			(xy 152.212172 -120.093051) (xy 152.235972 -120.145168) (xy 152.252112 -120.200142) (xy 152.260265 -120.256853)
			(xy 152.260265 -120.314147) (xy 152.252112 -120.370858) (xy 152.235972 -120.425832) (xy 152.212172 -120.477949)
			(xy 152.181198 -120.526149) (xy 152.143681 -120.569451) (xy 152.100383 -120.606973) (xy 152.052186 -120.637952)
			(xy 152.000071 -120.661757) (xy 151.945099 -120.677903) (xy 151.888389 -120.686062) (xy 151.859742 -120.686576)
			(xy 151.832361 -120.686121) (xy 151.778112 -120.678648) (xy 151.725384 -120.663861) (xy 151.675159 -120.642036)
			(xy 151.628372 -120.613579) (xy 151.585892 -120.57902) (xy 151.548511 -120.539002) (xy 151.532336 -120.516904)
			(xy 151.526759 -120.509656) (xy 151.51166 -120.499365) (xy 151.502872 -120.496838) (xy 151.4729 -120.489472)
			(xy 151.46395 -120.487723) (xy 151.445861 -120.489939) (xy 151.437594 -120.49379) (xy 151.412994 -120.506179)
			(xy 151.361468 -120.525648) (xy 151.307979 -120.538797) (xy 151.253299 -120.545435) (xy 151.225758 -120.54586)
			(xy 151.198217 -120.545432) (xy 151.143537 -120.538796) (xy 151.090048 -120.525649) (xy 151.038521 -120.506181)
			(xy 151.013922 -120.49379) (xy 151.005659 -120.489923) (xy 150.987565 -120.487702) (xy 150.978616 -120.489472)
			(xy 150.948644 -120.496838) (xy 150.939857 -120.499365) (xy 150.924759 -120.509659) (xy 150.91918 -120.516904)
			(xy 150.903028 -120.539021) (xy 150.865653 -120.579052) (xy 150.823173 -120.613619) (xy 150.776382 -120.642078)
			(xy 150.72615 -120.663899) (xy 150.673414 -120.678675) (xy 150.619157 -120.686131) (xy 150.591774 -120.686576)
			(xy 150.563128 -120.686043) (xy 150.506419 -120.677886) (xy 150.451448 -120.661742) (xy 150.399333 -120.637939)
			(xy 150.351137 -120.606963) (xy 150.307839 -120.569442) (xy 150.270322 -120.526142) (xy 150.239348 -120.477944)
			(xy 150.215549 -120.425828) (xy 150.199408 -120.370856) (xy 150.191255 -120.314146) (xy 150.191255 -120.256854)
			(xy 150.199408 -120.200144) (xy 150.215549 -120.145172) (xy 150.239348 -120.093056) (xy 150.270322 -120.044858)
			(xy 150.307839 -120.001558) (xy 150.351137 -119.964037) (xy 150.399333 -119.933061) (xy 150.451448 -119.909258)
			(xy 150.506419 -119.893114) (xy 150.563128 -119.884957) (xy 150.591774 -119.884444) (xy 150.606692 -119.88461)
			(xy 150.636441 -119.886901) (xy 150.65121 -119.889016) (xy 150.662386 -119.890794) (xy 150.683468 -119.884698)
			(xy 150.75027 -119.82704) (xy 150.75823 -119.819442) (xy 150.767316 -119.799426) (xy 150.767796 -119.788432)
			(xy 150.767796 -119.523764) (xy 150.767312 -119.512773) (xy 150.758222 -119.49276) (xy 150.75027 -119.485156)
			(xy 150.683468 -119.427498) (xy 150.662386 -119.421402) (xy 150.65121 -119.42318) (xy 150.636441 -119.42529)
			(xy 150.606692 -119.427577) (xy 150.591774 -119.427752) (xy 150.563126 -119.427268) (xy 150.506413 -119.41911)
			(xy 150.451439 -119.402965) (xy 150.399322 -119.379161) (xy 150.351122 -119.348182) (xy 150.307822 -119.31066)
			(xy 150.270302 -119.267357) (xy 150.239327 -119.219156) (xy 150.215526 -119.167037) (xy 150.199384 -119.112061)
			(xy 150.191231 -119.055348) (xy 140.456412 -119.055348) (xy 140.456412 -122.12065) (xy 152.833303 -122.12065)
			(xy 152.833303 -122.06335) (xy 152.841457 -122.006632) (xy 152.8576 -121.951652) (xy 152.881403 -121.899529)
			(xy 152.912382 -121.851324) (xy 152.949905 -121.808018) (xy 152.993209 -121.770493) (xy 153.041413 -121.739512)
			(xy 153.093535 -121.715707) (xy 153.148514 -121.699561) (xy 153.205232 -121.691404) (xy 153.233882 -121.690892)
			(xy 153.2488 -121.691058) (xy 153.278549 -121.693349) (xy 153.293318 -121.695464) (xy 153.304494 -121.697242)
			(xy 153.325576 -121.691146) (xy 153.392378 -121.633488) (xy 153.400362 -121.625912) (xy 153.409435 -121.605879)
			(xy 153.409904 -121.59488) (xy 153.409904 -121.330212) (xy 153.40939 -121.319224) (xy 153.400321 -121.299212)
			(xy 153.392378 -121.291604) (xy 153.325576 -121.233946) (xy 153.304494 -121.22785) (xy 153.293318 -121.229628)
			(xy 153.278549 -121.231737) (xy 153.2488 -121.234025) (xy 153.233882 -121.2342) (xy 153.205237 -121.23362)
			(xy 153.14853 -121.225464) (xy 153.093562 -121.209322) (xy 153.04145 -121.185521) (xy 152.993255 -121.154546)
			(xy 152.949959 -121.117028) (xy 152.912443 -121.07373) (xy 152.881471 -121.025535) (xy 152.857672 -120.973421)
			(xy 152.841532 -120.918452) (xy 152.833379 -120.861745) (xy 152.833379 -120.804455) (xy 152.841532 -120.747748)
			(xy 152.857672 -120.692779) (xy 152.881471 -120.640665) (xy 152.912443 -120.59247) (xy 152.949959 -120.549172)
			(xy 152.993255 -120.511654) (xy 153.04145 -120.480679) (xy 153.093562 -120.456878) (xy 153.14853 -120.440736)
			(xy 153.205237 -120.43258) (xy 153.233882 -120.432068) (xy 153.261262 -120.432561) (xy 153.31551 -120.440026)
			(xy 153.368238 -120.454804) (xy 153.418463 -120.476622) (xy 153.465251 -120.505074) (xy 153.507732 -120.539628)
			(xy 153.545113 -120.579644) (xy 153.561288 -120.60174) (xy 153.566868 -120.608985) (xy 153.581964 -120.619279)
			(xy 153.590752 -120.621806) (xy 153.620724 -120.629172) (xy 153.629673 -120.630929) (xy 153.647763 -120.628706)
			(xy 153.65603 -120.624854) (xy 153.680624 -120.612452) (xy 153.732152 -120.592987) (xy 153.785644 -120.579842)
			(xy 153.840325 -120.573208) (xy 153.867866 -120.572784) (xy 153.895407 -120.573198) (xy 153.950088 -120.579837)
			(xy 154.003578 -120.592988) (xy 154.055103 -120.612461) (xy 154.079702 -120.624854) (xy 154.087961 -120.628732)
			(xy 154.106058 -120.630948) (xy 154.115008 -120.629172) (xy 154.14498 -120.621806) (xy 154.153763 -120.619266)
			(xy 154.168864 -120.608983) (xy 154.174444 -120.60174) (xy 154.190594 -120.579621) (xy 154.227968 -120.539589)
			(xy 154.270447 -120.50502) (xy 154.317239 -120.47656) (xy 154.367472 -120.45474) (xy 154.420209 -120.439965)
			(xy 154.474466 -120.432511) (xy 154.50185 -120.432068) (xy 154.530505 -120.432483) (xy 154.587232 -120.440633)
			(xy 154.642221 -120.456773) (xy 154.694354 -120.480576) (xy 154.742568 -120.511556) (xy 154.785882 -120.549082)
			(xy 154.791014 -120.555004) (xy 160.769552 -120.555004) (xy 160.773623 -120.499382) (xy 160.785749 -120.444945)
			(xy 160.805672 -120.392854) (xy 160.832968 -120.344219) (xy 160.867054 -120.300076) (xy 160.907203 -120.261367)
			(xy 160.952561 -120.228916) (xy 161.002161 -120.203415) (xy 161.054945 -120.185408) (xy 161.109788 -120.175278)
			(xy 161.165522 -120.173241) (xy 161.220959 -120.179341) (xy 161.274916 -120.193447) (xy 161.326245 -120.215259)
			(xy 161.373851 -120.244313) (xy 161.416719 -120.279988) (xy 161.453936 -120.321525) (xy 161.484709 -120.368038)
			(xy 161.508381 -120.418535) (xy 161.524449 -120.471942) (xy 161.532569 -120.527118) (xy 161.533078 -120.555004)
			(xy 162.750752 -120.555004) (xy 162.754823 -120.499382) (xy 162.766949 -120.444945) (xy 162.786872 -120.392854)
			(xy 162.814168 -120.344219) (xy 162.848254 -120.300076) (xy 162.888403 -120.261367) (xy 162.933761 -120.228916)
			(xy 162.983361 -120.203415) (xy 163.036145 -120.185408) (xy 163.090988 -120.175278) (xy 163.146722 -120.173241)
			(xy 163.202159 -120.179341) (xy 163.256116 -120.193447) (xy 163.307445 -120.215259) (xy 163.355051 -120.244313)
			(xy 163.397919 -120.279988) (xy 163.435136 -120.321525) (xy 163.465909 -120.368038) (xy 163.489581 -120.418535)
			(xy 163.505649 -120.471942) (xy 163.513769 -120.527118) (xy 163.514278 -120.555004) (xy 163.513769 -120.58289)
			(xy 163.505649 -120.638066) (xy 163.489581 -120.691473) (xy 163.465909 -120.74197) (xy 163.435136 -120.788483)
			(xy 163.397919 -120.83002) (xy 163.355051 -120.865695) (xy 163.307445 -120.894749) (xy 163.256116 -120.916561)
			(xy 163.202159 -120.930667) (xy 163.146722 -120.936767) (xy 163.090988 -120.93473) (xy 163.036145 -120.9246)
			(xy 162.983361 -120.906593) (xy 162.933761 -120.881092) (xy 162.888403 -120.848641) (xy 162.848254 -120.809932)
			(xy 162.814168 -120.765789) (xy 162.786872 -120.717154) (xy 162.766949 -120.665063) (xy 162.754823 -120.610626)
			(xy 162.750752 -120.555004) (xy 161.533078 -120.555004) (xy 161.532569 -120.58289) (xy 161.524449 -120.638066)
			(xy 161.508381 -120.691473) (xy 161.484709 -120.74197) (xy 161.453936 -120.788483) (xy 161.416719 -120.83002)
			(xy 161.373851 -120.865695) (xy 161.326245 -120.894749) (xy 161.274916 -120.916561) (xy 161.220959 -120.930667)
			(xy 161.165522 -120.936767) (xy 161.109788 -120.93473) (xy 161.054945 -120.9246) (xy 161.002161 -120.906593)
			(xy 160.952561 -120.881092) (xy 160.907203 -120.848641) (xy 160.867054 -120.809932) (xy 160.832968 -120.765789)
			(xy 160.805672 -120.717154) (xy 160.785749 -120.665063) (xy 160.773623 -120.610626) (xy 160.769552 -120.555004)
			(xy 154.791014 -120.555004) (xy 154.823414 -120.592392) (xy 154.8544 -120.640602) (xy 154.878209 -120.692732)
			(xy 154.894356 -120.747719) (xy 154.902513 -120.804445) (xy 154.902513 -120.861755) (xy 154.894356 -120.918481)
			(xy 154.878209 -120.973468) (xy 154.8544 -121.025598) (xy 154.823414 -121.073808) (xy 154.785882 -121.117118)
			(xy 154.742568 -121.154644) (xy 154.694354 -121.185624) (xy 154.642221 -121.209427) (xy 154.587232 -121.225567)
			(xy 154.530505 -121.233717) (xy 154.50185 -121.2342) (xy 154.486932 -121.234031) (xy 154.457183 -121.231742)
			(xy 154.442414 -121.229628) (xy 154.431238 -121.22785) (xy 154.410156 -121.233946) (xy 154.343354 -121.291604)
			(xy 154.335378 -121.299188) (xy 154.3263 -121.319215) (xy 154.325828 -121.330212) (xy 154.325828 -121.59488)
			(xy 154.326336 -121.605869) (xy 154.335408 -121.625882) (xy 154.343354 -121.633488) (xy 154.410156 -121.691146)
			(xy 154.431238 -121.697242) (xy 154.442414 -121.695464) (xy 154.457183 -121.693351) (xy 154.486932 -121.691066)
			(xy 154.50185 -121.690892) (xy 154.530499 -121.691459) (xy 154.537161 -121.692416) (xy 165.265352 -121.692416)
			(xy 165.269423 -121.636794) (xy 165.281549 -121.582357) (xy 165.301472 -121.530266) (xy 165.328768 -121.481631)
			(xy 165.362854 -121.437488) (xy 165.403003 -121.398779) (xy 165.448361 -121.366328) (xy 165.497961 -121.340827)
			(xy 165.550745 -121.32282) (xy 165.605588 -121.31269) (xy 165.661322 -121.310653) (xy 165.716759 -121.316753)
			(xy 165.770716 -121.330859) (xy 165.822045 -121.352671) (xy 165.869651 -121.381725) (xy 165.912519 -121.4174)
			(xy 165.949736 -121.458937) (xy 165.980509 -121.50545) (xy 166.004181 -121.555947) (xy 166.020249 -121.609354)
			(xy 166.028369 -121.66453) (xy 166.028878 -121.692416) (xy 166.028369 -121.720302) (xy 166.020249 -121.775478)
			(xy 166.004181 -121.828885) (xy 165.980509 -121.879382) (xy 165.949736 -121.925895) (xy 165.912519 -121.967432)
			(xy 165.869651 -122.003107) (xy 165.822045 -122.032161) (xy 165.770716 -122.053973) (xy 165.716759 -122.068079)
			(xy 165.661322 -122.074179) (xy 165.605588 -122.072142) (xy 165.550745 -122.062012) (xy 165.497961 -122.044005)
			(xy 165.448361 -122.018504) (xy 165.403003 -121.986053) (xy 165.362854 -121.947344) (xy 165.328768 -121.903201)
			(xy 165.301472 -121.854566) (xy 165.281549 -121.802475) (xy 165.269423 -121.748038) (xy 165.265352 -121.692416)
			(xy 154.537161 -121.692416) (xy 154.587216 -121.699607) (xy 154.642195 -121.715744) (xy 154.694318 -121.739542)
			(xy 154.742523 -121.770517) (xy 154.785828 -121.808036) (xy 154.823353 -121.851337) (xy 154.854334 -121.899539)
			(xy 154.878138 -121.951658) (xy 154.894282 -122.006636) (xy 154.902437 -122.063351) (xy 154.902437 -122.120649)
			(xy 154.894282 -122.177365) (xy 154.878138 -122.232342) (xy 154.854334 -122.284461) (xy 154.823353 -122.332663)
			(xy 154.803907 -122.355102) (xy 160.769552 -122.355102) (xy 160.773623 -122.29948) (xy 160.785749 -122.245043)
			(xy 160.805672 -122.192952) (xy 160.832968 -122.144317) (xy 160.867054 -122.100174) (xy 160.907203 -122.061465)
			(xy 160.952561 -122.029014) (xy 161.002161 -122.003513) (xy 161.054945 -121.985506) (xy 161.109788 -121.975376)
			(xy 161.165522 -121.973339) (xy 161.220959 -121.979439) (xy 161.274916 -121.993545) (xy 161.326245 -122.015357)
			(xy 161.373851 -122.044411) (xy 161.416719 -122.080086) (xy 161.453936 -122.121623) (xy 161.459685 -122.130312)
			(xy 162.817046 -122.130312) (xy 162.821117 -122.07469) (xy 162.833243 -122.020253) (xy 162.853166 -121.968162)
			(xy 162.880462 -121.919527) (xy 162.914548 -121.875384) (xy 162.954697 -121.836675) (xy 163.000055 -121.804224)
			(xy 163.049655 -121.778723) (xy 163.102439 -121.760716) (xy 163.157282 -121.750586) (xy 163.213016 -121.748549)
			(xy 163.268453 -121.754649) (xy 163.32241 -121.768755) (xy 163.373739 -121.790567) (xy 163.421345 -121.819621)
			(xy 163.464213 -121.855296) (xy 163.50143 -121.896833) (xy 163.532203 -121.943346) (xy 163.555875 -121.993843)
			(xy 163.571943 -122.04725) (xy 163.580063 -122.102426) (xy 163.580572 -122.130312) (xy 163.580063 -122.158198)
			(xy 163.571943 -122.213374) (xy 163.555875 -122.266781) (xy 163.532203 -122.317278) (xy 163.50143 -122.363791)
			(xy 163.484802 -122.382349) (xy 167.35198 -122.382349) (xy 167.35198 -122.327851) (xy 167.359735 -122.273906)
			(xy 167.375088 -122.221615) (xy 167.397727 -122.17204) (xy 167.42719 -122.126192) (xy 167.462877 -122.085003)
			(xy 167.504063 -122.049311) (xy 167.549908 -122.019844) (xy 167.599481 -121.997201) (xy 167.651771 -121.981843)
			(xy 167.705715 -121.974082) (xy 167.732964 -121.973594) (xy 167.750076 -121.973786) (xy 167.784163 -121.976838)
			(xy 167.801036 -121.97969) (xy 167.812364 -121.98109) (xy 167.834377 -121.975177) (xy 167.843454 -121.96826)
			(xy 167.867838 -121.947178) (xy 167.876259 -121.939194) (xy 167.885391 -121.917888) (xy 167.885364 -121.906284)
			(xy 167.884856 -121.886472) (xy 167.884856 -121.022872) (xy 167.885364 -121.003568) (xy 167.885343 -120.991975)
			(xy 167.876217 -120.970687) (xy 167.867838 -120.962674) (xy 167.843454 -120.941846) (xy 167.834438 -120.934937)
			(xy 167.812555 -120.928984) (xy 167.80129 -120.930416) (xy 167.784356 -120.933297) (xy 167.75014 -120.936348)
			(xy 167.732964 -120.936512) (xy 167.705715 -120.936016) (xy 167.651771 -120.928255) (xy 167.599482 -120.912897)
			(xy 167.549909 -120.890254) (xy 167.504064 -120.860787) (xy 167.462878 -120.825096) (xy 167.427191 -120.783907)
			(xy 167.397729 -120.738059) (xy 167.37509 -120.688485) (xy 167.359737 -120.636193) (xy 167.351982 -120.582249)
			(xy 167.351982 -120.527751) (xy 167.359737 -120.473807) (xy 167.37509 -120.421515) (xy 167.397729 -120.371941)
			(xy 167.427191 -120.326093) (xy 167.462878 -120.284904) (xy 167.504064 -120.249213) (xy 167.549909 -120.219746)
			(xy 167.599482 -120.197103) (xy 167.651771 -120.181745) (xy 167.705715 -120.173984) (xy 167.732964 -120.173496)
			(xy 167.759941 -120.173958) (xy 167.813358 -120.181546) (xy 167.865171 -120.196591) (xy 167.914346 -120.218791)
			(xy 167.959899 -120.247703) (xy 168.00092 -120.282749) (xy 168.03659 -120.323229) (xy 168.066196 -120.368334)
			(xy 168.089146 -120.417162) (xy 168.104982 -120.46874) (xy 168.109646 -120.495314) (xy 168.109646 -120.495568)
			(xy 168.111826 -120.505837) (xy 168.123261 -120.523417) (xy 168.131744 -120.529604) (xy 168.203118 -120.577102)
			(xy 168.223692 -120.580658) (xy 168.234106 -120.578118) (xy 168.260871 -120.572036) (xy 168.315373 -120.56554)
			(xy 168.342818 -120.565164) (xy 168.36616 -120.565437) (xy 168.412606 -120.570146) (xy 168.435528 -120.574562)
			(xy 168.435782 -120.574562) (xy 168.445896 -120.576153) (xy 168.465945 -120.572088) (xy 168.474644 -120.566688)
			(xy 168.543986 -120.518936) (xy 168.554908 -120.501664) (xy 168.556432 -120.49125) (xy 168.561399 -120.463361)
			(xy 168.578144 -120.409246) (xy 168.602337 -120.358026) (xy 168.633498 -120.31072) (xy 168.671006 -120.26827)
			(xy 168.714115 -120.231521) (xy 168.761966 -120.201204) (xy 168.813607 -120.177922) (xy 168.868011 -120.16214)
			(xy 168.924095 -120.154171) (xy 168.952418 -120.153684) (xy 168.981787 -120.154211) (xy 169.039894 -120.162811)
			(xy 169.096124 -120.179796) (xy 169.149275 -120.204802) (xy 169.198209 -120.237294) (xy 169.220388 -120.256554)
			(xy 169.227564 -120.262452) (xy 169.24489 -120.269101) (xy 169.25417 -120.269508) (xy 169.285666 -120.269508)
			(xy 169.294935 -120.269044) (xy 169.312253 -120.262415) (xy 169.319448 -120.256554) (xy 169.341626 -120.237294)
			(xy 169.390564 -120.204809) (xy 169.443716 -120.179807) (xy 169.499945 -120.162822) (xy 169.558049 -120.154217)
			(xy 169.587418 -120.153684) (xy 169.604459 -120.153876) (xy 169.638414 -120.156798) (xy 169.655236 -120.159526)
			(xy 169.666291 -120.160886) (xy 169.68777 -120.15509) (xy 169.696638 -120.14835) (xy 169.721022 -120.127522)
			(xy 169.729169 -120.119859) (xy 169.738531 -120.099577) (xy 169.739056 -120.088406) (xy 169.739056 -120.086374)
			(xy 169.739056 -119.220996) (xy 169.738535 -119.209819) (xy 169.729192 -119.189523) (xy 169.721022 -119.18188)
			(xy 169.696638 -119.161052) (xy 169.687771 -119.154317) (xy 169.666291 -119.148534) (xy 169.655236 -119.149876)
			(xy 169.638409 -119.152533) (xy 169.604453 -119.155327) (xy 169.587418 -119.155464) (xy 169.558782 -119.155075)
			(xy 169.502092 -119.146926) (xy 169.44714 -119.130793) (xy 169.395042 -119.107003) (xy 169.346861 -119.07604)
			(xy 169.303577 -119.038536) (xy 169.26607 -118.995254) (xy 169.235106 -118.947074) (xy 169.211314 -118.894977)
			(xy 169.195178 -118.840025) (xy 169.187027 -118.783336) (xy 169.187027 -118.726064) (xy 169.195178 -118.669375)
			(xy 169.211314 -118.614423) (xy 169.235106 -118.562326) (xy 169.26607 -118.514146) (xy 169.303577 -118.470864)
			(xy 169.346861 -118.43336) (xy 169.395042 -118.402397) (xy 169.44714 -118.378607) (xy 169.502092 -118.362474)
			(xy 169.558782 -118.354325) (xy 169.587418 -118.35384) (xy 169.615729 -118.354378) (xy 169.671788 -118.362331)
			(xy 169.726172 -118.378091) (xy 169.777797 -118.401344) (xy 169.825639 -118.431628) (xy 169.868745 -118.468341)
			(xy 169.906258 -118.510752) (xy 169.937432 -118.558019) (xy 169.961647 -118.6092) (xy 169.978422 -118.663279)
			(xy 169.983404 -118.691152) (xy 169.984928 -118.701566) (xy 169.99585 -118.718838) (xy 170.065192 -118.76659)
			(xy 170.073891 -118.771991) (xy 170.09394 -118.776057) (xy 170.104054 -118.774464) (xy 170.104562 -118.774464)
			(xy 170.127415 -118.769991) (xy 170.173734 -118.765153) (xy 170.197018 -118.764812) (xy 170.220366 -118.765151)
			(xy 170.266812 -118.769985) (xy 170.289728 -118.774464) (xy 170.289982 -118.774464) (xy 170.300096 -118.776054)
			(xy 170.320145 -118.771989) (xy 170.328844 -118.76659) (xy 170.398186 -118.718838) (xy 170.409108 -118.701566)
			(xy 170.410632 -118.691152) (xy 170.41562 -118.663279) (xy 170.432393 -118.609197) (xy 170.456607 -118.558011)
			(xy 170.48778 -118.510741) (xy 170.525291 -118.468325) (xy 170.568395 -118.431607) (xy 170.616236 -118.401316)
			(xy 170.667861 -118.378056) (xy 170.722245 -118.362288) (xy 170.778306 -118.354326) (xy 170.806618 -118.35384)
			(xy 170.806872 -118.35384) (xy 170.837402 -118.354446) (xy 170.897752 -118.363729) (xy 170.956002 -118.382041)
			(xy 170.983656 -118.394988) (xy 170.98391 -118.394988) (xy 170.992081 -118.398568) (xy 171.009811 -118.40042)
			(xy 171.027106 -118.396099) (xy 171.03471 -118.391432) (xy 171.119292 -118.334028) (xy 171.130976 -118.30939)
			(xy 171.12996 -118.295674) (xy 171.12869 -118.265194) (xy 171.129184 -118.237943) (xy 171.136941 -118.183997)
			(xy 171.152297 -118.131703) (xy 171.174939 -118.082127) (xy 171.204405 -118.036278) (xy 171.240096 -117.995089)
			(xy 171.281286 -117.959399) (xy 171.327136 -117.929933) (xy 171.376713 -117.907293) (xy 171.429007 -117.891939)
			(xy 171.482954 -117.884183) (xy 171.537455 -117.884184) (xy 171.591402 -117.891941) (xy 171.643696 -117.907297)
			(xy 171.693272 -117.929938) (xy 171.739121 -117.959404) (xy 171.78031 -117.995095) (xy 171.816001 -118.036285)
			(xy 171.845466 -118.082135) (xy 171.868106 -118.131712) (xy 171.883461 -118.184006) (xy 171.891216 -118.237953)
			(xy 171.891216 -118.292454) (xy 171.883459 -118.346401) (xy 171.868104 -118.398694) (xy 171.845463 -118.448271)
			(xy 171.815997 -118.49412) (xy 171.780305 -118.535309) (xy 171.739116 -118.571) (xy 171.693266 -118.600465)
			(xy 171.643689 -118.623106) (xy 171.591396 -118.63846) (xy 171.537449 -118.646216) (xy 171.510198 -118.646702)
			(xy 171.482523 -118.646205) (xy 171.427755 -118.638201) (xy 171.374719 -118.622364) (xy 171.349416 -118.611142)
			(xy 171.349162 -118.611142) (xy 171.340938 -118.607598) (xy 171.323105 -118.60605) (xy 171.305843 -118.610788)
			(xy 171.298362 -118.615714) (xy 171.21505 -118.67515) (xy 171.203874 -118.700042) (xy 171.205398 -118.713758)
			(xy 171.206418 -118.723888) (xy 171.20756 -118.744218) (xy 171.207684 -118.754398) (xy 171.207684 -118.754906)
			(xy 171.207163 -118.783538) (xy 171.198983 -118.840214) (xy 171.18282 -118.895149) (xy 171.159002 -118.947225)
			(xy 171.128015 -118.99538) (xy 171.090489 -119.038635) (xy 171.047189 -119.076108) (xy 170.998996 -119.107036)
			(xy 170.946892 -119.130791) (xy 170.891937 -119.146887) (xy 170.83525 -119.154997) (xy 170.806618 -119.155464)
			(xy 170.789582 -119.155337) (xy 170.755626 -119.152541) (xy 170.7388 -119.149876) (xy 170.727744 -119.148537)
			(xy 170.706267 -119.154319) (xy 170.697398 -119.161052) (xy 170.673014 -119.18188) (xy 170.664872 -119.189548)
			(xy 170.655506 -119.209826) (xy 170.65498 -119.220996) (xy 170.65498 -119.222774) (xy 170.65498 -120.088406)
			(xy 170.655488 -120.099584) (xy 170.664839 -120.119882) (xy 170.673014 -120.127522) (xy 170.697398 -120.14835)
			(xy 170.706287 -120.155051) (xy 170.727749 -120.160854) (xy 170.7388 -120.159526) (xy 170.755624 -120.156818)
			(xy 170.789578 -120.15389) (xy 170.806618 -120.153684) (xy 170.835269 -120.154096) (xy 170.891987 -120.162253)
			(xy 170.946968 -120.178399) (xy 170.999091 -120.202205) (xy 171.047296 -120.233186) (xy 171.090601 -120.270712)
			(xy 171.128125 -120.314019) (xy 171.159104 -120.362225) (xy 171.182907 -120.414349) (xy 171.199051 -120.46933)
			(xy 171.207205 -120.526049) (xy 171.207205 -120.583351) (xy 171.199051 -120.64007) (xy 171.182907 -120.695051)
			(xy 171.159104 -120.747175) (xy 171.128125 -120.795381) (xy 171.090601 -120.838688) (xy 171.047296 -120.876214)
			(xy 170.999091 -120.907195) (xy 170.946968 -120.931001) (xy 170.891987 -120.947147) (xy 170.835269 -120.955304)
			(xy 170.806618 -120.955816) (xy 170.778296 -120.955341) (xy 170.722215 -120.94736) (xy 170.667816 -120.93157)
			(xy 170.616178 -120.908284) (xy 170.56833 -120.877964) (xy 170.525224 -120.841215) (xy 170.487716 -120.798767)
			(xy 170.456552 -120.751465) (xy 170.432353 -120.700249) (xy 170.4156 -120.646138) (xy 170.410632 -120.61825)
			(xy 170.409108 -120.607836) (xy 170.397932 -120.590056) (xy 170.328844 -120.542558) (xy 170.320137 -120.537173)
			(xy 170.300095 -120.533098) (xy 170.289982 -120.534684) (xy 170.289474 -120.534684) (xy 170.266623 -120.539168)
			(xy 170.220303 -120.543999) (xy 170.197018 -120.544336) (xy 170.17367 -120.544007) (xy 170.127224 -120.539166)
			(xy 170.104308 -120.534684) (xy 170.104054 -120.534684) (xy 170.093939 -120.533107) (xy 170.073891 -120.537161)
			(xy 170.065192 -120.542558) (xy 169.996104 -120.590056) (xy 169.984928 -120.607836) (xy 169.983404 -120.61825)
			(xy 169.978403 -120.646132) (xy 169.96166 -120.700245) (xy 169.937469 -120.751463) (xy 169.906312 -120.798767)
			(xy 169.868808 -120.841217) (xy 169.825703 -120.877966) (xy 169.777856 -120.908284) (xy 169.726219 -120.931568)
			(xy 169.67182 -120.947353) (xy 169.61574 -120.955327) (xy 169.587418 -120.955816) (xy 169.558049 -120.955268)
			(xy 169.499944 -120.946672) (xy 169.443714 -120.929693) (xy 169.390563 -120.904691) (xy 169.341628 -120.872204)
			(xy 169.319448 -120.852946) (xy 169.312292 -120.84702) (xy 169.29495 -120.840388) (xy 169.285666 -120.839992)
			(xy 169.25417 -120.839992) (xy 169.244897 -120.840425) (xy 169.22758 -120.847076) (xy 169.220388 -120.852946)
			(xy 169.198196 -120.872189) (xy 169.149262 -120.904676) (xy 169.096114 -120.929681) (xy 169.039888 -120.946671)
			(xy 168.981786 -120.95528) (xy 168.952418 -120.955816) (xy 168.935377 -120.955632) (xy 168.901422 -120.952705)
			(xy 168.8846 -120.949974) (xy 168.873544 -120.948636) (xy 168.852067 -120.954417) (xy 168.843198 -120.96115)
			(xy 168.818814 -120.981978) (xy 168.810673 -120.989647) (xy 168.801306 -121.009924) (xy 168.80078 -121.021094)
			(xy 168.80078 -121.022872) (xy 168.80078 -121.88825) (xy 168.801263 -121.899431) (xy 168.810632 -121.919728)
			(xy 168.818814 -121.927366) (xy 168.843198 -121.948194) (xy 168.852084 -121.954899) (xy 168.873549 -121.960698)
			(xy 168.8846 -121.95937) (xy 168.901425 -121.956663) (xy 168.935378 -121.953734) (xy 168.952418 -121.953528)
			(xy 168.981788 -121.954044) (xy 169.039895 -121.962645) (xy 169.096126 -121.979632) (xy 169.149277 -122.004641)
			(xy 169.19821 -122.037136) (xy 169.220388 -122.056398) (xy 169.227569 -122.062289) (xy 169.244891 -122.068944)
			(xy 169.25417 -122.069352) (xy 169.285666 -122.069352) (xy 169.294937 -122.068901) (xy 169.312255 -122.062264)
			(xy 169.319448 -122.056398) (xy 169.341632 -122.037145) (xy 169.390568 -122.004658) (xy 169.443718 -121.979654)
			(xy 169.499946 -121.962667) (xy 169.558049 -121.954061) (xy 169.587418 -121.953528) (xy 169.61574 -121.954025)
			(xy 169.671821 -121.961998) (xy 169.726223 -121.977783) (xy 169.777862 -122.001064) (xy 169.825711 -122.031381)
			(xy 169.868819 -122.068128) (xy 169.906328 -122.110575) (xy 169.937491 -122.157878) (xy 169.961688 -122.209094)
			(xy 169.978437 -122.263206) (xy 169.983404 -122.291094) (xy 169.984928 -122.301508) (xy 169.99585 -122.31878)
			(xy 170.065192 -122.366532) (xy 170.07389 -122.371935) (xy 170.093939 -122.375999) (xy 170.104054 -122.374406)
			(xy 170.104308 -122.374406) (xy 170.127228 -122.369975) (xy 170.173675 -122.36527) (xy 170.197018 -122.365008)
			(xy 170.22036 -122.365282) (xy 170.266806 -122.36999) (xy 170.289728 -122.374406) (xy 170.289982 -122.374406)
			(xy 170.300096 -122.37599) (xy 170.320144 -122.371928) (xy 170.328844 -122.366532) (xy 170.398186 -122.31878)
			(xy 170.409108 -122.301508) (xy 170.410632 -122.291094) (xy 170.415632 -122.263211) (xy 170.432371 -122.209096)
			(xy 170.45656 -122.157876) (xy 170.487716 -122.110569) (xy 170.52522 -122.068118) (xy 170.568325 -122.031368)
			(xy 170.616174 -122.00105) (xy 170.667812 -121.977767) (xy 170.722214 -121.961984) (xy 170.778296 -121.954015)
			(xy 170.806618 -121.953528) (xy 170.835265 -121.954052) (xy 170.891975 -121.962208) (xy 170.946948 -121.978352)
			(xy 170.999064 -122.002155) (xy 171.047262 -122.033131) (xy 171.090561 -122.070652) (xy 171.128079 -122.113953)
			(xy 171.159054 -122.162152) (xy 171.182854 -122.214269) (xy 171.198995 -122.269242) (xy 171.207149 -122.325953)
			(xy 171.207149 -122.383247) (xy 171.198995 -122.439958) (xy 171.182854 -122.494931) (xy 171.159054 -122.547048)
			(xy 171.128079 -122.595247) (xy 171.090561 -122.638548) (xy 171.047262 -122.676069) (xy 170.999064 -122.707045)
			(xy 170.946948 -122.730848) (xy 170.891975 -122.746992) (xy 170.835265 -122.755148) (xy 170.806618 -122.75566)
			(xy 170.789577 -122.755475) (xy 170.755622 -122.752549) (xy 170.7388 -122.749818) (xy 170.727744 -122.74847)
			(xy 170.706266 -122.754256) (xy 170.697398 -122.760994) (xy 170.673014 -122.781822) (xy 170.664853 -122.789473)
			(xy 170.655497 -122.809764) (xy 170.65498 -122.820938) (xy 170.65498 -122.822716) (xy 170.65498 -123.547378)
			(xy 172.927264 -123.547378) (xy 172.927264 -100.858574) (xy 172.927772 -100.84054) (xy 172.927772 -100.837746)
			(xy 172.927772 -100.753672) (xy 172.928164 -100.743599) (xy 172.935906 -100.725) (xy 172.942758 -100.717604)
			(xy 173.001686 -100.658676) (xy 173.003972 -100.656136) (xy 173.016926 -100.64242) (xy 173.72457 -99.93503)
			(xy 173.730666 -99.905058) (xy 173.725332 -99.89185) (xy 173.716715 -99.869271) (xy 173.704619 -99.82248)
			(xy 173.698524 -99.774537) (xy 173.698154 -99.750372) (xy 173.698652 -99.723122) (xy 173.706411 -99.669176)
			(xy 173.721768 -99.616884) (xy 173.744409 -99.567309) (xy 173.773875 -99.521461) (xy 173.809565 -99.480272)
			(xy 173.850753 -99.444581) (xy 173.896601 -99.415114) (xy 173.946175 -99.392471) (xy 173.998467 -99.377113)
			(xy 174.052412 -99.369352) (xy 174.079662 -99.368864) (xy 174.107039 -99.369323) (xy 174.161229 -99.377159)
			(xy 174.213743 -99.39266) (xy 174.263501 -99.415508) (xy 174.309483 -99.445234) (xy 174.350743 -99.481228)
			(xy 174.386435 -99.52275) (xy 174.415825 -99.568948) (xy 174.43831 -99.618872) (xy 174.453427 -99.671497)
			(xy 174.457614 -99.698556) (xy 174.460154 -99.716844) (xy 174.488856 -99.741736) (xy 183.314848 -99.741736)
			(xy 183.323327 -99.741414) (xy 183.33934 -99.735822) (xy 183.352665 -99.725328) (xy 183.35752 -99.718368)
			(xy 183.40324 -99.646994) (xy 183.409527 -99.635935) (xy 183.411386 -99.610598) (xy 183.406796 -99.598734)
			(xy 183.406796 -99.59848) (xy 183.395924 -99.573483) (xy 183.380553 -99.521187) (xy 183.372762 -99.467238)
			(xy 183.372252 -99.439984) (xy 183.372738 -99.412733) (xy 183.380494 -99.358785) (xy 183.395849 -99.30649)
			(xy 183.418491 -99.256913) (xy 183.447957 -99.211063) (xy 183.483648 -99.169872) (xy 183.524839 -99.134181)
			(xy 183.570689 -99.104715) (xy 183.620266 -99.082073) (xy 183.672561 -99.066718) (xy 183.726509 -99.058962)
			(xy 183.781011 -99.058962) (xy 183.834959 -99.066718) (xy 183.887254 -99.082073) (xy 183.936831 -99.104715)
			(xy 183.982681 -99.134181) (xy 184.023872 -99.169872) (xy 184.038713 -99.187) (xy 185.421776 -99.187)
			(xy 185.425847 -99.131378) (xy 185.437973 -99.076941) (xy 185.457896 -99.02485) (xy 185.485192 -98.976215)
			(xy 185.519278 -98.932072) (xy 185.559427 -98.893363) (xy 185.604785 -98.860912) (xy 185.654385 -98.835411)
			(xy 185.707169 -98.817404) (xy 185.762012 -98.807274) (xy 185.817746 -98.805237) (xy 185.873183 -98.811337)
			(xy 185.92714 -98.825443) (xy 185.978469 -98.847255) (xy 186.026075 -98.876309) (xy 186.068943 -98.911984)
			(xy 186.10616 -98.953521) (xy 186.136933 -99.000034) (xy 186.160605 -99.050531) (xy 186.176673 -99.103938)
			(xy 186.184793 -99.159114) (xy 186.185302 -99.187) (xy 186.184793 -99.214886) (xy 186.176673 -99.270062)
			(xy 186.160605 -99.323469) (xy 186.136933 -99.373966) (xy 186.10616 -99.420479) (xy 186.068943 -99.462016)
			(xy 186.026075 -99.497691) (xy 185.978469 -99.526745) (xy 185.92714 -99.548557) (xy 185.873183 -99.562663)
			(xy 185.817746 -99.568763) (xy 185.762012 -99.566726) (xy 185.707169 -99.556596) (xy 185.654385 -99.538589)
			(xy 185.604785 -99.513088) (xy 185.559427 -99.480637) (xy 185.519278 -99.441928) (xy 185.485192 -99.397785)
			(xy 185.457896 -99.34915) (xy 185.437973 -99.297059) (xy 185.425847 -99.242622) (xy 185.421776 -99.187)
			(xy 184.038713 -99.187) (xy 184.059563 -99.211063) (xy 184.089029 -99.256913) (xy 184.111671 -99.30649)
			(xy 184.127026 -99.358785) (xy 184.134782 -99.412733) (xy 184.135268 -99.439984) (xy 184.134798 -99.467242)
			(xy 184.127033 -99.521202) (xy 184.111646 -99.573502) (xy 184.100724 -99.59848) (xy 184.100724 -99.598734)
			(xy 184.097529 -99.606547) (xy 184.095967 -99.623346) (xy 184.099974 -99.639733) (xy 184.10428 -99.646994)
			(xy 184.15 -99.718368) (xy 184.154826 -99.725355) (xy 184.168148 -99.735872) (xy 184.184185 -99.741426)
			(xy 184.192672 -99.741736) (xy 186.28995 -99.741736) (xy 186.290712 -99.742244) (xy 186.30773 -99.742244)
			(xy 186.32595 -99.720623) (xy 186.36768 -99.682477) (xy 186.414582 -99.650906) (xy 186.46563 -99.626603)
			(xy 186.519706 -99.610099) (xy 186.575625 -99.601755) (xy 186.632163 -99.601755) (xy 186.688082 -99.610099)
			(xy 186.742158 -99.626603) (xy 186.793206 -99.650906) (xy 186.840108 -99.682477) (xy 186.881838 -99.720623)
			(xy 186.900058 -99.742244) (xy 186.917076 -99.742244) (xy 186.917838 -99.741736) (xy 188.06033 -99.741736)
			(xy 188.070403 -99.741343) (xy 188.089002 -99.733602) (xy 188.096398 -99.72675) (xy 190.032132 -97.790762)
			(xy 190.038736 -97.763838) (xy 190.034926 -97.751138) (xy 190.027217 -97.724038) (xy 190.018924 -97.668311)
			(xy 190.018416 -97.64014) (xy 190.018893 -97.612887) (xy 190.026645 -97.558935) (xy 190.041997 -97.506636)
			(xy 190.064637 -97.457055) (xy 190.094103 -97.4112) (xy 190.129795 -97.370006) (xy 190.170987 -97.334312)
			(xy 190.216841 -97.304844) (xy 190.266421 -97.282203) (xy 190.31872 -97.266848) (xy 190.372671 -97.259094)
			(xy 190.399924 -97.258632) (xy 190.428095 -97.259138) (xy 190.483824 -97.267425) (xy 190.510922 -97.275142)
			(xy 190.523622 -97.278952) (xy 190.550546 -97.272348) (xy 190.778384 -97.04451) (xy 190.779654 -97.04451)
			(xy 190.822326 -97.001838) (xy 190.829438 -96.987614) (xy 190.830708 -96.97974) (xy 190.835394 -96.95357)
			(xy 190.850988 -96.902745) (xy 190.873489 -96.854577) (xy 190.902461 -96.810002) (xy 190.937343 -96.769881)
			(xy 190.977458 -96.734994) (xy 191.022029 -96.706016) (xy 191.070193 -96.683508) (xy 191.121016 -96.667907)
			(xy 191.147192 -96.663256) (xy 191.155066 -96.661986) (xy 191.16929 -96.654874) (xy 191.211962 -96.612202)
			(xy 191.211962 -96.610932) (xy 191.679068 -96.14408) (xy 191.685926 -96.116648) (xy 191.681862 -96.103694)
			(xy 191.673694 -96.075892) (xy 191.664894 -96.01862) (xy 191.664336 -95.989648) (xy 191.6648 -95.962394)
			(xy 191.672552 -95.908441) (xy 191.687904 -95.856141) (xy 191.710544 -95.806558) (xy 191.740011 -95.760702)
			(xy 191.775705 -95.719508) (xy 191.816899 -95.683813) (xy 191.862754 -95.654346) (xy 191.912337 -95.631705)
			(xy 191.964637 -95.616353) (xy 192.01859 -95.6086) (xy 192.045844 -95.60814) (xy 192.074815 -95.608704)
			(xy 192.132087 -95.617502) (xy 192.15989 -95.625666) (xy 192.172844 -95.62973) (xy 192.200276 -95.622872)
			(xy 195.264278 -92.558616) (xy 195.271101 -92.551202) (xy 195.278831 -92.532614) (xy 195.279264 -92.522548)
			(xy 195.279264 -82.818986) (xy 195.27906 -82.809174) (xy 195.27222 -82.790801) (xy 195.25897 -82.776352)
			(xy 195.250308 -82.771742) (xy 195.226262 -82.759812) (xy 195.181542 -82.730122) (xy 195.141426 -82.694456)
			(xy 195.106708 -82.653516) (xy 195.078073 -82.608114) (xy 195.056086 -82.559144) (xy 195.041184 -82.507576)
			(xy 195.033659 -82.454427) (xy 195.033661 -82.400749) (xy 195.041189 -82.347601) (xy 195.056095 -82.296033)
			(xy 195.078084 -82.247065) (xy 195.106722 -82.201664) (xy 195.141443 -82.160727) (xy 195.181561 -82.125063)
			(xy 195.226283 -82.095376) (xy 195.250308 -82.083402) (xy 195.258969 -82.078797) (xy 195.272193 -82.064327)
			(xy 195.279063 -82.045967) (xy 195.279264 -82.036158) (xy 195.279264 -82.030316) (xy 195.279264 -80.796892)
			(xy 195.278794 -80.786958) (xy 195.271217 -80.76859) (xy 195.257238 -80.75447) (xy 195.248276 -80.750156)
			(xy 195.148962 -80.707992) (xy 195.11899 -80.71358) (xy 195.108068 -80.724248) (xy 195.086612 -80.744206)
			(xy 195.038708 -80.777952) (xy 194.98621 -80.803982) (xy 194.930352 -80.821685) (xy 194.872444 -80.830645)
			(xy 194.843146 -80.831182) (xy 194.815889 -80.830774) (xy 194.761929 -80.823022) (xy 194.709622 -80.807669)
			(xy 194.660033 -80.785027) (xy 194.614171 -80.755559) (xy 194.57297 -80.719863) (xy 194.537269 -80.678666)
			(xy 194.507795 -80.632807) (xy 194.485147 -80.583221) (xy 194.469788 -80.530916) (xy 194.462029 -80.476957)
			(xy 194.462029 -80.422443) (xy 194.469788 -80.368484) (xy 194.485147 -80.316179) (xy 194.507795 -80.266593)
			(xy 194.537269 -80.220734) (xy 194.57297 -80.179537) (xy 194.614171 -80.143841) (xy 194.660033 -80.114373)
			(xy 194.709622 -80.091731) (xy 194.761929 -80.076378) (xy 194.815889 -80.068626) (xy 194.843146 -80.068166)
			(xy 194.872445 -80.068714) (xy 194.930356 -80.077655) (xy 194.986218 -80.095351) (xy 195.038715 -80.121384)
			(xy 195.086612 -80.155142) (xy 195.108068 -80.1751) (xy 195.11899 -80.185768) (xy 195.148962 -80.191356)
			(xy 195.248276 -80.149192) (xy 195.257246 -80.144889) (xy 195.271237 -80.130774) (xy 195.278795 -80.112393)
			(xy 195.279264 -80.102456) (xy 195.279264 -78.684628) (xy 195.280026 -78.663292) (xy 195.28028 -78.659482)
			(xy 195.28028 -78.579472) (xy 195.280669 -78.569398) (xy 195.288413 -78.550799) (xy 195.295266 -78.543404)
			(xy 195.352416 -78.486254) (xy 195.354702 -78.483714) (xy 195.36918 -78.46822) (xy 197.232524 -76.604876)
			(xy 197.248018 -76.590398) (xy 197.250558 -76.588112) (xy 197.307708 -76.530962) (xy 197.315107 -76.524121)
			(xy 197.333707 -76.516403) (xy 197.343776 -76.515976) (xy 197.423786 -76.515976) (xy 197.427596 -76.515722)
			(xy 197.448932 -76.51496) (xy 197.989444 -76.51496) (xy 198.011542 -76.515722) (xy 198.015352 -76.515976)
			(xy 198.063612 -76.515976) (xy 198.070711 -76.516204) (xy 198.084371 -76.52007) (xy 198.090536 -76.523596)
			(xy 198.133208 -76.55052) (xy 198.135748 -76.552044) (xy 198.144284 -76.556792) (xy 198.160807 -76.567213)
			(xy 198.168768 -76.572872) (xy 198.171562 -76.574904) (xy 198.214996 -76.602082) (xy 198.221038 -76.606122)
			(xy 198.230718 -76.616957) (xy 198.234046 -76.623418) (xy 198.255128 -76.668122) (xy 198.256906 -76.671424)
			(xy 198.265542 -76.688188) (xy 198.305166 -76.770484) (xy 198.314818 -76.792582) (xy 198.316088 -76.795376)
			(xy 198.349616 -76.793852) (xy 198.365618 -76.793598) (xy 198.366126 -76.793598) (xy 198.382128 -76.793852)
			(xy 198.415656 -76.795376) (xy 198.416926 -76.792582) (xy 198.426578 -76.770484) (xy 198.466202 -76.688188)
			(xy 198.474838 -76.671424) (xy 198.476616 -76.668122) (xy 198.497698 -76.623418) (xy 198.501055 -76.616975)
			(xy 198.510724 -76.606143) (xy 198.516748 -76.602082) (xy 198.560182 -76.574904) (xy 198.562976 -76.572872)
			(xy 198.570929 -76.567201) (xy 198.587453 -76.55678) (xy 198.595996 -76.552044) (xy 198.598536 -76.55052)
			(xy 198.641208 -76.523596) (xy 198.647365 -76.520048) (xy 198.661029 -76.516174) (xy 198.668132 -76.515976)
			(xy 198.716392 -76.515976) (xy 198.720202 -76.515722) (xy 198.7423 -76.51496) (xy 199.418194 -76.51496)
			(xy 199.423085 -76.515089) (xy 199.432677 -76.517013) (xy 199.437244 -76.51877) (xy 199.533256 -76.557632)
			(xy 199.538078 -76.55973) (xy 199.546789 -76.565618) (xy 199.550528 -76.569316) (xy 199.586088 -76.606146)
			(xy 199.586596 -76.606654) (xy 199.605392 -76.62545) (xy 204.32979 -76.62545) (xy 204.333861 -76.569828)
			(xy 204.345987 -76.515391) (xy 204.36591 -76.4633) (xy 204.393206 -76.414665) (xy 204.427292 -76.370522)
			(xy 204.467441 -76.331813) (xy 204.512799 -76.299362) (xy 204.562399 -76.273861) (xy 204.615183 -76.255854)
			(xy 204.670026 -76.245724) (xy 204.72576 -76.243687) (xy 204.781197 -76.249787) (xy 204.835154 -76.263893)
			(xy 204.886483 -76.285705) (xy 204.934089 -76.314759) (xy 204.976957 -76.350434) (xy 205.014174 -76.391971)
			(xy 205.044947 -76.438484) (xy 205.068619 -76.488981) (xy 205.084687 -76.542388) (xy 205.092807 -76.597564)
			(xy 205.093316 -76.62545) (xy 205.092807 -76.653336) (xy 205.084687 -76.708512) (xy 205.068619 -76.761919)
			(xy 205.044947 -76.812416) (xy 205.014174 -76.858929) (xy 205.002842 -76.871576) (xy 221.119192 -76.871576)
			(xy 221.119673 -76.844139) (xy 221.127512 -76.789829) (xy 221.143054 -76.737203) (xy 221.165977 -76.687347)
			(xy 221.195808 -76.641291) (xy 221.231932 -76.599986) (xy 221.273602 -76.564284) (xy 221.319959 -76.534922)
			(xy 221.370046 -76.512507) (xy 221.396306 -76.504546) (xy 221.407228 -76.501498) (xy 221.423738 -76.487274)
			(xy 221.465648 -76.397358) (xy 221.465648 -76.375006) (xy 221.461076 -76.3651) (xy 221.450328 -76.340252)
			(xy 221.435172 -76.288281) (xy 221.427515 -76.234688) (xy 221.42704 -76.20762) (xy 221.427526 -76.180369)
			(xy 221.435282 -76.126421) (xy 221.450637 -76.074126) (xy 221.473279 -76.024549) (xy 221.502745 -75.978699)
			(xy 221.538436 -75.937508) (xy 221.579627 -75.901817) (xy 221.625477 -75.872351) (xy 221.675054 -75.849709)
			(xy 221.727349 -75.834354) (xy 221.781297 -75.826598) (xy 221.835799 -75.826598) (xy 221.889747 -75.834354)
			(xy 221.942042 -75.849709) (xy 221.991619 -75.872351) (xy 222.037469 -75.901817) (xy 222.07866 -75.937508)
			(xy 222.114351 -75.978699) (xy 222.143817 -76.024549) (xy 222.166459 -76.074126) (xy 222.181814 -76.126421)
			(xy 222.18957 -76.180369) (xy 222.190056 -76.20762) (xy 222.189609 -76.235058) (xy 222.18455 -76.270104)
			(xy 254.795272 -76.270104) (xy 254.799343 -76.214482) (xy 254.811469 -76.160045) (xy 254.831392 -76.107954)
			(xy 254.858688 -76.059319) (xy 254.892774 -76.015176) (xy 254.932923 -75.976467) (xy 254.978281 -75.944016)
			(xy 255.027881 -75.918515) (xy 255.080665 -75.900508) (xy 255.135508 -75.890378) (xy 255.191242 -75.888341)
			(xy 255.246679 -75.894441) (xy 255.300636 -75.908547) (xy 255.351965 -75.930359) (xy 255.399571 -75.959413)
			(xy 255.442439 -75.995088) (xy 255.479656 -76.036625) (xy 255.510429 -76.083138) (xy 255.534101 -76.133635)
			(xy 255.550169 -76.187042) (xy 255.558289 -76.242218) (xy 255.558798 -76.270104) (xy 255.811272 -76.270104)
			(xy 255.815343 -76.214482) (xy 255.827469 -76.160045) (xy 255.847392 -76.107954) (xy 255.874688 -76.059319)
			(xy 255.908774 -76.015176) (xy 255.948923 -75.976467) (xy 255.994281 -75.944016) (xy 256.043881 -75.918515)
			(xy 256.096665 -75.900508) (xy 256.151508 -75.890378) (xy 256.207242 -75.888341) (xy 256.262679 -75.894441)
			(xy 256.316636 -75.908547) (xy 256.367965 -75.930359) (xy 256.415571 -75.959413) (xy 256.458439 -75.995088)
			(xy 256.495656 -76.036625) (xy 256.526429 -76.083138) (xy 256.550101 -76.133635) (xy 256.566169 -76.187042)
			(xy 256.574289 -76.242218) (xy 256.574798 -76.270104) (xy 256.574289 -76.29799) (xy 256.566169 -76.353166)
			(xy 256.550101 -76.406573) (xy 256.526429 -76.45707) (xy 256.495656 -76.503583) (xy 256.458439 -76.54512)
			(xy 256.415571 -76.580795) (xy 256.367965 -76.609849) (xy 256.316636 -76.631661) (xy 256.262679 -76.645767)
			(xy 256.207242 -76.651867) (xy 256.151508 -76.64983) (xy 256.096665 -76.6397) (xy 256.043881 -76.621693)
			(xy 255.994281 -76.596192) (xy 255.948923 -76.563741) (xy 255.908774 -76.525032) (xy 255.874688 -76.480889)
			(xy 255.847392 -76.432254) (xy 255.827469 -76.380163) (xy 255.815343 -76.325726) (xy 255.811272 -76.270104)
			(xy 255.558798 -76.270104) (xy 255.558289 -76.29799) (xy 255.550169 -76.353166) (xy 255.534101 -76.406573)
			(xy 255.510429 -76.45707) (xy 255.479656 -76.503583) (xy 255.442439 -76.54512) (xy 255.399571 -76.580795)
			(xy 255.351965 -76.609849) (xy 255.300636 -76.631661) (xy 255.246679 -76.645767) (xy 255.191242 -76.651867)
			(xy 255.135508 -76.64983) (xy 255.080665 -76.6397) (xy 255.027881 -76.621693) (xy 254.978281 -76.596192)
			(xy 254.932923 -76.563741) (xy 254.892774 -76.525032) (xy 254.858688 -76.480889) (xy 254.831392 -76.432254)
			(xy 254.811469 -76.380163) (xy 254.799343 -76.325726) (xy 254.795272 -76.270104) (xy 222.18455 -76.270104)
			(xy 222.181769 -76.289372) (xy 222.166226 -76.342001) (xy 222.1433 -76.391859) (xy 222.113464 -76.437916)
			(xy 222.077335 -76.479222) (xy 222.035659 -76.514922) (xy 221.989297 -76.544281) (xy 221.939205 -76.566691)
			(xy 221.912942 -76.57465) (xy 221.90202 -76.577698) (xy 221.88551 -76.591922) (xy 221.8436 -76.681838)
			(xy 221.8436 -76.70419) (xy 221.848172 -76.714096) (xy 221.858915 -76.738945) (xy 221.874075 -76.790916)
			(xy 221.881733 -76.844508) (xy 221.882208 -76.871576) (xy 221.881722 -76.898827) (xy 221.881623 -76.899516)
			(xy 222.184976 -76.899516) (xy 222.185493 -76.872266) (xy 222.193247 -76.81832) (xy 222.208599 -76.766027)
			(xy 222.231237 -76.716451) (xy 222.2607 -76.670601) (xy 222.296389 -76.629411) (xy 222.337576 -76.59372)
			(xy 222.383423 -76.564253) (xy 222.432997 -76.54161) (xy 222.485289 -76.526254) (xy 222.539234 -76.518495)
			(xy 222.566484 -76.518008) (xy 222.59436 -76.518483) (xy 222.649517 -76.526597) (xy 222.702906 -76.542655)
			(xy 222.753389 -76.566314) (xy 222.799889 -76.59707) (xy 222.820992 -76.61529) (xy 222.82912 -76.622656)
			(xy 222.850456 -76.62926) (xy 222.949008 -76.615798) (xy 222.967804 -76.604114) (xy 222.9739 -76.594716)
			(xy 222.989061 -76.572136) (xy 223.024764 -76.531109) (xy 223.06593 -76.495567) (xy 223.111726 -76.46623)
			(xy 223.161223 -76.443693) (xy 223.213418 -76.428411) (xy 223.267255 -76.420696) (xy 223.294448 -76.420218)
			(xy 223.321702 -76.420633) (xy 223.375653 -76.428397) (xy 223.427951 -76.443759) (xy 223.47753 -76.466408)
			(xy 223.523381 -76.495882) (xy 223.564572 -76.531581) (xy 223.600263 -76.572778) (xy 223.629727 -76.618635)
			(xy 223.652366 -76.668219) (xy 223.667719 -76.720519) (xy 223.675472 -76.774472) (xy 223.675956 -76.801726)
			(xy 223.675386 -76.830654) (xy 223.666647 -76.887845) (xy 223.649373 -76.943061) (xy 223.62396 -76.995036)
			(xy 223.590991 -77.042578) (xy 223.551222 -77.084598) (xy 223.505564 -77.120131) (xy 223.455065 -77.148363)
			(xy 223.400882 -77.168647) (xy 223.37268 -77.175106) (xy 223.372426 -77.175106) (xy 223.364168 -77.177186)
			(xy 223.349584 -77.18596) (xy 223.338665 -77.199015) (xy 223.335342 -77.206856) (xy 223.305116 -77.286866)
			(xy 223.302392 -77.294973) (xy 223.301923 -77.31206) (xy 223.307107 -77.328347) (xy 223.311974 -77.33538)
			(xy 223.329764 -77.360257) (xy 223.358038 -77.414483) (xy 223.377301 -77.472524) (xy 223.387059 -77.532895)
			(xy 223.387666 -77.563472) (xy 224.659188 -77.563472) (xy 224.663259 -77.50785) (xy 224.675385 -77.453413)
			(xy 224.695308 -77.401322) (xy 224.722604 -77.352687) (xy 224.75669 -77.308544) (xy 224.796839 -77.269835)
			(xy 224.842197 -77.237384) (xy 224.891797 -77.211883) (xy 224.944581 -77.193876) (xy 224.999424 -77.183746)
			(xy 225.055158 -77.181709) (xy 225.110595 -77.187809) (xy 225.164552 -77.201915) (xy 225.215881 -77.223727)
			(xy 225.263487 -77.252781) (xy 225.306355 -77.288456) (xy 225.343572 -77.329993) (xy 225.374345 -77.376506)
			(xy 225.398017 -77.427003) (xy 225.398955 -77.430122) (xy 229.499668 -77.430122) (xy 229.500164 -77.402742)
			(xy 229.507628 -77.348494) (xy 229.522406 -77.295767) (xy 229.544224 -77.245541) (xy 229.572675 -77.198753)
			(xy 229.607229 -77.156273) (xy 229.647244 -77.118891) (xy 229.66934 -77.102716) (xy 229.676521 -77.097119)
			(xy 229.686666 -77.082012) (xy 229.689152 -77.073252) (xy 229.696518 -77.043534) (xy 229.698421 -77.03448)
			(xy 229.696345 -77.016113) (xy 229.692454 -77.00772) (xy 229.680083 -76.983146) (xy 229.660629 -76.931683)
			(xy 229.647479 -76.87826) (xy 229.640824 -76.823646) (xy 229.640384 -76.796138) (xy 229.640843 -76.766151)
			(xy 229.648667 -76.70669) (xy 229.664186 -76.64876) (xy 229.687135 -76.593351) (xy 229.71712 -76.541412)
			(xy 229.75363 -76.493831) (xy 229.796037 -76.451424) (xy 229.843618 -76.414916) (xy 229.895558 -76.384931)
			(xy 229.950967 -76.361983) (xy 230.008898 -76.346465) (xy 230.068359 -76.338642) (xy 230.098346 -76.338176)
			(xy 230.961946 -76.338176) (xy 230.991933 -76.338585) (xy 231.051393 -76.346419) (xy 231.109322 -76.361947)
			(xy 231.164728 -76.384904) (xy 231.216664 -76.414896) (xy 231.264242 -76.45141) (xy 231.306646 -76.493822)
			(xy 231.343151 -76.541405) (xy 231.373134 -76.593347) (xy 231.39608 -76.648758) (xy 231.411597 -76.706689)
			(xy 231.41942 -76.766151) (xy 231.419908 -76.796138) (xy 231.419519 -76.823711) (xy 231.41597 -76.853034)
			(xy 236.02264 -76.853034) (xy 236.026711 -76.797412) (xy 236.038837 -76.742975) (xy 236.05876 -76.690884)
			(xy 236.086056 -76.642249) (xy 236.120142 -76.598106) (xy 236.160291 -76.559397) (xy 236.205649 -76.526946)
			(xy 236.255249 -76.501445) (xy 236.308033 -76.483438) (xy 236.362876 -76.473308) (xy 236.41861 -76.471271)
			(xy 236.474047 -76.477371) (xy 236.528004 -76.491477) (xy 236.579333 -76.513289) (xy 236.626939 -76.542343)
			(xy 236.669807 -76.578018) (xy 236.707024 -76.619555) (xy 236.737797 -76.666068) (xy 236.761469 -76.716565)
			(xy 236.777537 -76.769972) (xy 236.785657 -76.825148) (xy 236.786166 -76.853034) (xy 236.785657 -76.88092)
			(xy 236.777537 -76.936096) (xy 236.761469 -76.989503) (xy 236.737797 -77.04) (xy 236.707024 -77.086513)
			(xy 236.669807 -77.12805) (xy 236.626939 -77.163725) (xy 236.579333 -77.192779) (xy 236.528004 -77.214591)
			(xy 236.474047 -77.228697) (xy 236.41861 -77.234797) (xy 236.362876 -77.23276) (xy 236.308033 -77.22263)
			(xy 236.255249 -77.204623) (xy 236.205649 -77.179122) (xy 236.160291 -77.146671) (xy 236.120142 -77.107962)
			(xy 236.086056 -77.063819) (xy 236.05876 -77.015184) (xy 236.038837 -76.963093) (xy 236.026711 -76.908656)
			(xy 236.02264 -76.853034) (xy 231.41597 -76.853034) (xy 231.412892 -76.878458) (xy 231.399737 -76.932013)
			(xy 231.380246 -76.983601) (xy 231.367838 -77.008228) (xy 231.363947 -77.016482) (xy 231.36174 -77.034583)
			(xy 231.36352 -77.043534) (xy 231.370886 -77.073506) (xy 231.373418 -77.082292) (xy 231.383707 -77.097391)
			(xy 231.390952 -77.10297) (xy 231.412979 -77.119177) (xy 231.452888 -77.156561) (xy 231.487348 -77.199022)
			(xy 231.515717 -77.245772) (xy 231.537471 -77.295943) (xy 231.552206 -77.348604) (xy 231.554402 -77.36459)
			(xy 234.24591 -77.36459) (xy 234.249981 -77.308968) (xy 234.262107 -77.254531) (xy 234.28203 -77.20244)
			(xy 234.309326 -77.153805) (xy 234.343412 -77.109662) (xy 234.383561 -77.070953) (xy 234.428919 -77.038502)
			(xy 234.478519 -77.013001) (xy 234.531303 -76.994994) (xy 234.586146 -76.984864) (xy 234.64188 -76.982827)
			(xy 234.697317 -76.988927) (xy 234.751274 -77.003033) (xy 234.802603 -77.024845) (xy 234.850209 -77.053899)
			(xy 234.893077 -77.089574) (xy 234.930294 -77.131111) (xy 234.961067 -77.177624) (xy 234.984739 -77.228121)
			(xy 235.000807 -77.281528) (xy 235.008927 -77.336704) (xy 235.009436 -77.36459) (xy 235.008927 -77.392476)
			(xy 235.000807 -77.447652) (xy 234.984739 -77.501059) (xy 234.961067 -77.551556) (xy 234.930294 -77.598069)
			(xy 234.893077 -77.639606) (xy 234.850209 -77.675281) (xy 234.802603 -77.704335) (xy 234.751274 -77.726147)
			(xy 234.697317 -77.740253) (xy 234.64188 -77.746353) (xy 234.586146 -77.744316) (xy 234.531303 -77.734186)
			(xy 234.478519 -77.716179) (xy 234.428919 -77.690678) (xy 234.383561 -77.658227) (xy 234.343412 -77.619518)
			(xy 234.309326 -77.575375) (xy 234.28203 -77.52674) (xy 234.262107 -77.474649) (xy 234.249981 -77.420212)
			(xy 234.24591 -77.36459) (xy 231.554402 -77.36459) (xy 231.559647 -77.40278) (xy 231.560116 -77.430122)
			(xy 231.560116 -77.433678) (xy 231.560744 -77.446094) (xy 231.57232 -77.468062) (xy 231.582214 -77.475588)
			(xy 231.662224 -77.530452) (xy 231.687624 -77.533246) (xy 231.699308 -77.52842) (xy 231.722985 -77.519401)
			(xy 231.772045 -77.506737) (xy 231.82231 -77.500357) (xy 231.847644 -77.499972) (xy 231.876167 -77.500488)
			(xy 231.932637 -77.508576) (xy 231.987392 -77.524583) (xy 232.039326 -77.548187) (xy 232.087392 -77.57891)
			(xy 232.130621 -77.616134) (xy 232.168139 -77.659106) (xy 232.199191 -77.706961) (xy 232.211626 -77.732636)
			(xy 232.216792 -77.742441) (xy 232.233631 -77.756804) (xy 232.244138 -77.760322) (xy 232.318814 -77.780896)
			(xy 232.329569 -77.783327) (xy 232.351306 -77.779773) (xy 232.360724 -77.774038) (xy 232.360978 -77.774038)
			(xy 232.384838 -77.758352) (xy 232.436284 -77.733578) (xy 232.490848 -77.716751) (xy 232.547312 -77.708247)
			(xy 232.575862 -77.707744) (xy 232.603113 -77.708301) (xy 232.657061 -77.716052) (xy 232.709357 -77.731403)
			(xy 232.758936 -77.754041) (xy 232.804788 -77.783504) (xy 232.84598 -77.819193) (xy 232.881673 -77.860381)
			(xy 232.911141 -77.906231) (xy 232.933784 -77.955807) (xy 232.94914 -78.008101) (xy 232.956897 -78.062049)
			(xy 232.956897 -78.116551) (xy 232.94914 -78.170499) (xy 232.933784 -78.222793) (xy 232.911141 -78.272369)
			(xy 232.881673 -78.318219) (xy 232.846113 -78.359254) (xy 233.33405 -78.359254) (xy 233.338121 -78.303632)
			(xy 233.350247 -78.249195) (xy 233.37017 -78.197104) (xy 233.397466 -78.148469) (xy 233.431552 -78.104326)
			(xy 233.471701 -78.065617) (xy 233.517059 -78.033166) (xy 233.566659 -78.007665) (xy 233.619443 -77.989658)
			(xy 233.674286 -77.979528) (xy 233.73002 -77.977491) (xy 233.785457 -77.983591) (xy 233.839414 -77.997697)
			(xy 233.890743 -78.019509) (xy 233.938349 -78.048563) (xy 233.981217 -78.084238) (xy 234.018434 -78.125775)
			(xy 234.049207 -78.172288) (xy 234.072879 -78.222785) (xy 234.088947 -78.276192) (xy 234.097067 -78.331368)
			(xy 234.097576 -78.359254) (xy 234.097067 -78.38714) (xy 234.088947 -78.442316) (xy 234.072879 -78.495723)
			(xy 234.049207 -78.54622) (xy 234.018434 -78.592733) (xy 233.981217 -78.63427) (xy 233.938349 -78.669945)
			(xy 233.890743 -78.698999) (xy 233.839414 -78.720811) (xy 233.785457 -78.734917) (xy 233.73002 -78.741017)
			(xy 233.674286 -78.73898) (xy 233.619443 -78.72885) (xy 233.566659 -78.710843) (xy 233.517059 -78.685342)
			(xy 233.471701 -78.652891) (xy 233.431552 -78.614182) (xy 233.397466 -78.570039) (xy 233.37017 -78.521404)
			(xy 233.350247 -78.469313) (xy 233.338121 -78.414876) (xy 233.33405 -78.359254) (xy 232.846113 -78.359254)
			(xy 232.84598 -78.359407) (xy 232.804788 -78.395096) (xy 232.758936 -78.424559) (xy 232.709357 -78.447197)
			(xy 232.657061 -78.462548) (xy 232.603113 -78.470299) (xy 232.575862 -78.47076) (xy 232.549534 -78.470285)
			(xy 232.497381 -78.463027) (xy 232.446721 -78.448668) (xy 232.398516 -78.427481) (xy 232.353681 -78.399868)
			(xy 232.313068 -78.366353) (xy 232.277449 -78.327573) (xy 232.247499 -78.284264) (xy 232.235248 -78.260956)
			(xy 232.235248 -78.260702) (xy 232.22978 -78.251056) (xy 232.212376 -78.237355) (xy 232.20172 -78.234286)
			(xy 232.126282 -78.216252) (xy 232.115376 -78.214207) (xy 232.093642 -78.218538) (xy 232.084372 -78.224634)
			(xy 232.058441 -78.242836) (xy 232.00208 -78.271762) (xy 231.941874 -78.291473) (xy 231.879319 -78.30148)
			(xy 231.847644 -78.302104) (xy 231.819026 -78.301561) (xy 231.762372 -78.293425) (xy 231.707451 -78.277311)
			(xy 231.655382 -78.253547) (xy 231.607223 -78.222617) (xy 231.563955 -78.185151) (xy 231.526457 -78.141909)
			(xy 231.495492 -78.093773) (xy 231.471691 -78.041721) (xy 231.455537 -77.986812) (xy 231.447359 -77.930164)
			(xy 231.446832 -77.901546) (xy 231.446832 -77.897482) (xy 231.446209 -77.885066) (xy 231.434628 -77.863099)
			(xy 231.424734 -77.855572) (xy 231.344724 -77.800708) (xy 231.319324 -77.797914) (xy 231.30764 -77.80274)
			(xy 231.283957 -77.811743) (xy 231.2349 -77.824413) (xy 231.184637 -77.8308) (xy 231.159304 -77.831188)
			(xy 231.13066 -77.830721) (xy 231.073954 -77.822565) (xy 231.018988 -77.806418) (xy 230.966881 -77.78261)
			(xy 230.918694 -77.751626) (xy 230.87541 -77.714096) (xy 230.83791 -77.670786) (xy 230.806958 -77.622578)
			(xy 230.783186 -77.570455) (xy 230.767077 -77.515477) (xy 230.75896 -77.458767) (xy 230.758492 -77.430122)
			(xy 230.758598 -77.415208) (xy 230.760761 -77.385459) (xy 230.76281 -77.370686) (xy 230.764588 -77.35951)
			(xy 230.758492 -77.338428) (xy 230.700834 -77.271626) (xy 230.693239 -77.263663) (xy 230.67322 -77.254579)
			(xy 230.662226 -77.2541) (xy 230.397558 -77.2541) (xy 230.386566 -77.254582) (xy 230.366554 -77.263674)
			(xy 230.35895 -77.271626) (xy 230.301292 -77.338428) (xy 230.295196 -77.35951) (xy 230.296974 -77.370686)
			(xy 230.299027 -77.385458) (xy 230.301185 -77.415208) (xy 230.301292 -77.430122) (xy 230.300781 -77.458752)
			(xy 230.292632 -77.51543) (xy 230.2765 -77.57037) (xy 230.252714 -77.622456) (xy 230.221756 -77.670627)
			(xy 230.184259 -77.713901) (xy 230.140985 -77.751398) (xy 230.092814 -77.782356) (xy 230.040728 -77.806142)
			(xy 229.985788 -77.822274) (xy 229.92911 -77.830423) (xy 229.87185 -77.830423) (xy 229.815172 -77.822274)
			(xy 229.760232 -77.806142) (xy 229.708146 -77.782356) (xy 229.659975 -77.751398) (xy 229.616701 -77.713901)
			(xy 229.579204 -77.670627) (xy 229.548246 -77.622456) (xy 229.52446 -77.57037) (xy 229.508328 -77.51543)
			(xy 229.500179 -77.458752) (xy 229.499668 -77.430122) (xy 225.398955 -77.430122) (xy 225.414085 -77.48041)
			(xy 225.422205 -77.535586) (xy 225.422714 -77.563472) (xy 225.422205 -77.591358) (xy 225.414085 -77.646534)
			(xy 225.398017 -77.699941) (xy 225.374345 -77.750438) (xy 225.343572 -77.796951) (xy 225.306355 -77.838488)
			(xy 225.263487 -77.874163) (xy 225.215881 -77.903217) (xy 225.164552 -77.925029) (xy 225.110595 -77.939135)
			(xy 225.055158 -77.945235) (xy 224.999424 -77.943198) (xy 224.944581 -77.933068) (xy 224.891797 -77.915061)
			(xy 224.842197 -77.88956) (xy 224.796839 -77.857109) (xy 224.75669 -77.8184) (xy 224.722604 -77.774257)
			(xy 224.695308 -77.725622) (xy 224.675385 -77.673531) (xy 224.663259 -77.619094) (xy 224.659188 -77.563472)
			(xy 223.387666 -77.563472) (xy 223.38718 -77.590723) (xy 223.379424 -77.644671) (xy 223.364069 -77.696966)
			(xy 223.341427 -77.746543) (xy 223.311961 -77.792393) (xy 223.27627 -77.833584) (xy 223.235079 -77.869275)
			(xy 223.189229 -77.898741) (xy 223.139652 -77.921383) (xy 223.087357 -77.936738) (xy 223.033409 -77.944494)
			(xy 222.978907 -77.944494) (xy 222.924959 -77.936738) (xy 222.872664 -77.921383) (xy 222.823087 -77.898741)
			(xy 222.777237 -77.869275) (xy 222.736046 -77.833584) (xy 222.700355 -77.792393) (xy 222.670889 -77.746543)
			(xy 222.648247 -77.696966) (xy 222.632892 -77.644671) (xy 222.625136 -77.590723) (xy 222.62465 -77.563472)
			(xy 222.62465 -77.562964) (xy 222.625048 -77.538614) (xy 222.631261 -77.490311) (xy 222.643581 -77.443195)
			(xy 222.652336 -77.42047) (xy 222.657162 -77.40904) (xy 222.654622 -77.383894) (xy 222.601536 -77.303884)
			(xy 222.594207 -77.293872) (xy 222.572512 -77.281888) (xy 222.560134 -77.281024) (xy 222.55988 -77.281024)
			(xy 222.532938 -77.280126) (xy 222.479709 -77.271601) (xy 222.428209 -77.25567) (xy 222.379464 -77.232651)
			(xy 222.334443 -77.203) (xy 222.294043 -77.16731) (xy 222.259068 -77.126289) (xy 222.230213 -77.080754)
			(xy 222.208053 -77.031612) (xy 222.19303 -76.97984) (xy 222.185441 -76.92647) (xy 222.184976 -76.899516)
			(xy 221.881623 -76.899516) (xy 221.873966 -76.952775) (xy 221.858611 -77.00507) (xy 221.835969 -77.054647)
			(xy 221.806503 -77.100497) (xy 221.770812 -77.141688) (xy 221.729621 -77.177379) (xy 221.683771 -77.206845)
			(xy 221.634194 -77.229487) (xy 221.581899 -77.244842) (xy 221.527951 -77.252598) (xy 221.473449 -77.252598)
			(xy 221.419501 -77.244842) (xy 221.367206 -77.229487) (xy 221.317629 -77.206845) (xy 221.271779 -77.177379)
			(xy 221.230588 -77.141688) (xy 221.194897 -77.100497) (xy 221.165431 -77.054647) (xy 221.142789 -77.00507)
			(xy 221.127434 -76.952775) (xy 221.119678 -76.898827) (xy 221.119192 -76.871576) (xy 205.002842 -76.871576)
			(xy 204.976957 -76.900466) (xy 204.934089 -76.936141) (xy 204.886483 -76.965195) (xy 204.835154 -76.987007)
			(xy 204.781197 -77.001113) (xy 204.72576 -77.007213) (xy 204.670026 -77.005176) (xy 204.615183 -76.995046)
			(xy 204.562399 -76.977039) (xy 204.512799 -76.951538) (xy 204.467441 -76.919087) (xy 204.427292 -76.880378)
			(xy 204.393206 -76.836235) (xy 204.36591 -76.7876) (xy 204.345987 -76.735509) (xy 204.333861 -76.681072)
			(xy 204.32979 -76.62545) (xy 199.605392 -76.62545) (xy 200.27392 -77.293978) (xy 200.284588 -77.305408)
			(xy 200.287128 -77.307948) (xy 200.308718 -77.328776) (xy 200.31238 -77.332546) (xy 200.318276 -77.341242)
			(xy 200.320402 -77.346048) (xy 200.331832 -77.373988) (xy 200.333102 -77.376782) (xy 200.337478 -77.386071)
			(xy 200.345102 -77.405138) (xy 200.348342 -77.414882) (xy 200.349612 -77.418438) (xy 200.35901 -77.441806)
			(xy 200.360768 -77.446372) (xy 200.362684 -77.455965) (xy 200.36282 -77.460856) (xy 200.36282 -77.48524)
			(xy 200.363074 -77.48905) (xy 200.363836 -77.510386) (xy 200.363836 -77.563472) (xy 205.228442 -77.563472)
			(xy 205.232513 -77.50785) (xy 205.244639 -77.453413) (xy 205.264562 -77.401322) (xy 205.291858 -77.352687)
			(xy 205.325944 -77.308544) (xy 205.366093 -77.269835) (xy 205.411451 -77.237384) (xy 205.461051 -77.211883)
			(xy 205.513835 -77.193876) (xy 205.568678 -77.183746) (xy 205.624412 -77.181709) (xy 205.679849 -77.187809)
			(xy 205.733806 -77.201915) (xy 205.785135 -77.223727) (xy 205.832741 -77.252781) (xy 205.875609 -77.288456)
			(xy 205.912826 -77.329993) (xy 205.943599 -77.376506) (xy 205.967271 -77.427003) (xy 205.983339 -77.48041)
			(xy 205.991459 -77.535586) (xy 205.991968 -77.563472) (xy 207.251806 -77.563472) (xy 207.255877 -77.50785)
			(xy 207.268003 -77.453413) (xy 207.287926 -77.401322) (xy 207.315222 -77.352687) (xy 207.349308 -77.308544)
			(xy 207.389457 -77.269835) (xy 207.434815 -77.237384) (xy 207.484415 -77.211883) (xy 207.537199 -77.193876)
			(xy 207.592042 -77.183746) (xy 207.647776 -77.181709) (xy 207.703213 -77.187809) (xy 207.75717 -77.201915)
			(xy 207.808499 -77.223727) (xy 207.856105 -77.252781) (xy 207.898973 -77.288456) (xy 207.93619 -77.329993)
			(xy 207.966963 -77.376506) (xy 207.990635 -77.427003) (xy 208.006703 -77.48041) (xy 208.013582 -77.52715)
			(xy 209.36915 -77.52715) (xy 209.373221 -77.471528) (xy 209.385347 -77.417091) (xy 209.40527 -77.365)
			(xy 209.432566 -77.316365) (xy 209.466652 -77.272222) (xy 209.506801 -77.233513) (xy 209.552159 -77.201062)
			(xy 209.601759 -77.175561) (xy 209.654543 -77.157554) (xy 209.709386 -77.147424) (xy 209.76512 -77.145387)
			(xy 209.820557 -77.151487) (xy 209.874514 -77.165593) (xy 209.925843 -77.187405) (xy 209.973449 -77.216459)
			(xy 210.016317 -77.252134) (xy 210.053534 -77.293671) (xy 210.084307 -77.340184) (xy 210.107979 -77.390681)
			(xy 210.124047 -77.444088) (xy 210.132167 -77.499264) (xy 210.132676 -77.52715) (xy 210.132167 -77.555036)
			(xy 210.130926 -77.563472) (xy 220.578678 -77.563472) (xy 220.582749 -77.50785) (xy 220.594875 -77.453413)
			(xy 220.614798 -77.401322) (xy 220.642094 -77.352687) (xy 220.67618 -77.308544) (xy 220.716329 -77.269835)
			(xy 220.761687 -77.237384) (xy 220.811287 -77.211883) (xy 220.864071 -77.193876) (xy 220.918914 -77.183746)
			(xy 220.974648 -77.181709) (xy 221.030085 -77.187809) (xy 221.084042 -77.201915) (xy 221.135371 -77.223727)
			(xy 221.182977 -77.252781) (xy 221.225845 -77.288456) (xy 221.263062 -77.329993) (xy 221.293835 -77.376506)
			(xy 221.317507 -77.427003) (xy 221.333575 -77.48041) (xy 221.341695 -77.535586) (xy 221.342204 -77.563472)
			(xy 221.341695 -77.591358) (xy 221.333575 -77.646534) (xy 221.317507 -77.699941) (xy 221.293835 -77.750438)
			(xy 221.263062 -77.796951) (xy 221.225845 -77.838488) (xy 221.182977 -77.874163) (xy 221.135371 -77.903217)
			(xy 221.084042 -77.925029) (xy 221.030085 -77.939135) (xy 220.974648 -77.945235) (xy 220.918914 -77.943198)
			(xy 220.864071 -77.933068) (xy 220.811287 -77.915061) (xy 220.761687 -77.88956) (xy 220.716329 -77.857109)
			(xy 220.67618 -77.8184) (xy 220.642094 -77.774257) (xy 220.614798 -77.725622) (xy 220.594875 -77.673531)
			(xy 220.582749 -77.619094) (xy 220.578678 -77.563472) (xy 210.130926 -77.563472) (xy 210.124047 -77.610212)
			(xy 210.107979 -77.663619) (xy 210.084307 -77.714116) (xy 210.053534 -77.760629) (xy 210.016317 -77.802166)
			(xy 209.973449 -77.837841) (xy 209.925843 -77.866895) (xy 209.874514 -77.888707) (xy 209.820557 -77.902813)
			(xy 209.76512 -77.908913) (xy 209.709386 -77.906876) (xy 209.654543 -77.896746) (xy 209.601759 -77.878739)
			(xy 209.552159 -77.853238) (xy 209.506801 -77.820787) (xy 209.466652 -77.782078) (xy 209.432566 -77.737935)
			(xy 209.40527 -77.6893) (xy 209.385347 -77.637209) (xy 209.373221 -77.582772) (xy 209.36915 -77.52715)
			(xy 208.013582 -77.52715) (xy 208.014823 -77.535586) (xy 208.015332 -77.563472) (xy 208.014823 -77.591358)
			(xy 208.006703 -77.646534) (xy 207.990635 -77.699941) (xy 207.966963 -77.750438) (xy 207.93619 -77.796951)
			(xy 207.898973 -77.838488) (xy 207.856105 -77.874163) (xy 207.808499 -77.903217) (xy 207.75717 -77.925029)
			(xy 207.703213 -77.939135) (xy 207.647776 -77.945235) (xy 207.592042 -77.943198) (xy 207.537199 -77.933068)
			(xy 207.484415 -77.915061) (xy 207.434815 -77.88956) (xy 207.389457 -77.857109) (xy 207.349308 -77.8184)
			(xy 207.315222 -77.774257) (xy 207.287926 -77.725622) (xy 207.268003 -77.673531) (xy 207.255877 -77.619094)
			(xy 207.251806 -77.563472) (xy 205.991968 -77.563472) (xy 205.991459 -77.591358) (xy 205.983339 -77.646534)
			(xy 205.967271 -77.699941) (xy 205.943599 -77.750438) (xy 205.912826 -77.796951) (xy 205.875609 -77.838488)
			(xy 205.832741 -77.874163) (xy 205.785135 -77.903217) (xy 205.733806 -77.925029) (xy 205.679849 -77.939135)
			(xy 205.624412 -77.945235) (xy 205.568678 -77.943198) (xy 205.513835 -77.933068) (xy 205.461051 -77.915061)
			(xy 205.411451 -77.88956) (xy 205.366093 -77.857109) (xy 205.325944 -77.8184) (xy 205.291858 -77.774257)
			(xy 205.264562 -77.725622) (xy 205.244639 -77.673531) (xy 205.232513 -77.619094) (xy 205.228442 -77.563472)
			(xy 200.363836 -77.563472) (xy 200.363836 -78.893416) (xy 205.222856 -78.893416) (xy 205.223342 -78.866165)
			(xy 205.231098 -78.812217) (xy 205.246453 -78.759922) (xy 205.269095 -78.710345) (xy 205.298561 -78.664495)
			(xy 205.334252 -78.623304) (xy 205.375443 -78.587613) (xy 205.421293 -78.558147) (xy 205.47087 -78.535505)
			(xy 205.523165 -78.52015) (xy 205.577113 -78.512394) (xy 205.631615 -78.512394) (xy 205.685563 -78.52015)
			(xy 205.737858 -78.535505) (xy 205.787435 -78.558147) (xy 205.820617 -78.579472) (xy 208.52714 -78.579472)
			(xy 208.531211 -78.52385) (xy 208.543337 -78.469413) (xy 208.56326 -78.417322) (xy 208.590556 -78.368687)
			(xy 208.624642 -78.324544) (xy 208.664791 -78.285835) (xy 208.710149 -78.253384) (xy 208.759749 -78.227883)
			(xy 208.812533 -78.209876) (xy 208.867376 -78.199746) (xy 208.92311 -78.197709) (xy 208.978547 -78.203809)
			(xy 209.032504 -78.217915) (xy 209.083833 -78.239727) (xy 209.131439 -78.268781) (xy 209.174307 -78.304456)
			(xy 209.211524 -78.345993) (xy 209.242297 -78.392506) (xy 209.265969 -78.443003) (xy 209.282037 -78.49641)
			(xy 209.290157 -78.551586) (xy 209.290666 -78.579472) (xy 218.929202 -78.579472) (xy 218.933273 -78.52385)
			(xy 218.945399 -78.469413) (xy 218.965322 -78.417322) (xy 218.992618 -78.368687) (xy 219.026704 -78.324544)
			(xy 219.066853 -78.285835) (xy 219.112211 -78.253384) (xy 219.161811 -78.227883) (xy 219.214595 -78.209876)
			(xy 219.269438 -78.199746) (xy 219.325172 -78.197709) (xy 219.380609 -78.203809) (xy 219.434566 -78.217915)
			(xy 219.485895 -78.239727) (xy 219.533501 -78.268781) (xy 219.576369 -78.304456) (xy 219.613586 -78.345993)
			(xy 219.644359 -78.392506) (xy 219.668031 -78.443003) (xy 219.684099 -78.49641) (xy 219.692219 -78.551586)
			(xy 219.692728 -78.579472) (xy 222.62414 -78.579472) (xy 222.628211 -78.52385) (xy 222.640337 -78.469413)
			(xy 222.66026 -78.417322) (xy 222.687556 -78.368687) (xy 222.721642 -78.324544) (xy 222.761791 -78.285835)
			(xy 222.807149 -78.253384) (xy 222.856749 -78.227883) (xy 222.909533 -78.209876) (xy 222.964376 -78.199746)
			(xy 223.02011 -78.197709) (xy 223.075547 -78.203809) (xy 223.129504 -78.217915) (xy 223.180833 -78.239727)
			(xy 223.228439 -78.268781) (xy 223.271307 -78.304456) (xy 223.308524 -78.345993) (xy 223.339297 -78.392506)
			(xy 223.362969 -78.443003) (xy 223.379037 -78.49641) (xy 223.387157 -78.551586) (xy 223.387666 -78.579472)
			(xy 224.659188 -78.579472) (xy 224.663259 -78.52385) (xy 224.675385 -78.469413) (xy 224.695308 -78.417322)
			(xy 224.722604 -78.368687) (xy 224.75669 -78.324544) (xy 224.796839 -78.285835) (xy 224.842197 -78.253384)
			(xy 224.891797 -78.227883) (xy 224.944581 -78.209876) (xy 224.999424 -78.199746) (xy 225.055158 -78.197709)
			(xy 225.110595 -78.203809) (xy 225.164552 -78.217915) (xy 225.215881 -78.239727) (xy 225.263487 -78.268781)
			(xy 225.306355 -78.304456) (xy 225.343572 -78.345993) (xy 225.374345 -78.392506) (xy 225.398017 -78.443003)
			(xy 225.414085 -78.49641) (xy 225.422205 -78.551586) (xy 225.422714 -78.579472) (xy 225.422205 -78.607358)
			(xy 225.414085 -78.662534) (xy 225.398017 -78.715941) (xy 225.374345 -78.766438) (xy 225.343572 -78.812951)
			(xy 225.306355 -78.854488) (xy 225.263487 -78.890163) (xy 225.215881 -78.919217) (xy 225.164552 -78.941029)
			(xy 225.110595 -78.955135) (xy 225.055158 -78.961235) (xy 224.999424 -78.959198) (xy 224.944581 -78.949068)
			(xy 224.891797 -78.931061) (xy 224.842197 -78.90556) (xy 224.796839 -78.873109) (xy 224.75669 -78.8344)
			(xy 224.722604 -78.790257) (xy 224.695308 -78.741622) (xy 224.675385 -78.689531) (xy 224.663259 -78.635094)
			(xy 224.659188 -78.579472) (xy 223.387666 -78.579472) (xy 223.387157 -78.607358) (xy 223.379037 -78.662534)
			(xy 223.362969 -78.715941) (xy 223.339297 -78.766438) (xy 223.308524 -78.812951) (xy 223.271307 -78.854488)
			(xy 223.228439 -78.890163) (xy 223.180833 -78.919217) (xy 223.129504 -78.941029) (xy 223.075547 -78.955135)
			(xy 223.02011 -78.961235) (xy 222.964376 -78.959198) (xy 222.909533 -78.949068) (xy 222.856749 -78.931061)
			(xy 222.807149 -78.90556) (xy 222.761791 -78.873109) (xy 222.721642 -78.8344) (xy 222.687556 -78.790257)
			(xy 222.66026 -78.741622) (xy 222.640337 -78.689531) (xy 222.628211 -78.635094) (xy 222.62414 -78.579472)
			(xy 219.692728 -78.579472) (xy 219.692219 -78.607358) (xy 219.684099 -78.662534) (xy 219.668031 -78.715941)
			(xy 219.644359 -78.766438) (xy 219.613586 -78.812951) (xy 219.576369 -78.854488) (xy 219.533501 -78.890163)
			(xy 219.485895 -78.919217) (xy 219.434566 -78.941029) (xy 219.380609 -78.955135) (xy 219.325172 -78.961235)
			(xy 219.269438 -78.959198) (xy 219.214595 -78.949068) (xy 219.161811 -78.931061) (xy 219.112211 -78.90556)
			(xy 219.066853 -78.873109) (xy 219.026704 -78.8344) (xy 218.992618 -78.790257) (xy 218.965322 -78.741622)
			(xy 218.945399 -78.689531) (xy 218.933273 -78.635094) (xy 218.929202 -78.579472) (xy 209.290666 -78.579472)
			(xy 209.290157 -78.607358) (xy 209.282037 -78.662534) (xy 209.265969 -78.715941) (xy 209.242297 -78.766438)
			(xy 209.211524 -78.812951) (xy 209.174307 -78.854488) (xy 209.131439 -78.890163) (xy 209.083833 -78.919217)
			(xy 209.032504 -78.941029) (xy 208.978547 -78.955135) (xy 208.92311 -78.961235) (xy 208.867376 -78.959198)
			(xy 208.812533 -78.949068) (xy 208.759749 -78.931061) (xy 208.710149 -78.90556) (xy 208.664791 -78.873109)
			(xy 208.624642 -78.8344) (xy 208.590556 -78.790257) (xy 208.56326 -78.741622) (xy 208.543337 -78.689531)
			(xy 208.531211 -78.635094) (xy 208.52714 -78.579472) (xy 205.820617 -78.579472) (xy 205.833285 -78.587613)
			(xy 205.874476 -78.623304) (xy 205.910167 -78.664495) (xy 205.939633 -78.710345) (xy 205.962275 -78.759922)
			(xy 205.97763 -78.812217) (xy 205.985386 -78.866165) (xy 205.985872 -78.893416) (xy 205.985368 -78.920818)
			(xy 205.977525 -78.975057) (xy 205.962002 -79.027617) (xy 205.939119 -79.077414) (xy 205.909346 -79.123425)
			(xy 205.873296 -79.164703) (xy 205.831712 -79.200399) (xy 205.808834 -79.215488) (xy 205.796619 -79.223762)
			(xy 205.77725 -79.246004) (xy 205.765038 -79.27285) (xy 205.761002 -79.302066) (xy 205.765476 -79.331218)
			(xy 205.778088 -79.357878) (xy 205.797789 -79.379827) (xy 205.810104 -79.387954) (xy 205.833506 -79.402938)
			(xy 205.876109 -79.438611) (xy 205.913087 -79.480087) (xy 205.943657 -79.526489) (xy 205.967172 -79.576835)
			(xy 205.972761 -79.595472) (xy 207.251806 -79.595472) (xy 207.255877 -79.53985) (xy 207.268003 -79.485413)
			(xy 207.287926 -79.433322) (xy 207.315222 -79.384687) (xy 207.349308 -79.340544) (xy 207.389457 -79.301835)
			(xy 207.434815 -79.269384) (xy 207.484415 -79.243883) (xy 207.537199 -79.225876) (xy 207.592042 -79.215746)
			(xy 207.647776 -79.213709) (xy 207.703213 -79.219809) (xy 207.75717 -79.233915) (xy 207.808499 -79.255727)
			(xy 207.856105 -79.284781) (xy 207.898973 -79.320456) (xy 207.93619 -79.361993) (xy 207.966963 -79.408506)
			(xy 207.990635 -79.459003) (xy 208.006703 -79.51241) (xy 208.014823 -79.567586) (xy 208.015332 -79.595472)
			(xy 220.578678 -79.595472) (xy 220.582749 -79.53985) (xy 220.594875 -79.485413) (xy 220.614798 -79.433322)
			(xy 220.642094 -79.384687) (xy 220.67618 -79.340544) (xy 220.716329 -79.301835) (xy 220.761687 -79.269384)
			(xy 220.811287 -79.243883) (xy 220.864071 -79.225876) (xy 220.918914 -79.215746) (xy 220.974648 -79.213709)
			(xy 221.030085 -79.219809) (xy 221.084042 -79.233915) (xy 221.135371 -79.255727) (xy 221.182977 -79.284781)
			(xy 221.225845 -79.320456) (xy 221.263062 -79.361993) (xy 221.293835 -79.408506) (xy 221.317507 -79.459003)
			(xy 221.333575 -79.51241) (xy 221.341695 -79.567586) (xy 221.342204 -79.595472) (xy 222.62414 -79.595472)
			(xy 222.628211 -79.53985) (xy 222.640337 -79.485413) (xy 222.66026 -79.433322) (xy 222.687556 -79.384687)
			(xy 222.721642 -79.340544) (xy 222.761791 -79.301835) (xy 222.807149 -79.269384) (xy 222.856749 -79.243883)
			(xy 222.909533 -79.225876) (xy 222.964376 -79.215746) (xy 223.02011 -79.213709) (xy 223.075547 -79.219809)
			(xy 223.129504 -79.233915) (xy 223.180833 -79.255727) (xy 223.228439 -79.284781) (xy 223.271307 -79.320456)
			(xy 223.308524 -79.361993) (xy 223.339297 -79.408506) (xy 223.362969 -79.459003) (xy 223.379037 -79.51241)
			(xy 223.387157 -79.567586) (xy 223.387666 -79.595472) (xy 224.659188 -79.595472) (xy 224.663259 -79.53985)
			(xy 224.675385 -79.485413) (xy 224.695308 -79.433322) (xy 224.722604 -79.384687) (xy 224.75669 -79.340544)
			(xy 224.796839 -79.301835) (xy 224.842197 -79.269384) (xy 224.891797 -79.243883) (xy 224.944581 -79.225876)
			(xy 224.999424 -79.215746) (xy 225.055158 -79.213709) (xy 225.110595 -79.219809) (xy 225.164552 -79.233915)
			(xy 225.175582 -79.238602) (xy 227.9777 -79.238602) (xy 227.9777 -78.374494) (xy 227.978222 -78.344522)
			(xy 227.986043 -78.28509) (xy 228.001553 -78.227186) (xy 228.024484 -78.171801) (xy 228.054446 -78.119882)
			(xy 228.090926 -78.072315) (xy 228.1333 -78.029914) (xy 228.180843 -77.993405) (xy 228.232744 -77.963411)
			(xy 228.288115 -77.940445) (xy 228.346009 -77.924899) (xy 228.405436 -77.91704) (xy 228.435408 -77.916532)
			(xy 228.462917 -77.91697) (xy 228.517531 -77.923622) (xy 228.570956 -77.93677) (xy 228.62242 -77.956224)
			(xy 228.64699 -77.968602) (xy 228.65539 -77.972465) (xy 228.67375 -77.97454) (xy 228.682804 -77.972666)
			(xy 228.712522 -77.9653) (xy 228.721282 -77.962817) (xy 228.736382 -77.952665) (xy 228.741986 -77.945488)
			(xy 228.758156 -77.923385) (xy 228.795529 -77.883354) (xy 228.838005 -77.848786) (xy 228.884794 -77.820325)
			(xy 228.935022 -77.798502) (xy 228.987755 -77.783723) (xy 229.04201 -77.776263) (xy 229.069392 -77.775816)
			(xy 229.098026 -77.776246) (xy 229.154712 -77.784395) (xy 229.209661 -77.800529) (xy 229.261754 -77.824318)
			(xy 229.309932 -77.855279) (xy 229.353213 -77.892781) (xy 229.390716 -77.936062) (xy 229.421678 -77.984239)
			(xy 229.445468 -78.036332) (xy 229.461603 -78.09128) (xy 229.469753 -78.147966) (xy 229.469753 -78.205234)
			(xy 229.461603 -78.26192) (xy 229.445468 -78.316868) (xy 229.421678 -78.368961) (xy 229.390716 -78.417138)
			(xy 229.353213 -78.460419) (xy 229.309932 -78.497921) (xy 229.261754 -78.528882) (xy 229.209661 -78.552671)
			(xy 229.154712 -78.568805) (xy 229.098026 -78.576954) (xy 229.069392 -78.57744) (xy 229.054478 -78.577326)
			(xy 229.024729 -78.575168) (xy 229.009956 -78.573122) (xy 228.99878 -78.571344) (xy 228.977698 -78.57744)
			(xy 228.910642 -78.635098) (xy 228.902667 -78.642683) (xy 228.893589 -78.662709) (xy 228.893116 -78.673706)
			(xy 228.893116 -78.958186) (xy 228.893657 -78.969205) (xy 228.902874 -78.989222) (xy 228.910896 -78.996794)
			(xy 228.92132 -79.005684) (xy 231.53446 -79.005684) (xy 231.538531 -78.950062) (xy 231.550657 -78.895625)
			(xy 231.57058 -78.843534) (xy 231.597876 -78.794899) (xy 231.631962 -78.750756) (xy 231.672111 -78.712047)
			(xy 231.717469 -78.679596) (xy 231.767069 -78.654095) (xy 231.819853 -78.636088) (xy 231.874696 -78.625958)
			(xy 231.93043 -78.623921) (xy 231.985867 -78.630021) (xy 232.039824 -78.644127) (xy 232.091153 -78.665939)
			(xy 232.138759 -78.694993) (xy 232.181627 -78.730668) (xy 232.218844 -78.772205) (xy 232.249617 -78.818718)
			(xy 232.273289 -78.869215) (xy 232.289357 -78.922622) (xy 232.297477 -78.977798) (xy 232.297986 -79.005684)
			(xy 232.297477 -79.03357) (xy 232.289357 -79.088746) (xy 232.273289 -79.142153) (xy 232.249617 -79.19265)
			(xy 232.218844 -79.239163) (xy 232.181627 -79.2807) (xy 232.138759 -79.316375) (xy 232.091153 -79.345429)
			(xy 232.039824 -79.367241) (xy 231.985867 -79.381347) (xy 231.93043 -79.387447) (xy 231.874696 -79.38541)
			(xy 231.819853 -79.37528) (xy 231.767069 -79.357273) (xy 231.717469 -79.331772) (xy 231.672111 -79.299321)
			(xy 231.631962 -79.260612) (xy 231.597876 -79.216469) (xy 231.57058 -79.167834) (xy 231.550657 -79.115743)
			(xy 231.538531 -79.061306) (xy 231.53446 -79.005684) (xy 228.92132 -79.005684) (xy 228.96957 -79.046832)
			(xy 228.978287 -79.05361) (xy 228.999486 -79.059686) (xy 229.010464 -79.058516) (xy 229.025102 -79.056373)
			(xy 229.054599 -79.054086) (xy 229.069392 -79.053944) (xy 229.096642 -79.054503) (xy 229.150587 -79.062258)
			(xy 229.202879 -79.077611) (xy 229.252454 -79.10025) (xy 229.298302 -79.129714) (xy 229.339491 -79.165404)
			(xy 229.375181 -79.206591) (xy 229.404646 -79.252439) (xy 229.427286 -79.302013) (xy 229.442641 -79.354305)
			(xy 229.450397 -79.40825) (xy 229.450397 -79.46275) (xy 229.442641 -79.516695) (xy 229.427286 -79.568987)
			(xy 229.404646 -79.618561) (xy 229.375181 -79.664409) (xy 229.339491 -79.705596) (xy 229.298302 -79.741286)
			(xy 229.252454 -79.77075) (xy 229.202879 -79.793389) (xy 229.150587 -79.808742) (xy 229.096642 -79.816497)
			(xy 229.069392 -79.81696) (xy 229.043484 -79.816494) (xy 228.992147 -79.809468) (xy 228.942233 -79.795562)
			(xy 228.894659 -79.775029) (xy 228.850301 -79.748249) (xy 228.809974 -79.715713) (xy 228.77442 -79.67802)
			(xy 228.759004 -79.657194) (xy 228.753182 -79.649861) (xy 228.737563 -79.639565) (xy 228.728524 -79.637128)
			(xy 228.698552 -79.63027) (xy 228.689251 -79.628618) (xy 228.670594 -79.631471) (xy 228.66223 -79.635858)
			(xy 228.636206 -79.650126) (xy 228.581288 -79.672626) (xy 228.523928 -79.687856) (xy 228.465082 -79.695562)
			(xy 228.435408 -79.696056) (xy 228.405453 -79.695511) (xy 228.346055 -79.687696) (xy 228.288185 -79.672197)
			(xy 228.232831 -79.649281) (xy 228.180941 -79.619338) (xy 228.133401 -79.582881) (xy 228.091024 -79.540532)
			(xy 228.054535 -79.493017) (xy 228.024557 -79.441147) (xy 228.001603 -79.385809) (xy 227.986065 -79.327949)
			(xy 227.978209 -79.268557) (xy 227.9777 -79.238602) (xy 225.175582 -79.238602) (xy 225.215881 -79.255727)
			(xy 225.263487 -79.284781) (xy 225.306355 -79.320456) (xy 225.343572 -79.361993) (xy 225.374345 -79.408506)
			(xy 225.398017 -79.459003) (xy 225.414085 -79.51241) (xy 225.422205 -79.567586) (xy 225.422714 -79.595472)
			(xy 225.422205 -79.623358) (xy 225.414085 -79.678534) (xy 225.398017 -79.731941) (xy 225.374345 -79.782438)
			(xy 225.343572 -79.828951) (xy 225.306355 -79.870488) (xy 225.263487 -79.906163) (xy 225.215881 -79.935217)
			(xy 225.164552 -79.957029) (xy 225.110595 -79.971135) (xy 225.055158 -79.977235) (xy 224.999424 -79.975198)
			(xy 224.944581 -79.965068) (xy 224.891797 -79.947061) (xy 224.842197 -79.92156) (xy 224.796839 -79.889109)
			(xy 224.75669 -79.8504) (xy 224.722604 -79.806257) (xy 224.695308 -79.757622) (xy 224.675385 -79.705531)
			(xy 224.663259 -79.651094) (xy 224.659188 -79.595472) (xy 223.387666 -79.595472) (xy 223.387157 -79.623358)
			(xy 223.379037 -79.678534) (xy 223.362969 -79.731941) (xy 223.339297 -79.782438) (xy 223.308524 -79.828951)
			(xy 223.271307 -79.870488) (xy 223.228439 -79.906163) (xy 223.180833 -79.935217) (xy 223.129504 -79.957029)
			(xy 223.075547 -79.971135) (xy 223.02011 -79.977235) (xy 222.964376 -79.975198) (xy 222.909533 -79.965068)
			(xy 222.856749 -79.947061) (xy 222.807149 -79.92156) (xy 222.761791 -79.889109) (xy 222.721642 -79.8504)
			(xy 222.687556 -79.806257) (xy 222.66026 -79.757622) (xy 222.640337 -79.705531) (xy 222.628211 -79.651094)
			(xy 222.62414 -79.595472) (xy 221.342204 -79.595472) (xy 221.341695 -79.623358) (xy 221.333575 -79.678534)
			(xy 221.317507 -79.731941) (xy 221.293835 -79.782438) (xy 221.263062 -79.828951) (xy 221.225845 -79.870488)
			(xy 221.182977 -79.906163) (xy 221.135371 -79.935217) (xy 221.084042 -79.957029) (xy 221.030085 -79.971135)
			(xy 220.974648 -79.977235) (xy 220.918914 -79.975198) (xy 220.864071 -79.965068) (xy 220.811287 -79.947061)
			(xy 220.761687 -79.92156) (xy 220.716329 -79.889109) (xy 220.67618 -79.8504) (xy 220.642094 -79.806257)
			(xy 220.614798 -79.757622) (xy 220.594875 -79.705531) (xy 220.582749 -79.651094) (xy 220.578678 -79.595472)
			(xy 208.015332 -79.595472) (xy 208.014823 -79.623358) (xy 208.006703 -79.678534) (xy 207.990635 -79.731941)
			(xy 207.966963 -79.782438) (xy 207.93619 -79.828951) (xy 207.898973 -79.870488) (xy 207.856105 -79.906163)
			(xy 207.808499 -79.935217) (xy 207.75717 -79.957029) (xy 207.703213 -79.971135) (xy 207.647776 -79.977235)
			(xy 207.592042 -79.975198) (xy 207.537199 -79.965068) (xy 207.484415 -79.947061) (xy 207.434815 -79.92156)
			(xy 207.389457 -79.889109) (xy 207.349308 -79.8504) (xy 207.315222 -79.806257) (xy 207.287926 -79.757622)
			(xy 207.268003 -79.705531) (xy 207.255877 -79.651094) (xy 207.251806 -79.595472) (xy 205.972761 -79.595472)
			(xy 205.983134 -79.63006) (xy 205.991207 -79.685037) (xy 205.991714 -79.71282) (xy 205.991228 -79.740071)
			(xy 205.983472 -79.794019) (xy 205.968117 -79.846314) (xy 205.945475 -79.895891) (xy 205.916009 -79.941741)
			(xy 205.880318 -79.982932) (xy 205.839127 -80.018623) (xy 205.793277 -80.048089) (xy 205.7437 -80.070731)
			(xy 205.691405 -80.086086) (xy 205.637457 -80.093842) (xy 205.582955 -80.093842) (xy 205.529007 -80.086086)
			(xy 205.476712 -80.070731) (xy 205.427135 -80.048089) (xy 205.381285 -80.018623) (xy 205.340094 -79.982932)
			(xy 205.304403 -79.941741) (xy 205.274937 -79.895891) (xy 205.252295 -79.846314) (xy 205.23694 -79.794019)
			(xy 205.229184 -79.740071) (xy 205.228698 -79.71282) (xy 205.22912 -79.685415) (xy 205.236974 -79.63117)
			(xy 205.252509 -79.578608) (xy 205.275405 -79.528809) (xy 205.305191 -79.482798) (xy 205.341254 -79.441523)
			(xy 205.382852 -79.405833) (xy 205.405736 -79.390748) (xy 205.417919 -79.382429) (xy 205.437292 -79.360199)
			(xy 205.449509 -79.333362) (xy 205.453552 -79.304153) (xy 205.449083 -79.275007) (xy 205.436475 -79.248351)
			(xy 205.416779 -79.226407) (xy 205.404466 -79.218282) (xy 205.381051 -79.203317) (xy 205.338444 -79.167644)
			(xy 205.301465 -79.126165) (xy 205.270895 -79.07976) (xy 205.247382 -79.02941) (xy 205.231425 -78.976181)
			(xy 205.223359 -78.921201) (xy 205.222856 -78.893416) (xy 200.363836 -78.893416) (xy 200.363836 -80.611472)
			(xy 205.228442 -80.611472) (xy 205.232513 -80.55585) (xy 205.244639 -80.501413) (xy 205.264562 -80.449322)
			(xy 205.291858 -80.400687) (xy 205.325944 -80.356544) (xy 205.366093 -80.317835) (xy 205.411451 -80.285384)
			(xy 205.461051 -80.259883) (xy 205.513835 -80.241876) (xy 205.568678 -80.231746) (xy 205.624412 -80.229709)
			(xy 205.679849 -80.235809) (xy 205.733806 -80.249915) (xy 205.785135 -80.271727) (xy 205.832741 -80.300781)
			(xy 205.875609 -80.336456) (xy 205.912826 -80.377993) (xy 205.943599 -80.424506) (xy 205.967271 -80.475003)
			(xy 205.977915 -80.51038) (xy 218.929202 -80.51038) (xy 218.933273 -80.454758) (xy 218.945399 -80.400321)
			(xy 218.965322 -80.34823) (xy 218.992618 -80.299595) (xy 219.026704 -80.255452) (xy 219.066853 -80.216743)
			(xy 219.112211 -80.184292) (xy 219.161811 -80.158791) (xy 219.214595 -80.140784) (xy 219.269438 -80.130654)
			(xy 219.325172 -80.128617) (xy 219.380609 -80.134717) (xy 219.434566 -80.148823) (xy 219.485895 -80.170635)
			(xy 219.507778 -80.18399) (xy 237.540292 -80.18399) (xy 237.540292 -79.319882) (xy 237.54081 -79.28991)
			(xy 237.548634 -79.230478) (xy 237.564144 -79.172575) (xy 237.587076 -79.11719) (xy 237.617038 -79.065271)
			(xy 237.653518 -79.017705) (xy 237.695893 -78.975305) (xy 237.743436 -78.938795) (xy 237.795337 -78.908801)
			(xy 237.850708 -78.885835) (xy 237.908601 -78.870289) (xy 237.968028 -78.862429) (xy 237.998 -78.86192)
			(xy 238.032717 -78.862605) (xy 238.101341 -78.873195) (xy 238.134652 -78.883002) (xy 238.145066 -78.886304)
			(xy 238.166656 -78.883764) (xy 238.25073 -78.832202) (xy 238.262922 -78.814422) (xy 238.264954 -78.803754)
			(xy 238.264954 -78.803246) (xy 238.270206 -78.775698) (xy 238.287447 -78.722334) (xy 238.311958 -78.671893)
			(xy 238.34326 -78.625362) (xy 238.380744 -78.583648) (xy 238.423675 -78.547566) (xy 238.471218 -78.517821)
			(xy 238.522442 -78.494993) (xy 238.576348 -78.479528) (xy 238.631884 -78.471728) (xy 238.659924 -78.471268)
			(xy 238.688574 -78.471712) (xy 238.745289 -78.47987) (xy 238.800267 -78.496016) (xy 238.852387 -78.519821)
			(xy 238.900589 -78.550801) (xy 238.943891 -78.588326) (xy 238.981413 -78.63163) (xy 239.012391 -78.679834)
			(xy 239.036193 -78.731956) (xy 239.052335 -78.786934) (xy 239.060489 -78.84365) (xy 239.060489 -78.90095)
			(xy 239.052335 -78.957666) (xy 239.036193 -79.012644) (xy 239.012391 -79.064766) (xy 238.981413 -79.11297)
			(xy 238.943891 -79.156274) (xy 238.900589 -79.193799) (xy 238.852387 -79.224779) (xy 238.800267 -79.248584)
			(xy 238.745289 -79.26473) (xy 238.688574 -79.272888) (xy 238.659924 -79.2734) (xy 238.631258 -79.27283)
			(xy 238.574527 -79.264539) (xy 238.546894 -79.25689) (xy 238.535439 -79.254118) (xy 238.51226 -79.258239)
			(xy 238.502444 -79.264764) (xy 238.455454 -79.299308) (xy 238.455708 -79.319628) (xy 238.455708 -79.320136)
			(xy 238.455708 -80.189324) (xy 238.456301 -80.201481) (xy 238.467157 -80.223224) (xy 238.476536 -80.23098)
			(xy 238.50219 -80.249776) (xy 238.512333 -80.256394) (xy 238.536205 -80.260249) (xy 238.54791 -80.257142)
			(xy 238.578018 -80.248019) (xy 238.640154 -80.238197) (xy 238.671608 -80.237584) (xy 238.671862 -80.237584)
			(xy 238.700495 -80.238076) (xy 238.75718 -80.246221) (xy 238.812128 -80.262351) (xy 238.864221 -80.286136)
			(xy 238.912398 -80.317094) (xy 238.95568 -80.354593) (xy 238.993183 -80.397871) (xy 239.024145 -80.446046)
			(xy 239.047936 -80.498137) (xy 239.064071 -80.553083) (xy 239.072221 -80.609767) (xy 239.072221 -80.667033)
			(xy 239.064071 -80.723717) (xy 239.053846 -80.758538) (xy 241.160044 -80.758538) (xy 241.164115 -80.702916)
			(xy 241.176241 -80.648479) (xy 241.196164 -80.596388) (xy 241.22346 -80.547753) (xy 241.257546 -80.50361)
			(xy 241.297695 -80.464901) (xy 241.343053 -80.43245) (xy 241.392653 -80.406949) (xy 241.445437 -80.388942)
			(xy 241.50028 -80.378812) (xy 241.556014 -80.376775) (xy 241.611451 -80.382875) (xy 241.665408 -80.396981)
			(xy 241.716737 -80.418793) (xy 241.764343 -80.447847) (xy 241.807211 -80.483522) (xy 241.844428 -80.525059)
			(xy 241.875201 -80.571572) (xy 241.898873 -80.622069) (xy 241.914941 -80.675476) (xy 241.923061 -80.730652)
			(xy 241.92357 -80.758538) (xy 241.923061 -80.786424) (xy 241.914941 -80.8416) (xy 241.898873 -80.895007)
			(xy 241.875201 -80.945504) (xy 241.844428 -80.992017) (xy 241.807211 -81.033554) (xy 241.764343 -81.069229)
			(xy 241.716737 -81.098283) (xy 241.665408 -81.120095) (xy 241.611451 -81.134201) (xy 241.556014 -81.140301)
			(xy 241.50028 -81.138264) (xy 241.445437 -81.128134) (xy 241.392653 -81.110127) (xy 241.343053 -81.084626)
			(xy 241.297695 -81.052175) (xy 241.257546 -81.013466) (xy 241.22346 -80.969323) (xy 241.196164 -80.920688)
			(xy 241.176241 -80.868597) (xy 241.164115 -80.81416) (xy 241.160044 -80.758538) (xy 239.053846 -80.758538)
			(xy 239.047936 -80.778663) (xy 239.024145 -80.830754) (xy 238.993183 -80.878929) (xy 238.95568 -80.922207)
			(xy 238.912398 -80.959706) (xy 238.864221 -80.990664) (xy 238.812128 -81.014449) (xy 238.75718 -81.030579)
			(xy 238.700495 -81.038724) (xy 238.671862 -81.039208) (xy 238.643405 -81.038669) (xy 238.587061 -81.030626)
			(xy 238.532422 -81.014692) (xy 238.480587 -80.991188) (xy 238.432599 -80.960587) (xy 238.389423 -80.923504)
			(xy 238.351927 -80.880687) (xy 238.320866 -80.832995) (xy 238.296865 -80.781388) (xy 238.280407 -80.726905)
			(xy 238.275622 -80.698848) (xy 238.27339 -80.68794) (xy 238.261156 -80.669368) (xy 238.252 -80.663034)
			(xy 238.176054 -80.616806) (xy 238.153702 -80.614266) (xy 238.143034 -80.617822) (xy 238.107782 -80.6288)
			(xy 238.034914 -80.640675) (xy 237.998 -80.641444) (xy 237.968044 -80.640919) (xy 237.908645 -80.633102)
			(xy 237.850774 -80.617602) (xy 237.79542 -80.594684) (xy 237.743529 -80.564739) (xy 237.695988 -80.52828)
			(xy 237.653611 -80.48593) (xy 237.617122 -80.438413) (xy 237.587145 -80.386541) (xy 237.564191 -80.331201)
			(xy 237.548655 -80.273339) (xy 237.5408 -80.213945) (xy 237.540292 -80.18399) (xy 219.507778 -80.18399)
			(xy 219.533501 -80.199689) (xy 219.576369 -80.235364) (xy 219.613586 -80.276901) (xy 219.644359 -80.323414)
			(xy 219.668031 -80.373911) (xy 219.684099 -80.427318) (xy 219.692219 -80.482494) (xy 219.692728 -80.51038)
			(xy 219.692219 -80.538266) (xy 219.684099 -80.593442) (xy 219.678675 -80.611472) (xy 222.62414 -80.611472)
			(xy 222.628211 -80.55585) (xy 222.640337 -80.501413) (xy 222.66026 -80.449322) (xy 222.687556 -80.400687)
			(xy 222.721642 -80.356544) (xy 222.761791 -80.317835) (xy 222.807149 -80.285384) (xy 222.856749 -80.259883)
			(xy 222.909533 -80.241876) (xy 222.964376 -80.231746) (xy 223.02011 -80.229709) (xy 223.075547 -80.235809)
			(xy 223.129504 -80.249915) (xy 223.180833 -80.271727) (xy 223.228439 -80.300781) (xy 223.271307 -80.336456)
			(xy 223.308524 -80.377993) (xy 223.339297 -80.424506) (xy 223.362969 -80.475003) (xy 223.379037 -80.52841)
			(xy 223.387157 -80.583586) (xy 223.387666 -80.611472) (xy 224.659188 -80.611472) (xy 224.663259 -80.55585)
			(xy 224.675385 -80.501413) (xy 224.695308 -80.449322) (xy 224.722604 -80.400687) (xy 224.75669 -80.356544)
			(xy 224.796839 -80.317835) (xy 224.842197 -80.285384) (xy 224.891797 -80.259883) (xy 224.944581 -80.241876)
			(xy 224.999424 -80.231746) (xy 225.055158 -80.229709) (xy 225.110595 -80.235809) (xy 225.164552 -80.249915)
			(xy 225.215881 -80.271727) (xy 225.263487 -80.300781) (xy 225.306355 -80.336456) (xy 225.343572 -80.377993)
			(xy 225.374345 -80.424506) (xy 225.398017 -80.475003) (xy 225.414085 -80.52841) (xy 225.422205 -80.583586)
			(xy 225.422714 -80.611472) (xy 225.422205 -80.639358) (xy 225.414085 -80.694534) (xy 225.398017 -80.747941)
			(xy 225.374345 -80.798438) (xy 225.343572 -80.844951) (xy 225.306355 -80.886488) (xy 225.263487 -80.922163)
			(xy 225.215881 -80.951217) (xy 225.164552 -80.973029) (xy 225.110595 -80.987135) (xy 225.055158 -80.993235)
			(xy 224.999424 -80.991198) (xy 224.944581 -80.981068) (xy 224.891797 -80.963061) (xy 224.842197 -80.93756)
			(xy 224.796839 -80.905109) (xy 224.75669 -80.8664) (xy 224.722604 -80.822257) (xy 224.695308 -80.773622)
			(xy 224.675385 -80.721531) (xy 224.663259 -80.667094) (xy 224.659188 -80.611472) (xy 223.387666 -80.611472)
			(xy 223.387157 -80.639358) (xy 223.379037 -80.694534) (xy 223.362969 -80.747941) (xy 223.339297 -80.798438)
			(xy 223.308524 -80.844951) (xy 223.271307 -80.886488) (xy 223.228439 -80.922163) (xy 223.180833 -80.951217)
			(xy 223.129504 -80.973029) (xy 223.075547 -80.987135) (xy 223.02011 -80.993235) (xy 222.964376 -80.991198)
			(xy 222.909533 -80.981068) (xy 222.856749 -80.963061) (xy 222.807149 -80.93756) (xy 222.761791 -80.905109)
			(xy 222.721642 -80.8664) (xy 222.687556 -80.822257) (xy 222.66026 -80.773622) (xy 222.640337 -80.721531)
			(xy 222.628211 -80.667094) (xy 222.62414 -80.611472) (xy 219.678675 -80.611472) (xy 219.668031 -80.646849)
			(xy 219.644359 -80.697346) (xy 219.613586 -80.743859) (xy 219.576369 -80.785396) (xy 219.533501 -80.821071)
			(xy 219.485895 -80.850125) (xy 219.434566 -80.871937) (xy 219.380609 -80.886043) (xy 219.325172 -80.892143)
			(xy 219.269438 -80.890106) (xy 219.214595 -80.879976) (xy 219.161811 -80.861969) (xy 219.112211 -80.836468)
			(xy 219.066853 -80.804017) (xy 219.026704 -80.765308) (xy 218.992618 -80.721165) (xy 218.965322 -80.67253)
			(xy 218.945399 -80.620439) (xy 218.933273 -80.566002) (xy 218.929202 -80.51038) (xy 205.977915 -80.51038)
			(xy 205.983339 -80.52841) (xy 205.991459 -80.583586) (xy 205.991968 -80.611472) (xy 205.991459 -80.639358)
			(xy 205.983339 -80.694534) (xy 205.967271 -80.747941) (xy 205.943599 -80.798438) (xy 205.912826 -80.844951)
			(xy 205.875609 -80.886488) (xy 205.832741 -80.922163) (xy 205.785135 -80.951217) (xy 205.733806 -80.973029)
			(xy 205.679849 -80.987135) (xy 205.624412 -80.993235) (xy 205.568678 -80.991198) (xy 205.513835 -80.981068)
			(xy 205.461051 -80.963061) (xy 205.411451 -80.93756) (xy 205.366093 -80.905109) (xy 205.325944 -80.8664)
			(xy 205.291858 -80.822257) (xy 205.264562 -80.773622) (xy 205.244639 -80.721531) (xy 205.232513 -80.667094)
			(xy 205.228442 -80.611472) (xy 200.363836 -80.611472) (xy 200.363836 -81.1784) (xy 207.161382 -81.1784)
			(xy 207.165453 -81.122778) (xy 207.177579 -81.068341) (xy 207.197502 -81.01625) (xy 207.224798 -80.967615)
			(xy 207.258884 -80.923472) (xy 207.299033 -80.884763) (xy 207.344391 -80.852312) (xy 207.393991 -80.826811)
			(xy 207.446775 -80.808804) (xy 207.501618 -80.798674) (xy 207.557352 -80.796637) (xy 207.612789 -80.802737)
			(xy 207.666746 -80.816843) (xy 207.718075 -80.838655) (xy 207.765681 -80.867709) (xy 207.808549 -80.903384)
			(xy 207.845766 -80.944921) (xy 207.876539 -80.991434) (xy 207.900211 -81.041931) (xy 207.916279 -81.095338)
			(xy 207.924399 -81.150514) (xy 207.924908 -81.1784) (xy 207.924537 -81.19872) (xy 240.342164 -81.19872)
			(xy 240.346235 -81.143098) (xy 240.358361 -81.088661) (xy 240.378284 -81.03657) (xy 240.40558 -80.987935)
			(xy 240.439666 -80.943792) (xy 240.479815 -80.905083) (xy 240.525173 -80.872632) (xy 240.574773 -80.847131)
			(xy 240.627557 -80.829124) (xy 240.6824 -80.818994) (xy 240.738134 -80.816957) (xy 240.793571 -80.823057)
			(xy 240.847528 -80.837163) (xy 240.898857 -80.858975) (xy 240.946463 -80.888029) (xy 240.989331 -80.923704)
			(xy 241.026548 -80.965241) (xy 241.057321 -81.011754) (xy 241.080993 -81.062251) (xy 241.097061 -81.115658)
			(xy 241.105181 -81.170834) (xy 241.10569 -81.19872) (xy 241.105181 -81.226606) (xy 241.097061 -81.281782)
			(xy 241.080993 -81.335189) (xy 241.057321 -81.385686) (xy 241.026548 -81.432199) (xy 240.989331 -81.473736)
			(xy 240.946463 -81.509411) (xy 240.898857 -81.538465) (xy 240.847528 -81.560277) (xy 240.793571 -81.574383)
			(xy 240.738134 -81.580483) (xy 240.6824 -81.578446) (xy 240.627557 -81.568316) (xy 240.574773 -81.550309)
			(xy 240.525173 -81.524808) (xy 240.479815 -81.492357) (xy 240.439666 -81.453648) (xy 240.40558 -81.409505)
			(xy 240.378284 -81.36087) (xy 240.358361 -81.308779) (xy 240.346235 -81.254342) (xy 240.342164 -81.19872)
			(xy 207.924537 -81.19872) (xy 207.924399 -81.206286) (xy 207.916279 -81.261462) (xy 207.900211 -81.314869)
			(xy 207.876539 -81.365366) (xy 207.845766 -81.411879) (xy 207.808549 -81.453416) (xy 207.765681 -81.489091)
			(xy 207.718075 -81.518145) (xy 207.666746 -81.539957) (xy 207.612789 -81.554063) (xy 207.557352 -81.560163)
			(xy 207.501618 -81.558126) (xy 207.446775 -81.547996) (xy 207.393991 -81.529989) (xy 207.344391 -81.504488)
			(xy 207.299033 -81.472037) (xy 207.258884 -81.433328) (xy 207.224798 -81.389185) (xy 207.197502 -81.34055)
			(xy 207.177579 -81.288459) (xy 207.165453 -81.234022) (xy 207.161382 -81.1784) (xy 200.363836 -81.1784)
			(xy 200.363836 -81.627472) (xy 205.228442 -81.627472) (xy 205.232513 -81.57185) (xy 205.244639 -81.517413)
			(xy 205.264562 -81.465322) (xy 205.291858 -81.416687) (xy 205.325944 -81.372544) (xy 205.366093 -81.333835)
			(xy 205.411451 -81.301384) (xy 205.461051 -81.275883) (xy 205.513835 -81.257876) (xy 205.568678 -81.247746)
			(xy 205.624412 -81.245709) (xy 205.679849 -81.251809) (xy 205.733806 -81.265915) (xy 205.785135 -81.287727)
			(xy 205.832741 -81.316781) (xy 205.875609 -81.352456) (xy 205.912826 -81.393993) (xy 205.943599 -81.440506)
			(xy 205.967271 -81.491003) (xy 205.983339 -81.54441) (xy 205.991459 -81.599586) (xy 205.991968 -81.627472)
			(xy 220.578678 -81.627472) (xy 220.582749 -81.57185) (xy 220.594875 -81.517413) (xy 220.614798 -81.465322)
			(xy 220.642094 -81.416687) (xy 220.67618 -81.372544) (xy 220.716329 -81.333835) (xy 220.761687 -81.301384)
			(xy 220.811287 -81.275883) (xy 220.864071 -81.257876) (xy 220.918914 -81.247746) (xy 220.974648 -81.245709)
			(xy 221.030085 -81.251809) (xy 221.084042 -81.265915) (xy 221.135371 -81.287727) (xy 221.182977 -81.316781)
			(xy 221.225845 -81.352456) (xy 221.263062 -81.393993) (xy 221.293835 -81.440506) (xy 221.317507 -81.491003)
			(xy 221.333575 -81.54441) (xy 221.341695 -81.599586) (xy 221.342204 -81.627472) (xy 222.62414 -81.627472)
			(xy 222.628211 -81.57185) (xy 222.640337 -81.517413) (xy 222.66026 -81.465322) (xy 222.687556 -81.416687)
			(xy 222.721642 -81.372544) (xy 222.761791 -81.333835) (xy 222.807149 -81.301384) (xy 222.856749 -81.275883)
			(xy 222.909533 -81.257876) (xy 222.964376 -81.247746) (xy 223.02011 -81.245709) (xy 223.075547 -81.251809)
			(xy 223.129504 -81.265915) (xy 223.180833 -81.287727) (xy 223.228439 -81.316781) (xy 223.271307 -81.352456)
			(xy 223.308524 -81.393993) (xy 223.339297 -81.440506) (xy 223.362969 -81.491003) (xy 223.379037 -81.54441)
			(xy 223.387157 -81.599586) (xy 223.387666 -81.627472) (xy 224.650044 -81.627472) (xy 224.654115 -81.57185)
			(xy 224.666241 -81.517413) (xy 224.686164 -81.465322) (xy 224.71346 -81.416687) (xy 224.747546 -81.372544)
			(xy 224.787695 -81.333835) (xy 224.833053 -81.301384) (xy 224.882653 -81.275883) (xy 224.935437 -81.257876)
			(xy 224.99028 -81.247746) (xy 225.046014 -81.245709) (xy 225.101451 -81.251809) (xy 225.155408 -81.265915)
			(xy 225.206737 -81.287727) (xy 225.254343 -81.316781) (xy 225.297211 -81.352456) (xy 225.334428 -81.393993)
			(xy 225.365201 -81.440506) (xy 225.388873 -81.491003) (xy 225.404941 -81.54441) (xy 225.413061 -81.599586)
			(xy 225.41357 -81.627472) (xy 225.413061 -81.655358) (xy 225.404941 -81.710534) (xy 225.388873 -81.763941)
			(xy 225.365201 -81.814438) (xy 225.334428 -81.860951) (xy 225.297211 -81.902488) (xy 225.254343 -81.938163)
			(xy 225.206737 -81.967217) (xy 225.155408 -81.989029) (xy 225.101451 -82.003135) (xy 225.046014 -82.009235)
			(xy 224.99028 -82.007198) (xy 224.935437 -81.997068) (xy 224.882653 -81.979061) (xy 224.833053 -81.95356)
			(xy 224.787695 -81.921109) (xy 224.747546 -81.8824) (xy 224.71346 -81.838257) (xy 224.686164 -81.789622)
			(xy 224.666241 -81.737531) (xy 224.654115 -81.683094) (xy 224.650044 -81.627472) (xy 223.387666 -81.627472)
			(xy 223.387157 -81.655358) (xy 223.379037 -81.710534) (xy 223.362969 -81.763941) (xy 223.339297 -81.814438)
			(xy 223.308524 -81.860951) (xy 223.271307 -81.902488) (xy 223.228439 -81.938163) (xy 223.180833 -81.967217)
			(xy 223.129504 -81.989029) (xy 223.075547 -82.003135) (xy 223.02011 -82.009235) (xy 222.964376 -82.007198)
			(xy 222.909533 -81.997068) (xy 222.856749 -81.979061) (xy 222.807149 -81.95356) (xy 222.761791 -81.921109)
			(xy 222.721642 -81.8824) (xy 222.687556 -81.838257) (xy 222.66026 -81.789622) (xy 222.640337 -81.737531)
			(xy 222.628211 -81.683094) (xy 222.62414 -81.627472) (xy 221.342204 -81.627472) (xy 221.341695 -81.655358)
			(xy 221.333575 -81.710534) (xy 221.317507 -81.763941) (xy 221.293835 -81.814438) (xy 221.263062 -81.860951)
			(xy 221.225845 -81.902488) (xy 221.182977 -81.938163) (xy 221.135371 -81.967217) (xy 221.084042 -81.989029)
			(xy 221.030085 -82.003135) (xy 220.974648 -82.009235) (xy 220.918914 -82.007198) (xy 220.864071 -81.997068)
			(xy 220.811287 -81.979061) (xy 220.761687 -81.95356) (xy 220.716329 -81.921109) (xy 220.67618 -81.8824)
			(xy 220.642094 -81.838257) (xy 220.614798 -81.789622) (xy 220.594875 -81.737531) (xy 220.582749 -81.683094)
			(xy 220.578678 -81.627472) (xy 205.991968 -81.627472) (xy 205.991459 -81.655358) (xy 205.983339 -81.710534)
			(xy 205.967271 -81.763941) (xy 205.943599 -81.814438) (xy 205.912826 -81.860951) (xy 205.875609 -81.902488)
			(xy 205.832741 -81.938163) (xy 205.785135 -81.967217) (xy 205.733806 -81.989029) (xy 205.679849 -82.003135)
			(xy 205.624412 -82.009235) (xy 205.568678 -82.007198) (xy 205.513835 -81.997068) (xy 205.461051 -81.979061)
			(xy 205.411451 -81.95356) (xy 205.366093 -81.921109) (xy 205.325944 -81.8824) (xy 205.291858 -81.838257)
			(xy 205.264562 -81.789622) (xy 205.244639 -81.737531) (xy 205.232513 -81.683094) (xy 205.228442 -81.627472)
			(xy 200.363836 -81.627472) (xy 200.363836 -82.767932) (xy 203.09662 -82.767932) (xy 203.100691 -82.71231)
			(xy 203.112817 -82.657873) (xy 203.13274 -82.605782) (xy 203.160036 -82.557147) (xy 203.194122 -82.513004)
			(xy 203.234271 -82.474295) (xy 203.279629 -82.441844) (xy 203.329229 -82.416343) (xy 203.382013 -82.398336)
			(xy 203.436856 -82.388206) (xy 203.49259 -82.386169) (xy 203.548027 -82.392269) (xy 203.601984 -82.406375)
			(xy 203.653313 -82.428187) (xy 203.700919 -82.457241) (xy 203.743787 -82.492916) (xy 203.781004 -82.534453)
			(xy 203.811777 -82.580966) (xy 203.835449 -82.631463) (xy 203.839062 -82.643472) (xy 205.228442 -82.643472)
			(xy 205.232513 -82.58785) (xy 205.244639 -82.533413) (xy 205.264562 -82.481322) (xy 205.291858 -82.432687)
			(xy 205.325944 -82.388544) (xy 205.366093 -82.349835) (xy 205.411451 -82.317384) (xy 205.461051 -82.291883)
			(xy 205.513835 -82.273876) (xy 205.568678 -82.263746) (xy 205.624412 -82.261709) (xy 205.679849 -82.267809)
			(xy 205.733806 -82.281915) (xy 205.785135 -82.303727) (xy 205.832741 -82.332781) (xy 205.875609 -82.368456)
			(xy 205.912826 -82.409993) (xy 205.943599 -82.456506) (xy 205.967271 -82.507003) (xy 205.983339 -82.56041)
			(xy 205.991459 -82.615586) (xy 205.991968 -82.643472) (xy 205.991634 -82.661755) (xy 212.850879 -82.661755)
			(xy 212.850879 -82.604445) (xy 212.859036 -82.547719) (xy 212.875183 -82.492731) (xy 212.898991 -82.440601)
			(xy 212.929977 -82.39239) (xy 212.967509 -82.34908) (xy 213.010823 -82.311552) (xy 213.059037 -82.280571)
			(xy 213.11117 -82.256768) (xy 213.16616 -82.240627) (xy 213.222887 -82.232476) (xy 213.251542 -82.231992)
			(xy 213.282483 -82.232587) (xy 213.343624 -82.242137) (xy 213.402566 -82.260986) (xy 213.457903 -82.288686)
			(xy 213.483444 -82.30616) (xy 213.483698 -82.306414) (xy 213.492 -82.311592) (xy 213.511063 -82.315914)
			(xy 213.520782 -82.314796) (xy 213.590886 -82.303874) (xy 213.600528 -82.301843) (xy 213.617375 -82.291657)
			(xy 213.623652 -82.284062) (xy 213.641778 -82.260772) (xy 213.68404 -82.219583) (xy 213.732138 -82.185387)
			(xy 213.784924 -82.158999) (xy 213.841142 -82.141048) (xy 213.899453 -82.131961) (xy 213.92896 -82.131408)
			(xy 213.956216 -82.131836) (xy 214.010173 -82.139589) (xy 214.062478 -82.154942) (xy 214.112066 -82.177583)
			(xy 214.157926 -82.207051) (xy 214.199125 -82.242747) (xy 214.234825 -82.283942) (xy 214.264298 -82.329799)
			(xy 214.286944 -82.379384) (xy 214.300125 -82.42427) (xy 218.848938 -82.42427) (xy 218.853009 -82.368648)
			(xy 218.865135 -82.314211) (xy 218.885058 -82.26212) (xy 218.912354 -82.213485) (xy 218.94644 -82.169342)
			(xy 218.986589 -82.130633) (xy 219.031947 -82.098182) (xy 219.081547 -82.072681) (xy 219.134331 -82.054674)
			(xy 219.189174 -82.044544) (xy 219.244908 -82.042507) (xy 219.300345 -82.048607) (xy 219.354302 -82.062713)
			(xy 219.405631 -82.084525) (xy 219.453237 -82.113579) (xy 219.4594 -82.118708) (xy 230.6099 -82.118708)
			(xy 230.613971 -82.063086) (xy 230.626097 -82.008649) (xy 230.64602 -81.956558) (xy 230.673316 -81.907923)
			(xy 230.707402 -81.86378) (xy 230.747551 -81.825071) (xy 230.792909 -81.79262) (xy 230.842509 -81.767119)
			(xy 230.895293 -81.749112) (xy 230.950136 -81.738982) (xy 231.00587 -81.736945) (xy 231.061307 -81.743045)
			(xy 231.115264 -81.757151) (xy 231.166593 -81.778963) (xy 231.214199 -81.808017) (xy 231.257067 -81.843692)
			(xy 231.294284 -81.885229) (xy 231.325057 -81.931742) (xy 231.348729 -81.982239) (xy 231.364797 -82.035646)
			(xy 231.372917 -82.090822) (xy 231.373426 -82.118708) (xy 231.372917 -82.146594) (xy 231.364797 -82.20177)
			(xy 231.348729 -82.255177) (xy 231.325057 -82.305674) (xy 231.294284 -82.352187) (xy 231.257067 -82.393724)
			(xy 231.214199 -82.429399) (xy 231.166593 -82.458453) (xy 231.115264 -82.480265) (xy 231.061307 -82.494371)
			(xy 231.00587 -82.500471) (xy 230.950136 -82.498434) (xy 230.895293 -82.488304) (xy 230.842509 -82.470297)
			(xy 230.792909 -82.444796) (xy 230.747551 -82.412345) (xy 230.707402 -82.373636) (xy 230.673316 -82.329493)
			(xy 230.64602 -82.280858) (xy 230.626097 -82.228767) (xy 230.613971 -82.17433) (xy 230.6099 -82.118708)
			(xy 219.4594 -82.118708) (xy 219.496105 -82.149254) (xy 219.533322 -82.190791) (xy 219.564095 -82.237304)
			(xy 219.587767 -82.287801) (xy 219.603835 -82.341208) (xy 219.611955 -82.396384) (xy 219.612464 -82.42427)
			(xy 219.611955 -82.452156) (xy 219.603835 -82.507332) (xy 219.587767 -82.560739) (xy 219.564095 -82.611236)
			(xy 219.542768 -82.643472) (xy 222.62414 -82.643472) (xy 222.628211 -82.58785) (xy 222.640337 -82.533413)
			(xy 222.66026 -82.481322) (xy 222.687556 -82.432687) (xy 222.721642 -82.388544) (xy 222.761791 -82.349835)
			(xy 222.807149 -82.317384) (xy 222.856749 -82.291883) (xy 222.909533 -82.273876) (xy 222.964376 -82.263746)
			(xy 223.02011 -82.261709) (xy 223.075547 -82.267809) (xy 223.129504 -82.281915) (xy 223.180833 -82.303727)
			(xy 223.228439 -82.332781) (xy 223.271307 -82.368456) (xy 223.308524 -82.409993) (xy 223.339297 -82.456506)
			(xy 223.362969 -82.507003) (xy 223.379037 -82.56041) (xy 223.387157 -82.615586) (xy 223.387666 -82.643472)
			(xy 224.650044 -82.643472) (xy 224.654115 -82.58785) (xy 224.666241 -82.533413) (xy 224.686164 -82.481322)
			(xy 224.71346 -82.432687) (xy 224.747546 -82.388544) (xy 224.787695 -82.349835) (xy 224.833053 -82.317384)
			(xy 224.882653 -82.291883) (xy 224.935437 -82.273876) (xy 224.99028 -82.263746) (xy 225.046014 -82.261709)
			(xy 225.101451 -82.267809) (xy 225.155408 -82.281915) (xy 225.206737 -82.303727) (xy 225.254343 -82.332781)
			(xy 225.297211 -82.368456) (xy 225.334428 -82.409993) (xy 225.365201 -82.456506) (xy 225.388873 -82.507003)
			(xy 225.404941 -82.56041) (xy 225.413061 -82.615586) (xy 225.41357 -82.643472) (xy 225.413061 -82.671358)
			(xy 225.404941 -82.726534) (xy 225.388873 -82.779941) (xy 225.365201 -82.830438) (xy 225.334428 -82.876951)
			(xy 225.297211 -82.918488) (xy 225.254343 -82.954163) (xy 225.206737 -82.983217) (xy 225.155408 -83.005029)
			(xy 225.101451 -83.019135) (xy 225.046014 -83.025235) (xy 224.99028 -83.023198) (xy 224.935437 -83.013068)
			(xy 224.882653 -82.995061) (xy 224.833053 -82.96956) (xy 224.787695 -82.937109) (xy 224.747546 -82.8984)
			(xy 224.71346 -82.854257) (xy 224.686164 -82.805622) (xy 224.666241 -82.753531) (xy 224.654115 -82.699094)
			(xy 224.650044 -82.643472) (xy 223.387666 -82.643472) (xy 223.387157 -82.671358) (xy 223.379037 -82.726534)
			(xy 223.362969 -82.779941) (xy 223.339297 -82.830438) (xy 223.308524 -82.876951) (xy 223.271307 -82.918488)
			(xy 223.228439 -82.954163) (xy 223.180833 -82.983217) (xy 223.129504 -83.005029) (xy 223.075547 -83.019135)
			(xy 223.02011 -83.025235) (xy 222.964376 -83.023198) (xy 222.909533 -83.013068) (xy 222.856749 -82.995061)
			(xy 222.807149 -82.96956) (xy 222.761791 -82.937109) (xy 222.721642 -82.8984) (xy 222.687556 -82.854257)
			(xy 222.66026 -82.805622) (xy 222.640337 -82.753531) (xy 222.628211 -82.699094) (xy 222.62414 -82.643472)
			(xy 219.542768 -82.643472) (xy 219.533322 -82.657749) (xy 219.496105 -82.699286) (xy 219.453237 -82.734961)
			(xy 219.405631 -82.764015) (xy 219.354302 -82.785827) (xy 219.300345 -82.799933) (xy 219.244908 -82.806033)
			(xy 219.189174 -82.803996) (xy 219.134331 -82.793866) (xy 219.081547 -82.775859) (xy 219.031947 -82.750358)
			(xy 218.986589 -82.717907) (xy 218.94644 -82.679198) (xy 218.912354 -82.635055) (xy 218.885058 -82.58642)
			(xy 218.865135 -82.534329) (xy 218.853009 -82.479892) (xy 218.848938 -82.42427) (xy 214.300125 -82.42427)
			(xy 214.302303 -82.431687) (xy 214.310061 -82.485644) (xy 214.310061 -82.540156) (xy 214.302303 -82.594113)
			(xy 214.286944 -82.646416) (xy 214.264298 -82.696001) (xy 214.234825 -82.741858) (xy 214.199125 -82.783053)
			(xy 214.157926 -82.818749) (xy 214.112066 -82.848217) (xy 214.062478 -82.870858) (xy 214.010173 -82.886211)
			(xy 213.956216 -82.893964) (xy 213.92896 -82.894424) (xy 213.901444 -82.893929) (xy 213.846985 -82.886019)
			(xy 213.794226 -82.870368) (xy 213.744263 -82.847301) (xy 213.720934 -82.832702) (xy 213.712552 -82.827368)
			(xy 213.693248 -82.823558) (xy 213.613746 -82.839306) (xy 213.604256 -82.841645) (xy 213.58793 -82.852366)
			(xy 213.581996 -82.860134) (xy 213.581742 -82.860642) (xy 213.565644 -82.883218) (xy 213.528195 -82.924109)
			(xy 213.485469 -82.959448) (xy 213.43828 -82.988563) (xy 213.38753 -83.010898) (xy 213.334186 -83.026026)
			(xy 213.279266 -83.033659) (xy 213.251542 -83.034124) (xy 213.222887 -83.033724) (xy 213.16616 -83.025573)
			(xy 213.11117 -83.009432) (xy 213.059037 -82.985629) (xy 213.010823 -82.954648) (xy 212.967509 -82.91712)
			(xy 212.929977 -82.87381) (xy 212.898991 -82.825599) (xy 212.875183 -82.773469) (xy 212.859036 -82.718481)
			(xy 212.850879 -82.661755) (xy 205.991634 -82.661755) (xy 205.991459 -82.671358) (xy 205.983339 -82.726534)
			(xy 205.967271 -82.779941) (xy 205.943599 -82.830438) (xy 205.912826 -82.876951) (xy 205.875609 -82.918488)
			(xy 205.832741 -82.954163) (xy 205.785135 -82.983217) (xy 205.733806 -83.005029) (xy 205.679849 -83.019135)
			(xy 205.624412 -83.025235) (xy 205.568678 -83.023198) (xy 205.513835 -83.013068) (xy 205.461051 -82.995061)
			(xy 205.411451 -82.96956) (xy 205.366093 -82.937109) (xy 205.325944 -82.8984) (xy 205.291858 -82.854257)
			(xy 205.264562 -82.805622) (xy 205.244639 -82.753531) (xy 205.232513 -82.699094) (xy 205.228442 -82.643472)
			(xy 203.839062 -82.643472) (xy 203.851517 -82.68487) (xy 203.859637 -82.740046) (xy 203.860146 -82.767932)
			(xy 203.859637 -82.795818) (xy 203.851517 -82.850994) (xy 203.835449 -82.904401) (xy 203.811777 -82.954898)
			(xy 203.781004 -83.001411) (xy 203.743787 -83.042948) (xy 203.700919 -83.078623) (xy 203.653313 -83.107677)
			(xy 203.601984 -83.129489) (xy 203.548027 -83.143595) (xy 203.49259 -83.149695) (xy 203.436856 -83.147658)
			(xy 203.382013 -83.137528) (xy 203.329229 -83.119521) (xy 203.279629 -83.09402) (xy 203.234271 -83.061569)
			(xy 203.194122 -83.02286) (xy 203.160036 -82.978717) (xy 203.13274 -82.930082) (xy 203.112817 -82.877991)
			(xy 203.100691 -82.823554) (xy 203.09662 -82.767932) (xy 200.363836 -82.767932) (xy 200.363836 -83.93684)
			(xy 205.22057 -83.93684) (xy 205.22057 -83.936586) (xy 205.221056 -83.909335) (xy 205.228812 -83.855387)
			(xy 205.244167 -83.803092) (xy 205.266809 -83.753515) (xy 205.296275 -83.707665) (xy 205.331966 -83.666474)
			(xy 205.373157 -83.630783) (xy 205.419007 -83.601317) (xy 205.468584 -83.578675) (xy 205.520879 -83.56332)
			(xy 205.574827 -83.555564) (xy 205.629329 -83.555564) (xy 205.683277 -83.56332) (xy 205.735572 -83.578675)
			(xy 205.785149 -83.601317) (xy 205.830999 -83.630783) (xy 205.87219 -83.666474) (xy 205.907881 -83.707665)
			(xy 205.937347 -83.753515) (xy 205.959989 -83.803092) (xy 205.975344 -83.855387) (xy 205.975369 -83.85556)
			(xy 218.830142 -83.85556) (xy 218.834213 -83.799938) (xy 218.846339 -83.745501) (xy 218.866262 -83.69341)
			(xy 218.893558 -83.644775) (xy 218.927644 -83.600632) (xy 218.967793 -83.561923) (xy 219.013151 -83.529472)
			(xy 219.062751 -83.503971) (xy 219.115535 -83.485964) (xy 219.170378 -83.475834) (xy 219.226112 -83.473797)
			(xy 219.281549 -83.479897) (xy 219.335506 -83.494003) (xy 219.338765 -83.495388) (xy 220.578678 -83.495388)
			(xy 220.582749 -83.439766) (xy 220.594875 -83.385329) (xy 220.614798 -83.333238) (xy 220.642094 -83.284603)
			(xy 220.67618 -83.24046) (xy 220.716329 -83.201751) (xy 220.761687 -83.1693) (xy 220.811287 -83.143799)
			(xy 220.864071 -83.125792) (xy 220.918914 -83.115662) (xy 220.974648 -83.113625) (xy 221.030085 -83.119725)
			(xy 221.084042 -83.133831) (xy 221.135371 -83.155643) (xy 221.182977 -83.184697) (xy 221.225845 -83.220372)
			(xy 221.263062 -83.261909) (xy 221.293835 -83.308422) (xy 221.317507 -83.358919) (xy 221.333575 -83.412326)
			(xy 221.341695 -83.467502) (xy 221.342204 -83.495388) (xy 221.341695 -83.523274) (xy 221.333575 -83.57845)
			(xy 221.317507 -83.631857) (xy 221.304562 -83.659472) (xy 222.62414 -83.659472) (xy 222.628211 -83.60385)
			(xy 222.640337 -83.549413) (xy 222.66026 -83.497322) (xy 222.687556 -83.448687) (xy 222.721642 -83.404544)
			(xy 222.761791 -83.365835) (xy 222.807149 -83.333384) (xy 222.856749 -83.307883) (xy 222.909533 -83.289876)
			(xy 222.964376 -83.279746) (xy 223.02011 -83.277709) (xy 223.075547 -83.283809) (xy 223.129504 -83.297915)
			(xy 223.180833 -83.319727) (xy 223.228439 -83.348781) (xy 223.271307 -83.384456) (xy 223.308524 -83.425993)
			(xy 223.339297 -83.472506) (xy 223.362969 -83.523003) (xy 223.379037 -83.57641) (xy 223.387157 -83.631586)
			(xy 223.387666 -83.659472) (xy 224.650044 -83.659472) (xy 224.654115 -83.60385) (xy 224.666241 -83.549413)
			(xy 224.686164 -83.497322) (xy 224.71346 -83.448687) (xy 224.747546 -83.404544) (xy 224.787695 -83.365835)
			(xy 224.833053 -83.333384) (xy 224.882653 -83.307883) (xy 224.935437 -83.289876) (xy 224.99028 -83.279746)
			(xy 225.046014 -83.277709) (xy 225.101451 -83.283809) (xy 225.155408 -83.297915) (xy 225.206737 -83.319727)
			(xy 225.254343 -83.348781) (xy 225.276682 -83.367372) (xy 232.68432 -83.367372) (xy 232.68432 -82.503518)
			(xy 232.684821 -82.473907) (xy 232.692459 -82.41518) (xy 232.707598 -82.357926) (xy 232.729985 -82.303099)
			(xy 232.759247 -82.251612) (xy 232.794896 -82.204322) (xy 232.83634 -82.162018) (xy 232.859326 -82.143346)
			(xy 232.867613 -82.136216) (xy 232.877761 -82.116881) (xy 232.878884 -82.106008) (xy 232.882948 -82.029808)
			(xy 232.883042 -82.019013) (xy 232.875272 -81.998891) (xy 232.867962 -81.990946) (xy 232.867708 -81.990692)
			(xy 232.848984 -81.971786) (xy 232.816239 -81.929844) (xy 232.789326 -81.88394) (xy 232.768718 -81.834882)
			(xy 232.754775 -81.78353) (xy 232.747744 -81.730786) (xy 232.747312 -81.70418) (xy 232.747823 -81.67555)
			(xy 232.755972 -81.618872) (xy 232.772104 -81.563932) (xy 232.79589 -81.511846) (xy 232.826848 -81.463675)
			(xy 232.864345 -81.420401) (xy 232.907619 -81.382904) (xy 232.95579 -81.351946) (xy 233.007876 -81.32816)
			(xy 233.062816 -81.312028) (xy 233.119494 -81.303879) (xy 233.176754 -81.303879) (xy 233.233432 -81.312028)
			(xy 233.288372 -81.32816) (xy 233.340458 -81.351946) (xy 233.388629 -81.382904) (xy 233.431903 -81.420401)
			(xy 233.4694 -81.463675) (xy 233.500358 -81.511846) (xy 233.524144 -81.563932) (xy 233.540276 -81.618872)
			(xy 233.548425 -81.67555) (xy 233.548936 -81.70418) (xy 233.548936 -81.704688) (xy 233.54847 -81.731765)
			(xy 233.541152 -81.785422) (xy 233.526674 -81.837604) (xy 233.505301 -81.887362) (xy 233.477422 -81.933787)
			(xy 233.443544 -81.976036) (xy 233.424222 -81.99501) (xy 233.416094 -82.00263) (xy 233.407966 -82.022696)
			(xy 233.411678 -82.118708) (xy 235.025436 -82.118708) (xy 235.029507 -82.063086) (xy 235.041633 -82.008649)
			(xy 235.061556 -81.956558) (xy 235.088852 -81.907923) (xy 235.122938 -81.86378) (xy 235.163087 -81.825071)
			(xy 235.208445 -81.79262) (xy 235.258045 -81.767119) (xy 235.310829 -81.749112) (xy 235.365672 -81.738982)
			(xy 235.421406 -81.736945) (xy 235.476843 -81.743045) (xy 235.5308 -81.757151) (xy 235.582129 -81.778963)
			(xy 235.629735 -81.808017) (xy 235.672603 -81.843692) (xy 235.70982 -81.885229) (xy 235.740593 -81.931742)
			(xy 235.764265 -81.982239) (xy 235.780333 -82.035646) (xy 235.788453 -82.090822) (xy 235.788962 -82.118708)
			(xy 235.788453 -82.146594) (xy 235.780333 -82.20177) (xy 235.764265 -82.255177) (xy 235.740593 -82.305674)
			(xy 235.70982 -82.352187) (xy 235.672603 -82.393724) (xy 235.629735 -82.429399) (xy 235.582129 -82.458453)
			(xy 235.5308 -82.480265) (xy 235.476843 -82.494371) (xy 235.421406 -82.500471) (xy 235.365672 -82.498434)
			(xy 235.310829 -82.488304) (xy 235.258045 -82.470297) (xy 235.208445 -82.444796) (xy 235.163087 -82.412345)
			(xy 235.122938 -82.373636) (xy 235.088852 -82.329493) (xy 235.061556 -82.280858) (xy 235.041633 -82.228767)
			(xy 235.029507 -82.17433) (xy 235.025436 -82.118708) (xy 233.411678 -82.118708) (xy 233.411776 -82.121248)
			(xy 233.421428 -82.140806) (xy 233.430064 -82.147664) (xy 233.45242 -82.166332) (xy 233.492656 -82.208442)
			(xy 233.527229 -82.255314) (xy 233.555582 -82.306191) (xy 233.577256 -82.360251) (xy 233.591902 -82.416623)
			(xy 233.599283 -82.474396) (xy 233.599736 -82.503518) (xy 233.599736 -82.847331) (xy 237.498107 -82.847331)
			(xy 237.498107 -82.790069) (xy 237.506256 -82.73339) (xy 237.52239 -82.678448) (xy 237.546178 -82.626361)
			(xy 237.577138 -82.57819) (xy 237.614638 -82.534915) (xy 237.657915 -82.497419) (xy 237.706089 -82.466463)
			(xy 237.758178 -82.442678) (xy 237.813121 -82.426549) (xy 237.869801 -82.418404) (xy 237.898432 -82.41792)
			(xy 237.925232 -82.418295) (xy 237.978368 -82.425309) (xy 238.00435 -82.43189) (xy 238.016034 -82.435192)
			(xy 238.03991 -82.430112) (xy 238.11357 -82.37093) (xy 238.122539 -82.363) (xy 238.132468 -82.341247)
			(xy 238.13262 -82.329274) (xy 238.13262 -82.328766) (xy 238.132112 -82.307176) (xy 238.13256 -82.277207)
			(xy 238.140386 -82.217782) (xy 238.155902 -82.159887) (xy 238.178842 -82.104513) (xy 238.208814 -82.052606)
			(xy 238.245304 -82.005056) (xy 238.287689 -81.962675) (xy 238.335243 -81.92619) (xy 238.387152 -81.896223)
			(xy 238.442529 -81.873288) (xy 238.500425 -81.857778) (xy 238.559851 -81.849957) (xy 238.58982 -81.849468)
			(xy 239.45342 -81.849468) (xy 239.483387 -81.849963) (xy 239.542808 -81.857788) (xy 239.6007 -81.873302)
			(xy 239.656072 -81.896239) (xy 239.707976 -81.926207) (xy 239.755525 -81.962693) (xy 239.797905 -82.005072)
			(xy 239.834391 -82.052621) (xy 239.864359 -82.104525) (xy 239.887297 -82.159896) (xy 239.902811 -82.217788)
			(xy 239.906033 -82.242256) (xy 246.544229 -82.242256) (xy 246.544229 -82.187744) (xy 246.551988 -82.133786)
			(xy 246.567347 -82.081481) (xy 246.589993 -82.031895) (xy 246.619467 -81.986037) (xy 246.655167 -81.94484)
			(xy 246.696367 -81.909144) (xy 246.742228 -81.879675) (xy 246.791817 -81.857033) (xy 246.844123 -81.841679)
			(xy 246.898081 -81.833926) (xy 246.925338 -81.833466) (xy 246.937309 -81.833576) (xy 246.961202 -81.835103)
			(xy 246.97309 -81.836514) (xy 246.973344 -81.836514) (xy 246.984061 -81.83738) (xy 247.004591 -81.831061)
			(xy 247.012968 -81.824322) (xy 247.070372 -81.773776) (xy 247.078182 -81.766246) (xy 247.087139 -81.746512)
			(xy 247.087644 -81.735676) (xy 247.087644 -78.121764) (xy 247.08739 -78.121764) (xy 247.087795 -78.097729)
			(xy 247.095196 -78.050234) (xy 247.10995 -78.004487) (xy 247.131694 -77.961619) (xy 247.159888 -77.922688)
			(xy 247.176544 -77.905356) (xy 247.442736 -77.639418) (xy 247.459999 -77.622771) (xy 247.498765 -77.594544)
			(xy 247.541466 -77.572721) (xy 247.587053 -77.55784) (xy 247.634406 -77.550266) (xy 247.658382 -77.549756)
			(xy 250.451366 -77.549756) (xy 250.456257 -77.549893) (xy 250.465849 -77.551812) (xy 250.470416 -77.553566)
			(xy 250.566174 -77.592428) (xy 250.570998 -77.594523) (xy 250.579708 -77.600413) (xy 250.583446 -77.604112)
			(xy 250.618752 -77.640688) (xy 250.61926 -77.641196) (xy 251.172726 -78.194408) (xy 251.189384 -78.211695)
			(xy 251.217634 -78.250507) (xy 251.239465 -78.293259) (xy 251.254341 -78.3389) (xy 251.261895 -78.386306)
			(xy 251.262388 -78.410308) (xy 251.262388 -78.979268) (xy 251.87351 -78.979268) (xy 251.877581 -78.923646)
			(xy 251.889707 -78.869209) (xy 251.90963 -78.817118) (xy 251.936926 -78.768483) (xy 251.971012 -78.72434)
			(xy 252.011161 -78.685631) (xy 252.056519 -78.65318) (xy 252.106119 -78.627679) (xy 252.158903 -78.609672)
			(xy 252.213746 -78.599542) (xy 252.26948 -78.597505) (xy 252.324917 -78.603605) (xy 252.378874 -78.617711)
			(xy 252.430203 -78.639523) (xy 252.43627 -78.643226) (xy 254.273302 -78.643226) (xy 254.277373 -78.587604)
			(xy 254.289499 -78.533167) (xy 254.309422 -78.481076) (xy 254.336718 -78.432441) (xy 254.370804 -78.388298)
			(xy 254.410953 -78.349589) (xy 254.456311 -78.317138) (xy 254.505911 -78.291637) (xy 254.558695 -78.27363)
			(xy 254.613538 -78.2635) (xy 254.669272 -78.261463) (xy 254.724709 -78.267563) (xy 254.778666 -78.281669)
			(xy 254.829995 -78.303481) (xy 254.877601 -78.332535) (xy 254.920469 -78.36821) (xy 254.957686 -78.409747)
			(xy 254.988459 -78.45626) (xy 255.009783 -78.501748) (xy 256.284728 -78.501748) (xy 256.288799 -78.446126)
			(xy 256.300925 -78.391689) (xy 256.320848 -78.339598) (xy 256.348144 -78.290963) (xy 256.38223 -78.24682)
			(xy 256.422379 -78.208111) (xy 256.467737 -78.17566) (xy 256.517337 -78.150159) (xy 256.570121 -78.132152)
			(xy 256.624964 -78.122022) (xy 256.680698 -78.119985) (xy 256.736135 -78.126085) (xy 256.790092 -78.140191)
			(xy 256.841421 -78.162003) (xy 256.889027 -78.191057) (xy 256.931895 -78.226732) (xy 256.969112 -78.268269)
			(xy 256.999885 -78.314782) (xy 257.023557 -78.365279) (xy 257.039625 -78.418686) (xy 257.047745 -78.473862)
			(xy 257.048254 -78.501748) (xy 257.047745 -78.529634) (xy 257.039625 -78.58481) (xy 257.023557 -78.638217)
			(xy 256.999885 -78.688714) (xy 256.969112 -78.735227) (xy 256.931895 -78.776764) (xy 256.889027 -78.812439)
			(xy 256.84291 -78.840584) (xy 259.167884 -78.840584) (xy 259.16837 -78.813333) (xy 259.176126 -78.759385)
			(xy 259.191481 -78.70709) (xy 259.214123 -78.657513) (xy 259.243589 -78.611663) (xy 259.27928 -78.570472)
			(xy 259.320471 -78.534781) (xy 259.366321 -78.505315) (xy 259.415898 -78.482673) (xy 259.468193 -78.467318)
			(xy 259.522141 -78.459562) (xy 259.576643 -78.459562) (xy 259.630591 -78.467318) (xy 259.682886 -78.482673)
			(xy 259.732463 -78.505315) (xy 259.778313 -78.534781) (xy 259.819504 -78.570472) (xy 259.855195 -78.611663)
			(xy 259.884661 -78.657513) (xy 259.907303 -78.70709) (xy 259.922658 -78.759385) (xy 259.930414 -78.813333)
			(xy 259.9309 -78.840584) (xy 259.930263 -78.872204) (xy 259.919821 -78.934576) (xy 259.89922 -78.994367)
			(xy 259.884672 -79.022448) (xy 259.880642 -79.030795) (xy 259.878307 -79.049168) (xy 259.8801 -79.058262)
			(xy 259.89788 -79.133446) (xy 259.908548 -79.149194) (xy 259.916168 -79.154274) (xy 259.937487 -79.169642)
			(xy 259.976117 -79.205275) (xy 260.009493 -79.24587) (xy 260.036983 -79.290661) (xy 260.058069 -79.338799)
			(xy 260.072352 -79.389376) (xy 260.07956 -79.441433) (xy 260.079998 -79.46771) (xy 260.079512 -79.494961)
			(xy 260.071756 -79.548909) (xy 260.056401 -79.601204) (xy 260.037442 -79.642716) (xy 261.293862 -79.642716)
			(xy 261.297933 -79.587094) (xy 261.310059 -79.532657) (xy 261.329982 -79.480566) (xy 261.357278 -79.431931)
			(xy 261.391364 -79.387788) (xy 261.431513 -79.349079) (xy 261.476871 -79.316628) (xy 261.526471 -79.291127)
			(xy 261.579255 -79.27312) (xy 261.634098 -79.26299) (xy 261.689832 -79.260953) (xy 261.745269 -79.267053)
			(xy 261.799226 -79.281159) (xy 261.850555 -79.302971) (xy 261.898161 -79.332025) (xy 261.941029 -79.3677)
			(xy 261.978246 -79.409237) (xy 262.009019 -79.45575) (xy 262.032691 -79.506247) (xy 262.048759 -79.559654)
			(xy 262.056879 -79.61483) (xy 262.057388 -79.642716) (xy 262.056879 -79.670602) (xy 262.048759 -79.725778)
			(xy 262.035081 -79.77124) (xy 273.32889 -79.77124) (xy 273.332961 -79.715618) (xy 273.345087 -79.661181)
			(xy 273.36501 -79.60909) (xy 273.392306 -79.560455) (xy 273.426392 -79.516312) (xy 273.466541 -79.477603)
			(xy 273.511899 -79.445152) (xy 273.561499 -79.419651) (xy 273.614283 -79.401644) (xy 273.669126 -79.391514)
			(xy 273.72486 -79.389477) (xy 273.780297 -79.395577) (xy 273.834254 -79.409683) (xy 273.885583 -79.431495)
			(xy 273.933189 -79.460549) (xy 273.976057 -79.496224) (xy 274.013274 -79.537761) (xy 274.044047 -79.584274)
			(xy 274.067719 -79.634771) (xy 274.083787 -79.688178) (xy 274.091907 -79.743354) (xy 274.092416 -79.77124)
			(xy 274.091907 -79.799126) (xy 274.083787 -79.854302) (xy 274.067719 -79.907709) (xy 274.044047 -79.958206)
			(xy 274.013274 -80.004719) (xy 273.976057 -80.046256) (xy 273.933189 -80.081931) (xy 273.885583 -80.110985)
			(xy 273.834254 -80.132797) (xy 273.780297 -80.146903) (xy 273.72486 -80.153003) (xy 273.669126 -80.150966)
			(xy 273.614283 -80.140836) (xy 273.561499 -80.122829) (xy 273.511899 -80.097328) (xy 273.466541 -80.064877)
			(xy 273.426392 -80.026168) (xy 273.392306 -79.982025) (xy 273.36501 -79.93339) (xy 273.345087 -79.881299)
			(xy 273.332961 -79.826862) (xy 273.32889 -79.77124) (xy 262.035081 -79.77124) (xy 262.032691 -79.779185)
			(xy 262.009019 -79.829682) (xy 261.978246 -79.876195) (xy 261.941029 -79.917732) (xy 261.898161 -79.953407)
			(xy 261.850555 -79.982461) (xy 261.799226 -80.004273) (xy 261.745269 -80.018379) (xy 261.689832 -80.024479)
			(xy 261.634098 -80.022442) (xy 261.579255 -80.012312) (xy 261.526471 -79.994305) (xy 261.476871 -79.968804)
			(xy 261.431513 -79.936353) (xy 261.391364 -79.897644) (xy 261.357278 -79.853501) (xy 261.329982 -79.804866)
			(xy 261.310059 -79.752775) (xy 261.297933 -79.698338) (xy 261.293862 -79.642716) (xy 260.037442 -79.642716)
			(xy 260.033759 -79.650781) (xy 260.004293 -79.696631) (xy 259.968602 -79.737822) (xy 259.927411 -79.773513)
			(xy 259.881561 -79.802979) (xy 259.831984 -79.825621) (xy 259.779689 -79.840976) (xy 259.725741 -79.848732)
			(xy 259.671239 -79.848732) (xy 259.617291 -79.840976) (xy 259.564996 -79.825621) (xy 259.515419 -79.802979)
			(xy 259.469569 -79.773513) (xy 259.428378 -79.737822) (xy 259.392687 -79.696631) (xy 259.363221 -79.650781)
			(xy 259.340579 -79.601204) (xy 259.325224 -79.548909) (xy 259.317468 -79.494961) (xy 259.316982 -79.46771)
			(xy 259.317618 -79.43609) (xy 259.328061 -79.373718) (xy 259.348662 -79.313927) (xy 259.36321 -79.285846)
			(xy 259.367243 -79.2775) (xy 259.369576 -79.259127) (xy 259.367782 -79.250032) (xy 259.350002 -79.174848)
			(xy 259.339334 -79.1591) (xy 259.331714 -79.15402) (xy 259.310388 -79.138661) (xy 259.271759 -79.103026)
			(xy 259.238385 -79.062429) (xy 259.210895 -79.017637) (xy 259.18981 -78.969497) (xy 259.175529 -78.91892)
			(xy 259.168321 -78.866861) (xy 259.167884 -78.840584) (xy 256.84291 -78.840584) (xy 256.841421 -78.841493)
			(xy 256.790092 -78.863305) (xy 256.736135 -78.877411) (xy 256.680698 -78.883511) (xy 256.624964 -78.881474)
			(xy 256.570121 -78.871344) (xy 256.517337 -78.853337) (xy 256.467737 -78.827836) (xy 256.422379 -78.795385)
			(xy 256.38223 -78.756676) (xy 256.348144 -78.712533) (xy 256.320848 -78.663898) (xy 256.300925 -78.611807)
			(xy 256.288799 -78.55737) (xy 256.284728 -78.501748) (xy 255.009783 -78.501748) (xy 255.012131 -78.506757)
			(xy 255.028199 -78.560164) (xy 255.036319 -78.61534) (xy 255.036828 -78.643226) (xy 255.036319 -78.671112)
			(xy 255.028199 -78.726288) (xy 255.012131 -78.779695) (xy 254.988459 -78.830192) (xy 254.957686 -78.876705)
			(xy 254.920469 -78.918242) (xy 254.877601 -78.953917) (xy 254.829995 -78.982971) (xy 254.778666 -79.004783)
			(xy 254.724709 -79.018889) (xy 254.669272 -79.024989) (xy 254.613538 -79.022952) (xy 254.558695 -79.012822)
			(xy 254.505911 -78.994815) (xy 254.456311 -78.969314) (xy 254.410953 -78.936863) (xy 254.370804 -78.898154)
			(xy 254.336718 -78.854011) (xy 254.309422 -78.805376) (xy 254.289499 -78.753285) (xy 254.277373 -78.698848)
			(xy 254.273302 -78.643226) (xy 252.43627 -78.643226) (xy 252.477809 -78.668577) (xy 252.520677 -78.704252)
			(xy 252.557894 -78.745789) (xy 252.588667 -78.792302) (xy 252.612339 -78.842799) (xy 252.628407 -78.896206)
			(xy 252.636527 -78.951382) (xy 252.637036 -78.979268) (xy 252.636527 -79.007154) (xy 252.628407 -79.06233)
			(xy 252.612339 -79.115737) (xy 252.588667 -79.166234) (xy 252.557894 -79.212747) (xy 252.520677 -79.254284)
			(xy 252.477809 -79.289959) (xy 252.430203 -79.319013) (xy 252.378874 -79.340825) (xy 252.324917 -79.354931)
			(xy 252.26948 -79.361031) (xy 252.213746 -79.358994) (xy 252.158903 -79.348864) (xy 252.106119 -79.330857)
			(xy 252.056519 -79.305356) (xy 252.011161 -79.272905) (xy 251.971012 -79.234196) (xy 251.936926 -79.190053)
			(xy 251.90963 -79.141418) (xy 251.889707 -79.089327) (xy 251.877581 -79.03489) (xy 251.87351 -78.979268)
			(xy 251.262388 -78.979268) (xy 251.262388 -79.30261) (xy 251.26193 -79.325799) (xy 251.254848 -79.371633)
			(xy 251.240923 -79.415872) (xy 251.220476 -79.4575) (xy 251.193976 -79.495561) (xy 251.178314 -79.512668)
			(xy 251.173019 -79.518625) (xy 251.166157 -79.533) (xy 251.164852 -79.540862) (xy 251.160788 -79.569564)
			(xy 251.159962 -79.577491) (xy 251.162823 -79.593163) (xy 251.166376 -79.600298) (xy 251.180389 -79.628042)
			(xy 251.200205 -79.686952) (xy 251.210232 -79.748291) (xy 251.210826 -79.779368) (xy 251.210248 -79.810447)
			(xy 251.20024 -79.871792) (xy 251.193472 -79.89189) (xy 254.870964 -79.89189) (xy 254.875035 -79.836268)
			(xy 254.887161 -79.781831) (xy 254.907084 -79.72974) (xy 254.93438 -79.681105) (xy 254.968466 -79.636962)
			(xy 255.008615 -79.598253) (xy 255.053973 -79.565802) (xy 255.103573 -79.540301) (xy 255.156357 -79.522294)
			(xy 255.2112 -79.512164) (xy 255.266934 -79.510127) (xy 255.322371 -79.516227) (xy 255.376328 -79.530333)
			(xy 255.427657 -79.552145) (xy 255.475263 -79.581199) (xy 255.518131 -79.616874) (xy 255.555348 -79.658411)
			(xy 255.586121 -79.704924) (xy 255.609793 -79.755421) (xy 255.625861 -79.808828) (xy 255.633981 -79.864004)
			(xy 255.63449 -79.89189) (xy 255.633981 -79.919776) (xy 255.625861 -79.974952) (xy 255.609793 -80.028359)
			(xy 255.586121 -80.078856) (xy 255.555348 -80.125369) (xy 255.518131 -80.166906) (xy 255.475263 -80.202581)
			(xy 255.427657 -80.231635) (xy 255.376328 -80.253447) (xy 255.322371 -80.267553) (xy 255.266934 -80.273653)
			(xy 255.2112 -80.271616) (xy 255.156357 -80.261486) (xy 255.103573 -80.243479) (xy 255.053973 -80.217978)
			(xy 255.008615 -80.185527) (xy 254.968466 -80.146818) (xy 254.93438 -80.102675) (xy 254.907084 -80.05404)
			(xy 254.887161 -80.001949) (xy 254.875035 -79.947512) (xy 254.870964 -79.89189) (xy 251.193472 -79.89189)
			(xy 251.180402 -79.930698) (xy 251.166376 -79.958438) (xy 251.162912 -79.965602) (xy 251.160064 -79.981248)
			(xy 251.160788 -79.989172) (xy 251.164852 -80.017874) (xy 251.166201 -80.02572) (xy 251.173071 -80.040075)
			(xy 251.178314 -80.046068) (xy 251.193992 -80.063163) (xy 251.220518 -80.101213) (xy 251.240975 -80.142843)
			(xy 251.254889 -80.18709) (xy 251.261941 -80.232934) (xy 251.262388 -80.256126) (xy 251.262388 -81.61655)
			(xy 251.902214 -81.61655) (xy 251.902727 -81.587087) (xy 251.911807 -81.528864) (xy 251.929729 -81.472729)
			(xy 251.956067 -81.420015) (xy 251.990194 -81.371977) (xy 252.0313 -81.329755) (xy 252.078407 -81.294353)
			(xy 252.104144 -81.28) (xy 252.116539 -81.272837) (xy 252.137076 -81.252913) (xy 252.15128 -81.228074)
			(xy 252.158035 -81.200269) (xy 252.156811 -81.171682) (xy 252.147704 -81.144556) (xy 252.13143 -81.121021)
			(xy 252.120654 -81.111598) (xy 252.099177 -81.093401) (xy 252.061302 -81.051757) (xy 252.029965 -81.004995)
			(xy 252.005847 -80.954132) (xy 251.989474 -80.900275) (xy 251.981201 -80.844596) (xy 251.9807 -80.81645)
			(xy 251.981186 -80.789199) (xy 251.988942 -80.735251) (xy 252.004297 -80.682956) (xy 252.026939 -80.633379)
			(xy 252.056405 -80.587529) (xy 252.092096 -80.546338) (xy 252.133287 -80.510647) (xy 252.179137 -80.481181)
			(xy 252.228714 -80.458539) (xy 252.281009 -80.443184) (xy 252.334957 -80.435428) (xy 252.389459 -80.435428)
			(xy 252.443407 -80.443184) (xy 252.495702 -80.458539) (xy 252.545279 -80.481181) (xy 252.591129 -80.510647)
			(xy 252.63232 -80.546338) (xy 252.668011 -80.587529) (xy 252.697477 -80.633379) (xy 252.720119 -80.682956)
			(xy 252.735474 -80.735251) (xy 252.740976 -80.773524) (xy 253.898652 -80.773524) (xy 253.902723 -80.717902)
			(xy 253.914849 -80.663465) (xy 253.934772 -80.611374) (xy 253.962068 -80.562739) (xy 253.996154 -80.518596)
			(xy 254.036303 -80.479887) (xy 254.081661 -80.447436) (xy 254.131261 -80.421935) (xy 254.184045 -80.403928)
			(xy 254.238888 -80.393798) (xy 254.294622 -80.391761) (xy 254.350059 -80.397861) (xy 254.404016 -80.411967)
			(xy 254.455345 -80.433779) (xy 254.502951 -80.462833) (xy 254.545819 -80.498508) (xy 254.583036 -80.540045)
			(xy 254.613809 -80.586558) (xy 254.637481 -80.637055) (xy 254.653549 -80.690462) (xy 254.661669 -80.745638)
			(xy 254.662178 -80.773524) (xy 254.661974 -80.7847) (xy 254.772158 -80.7847) (xy 254.776229 -80.729078)
			(xy 254.788355 -80.674641) (xy 254.808278 -80.62255) (xy 254.835574 -80.573915) (xy 254.86966 -80.529772)
			(xy 254.909809 -80.491063) (xy 254.955167 -80.458612) (xy 255.004767 -80.433111) (xy 255.057551 -80.415104)
			(xy 255.112394 -80.404974) (xy 255.168128 -80.402937) (xy 255.223565 -80.409037) (xy 255.277522 -80.423143)
			(xy 255.328851 -80.444955) (xy 255.376457 -80.474009) (xy 255.419325 -80.509684) (xy 255.456542 -80.551221)
			(xy 255.487315 -80.597734) (xy 255.510987 -80.648231) (xy 255.527055 -80.701638) (xy 255.535175 -80.756814)
			(xy 255.535684 -80.7847) (xy 255.535175 -80.812586) (xy 255.527055 -80.867762) (xy 255.510987 -80.921169)
			(xy 255.500214 -80.94415) (xy 273.221431 -80.94415) (xy 273.221431 -80.88685) (xy 273.229585 -80.830134)
			(xy 273.245729 -80.775156) (xy 273.269532 -80.723035) (xy 273.300511 -80.674832) (xy 273.338034 -80.631528)
			(xy 273.381338 -80.594006) (xy 273.429542 -80.563028) (xy 273.481664 -80.539226) (xy 273.536642 -80.523084)
			(xy 273.593358 -80.51493) (xy 273.622008 -80.514444) (xy 273.649359 -80.514954) (xy 273.70355 -80.522418)
			(xy 273.756223 -80.537179) (xy 273.806401 -80.558962) (xy 273.853152 -80.587365) (xy 273.895609 -80.621858)
			(xy 273.932983 -80.661803) (xy 273.94916 -80.683862) (xy 273.954745 -80.691103) (xy 273.969838 -80.701399)
			(xy 273.978624 -80.703928) (xy 274.008596 -80.711294) (xy 274.017547 -80.713034) (xy 274.035635 -80.710822)
			(xy 274.043902 -80.706976) (xy 274.068542 -80.694613) (xy 274.120136 -80.67519) (xy 274.17369 -80.662103)
			(xy 274.228427 -80.655542) (xy 274.255992 -80.65516) (xy 274.285958 -80.655689) (xy 274.345378 -80.663511)
			(xy 274.403268 -80.679021) (xy 274.458639 -80.701954) (xy 274.510543 -80.731919) (xy 274.558092 -80.768401)
			(xy 274.600472 -80.810778) (xy 274.636959 -80.858324) (xy 274.666928 -80.910225) (xy 274.689866 -80.965594)
			(xy 274.705381 -81.023483) (xy 274.713208 -81.082902) (xy 274.7137 -81.112868) (xy 274.7137 -81.976468)
			(xy 274.713209 -82.006437) (xy 274.705389 -82.065862) (xy 274.68988 -82.123757) (xy 274.666945 -82.179133)
			(xy 274.636979 -82.231041) (xy 274.600493 -82.278594) (xy 274.558112 -82.320977) (xy 274.510561 -82.357466)
			(xy 274.458655 -82.387435) (xy 274.40328 -82.410372) (xy 274.345385 -82.425885) (xy 274.285961 -82.433707)
			(xy 274.255992 -82.434176) (xy 274.255484 -82.434176) (xy 274.228045 -82.433761) (xy 274.173568 -82.427145)
			(xy 274.120273 -82.414058) (xy 274.068927 -82.394688) (xy 274.04441 -82.38236) (xy 274.036079 -82.378492)
			(xy 274.017842 -82.376417) (xy 274.00885 -82.378296) (xy 273.978878 -82.385662) (xy 273.970122 -82.388157)
			(xy 273.955021 -82.398301) (xy 273.949414 -82.405474) (xy 273.933226 -82.427571) (xy 273.89586 -82.467624)
			(xy 273.853391 -82.502218) (xy 273.80661 -82.530711) (xy 273.756386 -82.552573) (xy 273.703654 -82.567396)
			(xy 273.649395 -82.574906) (xy 273.622008 -82.5754) (xy 273.59336 -82.574846) (xy 273.536647 -82.566693)
			(xy 273.481672 -82.550552) (xy 273.429553 -82.526751) (xy 273.381353 -82.495775) (xy 273.338051 -82.458255)
			(xy 273.30053 -82.414954) (xy 273.269553 -82.366754) (xy 273.245751 -82.314636) (xy 273.229609 -82.259661)
			(xy 273.221455 -82.202948) (xy 273.221455 -82.145652) (xy 273.229609 -82.088939) (xy 273.245751 -82.033964)
			(xy 273.269553 -81.981846) (xy 273.30053 -81.933646) (xy 273.338051 -81.890345) (xy 273.381353 -81.852825)
			(xy 273.429553 -81.821849) (xy 273.481672 -81.798048) (xy 273.536647 -81.781907) (xy 273.59336 -81.773754)
			(xy 273.622008 -81.773268) (xy 273.636926 -81.773441) (xy 273.666675 -81.775727) (xy 273.681444 -81.77784)
			(xy 273.69262 -81.779618) (xy 273.713702 -81.773522) (xy 273.780758 -81.715864) (xy 273.788705 -81.708254)
			(xy 273.797799 -81.688247) (xy 273.798284 -81.677256) (xy 273.798284 -81.412588) (xy 273.79779 -81.401598)
			(xy 273.788707 -81.381585) (xy 273.780758 -81.37398) (xy 273.713702 -81.316322) (xy 273.69262 -81.310226)
			(xy 273.681444 -81.312004) (xy 273.666674 -81.31411) (xy 273.636926 -81.3164) (xy 273.622008 -81.316576)
			(xy 273.593358 -81.31607) (xy 273.536642 -81.307916) (xy 273.481664 -81.291774) (xy 273.429542 -81.267972)
			(xy 273.381338 -81.236994) (xy 273.338034 -81.199472) (xy 273.300511 -81.156168) (xy 273.269532 -81.107965)
			(xy 273.245729 -81.055844) (xy 273.229585 -81.000866) (xy 273.221431 -80.94415) (xy 255.500214 -80.94415)
			(xy 255.487315 -80.971666) (xy 255.456542 -81.018179) (xy 255.419325 -81.059716) (xy 255.376457 -81.095391)
			(xy 255.328851 -81.124445) (xy 255.277522 -81.146257) (xy 255.223565 -81.160363) (xy 255.168128 -81.166463)
			(xy 255.112394 -81.164426) (xy 255.057551 -81.154296) (xy 255.004767 -81.136289) (xy 254.955167 -81.110788)
			(xy 254.909809 -81.078337) (xy 254.86966 -81.039628) (xy 254.835574 -80.995485) (xy 254.808278 -80.94685)
			(xy 254.788355 -80.894759) (xy 254.776229 -80.840322) (xy 254.772158 -80.7847) (xy 254.661974 -80.7847)
			(xy 254.661669 -80.80141) (xy 254.653549 -80.856586) (xy 254.637481 -80.909993) (xy 254.613809 -80.96049)
			(xy 254.583036 -81.007003) (xy 254.545819 -81.04854) (xy 254.502951 -81.084215) (xy 254.455345 -81.113269)
			(xy 254.404016 -81.135081) (xy 254.350059 -81.149187) (xy 254.294622 -81.155287) (xy 254.238888 -81.15325)
			(xy 254.184045 -81.14312) (xy 254.131261 -81.125113) (xy 254.081661 -81.099612) (xy 254.036303 -81.067161)
			(xy 253.996154 -81.028452) (xy 253.962068 -80.984309) (xy 253.934772 -80.935674) (xy 253.914849 -80.883583)
			(xy 253.902723 -80.829146) (xy 253.898652 -80.773524) (xy 252.740976 -80.773524) (xy 252.74323 -80.789199)
			(xy 252.743716 -80.81645) (xy 252.743188 -80.845912) (xy 252.734108 -80.904134) (xy 252.716187 -80.960268)
			(xy 252.689852 -81.012981) (xy 252.655727 -81.061019) (xy 252.614625 -81.103242) (xy 252.567521 -81.138646)
			(xy 252.541786 -81.153) (xy 252.529391 -81.160165) (xy 252.508849 -81.180086) (xy 252.494641 -81.204925)
			(xy 252.487884 -81.232731) (xy 252.489109 -81.26132) (xy 252.498218 -81.288447) (xy 252.514497 -81.31198)
			(xy 252.525276 -81.321402) (xy 252.546759 -81.339592) (xy 252.584632 -81.381238) (xy 252.615968 -81.428002)
			(xy 252.640084 -81.478866) (xy 252.656456 -81.532724) (xy 252.664729 -81.588404) (xy 252.66523 -81.61655)
			(xy 252.664744 -81.643801) (xy 252.656988 -81.697749) (xy 252.641633 -81.750044) (xy 252.618991 -81.799621)
			(xy 252.589525 -81.845471) (xy 252.586722 -81.848706) (xy 253.2794 -81.848706) (xy 253.283471 -81.793084)
			(xy 253.295597 -81.738647) (xy 253.31552 -81.686556) (xy 253.342816 -81.637921) (xy 253.376902 -81.593778)
			(xy 253.417051 -81.555069) (xy 253.462409 -81.522618) (xy 253.512009 -81.497117) (xy 253.564793 -81.47911)
			(xy 253.619636 -81.46898) (xy 253.67537 -81.466943) (xy 253.730807 -81.473043) (xy 253.784764 -81.487149)
			(xy 253.836093 -81.508961) (xy 253.883699 -81.538015) (xy 253.913669 -81.562956) (xy 264.230864 -81.562956)
			(xy 264.234935 -81.507334) (xy 264.247061 -81.452897) (xy 264.266984 -81.400806) (xy 264.29428 -81.352171)
			(xy 264.328366 -81.308028) (xy 264.368515 -81.269319) (xy 264.413873 -81.236868) (xy 264.463473 -81.211367)
			(xy 264.516257 -81.19336) (xy 264.5711 -81.18323) (xy 264.626834 -81.181193) (xy 264.682271 -81.187293)
			(xy 264.736228 -81.201399) (xy 264.787557 -81.223211) (xy 264.835163 -81.252265) (xy 264.878031 -81.28794)
			(xy 264.915248 -81.329477) (xy 264.946021 -81.37599) (xy 264.969693 -81.426487) (xy 264.985761 -81.479894)
			(xy 264.993881 -81.53507) (xy 264.99439 -81.562956) (xy 264.993881 -81.590842) (xy 264.985761 -81.646018)
			(xy 264.969693 -81.699425) (xy 264.946021 -81.749922) (xy 264.915248 -81.796435) (xy 264.878031 -81.837972)
			(xy 264.835163 -81.873647) (xy 264.787557 -81.902701) (xy 264.736228 -81.924513) (xy 264.682271 -81.938619)
			(xy 264.626834 -81.944719) (xy 264.5711 -81.942682) (xy 264.516257 -81.932552) (xy 264.463473 -81.914545)
			(xy 264.413873 -81.889044) (xy 264.368515 -81.856593) (xy 264.328366 -81.817884) (xy 264.29428 -81.773741)
			(xy 264.266984 -81.725106) (xy 264.247061 -81.673015) (xy 264.234935 -81.618578) (xy 264.230864 -81.562956)
			(xy 253.913669 -81.562956) (xy 253.926567 -81.57369) (xy 253.963784 -81.615227) (xy 253.994557 -81.66174)
			(xy 254.018229 -81.712237) (xy 254.034297 -81.765644) (xy 254.042417 -81.82082) (xy 254.042926 -81.848706)
			(xy 254.042417 -81.876592) (xy 254.034297 -81.931768) (xy 254.018229 -81.985175) (xy 253.994557 -82.035672)
			(xy 253.980792 -82.056478) (xy 254.425956 -82.056478) (xy 254.430027 -82.000856) (xy 254.442153 -81.946419)
			(xy 254.462076 -81.894328) (xy 254.489372 -81.845693) (xy 254.523458 -81.80155) (xy 254.563607 -81.762841)
			(xy 254.608965 -81.73039) (xy 254.658565 -81.704889) (xy 254.711349 -81.686882) (xy 254.766192 -81.676752)
			(xy 254.821926 -81.674715) (xy 254.877363 -81.680815) (xy 254.93132 -81.694921) (xy 254.982649 -81.716733)
			(xy 255.030255 -81.745787) (xy 255.073123 -81.781462) (xy 255.11034 -81.822999) (xy 255.141113 -81.869512)
			(xy 255.164785 -81.920009) (xy 255.180853 -81.973416) (xy 255.188973 -82.028592) (xy 255.189482 -82.056478)
			(xy 255.188973 -82.084364) (xy 255.181676 -82.133948) (xy 257.009898 -82.133948) (xy 257.013969 -82.078326)
			(xy 257.026095 -82.023889) (xy 257.046018 -81.971798) (xy 257.073314 -81.923163) (xy 257.1074 -81.87902)
			(xy 257.147549 -81.840311) (xy 257.192907 -81.80786) (xy 257.242507 -81.782359) (xy 257.295291 -81.764352)
			(xy 257.350134 -81.754222) (xy 257.405868 -81.752185) (xy 257.461305 -81.758285) (xy 257.515262 -81.772391)
			(xy 257.566591 -81.794203) (xy 257.614197 -81.823257) (xy 257.657065 -81.858932) (xy 257.694282 -81.900469)
			(xy 257.725055 -81.946982) (xy 257.748727 -81.997479) (xy 257.752875 -82.011266) (xy 259.066536 -82.011266)
			(xy 259.070607 -81.955644) (xy 259.082733 -81.901207) (xy 259.102656 -81.849116) (xy 259.129952 -81.800481)
			(xy 259.164038 -81.756338) (xy 259.204187 -81.717629) (xy 259.249545 -81.685178) (xy 259.299145 -81.659677)
			(xy 259.351929 -81.64167) (xy 259.406772 -81.63154) (xy 259.462506 -81.629503) (xy 259.517943 -81.635603)
			(xy 259.5719 -81.649709) (xy 259.623229 -81.671521) (xy 259.670835 -81.700575) (xy 259.713703 -81.73625)
			(xy 259.75092 -81.777787) (xy 259.781693 -81.8243) (xy 259.805365 -81.874797) (xy 259.821433 -81.928204)
			(xy 259.829553 -81.98338) (xy 259.830062 -82.011266) (xy 259.829937 -82.018124) (xy 260.23011 -82.018124)
			(xy 260.234181 -81.962502) (xy 260.246307 -81.908065) (xy 260.26623 -81.855974) (xy 260.293526 -81.807339)
			(xy 260.327612 -81.763196) (xy 260.367761 -81.724487) (xy 260.413119 -81.692036) (xy 260.462719 -81.666535)
			(xy 260.515503 -81.648528) (xy 260.570346 -81.638398) (xy 260.62608 -81.636361) (xy 260.681517 -81.642461)
			(xy 260.735474 -81.656567) (xy 260.786803 -81.678379) (xy 260.834409 -81.707433) (xy 260.877277 -81.743108)
			(xy 260.914494 -81.784645) (xy 260.945267 -81.831158) (xy 260.968939 -81.881655) (xy 260.985007 -81.935062)
			(xy 260.993127 -81.990238) (xy 260.993636 -82.018124) (xy 260.993127 -82.04601) (xy 260.985007 -82.101186)
			(xy 260.968939 -82.154593) (xy 260.945267 -82.20509) (xy 260.914494 -82.251603) (xy 260.877277 -82.29314)
			(xy 260.834409 -82.328815) (xy 260.786803 -82.357869) (xy 260.735474 -82.379681) (xy 260.681517 -82.393787)
			(xy 260.62608 -82.399887) (xy 260.570346 -82.39785) (xy 260.515503 -82.38772) (xy 260.462719 -82.369713)
			(xy 260.413119 -82.344212) (xy 260.367761 -82.311761) (xy 260.327612 -82.273052) (xy 260.293526 -82.228909)
			(xy 260.26623 -82.180274) (xy 260.246307 -82.128183) (xy 260.234181 -82.073746) (xy 260.23011 -82.018124)
			(xy 259.829937 -82.018124) (xy 259.829553 -82.039152) (xy 259.821433 -82.094328) (xy 259.805365 -82.147735)
			(xy 259.781693 -82.198232) (xy 259.75092 -82.244745) (xy 259.713703 -82.286282) (xy 259.670835 -82.321957)
			(xy 259.623229 -82.351011) (xy 259.5719 -82.372823) (xy 259.517943 -82.386929) (xy 259.462506 -82.393029)
			(xy 259.406772 -82.390992) (xy 259.351929 -82.380862) (xy 259.299145 -82.362855) (xy 259.249545 -82.337354)
			(xy 259.204187 -82.304903) (xy 259.164038 -82.266194) (xy 259.129952 -82.222051) (xy 259.102656 -82.173416)
			(xy 259.082733 -82.121325) (xy 259.070607 -82.066888) (xy 259.066536 -82.011266) (xy 257.752875 -82.011266)
			(xy 257.764795 -82.050886) (xy 257.772915 -82.106062) (xy 257.773424 -82.133948) (xy 257.772915 -82.161834)
			(xy 257.764795 -82.21701) (xy 257.748727 -82.270417) (xy 257.725055 -82.320914) (xy 257.694282 -82.367427)
			(xy 257.657065 -82.408964) (xy 257.614197 -82.444639) (xy 257.566591 -82.473693) (xy 257.515262 -82.495505)
			(xy 257.461305 -82.509611) (xy 257.405868 -82.515711) (xy 257.350134 -82.513674) (xy 257.295291 -82.503544)
			(xy 257.242507 -82.485537) (xy 257.192907 -82.460036) (xy 257.147549 -82.427585) (xy 257.1074 -82.388876)
			(xy 257.073314 -82.344733) (xy 257.046018 -82.296098) (xy 257.026095 -82.244007) (xy 257.013969 -82.18957)
			(xy 257.009898 -82.133948) (xy 255.181676 -82.133948) (xy 255.180853 -82.13954) (xy 255.164785 -82.192947)
			(xy 255.141113 -82.243444) (xy 255.11034 -82.289957) (xy 255.073123 -82.331494) (xy 255.030255 -82.367169)
			(xy 254.982649 -82.396223) (xy 254.93132 -82.418035) (xy 254.877363 -82.432141) (xy 254.821926 -82.438241)
			(xy 254.766192 -82.436204) (xy 254.711349 -82.426074) (xy 254.658565 -82.408067) (xy 254.608965 -82.382566)
			(xy 254.563607 -82.350115) (xy 254.523458 -82.311406) (xy 254.489372 -82.267263) (xy 254.462076 -82.218628)
			(xy 254.442153 -82.166537) (xy 254.430027 -82.1121) (xy 254.425956 -82.056478) (xy 253.980792 -82.056478)
			(xy 253.963784 -82.082185) (xy 253.926567 -82.123722) (xy 253.883699 -82.159397) (xy 253.836093 -82.188451)
			(xy 253.784764 -82.210263) (xy 253.730807 -82.224369) (xy 253.67537 -82.230469) (xy 253.619636 -82.228432)
			(xy 253.564793 -82.218302) (xy 253.512009 -82.200295) (xy 253.462409 -82.174794) (xy 253.417051 -82.142343)
			(xy 253.376902 -82.103634) (xy 253.342816 -82.059491) (xy 253.31552 -82.010856) (xy 253.295597 -81.958765)
			(xy 253.283471 -81.904328) (xy 253.2794 -81.848706) (xy 252.586722 -81.848706) (xy 252.553834 -81.886662)
			(xy 252.512643 -81.922353) (xy 252.466793 -81.951819) (xy 252.417216 -81.974461) (xy 252.364921 -81.989816)
			(xy 252.310973 -81.997572) (xy 252.256471 -81.997572) (xy 252.202523 -81.989816) (xy 252.150228 -81.974461)
			(xy 252.100651 -81.951819) (xy 252.054801 -81.922353) (xy 252.01361 -81.886662) (xy 251.977919 -81.845471)
			(xy 251.948453 -81.799621) (xy 251.925811 -81.750044) (xy 251.910456 -81.697749) (xy 251.9027 -81.643801)
			(xy 251.902214 -81.61655) (xy 251.262388 -81.61655) (xy 251.262388 -82.052414) (xy 251.261951 -82.07642)
			(xy 251.254401 -82.123834) (xy 251.239521 -82.169482) (xy 251.217677 -82.212238) (xy 251.189408 -82.251045)
			(xy 251.172726 -82.268314) (xy 251.011182 -82.429858) (xy 250.993904 -82.446527) (xy 250.955093 -82.474783)
			(xy 250.912339 -82.496619) (xy 250.866695 -82.511497) (xy 250.819285 -82.519052) (xy 250.795282 -82.51952)
			(xy 247.431306 -82.51952) (xy 247.40487 -82.518888) (xy 247.352808 -82.509652) (xy 247.303118 -82.491577)
			(xy 247.279922 -82.47888) (xy 247.272653 -82.475093) (xy 247.256594 -82.471857) (xy 247.248426 -82.47253)
			(xy 247.218962 -82.476086) (xy 247.210832 -82.477383) (xy 247.195934 -82.484365) (xy 247.189752 -82.489802)
			(xy 247.168322 -82.509701) (xy 247.12051 -82.543372) (xy 247.068115 -82.569344) (xy 247.012368 -82.587007)
			(xy 246.954577 -82.595946) (xy 246.925338 -82.596482) (xy 246.898081 -82.596074) (xy 246.844123 -82.588321)
			(xy 246.791817 -82.572967) (xy 246.742228 -82.550325) (xy 246.696367 -82.520856) (xy 246.655167 -82.48516)
			(xy 246.619467 -82.443963) (xy 246.589993 -82.398105) (xy 246.567347 -82.348519) (xy 246.551988 -82.296214)
			(xy 246.544229 -82.242256) (xy 239.906033 -82.242256) (xy 239.910636 -82.277209) (xy 239.911128 -82.307176)
			(xy 239.911128 -82.30743) (xy 239.910836 -82.329996) (xy 239.906383 -82.374908) (xy 239.902238 -82.397092)
			(xy 239.900606 -82.408908) (xy 239.907099 -82.431828) (xy 239.914684 -82.441034) (xy 239.978692 -82.51063)
			(xy 240.001806 -82.519266) (xy 240.013744 -82.517742) (xy 240.025385 -82.516448) (xy 240.048768 -82.515048)
			(xy 240.06048 -82.514948) (xy 240.089109 -82.515477) (xy 240.145784 -82.523622) (xy 240.200723 -82.539749)
			(xy 240.252808 -82.563529) (xy 240.300979 -82.59448) (xy 240.344256 -82.63197) (xy 240.381758 -82.675237)
			(xy 240.41272 -82.7234) (xy 240.436515 -82.775479) (xy 240.437507 -82.778854) (xy 261.582408 -82.778854)
			(xy 261.58293 -82.750012) (xy 261.591615 -82.692986) (xy 261.608779 -82.637915) (xy 261.634032 -82.586053)
			(xy 261.666799 -82.53858) (xy 261.706335 -82.496576) (xy 261.728712 -82.478372) (xy 261.737484 -82.47082)
			(xy 261.747661 -82.450054) (xy 261.74827 -82.438494) (xy 261.74827 -82.35823) (xy 261.747693 -82.346663)
			(xy 261.737504 -82.325891) (xy 261.728712 -82.318352) (xy 261.706325 -82.300159) (xy 261.666787 -82.258155)
			(xy 261.634019 -82.210681) (xy 261.608768 -82.158816) (xy 261.59161 -82.103742) (xy 261.582934 -82.046713)
			(xy 261.582408 -82.01787) (xy 261.582894 -81.990619) (xy 261.59065 -81.936671) (xy 261.606005 -81.884376)
			(xy 261.628647 -81.834799) (xy 261.658113 -81.788949) (xy 261.693804 -81.747758) (xy 261.734995 -81.712067)
			(xy 261.780845 -81.682601) (xy 261.830422 -81.659959) (xy 261.882717 -81.644604) (xy 261.936665 -81.636848)
			(xy 261.991167 -81.636848) (xy 262.045115 -81.644604) (xy 262.09741 -81.659959) (xy 262.146987 -81.682601)
			(xy 262.192837 -81.712067) (xy 262.234028 -81.747758) (xy 262.269719 -81.788949) (xy 262.299185 -81.834799)
			(xy 262.321827 -81.884376) (xy 262.337182 -81.936671) (xy 262.344938 -81.990619) (xy 262.345424 -82.01787)
			(xy 262.344907 -82.046712) (xy 262.33622 -82.103738) (xy 262.319054 -82.158808) (xy 262.2938 -82.21067)
			(xy 262.261032 -82.258143) (xy 262.221497 -82.300147) (xy 262.19912 -82.318352) (xy 262.190371 -82.325925)
			(xy 262.180184 -82.346676) (xy 262.179562 -82.35823) (xy 262.179562 -82.438494) (xy 262.180115 -82.450065)
			(xy 262.19032 -82.470837) (xy 262.19912 -82.478372) (xy 262.221525 -82.496544) (xy 262.261061 -82.538553)
			(xy 262.293825 -82.586032) (xy 262.319073 -82.637901) (xy 262.336228 -82.692979) (xy 262.3449 -82.75001)
			(xy 262.345424 -82.778854) (xy 262.344908 -82.808427) (xy 262.335786 -82.866866) (xy 262.317753 -82.923197)
			(xy 262.291242 -82.976069) (xy 262.256887 -83.024216) (xy 262.215513 -83.066483) (xy 262.168111 -83.101857)
			(xy 262.142224 -83.116166) (xy 262.129778 -83.12277) (xy 262.115046 -83.1469) (xy 262.115344 -83.208028)
			(xy 273.37491 -83.208028) (xy 273.37491 -83.150772) (xy 273.383058 -83.094099) (xy 273.399188 -83.039162)
			(xy 273.422972 -82.98708) (xy 273.453926 -82.938913) (xy 273.491419 -82.89564) (xy 273.534688 -82.858144)
			(xy 273.582854 -82.827187) (xy 273.634934 -82.803399) (xy 273.68987 -82.787265) (xy 273.746542 -82.779113)
			(xy 273.77517 -82.7786) (xy 273.802517 -82.779024) (xy 273.856703 -82.786447) (xy 273.909377 -82.801173)
			(xy 273.959557 -82.822927) (xy 274.006311 -82.851305) (xy 274.04877 -82.88578) (xy 274.086145 -82.925711)
			(xy 274.102322 -82.947764) (xy 274.107885 -82.955024) (xy 274.122993 -82.96531) (xy 274.131786 -82.96783)
			(xy 274.161758 -82.975196) (xy 274.170711 -82.976917) (xy 274.188796 -82.974718) (xy 274.197064 -82.970878)
			(xy 274.2217 -82.958489) (xy 274.273285 -82.939002) (xy 274.326838 -82.925849) (xy 274.381582 -82.919222)
			(xy 274.409154 -82.918808) (xy 274.439137 -82.91935) (xy 274.498592 -82.927171) (xy 274.556517 -82.942687)
			(xy 274.611921 -82.96563) (xy 274.663856 -82.995608) (xy 274.711434 -83.03211) (xy 274.75384 -83.074509)
			(xy 274.790349 -83.122081) (xy 274.820337 -83.174011) (xy 274.843289 -83.229411) (xy 274.858814 -83.287334)
			(xy 274.866645 -83.346787) (xy 274.867116 -83.37677) (xy 274.867116 -84.24037) (xy 274.866665 -84.270357)
			(xy 274.85884 -84.329818) (xy 274.843319 -84.387749) (xy 274.82037 -84.443158) (xy 274.790384 -84.495097)
			(xy 274.753874 -84.542677) (xy 274.711465 -84.585084) (xy 274.663884 -84.621592) (xy 274.611943 -84.651577)
			(xy 274.556534 -84.674525) (xy 274.498602 -84.690043) (xy 274.439141 -84.697866) (xy 274.409154 -84.698332)
			(xy 274.381645 -84.697914) (xy 274.327029 -84.691256) (xy 274.273605 -84.678103) (xy 274.222141 -84.658643)
			(xy 274.197572 -84.646262) (xy 274.18916 -84.642431) (xy 274.17081 -84.640334) (xy 274.161758 -84.642198)
			(xy 274.13204 -84.649564) (xy 274.123278 -84.652043) (xy 274.10818 -84.662199) (xy 274.102576 -84.669376)
			(xy 274.086418 -84.691489) (xy 274.049045 -84.731521) (xy 274.006567 -84.766089) (xy 273.959776 -84.79455)
			(xy 273.909545 -84.816371) (xy 273.85681 -84.831148) (xy 273.802553 -84.838603) (xy 273.77517 -84.839048)
			(xy 273.746544 -84.838464) (xy 273.689875 -84.830312) (xy 273.634942 -84.814179) (xy 273.582865 -84.790392)
			(xy 273.534703 -84.759437) (xy 273.491436 -84.721943) (xy 273.453945 -84.678673) (xy 273.422993 -84.630508)
			(xy 273.399211 -84.578429) (xy 273.383082 -84.523496) (xy 273.374934 -84.466826) (xy 273.374934 -84.409574)
			(xy 273.383082 -84.352904) (xy 273.399211 -84.297971) (xy 273.422993 -84.245892) (xy 273.453945 -84.197727)
			(xy 273.491436 -84.154457) (xy 273.534703 -84.116963) (xy 273.582865 -84.086008) (xy 273.634942 -84.062221)
			(xy 273.689875 -84.046088) (xy 273.746544 -84.037936) (xy 273.77517 -84.037424) (xy 273.790084 -84.037531)
			(xy 273.819833 -84.039693) (xy 273.834606 -84.041742) (xy 273.845782 -84.04352) (xy 273.866864 -84.037424)
			(xy 273.933666 -83.979766) (xy 273.941613 -83.972157) (xy 273.950707 -83.952149) (xy 273.951192 -83.941158)
			(xy 273.951192 -83.67649) (xy 273.950695 -83.6655) (xy 273.941614 -83.645488) (xy 273.933666 -83.637882)
			(xy 273.866864 -83.580224) (xy 273.845782 -83.574128) (xy 273.834606 -83.575906) (xy 273.819832 -83.577949)
			(xy 273.790084 -83.580114) (xy 273.77517 -83.580224) (xy 273.746542 -83.579687) (xy 273.68987 -83.571535)
			(xy 273.634934 -83.555401) (xy 273.582854 -83.531613) (xy 273.534688 -83.500656) (xy 273.491419 -83.46316)
			(xy 273.453926 -83.419887) (xy 273.422972 -83.37172) (xy 273.399188 -83.319638) (xy 273.383058 -83.264701)
			(xy 273.37491 -83.208028) (xy 262.115344 -83.208028) (xy 262.115554 -83.25104) (xy 262.115961 -83.26027)
			(xy 262.122511 -83.277528) (xy 262.134748 -83.29135) (xy 262.142732 -83.295998) (xy 262.165525 -83.308464)
			(xy 262.207872 -83.338555) (xy 262.245744 -83.374115) (xy 262.278439 -83.414485) (xy 262.305353 -83.458919)
			(xy 262.325988 -83.506594) (xy 262.339961 -83.556629) (xy 262.347015 -83.608097) (xy 262.347456 -83.634072)
			(xy 262.34697 -83.661323) (xy 262.339214 -83.715271) (xy 262.323859 -83.767566) (xy 262.301217 -83.817143)
			(xy 262.271751 -83.862993) (xy 262.23606 -83.904184) (xy 262.194869 -83.939875) (xy 262.149019 -83.969341)
			(xy 262.099442 -83.991983) (xy 262.047147 -84.007338) (xy 261.993199 -84.015094) (xy 261.938697 -84.015094)
			(xy 261.884749 -84.007338) (xy 261.832454 -83.991983) (xy 261.782877 -83.969341) (xy 261.737027 -83.939875)
			(xy 261.695836 -83.904184) (xy 261.660145 -83.862993) (xy 261.630679 -83.817143) (xy 261.608037 -83.767566)
			(xy 261.592682 -83.715271) (xy 261.584926 -83.661323) (xy 261.58444 -83.634072) (xy 261.584996 -83.6045)
			(xy 261.594113 -83.546064) (xy 261.612141 -83.489736) (xy 261.638646 -83.436864) (xy 261.672993 -83.388717)
			(xy 261.714361 -83.346449) (xy 261.761756 -83.311071) (xy 261.78764 -83.29676) (xy 261.800086 -83.290156)
			(xy 261.814818 -83.266026) (xy 261.81431 -83.161886) (xy 261.813902 -83.152656) (xy 261.807356 -83.135395)
			(xy 261.795118 -83.121574) (xy 261.787132 -83.116928) (xy 261.764299 -83.104531) (xy 261.721953 -83.07443)
			(xy 261.684083 -83.038859) (xy 261.651392 -82.998479) (xy 261.624483 -82.954035) (xy 261.603855 -82.90635)
			(xy 261.589889 -82.856307) (xy 261.582844 -82.804832) (xy 261.582408 -82.778854) (xy 240.437507 -82.778854)
			(xy 240.452656 -82.830414) (xy 240.460816 -82.887087) (xy 240.460828 -82.944344) (xy 240.452692 -83.00102)
			(xy 240.436574 -83.055962) (xy 240.412802 -83.108051) (xy 240.381859 -83.156227) (xy 240.344376 -83.19951)
			(xy 240.301115 -83.237019) (xy 240.252957 -83.267989) (xy 240.200882 -83.291792) (xy 240.145949 -83.307942)
			(xy 240.089278 -83.316111) (xy 240.032021 -83.316132) (xy 239.975343 -83.308006) (xy 239.920399 -83.291897)
			(xy 239.868306 -83.268133) (xy 239.820124 -83.237198) (xy 239.776836 -83.199722) (xy 239.73932 -83.156467)
			(xy 239.708342 -83.108314) (xy 239.684531 -83.056242) (xy 239.668372 -83.001313) (xy 239.660194 -82.944642)
			(xy 239.659668 -82.916014) (xy 239.659743 -82.904047) (xy 239.66114 -82.880156) (xy 239.662462 -82.868262)
			(xy 239.663986 -82.85607) (xy 239.655604 -82.833464) (xy 239.577372 -82.76082) (xy 239.55375 -82.754216)
			(xy 239.541812 -82.756502) (xy 239.519934 -82.760489) (xy 239.475658 -82.764684) (xy 239.45342 -82.764884)
			(xy 238.58982 -82.764884) (xy 238.563513 -82.764529) (xy 238.511246 -82.758496) (xy 238.460017 -82.746506)
			(xy 238.435134 -82.73796) (xy 238.423582 -82.73453) (xy 238.399717 -82.737558) (xy 238.389414 -82.743802)
			(xy 238.321342 -82.790284) (xy 238.311814 -82.797627) (xy 238.300269 -82.818687) (xy 238.299244 -82.83067)
			(xy 238.297944 -82.858738) (xy 238.288428 -82.914116) (xy 238.271273 -82.967622) (xy 238.246815 -83.018209)
			(xy 238.215534 -83.064885) (xy 238.178042 -83.106737) (xy 238.135074 -83.142945) (xy 238.087472 -83.172798)
			(xy 238.036168 -83.195713) (xy 237.982167 -83.211241) (xy 237.926527 -83.219077) (xy 237.898432 -83.219544)
			(xy 237.869801 -83.218996) (xy 237.813121 -83.210851) (xy 237.758178 -83.194722) (xy 237.706089 -83.170937)
			(xy 237.657915 -83.139981) (xy 237.614638 -83.102485) (xy 237.577138 -83.05921) (xy 237.546178 -83.011039)
			(xy 237.52239 -82.958952) (xy 237.506256 -82.90401) (xy 237.498107 -82.847331) (xy 233.599736 -82.847331)
			(xy 233.599736 -83.367626) (xy 233.599233 -83.398191) (xy 233.591065 -83.458773) (xy 233.574904 -83.517729)
			(xy 233.551039 -83.574009) (xy 233.519894 -83.626611) (xy 233.482023 -83.674598) (xy 233.438102 -83.717116)
			(xy 233.413808 -83.735672) (xy 233.40441 -83.74253) (xy 233.393742 -83.762342) (xy 233.388662 -83.863688)
			(xy 233.397298 -83.88477) (xy 233.40568 -83.89239) (xy 233.425923 -83.911473) (xy 233.459075 -83.951318)
			(xy 236.444534 -83.951318) (xy 236.448605 -83.895696) (xy 236.460731 -83.841259) (xy 236.480654 -83.789168)
			(xy 236.50795 -83.740533) (xy 236.542036 -83.69639) (xy 236.582185 -83.657681) (xy 236.627543 -83.62523)
			(xy 236.677143 -83.599729) (xy 236.729927 -83.581722) (xy 236.78477 -83.571592) (xy 236.840504 -83.569555)
			(xy 236.895941 -83.575655) (xy 236.949898 -83.589761) (xy 237.001227 -83.611573) (xy 237.048833 -83.640627)
			(xy 237.091701 -83.676302) (xy 237.128918 -83.717839) (xy 237.159691 -83.764352) (xy 237.183363 -83.814849)
			(xy 237.199431 -83.868256) (xy 237.207551 -83.923432) (xy 237.20806 -83.951318) (xy 237.207551 -83.979204)
			(xy 237.199431 -84.03438) (xy 237.183363 -84.087787) (xy 237.159691 -84.138284) (xy 237.128918 -84.184797)
			(xy 237.091701 -84.226334) (xy 237.048833 -84.262009) (xy 237.001227 -84.291063) (xy 236.949898 -84.312875)
			(xy 236.895941 -84.326981) (xy 236.840504 -84.333081) (xy 236.78477 -84.331044) (xy 236.729927 -84.320914)
			(xy 236.677143 -84.302907) (xy 236.627543 -84.277406) (xy 236.582185 -84.244955) (xy 236.542036 -84.206246)
			(xy 236.50795 -84.162103) (xy 236.480654 -84.113468) (xy 236.460731 -84.061377) (xy 236.448605 -84.00694)
			(xy 236.444534 -83.951318) (xy 233.459075 -83.951318) (xy 233.461505 -83.954238) (xy 233.490828 -84.001515)
			(xy 233.513328 -84.052393) (xy 233.528572 -84.105895) (xy 233.536268 -84.160992) (xy 233.536744 -84.188808)
			(xy 233.536744 -84.189062) (xy 233.536233 -84.217692) (xy 233.528084 -84.27437) (xy 233.511952 -84.32931)
			(xy 233.488166 -84.381396) (xy 233.457208 -84.429567) (xy 233.454758 -84.432394) (xy 234.28909 -84.432394)
			(xy 234.293161 -84.376772) (xy 234.305287 -84.322335) (xy 234.32521 -84.270244) (xy 234.352506 -84.221609)
			(xy 234.386592 -84.177466) (xy 234.426741 -84.138757) (xy 234.472099 -84.106306) (xy 234.521699 -84.080805)
			(xy 234.574483 -84.062798) (xy 234.629326 -84.052668) (xy 234.68506 -84.050631) (xy 234.740497 -84.056731)
			(xy 234.794454 -84.070837) (xy 234.845783 -84.092649) (xy 234.893389 -84.121703) (xy 234.936257 -84.157378)
			(xy 234.973474 -84.198915) (xy 235.004247 -84.245428) (xy 235.027919 -84.295925) (xy 235.043987 -84.349332)
			(xy 235.052107 -84.404508) (xy 235.052616 -84.432394) (xy 235.052107 -84.46028) (xy 235.043987 -84.515456)
			(xy 235.027919 -84.568863) (xy 235.004247 -84.61936) (xy 234.973474 -84.665873) (xy 234.936257 -84.70741)
			(xy 234.893389 -84.743085) (xy 234.845783 -84.772139) (xy 234.794454 -84.793951) (xy 234.740497 -84.808057)
			(xy 234.68506 -84.814157) (xy 234.629326 -84.81212) (xy 234.574483 -84.80199) (xy 234.521699 -84.783983)
			(xy 234.472099 -84.758482) (xy 234.426741 -84.726031) (xy 234.386592 -84.687322) (xy 234.352506 -84.643179)
			(xy 234.32521 -84.594544) (xy 234.305287 -84.542453) (xy 234.293161 -84.488016) (xy 234.28909 -84.432394)
			(xy 233.454758 -84.432394) (xy 233.419711 -84.472841) (xy 233.376437 -84.510338) (xy 233.328266 -84.541296)
			(xy 233.27618 -84.565082) (xy 233.22124 -84.581214) (xy 233.164562 -84.589363) (xy 233.107302 -84.589363)
			(xy 233.050624 -84.581214) (xy 232.995684 -84.565082) (xy 232.943598 -84.541296) (xy 232.895427 -84.510338)
			(xy 232.852153 -84.472841) (xy 232.814656 -84.429567) (xy 232.783698 -84.381396) (xy 232.759912 -84.32931)
			(xy 232.74378 -84.27437) (xy 232.735631 -84.217692) (xy 232.73512 -84.189062) (xy 232.735558 -84.160745)
			(xy 232.743519 -84.104672) (xy 232.759293 -84.050278) (xy 232.782564 -83.998645) (xy 232.812869 -83.950801)
			(xy 232.849606 -83.907698) (xy 232.870502 -83.88858) (xy 232.878625 -83.880723) (xy 232.887584 -83.860004)
			(xy 232.887774 -83.848702) (xy 232.884472 -83.758532) (xy 232.874058 -83.738466) (xy 232.864914 -83.731608)
			(xy 232.841257 -83.712987) (xy 232.798523 -83.670579) (xy 232.761722 -83.622933) (xy 232.731488 -83.570871)
			(xy 232.708344 -83.515293) (xy 232.69269 -83.457159) (xy 232.684796 -83.397474) (xy 232.68432 -83.367372)
			(xy 225.276682 -83.367372) (xy 225.297211 -83.384456) (xy 225.334428 -83.425993) (xy 225.365201 -83.472506)
			(xy 225.388873 -83.523003) (xy 225.404941 -83.57641) (xy 225.413061 -83.631586) (xy 225.41357 -83.659472)
			(xy 225.413061 -83.687358) (xy 225.404941 -83.742534) (xy 225.388873 -83.795941) (xy 225.365201 -83.846438)
			(xy 225.334428 -83.892951) (xy 225.297211 -83.934488) (xy 225.254343 -83.970163) (xy 225.206737 -83.999217)
			(xy 225.155408 -84.021029) (xy 225.101451 -84.035135) (xy 225.046014 -84.041235) (xy 224.99028 -84.039198)
			(xy 224.935437 -84.029068) (xy 224.882653 -84.011061) (xy 224.833053 -83.98556) (xy 224.787695 -83.953109)
			(xy 224.747546 -83.9144) (xy 224.71346 -83.870257) (xy 224.686164 -83.821622) (xy 224.666241 -83.769531)
			(xy 224.654115 -83.715094) (xy 224.650044 -83.659472) (xy 223.387666 -83.659472) (xy 223.387157 -83.687358)
			(xy 223.379037 -83.742534) (xy 223.362969 -83.795941) (xy 223.339297 -83.846438) (xy 223.308524 -83.892951)
			(xy 223.271307 -83.934488) (xy 223.228439 -83.970163) (xy 223.180833 -83.999217) (xy 223.129504 -84.021029)
			(xy 223.075547 -84.035135) (xy 223.02011 -84.041235) (xy 222.964376 -84.039198) (xy 222.909533 -84.029068)
			(xy 222.856749 -84.011061) (xy 222.807149 -83.98556) (xy 222.761791 -83.953109) (xy 222.721642 -83.9144)
			(xy 222.687556 -83.870257) (xy 222.66026 -83.821622) (xy 222.640337 -83.769531) (xy 222.628211 -83.715094)
			(xy 222.62414 -83.659472) (xy 221.304562 -83.659472) (xy 221.293835 -83.682354) (xy 221.263062 -83.728867)
			(xy 221.225845 -83.770404) (xy 221.182977 -83.806079) (xy 221.135371 -83.835133) (xy 221.084042 -83.856945)
			(xy 221.030085 -83.871051) (xy 220.974648 -83.877151) (xy 220.918914 -83.875114) (xy 220.864071 -83.864984)
			(xy 220.811287 -83.846977) (xy 220.761687 -83.821476) (xy 220.716329 -83.789025) (xy 220.67618 -83.750316)
			(xy 220.642094 -83.706173) (xy 220.614798 -83.657538) (xy 220.594875 -83.605447) (xy 220.582749 -83.55101)
			(xy 220.578678 -83.495388) (xy 219.338765 -83.495388) (xy 219.386835 -83.515815) (xy 219.434441 -83.544869)
			(xy 219.477309 -83.580544) (xy 219.514526 -83.622081) (xy 219.545299 -83.668594) (xy 219.568971 -83.719091)
			(xy 219.585039 -83.772498) (xy 219.593159 -83.827674) (xy 219.593668 -83.85556) (xy 219.593159 -83.883446)
			(xy 219.585039 -83.938622) (xy 219.568971 -83.992029) (xy 219.545299 -84.042526) (xy 219.514526 -84.089039)
			(xy 219.477309 -84.130576) (xy 219.434441 -84.166251) (xy 219.386835 -84.195305) (xy 219.335506 -84.217117)
			(xy 219.281549 -84.231223) (xy 219.226112 -84.237323) (xy 219.170378 -84.235286) (xy 219.115535 -84.225156)
			(xy 219.062751 -84.207149) (xy 219.013151 -84.181648) (xy 218.967793 -84.149197) (xy 218.927644 -84.110488)
			(xy 218.893558 -84.066345) (xy 218.866262 -84.01771) (xy 218.846339 -83.965619) (xy 218.834213 -83.911182)
			(xy 218.830142 -83.85556) (xy 205.975369 -83.85556) (xy 205.9831 -83.909335) (xy 205.983586 -83.936586)
			(xy 205.98313 -83.963925) (xy 205.975343 -84.018044) (xy 205.95991 -84.070498) (xy 205.937149 -84.120212)
			(xy 205.907526 -84.166168) (xy 205.871646 -84.207426) (xy 205.851252 -84.225638) (xy 205.842616 -84.23275)
			(xy 205.833472 -84.253324) (xy 205.834488 -84.353654) (xy 205.84414 -84.373466) (xy 205.85303 -84.380832)
			(xy 205.874382 -84.399018) (xy 205.911993 -84.440622) (xy 205.943101 -84.487289) (xy 205.967035 -84.538011)
			(xy 205.983278 -84.591693) (xy 205.99148 -84.647175) (xy 205.991968 -84.675218) (xy 205.991968 -84.675472)
			(xy 205.991482 -84.702723) (xy 205.983726 -84.756671) (xy 205.981166 -84.765388) (xy 220.578678 -84.765388)
			(xy 220.582749 -84.709766) (xy 220.594875 -84.655329) (xy 220.614798 -84.603238) (xy 220.642094 -84.554603)
			(xy 220.67618 -84.51046) (xy 220.716329 -84.471751) (xy 220.761687 -84.4393) (xy 220.811287 -84.413799)
			(xy 220.864071 -84.395792) (xy 220.918914 -84.385662) (xy 220.974648 -84.383625) (xy 221.030085 -84.389725)
			(xy 221.084042 -84.403831) (xy 221.135371 -84.425643) (xy 221.182977 -84.454697) (xy 221.225845 -84.490372)
			(xy 221.263062 -84.531909) (xy 221.293835 -84.578422) (xy 221.317507 -84.628919) (xy 221.331513 -84.675472)
			(xy 222.62414 -84.675472) (xy 222.628211 -84.61985) (xy 222.640337 -84.565413) (xy 222.66026 -84.513322)
			(xy 222.687556 -84.464687) (xy 222.721642 -84.420544) (xy 222.761791 -84.381835) (xy 222.807149 -84.349384)
			(xy 222.856749 -84.323883) (xy 222.909533 -84.305876) (xy 222.964376 -84.295746) (xy 223.02011 -84.293709)
			(xy 223.075547 -84.299809) (xy 223.129504 -84.313915) (xy 223.180833 -84.335727) (xy 223.228439 -84.364781)
			(xy 223.271307 -84.400456) (xy 223.308524 -84.441993) (xy 223.339297 -84.488506) (xy 223.362969 -84.539003)
			(xy 223.379037 -84.59241) (xy 223.387157 -84.647586) (xy 223.387666 -84.675472) (xy 224.650044 -84.675472)
			(xy 224.654115 -84.61985) (xy 224.666241 -84.565413) (xy 224.686164 -84.513322) (xy 224.71346 -84.464687)
			(xy 224.747546 -84.420544) (xy 224.787695 -84.381835) (xy 224.833053 -84.349384) (xy 224.882653 -84.323883)
			(xy 224.935437 -84.305876) (xy 224.99028 -84.295746) (xy 225.046014 -84.293709) (xy 225.101451 -84.299809)
			(xy 225.155408 -84.313915) (xy 225.206737 -84.335727) (xy 225.254343 -84.364781) (xy 225.297211 -84.400456)
			(xy 225.308531 -84.41309) (xy 231.287572 -84.41309) (xy 231.291643 -84.357468) (xy 231.303769 -84.303031)
			(xy 231.323692 -84.25094) (xy 231.350988 -84.202305) (xy 231.385074 -84.158162) (xy 231.425223 -84.119453)
			(xy 231.470581 -84.087002) (xy 231.520181 -84.061501) (xy 231.572965 -84.043494) (xy 231.627808 -84.033364)
			(xy 231.683542 -84.031327) (xy 231.738979 -84.037427) (xy 231.792936 -84.051533) (xy 231.844265 -84.073345)
			(xy 231.891871 -84.102399) (xy 231.934739 -84.138074) (xy 231.971956 -84.179611) (xy 232.002729 -84.226124)
			(xy 232.026401 -84.276621) (xy 232.042469 -84.330028) (xy 232.050589 -84.385204) (xy 232.051098 -84.41309)
			(xy 232.050589 -84.440976) (xy 232.042469 -84.496152) (xy 232.026401 -84.549559) (xy 232.002729 -84.600056)
			(xy 231.971956 -84.646569) (xy 231.934739 -84.688106) (xy 231.891871 -84.723781) (xy 231.844265 -84.752835)
			(xy 231.792936 -84.774647) (xy 231.738979 -84.788753) (xy 231.683542 -84.794853) (xy 231.627808 -84.792816)
			(xy 231.572965 -84.782686) (xy 231.520181 -84.764679) (xy 231.470581 -84.739178) (xy 231.425223 -84.706727)
			(xy 231.385074 -84.668018) (xy 231.350988 -84.623875) (xy 231.323692 -84.57524) (xy 231.303769 -84.523149)
			(xy 231.291643 -84.468712) (xy 231.287572 -84.41309) (xy 225.308531 -84.41309) (xy 225.334428 -84.441993)
			(xy 225.365201 -84.488506) (xy 225.388873 -84.539003) (xy 225.404941 -84.59241) (xy 225.413061 -84.647586)
			(xy 225.41357 -84.675472) (xy 225.413061 -84.703358) (xy 225.404941 -84.758534) (xy 225.388873 -84.811941)
			(xy 225.365201 -84.862438) (xy 225.334428 -84.908951) (xy 225.297211 -84.950488) (xy 225.282787 -84.962492)
			(xy 227.845364 -84.962492) (xy 227.849435 -84.90687) (xy 227.861561 -84.852433) (xy 227.881484 -84.800342)
			(xy 227.90878 -84.751707) (xy 227.942866 -84.707564) (xy 227.983015 -84.668855) (xy 228.028373 -84.636404)
			(xy 228.077973 -84.610903) (xy 228.130757 -84.592896) (xy 228.1856 -84.582766) (xy 228.241334 -84.580729)
			(xy 228.296771 -84.586829) (xy 228.350728 -84.600935) (xy 228.402057 -84.622747) (xy 228.449663 -84.651801)
			(xy 228.492531 -84.687476) (xy 228.529748 -84.729013) (xy 228.560521 -84.775526) (xy 228.584193 -84.826023)
			(xy 228.600261 -84.87943) (xy 228.608381 -84.934606) (xy 228.60889 -84.962492) (xy 228.608381 -84.990378)
			(xy 228.600261 -85.045554) (xy 228.584193 -85.098961) (xy 228.560521 -85.149458) (xy 228.529748 -85.195971)
			(xy 228.492531 -85.237508) (xy 228.449663 -85.273183) (xy 228.402057 -85.302237) (xy 228.350728 -85.324049)
			(xy 228.296771 -85.338155) (xy 228.241334 -85.344255) (xy 228.1856 -85.342218) (xy 228.130757 -85.332088)
			(xy 228.077973 -85.314081) (xy 228.028373 -85.28858) (xy 227.983015 -85.256129) (xy 227.942866 -85.21742)
			(xy 227.90878 -85.173277) (xy 227.881484 -85.124642) (xy 227.861561 -85.072551) (xy 227.849435 -85.018114)
			(xy 227.845364 -84.962492) (xy 225.282787 -84.962492) (xy 225.254343 -84.986163) (xy 225.206737 -85.015217)
			(xy 225.155408 -85.037029) (xy 225.101451 -85.051135) (xy 225.046014 -85.057235) (xy 224.99028 -85.055198)
			(xy 224.935437 -85.045068) (xy 224.882653 -85.027061) (xy 224.833053 -85.00156) (xy 224.787695 -84.969109)
			(xy 224.747546 -84.9304) (xy 224.71346 -84.886257) (xy 224.686164 -84.837622) (xy 224.666241 -84.785531)
			(xy 224.654115 -84.731094) (xy 224.650044 -84.675472) (xy 223.387666 -84.675472) (xy 223.387157 -84.703358)
			(xy 223.379037 -84.758534) (xy 223.362969 -84.811941) (xy 223.339297 -84.862438) (xy 223.308524 -84.908951)
			(xy 223.271307 -84.950488) (xy 223.228439 -84.986163) (xy 223.180833 -85.015217) (xy 223.129504 -85.037029)
			(xy 223.075547 -85.051135) (xy 223.02011 -85.057235) (xy 222.964376 -85.055198) (xy 222.909533 -85.045068)
			(xy 222.856749 -85.027061) (xy 222.807149 -85.00156) (xy 222.761791 -84.969109) (xy 222.721642 -84.9304)
			(xy 222.687556 -84.886257) (xy 222.66026 -84.837622) (xy 222.640337 -84.785531) (xy 222.628211 -84.731094)
			(xy 222.62414 -84.675472) (xy 221.331513 -84.675472) (xy 221.333575 -84.682326) (xy 221.341695 -84.737502)
			(xy 221.342204 -84.765388) (xy 221.341695 -84.793274) (xy 221.333575 -84.84845) (xy 221.317507 -84.901857)
			(xy 221.293835 -84.952354) (xy 221.263062 -84.998867) (xy 221.225845 -85.040404) (xy 221.182977 -85.076079)
			(xy 221.135371 -85.105133) (xy 221.084042 -85.126945) (xy 221.030085 -85.141051) (xy 220.974648 -85.147151)
			(xy 220.918914 -85.145114) (xy 220.864071 -85.134984) (xy 220.811287 -85.116977) (xy 220.761687 -85.091476)
			(xy 220.716329 -85.059025) (xy 220.67618 -85.020316) (xy 220.642094 -84.976173) (xy 220.614798 -84.927538)
			(xy 220.594875 -84.875447) (xy 220.582749 -84.82101) (xy 220.578678 -84.765388) (xy 205.981166 -84.765388)
			(xy 205.968371 -84.808966) (xy 205.945729 -84.858543) (xy 205.916263 -84.904393) (xy 205.880572 -84.945584)
			(xy 205.839381 -84.981275) (xy 205.793531 -85.010741) (xy 205.743954 -85.033383) (xy 205.691659 -85.048738)
			(xy 205.637711 -85.056494) (xy 205.583209 -85.056494) (xy 205.529261 -85.048738) (xy 205.476966 -85.033383)
			(xy 205.427389 -85.010741) (xy 205.381539 -84.981275) (xy 205.340348 -84.945584) (xy 205.304657 -84.904393)
			(xy 205.275191 -84.858543) (xy 205.252549 -84.808966) (xy 205.237194 -84.756671) (xy 205.229438 -84.702723)
			(xy 205.228952 -84.675472) (xy 205.2294 -84.648133) (xy 205.237192 -84.594015) (xy 205.252628 -84.541562)
			(xy 205.27539 -84.491848) (xy 205.305014 -84.445892) (xy 205.340893 -84.404633) (xy 205.361286 -84.38642)
			(xy 205.369922 -84.379308) (xy 205.379066 -84.358734) (xy 205.37805 -84.258404) (xy 205.368398 -84.238592)
			(xy 205.359508 -84.231226) (xy 205.338172 -84.213024) (xy 205.300562 -84.171421) (xy 205.269454 -84.124757)
			(xy 205.245517 -84.074038) (xy 205.22927 -84.02036) (xy 205.221062 -83.964881) (xy 205.22057 -83.93684)
			(xy 200.363836 -83.93684) (xy 200.363836 -84.675472) (xy 202.825348 -84.675472) (xy 202.829419 -84.61985)
			(xy 202.841545 -84.565413) (xy 202.861468 -84.513322) (xy 202.888764 -84.464687) (xy 202.92285 -84.420544)
			(xy 202.962999 -84.381835) (xy 203.008357 -84.349384) (xy 203.057957 -84.323883) (xy 203.110741 -84.305876)
			(xy 203.165584 -84.295746) (xy 203.221318 -84.293709) (xy 203.276755 -84.299809) (xy 203.330712 -84.313915)
			(xy 203.382041 -84.335727) (xy 203.429647 -84.364781) (xy 203.472515 -84.400456) (xy 203.509732 -84.441993)
			(xy 203.540505 -84.488506) (xy 203.564177 -84.539003) (xy 203.580245 -84.59241) (xy 203.588365 -84.647586)
			(xy 203.588874 -84.675472) (xy 203.588365 -84.703358) (xy 203.580245 -84.758534) (xy 203.564177 -84.811941)
			(xy 203.540505 -84.862438) (xy 203.509732 -84.908951) (xy 203.472515 -84.950488) (xy 203.429647 -84.986163)
			(xy 203.382041 -85.015217) (xy 203.330712 -85.037029) (xy 203.276755 -85.051135) (xy 203.221318 -85.057235)
			(xy 203.165584 -85.055198) (xy 203.110741 -85.045068) (xy 203.057957 -85.027061) (xy 203.008357 -85.00156)
			(xy 202.962999 -84.969109) (xy 202.92285 -84.9304) (xy 202.888764 -84.886257) (xy 202.861468 -84.837622)
			(xy 202.841545 -84.785531) (xy 202.829419 -84.731094) (xy 202.825348 -84.675472) (xy 200.363836 -84.675472)
			(xy 200.363836 -85.691472) (xy 202.857352 -85.691472) (xy 202.861423 -85.63585) (xy 202.873549 -85.581413)
			(xy 202.893472 -85.529322) (xy 202.920768 -85.480687) (xy 202.954854 -85.436544) (xy 202.995003 -85.397835)
			(xy 203.040361 -85.365384) (xy 203.089961 -85.339883) (xy 203.142745 -85.321876) (xy 203.197588 -85.311746)
			(xy 203.253322 -85.309709) (xy 203.308759 -85.315809) (xy 203.362716 -85.329915) (xy 203.414045 -85.351727)
			(xy 203.461651 -85.380781) (xy 203.504519 -85.416456) (xy 203.541736 -85.457993) (xy 203.567444 -85.496851)
			(xy 231.553727 -85.496851) (xy 231.553727 -85.439549) (xy 231.561882 -85.382831) (xy 231.578026 -85.327851)
			(xy 231.601831 -85.275729) (xy 231.632811 -85.227524) (xy 231.670337 -85.18422) (xy 231.713644 -85.146697)
			(xy 231.76185 -85.115719) (xy 231.813974 -85.091918) (xy 231.868955 -85.075777) (xy 231.925673 -85.067625)
			(xy 231.954324 -85.06714) (xy 231.982612 -85.067625) (xy 232.038621 -85.075608) (xy 232.092953 -85.091386)
			(xy 232.144527 -85.114644) (xy 232.19232 -85.144921) (xy 232.214166 -85.162898) (xy 232.22232 -85.169181)
			(xy 232.241989 -85.175199) (xy 232.252266 -85.174582) (xy 232.335832 -85.165946) (xy 232.353866 -85.15604)
			(xy 232.360216 -85.147912) (xy 232.378838 -85.12464) (xy 232.421182 -85.082693) (xy 232.468606 -85.046589)
			(xy 232.520312 -85.016938) (xy 232.575424 -84.994241) (xy 232.633015 -84.978881) (xy 232.69211 -84.971116)
			(xy 232.721912 -84.97062) (xy 233.585512 -84.97062) (xy 233.616496 -84.971164) (xy 233.677898 -84.979526)
			(xy 233.73761 -84.996094) (xy 233.794541 -85.020567) (xy 233.84765 -85.052497) (xy 233.895966 -85.0913)
			(xy 233.938605 -85.136266) (xy 233.957114 -85.16112) (xy 233.963491 -85.169175) (xy 233.981054 -85.179794)
			(xy 233.99115 -85.181694) (xy 234.0737 -85.193632) (xy 234.093766 -85.188298) (xy 234.101894 -85.181948)
			(xy 234.123073 -85.166047) (xy 234.168817 -85.139359) (xy 234.217672 -85.118915) (xy 234.268791 -85.105071)
			(xy 234.321286 -85.098066) (xy 234.347766 -85.09762) (xy 234.376417 -85.098132) (xy 234.433135 -85.106283)
			(xy 234.488116 -85.122423) (xy 234.540241 -85.146223) (xy 234.576467 -85.169502) (xy 238.555276 -85.169502)
			(xy 238.555276 -84.305902) (xy 238.555797 -84.274882) (xy 238.564161 -84.213409) (xy 238.58075 -84.153629)
			(xy 238.605261 -84.096636) (xy 238.637243 -84.043476) (xy 238.676112 -83.995122) (xy 238.698278 -83.973416)
			(xy 238.705644 -83.966558) (xy 238.713772 -83.94827) (xy 238.716566 -83.856068) (xy 238.709454 -83.837526)
			(xy 238.702596 -83.83016) (xy 238.682276 -83.807733) (xy 238.647948 -83.757894) (xy 238.621497 -83.703463)
			(xy 238.603523 -83.645676) (xy 238.594434 -83.585845) (xy 238.593884 -83.555586) (xy 238.594395 -83.526956)
			(xy 238.602544 -83.470278) (xy 238.618676 -83.415338) (xy 238.642462 -83.363252) (xy 238.67342 -83.315081)
			(xy 238.710917 -83.271807) (xy 238.754191 -83.23431) (xy 238.802362 -83.203352) (xy 238.854448 -83.179566)
			(xy 238.909388 -83.163434) (xy 238.966066 -83.155285) (xy 239.023326 -83.155285) (xy 239.080004 -83.163434)
			(xy 239.134944 -83.179566) (xy 239.18703 -83.203352) (xy 239.235201 -83.23431) (xy 239.278475 -83.271807)
			(xy 239.315972 -83.315081) (xy 239.34693 -83.363252) (xy 239.370716 -83.415338) (xy 239.375576 -83.431888)
			(xy 247.814082 -83.431888) (xy 247.818153 -83.376266) (xy 247.830279 -83.321829) (xy 247.850202 -83.269738)
			(xy 247.877498 -83.221103) (xy 247.911584 -83.17696) (xy 247.951733 -83.138251) (xy 247.997091 -83.1058)
			(xy 248.046691 -83.080299) (xy 248.099475 -83.062292) (xy 248.154318 -83.052162) (xy 248.210052 -83.050125)
			(xy 248.265489 -83.056225) (xy 248.319446 -83.070331) (xy 248.370775 -83.092143) (xy 248.418381 -83.121197)
			(xy 248.461249 -83.156872) (xy 248.475755 -83.173062) (xy 257.00304 -83.173062) (xy 257.007111 -83.11744)
			(xy 257.019237 -83.063003) (xy 257.03916 -83.010912) (xy 257.066456 -82.962277) (xy 257.100542 -82.918134)
			(xy 257.140691 -82.879425) (xy 257.186049 -82.846974) (xy 257.235649 -82.821473) (xy 257.288433 -82.803466)
			(xy 257.343276 -82.793336) (xy 257.39901 -82.791299) (xy 257.454447 -82.797399) (xy 257.508404 -82.811505)
			(xy 257.559733 -82.833317) (xy 257.607339 -82.862371) (xy 257.650207 -82.898046) (xy 257.687424 -82.939583)
			(xy 257.718197 -82.986096) (xy 257.741869 -83.036593) (xy 257.757937 -83.09) (xy 257.766057 -83.145176)
			(xy 257.766566 -83.173062) (xy 257.766057 -83.200948) (xy 257.757937 -83.256124) (xy 257.741869 -83.309531)
			(xy 257.718197 -83.360028) (xy 257.687424 -83.406541) (xy 257.650207 -83.448078) (xy 257.607339 -83.483753)
			(xy 257.559733 -83.512807) (xy 257.508404 -83.534619) (xy 257.454447 -83.548725) (xy 257.39901 -83.554825)
			(xy 257.343276 -83.552788) (xy 257.288433 -83.542658) (xy 257.235649 -83.524651) (xy 257.186049 -83.49915)
			(xy 257.140691 -83.466699) (xy 257.100542 -83.42799) (xy 257.066456 -83.383847) (xy 257.03916 -83.335212)
			(xy 257.019237 -83.283121) (xy 257.007111 -83.228684) (xy 257.00304 -83.173062) (xy 248.475755 -83.173062)
			(xy 248.498466 -83.198409) (xy 248.529239 -83.244922) (xy 248.552911 -83.295419) (xy 248.568979 -83.348826)
			(xy 248.577099 -83.404002) (xy 248.577608 -83.431888) (xy 248.577099 -83.459774) (xy 248.568979 -83.51495)
			(xy 248.552911 -83.568357) (xy 248.529239 -83.618854) (xy 248.498466 -83.665367) (xy 248.461249 -83.706904)
			(xy 248.418381 -83.742579) (xy 248.370775 -83.771633) (xy 248.319446 -83.793445) (xy 248.265489 -83.807551)
			(xy 248.210052 -83.813651) (xy 248.154318 -83.811614) (xy 248.099475 -83.801484) (xy 248.046691 -83.783477)
			(xy 247.997091 -83.757976) (xy 247.951733 -83.725525) (xy 247.911584 -83.686816) (xy 247.877498 -83.642673)
			(xy 247.850202 -83.594038) (xy 247.830279 -83.541947) (xy 247.818153 -83.48751) (xy 247.814082 -83.431888)
			(xy 239.375576 -83.431888) (xy 239.386848 -83.470278) (xy 239.394997 -83.526956) (xy 239.395508 -83.555586)
			(xy 239.395508 -83.55584) (xy 239.394982 -83.58409) (xy 239.387023 -83.640028) (xy 239.371296 -83.694297)
			(xy 239.348112 -83.745823) (xy 239.317929 -83.793587) (xy 239.300004 -83.815428) (xy 239.293947 -83.823347)
			(xy 239.2878 -83.842292) (xy 239.288066 -83.852258) (xy 239.29467 -83.934046) (xy 239.303306 -83.951318)
			(xy 240.811048 -83.951318) (xy 240.815119 -83.895696) (xy 240.827245 -83.841259) (xy 240.847168 -83.789168)
			(xy 240.874464 -83.740533) (xy 240.90855 -83.69639) (xy 240.948699 -83.657681) (xy 240.994057 -83.62523)
			(xy 241.043657 -83.599729) (xy 241.096441 -83.581722) (xy 241.151284 -83.571592) (xy 241.207018 -83.569555)
			(xy 241.262455 -83.575655) (xy 241.316412 -83.589761) (xy 241.367741 -83.611573) (xy 241.415347 -83.640627)
			(xy 241.458215 -83.676302) (xy 241.495432 -83.717839) (xy 241.526205 -83.764352) (xy 241.549877 -83.814849)
			(xy 241.565945 -83.868256) (xy 241.574065 -83.923432) (xy 241.574574 -83.951318) (xy 241.574065 -83.979204)
			(xy 241.565945 -84.03438) (xy 241.549877 -84.087787) (xy 241.526205 -84.138284) (xy 241.495432 -84.184797)
			(xy 241.458215 -84.226334) (xy 241.415347 -84.262009) (xy 241.367741 -84.291063) (xy 241.316412 -84.312875)
			(xy 241.262455 -84.326981) (xy 241.207018 -84.333081) (xy 241.151284 -84.331044) (xy 241.096441 -84.320914)
			(xy 241.043657 -84.302907) (xy 240.994057 -84.277406) (xy 240.948699 -84.244955) (xy 240.90855 -84.206246)
			(xy 240.874464 -84.162103) (xy 240.847168 -84.113468) (xy 240.827245 -84.061377) (xy 240.815119 -84.00694)
			(xy 240.811048 -83.951318) (xy 239.303306 -83.951318) (xy 239.30356 -83.951826) (xy 239.310926 -83.958176)
			(xy 239.311434 -83.95843) (xy 239.332565 -83.977097) (xy 239.370543 -84.018774) (xy 239.403111 -84.064802)
			(xy 239.429775 -84.114484) (xy 239.450132 -84.167066) (xy 239.463873 -84.22175) (xy 239.47079 -84.277709)
			(xy 239.4712 -84.305902) (xy 239.4712 -84.748116) (xy 253.089916 -84.748116) (xy 253.093987 -84.692494)
			(xy 253.106113 -84.638057) (xy 253.126036 -84.585966) (xy 253.153332 -84.537331) (xy 253.187418 -84.493188)
			(xy 253.227567 -84.454479) (xy 253.272925 -84.422028) (xy 253.322525 -84.396527) (xy 253.375309 -84.37852)
			(xy 253.430152 -84.36839) (xy 253.485886 -84.366353) (xy 253.541323 -84.372453) (xy 253.59528 -84.386559)
			(xy 253.646609 -84.408371) (xy 253.694215 -84.437425) (xy 253.714113 -84.453984) (xy 254.399286 -84.453984)
			(xy 254.403357 -84.398362) (xy 254.415483 -84.343925) (xy 254.435406 -84.291834) (xy 254.462702 -84.243199)
			(xy 254.496788 -84.199056) (xy 254.536937 -84.160347) (xy 254.582295 -84.127896) (xy 254.631895 -84.102395)
			(xy 254.684679 -84.084388) (xy 254.739522 -84.074258) (xy 254.795256 -84.072221) (xy 254.850693 -84.078321)
			(xy 254.90465 -84.092427) (xy 254.955979 -84.114239) (xy 255.003585 -84.143293) (xy 255.046453 -84.178968)
			(xy 255.08367 -84.220505) (xy 255.114443 -84.267018) (xy 255.138115 -84.317515) (xy 255.154183 -84.370922)
			(xy 255.162303 -84.426098) (xy 255.162812 -84.453984) (xy 255.162303 -84.48187) (xy 255.154183 -84.537046)
			(xy 255.138115 -84.590453) (xy 255.119454 -84.63026) (xy 257.000754 -84.63026) (xy 257.004825 -84.574638)
			(xy 257.016951 -84.520201) (xy 257.036874 -84.46811) (xy 257.06417 -84.419475) (xy 257.098256 -84.375332)
			(xy 257.138405 -84.336623) (xy 257.183763 -84.304172) (xy 257.233363 -84.278671) (xy 257.286147 -84.260664)
			(xy 257.34099 -84.250534) (xy 257.396724 -84.248497) (xy 257.452161 -84.254597) (xy 257.506118 -84.268703)
			(xy 257.557447 -84.290515) (xy 257.605053 -84.319569) (xy 257.647921 -84.355244) (xy 257.685138 -84.396781)
			(xy 257.715911 -84.443294) (xy 257.739583 -84.493791) (xy 257.755651 -84.547198) (xy 257.763771 -84.602374)
			(xy 257.76428 -84.63026) (xy 257.763771 -84.658146) (xy 257.755651 -84.713322) (xy 257.743884 -84.752434)
			(xy 261.58774 -84.752434) (xy 261.591811 -84.696812) (xy 261.603937 -84.642375) (xy 261.62386 -84.590284)
			(xy 261.651156 -84.541649) (xy 261.685242 -84.497506) (xy 261.725391 -84.458797) (xy 261.770749 -84.426346)
			(xy 261.820349 -84.400845) (xy 261.873133 -84.382838) (xy 261.927976 -84.372708) (xy 261.98371 -84.370671)
			(xy 262.039147 -84.376771) (xy 262.093104 -84.390877) (xy 262.144433 -84.412689) (xy 262.192039 -84.441743)
			(xy 262.234907 -84.477418) (xy 262.272124 -84.518955) (xy 262.302897 -84.565468) (xy 262.326569 -84.615965)
			(xy 262.342637 -84.669372) (xy 262.350757 -84.724548) (xy 262.351266 -84.752434) (xy 262.35115 -84.758784)
			(xy 264.526774 -84.758784) (xy 264.530845 -84.703162) (xy 264.542971 -84.648725) (xy 264.562894 -84.596634)
			(xy 264.59019 -84.547999) (xy 264.624276 -84.503856) (xy 264.664425 -84.465147) (xy 264.709783 -84.432696)
			(xy 264.759383 -84.407195) (xy 264.812167 -84.389188) (xy 264.86701 -84.379058) (xy 264.922744 -84.377021)
			(xy 264.978181 -84.383121) (xy 265.032138 -84.397227) (xy 265.083467 -84.419039) (xy 265.131073 -84.448093)
			(xy 265.173941 -84.483768) (xy 265.211158 -84.525305) (xy 265.241931 -84.571818) (xy 265.265603 -84.622315)
			(xy 265.281671 -84.675722) (xy 265.289791 -84.730898) (xy 265.2903 -84.758784) (xy 265.289791 -84.78667)
			(xy 265.281671 -84.841846) (xy 265.265603 -84.895253) (xy 265.241931 -84.94575) (xy 265.211158 -84.992263)
			(xy 265.173941 -85.0338) (xy 265.131073 -85.069475) (xy 265.083467 -85.098529) (xy 265.032138 -85.120341)
			(xy 264.978181 -85.134447) (xy 264.922744 -85.140547) (xy 264.86701 -85.13851) (xy 264.812167 -85.12838)
			(xy 264.759383 -85.110373) (xy 264.709783 -85.084872) (xy 264.664425 -85.052421) (xy 264.624276 -85.013712)
			(xy 264.59019 -84.969569) (xy 264.562894 -84.920934) (xy 264.542971 -84.868843) (xy 264.530845 -84.814406)
			(xy 264.526774 -84.758784) (xy 262.35115 -84.758784) (xy 262.350757 -84.78032) (xy 262.342637 -84.835496)
			(xy 262.326569 -84.888903) (xy 262.302897 -84.9394) (xy 262.272124 -84.985913) (xy 262.234907 -85.02745)
			(xy 262.192039 -85.063125) (xy 262.144433 -85.092179) (xy 262.093104 -85.113991) (xy 262.039147 -85.128097)
			(xy 261.98371 -85.134197) (xy 261.927976 -85.13216) (xy 261.873133 -85.12203) (xy 261.820349 -85.104023)
			(xy 261.770749 -85.078522) (xy 261.725391 -85.046071) (xy 261.685242 -85.007362) (xy 261.651156 -84.963219)
			(xy 261.62386 -84.914584) (xy 261.603937 -84.862493) (xy 261.591811 -84.808056) (xy 261.58774 -84.752434)
			(xy 257.743884 -84.752434) (xy 257.739583 -84.766729) (xy 257.715911 -84.817226) (xy 257.685138 -84.863739)
			(xy 257.647921 -84.905276) (xy 257.605053 -84.940951) (xy 257.557447 -84.970005) (xy 257.506118 -84.991817)
			(xy 257.452161 -85.005923) (xy 257.396724 -85.012023) (xy 257.34099 -85.009986) (xy 257.286147 -84.999856)
			(xy 257.233363 -84.981849) (xy 257.183763 -84.956348) (xy 257.138405 -84.923897) (xy 257.098256 -84.885188)
			(xy 257.06417 -84.841045) (xy 257.036874 -84.79241) (xy 257.016951 -84.740319) (xy 257.004825 -84.685882)
			(xy 257.000754 -84.63026) (xy 255.119454 -84.63026) (xy 255.114443 -84.64095) (xy 255.08367 -84.687463)
			(xy 255.046453 -84.729) (xy 255.003585 -84.764675) (xy 254.955979 -84.793729) (xy 254.90465 -84.815541)
			(xy 254.850693 -84.829647) (xy 254.795256 -84.835747) (xy 254.739522 -84.83371) (xy 254.684679 -84.82358)
			(xy 254.631895 -84.805573) (xy 254.582295 -84.780072) (xy 254.536937 -84.747621) (xy 254.496788 -84.708912)
			(xy 254.462702 -84.664769) (xy 254.435406 -84.616134) (xy 254.415483 -84.564043) (xy 254.403357 -84.509606)
			(xy 254.399286 -84.453984) (xy 253.714113 -84.453984) (xy 253.737083 -84.4731) (xy 253.7743 -84.514637)
			(xy 253.805073 -84.56115) (xy 253.828745 -84.611647) (xy 253.844813 -84.665054) (xy 253.852933 -84.72023)
			(xy 253.853442 -84.748116) (xy 253.852933 -84.776002) (xy 253.844813 -84.831178) (xy 253.828745 -84.884585)
			(xy 253.805073 -84.935082) (xy 253.7743 -84.981595) (xy 253.737083 -85.023132) (xy 253.694215 -85.058807)
			(xy 253.646609 -85.087861) (xy 253.59528 -85.109673) (xy 253.541323 -85.123779) (xy 253.485886 -85.129879)
			(xy 253.430152 -85.127842) (xy 253.375309 -85.117712) (xy 253.322525 -85.099705) (xy 253.272925 -85.074204)
			(xy 253.227567 -85.041753) (xy 253.187418 -85.003044) (xy 253.153332 -84.958901) (xy 253.126036 -84.910266)
			(xy 253.106113 -84.858175) (xy 253.093987 -84.803738) (xy 253.089916 -84.748116) (xy 239.4712 -84.748116)
			(xy 239.4712 -85.169502) (xy 239.470605 -85.201442) (xy 239.461694 -85.264697) (xy 239.444072 -85.326098)
			(xy 239.418083 -85.384452) (xy 239.384232 -85.438625) (xy 239.343176 -85.487564) (xy 239.319816 -85.509354)
			(xy 239.319562 -85.509608) (xy 239.312731 -85.516504) (xy 239.304362 -85.533996) (xy 239.303306 -85.543644)
			(xy 239.3028 -85.551518) (xy 240.870484 -85.551518) (xy 240.874555 -85.495896) (xy 240.886681 -85.441459)
			(xy 240.906604 -85.389368) (xy 240.9339 -85.340733) (xy 240.967986 -85.29659) (xy 241.008135 -85.257881)
			(xy 241.053493 -85.22543) (xy 241.103093 -85.199929) (xy 241.155877 -85.181922) (xy 241.21072 -85.171792)
			(xy 241.266454 -85.169755) (xy 241.321891 -85.175855) (xy 241.375848 -85.189961) (xy 241.422741 -85.209888)
			(xy 247.814082 -85.209888) (xy 247.818153 -85.154266) (xy 247.830279 -85.099829) (xy 247.850202 -85.047738)
			(xy 247.877498 -84.999103) (xy 247.911584 -84.95496) (xy 247.951733 -84.916251) (xy 247.997091 -84.8838)
			(xy 248.046691 -84.858299) (xy 248.099475 -84.840292) (xy 248.154318 -84.830162) (xy 248.210052 -84.828125)
			(xy 248.265489 -84.834225) (xy 248.319446 -84.848331) (xy 248.370775 -84.870143) (xy 248.418381 -84.899197)
			(xy 248.461249 -84.934872) (xy 248.498466 -84.976409) (xy 248.529239 -85.022922) (xy 248.552911 -85.073419)
			(xy 248.568979 -85.126826) (xy 248.577099 -85.182002) (xy 248.577608 -85.209888) (xy 248.577099 -85.237774)
			(xy 248.568979 -85.29295) (xy 248.552911 -85.346357) (xy 248.529239 -85.396854) (xy 248.498466 -85.443367)
			(xy 248.461249 -85.484904) (xy 248.418381 -85.520579) (xy 248.370775 -85.549633) (xy 248.319446 -85.571445)
			(xy 248.265489 -85.585551) (xy 248.210052 -85.591651) (xy 248.154318 -85.589614) (xy 248.099475 -85.579484)
			(xy 248.046691 -85.561477) (xy 247.997091 -85.535976) (xy 247.951733 -85.503525) (xy 247.911584 -85.464816)
			(xy 247.877498 -85.420673) (xy 247.850202 -85.372038) (xy 247.830279 -85.319947) (xy 247.818153 -85.26551)
			(xy 247.814082 -85.209888) (xy 241.422741 -85.209888) (xy 241.427177 -85.211773) (xy 241.474783 -85.240827)
			(xy 241.517651 -85.276502) (xy 241.554868 -85.318039) (xy 241.585641 -85.364552) (xy 241.609313 -85.415049)
			(xy 241.625381 -85.468456) (xy 241.633501 -85.523632) (xy 241.63401 -85.551518) (xy 241.633501 -85.579404)
			(xy 241.625381 -85.63458) (xy 241.609313 -85.687987) (xy 241.585641 -85.738484) (xy 241.554868 -85.784997)
			(xy 241.517651 -85.826534) (xy 241.50109 -85.840316) (xy 251.947172 -85.840316) (xy 251.947728 -85.810672)
			(xy 251.956892 -85.752096) (xy 251.975002 -85.695642) (xy 252.001622 -85.642666) (xy 252.036112 -85.594443)
			(xy 252.077644 -85.552133) (xy 252.101096 -85.533992) (xy 252.108347 -85.528089) (xy 252.118376 -85.512326)
			(xy 252.120654 -85.503258) (xy 252.135894 -85.427058) (xy 252.132846 -85.40877) (xy 252.12802 -85.400642)
			(xy 252.115249 -85.378399) (xy 252.095106 -85.331231) (xy 252.081471 -85.281787) (xy 252.07459 -85.230961)
			(xy 252.074172 -85.205316) (xy 252.074658 -85.178065) (xy 252.082414 -85.124117) (xy 252.097769 -85.071822)
			(xy 252.120411 -85.022245) (xy 252.149877 -84.976395) (xy 252.185568 -84.935204) (xy 252.226759 -84.899513)
			(xy 252.272609 -84.870047) (xy 252.322186 -84.847405) (xy 252.374481 -84.83205) (xy 252.428429 -84.824294)
			(xy 252.482931 -84.824294) (xy 252.536879 -84.83205) (xy 252.589174 -84.847405) (xy 252.638751 -84.870047)
			(xy 252.684601 -84.899513) (xy 252.725792 -84.935204) (xy 252.761483 -84.976395) (xy 252.790949 -85.022245)
			(xy 252.813591 -85.071822) (xy 252.828946 -85.124117) (xy 252.836702 -85.178065) (xy 252.837188 -85.205316)
			(xy 252.836632 -85.23496) (xy 252.827465 -85.293534) (xy 252.809353 -85.349987) (xy 252.782733 -85.402963)
			(xy 252.748244 -85.451186) (xy 252.706715 -85.493498) (xy 252.683264 -85.51164) (xy 252.676028 -85.517559)
			(xy 252.665992 -85.53331) (xy 252.663706 -85.542374) (xy 252.648466 -85.618574) (xy 252.651514 -85.636862)
			(xy 252.65634 -85.64499) (xy 252.66912 -85.667228) (xy 252.689261 -85.714398) (xy 252.702894 -85.763844)
			(xy 252.709771 -85.814671) (xy 252.709915 -85.823552) (xy 261.571232 -85.823552) (xy 261.571718 -85.796301)
			(xy 261.579474 -85.742353) (xy 261.594829 -85.690058) (xy 261.617471 -85.640481) (xy 261.646937 -85.594631)
			(xy 261.682628 -85.55344) (xy 261.723819 -85.517749) (xy 261.769669 -85.488283) (xy 261.819246 -85.465641)
			(xy 261.871541 -85.450286) (xy 261.925489 -85.44253) (xy 261.979991 -85.44253) (xy 262.033939 -85.450286)
			(xy 262.086234 -85.465641) (xy 262.135811 -85.488283) (xy 262.181661 -85.517749) (xy 262.222852 -85.55344)
			(xy 262.258543 -85.594631) (xy 262.288009 -85.640481) (xy 262.310651 -85.690058) (xy 262.326006 -85.742353)
			(xy 262.333762 -85.796301) (xy 262.334248 -85.823552) (xy 262.333685 -85.852529) (xy 262.324931 -85.909818)
			(xy 262.307619 -85.965125) (xy 262.282144 -86.01718) (xy 262.249094 -86.064786) (xy 262.209227 -86.106848)
			(xy 262.186674 -86.12505) (xy 262.176201 -86.133708) (xy 262.159887 -86.155428) (xy 262.149882 -86.180682)
			(xy 262.146895 -86.207682) (xy 262.151139 -86.234513) (xy 262.162312 -86.259273) (xy 262.179621 -86.280207)
			(xy 262.190484 -86.288372) (xy 262.211606 -86.303746) (xy 262.249835 -86.339354) (xy 262.282849 -86.379843)
			(xy 262.306354 -86.41842) (xy 264.566906 -86.41842) (xy 264.570977 -86.362798) (xy 264.583103 -86.308361)
			(xy 264.603026 -86.25627) (xy 264.630322 -86.207635) (xy 264.664408 -86.163492) (xy 264.704557 -86.124783)
			(xy 264.749915 -86.092332) (xy 264.799515 -86.066831) (xy 264.852299 -86.048824) (xy 264.907142 -86.038694)
			(xy 264.962876 -86.036657) (xy 265.018313 -86.042757) (xy 265.07227 -86.056863) (xy 265.123599 -86.078675)
			(xy 265.171205 -86.107729) (xy 265.214073 -86.143404) (xy 265.25129 -86.184941) (xy 265.282063 -86.231454)
			(xy 265.305735 -86.281951) (xy 265.321803 -86.335358) (xy 265.326588 -86.367874) (xy 265.473178 -86.367874)
			(xy 265.477249 -86.312252) (xy 265.489375 -86.257815) (xy 265.509298 -86.205724) (xy 265.536594 -86.157089)
			(xy 265.57068 -86.112946) (xy 265.610829 -86.074237) (xy 265.656187 -86.041786) (xy 265.705787 -86.016285)
			(xy 265.758571 -85.998278) (xy 265.813414 -85.988148) (xy 265.869148 -85.986111) (xy 265.924585 -85.992211)
			(xy 265.978542 -86.006317) (xy 266.029871 -86.028129) (xy 266.077477 -86.057183) (xy 266.120345 -86.092858)
			(xy 266.157562 -86.134395) (xy 266.188335 -86.180908) (xy 266.212007 -86.231405) (xy 266.213175 -86.235286)
			(xy 269.194532 -86.235286) (xy 269.198603 -86.179664) (xy 269.210729 -86.125227) (xy 269.230652 -86.073136)
			(xy 269.257948 -86.024501) (xy 269.292034 -85.980358) (xy 269.332183 -85.941649) (xy 269.377541 -85.909198)
			(xy 269.427141 -85.883697) (xy 269.479925 -85.86569) (xy 269.534768 -85.85556) (xy 269.590502 -85.853523)
			(xy 269.645939 -85.859623) (xy 269.699896 -85.873729) (xy 269.751225 -85.895541) (xy 269.798831 -85.924595)
			(xy 269.841699 -85.96027) (xy 269.878916 -86.001807) (xy 269.909689 -86.04832) (xy 269.933361 -86.098817)
			(xy 269.949429 -86.152224) (xy 269.957549 -86.2074) (xy 269.958058 -86.235286) (xy 269.957549 -86.263172)
			(xy 269.949429 -86.318348) (xy 269.933361 -86.371755) (xy 269.909689 -86.422252) (xy 269.878916 -86.468765)
			(xy 269.841699 -86.510302) (xy 269.798831 -86.545977) (xy 269.783096 -86.55558) (xy 274.52142 -86.55558)
			(xy 274.525491 -86.499958) (xy 274.537617 -86.445521) (xy 274.55754 -86.39343) (xy 274.584836 -86.344795)
			(xy 274.618922 -86.300652) (xy 274.659071 -86.261943) (xy 274.704429 -86.229492) (xy 274.754029 -86.203991)
			(xy 274.806813 -86.185984) (xy 274.861656 -86.175854) (xy 274.91739 -86.173817) (xy 274.972827 -86.179917)
			(xy 275.026784 -86.194023) (xy 275.078113 -86.215835) (xy 275.125719 -86.244889) (xy 275.168587 -86.280564)
			(xy 275.197658 -86.31301) (xy 275.364192 -86.31301) (xy 275.368263 -86.257388) (xy 275.380389 -86.202951)
			(xy 275.400312 -86.15086) (xy 275.427608 -86.102225) (xy 275.461694 -86.058082) (xy 275.501843 -86.019373)
			(xy 275.547201 -85.986922) (xy 275.596801 -85.961421) (xy 275.649585 -85.943414) (xy 275.704428 -85.933284)
			(xy 275.760162 -85.931247) (xy 275.815599 -85.937347) (xy 275.869556 -85.951453) (xy 275.920885 -85.973265)
			(xy 275.968491 -86.002319) (xy 276.011359 -86.037994) (xy 276.048576 -86.079531) (xy 276.079349 -86.126044)
			(xy 276.103021 -86.176541) (xy 276.119089 -86.229948) (xy 276.127209 -86.285124) (xy 276.127718 -86.31301)
			(xy 276.127209 -86.340896) (xy 276.119089 -86.396072) (xy 276.103021 -86.449479) (xy 276.079349 -86.499976)
			(xy 276.048576 -86.546489) (xy 276.011359 -86.588026) (xy 275.968491 -86.623701) (xy 275.920885 -86.652755)
			(xy 275.869556 -86.674567) (xy 275.815599 -86.688673) (xy 275.760162 -86.694773) (xy 275.704428 -86.692736)
			(xy 275.649585 -86.682606) (xy 275.596801 -86.664599) (xy 275.547201 -86.639098) (xy 275.501843 -86.606647)
			(xy 275.461694 -86.567938) (xy 275.427608 -86.523795) (xy 275.400312 -86.47516) (xy 275.380389 -86.423069)
			(xy 275.368263 -86.368632) (xy 275.364192 -86.31301) (xy 275.197658 -86.31301) (xy 275.205804 -86.322101)
			(xy 275.236577 -86.368614) (xy 275.260249 -86.419111) (xy 275.276317 -86.472518) (xy 275.284437 -86.527694)
			(xy 275.284946 -86.55558) (xy 275.284437 -86.583466) (xy 275.276317 -86.638642) (xy 275.260249 -86.692049)
			(xy 275.236577 -86.742546) (xy 275.205804 -86.789059) (xy 275.168587 -86.830596) (xy 275.125719 -86.866271)
			(xy 275.078113 -86.895325) (xy 275.026784 -86.917137) (xy 274.972827 -86.931243) (xy 274.91739 -86.937343)
			(xy 274.861656 -86.935306) (xy 274.806813 -86.925176) (xy 274.754029 -86.907169) (xy 274.704429 -86.881668)
			(xy 274.659071 -86.849217) (xy 274.618922 -86.810508) (xy 274.584836 -86.766365) (xy 274.55754 -86.71773)
			(xy 274.537617 -86.665639) (xy 274.525491 -86.611202) (xy 274.52142 -86.55558) (xy 269.783096 -86.55558)
			(xy 269.751225 -86.575031) (xy 269.699896 -86.596843) (xy 269.645939 -86.610949) (xy 269.590502 -86.617049)
			(xy 269.534768 -86.615012) (xy 269.479925 -86.604882) (xy 269.427141 -86.586875) (xy 269.377541 -86.561374)
			(xy 269.332183 -86.528923) (xy 269.292034 -86.490214) (xy 269.257948 -86.446071) (xy 269.230652 -86.397436)
			(xy 269.210729 -86.345345) (xy 269.198603 -86.290908) (xy 269.194532 -86.235286) (xy 266.213175 -86.235286)
			(xy 266.228075 -86.284812) (xy 266.236195 -86.339988) (xy 266.236704 -86.367874) (xy 266.236195 -86.39576)
			(xy 266.228075 -86.450936) (xy 266.212007 -86.504343) (xy 266.188335 -86.55484) (xy 266.157562 -86.601353)
			(xy 266.120345 -86.64289) (xy 266.077477 -86.678565) (xy 266.029871 -86.707619) (xy 265.978542 -86.729431)
			(xy 265.924585 -86.743537) (xy 265.869148 -86.749637) (xy 265.813414 -86.7476) (xy 265.758571 -86.73747)
			(xy 265.705787 -86.719463) (xy 265.656187 -86.693962) (xy 265.610829 -86.661511) (xy 265.57068 -86.622802)
			(xy 265.536594 -86.578659) (xy 265.509298 -86.530024) (xy 265.489375 -86.477933) (xy 265.477249 -86.423496)
			(xy 265.473178 -86.367874) (xy 265.326588 -86.367874) (xy 265.329923 -86.390534) (xy 265.330432 -86.41842)
			(xy 265.329923 -86.446306) (xy 265.321803 -86.501482) (xy 265.305735 -86.554889) (xy 265.282063 -86.605386)
			(xy 265.25129 -86.651899) (xy 265.214073 -86.693436) (xy 265.171205 -86.729111) (xy 265.123599 -86.758165)
			(xy 265.07227 -86.779977) (xy 265.018313 -86.794083) (xy 264.962876 -86.800183) (xy 264.907142 -86.798146)
			(xy 264.852299 -86.788016) (xy 264.799515 -86.770009) (xy 264.749915 -86.744508) (xy 264.704557 -86.712057)
			(xy 264.664408 -86.673348) (xy 264.630322 -86.629205) (xy 264.603026 -86.58057) (xy 264.583103 -86.528479)
			(xy 264.570977 -86.474042) (xy 264.566906 -86.41842) (xy 262.306354 -86.41842) (xy 262.310032 -86.424456)
			(xy 262.330876 -86.472361) (xy 262.34499 -86.522661) (xy 262.352111 -86.574417) (xy 262.352536 -86.600538)
			(xy 262.35205 -86.627789) (xy 262.344294 -86.681737) (xy 262.328939 -86.734032) (xy 262.306297 -86.783609)
			(xy 262.276831 -86.829459) (xy 262.24114 -86.87065) (xy 262.199949 -86.906341) (xy 262.154099 -86.935807)
			(xy 262.104522 -86.958449) (xy 262.052227 -86.973804) (xy 261.998279 -86.98156) (xy 261.943777 -86.98156)
			(xy 261.889829 -86.973804) (xy 261.837534 -86.958449) (xy 261.787957 -86.935807) (xy 261.742107 -86.906341)
			(xy 261.700916 -86.87065) (xy 261.665225 -86.829459) (xy 261.635759 -86.783609) (xy 261.613117 -86.734032)
			(xy 261.597762 -86.681737) (xy 261.590006 -86.627789) (xy 261.58952 -86.600538) (xy 261.590089 -86.571561)
			(xy 261.598843 -86.514273) (xy 261.616155 -86.458967) (xy 261.641628 -86.406912) (xy 261.674677 -86.359306)
			(xy 261.714542 -86.317242) (xy 261.737094 -86.29904) (xy 261.74757 -86.290388) (xy 261.763872 -86.268663)
			(xy 261.773869 -86.243409) (xy 261.776852 -86.216412) (xy 261.772609 -86.189584) (xy 261.761443 -86.164825)
			(xy 261.744142 -86.143887) (xy 261.733284 -86.135718) (xy 261.71215 -86.120359) (xy 261.673923 -86.084748)
			(xy 261.640911 -86.044256) (xy 261.61373 -85.99964) (xy 261.592888 -85.951733) (xy 261.578776 -85.901431)
			(xy 261.571657 -85.849674) (xy 261.571232 -85.823552) (xy 252.709915 -85.823552) (xy 252.710188 -85.840316)
			(xy 252.709702 -85.867567) (xy 252.701946 -85.921515) (xy 252.686591 -85.97381) (xy 252.663949 -86.023387)
			(xy 252.634483 -86.069237) (xy 252.598792 -86.110428) (xy 252.557601 -86.146119) (xy 252.511751 -86.175585)
			(xy 252.462174 -86.198227) (xy 252.409879 -86.213582) (xy 252.355931 -86.221338) (xy 252.301429 -86.221338)
			(xy 252.247481 -86.213582) (xy 252.195186 -86.198227) (xy 252.145609 -86.175585) (xy 252.099759 -86.146119)
			(xy 252.058568 -86.110428) (xy 252.022877 -86.069237) (xy 251.993411 -86.023387) (xy 251.970769 -85.97381)
			(xy 251.955414 -85.921515) (xy 251.947658 -85.867567) (xy 251.947172 -85.840316) (xy 241.50109 -85.840316)
			(xy 241.474783 -85.862209) (xy 241.427177 -85.891263) (xy 241.375848 -85.913075) (xy 241.321891 -85.927181)
			(xy 241.266454 -85.933281) (xy 241.21072 -85.931244) (xy 241.155877 -85.921114) (xy 241.103093 -85.903107)
			(xy 241.053493 -85.877606) (xy 241.008135 -85.845155) (xy 240.967986 -85.806446) (xy 240.9339 -85.762303)
			(xy 240.906604 -85.713668) (xy 240.886681 -85.661577) (xy 240.874555 -85.60714) (xy 240.870484 -85.551518)
			(xy 239.3028 -85.551518) (xy 239.298734 -85.614764) (xy 239.298611 -85.624623) (xy 239.304878 -85.643299)
			(xy 239.310926 -85.651086) (xy 239.329114 -85.672973) (xy 239.359722 -85.720949) (xy 239.38323 -85.772775)
			(xy 239.399166 -85.827407) (xy 239.407208 -85.883744) (xy 239.4077 -85.912198) (xy 239.4077 -85.912452)
			(xy 239.407189 -85.941082) (xy 239.39904 -85.99776) (xy 239.382908 -86.0527) (xy 239.359122 -86.104786)
			(xy 239.328164 -86.152957) (xy 239.290667 -86.196231) (xy 239.247393 -86.233728) (xy 239.199222 -86.264686)
			(xy 239.147136 -86.288472) (xy 239.092196 -86.304604) (xy 239.035518 -86.312753) (xy 238.978258 -86.312753)
			(xy 238.92158 -86.304604) (xy 238.86664 -86.288472) (xy 238.814554 -86.264686) (xy 238.766383 -86.233728)
			(xy 238.723109 -86.196231) (xy 238.685612 -86.152957) (xy 238.654654 -86.104786) (xy 238.630868 -86.0527)
			(xy 238.614736 -85.99776) (xy 238.606587 -85.941082) (xy 238.606076 -85.912452) (xy 238.606615 -85.883294)
			(xy 238.615048 -85.825591) (xy 238.631759 -85.769721) (xy 238.656394 -85.716865) (xy 238.688432 -85.668138)
			(xy 238.707422 -85.646006) (xy 238.713592 -85.638337) (xy 238.720116 -85.619782) (xy 238.720122 -85.609938)
			(xy 238.716312 -85.528912) (xy 238.70793 -85.510878) (xy 238.700818 -85.504274) (xy 238.678269 -85.482555)
			(xy 238.638734 -85.434009) (xy 238.606183 -85.380529) (xy 238.581222 -85.323112) (xy 238.564319 -85.262829)
			(xy 238.555787 -85.200806) (xy 238.555276 -85.169502) (xy 234.576467 -85.169502) (xy 234.588447 -85.1772)
			(xy 234.631754 -85.214722) (xy 234.66928 -85.258026) (xy 234.700261 -85.30623) (xy 234.724066 -85.358352)
			(xy 234.74021 -85.413332) (xy 234.748365 -85.470049) (xy 234.748365 -85.527351) (xy 234.74489 -85.551518)
			(xy 236.50397 -85.551518) (xy 236.508041 -85.495896) (xy 236.520167 -85.441459) (xy 236.54009 -85.389368)
			(xy 236.567386 -85.340733) (xy 236.601472 -85.29659) (xy 236.641621 -85.257881) (xy 236.686979 -85.22543)
			(xy 236.736579 -85.199929) (xy 236.789363 -85.181922) (xy 236.844206 -85.171792) (xy 236.89994 -85.169755)
			(xy 236.955377 -85.175855) (xy 237.009334 -85.189961) (xy 237.060663 -85.211773) (xy 237.108269 -85.240827)
			(xy 237.151137 -85.276502) (xy 237.188354 -85.318039) (xy 237.219127 -85.364552) (xy 237.242799 -85.415049)
			(xy 237.258867 -85.468456) (xy 237.266987 -85.523632) (xy 237.267496 -85.551518) (xy 237.266987 -85.579404)
			(xy 237.258867 -85.63458) (xy 237.242799 -85.687987) (xy 237.219127 -85.738484) (xy 237.188354 -85.784997)
			(xy 237.151137 -85.826534) (xy 237.108269 -85.862209) (xy 237.060663 -85.891263) (xy 237.009334 -85.913075)
			(xy 236.955377 -85.927181) (xy 236.89994 -85.933281) (xy 236.844206 -85.931244) (xy 236.789363 -85.921114)
			(xy 236.736579 -85.903107) (xy 236.686979 -85.877606) (xy 236.641621 -85.845155) (xy 236.601472 -85.806446)
			(xy 236.567386 -85.762303) (xy 236.54009 -85.713668) (xy 236.520167 -85.661577) (xy 236.508041 -85.60714)
			(xy 236.50397 -85.551518) (xy 234.74489 -85.551518) (xy 234.74021 -85.584068) (xy 234.724066 -85.639048)
			(xy 234.700261 -85.69117) (xy 234.66928 -85.739374) (xy 234.631754 -85.782678) (xy 234.588447 -85.8202)
			(xy 234.540241 -85.851177) (xy 234.488116 -85.874977) (xy 234.433135 -85.891117) (xy 234.376417 -85.899268)
			(xy 234.347766 -85.899752) (xy 234.319567 -85.899212) (xy 234.263729 -85.891267) (xy 234.209555 -85.87558)
			(xy 234.158111 -85.852461) (xy 234.110412 -85.822365) (xy 234.067398 -85.785886) (xy 234.0483 -85.765132)
			(xy 234.048046 -85.764878) (xy 234.040898 -85.757721) (xy 234.022566 -85.749208) (xy 234.012486 -85.748368)
			(xy 233.939334 -85.74532) (xy 233.929127 -85.745333) (xy 233.909998 -85.752394) (xy 233.90225 -85.759036)
			(xy 233.901996 -85.75929) (xy 233.880633 -85.779111) (xy 233.833783 -85.813771) (xy 233.782912 -85.842202)
			(xy 233.728844 -85.863946) (xy 233.672452 -85.878649) (xy 233.61465 -85.886074) (xy 233.585512 -85.886544)
			(xy 232.721912 -85.886544) (xy 232.691096 -85.886023) (xy 232.630026 -85.877709) (xy 232.570622 -85.861282)
			(xy 232.513956 -85.837039) (xy 232.461053 -85.805418) (xy 232.412866 -85.76699) (xy 232.391204 -85.745066)
			(xy 232.383838 -85.737446) (xy 232.365042 -85.729318) (xy 232.2703 -85.729572) (xy 232.25125 -85.7377)
			(xy 232.244138 -85.745066) (xy 232.22518 -85.764319) (xy 232.182976 -85.79806) (xy 232.13662 -85.825823)
			(xy 232.086955 -85.847107) (xy 232.03488 -85.861524) (xy 231.981341 -85.868814) (xy 231.954324 -85.869272)
			(xy 231.925673 -85.868775) (xy 231.868955 -85.860623) (xy 231.813974 -85.844482) (xy 231.76185 -85.820681)
			(xy 231.713644 -85.789703) (xy 231.670337 -85.75218) (xy 231.632811 -85.708876) (xy 231.601831 -85.660671)
			(xy 231.578026 -85.608549) (xy 231.561882 -85.553569) (xy 231.553727 -85.496851) (xy 203.567444 -85.496851)
			(xy 203.572509 -85.504506) (xy 203.596181 -85.555003) (xy 203.612249 -85.60841) (xy 203.620369 -85.663586)
			(xy 203.620878 -85.691472) (xy 203.620369 -85.719358) (xy 203.612249 -85.774534) (xy 203.596181 -85.827941)
			(xy 203.572509 -85.878438) (xy 203.541736 -85.924951) (xy 203.504519 -85.966488) (xy 203.461651 -86.002163)
			(xy 203.414045 -86.031217) (xy 203.362716 -86.053029) (xy 203.308759 -86.067135) (xy 203.253322 -86.073235)
			(xy 203.197588 -86.071198) (xy 203.142745 -86.061068) (xy 203.089961 -86.043061) (xy 203.040361 -86.01756)
			(xy 202.995003 -85.985109) (xy 202.954854 -85.9464) (xy 202.920768 -85.902257) (xy 202.893472 -85.853622)
			(xy 202.873549 -85.801531) (xy 202.861423 -85.747094) (xy 202.857352 -85.691472) (xy 200.363836 -85.691472)
			(xy 200.363836 -86.586568) (xy 221.584772 -86.586568) (xy 221.588843 -86.530946) (xy 221.600969 -86.476509)
			(xy 221.620892 -86.424418) (xy 221.648188 -86.375783) (xy 221.682274 -86.33164) (xy 221.722423 -86.292931)
			(xy 221.767781 -86.26048) (xy 221.817381 -86.234979) (xy 221.870165 -86.216972) (xy 221.925008 -86.206842)
			(xy 221.980742 -86.204805) (xy 222.036179 -86.210905) (xy 222.090136 -86.225011) (xy 222.141465 -86.246823)
			(xy 222.189071 -86.275877) (xy 222.231939 -86.311552) (xy 222.254638 -86.336886) (xy 256.999484 -86.336886)
			(xy 257.003555 -86.281264) (xy 257.015681 -86.226827) (xy 257.035604 -86.174736) (xy 257.0629 -86.126101)
			(xy 257.096986 -86.081958) (xy 257.137135 -86.043249) (xy 257.182493 -86.010798) (xy 257.232093 -85.985297)
			(xy 257.284877 -85.96729) (xy 257.33972 -85.95716) (xy 257.395454 -85.955123) (xy 257.450891 -85.961223)
			(xy 257.504848 -85.975329) (xy 257.556177 -85.997141) (xy 257.603783 -86.026195) (xy 257.646651 -86.06187)
			(xy 257.683868 -86.103407) (xy 257.714641 -86.14992) (xy 257.738313 -86.200417) (xy 257.754381 -86.253824)
			(xy 257.762501 -86.309) (xy 257.76301 -86.336886) (xy 257.762501 -86.364772) (xy 257.754381 -86.419948)
			(xy 257.738313 -86.473355) (xy 257.714641 -86.523852) (xy 257.683868 -86.570365) (xy 257.657516 -86.599776)
			(xy 259.420612 -86.599776) (xy 259.424683 -86.544154) (xy 259.436809 -86.489717) (xy 259.456732 -86.437626)
			(xy 259.484028 -86.388991) (xy 259.518114 -86.344848) (xy 259.558263 -86.306139) (xy 259.603621 -86.273688)
			(xy 259.653221 -86.248187) (xy 259.706005 -86.23018) (xy 259.760848 -86.22005) (xy 259.816582 -86.218013)
			(xy 259.872019 -86.224113) (xy 259.925976 -86.238219) (xy 259.977305 -86.260031) (xy 260.024911 -86.289085)
			(xy 260.067779 -86.32476) (xy 260.104996 -86.366297) (xy 260.135769 -86.41281) (xy 260.159441 -86.463307)
			(xy 260.175509 -86.516714) (xy 260.183629 -86.57189) (xy 260.184138 -86.599776) (xy 260.183629 -86.627662)
			(xy 260.175509 -86.682838) (xy 260.159441 -86.736245) (xy 260.135769 -86.786742) (xy 260.104996 -86.833255)
			(xy 260.067779 -86.874792) (xy 260.024911 -86.910467) (xy 259.977305 -86.939521) (xy 259.925976 -86.961333)
			(xy 259.872019 -86.975439) (xy 259.816582 -86.981539) (xy 259.760848 -86.979502) (xy 259.706005 -86.969372)
			(xy 259.653221 -86.951365) (xy 259.603621 -86.925864) (xy 259.558263 -86.893413) (xy 259.518114 -86.854704)
			(xy 259.484028 -86.810561) (xy 259.456732 -86.761926) (xy 259.436809 -86.709835) (xy 259.424683 -86.655398)
			(xy 259.420612 -86.599776) (xy 257.657516 -86.599776) (xy 257.646651 -86.611902) (xy 257.603783 -86.647577)
			(xy 257.556177 -86.676631) (xy 257.504848 -86.698443) (xy 257.450891 -86.712549) (xy 257.395454 -86.718649)
			(xy 257.33972 -86.716612) (xy 257.284877 -86.706482) (xy 257.232093 -86.688475) (xy 257.182493 -86.662974)
			(xy 257.137135 -86.630523) (xy 257.096986 -86.591814) (xy 257.0629 -86.547671) (xy 257.035604 -86.499036)
			(xy 257.015681 -86.446945) (xy 257.003555 -86.392508) (xy 256.999484 -86.336886) (xy 222.254638 -86.336886)
			(xy 222.269156 -86.353089) (xy 222.299929 -86.399602) (xy 222.323601 -86.450099) (xy 222.339669 -86.503506)
			(xy 222.347789 -86.558682) (xy 222.348298 -86.586568) (xy 222.347789 -86.614454) (xy 222.339669 -86.66963)
			(xy 222.323601 -86.723037) (xy 222.299929 -86.773534) (xy 222.269156 -86.820047) (xy 222.231939 -86.861584)
			(xy 222.189071 -86.897259) (xy 222.141465 -86.926313) (xy 222.090136 -86.948125) (xy 222.036179 -86.962231)
			(xy 221.980742 -86.968331) (xy 221.925008 -86.966294) (xy 221.870165 -86.956164) (xy 221.817381 -86.938157)
			(xy 221.767781 -86.912656) (xy 221.722423 -86.880205) (xy 221.682274 -86.841496) (xy 221.648188 -86.797353)
			(xy 221.620892 -86.748718) (xy 221.600969 -86.696627) (xy 221.588843 -86.64219) (xy 221.584772 -86.586568)
			(xy 200.363836 -86.586568) (xy 200.363836 -87.150749) (xy 218.508602 -87.150749) (xy 218.508602 -87.096251)
			(xy 218.516358 -87.042309) (xy 218.531711 -86.990019) (xy 218.554349 -86.940446) (xy 218.583812 -86.8946)
			(xy 218.619499 -86.853413) (xy 218.660684 -86.817724) (xy 218.706529 -86.788259) (xy 218.7561 -86.765618)
			(xy 218.808389 -86.750262) (xy 218.862331 -86.742504) (xy 218.88958 -86.742016) (xy 218.917628 -86.742546)
			(xy 218.97312 -86.750765) (xy 219.026812 -86.767015) (xy 219.077549 -86.790945) (xy 219.124239 -86.82204)
			(xy 219.165877 -86.859632) (xy 219.201568 -86.902912) (xy 219.216478 -86.926674) (xy 219.224257 -86.938562)
			(xy 219.245022 -86.957927) (xy 219.270316 -86.970825) (xy 219.298185 -86.976259) (xy 219.326472 -86.973808)
			(xy 219.35299 -86.963662) (xy 219.37569 -86.946605) (xy 219.384626 -86.935564) (xy 219.40277 -86.912328)
			(xy 219.445002 -86.871198) (xy 219.493058 -86.837053) (xy 219.545794 -86.810706) (xy 219.601955 -86.792785)
			(xy 219.660204 -86.783714) (xy 219.68968 -86.783164) (xy 219.716932 -86.783682) (xy 219.770881 -86.791436)
			(xy 219.823177 -86.806789) (xy 219.872756 -86.829429) (xy 219.918609 -86.858894) (xy 219.959801 -86.894585)
			(xy 219.995494 -86.935775) (xy 220.024962 -86.981626) (xy 220.047604 -87.031204) (xy 220.058677 -87.068914)
			(xy 220.702884 -87.068914) (xy 220.706955 -87.013292) (xy 220.719081 -86.958855) (xy 220.739004 -86.906764)
			(xy 220.7663 -86.858129) (xy 220.800386 -86.813986) (xy 220.840535 -86.775277) (xy 220.885893 -86.742826)
			(xy 220.935493 -86.717325) (xy 220.988277 -86.699318) (xy 221.04312 -86.689188) (xy 221.098854 -86.687151)
			(xy 221.154291 -86.693251) (xy 221.208248 -86.707357) (xy 221.259577 -86.729169) (xy 221.307183 -86.758223)
			(xy 221.350051 -86.793898) (xy 221.387268 -86.835435) (xy 221.418041 -86.881948) (xy 221.441713 -86.932445)
			(xy 221.457781 -86.985852) (xy 221.465901 -87.041028) (xy 221.46641 -87.068914) (xy 221.465901 -87.0968)
			(xy 221.457781 -87.151976) (xy 221.441713 -87.205383) (xy 221.418041 -87.25588) (xy 221.387268 -87.302393)
			(xy 221.350051 -87.34393) (xy 221.307183 -87.379605) (xy 221.259577 -87.408659) (xy 221.208248 -87.430471)
			(xy 221.154291 -87.444577) (xy 221.098854 -87.450677) (xy 221.04312 -87.44864) (xy 220.988277 -87.43851)
			(xy 220.935493 -87.420503) (xy 220.885893 -87.395002) (xy 220.840535 -87.362551) (xy 220.800386 -87.323842)
			(xy 220.7663 -87.279699) (xy 220.739004 -87.231064) (xy 220.719081 -87.178973) (xy 220.706955 -87.124536)
			(xy 220.702884 -87.068914) (xy 220.058677 -87.068914) (xy 220.06296 -87.0835) (xy 220.070717 -87.137448)
			(xy 220.070717 -87.191952) (xy 220.06296 -87.2459) (xy 220.047604 -87.298196) (xy 220.024962 -87.347774)
			(xy 219.995494 -87.393625) (xy 219.959801 -87.434815) (xy 219.918609 -87.470506) (xy 219.872756 -87.499971)
			(xy 219.823177 -87.522611) (xy 219.770881 -87.537964) (xy 219.716932 -87.545718) (xy 219.68968 -87.54618)
			(xy 219.66163 -87.545683) (xy 219.606137 -87.537458) (xy 219.552444 -87.521203) (xy 219.501707 -87.497268)
			(xy 219.455017 -87.466167) (xy 219.41338 -87.42857) (xy 219.377692 -87.385286) (xy 219.362782 -87.361522)
			(xy 219.355055 -87.349598) (xy 219.334279 -87.330231) (xy 219.308973 -87.317335) (xy 219.281095 -87.311906)
			(xy 219.252799 -87.314364) (xy 219.226274 -87.324519) (xy 219.203571 -87.341586) (xy 219.194634 -87.352632)
			(xy 219.176512 -87.375886) (xy 219.134275 -87.417015) (xy 219.086215 -87.451158) (xy 219.033474 -87.477502)
			(xy 218.97731 -87.49542) (xy 218.919057 -87.504485) (xy 218.88958 -87.505032) (xy 218.862331 -87.504496)
			(xy 218.808389 -87.496738) (xy 218.7561 -87.481382) (xy 218.706529 -87.458741) (xy 218.660684 -87.429276)
			(xy 218.619499 -87.393587) (xy 218.583812 -87.3524) (xy 218.554349 -87.306554) (xy 218.531711 -87.256981)
			(xy 218.516358 -87.204691) (xy 218.508602 -87.150749) (xy 200.363836 -87.150749) (xy 200.363836 -87.655654)
			(xy 209.414616 -87.655654) (xy 209.418687 -87.600032) (xy 209.430813 -87.545595) (xy 209.450736 -87.493504)
			(xy 209.478032 -87.444869) (xy 209.512118 -87.400726) (xy 209.552267 -87.362017) (xy 209.597625 -87.329566)
			(xy 209.647225 -87.304065) (xy 209.700009 -87.286058) (xy 209.754852 -87.275928) (xy 209.810586 -87.273891)
			(xy 209.866023 -87.279991) (xy 209.91998 -87.294097) (xy 209.971309 -87.315909) (xy 210.018915 -87.344963)
			(xy 210.061783 -87.380638) (xy 210.099 -87.422175) (xy 210.129773 -87.468688) (xy 210.153445 -87.519185)
			(xy 210.169513 -87.572592) (xy 210.177633 -87.627768) (xy 210.178142 -87.655654) (xy 210.177633 -87.68354)
			(xy 210.169513 -87.738716) (xy 210.153445 -87.792123) (xy 210.129773 -87.84262) (xy 210.099 -87.889133)
			(xy 210.061783 -87.93067) (xy 210.018915 -87.966345) (xy 209.971309 -87.995399) (xy 209.91998 -88.017211)
			(xy 209.866023 -88.031317) (xy 209.810586 -88.037417) (xy 209.754852 -88.03538) (xy 209.700009 -88.02525)
			(xy 209.647225 -88.007243) (xy 209.597625 -87.981742) (xy 209.552267 -87.949291) (xy 209.512118 -87.910582)
			(xy 209.478032 -87.866439) (xy 209.450736 -87.817804) (xy 209.430813 -87.765713) (xy 209.418687 -87.711276)
			(xy 209.414616 -87.655654) (xy 200.363836 -87.655654) (xy 200.363836 -88.22436) (xy 202.80198 -88.22436)
			(xy 202.806051 -88.168738) (xy 202.818177 -88.114301) (xy 202.8381 -88.06221) (xy 202.865396 -88.013575)
			(xy 202.899482 -87.969432) (xy 202.939631 -87.930723) (xy 202.984989 -87.898272) (xy 203.034589 -87.872771)
			(xy 203.087373 -87.854764) (xy 203.142216 -87.844634) (xy 203.19795 -87.842597) (xy 203.253387 -87.848697)
			(xy 203.307344 -87.862803) (xy 203.358673 -87.884615) (xy 203.406279 -87.913669) (xy 203.449147 -87.949344)
			(xy 203.486364 -87.990881) (xy 203.517137 -88.037394) (xy 203.540809 -88.087891) (xy 203.556877 -88.141298)
			(xy 203.564997 -88.196474) (xy 203.565506 -88.22436) (xy 203.564997 -88.252246) (xy 203.556877 -88.307422)
			(xy 203.540809 -88.360829) (xy 203.518338 -88.408764) (xy 208.564986 -88.408764) (xy 208.569057 -88.353142)
			(xy 208.581183 -88.298705) (xy 208.601106 -88.246614) (xy 208.628402 -88.197979) (xy 208.662488 -88.153836)
			(xy 208.702637 -88.115127) (xy 208.747995 -88.082676) (xy 208.797595 -88.057175) (xy 208.850379 -88.039168)
			(xy 208.905222 -88.029038) (xy 208.960956 -88.027001) (xy 209.016393 -88.033101) (xy 209.07035 -88.047207)
			(xy 209.121679 -88.069019) (xy 209.169285 -88.098073) (xy 209.212153 -88.133748) (xy 209.24937 -88.175285)
			(xy 209.280143 -88.221798) (xy 209.303815 -88.272295) (xy 209.319883 -88.325702) (xy 209.328003 -88.380878)
			(xy 209.328373 -88.401144) (xy 210.261708 -88.401144) (xy 210.262298 -88.370694) (xy 210.271505 -88.310495)
			(xy 210.289714 -88.252382) (xy 210.316506 -88.197692) (xy 210.351264 -88.147686) (xy 210.393188 -88.103514)
			(xy 210.416902 -88.084406) (xy 210.425792 -88.077548) (xy 210.435952 -88.058244) (xy 210.441032 -87.959184)
			(xy 210.432904 -87.93861) (xy 210.42503 -87.93099) (xy 210.406812 -87.912942) (xy 210.374907 -87.872794)
			(xy 210.348666 -87.828735) (xy 210.328561 -87.781559) (xy 210.314956 -87.732115) (xy 210.308094 -87.681295)
			(xy 210.307682 -87.655654) (xy 210.308168 -87.628403) (xy 210.315924 -87.574455) (xy 210.331279 -87.52216)
			(xy 210.353921 -87.472583) (xy 210.383387 -87.426733) (xy 210.419078 -87.385542) (xy 210.460269 -87.349851)
			(xy 210.506119 -87.320385) (xy 210.555696 -87.297743) (xy 210.607991 -87.282388) (xy 210.661939 -87.274632)
			(xy 210.716441 -87.274632) (xy 210.770389 -87.282388) (xy 210.822684 -87.297743) (xy 210.872261 -87.320385)
			(xy 210.918111 -87.349851) (xy 210.959302 -87.385542) (xy 210.994993 -87.426733) (xy 211.024459 -87.472583)
			(xy 211.047101 -87.52216) (xy 211.062456 -87.574455) (xy 211.067411 -87.608918) (xy 221.615252 -87.608918)
			(xy 221.619323 -87.553296) (xy 221.631449 -87.498859) (xy 221.651372 -87.446768) (xy 221.678668 -87.398133)
			(xy 221.712754 -87.35399) (xy 221.752903 -87.315281) (xy 221.798261 -87.28283) (xy 221.847861 -87.257329)
			(xy 221.900645 -87.239322) (xy 221.955488 -87.229192) (xy 222.011222 -87.227155) (xy 222.066659 -87.233255)
			(xy 222.120616 -87.247361) (xy 222.171945 -87.269173) (xy 222.219551 -87.298227) (xy 222.262419 -87.333902)
			(xy 222.2975 -87.373055) (xy 231.337529 -87.373055) (xy 231.337529 -87.318545) (xy 231.345287 -87.264589)
			(xy 231.360644 -87.212287) (xy 231.383289 -87.162702) (xy 231.412761 -87.116845) (xy 231.448458 -87.075649)
			(xy 231.489655 -87.039953) (xy 231.535513 -87.010484) (xy 231.585098 -86.98784) (xy 231.637401 -86.972484)
			(xy 231.691357 -86.964728) (xy 231.718612 -86.964266) (xy 231.74605 -86.964772) (xy 231.800358 -86.972649)
			(xy 231.852978 -86.988223) (xy 231.902825 -87.011174) (xy 231.94887 -87.041028) (xy 231.990164 -87.07717)
			(xy 232.025855 -87.118854) (xy 232.055207 -87.16522) (xy 232.066846 -87.190072) (xy 232.071008 -87.198598)
			(xy 232.084455 -87.211965) (xy 232.101838 -87.21954) (xy 232.111296 -87.220298) (xy 232.21696 -87.224108)
			(xy 232.242106 -87.20963) (xy 232.248964 -87.19693) (xy 232.264033 -87.170046) (xy 232.300311 -87.120224)
			(xy 232.342942 -87.075716) (xy 232.391154 -87.037325) (xy 232.444079 -87.005745) (xy 232.50076 -86.981546)
			(xy 232.560173 -86.965164) (xy 232.621247 -86.956896) (xy 232.652062 -86.956392) (xy 233.516424 -86.956392)
			(xy 233.547197 -86.956912) (xy 233.608182 -86.965207) (xy 233.667507 -86.981591) (xy 233.696002 -86.993222)
			(xy 233.696256 -86.993222) (xy 233.70424 -86.996287) (xy 233.721293 -86.997443) (xy 233.737786 -86.992952)
			(xy 233.745024 -86.988396) (xy 233.815636 -86.939882) (xy 233.822501 -86.934791) (xy 233.832655 -86.921056)
			(xy 233.83771 -86.904741) (xy 233.837734 -86.896194) (xy 233.83748 -86.880954) (xy 233.837901 -86.852314)
			(xy 233.846056 -86.795617) (xy 233.862194 -86.740658) (xy 233.885986 -86.688552) (xy 233.916948 -86.640362)
			(xy 233.954451 -86.597066) (xy 233.997732 -86.559545) (xy 234.04591 -86.528564) (xy 234.098006 -86.504751)
			(xy 234.152959 -86.488591) (xy 234.209652 -86.480413) (xy 234.238292 -86.479888) (xy 234.268012 -86.48038)
			(xy 234.326801 -86.489144) (xy 234.383651 -86.506494) (xy 234.437315 -86.532052) (xy 234.486615 -86.565256)
			(xy 234.53047 -86.605377) (xy 234.567918 -86.651536) (xy 234.598138 -86.702719) (xy 234.620466 -86.757805)
			(xy 234.634412 -86.815585) (xy 234.63758 -86.84514) (xy 234.639074 -86.855621) (xy 234.649303 -86.874126)
			(xy 234.657392 -86.880954) (xy 234.717336 -86.92642) (xy 234.725979 -86.932346) (xy 234.746305 -86.937343)
			(xy 234.756706 -86.936072) (xy 234.757214 -86.936072) (xy 234.77748 -86.932563) (xy 234.818436 -86.928751)
			(xy 234.839002 -86.928452) (xy 235.702602 -86.928452) (xy 235.726859 -86.92882) (xy 235.775093 -86.934038)
			(xy 235.798868 -86.938866) (xy 235.799122 -86.938866) (xy 235.809824 -86.940649) (xy 235.831006 -86.936025)
			(xy 235.840016 -86.929976) (xy 235.90123 -86.884256) (xy 235.909457 -86.877402) (xy 235.919966 -86.858777)
			(xy 235.92155 -86.848188) (xy 235.92155 -86.84768) (xy 235.924261 -86.820685) (xy 235.936003 -86.767718)
			(xy 235.95478 -86.716818) (xy 235.980248 -86.668914) (xy 236.011942 -86.624881) (xy 236.049283 -86.585523)
			(xy 236.09159 -86.551559) (xy 236.138089 -86.523609) (xy 236.187933 -86.502183) (xy 236.24021 -86.487673)
			(xy 236.293966 -86.480344) (xy 236.321092 -86.479888) (xy 236.349724 -86.480374) (xy 236.406406 -86.488523)
			(xy 236.461351 -86.504655) (xy 236.513441 -86.528443) (xy 236.561615 -86.559402) (xy 236.604893 -86.596901)
			(xy 236.642394 -86.640178) (xy 236.673353 -86.688352) (xy 236.697142 -86.740442) (xy 236.713276 -86.795386)
			(xy 236.721425 -86.852068) (xy 236.721425 -86.909332) (xy 236.713276 -86.966014) (xy 236.697142 -87.020958)
			(xy 236.673353 -87.073048) (xy 236.642394 -87.121222) (xy 236.604893 -87.164499) (xy 236.561615 -87.201998)
			(xy 236.513441 -87.232957) (xy 236.461351 -87.256745) (xy 236.406406 -87.272877) (xy 236.349724 -87.281026)
			(xy 236.321092 -87.281512) (xy 236.309256 -87.281498) (xy 236.285618 -87.280225) (xy 236.273848 -87.278972)
			(xy 236.262926 -87.277702) (xy 236.242098 -87.284052) (xy 236.177074 -87.342726) (xy 236.169367 -87.350288)
			(xy 236.160684 -87.370035) (xy 236.16031 -87.380826) (xy 236.16031 -87.38108) (xy 236.160564 -87.385144)
			(xy 236.160564 -87.387684) (xy 236.160004 -87.417614) (xy 236.152037 -87.476945) (xy 236.136409 -87.534732)
			(xy 236.113384 -87.589991) (xy 236.083355 -87.641778) (xy 236.046835 -87.689211) (xy 236.004446 -87.731482)
			(xy 235.988191 -87.743925) (xy 237.458842 -87.743925) (xy 237.458842 -87.686675) (xy 237.466989 -87.630007)
			(xy 237.483118 -87.575075) (xy 237.506899 -87.522998) (xy 237.537849 -87.474834) (xy 237.575339 -87.431566)
			(xy 237.618604 -87.394072) (xy 237.666764 -87.363117) (xy 237.718839 -87.339331) (xy 237.77377 -87.323197)
			(xy 237.830437 -87.315045) (xy 237.859062 -87.314532) (xy 237.886709 -87.31494) (xy 237.94148 -87.322532)
			(xy 237.994689 -87.337577) (xy 238.045326 -87.359789) (xy 238.092431 -87.388747) (xy 238.135111 -87.423903)
			(xy 238.172556 -87.464589) (xy 238.204056 -87.510034) (xy 238.216948 -87.534496) (xy 238.22152 -87.543894)
			(xy 238.237268 -87.557102) (xy 238.317532 -87.581486) (xy 238.327509 -87.584035) (xy 238.347961 -87.581804)
			(xy 238.357156 -87.577168) (xy 238.35741 -87.577168) (xy 238.383221 -87.563195) (xy 238.437624 -87.541169)
			(xy 238.494393 -87.526266) (xy 238.5526 -87.51873) (xy 238.581946 -87.51824) (xy 239.445546 -87.51824)
			(xy 239.4767 -87.518783) (xy 239.538425 -87.527294) (xy 239.59843 -87.544084) (xy 239.655608 -87.568844)
			(xy 239.682528 -87.584534) (xy 239.682782 -87.584534) (xy 239.691938 -87.589458) (xy 239.712528 -87.592202)
			(xy 239.72266 -87.589868) (xy 239.804448 -87.566754) (xy 239.820704 -87.553546) (xy 239.82553 -87.544148)
			(xy 239.838465 -87.519886) (xy 239.869998 -87.474844) (xy 239.907393 -87.434537) (xy 239.949948 -87.399722)
			(xy 239.996864 -87.371052) (xy 240.04726 -87.349067) (xy 240.100188 -87.334178) (xy 240.154655 -87.326667)
			(xy 240.182146 -87.326216) (xy 240.210791 -87.326766) (xy 240.267497 -87.334925) (xy 240.322464 -87.351071)
			(xy 240.374575 -87.374874) (xy 240.422768 -87.405851) (xy 240.466062 -87.44337) (xy 240.503577 -87.486669)
			(xy 240.534548 -87.534866) (xy 240.558345 -87.586979) (xy 240.574484 -87.641948) (xy 240.577346 -87.661851)
			(xy 246.84685 -87.661851) (xy 246.84685 -87.607349) (xy 246.854606 -87.553401) (xy 246.869959 -87.501107)
			(xy 246.892599 -87.451529) (xy 246.922063 -87.405678) (xy 246.957752 -87.364486) (xy 246.998939 -87.328791)
			(xy 247.044787 -87.299322) (xy 247.094362 -87.276676) (xy 247.146655 -87.261316) (xy 247.200601 -87.253553)
			(xy 247.227852 -87.253064) (xy 247.228106 -87.253064) (xy 247.247808 -87.25333) (xy 247.287002 -87.257403)
			(xy 247.306338 -87.261192) (xy 247.31772 -87.262991) (xy 247.340063 -87.257458) (xy 247.349264 -87.250524)
			(xy 247.419622 -87.192358) (xy 247.42902 -87.171022) (xy 247.428766 -87.159338) (xy 247.428766 -87.150448)
			(xy 247.429204 -87.123191) (xy 247.436955 -87.06923) (xy 247.452308 -87.016921) (xy 247.474949 -86.96733)
			(xy 247.504417 -86.921466) (xy 247.540113 -86.880263) (xy 247.581309 -86.84456) (xy 247.627168 -86.815083)
			(xy 247.676754 -86.792433) (xy 247.72906 -86.777071) (xy 247.783019 -86.769309) (xy 247.837534 -86.769305)
			(xy 247.891495 -86.777061) (xy 247.911418 -86.78291) (xy 249.4821 -86.78291) (xy 249.486171 -86.727288)
			(xy 249.498297 -86.672851) (xy 249.51822 -86.62076) (xy 249.545516 -86.572125) (xy 249.579602 -86.527982)
			(xy 249.619751 -86.489273) (xy 249.665109 -86.456822) (xy 249.714709 -86.431321) (xy 249.767493 -86.413314)
			(xy 249.822336 -86.403184) (xy 249.87807 -86.401147) (xy 249.933507 -86.407247) (xy 249.987464 -86.421353)
			(xy 250.038793 -86.443165) (xy 250.086399 -86.472219) (xy 250.129267 -86.507894) (xy 250.166484 -86.549431)
			(xy 250.197257 -86.595944) (xy 250.220929 -86.646441) (xy 250.236997 -86.699848) (xy 250.245117 -86.755024)
			(xy 250.245626 -86.78291) (xy 250.245117 -86.810796) (xy 250.236997 -86.865972) (xy 250.220929 -86.919379)
			(xy 250.197257 -86.969876) (xy 250.166484 -87.016389) (xy 250.129267 -87.057926) (xy 250.086399 -87.093601)
			(xy 250.038793 -87.122655) (xy 249.987464 -87.144467) (xy 249.933507 -87.158573) (xy 249.87807 -87.164673)
			(xy 249.822336 -87.162636) (xy 249.767493 -87.152506) (xy 249.714709 -87.134499) (xy 249.665109 -87.108998)
			(xy 249.619751 -87.076547) (xy 249.579602 -87.037838) (xy 249.545516 -86.993695) (xy 249.51822 -86.94506)
			(xy 249.498297 -86.892969) (xy 249.486171 -86.838532) (xy 249.4821 -86.78291) (xy 247.911418 -86.78291)
			(xy 247.943802 -86.792417) (xy 247.993391 -86.815061) (xy 248.039253 -86.844532) (xy 248.080454 -86.88023)
			(xy 248.116155 -86.921429) (xy 248.145629 -86.967289) (xy 248.168276 -87.016877) (xy 248.183635 -87.069184)
			(xy 248.191393 -87.123144) (xy 248.191393 -87.177659) (xy 248.183634 -87.231619) (xy 248.168275 -87.283925)
			(xy 248.145627 -87.333513) (xy 248.140849 -87.340948) (xy 250.984002 -87.340948) (xy 250.988073 -87.285326)
			(xy 251.000199 -87.230889) (xy 251.020122 -87.178798) (xy 251.047418 -87.130163) (xy 251.081504 -87.08602)
			(xy 251.121653 -87.047311) (xy 251.167011 -87.01486) (xy 251.216611 -86.989359) (xy 251.269395 -86.971352)
			(xy 251.324238 -86.961222) (xy 251.379972 -86.959185) (xy 251.435409 -86.965285) (xy 251.489366 -86.979391)
			(xy 251.540695 -87.001203) (xy 251.588301 -87.030257) (xy 251.631169 -87.065932) (xy 251.668386 -87.107469)
			(xy 251.699159 -87.153982) (xy 251.722831 -87.204479) (xy 251.738899 -87.257886) (xy 251.747019 -87.313062)
			(xy 251.747528 -87.340948) (xy 251.747019 -87.368834) (xy 251.738899 -87.42401) (xy 251.722831 -87.477417)
			(xy 251.699159 -87.527914) (xy 251.668386 -87.574427) (xy 251.631169 -87.615964) (xy 251.588301 -87.651639)
			(xy 251.540695 -87.680693) (xy 251.489366 -87.702505) (xy 251.435409 -87.716611) (xy 251.405373 -87.719916)
			(xy 252.861062 -87.719916) (xy 252.865133 -87.664294) (xy 252.877259 -87.609857) (xy 252.897182 -87.557766)
			(xy 252.924478 -87.509131) (xy 252.958564 -87.464988) (xy 252.998713 -87.426279) (xy 253.044071 -87.393828)
			(xy 253.093671 -87.368327) (xy 253.146455 -87.35032) (xy 253.201298 -87.34019) (xy 253.257032 -87.338153)
			(xy 253.312469 -87.344253) (xy 253.366426 -87.358359) (xy 253.417755 -87.380171) (xy 253.465361 -87.409225)
			(xy 253.508229 -87.4449) (xy 253.545446 -87.486437) (xy 253.554051 -87.499444) (xy 256.099562 -87.499444)
			(xy 256.103633 -87.443822) (xy 256.115759 -87.389385) (xy 256.135682 -87.337294) (xy 256.162978 -87.288659)
			(xy 256.197064 -87.244516) (xy 256.237213 -87.205807) (xy 256.282571 -87.173356) (xy 256.332171 -87.147855)
			(xy 256.384955 -87.129848) (xy 256.439798 -87.119718) (xy 256.495532 -87.117681) (xy 256.550969 -87.123781)
			(xy 256.604926 -87.137887) (xy 256.656255 -87.159699) (xy 256.703861 -87.188753) (xy 256.746729 -87.224428)
			(xy 256.783946 -87.265965) (xy 256.814719 -87.312478) (xy 256.838391 -87.362975) (xy 256.854459 -87.416382)
			(xy 256.862579 -87.471558) (xy 256.863088 -87.499444) (xy 256.862579 -87.52733) (xy 256.854459 -87.582506)
			(xy 256.838391 -87.635913) (xy 256.814719 -87.68641) (xy 256.783946 -87.732923) (xy 256.746729 -87.77446)
			(xy 256.703861 -87.810135) (xy 256.656255 -87.839189) (xy 256.604926 -87.861001) (xy 256.550969 -87.875107)
			(xy 256.495532 -87.881207) (xy 256.439798 -87.87917) (xy 256.384955 -87.86904) (xy 256.332171 -87.851033)
			(xy 256.282571 -87.825532) (xy 256.237213 -87.793081) (xy 256.197064 -87.754372) (xy 256.162978 -87.710229)
			(xy 256.135682 -87.661594) (xy 256.115759 -87.609503) (xy 256.103633 -87.555066) (xy 256.099562 -87.499444)
			(xy 253.554051 -87.499444) (xy 253.576219 -87.53295) (xy 253.599891 -87.583447) (xy 253.615959 -87.636854)
			(xy 253.624079 -87.69203) (xy 253.624588 -87.719916) (xy 253.624079 -87.747802) (xy 253.615959 -87.802978)
			(xy 253.599891 -87.856385) (xy 253.576219 -87.906882) (xy 253.545446 -87.953395) (xy 253.508229 -87.994932)
			(xy 253.465361 -88.030607) (xy 253.417755 -88.059661) (xy 253.366426 -88.081473) (xy 253.336747 -88.089232)
			(xy 265.293346 -88.089232) (xy 265.297417 -88.03361) (xy 265.309543 -87.979173) (xy 265.329466 -87.927082)
			(xy 265.356762 -87.878447) (xy 265.390848 -87.834304) (xy 265.430997 -87.795595) (xy 265.476355 -87.763144)
			(xy 265.525955 -87.737643) (xy 265.578739 -87.719636) (xy 265.633582 -87.709506) (xy 265.689316 -87.707469)
			(xy 265.744753 -87.713569) (xy 265.79871 -87.727675) (xy 265.850039 -87.749487) (xy 265.897645 -87.778541)
			(xy 265.940513 -87.814216) (xy 265.951329 -87.826288) (xy 273.884647 -87.826288) (xy 273.884647 -87.768992)
			(xy 273.892801 -87.712278) (xy 273.908944 -87.657303) (xy 273.932745 -87.605184) (xy 273.963722 -87.556983)
			(xy 274.001243 -87.513681) (xy 274.044545 -87.47616) (xy 274.092746 -87.445183) (xy 274.144865 -87.421382)
			(xy 274.19984 -87.405239) (xy 274.256554 -87.397085) (xy 274.31385 -87.397085) (xy 274.370564 -87.405239)
			(xy 274.425539 -87.421382) (xy 274.477658 -87.445183) (xy 274.525859 -87.47616) (xy 274.569161 -87.513681)
			(xy 274.606682 -87.556983) (xy 274.637659 -87.605184) (xy 274.66146 -87.657303) (xy 274.677603 -87.712278)
			(xy 274.685757 -87.768992) (xy 274.686268 -87.79764) (xy 274.685757 -87.826288) (xy 274.677603 -87.883002)
			(xy 274.66146 -87.937977) (xy 274.637659 -87.990096) (xy 274.606682 -88.038297) (xy 274.569161 -88.081599)
			(xy 274.525859 -88.11912) (xy 274.477658 -88.150097) (xy 274.425539 -88.173898) (xy 274.370564 -88.190041)
			(xy 274.31385 -88.198195) (xy 274.256554 -88.198195) (xy 274.19984 -88.190041) (xy 274.144865 -88.173898)
			(xy 274.092746 -88.150097) (xy 274.044545 -88.11912) (xy 274.001243 -88.081599) (xy 273.963722 -88.038297)
			(xy 273.932745 -87.990096) (xy 273.908944 -87.937977) (xy 273.892801 -87.883002) (xy 273.884647 -87.826288)
			(xy 265.951329 -87.826288) (xy 265.97773 -87.855753) (xy 266.008503 -87.902266) (xy 266.032175 -87.952763)
			(xy 266.048243 -88.00617) (xy 266.056363 -88.061346) (xy 266.056872 -88.089232) (xy 266.056363 -88.117118)
			(xy 266.048243 -88.172294) (xy 266.032175 -88.225701) (xy 266.008503 -88.276198) (xy 265.97773 -88.322711)
			(xy 265.940513 -88.364248) (xy 265.897645 -88.399923) (xy 265.850039 -88.428977) (xy 265.79871 -88.450789)
			(xy 265.744753 -88.464895) (xy 265.689316 -88.470995) (xy 265.633582 -88.468958) (xy 265.578739 -88.458828)
			(xy 265.525955 -88.440821) (xy 265.476355 -88.41532) (xy 265.430997 -88.382869) (xy 265.390848 -88.34416)
			(xy 265.356762 -88.300017) (xy 265.329466 -88.251382) (xy 265.309543 -88.199291) (xy 265.297417 -88.144854)
			(xy 265.293346 -88.089232) (xy 253.336747 -88.089232) (xy 253.312469 -88.095579) (xy 253.257032 -88.101679)
			(xy 253.201298 -88.099642) (xy 253.146455 -88.089512) (xy 253.093671 -88.071505) (xy 253.044071 -88.046004)
			(xy 252.998713 -88.013553) (xy 252.958564 -87.974844) (xy 252.924478 -87.930701) (xy 252.897182 -87.882066)
			(xy 252.877259 -87.829975) (xy 252.865133 -87.775538) (xy 252.861062 -87.719916) (xy 251.405373 -87.719916)
			(xy 251.379972 -87.722711) (xy 251.324238 -87.720674) (xy 251.269395 -87.710544) (xy 251.216611 -87.692537)
			(xy 251.167011 -87.667036) (xy 251.121653 -87.634585) (xy 251.081504 -87.595876) (xy 251.047418 -87.551733)
			(xy 251.020122 -87.503098) (xy 251.000199 -87.451007) (xy 250.988073 -87.39657) (xy 250.984002 -87.340948)
			(xy 248.140849 -87.340948) (xy 248.116153 -87.379373) (xy 248.080452 -87.420571) (xy 248.039251 -87.45627)
			(xy 247.993389 -87.48574) (xy 247.943799 -87.508384) (xy 247.891492 -87.52374) (xy 247.837531 -87.531495)
			(xy 247.810274 -87.531956) (xy 247.781366 -87.531391) (xy 247.724221 -87.522588) (xy 247.696482 -87.51443)
			(xy 247.688278 -87.512193) (xy 247.67129 -87.512739) (xy 247.655427 -87.51884) (xy 247.64873 -87.524082)
			(xy 247.602502 -87.562436) (xy 247.605804 -87.58174) (xy 247.607774 -87.592109) (xy 247.618789 -87.610085)
			(xy 247.62714 -87.616538) (xy 247.6881 -87.658956) (xy 247.69703 -87.664493) (xy 247.717617 -87.668573)
			(xy 247.727978 -87.66683) (xy 247.728232 -87.66683) (xy 247.74842 -87.662657) (xy 247.789406 -87.658204)
			(xy 247.81002 -87.65794) (xy 247.810274 -87.65794) (xy 247.837532 -87.658305) (xy 247.891492 -87.66606)
			(xy 247.9438 -87.681416) (xy 247.993389 -87.70406) (xy 248.039252 -87.733531) (xy 248.080453 -87.769229)
			(xy 248.116154 -87.810428) (xy 248.145628 -87.856288) (xy 248.168275 -87.905876) (xy 248.183634 -87.958182)
			(xy 248.191393 -88.012143) (xy 248.191393 -88.049608) (xy 249.542806 -88.049608) (xy 249.546877 -87.993986)
			(xy 249.559003 -87.939549) (xy 249.578926 -87.887458) (xy 249.606222 -87.838823) (xy 249.640308 -87.79468)
			(xy 249.680457 -87.755971) (xy 249.725815 -87.72352) (xy 249.775415 -87.698019) (xy 249.828199 -87.680012)
			(xy 249.883042 -87.669882) (xy 249.938776 -87.667845) (xy 249.994213 -87.673945) (xy 250.04817 -87.688051)
			(xy 250.099499 -87.709863) (xy 250.147105 -87.738917) (xy 250.189973 -87.774592) (xy 250.22719 -87.816129)
			(xy 250.257963 -87.862642) (xy 250.281635 -87.913139) (xy 250.297703 -87.966546) (xy 250.305823 -88.021722)
			(xy 250.306332 -88.049608) (xy 250.305823 -88.077494) (xy 250.297703 -88.13267) (xy 250.281635 -88.186077)
			(xy 250.257963 -88.236574) (xy 250.22719 -88.283087) (xy 250.189973 -88.324624) (xy 250.147105 -88.360299)
			(xy 250.099499 -88.389353) (xy 250.04817 -88.411165) (xy 249.994213 -88.425271) (xy 249.938776 -88.431371)
			(xy 249.883042 -88.429334) (xy 249.828199 -88.419204) (xy 249.775415 -88.401197) (xy 249.725815 -88.375696)
			(xy 249.680457 -88.343245) (xy 249.640308 -88.304536) (xy 249.606222 -88.260393) (xy 249.578926 -88.211758)
			(xy 249.559003 -88.159667) (xy 249.546877 -88.10523) (xy 249.542806 -88.049608) (xy 248.191393 -88.049608)
			(xy 248.191393 -88.066657) (xy 248.183634 -88.120618) (xy 248.168275 -88.172924) (xy 248.145628 -88.222512)
			(xy 248.116154 -88.268372) (xy 248.080453 -88.309571) (xy 248.039252 -88.345269) (xy 247.993389 -88.37474)
			(xy 247.9438 -88.397384) (xy 247.891492 -88.41274) (xy 247.837532 -88.420495) (xy 247.810274 -88.420956)
			(xy 247.782946 -88.420516) (xy 247.728852 -88.412692) (xy 247.676425 -88.397236) (xy 247.626738 -88.374464)
			(xy 247.580805 -88.344841) (xy 247.539564 -88.308972) (xy 247.503858 -88.26759) (xy 247.474416 -88.22154)
			(xy 247.451839 -88.171764) (xy 247.43659 -88.119277) (xy 247.432322 -88.09228) (xy 247.430333 -88.081916)
			(xy 247.419331 -88.063938) (xy 247.410986 -88.057482) (xy 247.350026 -88.015064) (xy 247.341116 -88.009488)
			(xy 247.320512 -88.005431) (xy 247.310148 -88.00719) (xy 247.309894 -88.00719) (xy 247.289705 -88.011359)
			(xy 247.248719 -88.015815) (xy 247.228106 -88.01608) (xy 247.227852 -88.01608) (xy 247.200601 -88.015647)
			(xy 247.146654 -88.007884) (xy 247.094362 -87.992524) (xy 247.044787 -87.969878) (xy 246.998939 -87.940409)
			(xy 246.957752 -87.904714) (xy 246.922063 -87.863522) (xy 246.892599 -87.817671) (xy 246.869959 -87.768093)
			(xy 246.854606 -87.715799) (xy 246.84685 -87.661851) (xy 240.577346 -87.661851) (xy 240.582637 -87.698655)
			(xy 240.582637 -87.755945) (xy 240.574484 -87.812652) (xy 240.558345 -87.867621) (xy 240.534548 -87.919734)
			(xy 240.503577 -87.967931) (xy 240.466062 -88.01123) (xy 240.422768 -88.048749) (xy 240.374575 -88.079726)
			(xy 240.322464 -88.103529) (xy 240.267497 -88.119675) (xy 240.210791 -88.127834) (xy 240.182146 -88.128348)
			(xy 240.152414 -88.127781) (xy 240.093607 -88.118955) (xy 240.036747 -88.101549) (xy 240.00968 -88.089232)
			(xy 240.000282 -88.08466) (xy 239.9792 -88.083898) (xy 239.900206 -88.11514) (xy 239.890631 -88.119437)
			(xy 239.875811 -88.13427) (xy 239.871504 -88.143842) (xy 239.859916 -88.171987) (xy 239.830354 -88.225192)
			(xy 239.794 -88.274008) (xy 239.751494 -88.317573) (xy 239.703588 -88.355118) (xy 239.651126 -88.385981)
			(xy 239.595037 -88.409615) (xy 239.536309 -88.425605) (xy 239.475979 -88.433668) (xy 239.445546 -88.434164)
			(xy 238.581946 -88.434164) (xy 238.551277 -88.433638) (xy 238.490492 -88.425417) (xy 238.431348 -88.409155)
			(xy 238.374905 -88.385143) (xy 238.322171 -88.353813) (xy 238.274092 -88.315723) (xy 238.231528 -88.271556)
			(xy 238.19524 -88.222103) (xy 238.165878 -88.168248) (xy 238.154464 -88.139778) (xy 238.154464 -88.139524)
			(xy 238.150284 -88.130217) (xy 238.136013 -88.115665) (xy 238.126778 -88.11133) (xy 238.049308 -88.078818)
			(xy 238.02848 -88.078818) (xy 238.019082 -88.083136) (xy 237.993727 -88.093628) (xy 237.940873 -88.108375)
			(xy 237.886499 -88.115761) (xy 237.859062 -88.116156) (xy 237.830437 -88.115555) (xy 237.77377 -88.107403)
			(xy 237.718839 -88.091269) (xy 237.666764 -88.067483) (xy 237.618604 -88.036528) (xy 237.575339 -87.999034)
			(xy 237.537849 -87.955766) (xy 237.506899 -87.907602) (xy 237.483118 -87.855525) (xy 237.466989 -87.800593)
			(xy 237.458842 -87.743925) (xy 235.988191 -87.743925) (xy 235.956911 -87.767869) (xy 235.90504 -87.797752)
			(xy 235.849717 -87.820622) (xy 235.791887 -87.836089) (xy 235.732534 -87.843889) (xy 235.702602 -87.844376)
			(xy 234.839002 -87.844376) (xy 234.809092 -87.843878) (xy 234.749782 -87.83609) (xy 234.69199 -87.820645)
			(xy 234.636701 -87.797808) (xy 234.584857 -87.767965) (xy 234.537339 -87.731627) (xy 234.494957 -87.689411)
			(xy 234.458433 -87.642036) (xy 234.428388 -87.590309) (xy 234.405334 -87.53511) (xy 234.389663 -87.477379)
			(xy 234.381642 -87.4181) (xy 234.38104 -87.388192) (xy 234.38104 -87.384636) (xy 234.381294 -87.382604)
			(xy 234.381294 -87.38235) (xy 234.38078 -87.371892) (xy 234.372376 -87.352737) (xy 234.365038 -87.345266)
			(xy 234.302046 -87.286592) (xy 234.282234 -87.279734) (xy 234.271566 -87.280496) (xy 234.271058 -87.280496)
			(xy 234.238546 -87.28202) (xy 234.238038 -87.28202) (xy 234.204295 -87.281306) (xy 234.137772 -87.269938)
			(xy 234.105704 -87.259414) (xy 234.093512 -87.255096) (xy 234.067604 -87.259414) (xy 233.979466 -87.32901)
			(xy 233.96956 -87.352886) (xy 233.97083 -87.365586) (xy 233.97083 -87.366094) (xy 233.972076 -87.377994)
			(xy 233.973474 -87.401882) (xy 233.973624 -87.413846) (xy 233.973624 -87.414354) (xy 233.973079 -87.446281)
			(xy 233.964156 -87.509508) (xy 233.955844 -87.540338) (xy 233.95373 -87.548843) (xy 233.954734 -87.566324)
			(xy 233.961592 -87.582435) (xy 233.967274 -87.589106) (xy 234.035346 -87.662766) (xy 234.060238 -87.67064)
			(xy 234.073446 -87.6681) (xy 234.092169 -87.664554) (xy 234.130084 -87.660733) (xy 234.149138 -87.66048)
			(xy 234.176386 -87.661019) (xy 234.230327 -87.66878) (xy 234.282614 -87.684138) (xy 234.332183 -87.706781)
			(xy 234.378026 -87.736248) (xy 234.419208 -87.771939) (xy 234.454892 -87.813128) (xy 234.484351 -87.858976)
			(xy 234.506985 -87.908549) (xy 234.522335 -87.960839) (xy 234.530086 -88.014781) (xy 234.530082 -88.069277)
			(xy 234.522322 -88.123218) (xy 234.506965 -88.175506) (xy 234.484323 -88.225076) (xy 234.454857 -88.270919)
			(xy 234.419167 -88.312102) (xy 234.377979 -88.347787) (xy 234.332132 -88.377247) (xy 234.282559 -88.399882)
			(xy 234.230269 -88.415233) (xy 234.176327 -88.422985) (xy 234.121831 -88.422982) (xy 234.06789 -88.415224)
			(xy 234.015602 -88.399868) (xy 233.966032 -88.377227) (xy 233.920188 -88.347762) (xy 233.879004 -88.312073)
			(xy 233.843318 -88.270886) (xy 233.813857 -88.22504) (xy 233.791221 -88.175467) (xy 233.775869 -88.123178)
			(xy 233.768115 -88.069236) (xy 233.76763 -88.041988) (xy 233.76763 -88.041226) (xy 233.767846 -88.023207)
			(xy 233.771283 -87.987332) (xy 233.774488 -87.969598) (xy 233.777028 -87.956644) (xy 233.7689 -87.931498)
			(xy 233.694478 -87.864188) (xy 233.6878 -87.858615) (xy 233.671762 -87.85191) (xy 233.654407 -87.850922)
			(xy 233.645964 -87.853012) (xy 233.614363 -87.861777) (xy 233.549467 -87.87121) (xy 233.516678 -87.871808)
			(xy 232.652062 -87.871808) (xy 232.620958 -87.871344) (xy 232.559322 -87.862926) (xy 232.499395 -87.846237)
			(xy 232.442281 -87.821584) (xy 232.389032 -87.789422) (xy 232.34063 -87.750344) (xy 232.297968 -87.70507)
			(xy 232.261831 -87.654434) (xy 232.232887 -87.59937) (xy 232.221786 -87.57031) (xy 232.221786 -87.570056)
			(xy 232.218162 -87.561359) (xy 232.205688 -87.547256) (xy 232.188946 -87.538644) (xy 232.179622 -87.53729)
			(xy 232.08869 -87.52713) (xy 232.079251 -87.526514) (xy 232.061012 -87.531483) (xy 232.045806 -87.542715)
			(xy 232.04043 -87.550498) (xy 232.025363 -87.57336) (xy 231.989682 -87.614891) (xy 231.948428 -87.650893)
			(xy 231.90245 -87.680625) (xy 231.852693 -87.703476) (xy 231.800179 -87.718977) (xy 231.745989 -87.726809)
			(xy 231.718612 -87.727282) (xy 231.691357 -87.726872) (xy 231.637401 -87.719116) (xy 231.585098 -87.70376)
			(xy 231.535513 -87.681116) (xy 231.489655 -87.651647) (xy 231.448458 -87.615951) (xy 231.412761 -87.574755)
			(xy 231.383289 -87.528898) (xy 231.360644 -87.479313) (xy 231.345287 -87.427011) (xy 231.337529 -87.373055)
			(xy 222.2975 -87.373055) (xy 222.299636 -87.375439) (xy 222.330409 -87.421952) (xy 222.354081 -87.472449)
			(xy 222.370149 -87.525856) (xy 222.378269 -87.581032) (xy 222.378778 -87.608918) (xy 222.378269 -87.636804)
			(xy 222.370149 -87.69198) (xy 222.354081 -87.745387) (xy 222.330409 -87.795884) (xy 222.299636 -87.842397)
			(xy 222.262419 -87.883934) (xy 222.219551 -87.919609) (xy 222.171945 -87.948663) (xy 222.120616 -87.970475)
			(xy 222.066659 -87.984581) (xy 222.011222 -87.990681) (xy 221.955488 -87.988644) (xy 221.900645 -87.978514)
			(xy 221.847861 -87.960507) (xy 221.798261 -87.935006) (xy 221.752903 -87.902555) (xy 221.712754 -87.863846)
			(xy 221.678668 -87.819703) (xy 221.651372 -87.771068) (xy 221.631449 -87.718977) (xy 221.619323 -87.66454)
			(xy 221.615252 -87.608918) (xy 211.067411 -87.608918) (xy 211.070212 -87.628403) (xy 211.070698 -87.655654)
			(xy 211.070264 -87.683532) (xy 211.062147 -87.738695) (xy 211.046081 -87.792086) (xy 211.022407 -87.842567)
			(xy 210.991631 -87.88906) (xy 210.95441 -87.930573) (xy 210.933284 -87.94877) (xy 210.93303 -87.949024)
			(xy 210.925058 -87.956415) (xy 210.915717 -87.976023) (xy 210.914996 -87.98687) (xy 210.913718 -88.060984)
			(xy 224.650049 -88.060984) (xy 224.650049 -88.003688) (xy 224.658203 -87.946974) (xy 224.674346 -87.891999)
			(xy 224.698147 -87.83988) (xy 224.729124 -87.791679) (xy 224.766645 -87.748377) (xy 224.809947 -87.710856)
			(xy 224.858148 -87.679879) (xy 224.910267 -87.656078) (xy 224.965242 -87.639935) (xy 225.021956 -87.631781)
			(xy 225.079252 -87.631781) (xy 225.135966 -87.639935) (xy 225.190941 -87.656078) (xy 225.24306 -87.679879)
			(xy 225.291261 -87.710856) (xy 225.334563 -87.748377) (xy 225.372084 -87.791679) (xy 225.403061 -87.83988)
			(xy 225.426862 -87.891999) (xy 225.443005 -87.946974) (xy 225.451159 -88.003688) (xy 225.45167 -88.032336)
			(xy 225.451159 -88.060984) (xy 225.443005 -88.117698) (xy 225.426862 -88.172673) (xy 225.403061 -88.224792)
			(xy 225.372084 -88.272993) (xy 225.334563 -88.316295) (xy 225.291261 -88.353816) (xy 225.24306 -88.384793)
			(xy 225.190941 -88.408594) (xy 225.135966 -88.424737) (xy 225.079252 -88.432891) (xy 225.021956 -88.432891)
			(xy 224.965242 -88.424737) (xy 224.910267 -88.408594) (xy 224.858148 -88.384793) (xy 224.809947 -88.353816)
			(xy 224.766645 -88.316295) (xy 224.729124 -88.272993) (xy 224.698147 -88.224792) (xy 224.674346 -88.172673)
			(xy 224.658203 -88.117698) (xy 224.650049 -88.060984) (xy 210.913718 -88.060984) (xy 210.913472 -88.075262)
			(xy 210.922108 -88.095074) (xy 210.93049 -88.102694) (xy 210.951076 -88.121784) (xy 210.987256 -88.164713)
			(xy 211.017091 -88.212272) (xy 211.039995 -88.263529) (xy 211.055521 -88.317482) (xy 211.063365 -88.373073)
			(xy 211.06384 -88.401144) (xy 211.063329 -88.429792) (xy 211.055175 -88.486506) (xy 211.039032 -88.541481)
			(xy 211.015231 -88.5936) (xy 210.984254 -88.641801) (xy 210.946733 -88.685103) (xy 210.903431 -88.722624)
			(xy 210.85523 -88.753601) (xy 210.803111 -88.777402) (xy 210.748136 -88.793545) (xy 210.691422 -88.801699)
			(xy 210.634126 -88.801699) (xy 210.577412 -88.793545) (xy 210.522437 -88.777402) (xy 210.470318 -88.753601)
			(xy 210.422117 -88.722624) (xy 210.378815 -88.685103) (xy 210.341294 -88.641801) (xy 210.310317 -88.5936)
			(xy 210.286516 -88.541481) (xy 210.270373 -88.486506) (xy 210.262219 -88.429792) (xy 210.261708 -88.401144)
			(xy 209.328373 -88.401144) (xy 209.328512 -88.408764) (xy 209.328003 -88.43665) (xy 209.319883 -88.491826)
			(xy 209.303815 -88.545233) (xy 209.280143 -88.59573) (xy 209.24937 -88.642243) (xy 209.212153 -88.68378)
			(xy 209.169285 -88.719455) (xy 209.121679 -88.748509) (xy 209.07035 -88.770321) (xy 209.016393 -88.784427)
			(xy 208.960956 -88.790527) (xy 208.905222 -88.78849) (xy 208.850379 -88.77836) (xy 208.797595 -88.760353)
			(xy 208.747995 -88.734852) (xy 208.702637 -88.702401) (xy 208.662488 -88.663692) (xy 208.628402 -88.619549)
			(xy 208.601106 -88.570914) (xy 208.581183 -88.518823) (xy 208.569057 -88.464386) (xy 208.564986 -88.408764)
			(xy 203.518338 -88.408764) (xy 203.517137 -88.411326) (xy 203.486364 -88.457839) (xy 203.449147 -88.499376)
			(xy 203.406279 -88.535051) (xy 203.358673 -88.564105) (xy 203.307344 -88.585917) (xy 203.253387 -88.600023)
			(xy 203.19795 -88.606123) (xy 203.142216 -88.604086) (xy 203.087373 -88.593956) (xy 203.034589 -88.575949)
			(xy 202.984989 -88.550448) (xy 202.939631 -88.517997) (xy 202.899482 -88.479288) (xy 202.865396 -88.435145)
			(xy 202.8381 -88.38651) (xy 202.818177 -88.334419) (xy 202.806051 -88.279982) (xy 202.80198 -88.22436)
			(xy 200.363836 -88.22436) (xy 200.363836 -88.993472) (xy 202.091796 -88.993472) (xy 202.095867 -88.93785)
			(xy 202.107993 -88.883413) (xy 202.127916 -88.831322) (xy 202.155212 -88.782687) (xy 202.189298 -88.738544)
			(xy 202.229447 -88.699835) (xy 202.274805 -88.667384) (xy 202.324405 -88.641883) (xy 202.377189 -88.623876)
			(xy 202.432032 -88.613746) (xy 202.487766 -88.611709) (xy 202.543203 -88.617809) (xy 202.59716 -88.631915)
			(xy 202.648489 -88.653727) (xy 202.696095 -88.682781) (xy 202.738963 -88.718456) (xy 202.77618 -88.759993)
			(xy 202.806953 -88.806506) (xy 202.830625 -88.857003) (xy 202.846693 -88.91041) (xy 202.854813 -88.965586)
			(xy 202.855322 -88.993472) (xy 202.854813 -89.021358) (xy 202.846693 -89.076534) (xy 202.830625 -89.129941)
			(xy 202.806953 -89.180438) (xy 202.805287 -89.182956) (xy 227.930708 -89.182956) (xy 227.934779 -89.127334)
			(xy 227.946905 -89.072897) (xy 227.966828 -89.020806) (xy 227.994124 -88.972171) (xy 228.02821 -88.928028)
			(xy 228.068359 -88.889319) (xy 228.113717 -88.856868) (xy 228.163317 -88.831367) (xy 228.216101 -88.81336)
			(xy 228.270944 -88.80323) (xy 228.326678 -88.801193) (xy 228.382115 -88.807293) (xy 228.436072 -88.821399)
			(xy 228.487401 -88.843211) (xy 228.535007 -88.872265) (xy 228.55582 -88.889586) (xy 234.138976 -88.889586)
			(xy 234.143047 -88.833964) (xy 234.155173 -88.779527) (xy 234.175096 -88.727436) (xy 234.202392 -88.678801)
			(xy 234.236478 -88.634658) (xy 234.276627 -88.595949) (xy 234.321985 -88.563498) (xy 234.371585 -88.537997)
			(xy 234.424369 -88.51999) (xy 234.479212 -88.50986) (xy 234.534946 -88.507823) (xy 234.590383 -88.513923)
			(xy 234.64434 -88.528029) (xy 234.695669 -88.549841) (xy 234.743275 -88.578895) (xy 234.786143 -88.61457)
			(xy 234.82336 -88.656107) (xy 234.854133 -88.70262) (xy 234.877805 -88.753117) (xy 234.883481 -88.771984)
			(xy 250.730256 -88.771984) (xy 250.734327 -88.716362) (xy 250.746453 -88.661925) (xy 250.766376 -88.609834)
			(xy 250.793672 -88.561199) (xy 250.827758 -88.517056) (xy 250.867907 -88.478347) (xy 250.913265 -88.445896)
			(xy 250.962865 -88.420395) (xy 251.015649 -88.402388) (xy 251.070492 -88.392258) (xy 251.126226 -88.390221)
			(xy 251.181663 -88.396321) (xy 251.23562 -88.410427) (xy 251.286949 -88.432239) (xy 251.334555 -88.461293)
			(xy 251.377423 -88.496968) (xy 251.41464 -88.538505) (xy 251.445413 -88.585018) (xy 251.468523 -88.634316)
			(xy 253.724662 -88.634316) (xy 253.728733 -88.578694) (xy 253.740859 -88.524257) (xy 253.760782 -88.472166)
			(xy 253.788078 -88.423531) (xy 253.822164 -88.379388) (xy 253.862313 -88.340679) (xy 253.907671 -88.308228)
			(xy 253.957271 -88.282727) (xy 254.010055 -88.26472) (xy 254.064898 -88.25459) (xy 254.120632 -88.252553)
			(xy 254.176069 -88.258653) (xy 254.230026 -88.272759) (xy 254.281355 -88.294571) (xy 254.328961 -88.323625)
			(xy 254.371829 -88.3593) (xy 254.409046 -88.400837) (xy 254.439819 -88.44735) (xy 254.463491 -88.497847)
			(xy 254.469931 -88.519254) (xy 274.64588 -88.519254) (xy 274.649951 -88.463632) (xy 274.662077 -88.409195)
			(xy 274.682 -88.357104) (xy 274.709296 -88.308469) (xy 274.743382 -88.264326) (xy 274.783531 -88.225617)
			(xy 274.828889 -88.193166) (xy 274.878489 -88.167665) (xy 274.931273 -88.149658) (xy 274.986116 -88.139528)
			(xy 275.04185 -88.137491) (xy 275.097287 -88.143591) (xy 275.151244 -88.157697) (xy 275.202573 -88.179509)
			(xy 275.250179 -88.208563) (xy 275.293047 -88.244238) (xy 275.330264 -88.285775) (xy 275.361037 -88.332288)
			(xy 275.384709 -88.382785) (xy 275.400777 -88.436192) (xy 275.408897 -88.491368) (xy 275.409406 -88.519254)
			(xy 275.408897 -88.54714) (xy 275.400777 -88.602316) (xy 275.384709 -88.655723) (xy 275.361037 -88.70622)
			(xy 275.330264 -88.752733) (xy 275.293047 -88.79427) (xy 275.250179 -88.829945) (xy 275.202573 -88.858999)
			(xy 275.151244 -88.880811) (xy 275.097287 -88.894917) (xy 275.04185 -88.901017) (xy 274.986116 -88.89898)
			(xy 274.931273 -88.88885) (xy 274.878489 -88.870843) (xy 274.828889 -88.845342) (xy 274.783531 -88.812891)
			(xy 274.743382 -88.774182) (xy 274.709296 -88.730039) (xy 274.682 -88.681404) (xy 274.662077 -88.629313)
			(xy 274.649951 -88.574876) (xy 274.64588 -88.519254) (xy 254.469931 -88.519254) (xy 254.479559 -88.551254)
			(xy 254.487679 -88.60643) (xy 254.488188 -88.634316) (xy 254.487679 -88.662202) (xy 254.479559 -88.717378)
			(xy 254.463491 -88.770785) (xy 254.439819 -88.821282) (xy 254.409046 -88.867795) (xy 254.371829 -88.909332)
			(xy 254.328961 -88.945007) (xy 254.281355 -88.974061) (xy 254.230026 -88.995873) (xy 254.176069 -89.009979)
			(xy 254.120632 -89.016079) (xy 254.064898 -89.014042) (xy 254.010055 -89.003912) (xy 253.957271 -88.985905)
			(xy 253.907671 -88.960404) (xy 253.862313 -88.927953) (xy 253.822164 -88.889244) (xy 253.788078 -88.845101)
			(xy 253.760782 -88.796466) (xy 253.740859 -88.744375) (xy 253.728733 -88.689938) (xy 253.724662 -88.634316)
			(xy 251.468523 -88.634316) (xy 251.469085 -88.635515) (xy 251.485153 -88.688922) (xy 251.493273 -88.744098)
			(xy 251.493782 -88.771984) (xy 251.493273 -88.79987) (xy 251.485153 -88.855046) (xy 251.469085 -88.908453)
			(xy 251.445413 -88.95895) (xy 251.41464 -89.005463) (xy 251.377423 -89.047) (xy 251.334555 -89.082675)
			(xy 251.286949 -89.111729) (xy 251.23562 -89.133541) (xy 251.181663 -89.147647) (xy 251.126226 -89.153747)
			(xy 251.070492 -89.15171) (xy 251.015649 -89.14158) (xy 250.962865 -89.123573) (xy 250.913265 -89.098072)
			(xy 250.867907 -89.065621) (xy 250.827758 -89.026912) (xy 250.793672 -88.982769) (xy 250.766376 -88.934134)
			(xy 250.746453 -88.882043) (xy 250.734327 -88.827606) (xy 250.730256 -88.771984) (xy 234.883481 -88.771984)
			(xy 234.893873 -88.806524) (xy 234.901993 -88.8617) (xy 234.902502 -88.889586) (xy 234.901993 -88.917472)
			(xy 234.893873 -88.972648) (xy 234.877805 -89.026055) (xy 234.854133 -89.076552) (xy 234.82336 -89.123065)
			(xy 234.786143 -89.164602) (xy 234.743275 -89.200277) (xy 234.695669 -89.229331) (xy 234.64434 -89.251143)
			(xy 234.590383 -89.265249) (xy 234.534946 -89.271349) (xy 234.479212 -89.269312) (xy 234.424369 -89.259182)
			(xy 234.371585 -89.241175) (xy 234.321985 -89.215674) (xy 234.276627 -89.183223) (xy 234.236478 -89.144514)
			(xy 234.202392 -89.100371) (xy 234.175096 -89.051736) (xy 234.155173 -88.999645) (xy 234.143047 -88.945208)
			(xy 234.138976 -88.889586) (xy 228.55582 -88.889586) (xy 228.577875 -88.90794) (xy 228.615092 -88.949477)
			(xy 228.645865 -88.99599) (xy 228.669537 -89.046487) (xy 228.685605 -89.099894) (xy 228.693725 -89.15507)
			(xy 228.694234 -89.182956) (xy 228.693725 -89.210842) (xy 228.685605 -89.266018) (xy 228.669537 -89.319425)
			(xy 228.645865 -89.369922) (xy 228.615092 -89.416435) (xy 228.577875 -89.457972) (xy 228.535007 -89.493647)
			(xy 228.487401 -89.522701) (xy 228.436072 -89.544513) (xy 228.382115 -89.558619) (xy 228.326678 -89.564719)
			(xy 228.270944 -89.562682) (xy 228.216101 -89.552552) (xy 228.163317 -89.534545) (xy 228.113717 -89.509044)
			(xy 228.068359 -89.476593) (xy 228.02821 -89.437884) (xy 227.994124 -89.393741) (xy 227.966828 -89.345106)
			(xy 227.946905 -89.293015) (xy 227.934779 -89.238578) (xy 227.930708 -89.182956) (xy 202.805287 -89.182956)
			(xy 202.77618 -89.226951) (xy 202.738963 -89.268488) (xy 202.696095 -89.304163) (xy 202.648489 -89.333217)
			(xy 202.59716 -89.355029) (xy 202.543203 -89.369135) (xy 202.487766 -89.375235) (xy 202.432032 -89.373198)
			(xy 202.377189 -89.363068) (xy 202.324405 -89.345061) (xy 202.274805 -89.31956) (xy 202.229447 -89.287109)
			(xy 202.189298 -89.2484) (xy 202.155212 -89.204257) (xy 202.127916 -89.155622) (xy 202.107993 -89.103531)
			(xy 202.095867 -89.049094) (xy 202.091796 -88.993472) (xy 200.363836 -88.993472) (xy 200.363836 -90.009726)
			(xy 227.35235 -90.009726) (xy 227.356421 -89.954104) (xy 227.368547 -89.899667) (xy 227.38847 -89.847576)
			(xy 227.415766 -89.798941) (xy 227.449852 -89.754798) (xy 227.490001 -89.716089) (xy 227.535359 -89.683638)
			(xy 227.584959 -89.658137) (xy 227.637743 -89.64013) (xy 227.692586 -89.63) (xy 227.74832 -89.627963)
			(xy 227.803757 -89.634063) (xy 227.857714 -89.648169) (xy 227.909043 -89.669981) (xy 227.956649 -89.699035)
			(xy 227.999517 -89.73471) (xy 228.036734 -89.776247) (xy 228.050549 -89.797128) (xy 230.768142 -89.797128)
			(xy 230.772213 -89.741506) (xy 230.784339 -89.687069) (xy 230.804262 -89.634978) (xy 230.831558 -89.586343)
			(xy 230.865644 -89.5422) (xy 230.905793 -89.503491) (xy 230.951151 -89.47104) (xy 231.000751 -89.445539)
			(xy 231.053535 -89.427532) (xy 231.108378 -89.417402) (xy 231.164112 -89.415365) (xy 231.219549 -89.421465)
			(xy 231.273506 -89.435571) (xy 231.324835 -89.457383) (xy 231.372441 -89.486437) (xy 231.415309 -89.522112)
			(xy 231.452526 -89.563649) (xy 231.483299 -89.610162) (xy 231.506971 -89.660659) (xy 231.523039 -89.714066)
			(xy 231.531159 -89.769242) (xy 231.531668 -89.797128) (xy 231.531159 -89.825014) (xy 231.523039 -89.88019)
			(xy 231.506971 -89.933597) (xy 231.483299 -89.984094) (xy 231.452526 -90.030607) (xy 231.415309 -90.072144)
			(xy 231.372441 -90.107819) (xy 231.324835 -90.136873) (xy 231.273506 -90.158685) (xy 231.219549 -90.172791)
			(xy 231.164112 -90.178891) (xy 231.108378 -90.176854) (xy 231.053535 -90.166724) (xy 231.000751 -90.148717)
			(xy 230.951151 -90.123216) (xy 230.905793 -90.090765) (xy 230.865644 -90.052056) (xy 230.831558 -90.007913)
			(xy 230.804262 -89.959278) (xy 230.784339 -89.907187) (xy 230.772213 -89.85275) (xy 230.768142 -89.797128)
			(xy 228.050549 -89.797128) (xy 228.067507 -89.82276) (xy 228.091179 -89.873257) (xy 228.107247 -89.926664)
			(xy 228.115367 -89.98184) (xy 228.115876 -90.009726) (xy 228.115367 -90.037612) (xy 228.107247 -90.092788)
			(xy 228.091179 -90.146195) (xy 228.067507 -90.196692) (xy 228.036734 -90.243205) (xy 228.018328 -90.263747)
			(xy 229.611726 -90.263747) (xy 229.611726 -90.209253) (xy 229.619481 -90.155314) (xy 229.634833 -90.103027)
			(xy 229.65747 -90.053457) (xy 229.686931 -90.007614) (xy 229.722616 -89.966429) (xy 229.763799 -89.930742)
			(xy 229.809642 -89.901279) (xy 229.85921 -89.87864) (xy 229.911496 -89.863285) (xy 229.965435 -89.855527)
			(xy 229.992682 -89.85504) (xy 230.019221 -89.85549) (xy 230.071788 -89.862832) (xy 230.122829 -89.877391)
			(xy 230.171359 -89.898886) (xy 230.216441 -89.926901) (xy 230.257203 -89.960896) (xy 230.292859 -90.000214)
			(xy 230.322719 -90.044095) (xy 230.346208 -90.091692) (xy 230.362871 -90.142085) (xy 230.372386 -90.194303)
			(xy 230.373461 -90.212672) (xy 236.886494 -90.212672) (xy 236.890565 -90.15705) (xy 236.902691 -90.102613)
			(xy 236.922614 -90.050522) (xy 236.94991 -90.001887) (xy 236.983996 -89.957744) (xy 237.024145 -89.919035)
			(xy 237.069503 -89.886584) (xy 237.119103 -89.861083) (xy 237.171887 -89.843076) (xy 237.22673 -89.832946)
			(xy 237.282464 -89.830909) (xy 237.337901 -89.837009) (xy 237.391858 -89.851115) (xy 237.443187 -89.872927)
			(xy 237.490793 -89.901981) (xy 237.533661 -89.937656) (xy 237.570878 -89.979193) (xy 237.601651 -90.025706)
			(xy 237.625323 -90.076203) (xy 237.641391 -90.12961) (xy 237.649511 -90.184786) (xy 237.65002 -90.212672)
			(xy 237.649511 -90.240558) (xy 237.641391 -90.295734) (xy 237.625323 -90.349141) (xy 237.601651 -90.399638)
			(xy 237.570878 -90.446151) (xy 237.533661 -90.487688) (xy 237.490793 -90.523363) (xy 237.443187 -90.552417)
			(xy 237.391858 -90.574229) (xy 237.337901 -90.588335) (xy 237.282464 -90.594435) (xy 237.22673 -90.592398)
			(xy 237.171887 -90.582268) (xy 237.119103 -90.564261) (xy 237.069503 -90.53876) (xy 237.024145 -90.506309)
			(xy 236.983996 -90.4676) (xy 236.94991 -90.423457) (xy 236.922614 -90.374822) (xy 236.902691 -90.322731)
			(xy 236.890565 -90.268294) (xy 236.886494 -90.212672) (xy 230.373461 -90.212672) (xy 230.373936 -90.2208)
			(xy 230.374664 -90.230031) (xy 230.38189 -90.247067) (xy 230.394703 -90.260417) (xy 230.402892 -90.264742)
			(xy 230.483918 -90.303096) (xy 230.492374 -90.30672) (xy 230.510698 -90.308241) (xy 230.528377 -90.303188)
			(xy 230.535988 -90.298016) (xy 230.536242 -90.298016) (xy 230.561108 -90.28021) (xy 230.615337 -90.251937)
			(xy 230.673382 -90.232678) (xy 230.733756 -90.222926) (xy 230.764334 -90.222324) (xy 230.791588 -90.222746)
			(xy 230.845539 -90.230508) (xy 230.897837 -90.245869) (xy 230.947417 -90.268517) (xy 230.993268 -90.29799)
			(xy 231.034459 -90.333688) (xy 231.07015 -90.374885) (xy 231.099615 -90.420741) (xy 231.122254 -90.470325)
			(xy 231.137606 -90.522625) (xy 231.145358 -90.576578) (xy 231.145842 -90.603832) (xy 231.145409 -90.631204)
			(xy 231.137585 -90.685385) (xy 231.122089 -90.737889) (xy 231.118447 -90.745818) (xy 232.128312 -90.745818)
			(xy 232.132383 -90.690196) (xy 232.144509 -90.635759) (xy 232.164432 -90.583668) (xy 232.191728 -90.535033)
			(xy 232.225814 -90.49089) (xy 232.265963 -90.452181) (xy 232.311321 -90.41973) (xy 232.360921 -90.394229)
			(xy 232.413705 -90.376222) (xy 232.468548 -90.366092) (xy 232.524282 -90.364055) (xy 232.579719 -90.370155)
			(xy 232.633676 -90.384261) (xy 232.685005 -90.406073) (xy 232.732611 -90.435127) (xy 232.775479 -90.470802)
			(xy 232.812696 -90.512339) (xy 232.843469 -90.558852) (xy 232.867141 -90.609349) (xy 232.883209 -90.662756)
			(xy 232.891329 -90.717932) (xy 232.891838 -90.745818) (xy 233.650788 -90.745818) (xy 233.654859 -90.690196)
			(xy 233.666985 -90.635759) (xy 233.686908 -90.583668) (xy 233.714204 -90.535033) (xy 233.74829 -90.49089)
			(xy 233.788439 -90.452181) (xy 233.833797 -90.41973) (xy 233.883397 -90.394229) (xy 233.936181 -90.376222)
			(xy 233.991024 -90.366092) (xy 234.046758 -90.364055) (xy 234.102195 -90.370155) (xy 234.156152 -90.384261)
			(xy 234.207481 -90.406073) (xy 234.255087 -90.435127) (xy 234.297955 -90.470802) (xy 234.335172 -90.512339)
			(xy 234.365945 -90.558852) (xy 234.389617 -90.609349) (xy 234.405685 -90.662756) (xy 234.413805 -90.717932)
			(xy 234.414314 -90.745818) (xy 235.154468 -90.745818) (xy 235.158539 -90.690196) (xy 235.170665 -90.635759)
			(xy 235.190588 -90.583668) (xy 235.217884 -90.535033) (xy 235.25197 -90.49089) (xy 235.292119 -90.452181)
			(xy 235.337477 -90.41973) (xy 235.387077 -90.394229) (xy 235.439861 -90.376222) (xy 235.494704 -90.366092)
			(xy 235.550438 -90.364055) (xy 235.605875 -90.370155) (xy 235.659832 -90.384261) (xy 235.711161 -90.406073)
			(xy 235.758767 -90.435127) (xy 235.801635 -90.470802) (xy 235.838852 -90.512339) (xy 235.869625 -90.558852)
			(xy 235.893297 -90.609349) (xy 235.909365 -90.662756) (xy 235.917485 -90.717932) (xy 235.917994 -90.745818)
			(xy 235.917485 -90.773704) (xy 235.909365 -90.82888) (xy 235.893297 -90.882287) (xy 235.869625 -90.932784)
			(xy 235.838852 -90.979297) (xy 235.801635 -91.020834) (xy 235.758767 -91.056509) (xy 235.711161 -91.085563)
			(xy 235.703139 -91.088972) (xy 236.971838 -91.088972) (xy 236.975909 -91.03335) (xy 236.988035 -90.978913)
			(xy 237.007958 -90.926822) (xy 237.035254 -90.878187) (xy 237.06934 -90.834044) (xy 237.109489 -90.795335)
			(xy 237.154847 -90.762884) (xy 237.204447 -90.737383) (xy 237.257231 -90.719376) (xy 237.312074 -90.709246)
			(xy 237.367808 -90.707209) (xy 237.423245 -90.713309) (xy 237.477202 -90.727415) (xy 237.528531 -90.749227)
			(xy 237.576137 -90.778281) (xy 237.619005 -90.813956) (xy 237.656222 -90.855493) (xy 237.686995 -90.902006)
			(xy 237.710667 -90.952503) (xy 237.726735 -91.00591) (xy 237.734855 -91.061086) (xy 237.735364 -91.088972)
			(xy 237.734855 -91.116858) (xy 237.726735 -91.172034) (xy 237.710667 -91.225441) (xy 237.686995 -91.275938)
			(xy 237.656222 -91.322451) (xy 237.619005 -91.363988) (xy 237.576137 -91.399663) (xy 237.528531 -91.428717)
			(xy 237.477202 -91.450529) (xy 237.423245 -91.464635) (xy 237.367808 -91.470735) (xy 237.312074 -91.468698)
			(xy 237.257231 -91.458568) (xy 237.204447 -91.440561) (xy 237.154847 -91.41506) (xy 237.109489 -91.382609)
			(xy 237.06934 -91.3439) (xy 237.035254 -91.299757) (xy 237.007958 -91.251122) (xy 236.988035 -91.199031)
			(xy 236.975909 -91.144594) (xy 236.971838 -91.088972) (xy 235.703139 -91.088972) (xy 235.659832 -91.107375)
			(xy 235.605875 -91.121481) (xy 235.550438 -91.127581) (xy 235.494704 -91.125544) (xy 235.439861 -91.115414)
			(xy 235.387077 -91.097407) (xy 235.337477 -91.071906) (xy 235.292119 -91.039455) (xy 235.25197 -91.000746)
			(xy 235.217884 -90.956603) (xy 235.190588 -90.907968) (xy 235.170665 -90.855877) (xy 235.158539 -90.80144)
			(xy 235.154468 -90.745818) (xy 234.414314 -90.745818) (xy 234.413805 -90.773704) (xy 234.405685 -90.82888)
			(xy 234.389617 -90.882287) (xy 234.365945 -90.932784) (xy 234.335172 -90.979297) (xy 234.297955 -91.020834)
			(xy 234.255087 -91.056509) (xy 234.207481 -91.085563) (xy 234.156152 -91.107375) (xy 234.102195 -91.121481)
			(xy 234.046758 -91.127581) (xy 233.991024 -91.125544) (xy 233.936181 -91.115414) (xy 233.883397 -91.097407)
			(xy 233.833797 -91.071906) (xy 233.788439 -91.039455) (xy 233.74829 -91.000746) (xy 233.714204 -90.956603)
			(xy 233.686908 -90.907968) (xy 233.666985 -90.855877) (xy 233.654859 -90.80144) (xy 233.650788 -90.745818)
			(xy 232.891838 -90.745818) (xy 232.891329 -90.773704) (xy 232.883209 -90.82888) (xy 232.867141 -90.882287)
			(xy 232.843469 -90.932784) (xy 232.812696 -90.979297) (xy 232.775479 -91.020834) (xy 232.732611 -91.056509)
			(xy 232.685005 -91.085563) (xy 232.633676 -91.107375) (xy 232.579719 -91.121481) (xy 232.524282 -91.127581)
			(xy 232.468548 -91.125544) (xy 232.413705 -91.115414) (xy 232.360921 -91.097407) (xy 232.311321 -91.071906)
			(xy 232.265963 -91.039455) (xy 232.225814 -91.000746) (xy 232.191728 -90.956603) (xy 232.164432 -90.907968)
			(xy 232.144509 -90.855877) (xy 232.132383 -90.80144) (xy 232.128312 -90.745818) (xy 231.118447 -90.745818)
			(xy 231.09924 -90.787635) (xy 231.069507 -90.8336) (xy 231.051862 -90.85453) (xy 231.045818 -90.862034)
			(xy 231.039432 -90.880199) (xy 231.039416 -90.889836) (xy 231.042718 -90.969592) (xy 231.050592 -90.986864)
			(xy 231.05745 -90.993722) (xy 231.07528 -91.011731) (xy 231.106509 -91.051642) (xy 231.132179 -91.095337)
			(xy 231.151837 -91.142047) (xy 231.165137 -91.190948) (xy 231.171845 -91.241179) (xy 231.172258 -91.266518)
			(xy 231.171772 -91.293769) (xy 231.164016 -91.347717) (xy 231.148661 -91.400012) (xy 231.126019 -91.449589)
			(xy 231.096553 -91.495439) (xy 231.060862 -91.53663) (xy 231.019671 -91.572321) (xy 230.973821 -91.601787)
			(xy 230.924244 -91.624429) (xy 230.871949 -91.639784) (xy 230.818001 -91.64754) (xy 230.763499 -91.64754)
			(xy 230.709551 -91.639784) (xy 230.657256 -91.624429) (xy 230.607679 -91.601787) (xy 230.561829 -91.572321)
			(xy 230.520638 -91.53663) (xy 230.484947 -91.495439) (xy 230.455481 -91.449589) (xy 230.432839 -91.400012)
			(xy 230.417484 -91.347717) (xy 230.409728 -91.293769) (xy 230.409242 -91.266518) (xy 230.409708 -91.239148)
			(xy 230.417525 -91.184968) (xy 230.433013 -91.132465) (xy 230.455855 -91.082718) (xy 230.48558 -91.036751)
			(xy 230.503222 -91.01582) (xy 230.509242 -91.008299) (xy 230.515643 -90.990147) (xy 230.515668 -90.980514)
			(xy 230.512366 -90.900758) (xy 230.504492 -90.883486) (xy 230.497634 -90.876628) (xy 230.47735 -90.85612)
			(xy 230.442623 -90.810066) (xy 230.415233 -90.759303) (xy 230.395808 -90.704992) (xy 230.38479 -90.648374)
			(xy 230.38308 -90.61958) (xy 230.382357 -90.610348) (xy 230.375127 -90.593314) (xy 230.362313 -90.579964)
			(xy 230.354124 -90.575638) (xy 230.273098 -90.537284) (xy 230.264636 -90.533676) (xy 230.246316 -90.532151)
			(xy 230.228639 -90.537197) (xy 230.221028 -90.542364) (xy 230.220774 -90.542364) (xy 230.19591 -90.560173)
			(xy 230.14168 -90.588443) (xy 230.083634 -90.607701) (xy 230.02326 -90.617453) (xy 229.992682 -90.618056)
			(xy 229.965435 -90.617473) (xy 229.911496 -90.609715) (xy 229.85921 -90.59436) (xy 229.809642 -90.571721)
			(xy 229.763799 -90.542258) (xy 229.722616 -90.506571) (xy 229.686931 -90.465386) (xy 229.65747 -90.419543)
			(xy 229.634833 -90.369973) (xy 229.619481 -90.317686) (xy 229.611726 -90.263747) (xy 228.018328 -90.263747)
			(xy 227.999517 -90.284742) (xy 227.956649 -90.320417) (xy 227.909043 -90.349471) (xy 227.857714 -90.371283)
			(xy 227.803757 -90.385389) (xy 227.74832 -90.391489) (xy 227.692586 -90.389452) (xy 227.637743 -90.379322)
			(xy 227.584959 -90.361315) (xy 227.535359 -90.335814) (xy 227.490001 -90.303363) (xy 227.449852 -90.264654)
			(xy 227.415766 -90.220511) (xy 227.38847 -90.171876) (xy 227.368547 -90.119785) (xy 227.356421 -90.065348)
			(xy 227.35235 -90.009726) (xy 200.363836 -90.009726) (xy 200.363836 -90.6653) (xy 201.661012 -90.6653)
			(xy 201.665083 -90.609678) (xy 201.677209 -90.555241) (xy 201.697132 -90.50315) (xy 201.724428 -90.454515)
			(xy 201.758514 -90.410372) (xy 201.798663 -90.371663) (xy 201.844021 -90.339212) (xy 201.893621 -90.313711)
			(xy 201.946405 -90.295704) (xy 202.001248 -90.285574) (xy 202.056982 -90.283537) (xy 202.112419 -90.289637)
			(xy 202.166376 -90.303743) (xy 202.217705 -90.325555) (xy 202.265311 -90.354609) (xy 202.308179 -90.390284)
			(xy 202.345396 -90.431821) (xy 202.369126 -90.467688) (xy 214.358472 -90.467688) (xy 214.362543 -90.412066)
			(xy 214.374669 -90.357629) (xy 214.394592 -90.305538) (xy 214.421888 -90.256903) (xy 214.455974 -90.21276)
			(xy 214.496123 -90.174051) (xy 214.541481 -90.1416) (xy 214.591081 -90.116099) (xy 214.643865 -90.098092)
			(xy 214.698708 -90.087962) (xy 214.754442 -90.085925) (xy 214.809879 -90.092025) (xy 214.863836 -90.106131)
			(xy 214.915165 -90.127943) (xy 214.962771 -90.156997) (xy 215.005639 -90.192672) (xy 215.042856 -90.234209)
			(xy 215.073629 -90.280722) (xy 215.097301 -90.331219) (xy 215.113369 -90.384626) (xy 215.121489 -90.439802)
			(xy 215.121998 -90.467688) (xy 215.121489 -90.495574) (xy 215.113369 -90.55075) (xy 215.097301 -90.604157)
			(xy 215.084222 -90.632057) (xy 216.171429 -90.632057) (xy 216.171429 -90.577545) (xy 216.179187 -90.523589)
			(xy 216.194545 -90.471285) (xy 216.217191 -90.4217) (xy 216.246663 -90.375842) (xy 216.282362 -90.334646)
			(xy 216.32356 -90.29895) (xy 216.369419 -90.26948) (xy 216.419006 -90.246837) (xy 216.47131 -90.231482)
			(xy 216.525267 -90.223727) (xy 216.579779 -90.223731) (xy 216.633736 -90.231492) (xy 216.686038 -90.246854)
			(xy 216.735622 -90.269503) (xy 216.781478 -90.298978) (xy 216.822672 -90.334679) (xy 216.858365 -90.37588)
			(xy 216.887832 -90.421741) (xy 216.910471 -90.471329) (xy 216.925823 -90.523634) (xy 216.933574 -90.577592)
			(xy 216.934034 -90.604848) (xy 216.933626 -90.630207) (xy 216.926894 -90.680477) (xy 216.913543 -90.729406)
			(xy 216.904062 -90.75293) (xy 216.902284 -90.757756) (xy 216.899453 -90.768451) (xy 216.902405 -90.790362)
			(xy 216.914285 -90.809008) (xy 216.932895 -90.820943) (xy 216.954797 -90.82396) (xy 216.96553 -90.821256)
			(xy 216.976436 -90.818078) (xy 216.998549 -90.812868) (xy 217.009726 -90.810842) (xy 217.020832 -90.808362)
			(xy 217.039428 -90.795296) (xy 217.04554 -90.785696) (xy 217.089736 -90.706956) (xy 217.09126 -90.684096)
			(xy 217.086942 -90.673174) (xy 217.078412 -90.650706) (xy 217.066422 -90.604166) (xy 217.060381 -90.556488)
			(xy 217.060018 -90.532458) (xy 217.060018 -90.532204) (xy 217.060504 -90.504953) (xy 217.06826 -90.451005)
			(xy 217.083615 -90.39871) (xy 217.106257 -90.349133) (xy 217.135723 -90.303283) (xy 217.171414 -90.262092)
			(xy 217.212605 -90.226401) (xy 217.258455 -90.196935) (xy 217.308032 -90.174293) (xy 217.360327 -90.158938)
			(xy 217.414275 -90.151182) (xy 217.468777 -90.151182) (xy 217.522725 -90.158938) (xy 217.57502 -90.174293)
			(xy 217.624597 -90.196935) (xy 217.670447 -90.226401) (xy 217.711638 -90.262092) (xy 217.747329 -90.303283)
			(xy 217.776795 -90.349133) (xy 217.799437 -90.39871) (xy 217.814792 -90.451005) (xy 217.822548 -90.504953)
			(xy 217.823034 -90.532204) (xy 217.822616 -90.558954) (xy 217.81512 -90.611926) (xy 217.800305 -90.663333)
			(xy 217.778459 -90.712169) (xy 217.750011 -90.757478) (xy 217.715517 -90.798373) (xy 217.675653 -90.834053)
			(xy 217.6312 -90.86382) (xy 217.583026 -90.887091) (xy 217.532076 -90.903411) (xy 217.505788 -90.908378)
			(xy 217.494694 -90.910897) (xy 217.476096 -90.923938) (xy 217.469974 -90.933524) (xy 217.425778 -91.012264)
			(xy 217.424254 -91.035124) (xy 217.428572 -91.046046) (xy 217.437108 -91.068512) (xy 217.449096 -91.115053)
			(xy 217.455134 -91.162732) (xy 217.455496 -91.186762) (xy 217.455496 -91.187016) (xy 217.45501 -91.214267)
			(xy 217.447254 -91.268215) (xy 217.431899 -91.32051) (xy 217.409257 -91.370087) (xy 217.379791 -91.415937)
			(xy 217.367304 -91.430348) (xy 221.146624 -91.430348) (xy 221.147191 -91.401388) (xy 221.155962 -91.344135)
			(xy 221.173278 -91.288863) (xy 221.198743 -91.236841) (xy 221.231772 -91.18926) (xy 221.271609 -91.147214)
			(xy 221.317338 -91.111667) (xy 221.367912 -91.083433) (xy 221.422169 -91.063161) (xy 221.450408 -91.056714)
			(xy 221.459633 -91.054345) (xy 221.475554 -91.043916) (xy 221.481396 -91.036394) (xy 221.52737 -90.972386)
			(xy 221.531942 -90.953844) (xy 221.530672 -90.944446) (xy 221.530672 -90.943938) (xy 221.529053 -90.931108)
			(xy 221.527276 -90.905307) (xy 221.527116 -90.892376) (xy 221.527627 -90.863728) (xy 221.535781 -90.807014)
			(xy 221.551924 -90.752039) (xy 221.575725 -90.69992) (xy 221.606702 -90.651719) (xy 221.644223 -90.608417)
			(xy 221.687525 -90.570896) (xy 221.735726 -90.539919) (xy 221.787845 -90.516118) (xy 221.84282 -90.499975)
			(xy 221.899534 -90.491821) (xy 221.95683 -90.491821) (xy 222.013544 -90.499975) (xy 222.068519 -90.516118)
			(xy 222.120638 -90.539919) (xy 222.168839 -90.570896) (xy 222.212141 -90.608417) (xy 222.249662 -90.651719)
			(xy 222.280639 -90.69992) (xy 222.302643 -90.748104) (xy 224.04019 -90.748104) (xy 224.044261 -90.692482)
			(xy 224.056387 -90.638045) (xy 224.07631 -90.585954) (xy 224.103606 -90.537319) (xy 224.137692 -90.493176)
			(xy 224.177841 -90.454467) (xy 224.223199 -90.422016) (xy 224.272799 -90.396515) (xy 224.325583 -90.378508)
			(xy 224.380426 -90.368378) (xy 224.43616 -90.366341) (xy 224.491597 -90.372441) (xy 224.545554 -90.386547)
			(xy 224.596883 -90.408359) (xy 224.644489 -90.437413) (xy 224.687357 -90.473088) (xy 224.724574 -90.514625)
			(xy 224.755347 -90.561138) (xy 224.779019 -90.611635) (xy 224.795087 -90.665042) (xy 224.803207 -90.720218)
			(xy 224.803716 -90.748104) (xy 224.803271 -90.772488) (xy 225.37623 -90.772488) (xy 225.380301 -90.716866)
			(xy 225.392427 -90.662429) (xy 225.41235 -90.610338) (xy 225.439646 -90.561703) (xy 225.473732 -90.51756)
			(xy 225.513881 -90.478851) (xy 225.559239 -90.4464) (xy 225.608839 -90.420899) (xy 225.661623 -90.402892)
			(xy 225.716466 -90.392762) (xy 225.7722 -90.390725) (xy 225.827637 -90.396825) (xy 225.881594 -90.410931)
			(xy 225.932923 -90.432743) (xy 225.980529 -90.461797) (xy 226.023397 -90.497472) (xy 226.060614 -90.539009)
			(xy 226.091387 -90.585522) (xy 226.115059 -90.636019) (xy 226.131127 -90.689426) (xy 226.139247 -90.744602)
			(xy 226.139756 -90.772488) (xy 226.139247 -90.800374) (xy 226.131127 -90.85555) (xy 226.115059 -90.908957)
			(xy 226.091387 -90.959454) (xy 226.060614 -91.005967) (xy 226.04291 -91.025726) (xy 227.35235 -91.025726)
			(xy 227.356421 -90.970104) (xy 227.368547 -90.915667) (xy 227.38847 -90.863576) (xy 227.415766 -90.814941)
			(xy 227.449852 -90.770798) (xy 227.490001 -90.732089) (xy 227.535359 -90.699638) (xy 227.584959 -90.674137)
			(xy 227.637743 -90.65613) (xy 227.692586 -90.646) (xy 227.74832 -90.643963) (xy 227.803757 -90.650063)
			(xy 227.857714 -90.664169) (xy 227.909043 -90.685981) (xy 227.956649 -90.715035) (xy 227.999517 -90.75071)
			(xy 228.036734 -90.792247) (xy 228.067507 -90.83876) (xy 228.091179 -90.889257) (xy 228.107247 -90.942664)
			(xy 228.115367 -90.99784) (xy 228.115876 -91.025726) (xy 228.115367 -91.053612) (xy 228.107247 -91.108788)
			(xy 228.091179 -91.162195) (xy 228.067507 -91.212692) (xy 228.036734 -91.259205) (xy 227.999517 -91.300742)
			(xy 227.956649 -91.336417) (xy 227.909043 -91.365471) (xy 227.857714 -91.387283) (xy 227.803757 -91.401389)
			(xy 227.74832 -91.407489) (xy 227.692586 -91.405452) (xy 227.637743 -91.395322) (xy 227.584959 -91.377315)
			(xy 227.535359 -91.351814) (xy 227.490001 -91.319363) (xy 227.449852 -91.280654) (xy 227.415766 -91.236511)
			(xy 227.38847 -91.187876) (xy 227.368547 -91.135785) (xy 227.356421 -91.081348) (xy 227.35235 -91.025726)
			(xy 226.04291 -91.025726) (xy 226.023397 -91.047504) (xy 225.980529 -91.083179) (xy 225.932923 -91.112233)
			(xy 225.881594 -91.134045) (xy 225.827637 -91.148151) (xy 225.7722 -91.154251) (xy 225.716466 -91.152214)
			(xy 225.661623 -91.142084) (xy 225.608839 -91.124077) (xy 225.559239 -91.098576) (xy 225.513881 -91.066125)
			(xy 225.473732 -91.027416) (xy 225.439646 -90.983273) (xy 225.41235 -90.934638) (xy 225.392427 -90.882547)
			(xy 225.380301 -90.82811) (xy 225.37623 -90.772488) (xy 224.803271 -90.772488) (xy 224.803207 -90.77599)
			(xy 224.795087 -90.831166) (xy 224.779019 -90.884573) (xy 224.755347 -90.93507) (xy 224.724574 -90.981583)
			(xy 224.687357 -91.02312) (xy 224.644489 -91.058795) (xy 224.596883 -91.087849) (xy 224.545554 -91.109661)
			(xy 224.491597 -91.123767) (xy 224.43616 -91.129867) (xy 224.380426 -91.12783) (xy 224.325583 -91.1177)
			(xy 224.272799 -91.099693) (xy 224.223199 -91.074192) (xy 224.177841 -91.041741) (xy 224.137692 -91.003032)
			(xy 224.103606 -90.958889) (xy 224.07631 -90.910254) (xy 224.056387 -90.858163) (xy 224.044261 -90.803726)
			(xy 224.04019 -90.748104) (xy 222.302643 -90.748104) (xy 222.30444 -90.752039) (xy 222.320583 -90.807014)
			(xy 222.328737 -90.863728) (xy 222.329248 -90.892376) (xy 222.328789 -90.920632) (xy 222.320834 -90.976581)
			(xy 222.305106 -91.03086) (xy 222.281917 -91.082395) (xy 222.251724 -91.130166) (xy 222.215127 -91.173227)
			(xy 222.172849 -91.210725) (xy 222.125727 -91.24192) (xy 222.074693 -91.266193) (xy 222.020758 -91.283064)
			(xy 221.992952 -91.288108) (xy 221.983808 -91.289632) (xy 221.967044 -91.299284) (xy 221.912688 -91.369134)
			(xy 221.907354 -91.387422) (xy 221.908116 -91.397074) (xy 221.90964 -91.430348) (xy 221.909154 -91.457599)
			(xy 221.901398 -91.511547) (xy 221.886043 -91.563842) (xy 221.863401 -91.613419) (xy 221.833935 -91.659269)
			(xy 221.798244 -91.70046) (xy 221.757053 -91.736151) (xy 221.711203 -91.765617) (xy 221.661626 -91.788259)
			(xy 221.609331 -91.803614) (xy 221.555383 -91.81137) (xy 221.500881 -91.81137) (xy 221.446933 -91.803614)
			(xy 221.394638 -91.788259) (xy 221.345061 -91.765617) (xy 221.299211 -91.736151) (xy 221.25802 -91.70046)
			(xy 221.222329 -91.659269) (xy 221.192863 -91.613419) (xy 221.170221 -91.563842) (xy 221.154866 -91.511547)
			(xy 221.14711 -91.457599) (xy 221.146624 -91.430348) (xy 217.367304 -91.430348) (xy 217.3441 -91.457128)
			(xy 217.302909 -91.492819) (xy 217.257059 -91.522285) (xy 217.207482 -91.544927) (xy 217.155187 -91.560282)
			(xy 217.101239 -91.568038) (xy 217.046737 -91.568038) (xy 216.992789 -91.560282) (xy 216.940494 -91.544927)
			(xy 216.890917 -91.522285) (xy 216.845067 -91.492819) (xy 216.803876 -91.457128) (xy 216.768185 -91.415937)
			(xy 216.738719 -91.370087) (xy 216.716077 -91.32051) (xy 216.700722 -91.268215) (xy 216.692966 -91.214267)
			(xy 216.69248 -91.187016) (xy 216.692758 -91.166791) (xy 216.69709 -91.126574) (xy 216.701116 -91.106752)
			(xy 216.703656 -91.094814) (xy 216.69756 -91.0717) (xy 216.625932 -90.99169) (xy 216.60358 -90.983054)
			(xy 216.591388 -90.984324) (xy 216.552526 -90.986356) (xy 216.52527 -90.985873) (xy 216.471313 -90.978118)
			(xy 216.419008 -90.962764) (xy 216.369422 -90.940121) (xy 216.323562 -90.910652) (xy 216.282363 -90.874956)
			(xy 216.246664 -90.83376) (xy 216.217192 -90.787903) (xy 216.194546 -90.738317) (xy 216.179187 -90.686014)
			(xy 216.171429 -90.632057) (xy 215.084222 -90.632057) (xy 215.073629 -90.654654) (xy 215.042856 -90.701167)
			(xy 215.005639 -90.742704) (xy 214.962771 -90.778379) (xy 214.915165 -90.807433) (xy 214.863836 -90.829245)
			(xy 214.809879 -90.843351) (xy 214.754442 -90.849451) (xy 214.698708 -90.847414) (xy 214.643865 -90.837284)
			(xy 214.591081 -90.819277) (xy 214.541481 -90.793776) (xy 214.496123 -90.761325) (xy 214.455974 -90.722616)
			(xy 214.421888 -90.678473) (xy 214.394592 -90.629838) (xy 214.374669 -90.577747) (xy 214.362543 -90.52331)
			(xy 214.358472 -90.467688) (xy 202.369126 -90.467688) (xy 202.376169 -90.478334) (xy 202.399841 -90.528831)
			(xy 202.415909 -90.582238) (xy 202.424029 -90.637414) (xy 202.424538 -90.6653) (xy 202.424029 -90.693186)
			(xy 202.415909 -90.748362) (xy 202.399841 -90.801769) (xy 202.376169 -90.852266) (xy 202.345396 -90.898779)
			(xy 202.308179 -90.940316) (xy 202.265311 -90.975991) (xy 202.217705 -91.005045) (xy 202.166376 -91.026857)
			(xy 202.112419 -91.040963) (xy 202.056982 -91.047063) (xy 202.001248 -91.045026) (xy 201.946405 -91.034896)
			(xy 201.893621 -91.016889) (xy 201.844021 -90.991388) (xy 201.798663 -90.958937) (xy 201.758514 -90.920228)
			(xy 201.724428 -90.876085) (xy 201.697132 -90.82745) (xy 201.677209 -90.775359) (xy 201.665083 -90.720922)
			(xy 201.661012 -90.6653) (xy 200.363836 -90.6653) (xy 200.363836 -91.655646) (xy 215.233248 -91.655646)
			(xy 215.237319 -91.600024) (xy 215.249445 -91.545587) (xy 215.269368 -91.493496) (xy 215.296664 -91.444861)
			(xy 215.33075 -91.400718) (xy 215.370899 -91.362009) (xy 215.416257 -91.329558) (xy 215.465857 -91.304057)
			(xy 215.518641 -91.28605) (xy 215.573484 -91.27592) (xy 215.629218 -91.273883) (xy 215.684655 -91.279983)
			(xy 215.738612 -91.294089) (xy 215.789941 -91.315901) (xy 215.837547 -91.344955) (xy 215.880415 -91.38063)
			(xy 215.917632 -91.422167) (xy 215.948405 -91.46868) (xy 215.972077 -91.519177) (xy 215.988145 -91.572584)
			(xy 215.996265 -91.62776) (xy 215.996774 -91.655646) (xy 215.996265 -91.683532) (xy 215.988145 -91.738708)
			(xy 215.972077 -91.792115) (xy 215.948405 -91.842612) (xy 215.917632 -91.889125) (xy 215.880415 -91.930662)
			(xy 215.837547 -91.966337) (xy 215.789941 -91.995391) (xy 215.738612 -92.017203) (xy 215.684655 -92.031309)
			(xy 215.629218 -92.037409) (xy 215.573484 -92.035372) (xy 215.518641 -92.025242) (xy 215.465857 -92.007235)
			(xy 215.416257 -91.981734) (xy 215.370899 -91.949283) (xy 215.33075 -91.910574) (xy 215.296664 -91.866431)
			(xy 215.269368 -91.817796) (xy 215.249445 -91.765705) (xy 215.237319 -91.711268) (xy 215.233248 -91.655646)
			(xy 200.363836 -91.655646) (xy 200.363836 -92.041726) (xy 227.35235 -92.041726) (xy 227.356421 -91.986104)
			(xy 227.368547 -91.931667) (xy 227.38847 -91.879576) (xy 227.415766 -91.830941) (xy 227.449852 -91.786798)
			(xy 227.490001 -91.748089) (xy 227.535359 -91.715638) (xy 227.584959 -91.690137) (xy 227.637743 -91.67213)
			(xy 227.692586 -91.662) (xy 227.74832 -91.659963) (xy 227.803757 -91.666063) (xy 227.857714 -91.680169)
			(xy 227.909043 -91.701981) (xy 227.956649 -91.731035) (xy 227.999517 -91.76671) (xy 228.036734 -91.808247)
			(xy 228.067507 -91.85476) (xy 228.091179 -91.905257) (xy 228.107247 -91.958664) (xy 228.111584 -91.988132)
			(xy 229.487982 -91.988132) (xy 229.492053 -91.93251) (xy 229.504179 -91.878073) (xy 229.524102 -91.825982)
			(xy 229.551398 -91.777347) (xy 229.585484 -91.733204) (xy 229.625633 -91.694495) (xy 229.670991 -91.662044)
			(xy 229.720591 -91.636543) (xy 229.773375 -91.618536) (xy 229.828218 -91.608406) (xy 229.883952 -91.606369)
			(xy 229.939389 -91.612469) (xy 229.993346 -91.626575) (xy 230.044675 -91.648387) (xy 230.092281 -91.677441)
			(xy 230.135149 -91.713116) (xy 230.172366 -91.754653) (xy 230.203139 -91.801166) (xy 230.226811 -91.851663)
			(xy 230.242879 -91.90507) (xy 230.250999 -91.960246) (xy 230.251508 -91.988132) (xy 230.250999 -92.016018)
			(xy 230.242879 -92.071194) (xy 230.226811 -92.124601) (xy 230.203139 -92.175098) (xy 230.172366 -92.221611)
			(xy 230.14169 -92.255848) (xy 232.128312 -92.255848) (xy 232.132383 -92.200226) (xy 232.144509 -92.145789)
			(xy 232.164432 -92.093698) (xy 232.191728 -92.045063) (xy 232.225814 -92.00092) (xy 232.265963 -91.962211)
			(xy 232.311321 -91.92976) (xy 232.360921 -91.904259) (xy 232.413705 -91.886252) (xy 232.468548 -91.876122)
			(xy 232.524282 -91.874085) (xy 232.579719 -91.880185) (xy 232.633676 -91.894291) (xy 232.685005 -91.916103)
			(xy 232.732611 -91.945157) (xy 232.775479 -91.980832) (xy 232.812696 -92.022369) (xy 232.843469 -92.068882)
			(xy 232.867141 -92.119379) (xy 232.883209 -92.172786) (xy 232.891329 -92.227962) (xy 232.891838 -92.255848)
			(xy 232.891713 -92.262706) (xy 235.154468 -92.262706) (xy 235.158539 -92.207084) (xy 235.170665 -92.152647)
			(xy 235.190588 -92.100556) (xy 235.217884 -92.051921) (xy 235.25197 -92.007778) (xy 235.292119 -91.969069)
			(xy 235.337477 -91.936618) (xy 235.387077 -91.911117) (xy 235.439861 -91.89311) (xy 235.494704 -91.88298)
			(xy 235.550438 -91.880943) (xy 235.605875 -91.887043) (xy 235.659832 -91.901149) (xy 235.711161 -91.922961)
			(xy 235.758767 -91.952015) (xy 235.801635 -91.98769) (xy 235.812038 -91.9993) (xy 237.996724 -91.9993)
			(xy 238.000725 -91.944163) (xy 238.012642 -91.890181) (xy 238.032227 -91.838484) (xy 238.059069 -91.790156)
			(xy 238.092605 -91.746209) (xy 238.132135 -91.707562) (xy 238.176828 -91.675027) (xy 238.22575 -91.649283)
			(xy 238.277876 -91.630871) (xy 238.332114 -91.620176) (xy 238.359696 -91.618308) (xy 238.369081 -91.617392)
			(xy 238.38628 -91.609701) (xy 238.393224 -91.603322) (xy 238.41456 -91.581986) (xy 238.42125 -91.574502)
			(xy 238.428842 -91.555945) (xy 238.429292 -91.545918) (xy 238.429292 -90.793062) (xy 238.429673 -90.782987)
			(xy 238.437422 -90.764388) (xy 238.444278 -90.756994) (xy 239.398556 -89.80297) (xy 239.405974 -89.796152)
			(xy 239.42456 -89.78842) (xy 239.434624 -89.787984) (xy 239.52708 -89.787984) (xy 239.53587 -89.787601)
			(xy 239.552413 -89.781657) (xy 239.565968 -89.770464) (xy 239.570768 -89.763092) (xy 239.62233 -89.676478)
			(xy 239.622838 -89.649808) (xy 239.616488 -89.638124) (xy 239.602136 -89.610159) (xy 239.581774 -89.550697)
			(xy 239.571431 -89.488702) (xy 239.570768 -89.457276) (xy 239.570768 -89.456768) (xy 239.571254 -89.429517)
			(xy 239.57901 -89.375569) (xy 239.594365 -89.323274) (xy 239.617007 -89.273697) (xy 239.646473 -89.227847)
			(xy 239.682164 -89.186656) (xy 239.723355 -89.150965) (xy 239.769205 -89.121499) (xy 239.818782 -89.098857)
			(xy 239.871077 -89.083502) (xy 239.925025 -89.075746) (xy 239.979527 -89.075746) (xy 240.033475 -89.083502)
			(xy 240.08577 -89.098857) (xy 240.135347 -89.121499) (xy 240.181197 -89.150965) (xy 240.222388 -89.186656)
			(xy 240.258079 -89.227847) (xy 240.287545 -89.273697) (xy 240.310187 -89.323274) (xy 240.325542 -89.375569)
			(xy 240.333298 -89.429517) (xy 240.333784 -89.456768) (xy 240.333784 -89.457276) (xy 240.333664 -89.463118)
			(xy 248.974608 -89.463118) (xy 248.978679 -89.407496) (xy 248.990805 -89.353059) (xy 249.010728 -89.300968)
			(xy 249.038024 -89.252333) (xy 249.07211 -89.20819) (xy 249.112259 -89.169481) (xy 249.157617 -89.13703)
			(xy 249.207217 -89.111529) (xy 249.260001 -89.093522) (xy 249.314844 -89.083392) (xy 249.370578 -89.081355)
			(xy 249.426015 -89.087455) (xy 249.479972 -89.101561) (xy 249.531301 -89.123373) (xy 249.578907 -89.152427)
			(xy 249.621775 -89.188102) (xy 249.658992 -89.229639) (xy 249.689765 -89.276152) (xy 249.713437 -89.326649)
			(xy 249.729505 -89.380056) (xy 249.737625 -89.435232) (xy 249.73774 -89.441528) (xy 252.608078 -89.441528)
			(xy 252.612149 -89.385906) (xy 252.624275 -89.331469) (xy 252.644198 -89.279378) (xy 252.671494 -89.230743)
			(xy 252.70558 -89.1866) (xy 252.745729 -89.147891) (xy 252.791087 -89.11544) (xy 252.840687 -89.089939)
			(xy 252.893471 -89.071932) (xy 252.948314 -89.061802) (xy 253.004048 -89.059765) (xy 253.059485 -89.065865)
			(xy 253.113442 -89.079971) (xy 253.151369 -89.096088) (xy 258.801106 -89.096088) (xy 258.805177 -89.040466)
			(xy 258.817303 -88.986029) (xy 258.837226 -88.933938) (xy 258.864522 -88.885303) (xy 258.898608 -88.84116)
			(xy 258.938757 -88.802451) (xy 258.984115 -88.77) (xy 259.033715 -88.744499) (xy 259.086499 -88.726492)
			(xy 259.141342 -88.716362) (xy 259.197076 -88.714325) (xy 259.252513 -88.720425) (xy 259.30647 -88.734531)
			(xy 259.357799 -88.756343) (xy 259.405405 -88.785397) (xy 259.448273 -88.821072) (xy 259.48549 -88.862609)
			(xy 259.516263 -88.909122) (xy 259.539935 -88.959619) (xy 259.554629 -89.008458) (xy 261.557768 -89.008458)
			(xy 261.561839 -88.952836) (xy 261.573965 -88.898399) (xy 261.593888 -88.846308) (xy 261.621184 -88.797673)
			(xy 261.65527 -88.75353) (xy 261.695419 -88.714821) (xy 261.740777 -88.68237) (xy 261.790377 -88.656869)
			(xy 261.843161 -88.638862) (xy 261.898004 -88.628732) (xy 261.953738 -88.626695) (xy 262.009175 -88.632795)
			(xy 262.063132 -88.646901) (xy 262.114461 -88.668713) (xy 262.162067 -88.697767) (xy 262.204935 -88.733442)
			(xy 262.242152 -88.774979) (xy 262.272925 -88.821492) (xy 262.296597 -88.871989) (xy 262.312665 -88.925396)
			(xy 262.320785 -88.980572) (xy 262.321294 -89.008458) (xy 262.320785 -89.036344) (xy 262.312665 -89.09152)
			(xy 262.296597 -89.144927) (xy 262.272925 -89.195424) (xy 262.242152 -89.241937) (xy 262.204935 -89.283474)
			(xy 262.162067 -89.319149) (xy 262.114461 -89.348203) (xy 262.063132 -89.370015) (xy 262.009175 -89.384121)
			(xy 261.953738 -89.390221) (xy 261.898004 -89.388184) (xy 261.843161 -89.378054) (xy 261.790377 -89.360047)
			(xy 261.740777 -89.334546) (xy 261.695419 -89.302095) (xy 261.65527 -89.263386) (xy 261.621184 -89.219243)
			(xy 261.593888 -89.170608) (xy 261.573965 -89.118517) (xy 261.561839 -89.06408) (xy 261.557768 -89.008458)
			(xy 259.554629 -89.008458) (xy 259.556003 -89.013026) (xy 259.564123 -89.068202) (xy 259.564632 -89.096088)
			(xy 259.564123 -89.123974) (xy 259.556003 -89.17915) (xy 259.539935 -89.232557) (xy 259.516263 -89.283054)
			(xy 259.48549 -89.329567) (xy 259.448273 -89.371104) (xy 259.405405 -89.406779) (xy 259.357799 -89.435833)
			(xy 259.30647 -89.457645) (xy 259.252513 -89.471751) (xy 259.197076 -89.477851) (xy 259.141342 -89.475814)
			(xy 259.086499 -89.465684) (xy 259.033715 -89.447677) (xy 258.984115 -89.422176) (xy 258.938757 -89.389725)
			(xy 258.898608 -89.351016) (xy 258.864522 -89.306873) (xy 258.837226 -89.258238) (xy 258.817303 -89.206147)
			(xy 258.805177 -89.15171) (xy 258.801106 -89.096088) (xy 253.151369 -89.096088) (xy 253.164771 -89.101783)
			(xy 253.212377 -89.130837) (xy 253.255245 -89.166512) (xy 253.292462 -89.208049) (xy 253.323235 -89.254562)
			(xy 253.346907 -89.305059) (xy 253.362975 -89.358466) (xy 253.371095 -89.413642) (xy 253.371604 -89.441528)
			(xy 253.371095 -89.469414) (xy 253.362975 -89.52459) (xy 253.346907 -89.577997) (xy 253.323235 -89.628494)
			(xy 253.292462 -89.675007) (xy 253.255245 -89.716544) (xy 253.212377 -89.752219) (xy 253.164771 -89.781273)
			(xy 253.113442 -89.803085) (xy 253.059485 -89.817191) (xy 253.004048 -89.823291) (xy 252.948314 -89.821254)
			(xy 252.893471 -89.811124) (xy 252.840687 -89.793117) (xy 252.791087 -89.767616) (xy 252.745729 -89.735165)
			(xy 252.70558 -89.696456) (xy 252.671494 -89.652313) (xy 252.644198 -89.603678) (xy 252.624275 -89.551587)
			(xy 252.612149 -89.49715) (xy 252.608078 -89.441528) (xy 249.73774 -89.441528) (xy 249.738134 -89.463118)
			(xy 249.737625 -89.491004) (xy 249.729505 -89.54618) (xy 249.713437 -89.599587) (xy 249.689765 -89.650084)
			(xy 249.658992 -89.696597) (xy 249.621775 -89.738134) (xy 249.578907 -89.773809) (xy 249.531301 -89.802863)
			(xy 249.479972 -89.824675) (xy 249.426015 -89.838781) (xy 249.370578 -89.844881) (xy 249.314844 -89.842844)
			(xy 249.260001 -89.832714) (xy 249.207217 -89.814707) (xy 249.157617 -89.789206) (xy 249.112259 -89.756755)
			(xy 249.07211 -89.718046) (xy 249.038024 -89.673903) (xy 249.010728 -89.625268) (xy 248.990805 -89.573177)
			(xy 248.978679 -89.51874) (xy 248.974608 -89.463118) (xy 240.333664 -89.463118) (xy 240.333138 -89.488703)
			(xy 240.32279 -89.550699) (xy 240.30242 -89.61016) (xy 240.288064 -89.638124) (xy 240.281714 -89.649808)
			(xy 240.282222 -89.676478) (xy 240.333784 -89.763092) (xy 240.338601 -89.770453) (xy 240.352147 -89.781654)
			(xy 240.368684 -89.78761) (xy 240.377472 -89.787984) (xy 243.62283 -89.787984) (xy 243.632904 -89.788371)
			(xy 243.651503 -89.796116) (xy 243.658898 -89.80297) (xy 243.724473 -89.868502) (xy 251.846586 -89.868502)
			(xy 251.850657 -89.81288) (xy 251.862783 -89.758443) (xy 251.882706 -89.706352) (xy 251.910002 -89.657717)
			(xy 251.944088 -89.613574) (xy 251.984237 -89.574865) (xy 252.029595 -89.542414) (xy 252.079195 -89.516913)
			(xy 252.131979 -89.498906) (xy 252.186822 -89.488776) (xy 252.242556 -89.486739) (xy 252.297993 -89.492839)
			(xy 252.35195 -89.506945) (xy 252.403279 -89.528757) (xy 252.450885 -89.557811) (xy 252.493753 -89.593486)
			(xy 252.53097 -89.635023) (xy 252.561743 -89.681536) (xy 252.585415 -89.732033) (xy 252.601483 -89.78544)
			(xy 252.609603 -89.840616) (xy 252.610112 -89.868502) (xy 252.609603 -89.896388) (xy 252.608436 -89.904316)
			(xy 253.724662 -89.904316) (xy 253.728733 -89.848694) (xy 253.740859 -89.794257) (xy 253.760782 -89.742166)
			(xy 253.788078 -89.693531) (xy 253.822164 -89.649388) (xy 253.862313 -89.610679) (xy 253.907671 -89.578228)
			(xy 253.957271 -89.552727) (xy 254.010055 -89.53472) (xy 254.064898 -89.52459) (xy 254.120632 -89.522553)
			(xy 254.176069 -89.528653) (xy 254.230026 -89.542759) (xy 254.281355 -89.564571) (xy 254.328961 -89.593625)
			(xy 254.371829 -89.6293) (xy 254.409046 -89.670837) (xy 254.439819 -89.71735) (xy 254.463491 -89.767847)
			(xy 254.479559 -89.821254) (xy 254.487679 -89.87643) (xy 254.488188 -89.904316) (xy 254.487679 -89.932202)
			(xy 254.479559 -89.987378) (xy 254.463491 -90.040785) (xy 254.439819 -90.091282) (xy 254.409046 -90.137795)
			(xy 254.371829 -90.179332) (xy 254.328961 -90.215007) (xy 254.281355 -90.244061) (xy 254.230026 -90.265873)
			(xy 254.176069 -90.279979) (xy 254.120632 -90.286079) (xy 254.064898 -90.284042) (xy 254.010055 -90.273912)
			(xy 253.957271 -90.255905) (xy 253.907671 -90.230404) (xy 253.862313 -90.197953) (xy 253.822164 -90.159244)
			(xy 253.788078 -90.115101) (xy 253.760782 -90.066466) (xy 253.740859 -90.014375) (xy 253.728733 -89.959938)
			(xy 253.724662 -89.904316) (xy 252.608436 -89.904316) (xy 252.601483 -89.951564) (xy 252.585415 -90.004971)
			(xy 252.561743 -90.055468) (xy 252.53097 -90.101981) (xy 252.493753 -90.143518) (xy 252.450885 -90.179193)
			(xy 252.403279 -90.208247) (xy 252.35195 -90.230059) (xy 252.297993 -90.244165) (xy 252.242556 -90.250265)
			(xy 252.186822 -90.248228) (xy 252.131979 -90.238098) (xy 252.079195 -90.220091) (xy 252.029595 -90.19459)
			(xy 251.984237 -90.162139) (xy 251.944088 -90.12343) (xy 251.910002 -90.079287) (xy 251.882706 -90.030652)
			(xy 251.862783 -89.978561) (xy 251.850657 -89.924124) (xy 251.846586 -89.868502) (xy 243.724473 -89.868502)
			(xy 244.048026 -90.191844) (xy 244.054882 -90.199232) (xy 244.062592 -90.217841) (xy 244.063012 -90.227912)
			(xy 244.063012 -91.478354) (xy 269.030448 -91.478354) (xy 269.034519 -91.422732) (xy 269.046645 -91.368295)
			(xy 269.066568 -91.316204) (xy 269.093864 -91.267569) (xy 269.12795 -91.223426) (xy 269.168099 -91.184717)
			(xy 269.213457 -91.152266) (xy 269.263057 -91.126765) (xy 269.315841 -91.108758) (xy 269.370684 -91.098628)
			(xy 269.426418 -91.096591) (xy 269.481855 -91.102691) (xy 269.535812 -91.116797) (xy 269.587141 -91.138609)
			(xy 269.634747 -91.167663) (xy 269.677615 -91.203338) (xy 269.714832 -91.244875) (xy 269.745605 -91.291388)
			(xy 269.769277 -91.341885) (xy 269.785345 -91.395292) (xy 269.793465 -91.450468) (xy 269.793974 -91.478354)
			(xy 269.793465 -91.50624) (xy 269.785345 -91.561416) (xy 269.769277 -91.614823) (xy 269.745605 -91.66532)
			(xy 269.714832 -91.711833) (xy 269.677615 -91.75337) (xy 269.634747 -91.789045) (xy 269.587141 -91.818099)
			(xy 269.535812 -91.839911) (xy 269.481855 -91.854017) (xy 269.426418 -91.860117) (xy 269.370684 -91.85808)
			(xy 269.315841 -91.84795) (xy 269.263057 -91.829943) (xy 269.213457 -91.804442) (xy 269.168099 -91.771991)
			(xy 269.12795 -91.733282) (xy 269.093864 -91.689139) (xy 269.066568 -91.640504) (xy 269.046645 -91.588413)
			(xy 269.034519 -91.533976) (xy 269.030448 -91.478354) (xy 244.063012 -91.478354) (xy 244.063012 -92.526104)
			(xy 269.030448 -92.526104) (xy 269.034519 -92.470482) (xy 269.046645 -92.416045) (xy 269.066568 -92.363954)
			(xy 269.093864 -92.315319) (xy 269.12795 -92.271176) (xy 269.168099 -92.232467) (xy 269.213457 -92.200016)
			(xy 269.263057 -92.174515) (xy 269.315841 -92.156508) (xy 269.370684 -92.146378) (xy 269.426418 -92.144341)
			(xy 269.481855 -92.150441) (xy 269.535812 -92.164547) (xy 269.587141 -92.186359) (xy 269.634747 -92.215413)
			(xy 269.677615 -92.251088) (xy 269.714832 -92.292625) (xy 269.745605 -92.339138) (xy 269.769277 -92.389635)
			(xy 269.785345 -92.443042) (xy 269.793465 -92.498218) (xy 269.793974 -92.526104) (xy 269.793465 -92.55399)
			(xy 269.785345 -92.609166) (xy 269.769277 -92.662573) (xy 269.745605 -92.71307) (xy 269.714832 -92.759583)
			(xy 269.677615 -92.80112) (xy 269.634747 -92.836795) (xy 269.587141 -92.865849) (xy 269.535812 -92.887661)
			(xy 269.481855 -92.901767) (xy 269.426418 -92.907867) (xy 269.370684 -92.90583) (xy 269.315841 -92.8957)
			(xy 269.263057 -92.877693) (xy 269.213457 -92.852192) (xy 269.168099 -92.819741) (xy 269.12795 -92.781032)
			(xy 269.093864 -92.736889) (xy 269.066568 -92.688254) (xy 269.046645 -92.636163) (xy 269.034519 -92.581726)
			(xy 269.030448 -92.526104) (xy 244.063012 -92.526104) (xy 244.063012 -93.105986) (xy 249.565412 -93.105986)
			(xy 249.569483 -93.050364) (xy 249.581609 -92.995927) (xy 249.601532 -92.943836) (xy 249.628828 -92.895201)
			(xy 249.662914 -92.851058) (xy 249.703063 -92.812349) (xy 249.748421 -92.779898) (xy 249.798021 -92.754397)
			(xy 249.850805 -92.73639) (xy 249.905648 -92.72626) (xy 249.961382 -92.724223) (xy 250.016819 -92.730323)
			(xy 250.070776 -92.744429) (xy 250.122105 -92.766241) (xy 250.169711 -92.795295) (xy 250.212579 -92.83097)
			(xy 250.249796 -92.872507) (xy 250.280569 -92.91902) (xy 250.304241 -92.969517) (xy 250.320309 -93.022924)
			(xy 250.328429 -93.0781) (xy 250.328938 -93.105986) (xy 250.581412 -93.105986) (xy 250.585483 -93.050364)
			(xy 250.597609 -92.995927) (xy 250.617532 -92.943836) (xy 250.644828 -92.895201) (xy 250.678914 -92.851058)
			(xy 250.719063 -92.812349) (xy 250.764421 -92.779898) (xy 250.814021 -92.754397) (xy 250.866805 -92.73639)
			(xy 250.921648 -92.72626) (xy 250.977382 -92.724223) (xy 251.032819 -92.730323) (xy 251.086776 -92.744429)
			(xy 251.138105 -92.766241) (xy 251.185711 -92.795295) (xy 251.228579 -92.83097) (xy 251.265796 -92.872507)
			(xy 251.296569 -92.91902) (xy 251.320241 -92.969517) (xy 251.336309 -93.022924) (xy 251.344429 -93.0781)
			(xy 251.344938 -93.105986) (xy 251.597412 -93.105986) (xy 251.601483 -93.050364) (xy 251.613609 -92.995927)
			(xy 251.633532 -92.943836) (xy 251.660828 -92.895201) (xy 251.694914 -92.851058) (xy 251.735063 -92.812349)
			(xy 251.780421 -92.779898) (xy 251.830021 -92.754397) (xy 251.882805 -92.73639) (xy 251.937648 -92.72626)
			(xy 251.993382 -92.724223) (xy 252.048819 -92.730323) (xy 252.102776 -92.744429) (xy 252.154105 -92.766241)
			(xy 252.201711 -92.795295) (xy 252.244579 -92.83097) (xy 252.281796 -92.872507) (xy 252.312569 -92.91902)
			(xy 252.336241 -92.969517) (xy 252.352309 -93.022924) (xy 252.360429 -93.0781) (xy 252.360938 -93.105986)
			(xy 252.360429 -93.133872) (xy 252.352309 -93.189048) (xy 252.336241 -93.242455) (xy 252.312569 -93.292952)
			(xy 252.281796 -93.339465) (xy 252.244579 -93.381002) (xy 252.201711 -93.416677) (xy 252.154105 -93.445731)
			(xy 252.102776 -93.467543) (xy 252.048819 -93.481649) (xy 251.993382 -93.487749) (xy 251.937648 -93.485712)
			(xy 251.882805 -93.475582) (xy 251.830021 -93.457575) (xy 251.780421 -93.432074) (xy 251.735063 -93.399623)
			(xy 251.694914 -93.360914) (xy 251.660828 -93.316771) (xy 251.633532 -93.268136) (xy 251.613609 -93.216045)
			(xy 251.601483 -93.161608) (xy 251.597412 -93.105986) (xy 251.344938 -93.105986) (xy 251.344429 -93.133872)
			(xy 251.336309 -93.189048) (xy 251.320241 -93.242455) (xy 251.296569 -93.292952) (xy 251.265796 -93.339465)
			(xy 251.228579 -93.381002) (xy 251.185711 -93.416677) (xy 251.138105 -93.445731) (xy 251.086776 -93.467543)
			(xy 251.032819 -93.481649) (xy 250.977382 -93.487749) (xy 250.921648 -93.485712) (xy 250.866805 -93.475582)
			(xy 250.814021 -93.457575) (xy 250.764421 -93.432074) (xy 250.719063 -93.399623) (xy 250.678914 -93.360914)
			(xy 250.644828 -93.316771) (xy 250.617532 -93.268136) (xy 250.597609 -93.216045) (xy 250.585483 -93.161608)
			(xy 250.581412 -93.105986) (xy 250.328938 -93.105986) (xy 250.328429 -93.133872) (xy 250.320309 -93.189048)
			(xy 250.304241 -93.242455) (xy 250.280569 -93.292952) (xy 250.249796 -93.339465) (xy 250.212579 -93.381002)
			(xy 250.169711 -93.416677) (xy 250.122105 -93.445731) (xy 250.070776 -93.467543) (xy 250.016819 -93.481649)
			(xy 249.961382 -93.487749) (xy 249.905648 -93.485712) (xy 249.850805 -93.475582) (xy 249.798021 -93.457575)
			(xy 249.748421 -93.432074) (xy 249.703063 -93.399623) (xy 249.662914 -93.360914) (xy 249.628828 -93.316771)
			(xy 249.601532 -93.268136) (xy 249.581609 -93.216045) (xy 249.569483 -93.161608) (xy 249.565412 -93.105986)
			(xy 244.063012 -93.105986) (xy 244.063012 -93.808804) (xy 244.062612 -93.818877) (xy 244.054876 -93.837476)
			(xy 244.048026 -93.844872) (xy 243.79428 -94.098618) (xy 250.156724 -94.098618) (xy 250.160795 -94.042996)
			(xy 250.172921 -93.988559) (xy 250.192844 -93.936468) (xy 250.22014 -93.887833) (xy 250.254226 -93.84369)
			(xy 250.294375 -93.804981) (xy 250.339733 -93.77253) (xy 250.389333 -93.747029) (xy 250.442117 -93.729022)
			(xy 250.49696 -93.718892) (xy 250.552694 -93.716855) (xy 250.608131 -93.722955) (xy 250.662088 -93.737061)
			(xy 250.713417 -93.758873) (xy 250.761023 -93.787927) (xy 250.803891 -93.823602) (xy 250.841108 -93.865139)
			(xy 250.871881 -93.911652) (xy 250.895553 -93.962149) (xy 250.911621 -94.015556) (xy 250.919741 -94.070732)
			(xy 250.92025 -94.098618) (xy 250.919741 -94.126504) (xy 250.911621 -94.18168) (xy 250.895553 -94.235087)
			(xy 250.871881 -94.285584) (xy 250.841108 -94.332097) (xy 250.803891 -94.373634) (xy 250.761023 -94.409309)
			(xy 250.713417 -94.438363) (xy 250.662088 -94.460175) (xy 250.608131 -94.474281) (xy 250.552694 -94.480381)
			(xy 250.49696 -94.478344) (xy 250.442117 -94.468214) (xy 250.389333 -94.450207) (xy 250.339733 -94.424706)
			(xy 250.294375 -94.392255) (xy 250.254226 -94.353546) (xy 250.22014 -94.309403) (xy 250.192844 -94.260768)
			(xy 250.172921 -94.208677) (xy 250.160795 -94.15424) (xy 250.156724 -94.098618) (xy 243.79428 -94.098618)
			(xy 243.114576 -94.778322) (xy 243.107181 -94.785168) (xy 243.088578 -94.792884) (xy 243.078508 -94.793308)
			(xy 238.828072 -94.793308) (xy 238.817998 -94.792921) (xy 238.799399 -94.785176) (xy 238.792004 -94.778322)
			(xy 238.444278 -94.430596) (xy 238.43744 -94.423194) (xy 238.42972 -94.404596) (xy 238.429292 -94.394528)
			(xy 238.429292 -92.452698) (xy 238.4289 -92.442655) (xy 238.421327 -92.424059) (xy 238.41456 -92.41663)
			(xy 238.393224 -92.395294) (xy 238.386323 -92.388851) (xy 238.369099 -92.381154) (xy 238.359696 -92.380308)
			(xy 238.332115 -92.378424) (xy 238.277877 -92.367729) (xy 238.225751 -92.349317) (xy 238.176829 -92.323574)
			(xy 238.132135 -92.291038) (xy 238.092606 -92.252392) (xy 238.059069 -92.208444) (xy 238.032227 -92.160116)
			(xy 238.012642 -92.10842) (xy 238.000725 -92.054437) (xy 237.996724 -91.9993) (xy 235.812038 -91.9993)
			(xy 235.838852 -92.029227) (xy 235.869625 -92.07574) (xy 235.893297 -92.126237) (xy 235.909365 -92.179644)
			(xy 235.917485 -92.23482) (xy 235.917994 -92.262706) (xy 235.917485 -92.290592) (xy 235.909365 -92.345768)
			(xy 235.893297 -92.399175) (xy 235.869625 -92.449672) (xy 235.838852 -92.496185) (xy 235.801635 -92.537722)
			(xy 235.758767 -92.573397) (xy 235.711161 -92.602451) (xy 235.659832 -92.624263) (xy 235.605875 -92.638369)
			(xy 235.550438 -92.644469) (xy 235.494704 -92.642432) (xy 235.439861 -92.632302) (xy 235.387077 -92.614295)
			(xy 235.337477 -92.588794) (xy 235.292119 -92.556343) (xy 235.25197 -92.517634) (xy 235.217884 -92.473491)
			(xy 235.190588 -92.424856) (xy 235.170665 -92.372765) (xy 235.158539 -92.318328) (xy 235.154468 -92.262706)
			(xy 232.891713 -92.262706) (xy 232.891329 -92.283734) (xy 232.883209 -92.33891) (xy 232.867141 -92.392317)
			(xy 232.843469 -92.442814) (xy 232.812696 -92.489327) (xy 232.775479 -92.530864) (xy 232.732611 -92.566539)
			(xy 232.685005 -92.595593) (xy 232.633676 -92.617405) (xy 232.579719 -92.631511) (xy 232.524282 -92.637611)
			(xy 232.468548 -92.635574) (xy 232.413705 -92.625444) (xy 232.360921 -92.607437) (xy 232.311321 -92.581936)
			(xy 232.265963 -92.549485) (xy 232.225814 -92.510776) (xy 232.191728 -92.466633) (xy 232.164432 -92.417998)
			(xy 232.144509 -92.365907) (xy 232.132383 -92.31147) (xy 232.128312 -92.255848) (xy 230.14169 -92.255848)
			(xy 230.135149 -92.263148) (xy 230.092281 -92.298823) (xy 230.044675 -92.327877) (xy 229.993346 -92.349689)
			(xy 229.939389 -92.363795) (xy 229.883952 -92.369895) (xy 229.828218 -92.367858) (xy 229.773375 -92.357728)
			(xy 229.720591 -92.339721) (xy 229.670991 -92.31422) (xy 229.625633 -92.281769) (xy 229.585484 -92.24306)
			(xy 229.551398 -92.198917) (xy 229.524102 -92.150282) (xy 229.504179 -92.098191) (xy 229.492053 -92.043754)
			(xy 229.487982 -91.988132) (xy 228.111584 -91.988132) (xy 228.115367 -92.01384) (xy 228.115876 -92.041726)
			(xy 228.115367 -92.069612) (xy 228.107247 -92.124788) (xy 228.091179 -92.178195) (xy 228.067507 -92.228692)
			(xy 228.036734 -92.275205) (xy 227.999517 -92.316742) (xy 227.956649 -92.352417) (xy 227.909043 -92.381471)
			(xy 227.857714 -92.403283) (xy 227.803757 -92.417389) (xy 227.74832 -92.423489) (xy 227.692586 -92.421452)
			(xy 227.637743 -92.411322) (xy 227.584959 -92.393315) (xy 227.535359 -92.367814) (xy 227.490001 -92.335363)
			(xy 227.449852 -92.296654) (xy 227.415766 -92.252511) (xy 227.38847 -92.203876) (xy 227.368547 -92.151785)
			(xy 227.356421 -92.097348) (xy 227.35235 -92.041726) (xy 200.363836 -92.041726) (xy 200.363836 -92.665042)
			(xy 237.406432 -92.665042) (xy 237.410503 -92.60942) (xy 237.422629 -92.554983) (xy 237.442552 -92.502892)
			(xy 237.469848 -92.454257) (xy 237.503934 -92.410114) (xy 237.544083 -92.371405) (xy 237.589441 -92.338954)
			(xy 237.639041 -92.313453) (xy 237.691825 -92.295446) (xy 237.746668 -92.285316) (xy 237.802402 -92.283279)
			(xy 237.857839 -92.289379) (xy 237.911796 -92.303485) (xy 237.963125 -92.325297) (xy 238.010731 -92.354351)
			(xy 238.053599 -92.390026) (xy 238.090816 -92.431563) (xy 238.121589 -92.478076) (xy 238.145261 -92.528573)
			(xy 238.161329 -92.58198) (xy 238.169449 -92.637156) (xy 238.169958 -92.665042) (xy 238.169449 -92.692928)
			(xy 238.161329 -92.748104) (xy 238.145261 -92.801511) (xy 238.121589 -92.852008) (xy 238.090816 -92.898521)
			(xy 238.053599 -92.940058) (xy 238.010731 -92.975733) (xy 237.963125 -93.004787) (xy 237.911796 -93.026599)
			(xy 237.857839 -93.040705) (xy 237.802402 -93.046805) (xy 237.746668 -93.044768) (xy 237.691825 -93.034638)
			(xy 237.639041 -93.016631) (xy 237.589441 -92.99113) (xy 237.544083 -92.958679) (xy 237.503934 -92.91997)
			(xy 237.469848 -92.875827) (xy 237.442552 -92.827192) (xy 237.422629 -92.775101) (xy 237.410503 -92.720664)
			(xy 237.406432 -92.665042) (xy 200.363836 -92.665042) (xy 200.363836 -93.057726) (xy 227.35235 -93.057726)
			(xy 227.356421 -93.002104) (xy 227.368547 -92.947667) (xy 227.38847 -92.895576) (xy 227.415766 -92.846941)
			(xy 227.449852 -92.802798) (xy 227.490001 -92.764089) (xy 227.535359 -92.731638) (xy 227.584959 -92.706137)
			(xy 227.637743 -92.68813) (xy 227.692586 -92.678) (xy 227.74832 -92.675963) (xy 227.803757 -92.682063)
			(xy 227.857714 -92.696169) (xy 227.909043 -92.717981) (xy 227.956649 -92.747035) (xy 227.999517 -92.78271)
			(xy 228.036734 -92.824247) (xy 228.067507 -92.87076) (xy 228.091179 -92.921257) (xy 228.107247 -92.974664)
			(xy 228.115367 -93.02984) (xy 228.115876 -93.057726) (xy 228.115367 -93.085612) (xy 228.107247 -93.140788)
			(xy 228.091179 -93.194195) (xy 228.067507 -93.244692) (xy 228.05307 -93.266514) (xy 229.782876 -93.266514)
			(xy 229.786947 -93.210892) (xy 229.799073 -93.156455) (xy 229.818996 -93.104364) (xy 229.846292 -93.055729)
			(xy 229.880378 -93.011586) (xy 229.920527 -92.972877) (xy 229.965885 -92.940426) (xy 230.015485 -92.914925)
			(xy 230.068269 -92.896918) (xy 230.123112 -92.886788) (xy 230.178846 -92.884751) (xy 230.234283 -92.890851)
			(xy 230.28824 -92.904957) (xy 230.339569 -92.926769) (xy 230.387175 -92.955823) (xy 230.430043 -92.991498)
			(xy 230.46726 -93.033035) (xy 230.498033 -93.079548) (xy 230.521705 -93.130045) (xy 230.537773 -93.183452)
			(xy 230.545893 -93.238628) (xy 230.546402 -93.266514) (xy 230.545893 -93.2944) (xy 230.537773 -93.349576)
			(xy 230.521705 -93.402983) (xy 230.498033 -93.45348) (xy 230.46726 -93.499993) (xy 230.430043 -93.54153)
			(xy 230.387175 -93.577205) (xy 230.339569 -93.606259) (xy 230.28824 -93.628071) (xy 230.234283 -93.642177)
			(xy 230.178846 -93.648277) (xy 230.123112 -93.64624) (xy 230.068269 -93.63611) (xy 230.015485 -93.618103)
			(xy 229.965885 -93.592602) (xy 229.920527 -93.560151) (xy 229.880378 -93.521442) (xy 229.846292 -93.477299)
			(xy 229.818996 -93.428664) (xy 229.799073 -93.376573) (xy 229.786947 -93.322136) (xy 229.782876 -93.266514)
			(xy 228.05307 -93.266514) (xy 228.036734 -93.291205) (xy 227.999517 -93.332742) (xy 227.956649 -93.368417)
			(xy 227.909043 -93.397471) (xy 227.857714 -93.419283) (xy 227.803757 -93.433389) (xy 227.74832 -93.439489)
			(xy 227.692586 -93.437452) (xy 227.637743 -93.427322) (xy 227.584959 -93.409315) (xy 227.535359 -93.383814)
			(xy 227.490001 -93.351363) (xy 227.449852 -93.312654) (xy 227.415766 -93.268511) (xy 227.38847 -93.219876)
			(xy 227.368547 -93.167785) (xy 227.356421 -93.113348) (xy 227.35235 -93.057726) (xy 200.363836 -93.057726)
			(xy 200.363836 -97.098358) (xy 200.363344 -97.122095) (xy 200.355975 -97.168994) (xy 200.341454 -97.214193)
			(xy 200.320129 -97.256608) (xy 200.292511 -97.295223) (xy 200.276206 -97.31248) (xy 200.273666 -97.31502)
			(xy 198.888604 -98.700082) (xy 203.041004 -98.700082) (xy 203.045008 -98.494894) (xy 203.057015 -98.290018)
			(xy 203.077006 -98.085767) (xy 203.104951 -97.882452) (xy 203.140807 -97.680381) (xy 203.184521 -97.479863)
			(xy 203.236024 -97.281204) (xy 203.295239 -97.084705) (xy 203.362075 -96.890666) (xy 203.436431 -96.699383)
			(xy 203.518194 -96.511146) (xy 203.607239 -96.326243) (xy 203.70343 -96.144955) (xy 203.806621 -95.967558)
			(xy 203.916655 -95.794321) (xy 204.033364 -95.62551) (xy 204.15657 -95.461381) (xy 204.286087 -95.302184)
			(xy 204.421716 -95.148162) (xy 204.563251 -94.999548) (xy 204.710476 -94.85657) (xy 204.863168 -94.719445)
			(xy 205.021094 -94.588381) (xy 205.184013 -94.463579) (xy 205.351678 -94.345229) (xy 205.523832 -94.23351)
			(xy 205.700214 -94.128593) (xy 205.880555 -94.030638) (xy 206.064581 -93.939794) (xy 206.252011 -93.856198)
			(xy 206.44256 -93.779979) (xy 206.635937 -93.711253) (xy 206.831849 -93.650124) (xy 207.029996 -93.596685)
			(xy 207.230078 -93.551018) (xy 207.431789 -93.513191) (xy 207.634822 -93.483264) (xy 207.838869 -93.461281)
			(xy 208.043618 -93.447276) (xy 208.248757 -93.44127) (xy 208.453974 -93.443272) (xy 208.658957 -93.45328)
			(xy 208.863394 -93.471277) (xy 209.066972 -93.497237) (xy 209.269383 -93.53112) (xy 209.470317 -93.572875)
			(xy 209.66947 -93.622438) (xy 209.866537 -93.679733) (xy 210.061219 -93.744673) (xy 210.253219 -93.817159)
			(xy 210.442244 -93.897082) (xy 210.628007 -93.984318) (xy 210.800556 -94.073726) (xy 227.35235 -94.073726)
			(xy 227.356421 -94.018104) (xy 227.368547 -93.963667) (xy 227.38847 -93.911576) (xy 227.415766 -93.862941)
			(xy 227.449852 -93.818798) (xy 227.490001 -93.780089) (xy 227.535359 -93.747638) (xy 227.584959 -93.722137)
			(xy 227.637743 -93.70413) (xy 227.692586 -93.694) (xy 227.74832 -93.691963) (xy 227.803757 -93.698063)
			(xy 227.857714 -93.712169) (xy 227.909043 -93.733981) (xy 227.956649 -93.763035) (xy 227.976242 -93.77934)
			(xy 232.128312 -93.77934) (xy 232.132383 -93.723718) (xy 232.144509 -93.669281) (xy 232.164432 -93.61719)
			(xy 232.191728 -93.568555) (xy 232.225814 -93.524412) (xy 232.265963 -93.485703) (xy 232.311321 -93.453252)
			(xy 232.360921 -93.427751) (xy 232.413705 -93.409744) (xy 232.468548 -93.399614) (xy 232.524282 -93.397577)
			(xy 232.579719 -93.403677) (xy 232.633676 -93.417783) (xy 232.685005 -93.439595) (xy 232.732611 -93.468649)
			(xy 232.775479 -93.504324) (xy 232.812696 -93.545861) (xy 232.843469 -93.592374) (xy 232.867141 -93.642871)
			(xy 232.883209 -93.696278) (xy 232.891329 -93.751454) (xy 232.891838 -93.77934) (xy 233.670854 -93.77934)
			(xy 233.674925 -93.723718) (xy 233.687051 -93.669281) (xy 233.706974 -93.61719) (xy 233.73427 -93.568555)
			(xy 233.768356 -93.524412) (xy 233.808505 -93.485703) (xy 233.853863 -93.453252) (xy 233.903463 -93.427751)
			(xy 233.956247 -93.409744) (xy 234.01109 -93.399614) (xy 234.066824 -93.397577) (xy 234.122261 -93.403677)
			(xy 234.176218 -93.417783) (xy 234.227547 -93.439595) (xy 234.275153 -93.468649) (xy 234.318021 -93.504324)
			(xy 234.355238 -93.545861) (xy 234.386011 -93.592374) (xy 234.409683 -93.642871) (xy 234.425751 -93.696278)
			(xy 234.433871 -93.751454) (xy 234.43438 -93.77934) (xy 235.154468 -93.77934) (xy 235.158539 -93.723718)
			(xy 235.170665 -93.669281) (xy 235.190588 -93.61719) (xy 235.217884 -93.568555) (xy 235.25197 -93.524412)
			(xy 235.292119 -93.485703) (xy 235.337477 -93.453252) (xy 235.387077 -93.427751) (xy 235.439861 -93.409744)
			(xy 235.494704 -93.399614) (xy 235.550438 -93.397577) (xy 235.605875 -93.403677) (xy 235.659832 -93.417783)
			(xy 235.711161 -93.439595) (xy 235.758767 -93.468649) (xy 235.801635 -93.504324) (xy 235.838852 -93.545861)
			(xy 235.869625 -93.592374) (xy 235.893297 -93.642871) (xy 235.909365 -93.696278) (xy 235.917485 -93.751454)
			(xy 235.917762 -93.76664) (xy 236.86592 -93.76664) (xy 236.869991 -93.711018) (xy 236.882117 -93.656581)
			(xy 236.90204 -93.60449) (xy 236.929336 -93.555855) (xy 236.963422 -93.511712) (xy 237.003571 -93.473003)
			(xy 237.048929 -93.440552) (xy 237.098529 -93.415051) (xy 237.151313 -93.397044) (xy 237.206156 -93.386914)
			(xy 237.26189 -93.384877) (xy 237.317327 -93.390977) (xy 237.371284 -93.405083) (xy 237.422613 -93.426895)
			(xy 237.470219 -93.455949) (xy 237.513087 -93.491624) (xy 237.550304 -93.533161) (xy 237.581077 -93.579674)
			(xy 237.604749 -93.630171) (xy 237.620817 -93.683578) (xy 237.628937 -93.738754) (xy 237.629446 -93.76664)
			(xy 237.628937 -93.794526) (xy 237.620817 -93.849702) (xy 237.604749 -93.903109) (xy 237.581077 -93.953606)
			(xy 237.550304 -94.000119) (xy 237.513087 -94.041656) (xy 237.470219 -94.077331) (xy 237.422613 -94.106385)
			(xy 237.371284 -94.128197) (xy 237.317327 -94.142303) (xy 237.26189 -94.148403) (xy 237.206156 -94.146366)
			(xy 237.151313 -94.136236) (xy 237.098529 -94.118229) (xy 237.048929 -94.092728) (xy 237.003571 -94.060277)
			(xy 236.963422 -94.021568) (xy 236.929336 -93.977425) (xy 236.90204 -93.92879) (xy 236.882117 -93.876699)
			(xy 236.869991 -93.822262) (xy 236.86592 -93.76664) (xy 235.917762 -93.76664) (xy 235.917994 -93.77934)
			(xy 235.917485 -93.807226) (xy 235.909365 -93.862402) (xy 235.893297 -93.915809) (xy 235.869625 -93.966306)
			(xy 235.838852 -94.012819) (xy 235.801635 -94.054356) (xy 235.758767 -94.090031) (xy 235.711161 -94.119085)
			(xy 235.659832 -94.140897) (xy 235.605875 -94.155003) (xy 235.550438 -94.161103) (xy 235.494704 -94.159066)
			(xy 235.439861 -94.148936) (xy 235.387077 -94.130929) (xy 235.337477 -94.105428) (xy 235.292119 -94.072977)
			(xy 235.25197 -94.034268) (xy 235.217884 -93.990125) (xy 235.190588 -93.94149) (xy 235.170665 -93.889399)
			(xy 235.158539 -93.834962) (xy 235.154468 -93.77934) (xy 234.43438 -93.77934) (xy 234.433871 -93.807226)
			(xy 234.425751 -93.862402) (xy 234.409683 -93.915809) (xy 234.386011 -93.966306) (xy 234.355238 -94.012819)
			(xy 234.318021 -94.054356) (xy 234.275153 -94.090031) (xy 234.227547 -94.119085) (xy 234.176218 -94.140897)
			(xy 234.122261 -94.155003) (xy 234.066824 -94.161103) (xy 234.01109 -94.159066) (xy 233.956247 -94.148936)
			(xy 233.903463 -94.130929) (xy 233.853863 -94.105428) (xy 233.808505 -94.072977) (xy 233.768356 -94.034268)
			(xy 233.73427 -93.990125) (xy 233.706974 -93.94149) (xy 233.687051 -93.889399) (xy 233.674925 -93.834962)
			(xy 233.670854 -93.77934) (xy 232.891838 -93.77934) (xy 232.891329 -93.807226) (xy 232.883209 -93.862402)
			(xy 232.867141 -93.915809) (xy 232.843469 -93.966306) (xy 232.812696 -94.012819) (xy 232.775479 -94.054356)
			(xy 232.732611 -94.090031) (xy 232.685005 -94.119085) (xy 232.633676 -94.140897) (xy 232.579719 -94.155003)
			(xy 232.524282 -94.161103) (xy 232.468548 -94.159066) (xy 232.413705 -94.148936) (xy 232.360921 -94.130929)
			(xy 232.311321 -94.105428) (xy 232.265963 -94.072977) (xy 232.225814 -94.034268) (xy 232.191728 -93.990125)
			(xy 232.164432 -93.94149) (xy 232.144509 -93.889399) (xy 232.132383 -93.834962) (xy 232.128312 -93.77934)
			(xy 227.976242 -93.77934) (xy 227.999517 -93.79871) (xy 228.036734 -93.840247) (xy 228.067507 -93.88676)
			(xy 228.091179 -93.937257) (xy 228.107247 -93.990664) (xy 228.115367 -94.04584) (xy 228.115876 -94.073726)
			(xy 228.115367 -94.101612) (xy 228.107247 -94.156788) (xy 228.091179 -94.210195) (xy 228.067507 -94.260692)
			(xy 228.036734 -94.307205) (xy 227.999517 -94.348742) (xy 227.956649 -94.384417) (xy 227.909043 -94.413471)
			(xy 227.857714 -94.435283) (xy 227.803757 -94.449389) (xy 227.74832 -94.455489) (xy 227.692586 -94.453452)
			(xy 227.637743 -94.443322) (xy 227.584959 -94.425315) (xy 227.535359 -94.399814) (xy 227.490001 -94.367363)
			(xy 227.449852 -94.328654) (xy 227.415766 -94.284511) (xy 227.38847 -94.235876) (xy 227.368547 -94.183785)
			(xy 227.356421 -94.129348) (xy 227.35235 -94.073726) (xy 210.800556 -94.073726) (xy 210.810225 -94.078736)
			(xy 210.988621 -94.180191) (xy 211.162922 -94.28853) (xy 211.332864 -94.403586) (xy 211.498187 -94.525186)
			(xy 211.65864 -94.653143) (xy 211.813979 -94.787262) (xy 211.963966 -94.927341) (xy 212.108374 -95.073165)
			(xy 212.154015 -95.123) (xy 216.555826 -95.123) (xy 216.559897 -95.067378) (xy 216.572023 -95.012941)
			(xy 216.591946 -94.96085) (xy 216.619242 -94.912215) (xy 216.653328 -94.868072) (xy 216.693477 -94.829363)
			(xy 216.738835 -94.796912) (xy 216.788435 -94.771411) (xy 216.841219 -94.753404) (xy 216.896062 -94.743274)
			(xy 216.951796 -94.741237) (xy 217.007233 -94.747337) (xy 217.06119 -94.761443) (xy 217.112519 -94.783255)
			(xy 217.160125 -94.812309) (xy 217.202993 -94.847984) (xy 217.24021 -94.889521) (xy 217.270983 -94.936034)
			(xy 217.294655 -94.986531) (xy 217.310723 -95.039938) (xy 217.318843 -95.095114) (xy 217.319352 -95.123)
			(xy 217.698826 -95.123) (xy 217.702897 -95.067378) (xy 217.715023 -95.012941) (xy 217.734946 -94.96085)
			(xy 217.762242 -94.912215) (xy 217.796328 -94.868072) (xy 217.836477 -94.829363) (xy 217.881835 -94.796912)
			(xy 217.931435 -94.771411) (xy 217.984219 -94.753404) (xy 218.039062 -94.743274) (xy 218.094796 -94.741237)
			(xy 218.150233 -94.747337) (xy 218.20419 -94.761443) (xy 218.255519 -94.783255) (xy 218.303125 -94.812309)
			(xy 218.345993 -94.847984) (xy 218.38321 -94.889521) (xy 218.413983 -94.936034) (xy 218.437655 -94.986531)
			(xy 218.453723 -95.039938) (xy 218.461843 -95.095114) (xy 218.462352 -95.123) (xy 218.841826 -95.123)
			(xy 218.845897 -95.067378) (xy 218.858023 -95.012941) (xy 218.877946 -94.96085) (xy 218.905242 -94.912215)
			(xy 218.939328 -94.868072) (xy 218.979477 -94.829363) (xy 219.024835 -94.796912) (xy 219.074435 -94.771411)
			(xy 219.127219 -94.753404) (xy 219.182062 -94.743274) (xy 219.237796 -94.741237) (xy 219.293233 -94.747337)
			(xy 219.34719 -94.761443) (xy 219.398519 -94.783255) (xy 219.446125 -94.812309) (xy 219.488993 -94.847984)
			(xy 219.52621 -94.889521) (xy 219.556983 -94.936034) (xy 219.568103 -94.959755) (xy 220.112755 -94.959755)
			(xy 220.112755 -94.905245) (xy 220.120514 -94.85129) (xy 220.135872 -94.798989) (xy 220.158518 -94.749406)
			(xy 220.18799 -94.703551) (xy 220.223688 -94.662357) (xy 220.264886 -94.626663) (xy 220.310745 -94.597196)
			(xy 220.36033 -94.574556) (xy 220.412633 -94.559204) (xy 220.466589 -94.551452) (xy 220.493844 -94.550992)
			(xy 220.520531 -94.551414) (xy 220.573382 -94.558871) (xy 220.624678 -94.573619) (xy 220.673418 -94.59537)
			(xy 220.718653 -94.623701) (xy 220.759499 -94.658057) (xy 220.79516 -94.69777) (xy 220.824939 -94.742065)
			(xy 220.836998 -94.765876) (xy 220.844112 -94.779437) (xy 220.865016 -94.8018) (xy 220.891604 -94.816971)
			(xy 220.921491 -94.823589) (xy 220.951998 -94.821062) (xy 220.980389 -94.809615) (xy 221.004118 -94.790276)
			(xy 221.01302 -94.777814) (xy 221.028267 -94.755691) (xy 221.063951 -94.715526) (xy 221.104916 -94.680761)
			(xy 221.15035 -94.652085) (xy 221.199358 -94.630064) (xy 221.250969 -94.615134) (xy 221.304164 -94.607589)
			(xy 221.331028 -94.607126) (xy 221.35828 -94.607546) (xy 221.41223 -94.615306) (xy 221.431944 -94.621096)
			(xy 229.829358 -94.621096) (xy 229.833429 -94.565474) (xy 229.845555 -94.511037) (xy 229.865478 -94.458946)
			(xy 229.892774 -94.410311) (xy 229.92686 -94.366168) (xy 229.967009 -94.327459) (xy 230.012367 -94.295008)
			(xy 230.061967 -94.269507) (xy 230.114751 -94.2515) (xy 230.169594 -94.24137) (xy 230.225328 -94.239333)
			(xy 230.280765 -94.245433) (xy 230.334722 -94.259539) (xy 230.386051 -94.281351) (xy 230.433657 -94.310405)
			(xy 230.476525 -94.34608) (xy 230.513742 -94.387617) (xy 230.544515 -94.43413) (xy 230.568187 -94.484627)
			(xy 230.584255 -94.538034) (xy 230.592375 -94.59321) (xy 230.592884 -94.621096) (xy 230.592375 -94.648982)
			(xy 230.587956 -94.679008) (xy 231.593134 -94.679008) (xy 231.597205 -94.623386) (xy 231.609331 -94.568949)
			(xy 231.629254 -94.516858) (xy 231.65655 -94.468223) (xy 231.690636 -94.42408) (xy 231.730785 -94.385371)
			(xy 231.776143 -94.35292) (xy 231.825743 -94.327419) (xy 231.878527 -94.309412) (xy 231.93337 -94.299282)
			(xy 231.989104 -94.297245) (xy 232.044541 -94.303345) (xy 232.098498 -94.317451) (xy 232.149827 -94.339263)
			(xy 232.197433 -94.368317) (xy 232.240301 -94.403992) (xy 232.277518 -94.445529) (xy 232.308291 -94.492042)
			(xy 232.331963 -94.542539) (xy 232.348031 -94.595946) (xy 232.354573 -94.6404) (xy 235.823504 -94.6404)
			(xy 235.827575 -94.584778) (xy 235.839701 -94.530341) (xy 235.859624 -94.47825) (xy 235.88692 -94.429615)
			(xy 235.921006 -94.385472) (xy 235.961155 -94.346763) (xy 236.006513 -94.314312) (xy 236.056113 -94.288811)
			(xy 236.108897 -94.270804) (xy 236.16374 -94.260674) (xy 236.219474 -94.258637) (xy 236.274911 -94.264737)
			(xy 236.328868 -94.278843) (xy 236.380197 -94.300655) (xy 236.427803 -94.329709) (xy 236.470671 -94.365384)
			(xy 236.507888 -94.406921) (xy 236.538661 -94.453434) (xy 236.562333 -94.503931) (xy 236.578401 -94.557338)
			(xy 236.586521 -94.612514) (xy 236.58703 -94.6404) (xy 236.586521 -94.668286) (xy 236.578401 -94.723462)
			(xy 236.562333 -94.776869) (xy 236.538661 -94.827366) (xy 236.507888 -94.873879) (xy 236.470671 -94.915416)
			(xy 236.427803 -94.951091) (xy 236.380197 -94.980145) (xy 236.328868 -95.001957) (xy 236.274911 -95.016063)
			(xy 236.219474 -95.022163) (xy 236.16374 -95.020126) (xy 236.108897 -95.009996) (xy 236.056113 -94.991989)
			(xy 236.006513 -94.966488) (xy 235.961155 -94.934037) (xy 235.921006 -94.895328) (xy 235.88692 -94.851185)
			(xy 235.859624 -94.80255) (xy 235.839701 -94.750459) (xy 235.827575 -94.696022) (xy 235.823504 -94.6404)
			(xy 232.354573 -94.6404) (xy 232.356151 -94.651122) (xy 232.35666 -94.679008) (xy 232.356151 -94.706894)
			(xy 232.348031 -94.76207) (xy 232.331963 -94.815477) (xy 232.308291 -94.865974) (xy 232.277518 -94.912487)
			(xy 232.240301 -94.954024) (xy 232.197433 -94.989699) (xy 232.149827 -95.018753) (xy 232.098498 -95.040565)
			(xy 232.044541 -95.054671) (xy 231.989104 -95.060771) (xy 231.93337 -95.058734) (xy 231.878527 -95.048604)
			(xy 231.825743 -95.030597) (xy 231.776143 -95.005096) (xy 231.730785 -94.972645) (xy 231.690636 -94.933936)
			(xy 231.65655 -94.889793) (xy 231.629254 -94.841158) (xy 231.609331 -94.789067) (xy 231.597205 -94.73463)
			(xy 231.593134 -94.679008) (xy 230.587956 -94.679008) (xy 230.584255 -94.704158) (xy 230.568187 -94.757565)
			(xy 230.544515 -94.808062) (xy 230.513742 -94.854575) (xy 230.476525 -94.896112) (xy 230.433657 -94.931787)
			(xy 230.386051 -94.960841) (xy 230.334722 -94.982653) (xy 230.280765 -94.996759) (xy 230.225328 -95.002859)
			(xy 230.169594 -95.000822) (xy 230.114751 -94.990692) (xy 230.061967 -94.972685) (xy 230.012367 -94.947184)
			(xy 229.967009 -94.914733) (xy 229.92686 -94.876024) (xy 229.892774 -94.831881) (xy 229.865478 -94.783246)
			(xy 229.845555 -94.731155) (xy 229.833429 -94.676718) (xy 229.829358 -94.621096) (xy 221.431944 -94.621096)
			(xy 221.464526 -94.630665) (xy 221.514104 -94.65331) (xy 221.559955 -94.68278) (xy 221.601146 -94.718474)
			(xy 221.636837 -94.759667) (xy 221.666304 -94.805521) (xy 221.688945 -94.8551) (xy 221.7043 -94.907398)
			(xy 221.712056 -94.961348) (xy 221.712056 -95.015852) (xy 221.7043 -95.069802) (xy 221.69845 -95.089726)
			(xy 227.35235 -95.089726) (xy 227.356421 -95.034104) (xy 227.368547 -94.979667) (xy 227.38847 -94.927576)
			(xy 227.415766 -94.878941) (xy 227.449852 -94.834798) (xy 227.490001 -94.796089) (xy 227.535359 -94.763638)
			(xy 227.584959 -94.738137) (xy 227.637743 -94.72013) (xy 227.692586 -94.71) (xy 227.74832 -94.707963)
			(xy 227.803757 -94.714063) (xy 227.857714 -94.728169) (xy 227.909043 -94.749981) (xy 227.956649 -94.779035)
			(xy 227.999517 -94.81471) (xy 228.036734 -94.856247) (xy 228.067507 -94.90276) (xy 228.091179 -94.953257)
			(xy 228.107247 -95.006664) (xy 228.115367 -95.06184) (xy 228.115876 -95.089726) (xy 228.115367 -95.117612)
			(xy 228.107247 -95.172788) (xy 228.091179 -95.226195) (xy 228.067507 -95.276692) (xy 228.036734 -95.323205)
			(xy 227.999517 -95.364742) (xy 227.956649 -95.400417) (xy 227.909043 -95.429471) (xy 227.857714 -95.451283)
			(xy 227.803757 -95.465389) (xy 227.74832 -95.471489) (xy 227.692586 -95.469452) (xy 227.637743 -95.459322)
			(xy 227.584959 -95.441315) (xy 227.535359 -95.415814) (xy 227.490001 -95.383363) (xy 227.449852 -95.344654)
			(xy 227.415766 -95.300511) (xy 227.38847 -95.251876) (xy 227.368547 -95.199785) (xy 227.356421 -95.145348)
			(xy 227.35235 -95.089726) (xy 221.69845 -95.089726) (xy 221.688945 -95.1221) (xy 221.666304 -95.171679)
			(xy 221.636837 -95.217533) (xy 221.601146 -95.258726) (xy 221.559955 -95.29442) (xy 221.514104 -95.32389)
			(xy 221.464526 -95.346535) (xy 221.41223 -95.361894) (xy 221.35828 -95.369654) (xy 221.331028 -95.370142)
			(xy 221.304344 -95.369641) (xy 221.251498 -95.362195) (xy 221.200204 -95.347458) (xy 221.151465 -95.325718)
			(xy 221.10623 -95.297398) (xy 221.065383 -95.263052) (xy 221.029719 -95.223349) (xy 220.999936 -95.179065)
			(xy 220.987874 -95.155258) (xy 220.9808 -95.141672) (xy 220.959891 -95.1193) (xy 220.933294 -95.104124)
			(xy 220.903396 -95.097505) (xy 220.872879 -95.100039) (xy 220.844482 -95.111496) (xy 220.820752 -95.130851)
			(xy 220.811852 -95.14332) (xy 220.796602 -95.165441) (xy 220.760921 -95.20561) (xy 220.719958 -95.240377)
			(xy 220.674523 -95.269054) (xy 220.625516 -95.291075) (xy 220.573904 -95.306005) (xy 220.520708 -95.313547)
			(xy 220.493844 -95.314008) (xy 220.466589 -95.313548) (xy 220.412633 -95.305796) (xy 220.36033 -95.290444)
			(xy 220.310745 -95.267804) (xy 220.264886 -95.238337) (xy 220.223688 -95.202643) (xy 220.18799 -95.161449)
			(xy 220.158518 -95.115594) (xy 220.135872 -95.066011) (xy 220.120514 -95.01371) (xy 220.112755 -94.959755)
			(xy 219.568103 -94.959755) (xy 219.580655 -94.986531) (xy 219.596723 -95.039938) (xy 219.604843 -95.095114)
			(xy 219.605352 -95.123) (xy 219.604843 -95.150886) (xy 219.596723 -95.206062) (xy 219.580655 -95.259469)
			(xy 219.556983 -95.309966) (xy 219.52621 -95.356479) (xy 219.488993 -95.398016) (xy 219.446125 -95.433691)
			(xy 219.398519 -95.462745) (xy 219.34719 -95.484557) (xy 219.293233 -95.498663) (xy 219.237796 -95.504763)
			(xy 219.182062 -95.502726) (xy 219.127219 -95.492596) (xy 219.074435 -95.474589) (xy 219.024835 -95.449088)
			(xy 218.979477 -95.416637) (xy 218.939328 -95.377928) (xy 218.905242 -95.333785) (xy 218.877946 -95.28515)
			(xy 218.858023 -95.233059) (xy 218.845897 -95.178622) (xy 218.841826 -95.123) (xy 218.462352 -95.123)
			(xy 218.461843 -95.150886) (xy 218.453723 -95.206062) (xy 218.437655 -95.259469) (xy 218.413983 -95.309966)
			(xy 218.38321 -95.356479) (xy 218.345993 -95.398016) (xy 218.303125 -95.433691) (xy 218.255519 -95.462745)
			(xy 218.20419 -95.484557) (xy 218.150233 -95.498663) (xy 218.094796 -95.504763) (xy 218.039062 -95.502726)
			(xy 217.984219 -95.492596) (xy 217.931435 -95.474589) (xy 217.881835 -95.449088) (xy 217.836477 -95.416637)
			(xy 217.796328 -95.377928) (xy 217.762242 -95.333785) (xy 217.734946 -95.28515) (xy 217.715023 -95.233059)
			(xy 217.702897 -95.178622) (xy 217.698826 -95.123) (xy 217.319352 -95.123) (xy 217.318843 -95.150886)
			(xy 217.310723 -95.206062) (xy 217.294655 -95.259469) (xy 217.270983 -95.309966) (xy 217.24021 -95.356479)
			(xy 217.202993 -95.398016) (xy 217.160125 -95.433691) (xy 217.112519 -95.462745) (xy 217.06119 -95.484557)
			(xy 217.007233 -95.498663) (xy 216.951796 -95.504763) (xy 216.896062 -95.502726) (xy 216.841219 -95.492596)
			(xy 216.788435 -95.474589) (xy 216.738835 -95.449088) (xy 216.693477 -95.416637) (xy 216.653328 -95.377928)
			(xy 216.619242 -95.333785) (xy 216.591946 -95.28515) (xy 216.572023 -95.233059) (xy 216.559897 -95.178622)
			(xy 216.555826 -95.123) (xy 212.154015 -95.123) (xy 212.246982 -95.224511) (xy 212.37958 -95.381151)
			(xy 212.49228 -95.525336) (xy 230.922066 -95.525336) (xy 230.926137 -95.469714) (xy 230.938263 -95.415277)
			(xy 230.958186 -95.363186) (xy 230.985482 -95.314551) (xy 231.019568 -95.270408) (xy 231.059717 -95.231699)
			(xy 231.105075 -95.199248) (xy 231.154675 -95.173747) (xy 231.207459 -95.15574) (xy 231.262302 -95.14561)
			(xy 231.318036 -95.143573) (xy 231.373473 -95.149673) (xy 231.42743 -95.163779) (xy 231.478759 -95.185591)
			(xy 231.526365 -95.214645) (xy 231.569233 -95.25032) (xy 231.60645 -95.291857) (xy 231.637223 -95.33837)
			(xy 231.660895 -95.388867) (xy 231.676963 -95.442274) (xy 231.685083 -95.49745) (xy 231.685592 -95.525336)
			(xy 231.685083 -95.553222) (xy 231.676963 -95.608398) (xy 231.660895 -95.661805) (xy 231.637223 -95.712302)
			(xy 231.60645 -95.758815) (xy 231.569233 -95.800352) (xy 231.526365 -95.836027) (xy 231.478759 -95.865081)
			(xy 231.42743 -95.886893) (xy 231.373473 -95.900999) (xy 231.318036 -95.907099) (xy 231.262302 -95.905062)
			(xy 231.207459 -95.894932) (xy 231.154675 -95.876925) (xy 231.105075 -95.851424) (xy 231.059717 -95.818973)
			(xy 231.019568 -95.780264) (xy 230.985482 -95.736121) (xy 230.958186 -95.687486) (xy 230.938263 -95.635395)
			(xy 230.926137 -95.580958) (xy 230.922066 -95.525336) (xy 212.49228 -95.525336) (xy 212.505966 -95.542845)
			(xy 212.625946 -95.709347) (xy 212.739339 -95.880403) (xy 212.780441 -95.947992) (xy 232.365802 -95.947992)
			(xy 232.369873 -95.89237) (xy 232.381999 -95.837933) (xy 232.401922 -95.785842) (xy 232.429218 -95.737207)
			(xy 232.463304 -95.693064) (xy 232.503453 -95.654355) (xy 232.548811 -95.621904) (xy 232.598411 -95.596403)
			(xy 232.651195 -95.578396) (xy 232.706038 -95.568266) (xy 232.761772 -95.566229) (xy 232.817209 -95.572329)
			(xy 232.871166 -95.586435) (xy 232.922495 -95.608247) (xy 232.970101 -95.637301) (xy 233.012969 -95.672976)
			(xy 233.050186 -95.714513) (xy 233.060136 -95.729552) (xy 233.639104 -95.729552) (xy 233.643175 -95.67393)
			(xy 233.655301 -95.619493) (xy 233.675224 -95.567402) (xy 233.70252 -95.518767) (xy 233.736606 -95.474624)
			(xy 233.776755 -95.435915) (xy 233.822113 -95.403464) (xy 233.871713 -95.377963) (xy 233.924497 -95.359956)
			(xy 233.97934 -95.349826) (xy 234.035074 -95.347789) (xy 234.090511 -95.353889) (xy 234.144468 -95.367995)
			(xy 234.195797 -95.389807) (xy 234.243403 -95.418861) (xy 234.286271 -95.454536) (xy 234.323488 -95.496073)
			(xy 234.354261 -95.542586) (xy 234.377933 -95.593083) (xy 234.394001 -95.64649) (xy 234.402121 -95.701666)
			(xy 234.402319 -95.712534) (xy 235.82452 -95.712534) (xy 235.828591 -95.656912) (xy 235.840717 -95.602475)
			(xy 235.86064 -95.550384) (xy 235.887936 -95.501749) (xy 235.922022 -95.457606) (xy 235.962171 -95.418897)
			(xy 236.007529 -95.386446) (xy 236.057129 -95.360945) (xy 236.109913 -95.342938) (xy 236.164756 -95.332808)
			(xy 236.22049 -95.330771) (xy 236.275927 -95.336871) (xy 236.329884 -95.350977) (xy 236.381213 -95.372789)
			(xy 236.428819 -95.401843) (xy 236.471687 -95.437518) (xy 236.508904 -95.479055) (xy 236.539677 -95.525568)
			(xy 236.563349 -95.576065) (xy 236.579417 -95.629472) (xy 236.587537 -95.684648) (xy 236.588046 -95.712534)
			(xy 236.587537 -95.74042) (xy 236.579417 -95.795596) (xy 236.563349 -95.849003) (xy 236.539677 -95.8995)
			(xy 236.508904 -95.946013) (xy 236.471687 -95.98755) (xy 236.428819 -96.023225) (xy 236.381213 -96.052279)
			(xy 236.329884 -96.074091) (xy 236.275927 -96.088197) (xy 236.22049 -96.094297) (xy 236.164756 -96.09226)
			(xy 236.109913 -96.08213) (xy 236.057129 -96.064123) (xy 236.007529 -96.038622) (xy 235.962171 -96.006171)
			(xy 235.922022 -95.967462) (xy 235.887936 -95.923319) (xy 235.86064 -95.874684) (xy 235.840717 -95.822593)
			(xy 235.828591 -95.768156) (xy 235.82452 -95.712534) (xy 234.402319 -95.712534) (xy 234.40263 -95.729552)
			(xy 234.402121 -95.757438) (xy 234.394001 -95.812614) (xy 234.377933 -95.866021) (xy 234.354261 -95.916518)
			(xy 234.323488 -95.963031) (xy 234.286271 -96.004568) (xy 234.243403 -96.040243) (xy 234.195797 -96.069297)
			(xy 234.144468 -96.091109) (xy 234.090511 -96.105215) (xy 234.035074 -96.111315) (xy 233.97934 -96.109278)
			(xy 233.924497 -96.099148) (xy 233.871713 -96.081141) (xy 233.822113 -96.05564) (xy 233.776755 -96.023189)
			(xy 233.736606 -95.98448) (xy 233.70252 -95.940337) (xy 233.675224 -95.891702) (xy 233.655301 -95.839611)
			(xy 233.643175 -95.785174) (xy 233.639104 -95.729552) (xy 233.060136 -95.729552) (xy 233.080959 -95.761026)
			(xy 233.104631 -95.811523) (xy 233.120699 -95.86493) (xy 233.128819 -95.920106) (xy 233.129328 -95.947992)
			(xy 233.128819 -95.975878) (xy 233.120699 -96.031054) (xy 233.104631 -96.084461) (xy 233.080959 -96.134958)
			(xy 233.050186 -96.181471) (xy 233.012969 -96.223008) (xy 232.970101 -96.258683) (xy 232.922495 -96.287737)
			(xy 232.871166 -96.309549) (xy 232.817209 -96.323655) (xy 232.761772 -96.329755) (xy 232.706038 -96.327718)
			(xy 232.651195 -96.317588) (xy 232.598411 -96.299581) (xy 232.548811 -96.27408) (xy 232.503453 -96.241629)
			(xy 232.463304 -96.20292) (xy 232.429218 -96.158777) (xy 232.401922 -96.110142) (xy 232.381999 -96.058051)
			(xy 232.369873 -96.003614) (xy 232.365802 -95.947992) (xy 212.780441 -95.947992) (xy 212.845972 -96.055753)
			(xy 212.945682 -96.23513) (xy 213.038318 -96.41826) (xy 213.123738 -96.604866) (xy 213.201812 -96.794662)
			(xy 213.272422 -96.98736) (xy 213.335459 -97.182666) (xy 213.390829 -97.380282) (xy 213.438446 -97.579909)
			(xy 213.478238 -97.781241) (xy 213.479617 -97.79) (xy 216.555826 -97.79) (xy 216.559897 -97.734378)
			(xy 216.572023 -97.679941) (xy 216.591946 -97.62785) (xy 216.619242 -97.579215) (xy 216.653328 -97.535072)
			(xy 216.693477 -97.496363) (xy 216.738835 -97.463912) (xy 216.788435 -97.438411) (xy 216.841219 -97.420404)
			(xy 216.896062 -97.410274) (xy 216.951796 -97.408237) (xy 217.007233 -97.414337) (xy 217.06119 -97.428443)
			(xy 217.112519 -97.450255) (xy 217.160125 -97.479309) (xy 217.202993 -97.514984) (xy 217.24021 -97.556521)
			(xy 217.270983 -97.603034) (xy 217.294655 -97.653531) (xy 217.310723 -97.706938) (xy 217.318843 -97.762114)
			(xy 217.319352 -97.79) (xy 217.318855 -97.817224) (xy 217.699753 -97.817224) (xy 217.699757 -97.762717)
			(xy 217.707519 -97.708766) (xy 217.72288 -97.656468) (xy 217.745527 -97.606888) (xy 217.775 -97.561037)
			(xy 217.810698 -97.519847) (xy 217.851896 -97.484156) (xy 217.897753 -97.454692) (xy 217.947337 -97.432054)
			(xy 217.999637 -97.416703) (xy 218.05359 -97.408952) (xy 218.080844 -97.408492) (xy 218.101164 -97.409)
			(xy 218.112086 -97.409508) (xy 218.132152 -97.401888) (xy 218.200732 -97.333308) (xy 218.208352 -97.313242)
			(xy 218.207844 -97.30232) (xy 218.207336 -97.282) (xy 218.207778 -97.254749) (xy 218.215534 -97.200803)
			(xy 218.230888 -97.148509) (xy 218.253528 -97.098933) (xy 218.282993 -97.053083) (xy 218.318683 -97.011894)
			(xy 218.359872 -96.976202) (xy 218.40572 -96.946735) (xy 218.455296 -96.924093) (xy 218.507589 -96.908737)
			(xy 218.561535 -96.900979) (xy 218.616036 -96.900977) (xy 218.669983 -96.908731) (xy 218.722277 -96.924083)
			(xy 218.771854 -96.946721) (xy 218.817705 -96.976184) (xy 218.858896 -97.011873) (xy 218.894589 -97.05306)
			(xy 218.924058 -97.098907) (xy 218.946701 -97.148482) (xy 218.96206 -97.200774) (xy 218.96982 -97.25472)
			(xy 218.969824 -97.309221) (xy 218.962072 -97.363168) (xy 218.946722 -97.415463) (xy 218.924086 -97.465041)
			(xy 218.894624 -97.510893) (xy 218.872873 -97.536) (xy 219.095826 -97.536) (xy 219.099897 -97.480378)
			(xy 219.112023 -97.425941) (xy 219.131946 -97.37385) (xy 219.159242 -97.325215) (xy 219.193328 -97.281072)
			(xy 219.233477 -97.242363) (xy 219.278835 -97.209912) (xy 219.328435 -97.184411) (xy 219.381219 -97.166404)
			(xy 219.436062 -97.156274) (xy 219.491796 -97.154237) (xy 219.547233 -97.160337) (xy 219.60119 -97.174443)
			(xy 219.652519 -97.196255) (xy 219.700125 -97.225309) (xy 219.742993 -97.260984) (xy 219.78021 -97.302521)
			(xy 219.787639 -97.31375) (xy 221.292926 -97.31375) (xy 221.296997 -97.258128) (xy 221.309123 -97.203691)
			(xy 221.329046 -97.1516) (xy 221.356342 -97.102965) (xy 221.390428 -97.058822) (xy 221.430577 -97.020113)
			(xy 221.475935 -96.987662) (xy 221.525535 -96.962161) (xy 221.578319 -96.944154) (xy 221.633162 -96.934024)
			(xy 221.688896 -96.931987) (xy 221.744333 -96.938087) (xy 221.79829 -96.952193) (xy 221.849619 -96.974005)
			(xy 221.897225 -97.003059) (xy 221.940093 -97.038734) (xy 221.97731 -97.080271) (xy 222.008083 -97.126784)
			(xy 222.031755 -97.177281) (xy 222.047823 -97.230688) (xy 222.055943 -97.285864) (xy 222.056452 -97.31375)
			(xy 222.308926 -97.31375) (xy 222.312997 -97.258128) (xy 222.325123 -97.203691) (xy 222.345046 -97.1516)
			(xy 222.372342 -97.102965) (xy 222.406428 -97.058822) (xy 222.446577 -97.020113) (xy 222.491935 -96.987662)
			(xy 222.541535 -96.962161) (xy 222.594319 -96.944154) (xy 222.649162 -96.934024) (xy 222.704896 -96.931987)
			(xy 222.760333 -96.938087) (xy 222.81429 -96.952193) (xy 222.865619 -96.974005) (xy 222.913225 -97.003059)
			(xy 222.956093 -97.038734) (xy 222.99331 -97.080271) (xy 223.024083 -97.126784) (xy 223.047755 -97.177281)
			(xy 223.063823 -97.230688) (xy 223.071943 -97.285864) (xy 223.072452 -97.31375) (xy 223.324926 -97.31375)
			(xy 223.328997 -97.258128) (xy 223.341123 -97.203691) (xy 223.361046 -97.1516) (xy 223.388342 -97.102965)
			(xy 223.422428 -97.058822) (xy 223.462577 -97.020113) (xy 223.507935 -96.987662) (xy 223.557535 -96.962161)
			(xy 223.610319 -96.944154) (xy 223.665162 -96.934024) (xy 223.720896 -96.931987) (xy 223.776333 -96.938087)
			(xy 223.83029 -96.952193) (xy 223.881619 -96.974005) (xy 223.929225 -97.003059) (xy 223.972093 -97.038734)
			(xy 224.00931 -97.080271) (xy 224.040083 -97.126784) (xy 224.063755 -97.177281) (xy 224.079823 -97.230688)
			(xy 224.087943 -97.285864) (xy 224.088452 -97.31375) (xy 224.340926 -97.31375) (xy 224.344997 -97.258128)
			(xy 224.357123 -97.203691) (xy 224.377046 -97.1516) (xy 224.404342 -97.102965) (xy 224.438428 -97.058822)
			(xy 224.478577 -97.020113) (xy 224.523935 -96.987662) (xy 224.573535 -96.962161) (xy 224.626319 -96.944154)
			(xy 224.681162 -96.934024) (xy 224.736896 -96.931987) (xy 224.792333 -96.938087) (xy 224.84629 -96.952193)
			(xy 224.897619 -96.974005) (xy 224.945225 -97.003059) (xy 224.988093 -97.038734) (xy 225.02531 -97.080271)
			(xy 225.056083 -97.126784) (xy 225.079755 -97.177281) (xy 225.095823 -97.230688) (xy 225.103943 -97.285864)
			(xy 225.104452 -97.31375) (xy 225.356926 -97.31375) (xy 225.360997 -97.258128) (xy 225.373123 -97.203691)
			(xy 225.393046 -97.1516) (xy 225.420342 -97.102965) (xy 225.454428 -97.058822) (xy 225.494577 -97.020113)
			(xy 225.539935 -96.987662) (xy 225.589535 -96.962161) (xy 225.642319 -96.944154) (xy 225.697162 -96.934024)
			(xy 225.752896 -96.931987) (xy 225.808333 -96.938087) (xy 225.86229 -96.952193) (xy 225.913619 -96.974005)
			(xy 225.961225 -97.003059) (xy 226.004093 -97.038734) (xy 226.04131 -97.080271) (xy 226.072083 -97.126784)
			(xy 226.095755 -97.177281) (xy 226.111823 -97.230688) (xy 226.119943 -97.285864) (xy 226.120452 -97.31375)
			(xy 226.626926 -97.31375) (xy 226.630997 -97.258128) (xy 226.643123 -97.203691) (xy 226.663046 -97.1516)
			(xy 226.690342 -97.102965) (xy 226.724428 -97.058822) (xy 226.764577 -97.020113) (xy 226.809935 -96.987662)
			(xy 226.859535 -96.962161) (xy 226.912319 -96.944154) (xy 226.967162 -96.934024) (xy 227.022896 -96.931987)
			(xy 227.078333 -96.938087) (xy 227.13229 -96.952193) (xy 227.183619 -96.974005) (xy 227.231225 -97.003059)
			(xy 227.274093 -97.038734) (xy 227.31131 -97.080271) (xy 227.342083 -97.126784) (xy 227.365755 -97.177281)
			(xy 227.381823 -97.230688) (xy 227.389943 -97.285864) (xy 227.390452 -97.31375) (xy 227.642926 -97.31375)
			(xy 227.646997 -97.258128) (xy 227.659123 -97.203691) (xy 227.679046 -97.1516) (xy 227.706342 -97.102965)
			(xy 227.740428 -97.058822) (xy 227.780577 -97.020113) (xy 227.825935 -96.987662) (xy 227.875535 -96.962161)
			(xy 227.928319 -96.944154) (xy 227.983162 -96.934024) (xy 228.038896 -96.931987) (xy 228.094333 -96.938087)
			(xy 228.14829 -96.952193) (xy 228.199619 -96.974005) (xy 228.247225 -97.003059) (xy 228.290093 -97.038734)
			(xy 228.32731 -97.080271) (xy 228.358083 -97.126784) (xy 228.381755 -97.177281) (xy 228.397823 -97.230688)
			(xy 228.405943 -97.285864) (xy 228.406452 -97.31375) (xy 228.405943 -97.341636) (xy 228.397823 -97.396812)
			(xy 228.381755 -97.450219) (xy 228.358083 -97.500716) (xy 228.32731 -97.547229) (xy 228.290093 -97.588766)
			(xy 228.247225 -97.624441) (xy 228.199619 -97.653495) (xy 228.14829 -97.675307) (xy 228.094333 -97.689413)
			(xy 228.038896 -97.695513) (xy 227.983162 -97.693476) (xy 227.928319 -97.683346) (xy 227.875535 -97.665339)
			(xy 227.825935 -97.639838) (xy 227.780577 -97.607387) (xy 227.740428 -97.568678) (xy 227.706342 -97.524535)
			(xy 227.679046 -97.4759) (xy 227.659123 -97.423809) (xy 227.646997 -97.369372) (xy 227.642926 -97.31375)
			(xy 227.390452 -97.31375) (xy 227.389943 -97.341636) (xy 227.381823 -97.396812) (xy 227.365755 -97.450219)
			(xy 227.342083 -97.500716) (xy 227.31131 -97.547229) (xy 227.274093 -97.588766) (xy 227.231225 -97.624441)
			(xy 227.183619 -97.653495) (xy 227.13229 -97.675307) (xy 227.078333 -97.689413) (xy 227.022896 -97.695513)
			(xy 226.967162 -97.693476) (xy 226.912319 -97.683346) (xy 226.859535 -97.665339) (xy 226.809935 -97.639838)
			(xy 226.764577 -97.607387) (xy 226.724428 -97.568678) (xy 226.690342 -97.524535) (xy 226.663046 -97.4759)
			(xy 226.643123 -97.423809) (xy 226.630997 -97.369372) (xy 226.626926 -97.31375) (xy 226.120452 -97.31375)
			(xy 226.119943 -97.341636) (xy 226.111823 -97.396812) (xy 226.095755 -97.450219) (xy 226.072083 -97.500716)
			(xy 226.04131 -97.547229) (xy 226.004093 -97.588766) (xy 225.961225 -97.624441) (xy 225.913619 -97.653495)
			(xy 225.86229 -97.675307) (xy 225.808333 -97.689413) (xy 225.752896 -97.695513) (xy 225.697162 -97.693476)
			(xy 225.642319 -97.683346) (xy 225.589535 -97.665339) (xy 225.539935 -97.639838) (xy 225.494577 -97.607387)
			(xy 225.454428 -97.568678) (xy 225.420342 -97.524535) (xy 225.393046 -97.4759) (xy 225.373123 -97.423809)
			(xy 225.360997 -97.369372) (xy 225.356926 -97.31375) (xy 225.104452 -97.31375) (xy 225.103943 -97.341636)
			(xy 225.095823 -97.396812) (xy 225.079755 -97.450219) (xy 225.056083 -97.500716) (xy 225.02531 -97.547229)
			(xy 224.988093 -97.588766) (xy 224.945225 -97.624441) (xy 224.897619 -97.653495) (xy 224.84629 -97.675307)
			(xy 224.792333 -97.689413) (xy 224.736896 -97.695513) (xy 224.681162 -97.693476) (xy 224.626319 -97.683346)
			(xy 224.573535 -97.665339) (xy 224.523935 -97.639838) (xy 224.478577 -97.607387) (xy 224.438428 -97.568678)
			(xy 224.404342 -97.524535) (xy 224.377046 -97.4759) (xy 224.357123 -97.423809) (xy 224.344997 -97.369372)
			(xy 224.340926 -97.31375) (xy 224.088452 -97.31375) (xy 224.087943 -97.341636) (xy 224.079823 -97.396812)
			(xy 224.063755 -97.450219) (xy 224.040083 -97.500716) (xy 224.00931 -97.547229) (xy 223.972093 -97.588766)
			(xy 223.929225 -97.624441) (xy 223.881619 -97.653495) (xy 223.83029 -97.675307) (xy 223.776333 -97.689413)
			(xy 223.720896 -97.695513) (xy 223.665162 -97.693476) (xy 223.610319 -97.683346) (xy 223.557535 -97.665339)
			(xy 223.507935 -97.639838) (xy 223.462577 -97.607387) (xy 223.422428 -97.568678) (xy 223.388342 -97.524535)
			(xy 223.361046 -97.4759) (xy 223.341123 -97.423809) (xy 223.328997 -97.369372) (xy 223.324926 -97.31375)
			(xy 223.072452 -97.31375) (xy 223.071943 -97.341636) (xy 223.063823 -97.396812) (xy 223.047755 -97.450219)
			(xy 223.024083 -97.500716) (xy 222.99331 -97.547229) (xy 222.956093 -97.588766) (xy 222.913225 -97.624441)
			(xy 222.865619 -97.653495) (xy 222.81429 -97.675307) (xy 222.760333 -97.689413) (xy 222.704896 -97.695513)
			(xy 222.649162 -97.693476) (xy 222.594319 -97.683346) (xy 222.541535 -97.665339) (xy 222.491935 -97.639838)
			(xy 222.446577 -97.607387) (xy 222.406428 -97.568678) (xy 222.372342 -97.524535) (xy 222.345046 -97.4759)
			(xy 222.325123 -97.423809) (xy 222.312997 -97.369372) (xy 222.308926 -97.31375) (xy 222.056452 -97.31375)
			(xy 222.055943 -97.341636) (xy 222.047823 -97.396812) (xy 222.031755 -97.450219) (xy 222.008083 -97.500716)
			(xy 221.97731 -97.547229) (xy 221.940093 -97.588766) (xy 221.897225 -97.624441) (xy 221.849619 -97.653495)
			(xy 221.79829 -97.675307) (xy 221.744333 -97.689413) (xy 221.688896 -97.695513) (xy 221.633162 -97.693476)
			(xy 221.578319 -97.683346) (xy 221.525535 -97.665339) (xy 221.475935 -97.639838) (xy 221.430577 -97.607387)
			(xy 221.390428 -97.568678) (xy 221.356342 -97.524535) (xy 221.329046 -97.4759) (xy 221.309123 -97.423809)
			(xy 221.296997 -97.369372) (xy 221.292926 -97.31375) (xy 219.787639 -97.31375) (xy 219.810983 -97.349034)
			(xy 219.834655 -97.399531) (xy 219.850723 -97.452938) (xy 219.858843 -97.508114) (xy 219.859352 -97.536)
			(xy 219.858843 -97.563886) (xy 219.850723 -97.619062) (xy 219.834655 -97.672469) (xy 219.810983 -97.722966)
			(xy 219.78021 -97.769479) (xy 219.761823 -97.79) (xy 219.984826 -97.79) (xy 219.988897 -97.734378)
			(xy 220.001023 -97.679941) (xy 220.020946 -97.62785) (xy 220.048242 -97.579215) (xy 220.082328 -97.535072)
			(xy 220.122477 -97.496363) (xy 220.167835 -97.463912) (xy 220.217435 -97.438411) (xy 220.270219 -97.420404)
			(xy 220.325062 -97.410274) (xy 220.380796 -97.408237) (xy 220.436233 -97.414337) (xy 220.49019 -97.428443)
			(xy 220.541519 -97.450255) (xy 220.589125 -97.479309) (xy 220.631993 -97.514984) (xy 220.66921 -97.556521)
			(xy 220.699983 -97.603034) (xy 220.723655 -97.653531) (xy 220.739723 -97.706938) (xy 220.747843 -97.762114)
			(xy 220.748352 -97.79) (xy 220.747843 -97.817886) (xy 220.739723 -97.873062) (xy 220.723655 -97.926469)
			(xy 220.699983 -97.976966) (xy 220.66921 -98.023479) (xy 220.631993 -98.065016) (xy 220.589125 -98.100691)
			(xy 220.541519 -98.129745) (xy 220.49019 -98.151557) (xy 220.436233 -98.165663) (xy 220.380796 -98.171763)
			(xy 220.325062 -98.169726) (xy 220.270219 -98.159596) (xy 220.217435 -98.141589) (xy 220.167835 -98.116088)
			(xy 220.122477 -98.083637) (xy 220.082328 -98.044928) (xy 220.048242 -98.000785) (xy 220.020946 -97.95215)
			(xy 220.001023 -97.900059) (xy 219.988897 -97.845622) (xy 219.984826 -97.79) (xy 219.761823 -97.79)
			(xy 219.742993 -97.811016) (xy 219.700125 -97.846691) (xy 219.652519 -97.875745) (xy 219.60119 -97.897557)
			(xy 219.547233 -97.911663) (xy 219.491796 -97.917763) (xy 219.436062 -97.915726) (xy 219.381219 -97.905596)
			(xy 219.328435 -97.887589) (xy 219.278835 -97.862088) (xy 219.233477 -97.829637) (xy 219.193328 -97.790928)
			(xy 219.159242 -97.746785) (xy 219.131946 -97.69815) (xy 219.112023 -97.646059) (xy 219.099897 -97.591622)
			(xy 219.095826 -97.536) (xy 218.872873 -97.536) (xy 218.858938 -97.552086) (xy 218.817752 -97.58778)
			(xy 218.771906 -97.617251) (xy 218.722332 -97.639896) (xy 218.67004 -97.655257) (xy 218.616095 -97.663019)
			(xy 218.588844 -97.663508) (xy 218.568524 -97.663) (xy 218.557602 -97.662492) (xy 218.537536 -97.670112)
			(xy 218.468956 -97.738692) (xy 218.461336 -97.758758) (xy 218.461844 -97.76968) (xy 218.462352 -97.79)
			(xy 218.461845 -97.817254) (xy 218.454087 -97.871206) (xy 218.43873 -97.923505) (xy 218.416087 -97.973086)
			(xy 218.386618 -98.01894) (xy 218.350922 -98.060133) (xy 218.309728 -98.095826) (xy 218.263873 -98.125294)
			(xy 218.214291 -98.147936) (xy 218.161991 -98.16329) (xy 218.108039 -98.171046) (xy 218.053532 -98.171044)
			(xy 217.99958 -98.163284) (xy 217.947282 -98.147925) (xy 217.897701 -98.12528) (xy 217.851849 -98.095809)
			(xy 217.810657 -98.060112) (xy 217.774965 -98.018916) (xy 217.745499 -97.97306) (xy 217.722859 -97.923477)
			(xy 217.707506 -97.871177) (xy 217.699753 -97.817224) (xy 217.318855 -97.817224) (xy 217.318843 -97.817886)
			(xy 217.310723 -97.873062) (xy 217.294655 -97.926469) (xy 217.270983 -97.976966) (xy 217.24021 -98.023479)
			(xy 217.202993 -98.065016) (xy 217.160125 -98.100691) (xy 217.112519 -98.129745) (xy 217.06119 -98.151557)
			(xy 217.007233 -98.165663) (xy 216.951796 -98.171763) (xy 216.896062 -98.169726) (xy 216.841219 -98.159596)
			(xy 216.788435 -98.141589) (xy 216.738835 -98.116088) (xy 216.693477 -98.083637) (xy 216.653328 -98.044928)
			(xy 216.619242 -98.000785) (xy 216.591946 -97.95215) (xy 216.572023 -97.900059) (xy 216.559897 -97.845622)
			(xy 216.555826 -97.79) (xy 213.479617 -97.79) (xy 213.510145 -97.983973) (xy 213.534118 -98.187795)
			(xy 213.55012 -98.392398) (xy 213.551234 -98.420936) (xy 225.995736 -98.420936) (xy 225.999807 -98.365314)
			(xy 226.011933 -98.310877) (xy 226.031856 -98.258786) (xy 226.059152 -98.210151) (xy 226.093238 -98.166008)
			(xy 226.133387 -98.127299) (xy 226.178745 -98.094848) (xy 226.228345 -98.069347) (xy 226.281129 -98.05134)
			(xy 226.335972 -98.04121) (xy 226.391706 -98.039173) (xy 226.447143 -98.045273) (xy 226.5011 -98.059379)
			(xy 226.552429 -98.081191) (xy 226.600035 -98.110245) (xy 226.642903 -98.14592) (xy 226.68012 -98.187457)
			(xy 226.710893 -98.23397) (xy 226.734565 -98.284467) (xy 226.738025 -98.295968) (xy 231.03027 -98.295968)
			(xy 231.034341 -98.240346) (xy 231.046467 -98.185909) (xy 231.06639 -98.133818) (xy 231.093686 -98.085183)
			(xy 231.127772 -98.04104) (xy 231.167921 -98.002331) (xy 231.213279 -97.96988) (xy 231.262879 -97.944379)
			(xy 231.315663 -97.926372) (xy 231.370506 -97.916242) (xy 231.42624 -97.914205) (xy 231.481677 -97.920305)
			(xy 231.535634 -97.934411) (xy 231.586963 -97.956223) (xy 231.634569 -97.985277) (xy 231.677437 -98.020952)
			(xy 231.714654 -98.062489) (xy 231.745427 -98.109002) (xy 231.769099 -98.159499) (xy 231.785167 -98.212906)
			(xy 231.793287 -98.268082) (xy 231.793796 -98.295968) (xy 232.04627 -98.295968) (xy 232.050341 -98.240346)
			(xy 232.062467 -98.185909) (xy 232.08239 -98.133818) (xy 232.109686 -98.085183) (xy 232.143772 -98.04104)
			(xy 232.183921 -98.002331) (xy 232.229279 -97.96988) (xy 232.278879 -97.944379) (xy 232.331663 -97.926372)
			(xy 232.386506 -97.916242) (xy 232.44224 -97.914205) (xy 232.497677 -97.920305) (xy 232.551634 -97.934411)
			(xy 232.602963 -97.956223) (xy 232.650569 -97.985277) (xy 232.693437 -98.020952) (xy 232.730654 -98.062489)
			(xy 232.761427 -98.109002) (xy 232.785099 -98.159499) (xy 232.801167 -98.212906) (xy 232.809287 -98.268082)
			(xy 232.809796 -98.295968) (xy 233.06227 -98.295968) (xy 233.066341 -98.240346) (xy 233.078467 -98.185909)
			(xy 233.09839 -98.133818) (xy 233.125686 -98.085183) (xy 233.159772 -98.04104) (xy 233.199921 -98.002331)
			(xy 233.245279 -97.96988) (xy 233.294879 -97.944379) (xy 233.347663 -97.926372) (xy 233.402506 -97.916242)
			(xy 233.45824 -97.914205) (xy 233.513677 -97.920305) (xy 233.567634 -97.934411) (xy 233.618963 -97.956223)
			(xy 233.666569 -97.985277) (xy 233.709437 -98.020952) (xy 233.746654 -98.062489) (xy 233.777427 -98.109002)
			(xy 233.801099 -98.159499) (xy 233.817167 -98.212906) (xy 233.825287 -98.268082) (xy 233.825796 -98.295968)
			(xy 234.07827 -98.295968) (xy 234.082341 -98.240346) (xy 234.094467 -98.185909) (xy 234.11439 -98.133818)
			(xy 234.141686 -98.085183) (xy 234.175772 -98.04104) (xy 234.215921 -98.002331) (xy 234.261279 -97.96988)
			(xy 234.310879 -97.944379) (xy 234.363663 -97.926372) (xy 234.418506 -97.916242) (xy 234.47424 -97.914205)
			(xy 234.529677 -97.920305) (xy 234.583634 -97.934411) (xy 234.634963 -97.956223) (xy 234.682569 -97.985277)
			(xy 234.725437 -98.020952) (xy 234.762654 -98.062489) (xy 234.793427 -98.109002) (xy 234.817099 -98.159499)
			(xy 234.833167 -98.212906) (xy 234.841287 -98.268082) (xy 234.841796 -98.295968) (xy 235.09427 -98.295968)
			(xy 235.098341 -98.240346) (xy 235.110467 -98.185909) (xy 235.13039 -98.133818) (xy 235.157686 -98.085183)
			(xy 235.191772 -98.04104) (xy 235.231921 -98.002331) (xy 235.277279 -97.96988) (xy 235.326879 -97.944379)
			(xy 235.379663 -97.926372) (xy 235.434506 -97.916242) (xy 235.49024 -97.914205) (xy 235.545677 -97.920305)
			(xy 235.599634 -97.934411) (xy 235.650963 -97.956223) (xy 235.698569 -97.985277) (xy 235.741437 -98.020952)
			(xy 235.778654 -98.062489) (xy 235.809427 -98.109002) (xy 235.833099 -98.159499) (xy 235.849167 -98.212906)
			(xy 235.857287 -98.268082) (xy 235.857796 -98.295968) (xy 236.11027 -98.295968) (xy 236.114341 -98.240346)
			(xy 236.126467 -98.185909) (xy 236.14639 -98.133818) (xy 236.173686 -98.085183) (xy 236.207772 -98.04104)
			(xy 236.247921 -98.002331) (xy 236.293279 -97.96988) (xy 236.342879 -97.944379) (xy 236.395663 -97.926372)
			(xy 236.450506 -97.916242) (xy 236.50624 -97.914205) (xy 236.561677 -97.920305) (xy 236.615634 -97.934411)
			(xy 236.666963 -97.956223) (xy 236.714569 -97.985277) (xy 236.757437 -98.020952) (xy 236.794654 -98.062489)
			(xy 236.825427 -98.109002) (xy 236.849099 -98.159499) (xy 236.865167 -98.212906) (xy 236.873287 -98.268082)
			(xy 236.873796 -98.295968) (xy 236.873287 -98.323854) (xy 236.865167 -98.37903) (xy 236.849099 -98.432437)
			(xy 236.825427 -98.482934) (xy 236.794654 -98.529447) (xy 236.757437 -98.570984) (xy 236.714569 -98.606659)
			(xy 236.666963 -98.635713) (xy 236.615634 -98.657525) (xy 236.561677 -98.671631) (xy 236.50624 -98.677731)
			(xy 236.450506 -98.675694) (xy 236.395663 -98.665564) (xy 236.342879 -98.647557) (xy 236.293279 -98.622056)
			(xy 236.247921 -98.589605) (xy 236.207772 -98.550896) (xy 236.173686 -98.506753) (xy 236.14639 -98.458118)
			(xy 236.126467 -98.406027) (xy 236.114341 -98.35159) (xy 236.11027 -98.295968) (xy 235.857796 -98.295968)
			(xy 235.857287 -98.323854) (xy 235.849167 -98.37903) (xy 235.833099 -98.432437) (xy 235.809427 -98.482934)
			(xy 235.778654 -98.529447) (xy 235.741437 -98.570984) (xy 235.698569 -98.606659) (xy 235.650963 -98.635713)
			(xy 235.599634 -98.657525) (xy 235.545677 -98.671631) (xy 235.49024 -98.677731) (xy 235.434506 -98.675694)
			(xy 235.379663 -98.665564) (xy 235.326879 -98.647557) (xy 235.277279 -98.622056) (xy 235.231921 -98.589605)
			(xy 235.191772 -98.550896) (xy 235.157686 -98.506753) (xy 235.13039 -98.458118) (xy 235.110467 -98.406027)
			(xy 235.098341 -98.35159) (xy 235.09427 -98.295968) (xy 234.841796 -98.295968) (xy 234.841287 -98.323854)
			(xy 234.833167 -98.37903) (xy 234.817099 -98.432437) (xy 234.793427 -98.482934) (xy 234.762654 -98.529447)
			(xy 234.725437 -98.570984) (xy 234.682569 -98.606659) (xy 234.634963 -98.635713) (xy 234.583634 -98.657525)
			(xy 234.529677 -98.671631) (xy 234.47424 -98.677731) (xy 234.418506 -98.675694) (xy 234.363663 -98.665564)
			(xy 234.310879 -98.647557) (xy 234.261279 -98.622056) (xy 234.215921 -98.589605) (xy 234.175772 -98.550896)
			(xy 234.141686 -98.506753) (xy 234.11439 -98.458118) (xy 234.094467 -98.406027) (xy 234.082341 -98.35159)
			(xy 234.07827 -98.295968) (xy 233.825796 -98.295968) (xy 233.825287 -98.323854) (xy 233.817167 -98.37903)
			(xy 233.801099 -98.432437) (xy 233.777427 -98.482934) (xy 233.746654 -98.529447) (xy 233.709437 -98.570984)
			(xy 233.666569 -98.606659) (xy 233.618963 -98.635713) (xy 233.567634 -98.657525) (xy 233.513677 -98.671631)
			(xy 233.45824 -98.677731) (xy 233.402506 -98.675694) (xy 233.347663 -98.665564) (xy 233.294879 -98.647557)
			(xy 233.245279 -98.622056) (xy 233.199921 -98.589605) (xy 233.159772 -98.550896) (xy 233.125686 -98.506753)
			(xy 233.09839 -98.458118) (xy 233.078467 -98.406027) (xy 233.066341 -98.35159) (xy 233.06227 -98.295968)
			(xy 232.809796 -98.295968) (xy 232.809287 -98.323854) (xy 232.801167 -98.37903) (xy 232.785099 -98.432437)
			(xy 232.761427 -98.482934) (xy 232.730654 -98.529447) (xy 232.693437 -98.570984) (xy 232.650569 -98.606659)
			(xy 232.602963 -98.635713) (xy 232.551634 -98.657525) (xy 232.497677 -98.671631) (xy 232.44224 -98.677731)
			(xy 232.386506 -98.675694) (xy 232.331663 -98.665564) (xy 232.278879 -98.647557) (xy 232.229279 -98.622056)
			(xy 232.183921 -98.589605) (xy 232.143772 -98.550896) (xy 232.109686 -98.506753) (xy 232.08239 -98.458118)
			(xy 232.062467 -98.406027) (xy 232.050341 -98.35159) (xy 232.04627 -98.295968) (xy 231.793796 -98.295968)
			(xy 231.793287 -98.323854) (xy 231.785167 -98.37903) (xy 231.769099 -98.432437) (xy 231.745427 -98.482934)
			(xy 231.714654 -98.529447) (xy 231.677437 -98.570984) (xy 231.634569 -98.606659) (xy 231.586963 -98.635713)
			(xy 231.535634 -98.657525) (xy 231.481677 -98.671631) (xy 231.42624 -98.677731) (xy 231.370506 -98.675694)
			(xy 231.315663 -98.665564) (xy 231.262879 -98.647557) (xy 231.213279 -98.622056) (xy 231.167921 -98.589605)
			(xy 231.127772 -98.550896) (xy 231.093686 -98.506753) (xy 231.06639 -98.458118) (xy 231.046467 -98.406027)
			(xy 231.034341 -98.35159) (xy 231.03027 -98.295968) (xy 226.738025 -98.295968) (xy 226.750633 -98.337874)
			(xy 226.758753 -98.39305) (xy 226.759262 -98.420936) (xy 226.758753 -98.448822) (xy 226.750633 -98.503998)
			(xy 226.734565 -98.557405) (xy 226.710893 -98.607902) (xy 226.68012 -98.654415) (xy 226.642903 -98.695952)
			(xy 226.63794 -98.700082) (xy 254.040902 -98.700082) (xy 254.044906 -98.494894) (xy 254.056913 -98.290018)
			(xy 254.076904 -98.085767) (xy 254.104849 -97.882452) (xy 254.140705 -97.680381) (xy 254.184419 -97.479863)
			(xy 254.235922 -97.281204) (xy 254.295137 -97.084705) (xy 254.361973 -96.890666) (xy 254.436329 -96.699383)
			(xy 254.518092 -96.511146) (xy 254.607137 -96.326243) (xy 254.703328 -96.144955) (xy 254.806519 -95.967558)
			(xy 254.916553 -95.794321) (xy 255.033262 -95.62551) (xy 255.156468 -95.461381) (xy 255.285985 -95.302184)
			(xy 255.421614 -95.148162) (xy 255.563149 -94.999548) (xy 255.710374 -94.85657) (xy 255.863066 -94.719445)
			(xy 256.020992 -94.588381) (xy 256.183911 -94.463579) (xy 256.351576 -94.345229) (xy 256.52373 -94.23351)
			(xy 256.700112 -94.128593) (xy 256.880453 -94.030638) (xy 257.064479 -93.939794) (xy 257.251909 -93.856198)
			(xy 257.442458 -93.779979) (xy 257.635835 -93.711253) (xy 257.831747 -93.650124) (xy 258.029894 -93.596685)
			(xy 258.229976 -93.551018) (xy 258.431687 -93.513191) (xy 258.63472 -93.483264) (xy 258.838767 -93.461281)
			(xy 259.043516 -93.447276) (xy 259.248655 -93.44127) (xy 259.453872 -93.443272) (xy 259.658855 -93.45328)
			(xy 259.863292 -93.471277) (xy 260.06687 -93.497237) (xy 260.269281 -93.53112) (xy 260.470215 -93.572875)
			(xy 260.669368 -93.622438) (xy 260.866435 -93.679733) (xy 261.061117 -93.744673) (xy 261.253117 -93.817159)
			(xy 261.442142 -93.897082) (xy 261.627905 -93.984318) (xy 261.810123 -94.078736) (xy 261.988519 -94.180191)
			(xy 262.16282 -94.28853) (xy 262.332762 -94.403586) (xy 262.498085 -94.525186) (xy 262.658538 -94.653143)
			(xy 262.813877 -94.787262) (xy 262.963864 -94.927341) (xy 263.108272 -95.073165) (xy 263.24688 -95.224511)
			(xy 263.379478 -95.381151) (xy 263.505864 -95.542845) (xy 263.625844 -95.709347) (xy 263.739237 -95.880403)
			(xy 263.84587 -96.055753) (xy 263.906263 -96.1644) (xy 269.425418 -96.1644) (xy 269.429489 -96.108778)
			(xy 269.441615 -96.054341) (xy 269.461538 -96.00225) (xy 269.488834 -95.953615) (xy 269.52292 -95.909472)
			(xy 269.563069 -95.870763) (xy 269.608427 -95.838312) (xy 269.658027 -95.812811) (xy 269.710811 -95.794804)
			(xy 269.765654 -95.784674) (xy 269.821388 -95.782637) (xy 269.876825 -95.788737) (xy 269.930782 -95.802843)
			(xy 269.982111 -95.824655) (xy 270.029717 -95.853709) (xy 270.072585 -95.889384) (xy 270.109802 -95.930921)
			(xy 270.140575 -95.977434) (xy 270.164247 -96.027931) (xy 270.180315 -96.081338) (xy 270.188435 -96.136514)
			(xy 270.188944 -96.1644) (xy 270.188435 -96.192286) (xy 270.180315 -96.247462) (xy 270.164247 -96.300869)
			(xy 270.140575 -96.351366) (xy 270.109802 -96.397879) (xy 270.072585 -96.439416) (xy 270.029717 -96.475091)
			(xy 269.982111 -96.504145) (xy 269.930782 -96.525957) (xy 269.876825 -96.540063) (xy 269.821388 -96.546163)
			(xy 269.765654 -96.544126) (xy 269.710811 -96.533996) (xy 269.658027 -96.515989) (xy 269.608427 -96.490488)
			(xy 269.563069 -96.458037) (xy 269.52292 -96.419328) (xy 269.488834 -96.375185) (xy 269.461538 -96.32655)
			(xy 269.441615 -96.274459) (xy 269.429489 -96.220022) (xy 269.425418 -96.1644) (xy 263.906263 -96.1644)
			(xy 263.94558 -96.23513) (xy 264.038216 -96.41826) (xy 264.123636 -96.604866) (xy 264.20171 -96.794662)
			(xy 264.27232 -96.98736) (xy 264.334626 -97.1804) (xy 269.425418 -97.1804) (xy 269.429489 -97.124778)
			(xy 269.441615 -97.070341) (xy 269.461538 -97.01825) (xy 269.488834 -96.969615) (xy 269.52292 -96.925472)
			(xy 269.563069 -96.886763) (xy 269.608427 -96.854312) (xy 269.658027 -96.828811) (xy 269.710811 -96.810804)
			(xy 269.765654 -96.800674) (xy 269.821388 -96.798637) (xy 269.876825 -96.804737) (xy 269.930782 -96.818843)
			(xy 269.982111 -96.840655) (xy 270.029717 -96.869709) (xy 270.072585 -96.905384) (xy 270.109802 -96.946921)
			(xy 270.140575 -96.993434) (xy 270.164247 -97.043931) (xy 270.180315 -97.097338) (xy 270.188435 -97.152514)
			(xy 270.188944 -97.1804) (xy 270.188435 -97.208286) (xy 270.180315 -97.263462) (xy 270.164247 -97.316869)
			(xy 270.140575 -97.367366) (xy 270.109802 -97.413879) (xy 270.072585 -97.455416) (xy 270.029717 -97.491091)
			(xy 269.982111 -97.520145) (xy 269.930782 -97.541957) (xy 269.876825 -97.556063) (xy 269.821388 -97.562163)
			(xy 269.765654 -97.560126) (xy 269.710811 -97.549996) (xy 269.658027 -97.531989) (xy 269.608427 -97.506488)
			(xy 269.563069 -97.474037) (xy 269.52292 -97.435328) (xy 269.488834 -97.391185) (xy 269.461538 -97.34255)
			(xy 269.441615 -97.290459) (xy 269.429489 -97.236022) (xy 269.425418 -97.1804) (xy 264.334626 -97.1804)
			(xy 264.335357 -97.182666) (xy 264.390727 -97.380282) (xy 264.438344 -97.579909) (xy 264.478136 -97.781241)
			(xy 264.510043 -97.983973) (xy 264.534016 -98.187795) (xy 264.550018 -98.392398) (xy 264.558025 -98.597468)
			(xy 264.558526 -98.700082) (xy 264.558025 -98.802696) (xy 264.550018 -99.007766) (xy 264.534016 -99.212369)
			(xy 264.510043 -99.416191) (xy 264.478136 -99.618923) (xy 264.438344 -99.820255) (xy 264.390727 -100.019882)
			(xy 264.335357 -100.217498) (xy 264.275112 -100.404154) (xy 268.933087 -100.404154) (xy 268.933087 -100.346846)
			(xy 268.941243 -100.290123) (xy 268.957389 -100.235137) (xy 268.981196 -100.183009) (xy 269.01218 -100.1348)
			(xy 269.049709 -100.091491) (xy 269.093021 -100.053964) (xy 269.141232 -100.022984) (xy 269.193361 -99.99918)
			(xy 269.248348 -99.983037) (xy 269.305072 -99.974885) (xy 269.333726 -99.9744) (xy 269.348644 -99.974572)
			(xy 269.378393 -99.976859) (xy 269.393162 -99.978972) (xy 269.404338 -99.98075) (xy 269.42542 -99.974654)
			(xy 269.492222 -99.916996) (xy 269.500194 -99.909408) (xy 269.509275 -99.889385) (xy 269.509748 -99.878388)
			(xy 269.509748 -99.61372) (xy 269.509217 -99.602734) (xy 269.500158 -99.582723) (xy 269.492222 -99.575112)
			(xy 269.42542 -99.517454) (xy 269.404338 -99.511358) (xy 269.393162 -99.513136) (xy 269.378392 -99.51524)
			(xy 269.348644 -99.517531) (xy 269.333726 -99.517708) (xy 269.305078 -99.517139) (xy 269.248364 -99.508988)
			(xy 269.193388 -99.492849) (xy 269.141268 -99.46905) (xy 269.093066 -99.438075) (xy 269.049763 -99.400555)
			(xy 269.012241 -99.357255) (xy 268.981263 -99.309055) (xy 268.95746 -99.256937) (xy 268.941317 -99.201961)
			(xy 268.933163 -99.145248) (xy 268.933163 -99.087952) (xy 268.941317 -99.031239) (xy 268.95746 -98.976263)
			(xy 268.981263 -98.924145) (xy 269.012241 -98.875945) (xy 269.049763 -98.832645) (xy 269.093066 -98.795125)
			(xy 269.141268 -98.76415) (xy 269.193388 -98.740351) (xy 269.248364 -98.724212) (xy 269.305078 -98.716061)
			(xy 269.333726 -98.715576) (xy 269.361107 -98.716033) (xy 269.415357 -98.723503) (xy 269.468086 -98.738288)
			(xy 269.518311 -98.760112) (xy 269.565099 -98.788569) (xy 269.607578 -98.823129) (xy 269.644958 -98.863149)
			(xy 269.661132 -98.885248) (xy 269.666695 -98.892508) (xy 269.681803 -98.902794) (xy 269.690596 -98.905314)
			(xy 269.720568 -98.91268) (xy 269.729521 -98.914407) (xy 269.747606 -98.912204) (xy 269.755874 -98.908362)
			(xy 269.780478 -98.895981) (xy 269.832003 -98.87651) (xy 269.885491 -98.86336) (xy 269.94017 -98.856719)
			(xy 269.96771 -98.856292) (xy 269.99525 -98.856727) (xy 270.049931 -98.86336) (xy 270.10342 -98.876505)
			(xy 270.154947 -98.895971) (xy 270.179546 -98.908362) (xy 270.187797 -98.912262) (xy 270.205901 -98.914463)
			(xy 270.214852 -98.91268) (xy 270.244824 -98.905314) (xy 270.253612 -98.902789) (xy 270.268711 -98.892495)
			(xy 270.274288 -98.885248) (xy 270.290475 -98.863157) (xy 270.327843 -98.823124) (xy 270.370315 -98.788553)
			(xy 270.417101 -98.760089) (xy 270.467328 -98.738264) (xy 270.520059 -98.723483) (xy 270.574312 -98.716023)
			(xy 270.601694 -98.715576) (xy 270.630347 -98.715978) (xy 270.687071 -98.724133) (xy 270.742056 -98.740278)
			(xy 270.794184 -98.764083) (xy 270.842394 -98.795065) (xy 270.885703 -98.832592) (xy 270.923232 -98.875901)
			(xy 270.954214 -98.924111) (xy 270.97802 -98.976238) (xy 270.994165 -99.031224) (xy 271.002321 -99.087947)
			(xy 271.002321 -99.145253) (xy 270.994165 -99.201976) (xy 270.97802 -99.256962) (xy 270.954214 -99.309089)
			(xy 270.923232 -99.357299) (xy 270.885703 -99.400608) (xy 270.842394 -99.438135) (xy 270.794184 -99.469117)
			(xy 270.742056 -99.492922) (xy 270.687071 -99.509067) (xy 270.630347 -99.517222) (xy 270.601694 -99.517708)
			(xy 270.586776 -99.517534) (xy 270.557027 -99.515248) (xy 270.542258 -99.513136) (xy 270.531082 -99.511358)
			(xy 270.51 -99.517454) (xy 270.443198 -99.575112) (xy 270.435225 -99.5827) (xy 270.426144 -99.602723)
			(xy 270.425672 -99.61372) (xy 270.425672 -99.878388) (xy 270.426193 -99.889375) (xy 270.435258 -99.909387)
			(xy 270.443198 -99.916996) (xy 270.51 -99.974654) (xy 270.531082 -99.98075) (xy 270.542258 -99.978972)
			(xy 270.557027 -99.976866) (xy 270.586776 -99.974576) (xy 270.601694 -99.9744) (xy 270.630342 -99.974954)
			(xy 270.687054 -99.983107) (xy 270.742029 -99.999249) (xy 270.794148 -100.02305) (xy 270.842348 -100.054026)
			(xy 270.88565 -100.091546) (xy 270.923171 -100.134847) (xy 270.954147 -100.183047) (xy 270.977949 -100.235165)
			(xy 270.994091 -100.29014) (xy 271.002245 -100.346852) (xy 271.002245 -100.404148) (xy 270.994091 -100.46086)
			(xy 270.977949 -100.515835) (xy 270.954147 -100.567953) (xy 270.923171 -100.616153) (xy 270.88565 -100.659454)
			(xy 270.842348 -100.696974) (xy 270.794148 -100.72795) (xy 270.742029 -100.751751) (xy 270.687054 -100.767893)
			(xy 270.630342 -100.776046) (xy 270.601694 -100.776532) (xy 270.574314 -100.776057) (xy 270.520064 -100.768589)
			(xy 270.467336 -100.753807) (xy 270.417111 -100.731986) (xy 270.370323 -100.703532) (xy 270.327843 -100.668975)
			(xy 270.290462 -100.628957) (xy 270.274288 -100.60686) (xy 270.268716 -100.599607) (xy 270.253615 -100.589317)
			(xy 270.244824 -100.586794) (xy 270.214852 -100.579428) (xy 270.205898 -100.57771) (xy 270.187814 -100.579907)
			(xy 270.179546 -100.583746) (xy 270.154938 -100.59612) (xy 270.103415 -100.615592) (xy 270.049928 -100.628745)
			(xy 269.99525 -100.635388) (xy 269.96771 -100.635816) (xy 269.940169 -100.635412) (xy 269.885487 -100.62877)
			(xy 269.831998 -100.615616) (xy 269.780472 -100.596141) (xy 269.755874 -100.583746) (xy 269.747619 -100.579856)
			(xy 269.729518 -100.577648) (xy 269.720568 -100.579428) (xy 269.690596 -100.586794) (xy 269.68181 -100.589324)
			(xy 269.66671 -100.599615) (xy 269.661132 -100.60686) (xy 269.644997 -100.62899) (xy 269.60762 -100.669022)
			(xy 269.565138 -100.70359) (xy 269.518344 -100.732048) (xy 269.468109 -100.753867) (xy 269.41537 -100.76864)
			(xy 269.36111 -100.77609) (xy 269.333726 -100.776532) (xy 269.305072 -100.776115) (xy 269.248348 -100.767963)
			(xy 269.193361 -100.75182) (xy 269.141232 -100.728016) (xy 269.093021 -100.697036) (xy 269.049709 -100.659509)
			(xy 269.01218 -100.6162) (xy 268.981196 -100.567991) (xy 268.957389 -100.515863) (xy 268.941243 -100.460877)
			(xy 268.933087 -100.404154) (xy 264.275112 -100.404154) (xy 264.27232 -100.412804) (xy 264.20171 -100.605502)
			(xy 264.123636 -100.795298) (xy 264.052018 -100.951752) (xy 266.900611 -100.951752) (xy 266.900611 -100.894448)
			(xy 266.908766 -100.837729) (xy 266.924911 -100.782747) (xy 266.948716 -100.730623) (xy 266.979697 -100.682417)
			(xy 267.017223 -100.639111) (xy 267.060531 -100.601586) (xy 267.108738 -100.570607) (xy 267.160864 -100.546804)
			(xy 267.215846 -100.530662) (xy 267.272566 -100.52251) (xy 267.301218 -100.522024) (xy 267.328598 -100.522509)
			(xy 267.382846 -100.529977) (xy 267.435573 -100.544759) (xy 267.485798 -100.566579) (xy 267.532585 -100.595031)
			(xy 267.575066 -100.629585) (xy 267.612449 -100.6696) (xy 267.628624 -100.691696) (xy 267.63418 -100.698962)
			(xy 267.649294 -100.709243) (xy 267.658088 -100.711762) (xy 267.68806 -100.719128) (xy 267.697013 -100.720856)
			(xy 267.715099 -100.718654) (xy 267.723366 -100.71481) (xy 267.747974 -100.702436) (xy 267.799497 -100.682963)
			(xy 267.852984 -100.66981) (xy 267.907662 -100.663168) (xy 267.935202 -100.66274) (xy 267.962742 -100.663184)
			(xy 268.017422 -100.669815) (xy 268.070911 -100.682958) (xy 268.122438 -100.702421) (xy 268.147038 -100.71481)
			(xy 268.15529 -100.718707) (xy 268.173393 -100.720909) (xy 268.182344 -100.719128) (xy 268.212316 -100.711762)
			(xy 268.221098 -100.709219) (xy 268.236198 -100.698937) (xy 268.24178 -100.691696) (xy 268.257895 -100.669551)
			(xy 268.295277 -100.629521) (xy 268.337762 -100.594956) (xy 268.38456 -100.5665) (xy 268.434798 -100.544684)
			(xy 268.487539 -100.529914) (xy 268.541801 -100.522465) (xy 268.569186 -100.522024) (xy 268.597836 -100.52253)
			(xy 268.654553 -100.530683) (xy 268.709532 -100.546824) (xy 268.761654 -100.570626) (xy 268.809859 -100.601604)
			(xy 268.853164 -100.639126) (xy 268.890688 -100.68243) (xy 268.921667 -100.730633) (xy 268.945471 -100.782755)
			(xy 268.961614 -100.837734) (xy 268.969769 -100.89445) (xy 268.969769 -100.95175) (xy 268.961614 -101.008466)
			(xy 268.945471 -101.063445) (xy 268.921667 -101.115567) (xy 268.890688 -101.16377) (xy 268.853164 -101.207074)
			(xy 268.809859 -101.244596) (xy 268.761654 -101.275574) (xy 268.709532 -101.299376) (xy 268.654553 -101.315517)
			(xy 268.597836 -101.32367) (xy 268.569186 -101.324156) (xy 268.554268 -101.323983) (xy 268.524519 -101.321697)
			(xy 268.50975 -101.319584) (xy 268.498574 -101.317806) (xy 268.477492 -101.323902) (xy 268.41069 -101.38156)
			(xy 268.40274 -101.389167) (xy 268.393646 -101.409176) (xy 268.393164 -101.420168) (xy 268.393164 -101.684836)
			(xy 268.393661 -101.695826) (xy 268.402743 -101.715837) (xy 268.41069 -101.723444) (xy 268.477492 -101.781102)
			(xy 268.498574 -101.787198) (xy 268.50975 -101.78542) (xy 268.52452 -101.783315) (xy 268.554268 -101.781025)
			(xy 268.569186 -101.780848) (xy 268.597838 -101.781306) (xy 268.654558 -101.789459) (xy 268.70954 -101.805602)
			(xy 268.761666 -101.829405) (xy 268.809873 -101.860384) (xy 268.853181 -101.897909) (xy 268.890707 -101.941216)
			(xy 268.921688 -101.989422) (xy 268.945493 -102.041546) (xy 268.961638 -102.096528) (xy 268.969793 -102.153248)
			(xy 268.969793 -102.210552) (xy 268.961638 -102.267272) (xy 268.945493 -102.322254) (xy 268.921688 -102.374378)
			(xy 268.890707 -102.422584) (xy 268.853181 -102.465891) (xy 268.809873 -102.503416) (xy 268.761666 -102.534395)
			(xy 268.70954 -102.558198) (xy 268.654558 -102.574341) (xy 268.597838 -102.582494) (xy 268.569186 -102.58298)
			(xy 268.541806 -102.582491) (xy 268.487559 -102.575023) (xy 268.434832 -102.560242) (xy 268.384607 -102.538423)
			(xy 268.337819 -102.509972) (xy 268.295339 -102.475417) (xy 268.257956 -102.435404) (xy 268.24178 -102.413308)
			(xy 268.236222 -102.406043) (xy 268.22111 -102.395761) (xy 268.212316 -102.393242) (xy 268.182344 -102.385876)
			(xy 268.173391 -102.38415) (xy 268.155305 -102.386351) (xy 268.147038 -102.390194) (xy 268.12243 -102.402567)
			(xy 268.070907 -102.42204) (xy 268.01742 -102.435194) (xy 267.962742 -102.441836) (xy 267.935202 -102.442264)
			(xy 267.907662 -102.441818) (xy 267.852982 -102.435187) (xy 267.799493 -102.422045) (xy 267.747966 -102.402583)
			(xy 267.723366 -102.390194) (xy 267.715114 -102.386299) (xy 267.697011 -102.384095) (xy 267.68806 -102.385876)
			(xy 267.658088 -102.393242) (xy 267.649306 -102.395785) (xy 267.634206 -102.406067) (xy 267.628624 -102.413308)
			(xy 267.612508 -102.435452) (xy 267.575126 -102.475482) (xy 267.532641 -102.510047) (xy 267.485843 -102.538503)
			(xy 267.435605 -102.560319) (xy 267.382864 -102.57509) (xy 267.328603 -102.582539) (xy 267.301218 -102.58298)
			(xy 267.272568 -102.582467) (xy 267.215851 -102.574314) (xy 267.160872 -102.558173) (xy 267.10875 -102.534372)
			(xy 267.060546 -102.503395) (xy 267.01724 -102.465872) (xy 266.979716 -102.422569) (xy 266.948737 -102.374366)
			(xy 266.924933 -102.322245) (xy 266.90879 -102.267266) (xy 266.900635 -102.21055) (xy 266.900635 -102.15325)
			(xy 266.90879 -102.096534) (xy 266.924933 -102.041555) (xy 266.948737 -101.989434) (xy 266.979716 -101.941231)
			(xy 267.01724 -101.897928) (xy 267.060546 -101.860405) (xy 267.10875 -101.829428) (xy 267.160872 -101.805627)
			(xy 267.215851 -101.789486) (xy 267.272568 -101.781333) (xy 267.301218 -101.780848) (xy 267.316136 -101.78102)
			(xy 267.345885 -101.783307) (xy 267.360654 -101.78542) (xy 267.37183 -101.787198) (xy 267.392912 -101.781102)
			(xy 267.459714 -101.723444) (xy 267.467663 -101.715836) (xy 267.476757 -101.695828) (xy 267.47724 -101.684836)
			(xy 267.47724 -101.420168) (xy 267.47674 -101.409179) (xy 267.46766 -101.389167) (xy 267.459714 -101.38156)
			(xy 267.392912 -101.323902) (xy 267.37183 -101.317806) (xy 267.360654 -101.319584) (xy 267.345884 -101.321689)
			(xy 267.316136 -101.323979) (xy 267.301218 -101.324156) (xy 267.272566 -101.32369) (xy 267.215846 -101.315538)
			(xy 267.160864 -101.299396) (xy 267.108738 -101.275593) (xy 267.060531 -101.244614) (xy 267.017223 -101.207089)
			(xy 266.979697 -101.163783) (xy 266.948716 -101.115577) (xy 266.924911 -101.063453) (xy 266.908766 -101.008471)
			(xy 266.900611 -100.951752) (xy 264.052018 -100.951752) (xy 264.038216 -100.981904) (xy 263.94558 -101.165034)
			(xy 263.84587 -101.344411) (xy 263.739237 -101.519761) (xy 263.625844 -101.690817) (xy 263.505864 -101.857319)
			(xy 263.379478 -102.019013) (xy 263.24688 -102.175653) (xy 263.108272 -102.326999) (xy 262.963864 -102.472823)
			(xy 262.813877 -102.612902) (xy 262.660608 -102.745234) (xy 268.933359 -102.745234) (xy 268.933359 -102.687966)
			(xy 268.941509 -102.63128) (xy 268.957644 -102.576332) (xy 268.981435 -102.524239) (xy 269.012398 -102.476063)
			(xy 269.049902 -102.432784) (xy 269.093184 -102.395282) (xy 269.141362 -102.364323) (xy 269.193457 -102.340535)
			(xy 269.248406 -102.324404) (xy 269.305092 -102.316257) (xy 269.333726 -102.315772) (xy 269.361098 -102.3162)
			(xy 269.415332 -102.32365) (xy 269.468049 -102.338407) (xy 269.518269 -102.360197) (xy 269.565058 -102.388616)
			(xy 269.607546 -102.423135) (xy 269.644945 -102.463112) (xy 269.661132 -102.48519) (xy 269.666686 -102.492458)
			(xy 269.681801 -102.502738) (xy 269.690596 -102.505256) (xy 269.720568 -102.512622) (xy 269.72952 -102.514355)
			(xy 269.747607 -102.512149) (xy 269.755874 -102.508304) (xy 269.78048 -102.495943) (xy 269.832015 -102.476543)
			(xy 269.885505 -102.46346) (xy 269.940177 -102.456884) (xy 269.96771 -102.456488) (xy 269.995244 -102.456884)
			(xy 270.049918 -102.463449) (xy 270.103408 -102.476531) (xy 270.154941 -102.49594) (xy 270.179546 -102.508304)
			(xy 270.187796 -102.512205) (xy 270.205901 -102.514405) (xy 270.214852 -102.512622) (xy 270.244824 -102.505256)
			(xy 270.253608 -102.502718) (xy 270.268707 -102.492432) (xy 270.274288 -102.48519) (xy 270.290493 -102.463128)
			(xy 270.32789 -102.423155) (xy 270.370377 -102.38864) (xy 270.417163 -102.360225) (xy 270.46738 -102.338438)
			(xy 270.520094 -102.323684) (xy 270.574324 -102.316238) (xy 270.601694 -102.315772) (xy 270.630325 -102.31629)
			(xy 270.687004 -102.324439) (xy 270.741947 -102.34057) (xy 270.794034 -102.364357) (xy 270.842206 -102.395315)
			(xy 270.885482 -102.432813) (xy 270.922981 -102.476089) (xy 270.95394 -102.52426) (xy 270.977727 -102.576348)
			(xy 270.99386 -102.63129) (xy 271.002009 -102.687969) (xy 271.002009 -102.745231) (xy 270.99386 -102.80191)
			(xy 270.977727 -102.856852) (xy 270.95394 -102.90894) (xy 270.922981 -102.957111) (xy 270.885482 -103.000387)
			(xy 270.842206 -103.037885) (xy 270.794034 -103.068843) (xy 270.741947 -103.09263) (xy 270.687004 -103.108761)
			(xy 270.630325 -103.11691) (xy 270.601694 -103.117396) (xy 270.58678 -103.117282) (xy 270.557031 -103.115124)
			(xy 270.542258 -103.113078) (xy 270.531082 -103.1113) (xy 270.51 -103.117396) (xy 270.443198 -103.175054)
			(xy 270.435252 -103.182665) (xy 270.426155 -103.202671) (xy 270.425672 -103.213662) (xy 270.425672 -103.47833)
			(xy 270.426169 -103.48932) (xy 270.435251 -103.509331) (xy 270.443198 -103.516938) (xy 270.51 -103.574596)
			(xy 270.531082 -103.580692) (xy 270.542258 -103.578914) (xy 270.557031 -103.576864) (xy 270.58678 -103.574704)
			(xy 270.601694 -103.574596) (xy 270.630327 -103.575066) (xy 270.687009 -103.583215) (xy 270.741955 -103.599348)
			(xy 270.794046 -103.623136) (xy 270.842221 -103.654096) (xy 270.885499 -103.691596) (xy 270.923001 -103.734874)
			(xy 270.953961 -103.783049) (xy 270.97775 -103.835139) (xy 270.993884 -103.890085) (xy 271.002033 -103.946767)
			(xy 271.002033 -104.004033) (xy 270.993884 -104.060715) (xy 270.97775 -104.115661) (xy 270.953961 -104.167751)
			(xy 270.923001 -104.215926) (xy 270.885499 -104.259204) (xy 270.842221 -104.296704) (xy 270.794046 -104.327664)
			(xy 270.741955 -104.351452) (xy 270.687009 -104.367585) (xy 270.630327 -104.375734) (xy 270.601694 -104.37622)
			(xy 270.574323 -104.37578) (xy 270.520089 -104.368333) (xy 270.467372 -104.353578) (xy 270.417152 -104.33179)
			(xy 270.370363 -104.303373) (xy 270.327874 -104.268855) (xy 270.290475 -104.228879) (xy 270.274288 -104.206802)
			(xy 270.268728 -104.199539) (xy 270.253617 -104.189256) (xy 270.244824 -104.186736) (xy 270.214852 -104.17937)
			(xy 270.205898 -104.177648) (xy 270.187813 -104.179846) (xy 270.179546 -104.183688) (xy 270.154936 -104.196041)
			(xy 270.103402 -104.215443) (xy 270.049914 -104.228528) (xy 269.995243 -104.235107) (xy 269.96771 -104.235504)
			(xy 269.940176 -104.2351) (xy 269.885503 -104.228538) (xy 269.832012 -104.215458) (xy 269.780479 -104.196051)
			(xy 269.755874 -104.183688) (xy 269.74762 -104.179797) (xy 269.729519 -104.177591) (xy 269.720568 -104.17937)
			(xy 269.690596 -104.186736) (xy 269.681816 -104.189284) (xy 269.666715 -104.199563) (xy 269.661132 -104.206802)
			(xy 269.644942 -104.228875) (xy 269.607539 -104.268844) (xy 269.565049 -104.303355) (xy 269.518259 -104.331767)
			(xy 269.468041 -104.353552) (xy 269.415327 -104.368305) (xy 269.361096 -104.375753) (xy 269.333726 -104.37622)
			(xy 269.305094 -104.375719) (xy 269.248411 -104.367573) (xy 269.193465 -104.351442) (xy 269.141374 -104.327656)
			(xy 269.093198 -104.296698) (xy 269.049919 -104.259199) (xy 269.012417 -104.215923) (xy 268.981456 -104.167749)
			(xy 268.957667 -104.115659) (xy 268.941533 -104.060714) (xy 268.933383 -104.004032) (xy 268.933383 -103.946768)
			(xy 268.941533 -103.890086) (xy 268.957667 -103.835141) (xy 268.981456 -103.783051) (xy 269.012417 -103.734877)
			(xy 269.049919 -103.691601) (xy 269.093198 -103.654102) (xy 269.141374 -103.623144) (xy 269.193465 -103.599358)
			(xy 269.248411 -103.583227) (xy 269.305094 -103.575081) (xy 269.333726 -103.574596) (xy 269.34864 -103.574708)
			(xy 269.378389 -103.576867) (xy 269.393162 -103.578914) (xy 269.404338 -103.580692) (xy 269.42542 -103.574596)
			(xy 269.492222 -103.516938) (xy 269.500175 -103.509333) (xy 269.509267 -103.489322) (xy 269.509748 -103.47833)
			(xy 269.509748 -103.213662) (xy 269.509249 -103.202673) (xy 269.500168 -103.182662) (xy 269.492222 -103.175054)
			(xy 269.42542 -103.117396) (xy 269.404338 -103.1113) (xy 269.393162 -103.113078) (xy 269.378389 -103.115126)
			(xy 269.34864 -103.117287) (xy 269.333726 -103.117396) (xy 269.305092 -103.116943) (xy 269.248406 -103.108796)
			(xy 269.193457 -103.092665) (xy 269.141362 -103.068877) (xy 269.093184 -103.037918) (xy 269.049902 -103.000416)
			(xy 269.012398 -102.957137) (xy 268.981435 -102.908961) (xy 268.957644 -102.856868) (xy 268.941509 -102.80192)
			(xy 268.933359 -102.745234) (xy 262.660608 -102.745234) (xy 262.658538 -102.747021) (xy 262.498085 -102.874978)
			(xy 262.332762 -102.996578) (xy 262.16282 -103.111634) (xy 261.988519 -103.219973) (xy 261.810123 -103.321428)
			(xy 261.627905 -103.415846) (xy 261.442142 -103.503082) (xy 261.253117 -103.583005) (xy 261.061117 -103.655491)
			(xy 260.866435 -103.720431) (xy 260.669368 -103.777726) (xy 260.470215 -103.827289) (xy 260.269281 -103.869044)
			(xy 260.06687 -103.902927) (xy 259.863292 -103.928887) (xy 259.658855 -103.946884) (xy 259.453872 -103.956892)
			(xy 259.248655 -103.958894) (xy 259.043516 -103.952888) (xy 258.838767 -103.938883) (xy 258.63472 -103.9169)
			(xy 258.431687 -103.886973) (xy 258.229976 -103.849146) (xy 258.029894 -103.803479) (xy 257.831747 -103.75004)
			(xy 257.635835 -103.688911) (xy 257.442458 -103.620185) (xy 257.251909 -103.543966) (xy 257.064479 -103.46037)
			(xy 256.880453 -103.369526) (xy 256.700112 -103.271571) (xy 256.52373 -103.166654) (xy 256.351576 -103.054935)
			(xy 256.183911 -102.936585) (xy 256.020992 -102.811783) (xy 255.863066 -102.680719) (xy 255.710374 -102.543594)
			(xy 255.563149 -102.400616) (xy 255.421614 -102.252002) (xy 255.285985 -102.09798) (xy 255.156468 -101.938783)
			(xy 255.033262 -101.774654) (xy 254.916553 -101.605843) (xy 254.806519 -101.432606) (xy 254.703328 -101.255209)
			(xy 254.607137 -101.073921) (xy 254.518092 -100.889018) (xy 254.436329 -100.700781) (xy 254.361973 -100.509498)
			(xy 254.295137 -100.315459) (xy 254.235922 -100.11896) (xy 254.184419 -99.920301) (xy 254.140705 -99.719783)
			(xy 254.104849 -99.517712) (xy 254.076904 -99.314397) (xy 254.056913 -99.110146) (xy 254.044906 -98.90527)
			(xy 254.040902 -98.700082) (xy 226.63794 -98.700082) (xy 226.600035 -98.731627) (xy 226.552429 -98.760681)
			(xy 226.5011 -98.782493) (xy 226.447143 -98.796599) (xy 226.391706 -98.802699) (xy 226.335972 -98.800662)
			(xy 226.281129 -98.790532) (xy 226.228345 -98.772525) (xy 226.178745 -98.747024) (xy 226.133387 -98.714573)
			(xy 226.093238 -98.675864) (xy 226.059152 -98.631721) (xy 226.031856 -98.583086) (xy 226.011933 -98.530995)
			(xy 225.999807 -98.476558) (xy 225.995736 -98.420936) (xy 213.551234 -98.420936) (xy 213.558127 -98.597468)
			(xy 213.558628 -98.700082) (xy 213.558127 -98.802696) (xy 213.55012 -99.007766) (xy 213.534118 -99.212369)
			(xy 213.510145 -99.416191) (xy 213.478238 -99.618923) (xy 213.438446 -99.820255) (xy 213.43809 -99.821746)
			(xy 216.555826 -99.821746) (xy 216.559897 -99.766124) (xy 216.572023 -99.711687) (xy 216.591946 -99.659596)
			(xy 216.619242 -99.610961) (xy 216.653328 -99.566818) (xy 216.693477 -99.528109) (xy 216.738835 -99.495658)
			(xy 216.788435 -99.470157) (xy 216.841219 -99.45215) (xy 216.896062 -99.44202) (xy 216.951796 -99.439983)
			(xy 217.007233 -99.446083) (xy 217.06119 -99.460189) (xy 217.112519 -99.482001) (xy 217.160125 -99.511055)
			(xy 217.202993 -99.54673) (xy 217.24021 -99.588267) (xy 217.270983 -99.63478) (xy 217.294655 -99.685277)
			(xy 217.310723 -99.738684) (xy 217.318843 -99.79386) (xy 217.319352 -99.821746) (xy 217.318843 -99.849632)
			(xy 217.310723 -99.904808) (xy 217.294655 -99.958215) (xy 217.270983 -100.008712) (xy 217.24021 -100.055225)
			(xy 217.221596 -100.076) (xy 218.371672 -100.076) (xy 218.375743 -100.020378) (xy 218.387869 -99.965941)
			(xy 218.407792 -99.91385) (xy 218.435088 -99.865215) (xy 218.469174 -99.821072) (xy 218.509323 -99.782363)
			(xy 218.554681 -99.749912) (xy 218.604281 -99.724411) (xy 218.657065 -99.706404) (xy 218.711908 -99.696274)
			(xy 218.767642 -99.694237) (xy 218.823079 -99.700337) (xy 218.877036 -99.714443) (xy 218.928365 -99.736255)
			(xy 218.975971 -99.765309) (xy 219.018839 -99.800984) (xy 219.037669 -99.822) (xy 219.984826 -99.822)
			(xy 219.988897 -99.766378) (xy 220.001023 -99.711941) (xy 220.020946 -99.65985) (xy 220.048242 -99.611215)
			(xy 220.082328 -99.567072) (xy 220.122477 -99.528363) (xy 220.167835 -99.495912) (xy 220.217435 -99.470411)
			(xy 220.270219 -99.452404) (xy 220.325062 -99.442274) (xy 220.380796 -99.440237) (xy 220.436233 -99.446337)
			(xy 220.49019 -99.460443) (xy 220.541519 -99.482255) (xy 220.579633 -99.505516) (xy 221.292926 -99.505516)
			(xy 221.296997 -99.449894) (xy 221.309123 -99.395457) (xy 221.329046 -99.343366) (xy 221.356342 -99.294731)
			(xy 221.390428 -99.250588) (xy 221.430577 -99.211879) (xy 221.475935 -99.179428) (xy 221.525535 -99.153927)
			(xy 221.578319 -99.13592) (xy 221.633162 -99.12579) (xy 221.688896 -99.123753) (xy 221.744333 -99.129853)
			(xy 221.79829 -99.143959) (xy 221.849619 -99.165771) (xy 221.897225 -99.194825) (xy 221.940093 -99.2305)
			(xy 221.97731 -99.272037) (xy 222.008083 -99.31855) (xy 222.031755 -99.369047) (xy 222.047823 -99.422454)
			(xy 222.055943 -99.47763) (xy 222.056345 -99.499674) (xy 222.606868 -99.499674) (xy 222.610939 -99.444052)
			(xy 222.623065 -99.389615) (xy 222.642988 -99.337524) (xy 222.670284 -99.288889) (xy 222.70437 -99.244746)
			(xy 222.744519 -99.206037) (xy 222.789877 -99.173586) (xy 222.839477 -99.148085) (xy 222.892261 -99.130078)
			(xy 222.947104 -99.119948) (xy 223.002838 -99.117911) (xy 223.058275 -99.124011) (xy 223.112232 -99.138117)
			(xy 223.163561 -99.159929) (xy 223.211167 -99.188983) (xy 223.254035 -99.224658) (xy 223.291252 -99.266195)
			(xy 223.322025 -99.312708) (xy 223.334419 -99.339146) (xy 223.880932 -99.339146) (xy 223.885003 -99.283524)
			(xy 223.897129 -99.229087) (xy 223.917052 -99.176996) (xy 223.944348 -99.128361) (xy 223.978434 -99.084218)
			(xy 224.018583 -99.045509) (xy 224.063941 -99.013058) (xy 224.113541 -98.987557) (xy 224.166325 -98.96955)
			(xy 224.221168 -98.95942) (xy 224.276902 -98.957383) (xy 224.332339 -98.963483) (xy 224.386296 -98.977589)
			(xy 224.437625 -98.999401) (xy 224.485231 -99.028455) (xy 224.528099 -99.06413) (xy 224.565316 -99.105667)
			(xy 224.596089 -99.15218) (xy 224.619761 -99.202677) (xy 224.635829 -99.256084) (xy 224.643949 -99.31126)
			(xy 224.644458 -99.339146) (xy 224.643949 -99.367032) (xy 224.635829 -99.422208) (xy 224.619761 -99.475615)
			(xy 224.596089 -99.526112) (xy 224.565316 -99.572625) (xy 224.560812 -99.577652) (xy 225.818444 -99.577652)
			(xy 225.822515 -99.52203) (xy 225.834641 -99.467593) (xy 225.854564 -99.415502) (xy 225.88186 -99.366867)
			(xy 225.915946 -99.322724) (xy 225.956095 -99.284015) (xy 226.001453 -99.251564) (xy 226.051053 -99.226063)
			(xy 226.103837 -99.208056) (xy 226.15868 -99.197926) (xy 226.214414 -99.195889) (xy 226.269851 -99.201989)
			(xy 226.323808 -99.216095) (xy 226.375137 -99.237907) (xy 226.422743 -99.266961) (xy 226.465611 -99.302636)
			(xy 226.502828 -99.344173) (xy 226.533601 -99.390686) (xy 226.557273 -99.441183) (xy 226.573341 -99.49459)
			(xy 226.581461 -99.549766) (xy 226.58197 -99.577652) (xy 226.581461 -99.605538) (xy 226.573341 -99.660714)
			(xy 226.557273 -99.714121) (xy 226.533601 -99.764618) (xy 226.52807 -99.772978) (xy 243.553486 -99.772978)
			(xy 243.557557 -99.717356) (xy 243.569683 -99.662919) (xy 243.589606 -99.610828) (xy 243.616902 -99.562193)
			(xy 243.650988 -99.51805) (xy 243.691137 -99.479341) (xy 243.736495 -99.44689) (xy 243.786095 -99.421389)
			(xy 243.838879 -99.403382) (xy 243.893722 -99.393252) (xy 243.949456 -99.391215) (xy 244.004893 -99.397315)
			(xy 244.05885 -99.411421) (xy 244.110179 -99.433233) (xy 244.157785 -99.462287) (xy 244.200653 -99.497962)
			(xy 244.23787 -99.539499) (xy 244.268643 -99.586012) (xy 244.292315 -99.636509) (xy 244.308383 -99.689916)
			(xy 244.316503 -99.745092) (xy 244.317012 -99.772978) (xy 244.316503 -99.800864) (xy 244.308383 -99.85604)
			(xy 244.292315 -99.909447) (xy 244.268643 -99.959944) (xy 244.23787 -100.006457) (xy 244.200653 -100.047994)
			(xy 244.157785 -100.083669) (xy 244.110179 -100.112723) (xy 244.05885 -100.134535) (xy 244.004893 -100.148641)
			(xy 243.949456 -100.154741) (xy 243.893722 -100.152704) (xy 243.838879 -100.142574) (xy 243.786095 -100.124567)
			(xy 243.736495 -100.099066) (xy 243.691137 -100.066615) (xy 243.650988 -100.027906) (xy 243.616902 -99.983763)
			(xy 243.589606 -99.935128) (xy 243.569683 -99.883037) (xy 243.557557 -99.8286) (xy 243.553486 -99.772978)
			(xy 226.52807 -99.772978) (xy 226.502828 -99.811131) (xy 226.465611 -99.852668) (xy 226.422743 -99.888343)
			(xy 226.375137 -99.917397) (xy 226.323808 -99.939209) (xy 226.269851 -99.953315) (xy 226.214414 -99.959415)
			(xy 226.15868 -99.957378) (xy 226.103837 -99.947248) (xy 226.051053 -99.929241) (xy 226.001453 -99.90374)
			(xy 225.956095 -99.871289) (xy 225.915946 -99.83258) (xy 225.88186 -99.788437) (xy 225.854564 -99.739802)
			(xy 225.834641 -99.687711) (xy 225.822515 -99.633274) (xy 225.818444 -99.577652) (xy 224.560812 -99.577652)
			(xy 224.528099 -99.614162) (xy 224.485231 -99.649837) (xy 224.437625 -99.678891) (xy 224.386296 -99.700703)
			(xy 224.332339 -99.714809) (xy 224.276902 -99.720909) (xy 224.221168 -99.718872) (xy 224.166325 -99.708742)
			(xy 224.113541 -99.690735) (xy 224.063941 -99.665234) (xy 224.018583 -99.632783) (xy 223.978434 -99.594074)
			(xy 223.944348 -99.549931) (xy 223.917052 -99.501296) (xy 223.897129 -99.449205) (xy 223.885003 -99.394768)
			(xy 223.880932 -99.339146) (xy 223.334419 -99.339146) (xy 223.345697 -99.363205) (xy 223.361765 -99.416612)
			(xy 223.369885 -99.471788) (xy 223.370394 -99.499674) (xy 223.369885 -99.52756) (xy 223.361765 -99.582736)
			(xy 223.345697 -99.636143) (xy 223.322025 -99.68664) (xy 223.291252 -99.733153) (xy 223.254035 -99.77469)
			(xy 223.211167 -99.810365) (xy 223.163561 -99.839419) (xy 223.112232 -99.861231) (xy 223.058275 -99.875337)
			(xy 223.002838 -99.881437) (xy 222.947104 -99.8794) (xy 222.892261 -99.86927) (xy 222.839477 -99.851263)
			(xy 222.789877 -99.825762) (xy 222.744519 -99.793311) (xy 222.70437 -99.754602) (xy 222.670284 -99.710459)
			(xy 222.642988 -99.661824) (xy 222.623065 -99.609733) (xy 222.610939 -99.555296) (xy 222.606868 -99.499674)
			(xy 222.056345 -99.499674) (xy 222.056452 -99.505516) (xy 222.055943 -99.533402) (xy 222.047823 -99.588578)
			(xy 222.031755 -99.641985) (xy 222.008083 -99.692482) (xy 221.97731 -99.738995) (xy 221.940093 -99.780532)
			(xy 221.897225 -99.816207) (xy 221.849619 -99.845261) (xy 221.79829 -99.867073) (xy 221.744333 -99.881179)
			(xy 221.688896 -99.887279) (xy 221.633162 -99.885242) (xy 221.578319 -99.875112) (xy 221.525535 -99.857105)
			(xy 221.475935 -99.831604) (xy 221.430577 -99.799153) (xy 221.390428 -99.760444) (xy 221.356342 -99.716301)
			(xy 221.329046 -99.667666) (xy 221.309123 -99.615575) (xy 221.296997 -99.561138) (xy 221.292926 -99.505516)
			(xy 220.579633 -99.505516) (xy 220.589125 -99.511309) (xy 220.631993 -99.546984) (xy 220.66921 -99.588521)
			(xy 220.699983 -99.635034) (xy 220.723655 -99.685531) (xy 220.739723 -99.738938) (xy 220.747843 -99.794114)
			(xy 220.748352 -99.822) (xy 220.747843 -99.849886) (xy 220.739723 -99.905062) (xy 220.723655 -99.958469)
			(xy 220.699983 -100.008966) (xy 220.66921 -100.055479) (xy 220.631993 -100.097016) (xy 220.589125 -100.132691)
			(xy 220.541519 -100.161745) (xy 220.49019 -100.183557) (xy 220.436233 -100.197663) (xy 220.380796 -100.203763)
			(xy 220.325062 -100.201726) (xy 220.270219 -100.191596) (xy 220.217435 -100.173589) (xy 220.167835 -100.148088)
			(xy 220.122477 -100.115637) (xy 220.082328 -100.076928) (xy 220.048242 -100.032785) (xy 220.020946 -99.98415)
			(xy 220.001023 -99.932059) (xy 219.988897 -99.877622) (xy 219.984826 -99.822) (xy 219.037669 -99.822)
			(xy 219.056056 -99.842521) (xy 219.086829 -99.889034) (xy 219.110501 -99.939531) (xy 219.126569 -99.992938)
			(xy 219.134689 -100.048114) (xy 219.135198 -100.076) (xy 219.134689 -100.103886) (xy 219.126569 -100.159062)
			(xy 219.110501 -100.212469) (xy 219.086829 -100.262966) (xy 219.056056 -100.309479) (xy 219.018839 -100.351016)
			(xy 218.975971 -100.386691) (xy 218.928365 -100.415745) (xy 218.877036 -100.437557) (xy 218.823079 -100.451663)
			(xy 218.767642 -100.457763) (xy 218.711908 -100.455726) (xy 218.657065 -100.445596) (xy 218.604281 -100.427589)
			(xy 218.554681 -100.402088) (xy 218.509323 -100.369637) (xy 218.469174 -100.330928) (xy 218.435088 -100.286785)
			(xy 218.407792 -100.23815) (xy 218.387869 -100.186059) (xy 218.375743 -100.131622) (xy 218.371672 -100.076)
			(xy 217.221596 -100.076) (xy 217.202993 -100.096762) (xy 217.160125 -100.132437) (xy 217.112519 -100.161491)
			(xy 217.06119 -100.183303) (xy 217.007233 -100.197409) (xy 216.951796 -100.203509) (xy 216.896062 -100.201472)
			(xy 216.841219 -100.191342) (xy 216.788435 -100.173335) (xy 216.738835 -100.147834) (xy 216.693477 -100.115383)
			(xy 216.653328 -100.076674) (xy 216.619242 -100.032531) (xy 216.591946 -99.983896) (xy 216.572023 -99.931805)
			(xy 216.559897 -99.877368) (xy 216.555826 -99.821746) (xy 213.43809 -99.821746) (xy 213.390829 -100.019882)
			(xy 213.335459 -100.217498) (xy 213.272422 -100.412804) (xy 213.201812 -100.605502) (xy 213.123738 -100.795298)
			(xy 213.038318 -100.981904) (xy 212.945682 -101.165034) (xy 212.915684 -101.219) (xy 220.238826 -101.219)
			(xy 220.242897 -101.163378) (xy 220.255023 -101.108941) (xy 220.274946 -101.05685) (xy 220.302242 -101.008215)
			(xy 220.336328 -100.964072) (xy 220.376477 -100.925363) (xy 220.421835 -100.892912) (xy 220.471435 -100.867411)
			(xy 220.524219 -100.849404) (xy 220.579062 -100.839274) (xy 220.634796 -100.837237) (xy 220.690233 -100.843337)
			(xy 220.74419 -100.857443) (xy 220.795519 -100.879255) (xy 220.843125 -100.908309) (xy 220.885993 -100.943984)
			(xy 220.92321 -100.985521) (xy 220.953983 -101.032034) (xy 220.977655 -101.082531) (xy 220.993723 -101.135938)
			(xy 221.001843 -101.191114) (xy 221.002352 -101.219) (xy 221.001843 -101.246886) (xy 220.993723 -101.302062)
			(xy 220.977655 -101.355469) (xy 220.953983 -101.405966) (xy 220.92321 -101.452479) (xy 220.885993 -101.494016)
			(xy 220.843125 -101.529691) (xy 220.795519 -101.558745) (xy 220.74419 -101.580557) (xy 220.690233 -101.594663)
			(xy 220.634796 -101.600763) (xy 220.579062 -101.598726) (xy 220.524219 -101.588596) (xy 220.471435 -101.570589)
			(xy 220.421835 -101.545088) (xy 220.376477 -101.512637) (xy 220.336328 -101.473928) (xy 220.302242 -101.429785)
			(xy 220.274946 -101.38115) (xy 220.255023 -101.329059) (xy 220.242897 -101.274622) (xy 220.238826 -101.219)
			(xy 212.915684 -101.219) (xy 212.845972 -101.344411) (xy 212.739339 -101.519761) (xy 212.655167 -101.646736)
			(xy 217.531694 -101.646736) (xy 217.535765 -101.591114) (xy 217.547891 -101.536677) (xy 217.567814 -101.484586)
			(xy 217.59511 -101.435951) (xy 217.629196 -101.391808) (xy 217.669345 -101.353099) (xy 217.714703 -101.320648)
			(xy 217.764303 -101.295147) (xy 217.817087 -101.27714) (xy 217.87193 -101.26701) (xy 217.927664 -101.264973)
			(xy 217.983101 -101.271073) (xy 218.037058 -101.285179) (xy 218.088387 -101.306991) (xy 218.135993 -101.336045)
			(xy 218.178861 -101.37172) (xy 218.216078 -101.413257) (xy 218.246851 -101.45977) (xy 218.270523 -101.510267)
			(xy 218.286591 -101.563674) (xy 218.294711 -101.61885) (xy 218.29522 -101.646736) (xy 218.295011 -101.658166)
			(xy 218.69857 -101.658166) (xy 218.702641 -101.602544) (xy 218.714767 -101.548107) (xy 218.73469 -101.496016)
			(xy 218.761986 -101.447381) (xy 218.796072 -101.403238) (xy 218.836221 -101.364529) (xy 218.881579 -101.332078)
			(xy 218.931179 -101.306577) (xy 218.983963 -101.28857) (xy 219.038806 -101.27844) (xy 219.09454 -101.276403)
			(xy 219.149977 -101.282503) (xy 219.203934 -101.296609) (xy 219.255263 -101.318421) (xy 219.302869 -101.347475)
			(xy 219.345737 -101.38315) (xy 219.382954 -101.424687) (xy 219.413727 -101.4712) (xy 219.437399 -101.521697)
			(xy 219.453467 -101.575104) (xy 219.461587 -101.63028) (xy 219.462096 -101.658166) (xy 219.461587 -101.686052)
			(xy 219.453467 -101.741228) (xy 219.437399 -101.794635) (xy 219.413727 -101.845132) (xy 219.382954 -101.891645)
			(xy 219.345737 -101.933182) (xy 219.302869 -101.968857) (xy 219.255263 -101.997911) (xy 219.203934 -102.019723)
			(xy 219.149977 -102.033829) (xy 219.09454 -102.039929) (xy 219.038806 -102.037892) (xy 218.983963 -102.027762)
			(xy 218.931179 -102.009755) (xy 218.881579 -101.984254) (xy 218.836221 -101.951803) (xy 218.796072 -101.913094)
			(xy 218.761986 -101.868951) (xy 218.73469 -101.820316) (xy 218.714767 -101.768225) (xy 218.702641 -101.713788)
			(xy 218.69857 -101.658166) (xy 218.295011 -101.658166) (xy 218.294711 -101.674622) (xy 218.286591 -101.729798)
			(xy 218.270523 -101.783205) (xy 218.246851 -101.833702) (xy 218.216078 -101.880215) (xy 218.178861 -101.921752)
			(xy 218.135993 -101.957427) (xy 218.088387 -101.986481) (xy 218.037058 -102.008293) (xy 217.983101 -102.022399)
			(xy 217.927664 -102.028499) (xy 217.87193 -102.026462) (xy 217.817087 -102.016332) (xy 217.764303 -101.998325)
			(xy 217.714703 -101.972824) (xy 217.669345 -101.940373) (xy 217.629196 -101.901664) (xy 217.59511 -101.857521)
			(xy 217.567814 -101.808886) (xy 217.547891 -101.756795) (xy 217.535765 -101.702358) (xy 217.531694 -101.646736)
			(xy 212.655167 -101.646736) (xy 212.625946 -101.690817) (xy 212.505966 -101.857319) (xy 212.37958 -102.019013)
			(xy 212.246982 -102.175653) (xy 212.108374 -102.326999) (xy 211.963966 -102.472823) (xy 211.813979 -102.612902)
			(xy 211.65864 -102.747021) (xy 211.546791 -102.836218) (xy 217.543124 -102.836218) (xy 217.547195 -102.780596)
			(xy 217.559321 -102.726159) (xy 217.579244 -102.674068) (xy 217.60654 -102.625433) (xy 217.640626 -102.58129)
			(xy 217.680775 -102.542581) (xy 217.726133 -102.51013) (xy 217.775733 -102.484629) (xy 217.828517 -102.466622)
			(xy 217.88336 -102.456492) (xy 217.939094 -102.454455) (xy 217.994531 -102.460555) (xy 218.048488 -102.474661)
			(xy 218.099817 -102.496473) (xy 218.147423 -102.525527) (xy 218.190291 -102.561202) (xy 218.227508 -102.602739)
			(xy 218.258281 -102.649252) (xy 218.281953 -102.699749) (xy 218.298021 -102.753156) (xy 218.306141 -102.808332)
			(xy 218.30665 -102.836218) (xy 218.709746 -102.836218) (xy 218.713817 -102.780596) (xy 218.725943 -102.726159)
			(xy 218.745866 -102.674068) (xy 218.773162 -102.625433) (xy 218.807248 -102.58129) (xy 218.847397 -102.542581)
			(xy 218.892755 -102.51013) (xy 218.942355 -102.484629) (xy 218.995139 -102.466622) (xy 219.049982 -102.456492)
			(xy 219.105716 -102.454455) (xy 219.161153 -102.460555) (xy 219.21511 -102.474661) (xy 219.266439 -102.496473)
			(xy 219.314045 -102.525527) (xy 219.356913 -102.561202) (xy 219.39413 -102.602739) (xy 219.424903 -102.649252)
			(xy 219.448575 -102.699749) (xy 219.464643 -102.753156) (xy 219.472763 -102.808332) (xy 219.473272 -102.836218)
			(xy 219.472763 -102.864104) (xy 219.465989 -102.910132) (xy 224.984056 -102.910132) (xy 224.984527 -102.882762)
			(xy 224.992342 -102.828582) (xy 225.007829 -102.776079) (xy 225.03067 -102.726332) (xy 225.060394 -102.680365)
			(xy 225.078036 -102.659434) (xy 225.07829 -102.65918) (xy 225.08389 -102.652103) (xy 225.090129 -102.635179)
			(xy 225.090482 -102.62616) (xy 225.090482 -102.559104) (xy 225.090127 -102.550087) (xy 225.083879 -102.53317)
			(xy 225.07829 -102.526084) (xy 225.078036 -102.526084) (xy 225.078036 -102.52583) (xy 225.060426 -102.504872)
			(xy 225.0307 -102.458909) (xy 225.007852 -102.409167) (xy 224.992353 -102.356669) (xy 224.984521 -102.302493)
			(xy 224.984517 -102.247755) (xy 224.992342 -102.193579) (xy 225.007835 -102.141078) (xy 225.030676 -102.091333)
			(xy 225.060397 -102.045367) (xy 225.078036 -102.024434) (xy 225.07829 -102.02418) (xy 225.08389 -102.017103)
			(xy 225.090129 -102.000179) (xy 225.090482 -101.99116) (xy 225.090482 -101.924104) (xy 225.090127 -101.915087)
			(xy 225.083879 -101.89817) (xy 225.07829 -101.891084) (xy 225.078036 -101.891084) (xy 225.078036 -101.89083)
			(xy 225.060403 -101.869893) (xy 225.030689 -101.823922) (xy 225.007851 -101.774176) (xy 224.992359 -101.721676)
			(xy 224.98453 -101.667501) (xy 224.984056 -101.640132) (xy 224.984542 -101.612881) (xy 224.992298 -101.558933)
			(xy 225.007653 -101.506638) (xy 225.030295 -101.457061) (xy 225.059761 -101.411211) (xy 225.095452 -101.37002)
			(xy 225.136643 -101.334329) (xy 225.182493 -101.304863) (xy 225.23207 -101.282221) (xy 225.284365 -101.266866)
			(xy 225.338313 -101.25911) (xy 225.392815 -101.25911) (xy 225.446763 -101.266866) (xy 225.499058 -101.282221)
			(xy 225.548635 -101.304863) (xy 225.594485 -101.334329) (xy 225.635676 -101.37002) (xy 225.671367 -101.411211)
			(xy 225.700833 -101.457061) (xy 225.723475 -101.506638) (xy 225.73883 -101.558933) (xy 225.746586 -101.612881)
			(xy 225.747072 -101.640132) (xy 225.746632 -101.667503) (xy 225.738809 -101.721684) (xy 225.723314 -101.774187)
			(xy 225.700466 -101.823934) (xy 225.670736 -101.869899) (xy 225.653092 -101.89083) (xy 225.652838 -101.891084)
			(xy 225.647245 -101.898166) (xy 225.641004 -101.915086) (xy 225.640646 -101.924104) (xy 225.640646 -101.99116)
			(xy 225.641012 -102.000176) (xy 225.647252 -102.017094) (xy 225.652838 -102.02418) (xy 225.653092 -102.02418)
			(xy 225.653092 -102.024434) (xy 225.670763 -102.045342) (xy 225.700485 -102.091314) (xy 225.723328 -102.141065)
			(xy 225.738821 -102.193571) (xy 225.746646 -102.247752) (xy 225.746642 -102.302496) (xy 225.73881 -102.356677)
			(xy 225.723311 -102.40918) (xy 225.700462 -102.458928) (xy 225.670734 -102.504897) (xy 225.653092 -102.52583)
			(xy 225.652838 -102.526084) (xy 225.647245 -102.533166) (xy 225.641004 -102.550086) (xy 225.640646 -102.559104)
			(xy 225.640646 -102.62616) (xy 225.641012 -102.635176) (xy 225.647252 -102.652094) (xy 225.648871 -102.654148)
			(xy 226.6389 -102.654148) (xy 226.6389 -102.599652) (xy 226.646655 -102.54571) (xy 226.662008 -102.493421)
			(xy 226.684645 -102.443849) (xy 226.714107 -102.398003) (xy 226.749792 -102.356816) (xy 226.790976 -102.321127)
			(xy 226.836819 -102.291661) (xy 226.886389 -102.26902) (xy 226.938677 -102.253663) (xy 226.992618 -102.245903)
			(xy 227.019866 -102.245414) (xy 227.046182 -102.245833) (xy 227.098312 -102.253077) (xy 227.148956 -102.267405)
			(xy 227.197155 -102.288547) (xy 227.241997 -102.316102) (xy 227.282635 -102.349549) (xy 227.30079 -102.368604)
			(xy 227.308313 -102.376004) (xy 227.327592 -102.384529) (xy 227.338128 -102.385114) (xy 227.412804 -102.385114)
			(xy 227.423355 -102.384596) (xy 227.44265 -102.376053) (xy 227.450142 -102.368604) (xy 227.468285 -102.349536)
			(xy 227.508917 -102.31608) (xy 227.55376 -102.288522) (xy 227.601963 -102.267386) (xy 227.652613 -102.253072)
			(xy 227.704749 -102.24585) (xy 227.731066 -102.245414) (xy 227.758322 -102.245831) (xy 227.81228 -102.253584)
			(xy 227.864585 -102.268938) (xy 227.914172 -102.29158) (xy 227.960032 -102.321049) (xy 228.001231 -102.356745)
			(xy 228.036931 -102.397941) (xy 228.066404 -102.443798) (xy 228.08612 -102.486968) (xy 228.66223 -102.486968)
			(xy 228.66267 -102.459597) (xy 228.670493 -102.405416) (xy 228.685988 -102.352913) (xy 228.708835 -102.303166)
			(xy 228.738566 -102.257201) (xy 228.75621 -102.23627) (xy 228.756464 -102.236016) (xy 228.762058 -102.228935)
			(xy 228.768298 -102.212014) (xy 228.768656 -102.202996) (xy 228.768656 -102.13594) (xy 228.768289 -102.126924)
			(xy 228.76205 -102.110006) (xy 228.756464 -102.10292) (xy 228.75621 -102.10292) (xy 228.75621 -102.102666)
			(xy 228.738539 -102.081758) (xy 228.708816 -102.035786) (xy 228.685974 -101.986035) (xy 228.670481 -101.93353)
			(xy 228.662656 -101.879348) (xy 228.662659 -101.824604) (xy 228.670491 -101.770423) (xy 228.685991 -101.71792)
			(xy 228.70884 -101.668172) (xy 228.738568 -101.622203) (xy 228.75621 -101.60127) (xy 228.756464 -101.601016)
			(xy 228.762058 -101.593935) (xy 228.768298 -101.577014) (xy 228.768656 -101.567996) (xy 228.768656 -101.50094)
			(xy 228.768289 -101.491924) (xy 228.76205 -101.475006) (xy 228.756464 -101.46792) (xy 228.75621 -101.46792)
			(xy 228.75621 -101.467666) (xy 228.73859 -101.446719) (xy 228.708875 -101.40075) (xy 228.686035 -101.351007)
			(xy 228.67054 -101.298509) (xy 228.662707 -101.244336) (xy 228.66223 -101.216968) (xy 228.662716 -101.189717)
			(xy 228.670472 -101.135769) (xy 228.685827 -101.083474) (xy 228.708469 -101.033897) (xy 228.737935 -100.988047)
			(xy 228.773626 -100.946856) (xy 228.814817 -100.911165) (xy 228.860667 -100.881699) (xy 228.910244 -100.859057)
			(xy 228.962539 -100.843702) (xy 229.016487 -100.835946) (xy 229.070989 -100.835946) (xy 229.124937 -100.843702)
			(xy 229.177232 -100.859057) (xy 229.226809 -100.881699) (xy 229.272659 -100.911165) (xy 229.31385 -100.946856)
			(xy 229.349541 -100.988047) (xy 229.379007 -101.033897) (xy 229.401649 -101.083474) (xy 229.417004 -101.135769)
			(xy 229.42476 -101.189717) (xy 229.425246 -101.216968) (xy 229.424774 -101.244338) (xy 229.41696 -101.298518)
			(xy 229.401473 -101.351021) (xy 229.378632 -101.400768) (xy 229.348907 -101.446735) (xy 229.331266 -101.467666)
			(xy 229.331012 -101.46792) (xy 229.325412 -101.474998) (xy 229.319173 -101.491921) (xy 229.31882 -101.50094)
			(xy 229.31882 -101.567996) (xy 229.319174 -101.577013) (xy 229.325423 -101.59393) (xy 229.331012 -101.601016)
			(xy 229.331266 -101.601016) (xy 229.331266 -101.60127) (xy 229.348876 -101.622228) (xy 229.378602 -101.668191)
			(xy 229.40145 -101.717933) (xy 229.416949 -101.770432) (xy 229.424781 -101.824607) (xy 229.424784 -101.879345)
			(xy 229.416959 -101.933521) (xy 229.401467 -101.986022) (xy 229.378625 -102.035766) (xy 229.348905 -102.081733)
			(xy 229.331266 -102.102666) (xy 229.331012 -102.10292) (xy 229.325412 -102.109998) (xy 229.319173 -102.126921)
			(xy 229.31882 -102.13594) (xy 229.31882 -102.202996) (xy 229.319174 -102.212013) (xy 229.325423 -102.22893)
			(xy 229.331012 -102.236016) (xy 229.331266 -102.236016) (xy 229.331266 -102.23627) (xy 229.348899 -102.257207)
			(xy 229.378613 -102.303178) (xy 229.401451 -102.352924) (xy 229.416943 -102.405424) (xy 229.424772 -102.459599)
			(xy 229.425246 -102.486968) (xy 229.424979 -102.501954) (xy 231.856534 -102.501954) (xy 231.857023 -102.474585)
			(xy 231.864834 -102.420406) (xy 231.880318 -102.367903) (xy 231.903154 -102.318156) (xy 231.932875 -102.272188)
			(xy 231.950514 -102.251256) (xy 231.950768 -102.251002) (xy 231.956368 -102.243925) (xy 231.962605 -102.227001)
			(xy 231.96296 -102.217982) (xy 231.96296 -102.150926) (xy 231.962599 -102.141909) (xy 231.956355 -102.124992)
			(xy 231.950768 -102.117906) (xy 231.950514 -102.117906) (xy 231.950514 -102.117652) (xy 231.932829 -102.096755)
			(xy 231.903107 -102.050781) (xy 231.880265 -102.001029) (xy 231.864773 -101.948521) (xy 231.856949 -101.894338)
			(xy 231.856954 -101.839593) (xy 231.864788 -101.785411) (xy 231.880289 -101.732906) (xy 231.90314 -101.683158)
			(xy 231.932871 -101.637189) (xy 231.950514 -101.616256) (xy 231.950768 -101.616002) (xy 231.956368 -101.608925)
			(xy 231.962605 -101.592001) (xy 231.96296 -101.582982) (xy 231.96296 -101.515926) (xy 231.962599 -101.506909)
			(xy 231.956355 -101.489992) (xy 231.950768 -101.482906) (xy 231.950514 -101.482906) (xy 231.950514 -101.482652)
			(xy 231.932888 -101.461709) (xy 231.903174 -101.41574) (xy 231.880335 -101.365995) (xy 231.864841 -101.313496)
			(xy 231.85701 -101.259322) (xy 231.856534 -101.231954) (xy 231.85702 -101.204703) (xy 231.864776 -101.150755)
			(xy 231.880131 -101.09846) (xy 231.902773 -101.048883) (xy 231.932239 -101.003033) (xy 231.96793 -100.961842)
			(xy 232.009121 -100.926151) (xy 232.054971 -100.896685) (xy 232.104548 -100.874043) (xy 232.156843 -100.858688)
			(xy 232.210791 -100.850932) (xy 232.265293 -100.850932) (xy 232.319241 -100.858688) (xy 232.371536 -100.874043)
			(xy 232.421113 -100.896685) (xy 232.466963 -100.926151) (xy 232.508154 -100.961842) (xy 232.543845 -101.003033)
			(xy 232.573311 -101.048883) (xy 232.595953 -101.09846) (xy 232.611308 -101.150755) (xy 232.619064 -101.204703)
			(xy 232.61955 -101.231954) (xy 232.619069 -101.259324) (xy 232.611257 -101.313503) (xy 232.595772 -101.366006)
			(xy 232.572933 -101.415753) (xy 232.543211 -101.46172) (xy 232.52557 -101.482652) (xy 232.525316 -101.482906)
			(xy 232.519723 -101.489988) (xy 232.513479 -101.506908) (xy 232.513124 -101.515926) (xy 232.513124 -101.582982)
			(xy 232.513485 -101.591999) (xy 232.519729 -101.608916) (xy 232.525316 -101.616002) (xy 232.52557 -101.616002)
			(xy 232.52557 -101.616256) (xy 232.543166 -101.637225) (xy 232.572893 -101.683187) (xy 232.595741 -101.732927)
			(xy 232.611241 -101.785423) (xy 232.619074 -101.839597) (xy 232.619079 -101.894334) (xy 232.611256 -101.948509)
			(xy 232.595765 -102.001008) (xy 232.572926 -102.050753) (xy 232.543208 -102.096719) (xy 232.52557 -102.117652)
			(xy 232.525316 -102.117906) (xy 232.519723 -102.124988) (xy 232.513479 -102.141908) (xy 232.513124 -102.150926)
			(xy 232.513124 -102.201726) (xy 245.578374 -102.201726) (xy 245.582445 -102.146104) (xy 245.594571 -102.091667)
			(xy 245.614494 -102.039576) (xy 245.64179 -101.990941) (xy 245.675876 -101.946798) (xy 245.716025 -101.908089)
			(xy 245.761383 -101.875638) (xy 245.810983 -101.850137) (xy 245.863767 -101.83213) (xy 245.91861 -101.822)
			(xy 245.974344 -101.819963) (xy 246.029781 -101.826063) (xy 246.083738 -101.840169) (xy 246.135067 -101.861981)
			(xy 246.182673 -101.891035) (xy 246.225541 -101.92671) (xy 246.262758 -101.968247) (xy 246.293531 -102.01476)
			(xy 246.317203 -102.065257) (xy 246.333271 -102.118664) (xy 246.341391 -102.17384) (xy 246.3419 -102.201726)
			(xy 246.341391 -102.229612) (xy 246.333271 -102.284788) (xy 246.317203 -102.338195) (xy 246.293531 -102.388692)
			(xy 246.262758 -102.435205) (xy 246.225541 -102.476742) (xy 246.182673 -102.512417) (xy 246.135067 -102.541471)
			(xy 246.083738 -102.563283) (xy 246.029781 -102.577389) (xy 245.974344 -102.583489) (xy 245.91861 -102.581452)
			(xy 245.863767 -102.571322) (xy 245.810983 -102.553315) (xy 245.761383 -102.527814) (xy 245.716025 -102.495363)
			(xy 245.675876 -102.456654) (xy 245.64179 -102.412511) (xy 245.614494 -102.363876) (xy 245.594571 -102.311785)
			(xy 245.582445 -102.257348) (xy 245.578374 -102.201726) (xy 232.513124 -102.201726) (xy 232.513124 -102.217982)
			(xy 232.513485 -102.226999) (xy 232.519729 -102.243916) (xy 232.525316 -102.251002) (xy 232.52557 -102.251002)
			(xy 232.52557 -102.251256) (xy 232.543197 -102.272198) (xy 232.572912 -102.318167) (xy 232.595751 -102.367912)
			(xy 232.611244 -102.420411) (xy 232.619075 -102.474585) (xy 232.61955 -102.501954) (xy 232.619064 -102.529205)
			(xy 232.611308 -102.583153) (xy 232.595953 -102.635448) (xy 232.573311 -102.685025) (xy 232.543845 -102.730875)
			(xy 232.508154 -102.772066) (xy 232.466963 -102.807757) (xy 232.421113 -102.837223) (xy 232.371536 -102.859865)
			(xy 232.319241 -102.87522) (xy 232.265293 -102.882976) (xy 232.210791 -102.882976) (xy 232.156843 -102.87522)
			(xy 232.104548 -102.859865) (xy 232.054971 -102.837223) (xy 232.009121 -102.807757) (xy 231.96793 -102.772066)
			(xy 231.932239 -102.730875) (xy 231.902773 -102.685025) (xy 231.880131 -102.635448) (xy 231.864776 -102.583153)
			(xy 231.85702 -102.529205) (xy 231.856534 -102.501954) (xy 229.424979 -102.501954) (xy 229.42476 -102.514219)
			(xy 229.417004 -102.568167) (xy 229.401649 -102.620462) (xy 229.379007 -102.670039) (xy 229.349541 -102.715889)
			(xy 229.31385 -102.75708) (xy 229.272659 -102.792771) (xy 229.226809 -102.822237) (xy 229.177232 -102.844879)
			(xy 229.124937 -102.860234) (xy 229.070989 -102.86799) (xy 229.016487 -102.86799) (xy 228.962539 -102.860234)
			(xy 228.910244 -102.844879) (xy 228.860667 -102.822237) (xy 228.814817 -102.792771) (xy 228.773626 -102.75708)
			(xy 228.737935 -102.715889) (xy 228.708469 -102.670039) (xy 228.685827 -102.620462) (xy 228.670472 -102.568167)
			(xy 228.662716 -102.514219) (xy 228.66223 -102.486968) (xy 228.08612 -102.486968) (xy 228.08905 -102.493383)
			(xy 228.104409 -102.545687) (xy 228.112167 -102.599644) (xy 228.112167 -102.654156) (xy 228.104409 -102.708113)
			(xy 228.08905 -102.760417) (xy 228.066404 -102.810002) (xy 228.036931 -102.855859) (xy 228.001231 -102.897055)
			(xy 227.960032 -102.932751) (xy 227.914172 -102.96222) (xy 227.864585 -102.984862) (xy 227.817145 -102.998788)
			(xy 245.903133 -102.998788) (xy 245.910884 -102.944834) (xy 245.926235 -102.892532) (xy 245.948873 -102.842947)
			(xy 245.978337 -102.797088) (xy 246.014028 -102.755889) (xy 246.055219 -102.720189) (xy 246.101071 -102.690714)
			(xy 246.150651 -102.668065) (xy 246.20295 -102.652702) (xy 246.256903 -102.644939) (xy 246.311411 -102.644933)
			(xy 246.365365 -102.652684) (xy 246.417668 -102.668035) (xy 246.467253 -102.690673) (xy 246.513112 -102.720137)
			(xy 246.55431 -102.755828) (xy 246.590011 -102.797018) (xy 246.619485 -102.84287) (xy 246.642135 -102.89245)
			(xy 246.657497 -102.944749) (xy 246.665261 -102.998702) (xy 246.66575 -103.025956) (xy 246.665643 -103.038952)
			(xy 246.663863 -103.064883) (xy 246.662194 -103.077772) (xy 246.661141 -103.089375) (xy 246.668426 -103.111479)
			(xy 246.676164 -103.12019) (xy 246.74068 -103.185976) (xy 246.76227 -103.19385) (xy 246.773954 -103.19258)
			(xy 246.774462 -103.19258) (xy 246.785093 -103.191423) (xy 246.806441 -103.19015) (xy 246.817134 -103.19004)
			(xy 246.844382 -103.190515) (xy 246.898321 -103.198274) (xy 246.950608 -103.213631) (xy 247.000177 -103.236273)
			(xy 247.046019 -103.265738) (xy 247.087202 -103.301427) (xy 247.122886 -103.342614) (xy 247.152347 -103.388459)
			(xy 247.174983 -103.43803) (xy 247.190334 -103.490319) (xy 247.198088 -103.544259) (xy 247.198087 -103.598754)
			(xy 247.190331 -103.652695) (xy 247.174978 -103.704982) (xy 247.15234 -103.754553) (xy 247.122878 -103.800397)
			(xy 247.087192 -103.841582) (xy 247.046008 -103.87727) (xy 247.000165 -103.906733) (xy 246.950595 -103.929373)
			(xy 246.899357 -103.94442) (xy 251.43155 -103.94442) (xy 251.435621 -103.888798) (xy 251.447747 -103.834361)
			(xy 251.46767 -103.78227) (xy 251.494966 -103.733635) (xy 251.529052 -103.689492) (xy 251.569201 -103.650783)
			(xy 251.614559 -103.618332) (xy 251.664159 -103.592831) (xy 251.716943 -103.574824) (xy 251.771786 -103.564694)
			(xy 251.82752 -103.562657) (xy 251.882957 -103.568757) (xy 251.936914 -103.582863) (xy 251.988243 -103.604675)
			(xy 252.035849 -103.633729) (xy 252.078717 -103.669404) (xy 252.115934 -103.710941) (xy 252.146707 -103.757454)
			(xy 252.170379 -103.807951) (xy 252.186447 -103.861358) (xy 252.194567 -103.916534) (xy 252.195076 -103.94442)
			(xy 252.194567 -103.972306) (xy 252.186447 -104.027482) (xy 252.170379 -104.080889) (xy 252.146707 -104.131386)
			(xy 252.115934 -104.177899) (xy 252.078717 -104.219436) (xy 252.035849 -104.255111) (xy 251.988243 -104.284165)
			(xy 251.936914 -104.305977) (xy 251.882957 -104.320083) (xy 251.82752 -104.326183) (xy 251.771786 -104.324146)
			(xy 251.716943 -104.314016) (xy 251.664159 -104.296009) (xy 251.614559 -104.270508) (xy 251.569201 -104.238057)
			(xy 251.529052 -104.199348) (xy 251.494966 -104.155205) (xy 251.46767 -104.10657) (xy 251.447747 -104.054479)
			(xy 251.435621 -104.000042) (xy 251.43155 -103.94442) (xy 246.899357 -103.94442) (xy 246.898308 -103.944728)
			(xy 246.844368 -103.952486) (xy 246.789873 -103.952489) (xy 246.735932 -103.944737) (xy 246.683644 -103.929388)
			(xy 246.634071 -103.906753) (xy 246.588225 -103.877295) (xy 246.547037 -103.841612) (xy 246.511347 -103.80043)
			(xy 246.48188 -103.754589) (xy 246.459236 -103.705021) (xy 246.443877 -103.652735) (xy 246.436116 -103.598795)
			(xy 246.435626 -103.571548) (xy 246.435733 -103.558552) (xy 246.437513 -103.532621) (xy 246.439182 -103.519732)
			(xy 246.440239 -103.508129) (xy 246.432952 -103.486024) (xy 246.425212 -103.477314) (xy 246.360696 -103.411528)
			(xy 246.339106 -103.403654) (xy 246.327422 -103.404924) (xy 246.326914 -103.404924) (xy 246.316283 -103.406083)
			(xy 246.294935 -103.407355) (xy 246.284242 -103.407464) (xy 246.256988 -103.407067) (xy 246.203033 -103.399316)
			(xy 246.150731 -103.383965) (xy 246.101146 -103.361327) (xy 246.055287 -103.331862) (xy 246.014089 -103.296171)
			(xy 245.978389 -103.254981) (xy 245.948914 -103.209128) (xy 245.926265 -103.159548) (xy 245.910902 -103.10725)
			(xy 245.903139 -103.053297) (xy 245.903133 -102.998788) (xy 227.817145 -102.998788) (xy 227.81228 -103.000216)
			(xy 227.758322 -103.007969) (xy 227.731066 -103.00843) (xy 227.704752 -103.007976) (xy 227.652623 -103.000737)
			(xy 227.60198 -102.986414) (xy 227.553782 -102.96528) (xy 227.508938 -102.937732) (xy 227.468299 -102.904292)
			(xy 227.450142 -102.88524) (xy 227.442601 -102.877861) (xy 227.423336 -102.869322) (xy 227.412804 -102.86873)
			(xy 227.338128 -102.86873) (xy 227.327577 -102.869252) (xy 227.308281 -102.877791) (xy 227.30079 -102.88524)
			(xy 227.28264 -102.904301) (xy 227.242008 -102.937756) (xy 227.197167 -102.965313) (xy 227.148965 -102.986451)
			(xy 227.098317 -103.000767) (xy 227.046182 -103.007991) (xy 227.019866 -103.00843) (xy 226.992618 -103.007897)
			(xy 226.938677 -103.000137) (xy 226.886389 -102.98478) (xy 226.836819 -102.962139) (xy 226.790976 -102.932673)
			(xy 226.749792 -102.896984) (xy 226.714107 -102.855797) (xy 226.684645 -102.809951) (xy 226.662008 -102.760379)
			(xy 226.646655 -102.70809) (xy 226.6389 -102.654148) (xy 225.648871 -102.654148) (xy 225.652838 -102.65918)
			(xy 225.653092 -102.659688) (xy 225.664036 -102.672422) (xy 225.683877 -102.699514) (xy 225.692716 -102.71379)
			(xy 225.69805 -102.72268) (xy 225.715068 -102.734872) (xy 225.808286 -102.755192) (xy 225.82886 -102.750874)
			(xy 225.837496 -102.745032) (xy 225.861562 -102.729035) (xy 225.913492 -102.703691) (xy 225.96865 -102.686464)
			(xy 226.025774 -102.677749) (xy 226.054666 -102.677214) (xy 226.081922 -102.677631) (xy 226.13588 -102.685384)
			(xy 226.188185 -102.700738) (xy 226.237772 -102.72338) (xy 226.283632 -102.752849) (xy 226.324831 -102.788545)
			(xy 226.360531 -102.829741) (xy 226.390004 -102.875598) (xy 226.41265 -102.925183) (xy 226.428009 -102.977487)
			(xy 226.435767 -103.031444) (xy 226.435767 -103.085956) (xy 226.428009 -103.139913) (xy 226.41265 -103.192217)
			(xy 226.390004 -103.241802) (xy 226.360531 -103.287659) (xy 226.324831 -103.328855) (xy 226.283632 -103.364551)
			(xy 226.237772 -103.39402) (xy 226.188185 -103.416662) (xy 226.13588 -103.432016) (xy 226.081922 -103.439769)
			(xy 226.054666 -103.44023) (xy 226.026574 -103.439756) (xy 225.970996 -103.431525) (xy 225.917227 -103.415229)
			(xy 225.866429 -103.391223) (xy 225.819703 -103.360025) (xy 225.778058 -103.322311) (xy 225.742396 -103.278895)
			(xy 225.727514 -103.255064) (xy 225.72218 -103.246174) (xy 225.705162 -103.233982) (xy 225.611944 -103.213662)
			(xy 225.59137 -103.21798) (xy 225.582734 -103.223822) (xy 225.558664 -103.239812) (xy 225.506735 -103.265157)
			(xy 225.451579 -103.282385) (xy 225.394456 -103.291103) (xy 225.365564 -103.29164) (xy 225.338313 -103.291156)
			(xy 225.284367 -103.283395) (xy 225.232074 -103.268037) (xy 225.182499 -103.245394) (xy 225.13665 -103.215927)
			(xy 225.095462 -103.180236) (xy 225.059771 -103.139046) (xy 225.030304 -103.093197) (xy 225.007661 -103.043622)
			(xy 224.992304 -102.991329) (xy 224.984544 -102.937383) (xy 224.984056 -102.910132) (xy 219.465989 -102.910132)
			(xy 219.464643 -102.91928) (xy 219.448575 -102.972687) (xy 219.424903 -103.023184) (xy 219.39413 -103.069697)
			(xy 219.356913 -103.111234) (xy 219.314045 -103.146909) (xy 219.266439 -103.175963) (xy 219.21511 -103.197775)
			(xy 219.161153 -103.211881) (xy 219.105716 -103.217981) (xy 219.049982 -103.215944) (xy 218.995139 -103.205814)
			(xy 218.942355 -103.187807) (xy 218.892755 -103.162306) (xy 218.847397 -103.129855) (xy 218.807248 -103.091146)
			(xy 218.773162 -103.047003) (xy 218.745866 -102.998368) (xy 218.725943 -102.946277) (xy 218.713817 -102.89184)
			(xy 218.709746 -102.836218) (xy 218.30665 -102.836218) (xy 218.306141 -102.864104) (xy 218.298021 -102.91928)
			(xy 218.281953 -102.972687) (xy 218.258281 -103.023184) (xy 218.227508 -103.069697) (xy 218.190291 -103.111234)
			(xy 218.147423 -103.146909) (xy 218.099817 -103.175963) (xy 218.048488 -103.197775) (xy 217.994531 -103.211881)
			(xy 217.939094 -103.217981) (xy 217.88336 -103.215944) (xy 217.828517 -103.205814) (xy 217.775733 -103.187807)
			(xy 217.726133 -103.162306) (xy 217.680775 -103.129855) (xy 217.640626 -103.091146) (xy 217.60654 -103.047003)
			(xy 217.579244 -102.998368) (xy 217.559321 -102.946277) (xy 217.547195 -102.89184) (xy 217.543124 -102.836218)
			(xy 211.546791 -102.836218) (xy 211.498187 -102.874978) (xy 211.332864 -102.996578) (xy 211.162922 -103.111634)
			(xy 210.988621 -103.219973) (xy 210.810225 -103.321428) (xy 210.628007 -103.415846) (xy 210.442244 -103.503082)
			(xy 210.253219 -103.583005) (xy 210.061219 -103.655491) (xy 209.866537 -103.720431) (xy 209.66947 -103.777726)
			(xy 209.525282 -103.81361) (xy 214.526874 -103.81361) (xy 214.530945 -103.757988) (xy 214.543071 -103.703551)
			(xy 214.562994 -103.65146) (xy 214.59029 -103.602825) (xy 214.624376 -103.558682) (xy 214.664525 -103.519973)
			(xy 214.709883 -103.487522) (xy 214.759483 -103.462021) (xy 214.812267 -103.444014) (xy 214.86711 -103.433884)
			(xy 214.922844 -103.431847) (xy 214.978281 -103.437947) (xy 215.032238 -103.452053) (xy 215.083567 -103.473865)
			(xy 215.131173 -103.502919) (xy 215.174041 -103.538594) (xy 215.1973 -103.564553) (xy 220.431836 -103.564553)
			(xy 220.431836 -103.510047) (xy 220.439592 -103.456096) (xy 220.454948 -103.403798) (xy 220.477589 -103.354218)
			(xy 220.507055 -103.308364) (xy 220.542747 -103.26717) (xy 220.583938 -103.231475) (xy 220.62979 -103.202004)
			(xy 220.679368 -103.179359) (xy 220.731665 -103.163999) (xy 220.785615 -103.156238) (xy 220.812868 -103.15575)
			(xy 220.839962 -103.156196) (xy 220.893606 -103.163859) (xy 220.945626 -103.179037) (xy 220.994974 -103.201424)
			(xy 221.040658 -103.230568) (xy 221.081757 -103.265884) (xy 221.117446 -103.306661) (xy 221.147005 -103.352077)
			(xy 221.16984 -103.40122) (xy 221.17812 -103.427022) (xy 221.182542 -103.440368) (xy 221.197638 -103.464076)
			(xy 221.218626 -103.48277) (xy 221.243916 -103.495034) (xy 221.271592 -103.499938) (xy 221.299556 -103.49711)
			(xy 221.325689 -103.486766) (xy 221.337124 -103.478584) (xy 221.357132 -103.463741) (xy 221.400296 -103.438866)
			(xy 221.446336 -103.419833) (xy 221.494466 -103.406969) (xy 221.543862 -103.400493) (xy 221.568772 -103.400098)
			(xy 221.596027 -103.400547) (xy 221.649981 -103.408301) (xy 221.702283 -103.423655) (xy 221.751868 -103.446296)
			(xy 221.797725 -103.475764) (xy 221.838922 -103.511458) (xy 221.874619 -103.552652) (xy 221.90409 -103.598508)
			(xy 221.926735 -103.64809) (xy 221.942093 -103.700391) (xy 221.949851 -103.754345) (xy 221.949851 -103.808855)
			(xy 221.942093 -103.862809) (xy 221.926735 -103.91511) (xy 221.90409 -103.964692) (xy 221.874619 -104.010548)
			(xy 221.838922 -104.051742) (xy 221.797725 -104.087436) (xy 221.751868 -104.116904) (xy 221.702283 -104.139545)
			(xy 221.649981 -104.154899) (xy 221.596027 -104.162653) (xy 221.568772 -104.163114) (xy 221.541681 -104.162587)
			(xy 221.488042 -104.154931) (xy 221.436027 -104.139761) (xy 221.386682 -104.117384) (xy 221.340999 -104.08825)
			(xy 221.299899 -104.052944) (xy 221.264208 -104.012178) (xy 221.234645 -103.966772) (xy 221.211804 -103.91764)
			(xy 221.20352 -103.891842) (xy 221.199018 -103.878525) (xy 221.183941 -103.854816) (xy 221.162969 -103.836117)
			(xy 221.137692 -103.823848) (xy 221.110027 -103.818939) (xy 221.082072 -103.821761) (xy 221.055947 -103.832101)
			(xy 221.044516 -103.84028) (xy 221.024492 -103.8551) (xy 220.981332 -103.87998) (xy 220.935296 -103.899017)
			(xy 220.88717 -103.911887) (xy 220.837777 -103.918368) (xy 220.812868 -103.918766) (xy 220.785615 -103.918362)
			(xy 220.731665 -103.910601) (xy 220.679368 -103.895241) (xy 220.62979 -103.872596) (xy 220.583938 -103.843125)
			(xy 220.542747 -103.80743) (xy 220.507055 -103.766236) (xy 220.477589 -103.720382) (xy 220.454948 -103.670802)
			(xy 220.439592 -103.618504) (xy 220.431836 -103.564553) (xy 215.1973 -103.564553) (xy 215.211258 -103.580131)
			(xy 215.242031 -103.626644) (xy 215.265703 -103.677141) (xy 215.281771 -103.730548) (xy 215.289891 -103.785724)
			(xy 215.2904 -103.81361) (xy 215.289891 -103.841496) (xy 215.281771 -103.896672) (xy 215.265703 -103.950079)
			(xy 215.242031 -104.000576) (xy 215.211258 -104.047089) (xy 215.174041 -104.088626) (xy 215.131173 -104.124301)
			(xy 215.083567 -104.153355) (xy 215.032238 -104.175167) (xy 214.978281 -104.189273) (xy 214.922844 -104.195373)
			(xy 214.86711 -104.193336) (xy 214.812267 -104.183206) (xy 214.759483 -104.165199) (xy 214.709883 -104.139698)
			(xy 214.664525 -104.107247) (xy 214.624376 -104.068538) (xy 214.59029 -104.024395) (xy 214.562994 -103.97576)
			(xy 214.543071 -103.923669) (xy 214.530945 -103.869232) (xy 214.526874 -103.81361) (xy 209.525282 -103.81361)
			(xy 209.470317 -103.827289) (xy 209.269383 -103.869044) (xy 209.066972 -103.902927) (xy 208.863394 -103.928887)
			(xy 208.658957 -103.946884) (xy 208.453974 -103.956892) (xy 208.248757 -103.958894) (xy 208.043618 -103.952888)
			(xy 207.838869 -103.938883) (xy 207.634822 -103.9169) (xy 207.431789 -103.886973) (xy 207.230078 -103.849146)
			(xy 207.029996 -103.803479) (xy 206.831849 -103.75004) (xy 206.635937 -103.688911) (xy 206.44256 -103.620185)
			(xy 206.252011 -103.543966) (xy 206.064581 -103.46037) (xy 205.880555 -103.369526) (xy 205.700214 -103.271571)
			(xy 205.523832 -103.166654) (xy 205.351678 -103.054935) (xy 205.184013 -102.936585) (xy 205.021094 -102.811783)
			(xy 204.863168 -102.680719) (xy 204.710476 -102.543594) (xy 204.563251 -102.400616) (xy 204.421716 -102.252002)
			(xy 204.286087 -102.09798) (xy 204.15657 -101.938783) (xy 204.033364 -101.774654) (xy 203.916655 -101.605843)
			(xy 203.806621 -101.432606) (xy 203.70343 -101.255209) (xy 203.607239 -101.073921) (xy 203.518194 -100.889018)
			(xy 203.436431 -100.700781) (xy 203.362075 -100.509498) (xy 203.295239 -100.315459) (xy 203.236024 -100.11896)
			(xy 203.184521 -99.920301) (xy 203.140807 -99.719783) (xy 203.104951 -99.517712) (xy 203.077006 -99.314397)
			(xy 203.057015 -99.110146) (xy 203.045008 -98.90527) (xy 203.041004 -98.700082) (xy 198.888604 -98.700082)
			(xy 195.352162 -102.236524) (xy 195.344034 -102.243128) (xy 195.320666 -102.258368) (xy 195.300581 -102.270831)
			(xy 195.25742 -102.290097) (xy 195.211811 -102.302506) (xy 195.164838 -102.307763) (xy 195.117614 -102.305743)
			(xy 195.094352 -102.301548) (xy 195.073778 -102.296722) (xy 195.006468 -102.278434) (xy 194.975988 -102.289864)
			(xy 194.967352 -102.302564) (xy 194.953468 -102.322415) (xy 194.921453 -102.358772) (xy 194.885093 -102.390785)
			(xy 194.865244 -102.404672) (xy 194.852544 -102.413308) (xy 194.841114 -102.443788) (xy 194.850766 -102.479856)
			(xy 194.855794 -102.499414) (xy 194.861278 -102.539422) (xy 194.861688 -102.559612) (xy 194.861688 -102.600506)
			(xy 194.861089 -102.627368) (xy 194.851639 -102.680257) (xy 194.842892 -102.705662) (xy 194.840324 -102.713562)
			(xy 194.839945 -102.730159) (xy 194.84213 -102.738174) (xy 194.850512 -102.765352) (xy 194.853288 -102.773289)
			(xy 194.863148 -102.786898) (xy 194.869816 -102.792022) (xy 194.891066 -102.80735) (xy 194.929515 -102.842943)
			(xy 194.96273 -102.883465) (xy 194.972883 -102.90005) (xy 200.172572 -102.90005) (xy 200.172572 -102.84555)
			(xy 200.180328 -102.791603) (xy 200.195682 -102.73931) (xy 200.218321 -102.689733) (xy 200.247786 -102.643884)
			(xy 200.283475 -102.602693) (xy 200.324663 -102.567001) (xy 200.370511 -102.537534) (xy 200.420085 -102.514891)
			(xy 200.472378 -102.499533) (xy 200.526324 -102.491774) (xy 200.553574 -102.491286) (xy 200.581945 -102.49174)
			(xy 200.638062 -102.500126) (xy 200.692319 -102.516732) (xy 200.743517 -102.541192) (xy 200.790527 -102.572965)
			(xy 200.832313 -102.611352) (xy 200.867951 -102.655504) (xy 200.896657 -102.704448) (xy 200.917796 -102.757104)
			(xy 200.930902 -102.81231) (xy 200.933812 -102.840536) (xy 200.934828 -102.853998) (xy 200.950322 -102.87635)
			(xy 201.042524 -102.91953) (xy 201.05072 -102.922955) (xy 201.068403 -102.924511) (xy 201.085561 -102.919959)
			(xy 201.09307 -102.915212) (xy 201.117212 -102.899046) (xy 201.169355 -102.87342) (xy 201.22478 -102.855997)
			(xy 201.282206 -102.84718) (xy 201.311256 -102.846632) (xy 201.33851 -102.847096) (xy 201.392463 -102.854848)
			(xy 201.444763 -102.870201) (xy 201.494345 -102.892841) (xy 201.540201 -102.922308) (xy 201.581395 -102.958002)
			(xy 201.617089 -102.999196) (xy 201.646557 -103.045051) (xy 201.669198 -103.094633) (xy 201.684551 -103.146934)
			(xy 201.692303 -103.200886) (xy 201.692764 -103.22814) (xy 201.692349 -103.254082) (xy 201.685308 -103.305487)
			(xy 201.671361 -103.355461) (xy 201.650767 -103.403083) (xy 201.623905 -103.447473) (xy 201.607928 -103.467916)
			(xy 201.602475 -103.475373) (xy 201.596729 -103.492911) (xy 201.597543 -103.511349) (xy 201.600816 -103.519986)
			(xy 201.641964 -103.615744) (xy 201.66457 -103.632) (xy 201.678794 -103.63327) (xy 201.707145 -103.635988)
			(xy 201.762632 -103.648834) (xy 201.815591 -103.66979) (xy 201.864844 -103.698389) (xy 201.909295 -103.733996)
			(xy 201.947957 -103.775818) (xy 201.979968 -103.822925) (xy 202.004616 -103.874269) (xy 202.021354 -103.928708)
			(xy 202.029809 -103.985031) (xy 202.03033 -104.013508) (xy 202.029844 -104.040759) (xy 202.022088 -104.094707)
			(xy 202.006733 -104.147002) (xy 201.984091 -104.196579) (xy 201.954625 -104.242429) (xy 201.918934 -104.28362)
			(xy 201.877743 -104.319311) (xy 201.831893 -104.348777) (xy 201.782316 -104.371419) (xy 201.730021 -104.386774)
			(xy 201.676073 -104.39453) (xy 201.621571 -104.39453) (xy 201.567623 -104.386774) (xy 201.515328 -104.371419)
			(xy 201.465751 -104.348777) (xy 201.419901 -104.319311) (xy 201.37871 -104.28362) (xy 201.343019 -104.242429)
			(xy 201.313553 -104.196579) (xy 201.290911 -104.147002) (xy 201.275556 -104.094707) (xy 201.2678 -104.040759)
			(xy 201.267314 -104.013508) (xy 201.267761 -103.987567) (xy 201.274795 -103.936164) (xy 201.288734 -103.88619)
			(xy 201.309322 -103.838567) (xy 201.336177 -103.794176) (xy 201.35215 -103.773732) (xy 201.35764 -103.766299)
			(xy 201.363377 -103.748747) (xy 201.362546 -103.7303) (xy 201.359262 -103.721662) (xy 201.318114 -103.625904)
			(xy 201.295508 -103.609648) (xy 201.281284 -103.608378) (xy 201.254535 -103.605838) (xy 201.202084 -103.594184)
			(xy 201.151789 -103.575281) (xy 201.104646 -103.549503) (xy 201.06159 -103.517362) (xy 201.023473 -103.479493)
			(xy 200.991051 -103.436647) (xy 200.964965 -103.389674) (xy 200.945734 -103.339503) (xy 200.933738 -103.287129)
			(xy 200.931018 -103.260398) (xy 200.930002 -103.246936) (xy 200.914508 -103.224584) (xy 200.822306 -103.181404)
			(xy 200.814103 -103.177998) (xy 200.796424 -103.176432) (xy 200.779268 -103.180977) (xy 200.77176 -103.185722)
			(xy 200.747612 -103.201879) (xy 200.695471 -103.227506) (xy 200.640048 -103.244932) (xy 200.582623 -103.253752)
			(xy 200.553574 -103.254302) (xy 200.526324 -103.253826) (xy 200.472378 -103.246067) (xy 200.420085 -103.230709)
			(xy 200.370511 -103.208066) (xy 200.324663 -103.178599) (xy 200.283475 -103.142907) (xy 200.247786 -103.101716)
			(xy 200.218321 -103.055867) (xy 200.195682 -103.00629) (xy 200.180328 -102.953997) (xy 200.172572 -102.90005)
			(xy 194.972883 -102.90005) (xy 194.990086 -102.928153) (xy 195.011066 -102.976165) (xy 195.025276 -103.026596)
			(xy 195.032449 -103.078498) (xy 195.032884 -103.104696) (xy 195.032441 -103.13195) (xy 195.024684 -103.185903)
			(xy 195.009327 -103.238202) (xy 194.986683 -103.287784) (xy 194.957213 -103.333638) (xy 194.921518 -103.374832)
			(xy 194.880322 -103.410525) (xy 194.834467 -103.439993) (xy 194.784884 -103.462634) (xy 194.732583 -103.477988)
			(xy 194.67863 -103.485742) (xy 194.651376 -103.486204) (xy 194.622807 -103.48568) (xy 194.566306 -103.477176)
			(xy 194.511707 -103.460331) (xy 194.460236 -103.435524) (xy 194.413045 -103.403311) (xy 194.371192 -103.364413)
			(xy 194.335616 -103.319702) (xy 194.320922 -103.295196) (xy 194.314765 -103.285683) (xy 194.296134 -103.272831)
			(xy 194.273788 -103.269235) (xy 194.262756 -103.271828) (xy 194.242233 -103.277289) (xy 194.20017 -103.283149)
			(xy 194.178936 -103.283512) (xy 192.603882 -103.283512) (xy 192.578781 -103.282995) (xy 192.52926 -103.274752)
			(xy 192.481746 -103.25854) (xy 192.437516 -103.234792) (xy 192.397752 -103.204146) (xy 192.363522 -103.167422)
			(xy 192.335742 -103.125606) (xy 192.32499 -103.102918) (xy 192.323974 -103.100378) (xy 192.32245 -103.096314)
			(xy 192.282318 -103.003858) (xy 192.255902 -102.987348) (xy 192.241932 -102.987856) (xy 192.2399 -102.987856)
			(xy 192.212468 -102.987856) (xy 192.198498 -102.987348) (xy 192.172336 -103.003858) (xy 192.127886 -103.10622)
			(xy 192.125346 -103.111046) (xy 192.114253 -103.132828) (xy 192.086189 -103.172848) (xy 192.052124 -103.207901)
			(xy 192.012922 -103.237098) (xy 191.969581 -103.259697) (xy 191.9232 -103.275123) (xy 191.874957 -103.282985)
			(xy 191.850518 -103.283512) (xy 191.61125 -103.283512) (xy 191.600883 -103.284018) (xy 191.581866 -103.292283)
			(xy 191.57442 -103.299514) (xy 191.517016 -103.36022) (xy 191.509904 -103.380032) (xy 191.510666 -103.390446)
			(xy 191.511428 -103.415338) (xy 191.511428 -103.415846) (xy 191.51092 -103.433118) (xy 191.510412 -103.446072)
			(xy 191.521588 -103.46944) (xy 191.61252 -103.533448) (xy 191.638174 -103.536496) (xy 191.650112 -103.53167)
			(xy 191.67265 -103.523064) (xy 191.719357 -103.510983) (xy 191.767214 -103.504877) (xy 191.791336 -103.504492)
			(xy 191.791844 -103.504492) (xy 191.819093 -103.504981) (xy 191.873036 -103.512742) (xy 191.925326 -103.528101)
			(xy 191.974897 -103.550745) (xy 192.020742 -103.580212) (xy 192.061927 -103.615904) (xy 192.097614 -103.657093)
			(xy 192.127076 -103.702941) (xy 192.149714 -103.752516) (xy 192.165067 -103.804807) (xy 192.172822 -103.858751)
			(xy 192.172822 -103.913249) (xy 192.165067 -103.967193) (xy 192.149714 -104.019484) (xy 192.127076 -104.069059)
			(xy 192.097614 -104.114907) (xy 192.092598 -104.120696) (xy 194.269358 -104.120696) (xy 194.273429 -104.065074)
			(xy 194.285555 -104.010637) (xy 194.305478 -103.958546) (xy 194.332774 -103.909911) (xy 194.36686 -103.865768)
			(xy 194.407009 -103.827059) (xy 194.452367 -103.794608) (xy 194.501967 -103.769107) (xy 194.554751 -103.7511)
			(xy 194.609594 -103.74097) (xy 194.665328 -103.738933) (xy 194.720765 -103.745033) (xy 194.774722 -103.759139)
			(xy 194.826051 -103.780951) (xy 194.873657 -103.810005) (xy 194.916525 -103.84568) (xy 194.953742 -103.887217)
			(xy 194.984515 -103.93373) (xy 195.008187 -103.984227) (xy 195.024255 -104.037634) (xy 195.032375 -104.09281)
			(xy 195.032884 -104.120696) (xy 195.032375 -104.148582) (xy 195.024255 -104.203758) (xy 195.008187 -104.257165)
			(xy 194.984515 -104.307662) (xy 194.953742 -104.354175) (xy 194.916525 -104.395712) (xy 194.873657 -104.431387)
			(xy 194.826051 -104.460441) (xy 194.774722 -104.482253) (xy 194.735327 -104.492552) (xy 215.414096 -104.492552)
			(xy 215.418167 -104.43693) (xy 215.430293 -104.382493) (xy 215.450216 -104.330402) (xy 215.477512 -104.281767)
			(xy 215.511598 -104.237624) (xy 215.551747 -104.198915) (xy 215.597105 -104.166464) (xy 215.646705 -104.140963)
			(xy 215.699489 -104.122956) (xy 215.754332 -104.112826) (xy 215.810066 -104.110789) (xy 215.865503 -104.116889)
			(xy 215.91946 -104.130995) (xy 215.970789 -104.152807) (xy 216.018395 -104.181861) (xy 216.061263 -104.217536)
			(xy 216.09848 -104.259073) (xy 216.129253 -104.305586) (xy 216.152925 -104.356083) (xy 216.168993 -104.40949)
			(xy 216.177113 -104.464666) (xy 216.177622 -104.492552) (xy 216.177113 -104.520438) (xy 216.168993 -104.575614)
			(xy 216.152925 -104.629021) (xy 216.147719 -104.640126) (xy 216.7923 -104.640126) (xy 216.796371 -104.584504)
			(xy 216.808497 -104.530067) (xy 216.82842 -104.477976) (xy 216.855716 -104.429341) (xy 216.889802 -104.385198)
			(xy 216.929951 -104.346489) (xy 216.975309 -104.314038) (xy 217.024909 -104.288537) (xy 217.077693 -104.27053)
			(xy 217.132536 -104.2604) (xy 217.18827 -104.258363) (xy 217.243707 -104.264463) (xy 217.297664 -104.278569)
			(xy 217.348993 -104.300381) (xy 217.396599 -104.329435) (xy 217.439467 -104.36511) (xy 217.442366 -104.368346)
			(xy 218.571062 -104.368346) (xy 218.575133 -104.312724) (xy 218.587259 -104.258287) (xy 218.607182 -104.206196)
			(xy 218.634478 -104.157561) (xy 218.668564 -104.113418) (xy 218.708713 -104.074709) (xy 218.754071 -104.042258)
			(xy 218.803671 -104.016757) (xy 218.856455 -103.99875) (xy 218.911298 -103.98862) (xy 218.967032 -103.986583)
			(xy 219.022469 -103.992683) (xy 219.076426 -104.006789) (xy 219.127755 -104.028601) (xy 219.175361 -104.057655)
			(xy 219.218229 -104.09333) (xy 219.255446 -104.134867) (xy 219.286219 -104.18138) (xy 219.309891 -104.231877)
			(xy 219.325959 -104.285284) (xy 219.334079 -104.34046) (xy 219.334588 -104.368346) (xy 219.334079 -104.396232)
			(xy 219.325959 -104.451408) (xy 219.309891 -104.504815) (xy 219.286219 -104.555312) (xy 219.270912 -104.578448)
			(xy 222.806304 -104.578448) (xy 222.806304 -104.523952) (xy 222.814059 -104.470012) (xy 222.829411 -104.417724)
			(xy 222.852048 -104.368153) (xy 222.881508 -104.322308) (xy 222.917193 -104.281121) (xy 222.958376 -104.245432)
			(xy 223.004218 -104.215967) (xy 223.053787 -104.193325) (xy 223.106073 -104.177968) (xy 223.160013 -104.170207)
			(xy 223.18726 -104.169718) (xy 223.21463 -104.170203) (xy 223.268808 -104.178016) (xy 223.321311 -104.1935)
			(xy 223.371058 -104.216338) (xy 223.417026 -104.246058) (xy 223.437958 -104.263698) (xy 223.438212 -104.263952)
			(xy 223.445286 -104.269556) (xy 223.462213 -104.275791) (xy 223.471232 -104.276144) (xy 223.538288 -104.276144)
			(xy 223.547306 -104.275793) (xy 223.564223 -104.269543) (xy 223.571308 -104.263952) (xy 223.571308 -104.263698)
			(xy 223.571562 -104.263698) (xy 223.592497 -104.246063) (xy 223.638469 -104.216351) (xy 223.688216 -104.193514)
			(xy 223.740716 -104.178022) (xy 223.794891 -104.170193) (xy 223.82226 -104.169718) (xy 223.849517 -104.170126)
			(xy 223.903476 -104.177879) (xy 223.955782 -104.193233) (xy 224.00537 -104.215874) (xy 224.051232 -104.245343)
			(xy 224.092432 -104.28104) (xy 224.128133 -104.322236) (xy 224.157606 -104.368094) (xy 224.180253 -104.417681)
			(xy 224.195612 -104.469985) (xy 224.203371 -104.523943) (xy 224.203371 -104.578457) (xy 224.195612 -104.632415)
			(xy 224.180253 -104.684719) (xy 224.157606 -104.734306) (xy 224.128133 -104.780164) (xy 224.092432 -104.82136)
			(xy 224.051232 -104.857057) (xy 224.00537 -104.886526) (xy 223.955782 -104.909167) (xy 223.903476 -104.924521)
			(xy 223.849517 -104.932274) (xy 223.82226 -104.932734) (xy 223.79489 -104.932249) (xy 223.740711 -104.924438)
			(xy 223.688208 -104.908954) (xy 223.638461 -104.886116) (xy 223.592494 -104.856394) (xy 223.571562 -104.838754)
			(xy 223.571308 -104.8385) (xy 223.564223 -104.832911) (xy 223.547305 -104.826666) (xy 223.538288 -104.826308)
			(xy 223.471232 -104.826308) (xy 223.462216 -104.826678) (xy 223.445299 -104.832916) (xy 223.438212 -104.8385)
			(xy 223.438212 -104.838754) (xy 223.437958 -104.838754) (xy 223.417009 -104.856372) (xy 223.371042 -104.886089)
			(xy 223.321298 -104.908929) (xy 223.268801 -104.924425) (xy 223.214628 -104.932258) (xy 223.18726 -104.932734)
			(xy 223.160013 -104.932193) (xy 223.106073 -104.924432) (xy 223.053787 -104.909075) (xy 223.004218 -104.886433)
			(xy 222.958376 -104.856968) (xy 222.917193 -104.821279) (xy 222.881508 -104.780092) (xy 222.852048 -104.734247)
			(xy 222.829411 -104.684676) (xy 222.814059 -104.632388) (xy 222.806304 -104.578448) (xy 219.270912 -104.578448)
			(xy 219.255446 -104.601825) (xy 219.218229 -104.643362) (xy 219.175361 -104.679037) (xy 219.127755 -104.708091)
			(xy 219.076426 -104.729903) (xy 219.022469 -104.744009) (xy 218.967032 -104.750109) (xy 218.911298 -104.748072)
			(xy 218.856455 -104.737942) (xy 218.803671 -104.719935) (xy 218.754071 -104.694434) (xy 218.708713 -104.661983)
			(xy 218.668564 -104.623274) (xy 218.634478 -104.579131) (xy 218.607182 -104.530496) (xy 218.587259 -104.478405)
			(xy 218.575133 -104.423968) (xy 218.571062 -104.368346) (xy 217.442366 -104.368346) (xy 217.476684 -104.406647)
			(xy 217.507457 -104.45316) (xy 217.531129 -104.503657) (xy 217.547197 -104.557064) (xy 217.555317 -104.61224)
			(xy 217.555826 -104.640126) (xy 217.555317 -104.668012) (xy 217.547197 -104.723188) (xy 217.531129 -104.776595)
			(xy 217.507457 -104.827092) (xy 217.476684 -104.873605) (xy 217.439467 -104.915142) (xy 217.396599 -104.950817)
			(xy 217.348993 -104.979871) (xy 217.297664 -105.001683) (xy 217.243707 -105.015789) (xy 217.18827 -105.021889)
			(xy 217.132536 -105.019852) (xy 217.077693 -105.009722) (xy 217.024909 -104.991715) (xy 216.975309 -104.966214)
			(xy 216.929951 -104.933763) (xy 216.889802 -104.895054) (xy 216.855716 -104.850911) (xy 216.82842 -104.802276)
			(xy 216.808497 -104.750185) (xy 216.796371 -104.695748) (xy 216.7923 -104.640126) (xy 216.147719 -104.640126)
			(xy 216.129253 -104.679518) (xy 216.09848 -104.726031) (xy 216.061263 -104.767568) (xy 216.018395 -104.803243)
			(xy 215.970789 -104.832297) (xy 215.91946 -104.854109) (xy 215.865503 -104.868215) (xy 215.810066 -104.874315)
			(xy 215.754332 -104.872278) (xy 215.699489 -104.862148) (xy 215.646705 -104.844141) (xy 215.597105 -104.81864)
			(xy 215.551747 -104.786189) (xy 215.511598 -104.74748) (xy 215.477512 -104.703337) (xy 215.450216 -104.654702)
			(xy 215.430293 -104.602611) (xy 215.418167 -104.548174) (xy 215.414096 -104.492552) (xy 194.735327 -104.492552)
			(xy 194.720765 -104.496359) (xy 194.665328 -104.502459) (xy 194.609594 -104.500422) (xy 194.554751 -104.490292)
			(xy 194.501967 -104.472285) (xy 194.452367 -104.446784) (xy 194.407009 -104.414333) (xy 194.36686 -104.375624)
			(xy 194.332774 -104.331481) (xy 194.305478 -104.282846) (xy 194.285555 -104.230755) (xy 194.273429 -104.176318)
			(xy 194.269358 -104.120696) (xy 192.092598 -104.120696) (xy 192.061927 -104.156096) (xy 192.020742 -104.191788)
			(xy 191.974897 -104.221255) (xy 191.925326 -104.243899) (xy 191.873036 -104.259258) (xy 191.819093 -104.267019)
			(xy 191.791844 -104.267508) (xy 191.764651 -104.266987) (xy 191.710817 -104.259269) (xy 191.658624 -104.243984)
			(xy 191.609131 -104.22144) (xy 191.563342 -104.192096) (xy 191.522184 -104.156546) (xy 191.486493 -104.115511)
			(xy 191.456991 -104.069823) (xy 191.434277 -104.020409) (xy 191.418812 -103.968269) (xy 191.410909 -103.914461)
			(xy 191.410336 -103.88727) (xy 191.410336 -103.874316) (xy 191.39789 -103.85171) (xy 191.304164 -103.791512)
			(xy 191.278764 -103.789734) (xy 191.266826 -103.795068) (xy 191.239761 -103.806734) (xy 191.18318 -103.823223)
			(xy 191.124843 -103.831599) (xy 191.095376 -103.832152) (xy 191.094614 -103.832152) (xy 191.0642 -103.831643)
			(xy 191.004017 -103.822803) (xy 190.945759 -103.805309) (xy 190.890662 -103.779532) (xy 190.839898 -103.74602)
			(xy 190.794544 -103.705484) (xy 190.755564 -103.658787) (xy 190.723786 -103.606919) (xy 190.711328 -103.579168)
			(xy 190.705842 -103.567918) (xy 190.686393 -103.552207) (xy 190.674244 -103.549196) (xy 190.592456 -103.533448)
			(xy 190.58009 -103.531772) (xy 190.556261 -103.53907) (xy 190.54699 -103.547418) (xy 190.401956 -103.692452)
			(xy 190.395693 -103.699319) (xy 190.388092 -103.716258) (xy 190.387064 -103.734795) (xy 190.38951 -103.74376)
			(xy 190.42126 -103.84282) (xy 190.442596 -103.861362) (xy 190.45682 -103.863648) (xy 190.483241 -103.868518)
			(xy 190.534502 -103.884588) (xy 190.583002 -103.907692) (xy 190.62778 -103.937372) (xy 190.667951 -103.973041)
			(xy 190.70272 -104.013994) (xy 190.7314 -104.05942) (xy 190.753422 -104.10842) (xy 190.768351 -104.160026)
			(xy 190.775892 -104.213215) (xy 190.776352 -104.240076) (xy 190.7758 -104.267325) (xy 190.768047 -104.321268)
			(xy 190.752698 -104.373558) (xy 190.730062 -104.423133) (xy 190.700603 -104.468981) (xy 190.664918 -104.51017)
			(xy 190.623735 -104.545862) (xy 190.577892 -104.57533) (xy 190.528322 -104.597974) (xy 190.476034 -104.613333)
			(xy 190.422093 -104.621095) (xy 190.394844 -104.621584) (xy 190.367979 -104.621185) (xy 190.314783 -104.613639)
			(xy 190.263171 -104.598705) (xy 190.214164 -104.576678) (xy 190.168733 -104.547994) (xy 190.127774 -104.51322)
			(xy 190.0921 -104.473043) (xy 190.062415 -104.428259) (xy 190.039306 -104.379754) (xy 190.02323 -104.328486)
			(xy 190.018416 -104.302052) (xy 190.01613 -104.287828) (xy 189.997588 -104.266492) (xy 189.898528 -104.234488)
			(xy 189.889559 -104.232093) (xy 189.87104 -104.233153) (xy 189.854092 -104.240693) (xy 189.84722 -104.246934)
			(xy 188.112654 -105.981754) (xy 188.106441 -105.98854) (xy 188.098875 -106.005296) (xy 188.097668 -106.023642)
			(xy 188.099954 -106.032554) (xy 188.13018 -106.130852) (xy 188.151008 -106.149394) (xy 188.164724 -106.152188)
			(xy 188.207031 -106.160906) (xy 188.289939 -106.185174) (xy 188.370271 -106.216945) (xy 188.44735 -106.255952)
			(xy 188.520525 -106.301865) (xy 188.58918 -106.354298) (xy 188.652736 -106.412807) (xy 188.710656 -106.476901)
			(xy 188.762452 -106.546037) (xy 188.807687 -106.619633) (xy 188.845981 -106.697069) (xy 188.877009 -106.777691)
			(xy 188.90051 -106.86082) (xy 188.916287 -106.945754) (xy 188.924205 -107.031777) (xy 188.924692 -107.07497)
			(xy 188.924124 -107.118399) (xy 188.924122 -107.11842) (xy 190.307462 -107.11842) (xy 190.307462 -107.03152)
			(xy 190.31548 -106.944991) (xy 190.331448 -106.859571) (xy 190.355229 -106.775989) (xy 190.386621 -106.694957)
			(xy 190.425355 -106.617168) (xy 190.471102 -106.543284) (xy 190.523471 -106.473937) (xy 190.582015 -106.409717)
			(xy 190.646235 -106.351173) (xy 190.715582 -106.298804) (xy 190.789466 -106.253057) (xy 190.867255 -106.214323)
			(xy 190.948287 -106.182931) (xy 191.031869 -106.15915) (xy 191.117289 -106.143182) (xy 191.203818 -106.135164)
			(xy 191.290718 -106.135164) (xy 191.377247 -106.143182) (xy 191.462667 -106.15915) (xy 191.546249 -106.182931)
			(xy 191.627281 -106.214323) (xy 191.70507 -106.253057) (xy 191.778954 -106.298804) (xy 191.848301 -106.351173)
			(xy 191.912521 -106.409717) (xy 191.971065 -106.473937) (xy 192.023434 -106.543284) (xy 192.069181 -106.617168)
			(xy 192.107915 -106.694957) (xy 192.139307 -106.775989) (xy 192.163088 -106.859571) (xy 192.177001 -106.934)
			(xy 198.903336 -106.934) (xy 198.903793 -106.906629) (xy 198.911612 -106.85245) (xy 198.927103 -106.799946)
			(xy 198.949946 -106.750199) (xy 198.979673 -106.704233) (xy 198.997316 -106.683302) (xy 198.99757 -106.683048)
			(xy 199.003151 -106.675958) (xy 199.009399 -106.659044) (xy 199.009762 -106.650028) (xy 199.009762 -106.582972)
			(xy 199.009427 -106.573953) (xy 199.003165 -106.557035) (xy 198.99757 -106.549952) (xy 198.997316 -106.549952)
			(xy 198.997316 -106.549698) (xy 198.979676 -106.528765) (xy 198.949952 -106.482797) (xy 198.927107 -106.433051)
			(xy 198.911611 -106.380549) (xy 198.903783 -106.32637) (xy 198.903783 -106.27163) (xy 198.911611 -106.217451)
			(xy 198.927107 -106.164949) (xy 198.949952 -106.115203) (xy 198.979676 -106.069235) (xy 198.997316 -106.048302)
			(xy 198.99757 -106.048048) (xy 199.003151 -106.040958) (xy 199.009399 -106.024044) (xy 199.009762 -106.015028)
			(xy 199.009762 -105.947972) (xy 199.009427 -105.938953) (xy 199.003165 -105.922035) (xy 198.99757 -105.914952)
			(xy 198.997316 -105.914952) (xy 198.997316 -105.914698) (xy 198.979676 -105.893765) (xy 198.949952 -105.847797)
			(xy 198.927107 -105.798051) (xy 198.911611 -105.745549) (xy 198.903783 -105.69137) (xy 198.903783 -105.63663)
			(xy 198.911611 -105.582451) (xy 198.927107 -105.529949) (xy 198.949952 -105.480203) (xy 198.979676 -105.434235)
			(xy 198.997316 -105.413302) (xy 198.99757 -105.413048) (xy 199.003151 -105.405958) (xy 199.009399 -105.389044)
			(xy 199.009762 -105.380028) (xy 199.009762 -105.312972) (xy 199.009427 -105.303953) (xy 199.003165 -105.287035)
			(xy 198.99757 -105.279952) (xy 198.997316 -105.279952) (xy 198.997316 -105.279698) (xy 198.979665 -105.258775)
			(xy 198.949954 -105.2128) (xy 198.92712 -105.16305) (xy 198.911632 -105.110548) (xy 198.903808 -105.05637)
			(xy 198.903336 -105.029) (xy 198.903822 -105.001749) (xy 198.911578 -104.947801) (xy 198.926933 -104.895506)
			(xy 198.949575 -104.845929) (xy 198.979041 -104.800079) (xy 199.014732 -104.758888) (xy 199.055923 -104.723197)
			(xy 199.101773 -104.693731) (xy 199.15135 -104.671089) (xy 199.203645 -104.655734) (xy 199.257593 -104.647978)
			(xy 199.312095 -104.647978) (xy 199.366043 -104.655734) (xy 199.418338 -104.671089) (xy 199.467915 -104.693731)
			(xy 199.513765 -104.723197) (xy 199.554956 -104.758888) (xy 199.590647 -104.800079) (xy 199.620113 -104.845929)
			(xy 199.642755 -104.895506) (xy 199.65811 -104.947801) (xy 199.665866 -105.001749) (xy 199.666352 -105.029)
			(xy 199.665898 -105.056371) (xy 199.658079 -105.110551) (xy 199.652913 -105.12806) (xy 217.654632 -105.12806)
			(xy 217.655118 -105.100809) (xy 217.662874 -105.046861) (xy 217.678229 -104.994566) (xy 217.700871 -104.944989)
			(xy 217.730337 -104.899139) (xy 217.766028 -104.857948) (xy 217.807219 -104.822257) (xy 217.853069 -104.792791)
			(xy 217.902646 -104.770149) (xy 217.954941 -104.754794) (xy 218.008889 -104.747038) (xy 218.063391 -104.747038)
			(xy 218.117339 -104.754794) (xy 218.169634 -104.770149) (xy 218.219211 -104.792791) (xy 218.265061 -104.822257)
			(xy 218.306252 -104.857948) (xy 218.341943 -104.899139) (xy 218.371409 -104.944989) (xy 218.394051 -104.994566)
			(xy 218.409406 -105.046861) (xy 218.417162 -105.100809) (xy 218.417648 -105.12806) (xy 218.417163 -105.155052)
			(xy 218.409562 -105.208499) (xy 218.394508 -105.260343) (xy 218.372299 -105.309548) (xy 218.34338 -105.355133)
			(xy 218.326208 -105.375964) (xy 218.319096 -105.384092) (xy 218.313 -105.404666) (xy 218.323922 -105.49001)
			(xy 218.32568 -105.500559) (xy 218.336746 -105.51884) (xy 218.337029 -105.519055) (xy 222.355843 -105.519055)
			(xy 222.355843 -105.464545) (xy 222.363601 -105.410591) (xy 222.378958 -105.35829) (xy 222.401603 -105.308707)
			(xy 222.431073 -105.262852) (xy 222.46677 -105.221657) (xy 222.507966 -105.185962) (xy 222.553823 -105.156494)
			(xy 222.603407 -105.133852) (xy 222.655709 -105.118497) (xy 222.709663 -105.110742) (xy 222.736918 -105.11028)
			(xy 222.76429 -105.110716) (xy 222.818471 -105.118538) (xy 222.870975 -105.134033) (xy 222.920721 -105.156882)
			(xy 222.966686 -105.186615) (xy 222.987616 -105.20426) (xy 222.98787 -105.204514) (xy 222.99496 -105.210096)
			(xy 223.011874 -105.216345) (xy 223.02089 -105.216706) (xy 223.087946 -105.216706) (xy 223.09696 -105.216322)
			(xy 223.113877 -105.210093) (xy 223.120966 -105.204514) (xy 223.120966 -105.20426) (xy 223.12122 -105.20426)
			(xy 223.142166 -105.186638) (xy 223.188136 -105.156925) (xy 223.23788 -105.134086) (xy 223.290377 -105.118591)
			(xy 223.34455 -105.110757) (xy 223.371918 -105.11028) (xy 223.399168 -105.110791) (xy 223.453112 -105.11855)
			(xy 223.505402 -105.133906) (xy 223.554976 -105.156547) (xy 223.600822 -105.186013) (xy 223.642009 -105.221704)
			(xy 223.677698 -105.262892) (xy 223.707161 -105.30874) (xy 223.7298 -105.358314) (xy 223.745154 -105.410606)
			(xy 223.75291 -105.46455) (xy 223.75291 -105.510953) (xy 225.112538 -105.510953) (xy 225.112538 -105.456447)
			(xy 225.120295 -105.402495) (xy 225.13565 -105.350197) (xy 225.158292 -105.300615) (xy 225.18776 -105.254761)
			(xy 225.223453 -105.213567) (xy 225.264645 -105.177872) (xy 225.310498 -105.148402) (xy 225.360078 -105.125757)
			(xy 225.412376 -105.110399) (xy 225.466327 -105.102639) (xy 225.49358 -105.102152) (xy 225.52095 -105.102617)
			(xy 225.57513 -105.110433) (xy 225.627634 -105.125922) (xy 225.677381 -105.148764) (xy 225.723347 -105.17849)
			(xy 225.744278 -105.196132) (xy 225.744532 -105.196386) (xy 225.751635 -105.201949) (xy 225.768539 -105.20821)
			(xy 225.777552 -105.208578) (xy 225.844608 -105.208578) (xy 225.853626 -105.20823) (xy 225.870543 -105.201977)
			(xy 225.877628 -105.196386) (xy 225.877628 -105.196132) (xy 225.877882 -105.196132) (xy 225.898814 -105.178493)
			(xy 225.944786 -105.14878) (xy 225.994534 -105.125943) (xy 226.047035 -105.110453) (xy 226.101211 -105.102625)
			(xy 226.12858 -105.102152) (xy 226.155831 -105.102694) (xy 226.209778 -105.110448) (xy 226.262073 -105.1258)
			(xy 226.311651 -105.148439) (xy 226.357501 -105.177904) (xy 226.398692 -105.213594) (xy 226.434384 -105.254783)
			(xy 226.463851 -105.300632) (xy 226.486493 -105.350208) (xy 226.501848 -105.402502) (xy 226.509605 -105.456449)
			(xy 226.509605 -105.510951) (xy 226.501848 -105.564898) (xy 226.486493 -105.617192) (xy 226.463851 -105.666768)
			(xy 226.434384 -105.712617) (xy 226.398692 -105.753806) (xy 226.357501 -105.789496) (xy 226.311651 -105.818961)
			(xy 226.262073 -105.8416) (xy 226.209778 -105.856952) (xy 226.155831 -105.864706) (xy 226.12858 -105.865168)
			(xy 226.101209 -105.864721) (xy 226.047029 -105.8569) (xy 225.994525 -105.841407) (xy 225.944779 -105.818561)
			(xy 225.898813 -105.788831) (xy 225.877882 -105.771188) (xy 225.877628 -105.770934) (xy 225.870543 -105.765345)
			(xy 225.853625 -105.759102) (xy 225.844608 -105.758742) (xy 225.777552 -105.758742) (xy 225.768537 -105.759115)
			(xy 225.751619 -105.76535) (xy 225.744532 -105.770934) (xy 225.744532 -105.771188) (xy 225.744278 -105.771188)
			(xy 225.723326 -105.788802) (xy 225.677359 -105.818518) (xy 225.627616 -105.841359) (xy 225.57512 -105.856856)
			(xy 225.520948 -105.864691) (xy 225.49358 -105.865168) (xy 225.466327 -105.864761) (xy 225.412376 -105.857001)
			(xy 225.360078 -105.841643) (xy 225.310498 -105.818998) (xy 225.264645 -105.789528) (xy 225.223453 -105.753833)
			(xy 225.18776 -105.712639) (xy 225.158292 -105.666785) (xy 225.13565 -105.617203) (xy 225.120295 -105.564905)
			(xy 225.112538 -105.510953) (xy 223.75291 -105.510953) (xy 223.75291 -105.51905) (xy 223.745154 -105.572994)
			(xy 223.7298 -105.625286) (xy 223.707161 -105.67486) (xy 223.677698 -105.720708) (xy 223.642009 -105.761896)
			(xy 223.600822 -105.797587) (xy 223.554976 -105.827053) (xy 223.505402 -105.849694) (xy 223.453112 -105.86505)
			(xy 223.399168 -105.872809) (xy 223.371918 -105.873296) (xy 223.344548 -105.87282) (xy 223.290369 -105.865005)
			(xy 223.237866 -105.849518) (xy 223.188119 -105.826679) (xy 223.142152 -105.796956) (xy 223.12122 -105.779316)
			(xy 223.120966 -105.779062) (xy 223.113868 -105.773493) (xy 223.09696 -105.767237) (xy 223.087946 -105.76687)
			(xy 223.02089 -105.76687) (xy 223.011873 -105.767229) (xy 222.994957 -105.773476) (xy 222.98787 -105.779062)
			(xy 222.98787 -105.779316) (xy 222.987616 -105.779316) (xy 222.966691 -105.796964) (xy 222.920716 -105.826674)
			(xy 222.870967 -105.849508) (xy 222.818464 -105.864997) (xy 222.764288 -105.872823) (xy 222.736918 -105.873296)
			(xy 222.709663 -105.872858) (xy 222.655709 -105.865103) (xy 222.603407 -105.849748) (xy 222.553823 -105.827106)
			(xy 222.507966 -105.797638) (xy 222.46677 -105.761943) (xy 222.431073 -105.720748) (xy 222.401603 -105.674893)
			(xy 222.378958 -105.62531) (xy 222.363601 -105.573009) (xy 222.355843 -105.519055) (xy 218.337029 -105.519055)
			(xy 218.345258 -105.525316) (xy 218.369563 -105.542923) (xy 218.41282 -105.584522) (xy 218.431364 -105.60812)
			(xy 218.437206 -105.615994) (xy 218.454732 -105.626408) (xy 218.545156 -105.639616) (xy 218.56446 -105.63479)
			(xy 218.572334 -105.628948) (xy 218.572588 -105.628948) (xy 218.597318 -105.611424) (xy 218.651176 -105.583625)
			(xy 218.708752 -105.564695) (xy 218.768598 -105.555109) (xy 218.798902 -105.554526) (xy 218.826156 -105.554954)
			(xy 218.88011 -105.562712) (xy 218.932411 -105.57807) (xy 218.981993 -105.600715) (xy 219.027848 -105.630186)
			(xy 219.069042 -105.665884) (xy 219.104735 -105.707081) (xy 219.134202 -105.752938) (xy 219.156843 -105.802523)
			(xy 219.172196 -105.854825) (xy 219.179949 -105.90878) (xy 219.18041 -105.936034) (xy 219.179985 -105.962068)
			(xy 219.172893 -106.013652) (xy 219.158859 -106.063794) (xy 219.151679 -106.080351) (xy 219.615483 -106.080351)
			(xy 219.615483 -106.025849) (xy 219.62324 -105.971901) (xy 219.638596 -105.919606) (xy 219.661237 -105.870028)
			(xy 219.690704 -105.824178) (xy 219.726397 -105.782988) (xy 219.767588 -105.747297) (xy 219.813439 -105.717831)
			(xy 219.863017 -105.695191) (xy 219.915312 -105.679837) (xy 219.969261 -105.672082) (xy 219.996512 -105.67162)
			(xy 220.022854 -105.672053) (xy 220.075035 -105.67931) (xy 220.125723 -105.69367) (xy 220.173956 -105.714862)
			(xy 220.218819 -105.742483) (xy 220.259459 -105.776008) (xy 220.295105 -105.814801) (xy 220.310456 -105.836212)
			(xy 220.319216 -105.847982) (xy 220.342029 -105.866408) (xy 220.369139 -105.877587) (xy 220.398308 -105.880599)
			(xy 220.42713 -105.875195) (xy 220.453227 -105.86182) (xy 220.474445 -105.841578) (xy 220.48216 -105.8291)
			(xy 220.496878 -105.804579) (xy 220.532477 -105.759821) (xy 220.574356 -105.720878) (xy 220.621579 -105.688621)
			(xy 220.673087 -105.663773) (xy 220.727727 -105.64689) (xy 220.784274 -105.63835) (xy 220.812868 -105.637838)
			(xy 220.840126 -105.638207) (xy 220.894087 -105.645961) (xy 220.946395 -105.661316) (xy 220.995985 -105.68396)
			(xy 221.041848 -105.71343) (xy 221.083049 -105.749128) (xy 221.118751 -105.790327) (xy 221.148225 -105.836187)
			(xy 221.170873 -105.885775) (xy 221.186232 -105.938082) (xy 221.193991 -105.992042) (xy 221.193991 -106.046558)
			(xy 221.186232 -106.100518) (xy 221.170873 -106.152825) (xy 221.148225 -106.202413) (xy 221.118751 -106.248273)
			(xy 221.083049 -106.289472) (xy 221.041848 -106.32517) (xy 220.995985 -106.35464) (xy 220.946395 -106.377284)
			(xy 220.894087 -106.392639) (xy 220.840126 -106.400393) (xy 220.812868 -106.400854) (xy 220.786528 -106.400372)
			(xy 220.734349 -106.393125) (xy 220.683661 -106.378774) (xy 220.635427 -106.35759) (xy 220.590564 -106.329977)
			(xy 220.549923 -106.296458) (xy 220.514276 -106.25767) (xy 220.498924 -106.236262) (xy 220.490198 -106.224461)
			(xy 220.467381 -106.206021) (xy 220.440262 -106.194833) (xy 220.41108 -106.191821) (xy 220.382247 -106.197234)
			(xy 220.356145 -106.210624) (xy 220.33493 -106.230886) (xy 220.32722 -106.243374) (xy 220.312507 -106.267898)
			(xy 220.276908 -106.312657) (xy 220.235028 -106.351601) (xy 220.187804 -106.383858) (xy 220.136295 -106.408706)
			(xy 220.081655 -106.425588) (xy 220.025107 -106.434125) (xy 219.996512 -106.434636) (xy 219.969261 -106.434118)
			(xy 219.915312 -106.426363) (xy 219.863017 -106.411009) (xy 219.813439 -106.388369) (xy 219.767588 -106.358903)
			(xy 219.726397 -106.323212) (xy 219.690704 -106.282022) (xy 219.661237 -106.236172) (xy 219.638596 -106.186594)
			(xy 219.62324 -106.134299) (xy 219.615483 -106.080351) (xy 219.151679 -106.080351) (xy 219.138143 -106.111565)
			(xy 219.111129 -106.156079) (xy 219.095066 -106.176572) (xy 219.089322 -106.184327) (xy 219.083584 -106.202739)
			(xy 219.08389 -106.212386) (xy 219.09024 -106.292142) (xy 219.098876 -106.309922) (xy 219.106242 -106.316272)
			(xy 219.125887 -106.334454) (xy 219.160411 -106.37536) (xy 219.188882 -106.420688) (xy 219.21074 -106.46955)
			(xy 219.225557 -106.520986) (xy 219.233042 -106.573988) (xy 219.233496 -106.600752) (xy 219.233 -106.628004)
			(xy 219.225249 -106.681955) (xy 219.209899 -106.734253) (xy 219.187261 -106.783833) (xy 219.157797 -106.829687)
			(xy 219.122106 -106.870881) (xy 219.080916 -106.906575) (xy 219.035065 -106.936044) (xy 218.985486 -106.958686)
			(xy 218.93319 -106.974042) (xy 218.87924 -106.981797) (xy 218.851988 -106.98226) (xy 218.823214 -106.981747)
			(xy 218.76632 -106.973091) (xy 218.71137 -106.955991) (xy 218.65961 -106.930835) (xy 218.612213 -106.898194)
			(xy 218.590876 -106.878882) (xy 218.583002 -106.871516) (xy 218.56319 -106.864404) (xy 218.466924 -106.87177)
			(xy 218.448128 -106.881676) (xy 218.441524 -106.890058) (xy 218.42332 -106.91226) (xy 218.381381 -106.95147)
			(xy 218.334041 -106.983954) (xy 218.282369 -107.00898) (xy 218.227531 -107.025982) (xy 218.170765 -107.034577)
			(xy 218.142058 -107.035092) (xy 218.114805 -107.034661) (xy 218.060854 -107.026899) (xy 218.008558 -107.011537)
			(xy 217.958979 -106.98889) (xy 217.913128 -106.959418) (xy 217.871938 -106.923721) (xy 217.836247 -106.882525)
			(xy 217.806782 -106.83667) (xy 217.784142 -106.787088) (xy 217.768789 -106.734789) (xy 217.761035 -106.680837)
			(xy 217.76055 -106.653584) (xy 217.761021 -106.626682) (xy 217.768594 -106.573413) (xy 217.783573 -106.521736)
			(xy 217.805662 -106.472675) (xy 217.834423 -106.427203) (xy 217.869285 -106.386221) (xy 217.909558 -106.350541)
			(xy 217.931746 -106.335322) (xy 217.942668 -106.32821) (xy 217.954606 -106.30535) (xy 217.952574 -106.193082)
			(xy 217.93962 -106.17073) (xy 217.928444 -106.163872) (xy 217.904851 -106.148937) (xy 217.861897 -106.113262)
			(xy 217.824601 -106.071707) (xy 217.793762 -106.02516) (xy 217.770037 -105.974614) (xy 217.753934 -105.921149)
			(xy 217.745796 -105.865908) (xy 217.74531 -105.83799) (xy 217.745776 -105.810997) (xy 217.753383 -105.75755)
			(xy 217.768442 -105.705707) (xy 217.790655 -105.656502) (xy 217.819577 -105.610917) (xy 217.83675 -105.590086)
			(xy 217.843862 -105.581958) (xy 217.849958 -105.561384) (xy 217.839036 -105.47604) (xy 217.837233 -105.465503)
			(xy 217.826198 -105.447218) (xy 217.8177 -105.440734) (xy 217.79648 -105.425367) (xy 217.758029 -105.38978)
			(xy 217.724811 -105.349265) (xy 217.697452 -105.304585) (xy 217.676467 -105.256579) (xy 217.66225 -105.206153)
			(xy 217.65507 -105.154256) (xy 217.654632 -105.12806) (xy 199.652913 -105.12806) (xy 199.642588 -105.163055)
			(xy 199.619743 -105.212801) (xy 199.590015 -105.258767) (xy 199.572372 -105.279698) (xy 199.572118 -105.279952)
			(xy 199.566548 -105.28705) (xy 199.560291 -105.303958) (xy 199.559926 -105.312972) (xy 199.559926 -105.380028)
			(xy 199.560264 -105.389047) (xy 199.566524 -105.405964) (xy 199.572118 -105.413048) (xy 199.572372 -105.413048)
			(xy 199.572372 -105.413302) (xy 199.590013 -105.434235) (xy 199.619738 -105.480202) (xy 199.642583 -105.529949)
			(xy 199.658079 -105.582451) (xy 199.665908 -105.636629) (xy 199.665908 -105.691371) (xy 199.658079 -105.745549)
			(xy 199.642583 -105.798051) (xy 199.619738 -105.847798) (xy 199.590013 -105.893765) (xy 199.572372 -105.914698)
			(xy 199.572118 -105.914952) (xy 199.566548 -105.92205) (xy 199.560291 -105.938958) (xy 199.559926 -105.947972)
			(xy 199.559926 -106.015028) (xy 199.560264 -106.024047) (xy 199.566524 -106.040964) (xy 199.572118 -106.048048)
			(xy 199.572372 -106.048048) (xy 199.572372 -106.048302) (xy 199.590013 -106.069235) (xy 199.619738 -106.115202)
			(xy 199.642583 -106.164949) (xy 199.658079 -106.217451) (xy 199.665908 -106.271629) (xy 199.665908 -106.326371)
			(xy 199.658079 -106.380549) (xy 199.642583 -106.433051) (xy 199.619738 -106.482798) (xy 199.590013 -106.528765)
			(xy 199.572372 -106.549698) (xy 199.572118 -106.549952) (xy 199.566548 -106.55705) (xy 199.560291 -106.573958)
			(xy 199.559926 -106.582972) (xy 199.559926 -106.650028) (xy 199.560264 -106.659047) (xy 199.566524 -106.675964)
			(xy 199.572118 -106.683048) (xy 199.572372 -106.683048) (xy 199.572372 -106.683302) (xy 199.590021 -106.704226)
			(xy 199.619732 -106.750201) (xy 199.642567 -106.79995) (xy 199.658055 -106.852453) (xy 199.66588 -106.90663)
			(xy 199.666352 -106.934) (xy 199.665866 -106.961251) (xy 199.65811 -107.015199) (xy 199.642755 -107.067494)
			(xy 199.620113 -107.117071) (xy 199.590647 -107.162921) (xy 199.554956 -107.204112) (xy 199.513765 -107.239803)
			(xy 199.467915 -107.269269) (xy 199.418338 -107.291911) (xy 199.366043 -107.307266) (xy 199.312095 -107.315022)
			(xy 199.257593 -107.315022) (xy 199.203645 -107.307266) (xy 199.15135 -107.291911) (xy 199.101773 -107.269269)
			(xy 199.055923 -107.239803) (xy 199.014732 -107.204112) (xy 198.979041 -107.162921) (xy 198.949575 -107.117071)
			(xy 198.926933 -107.067494) (xy 198.911578 -107.015199) (xy 198.903822 -106.961251) (xy 198.903336 -106.934)
			(xy 192.177001 -106.934) (xy 192.179056 -106.944991) (xy 192.187074 -107.03152) (xy 192.187576 -107.07497)
			(xy 192.187074 -107.11842) (xy 192.179056 -107.204949) (xy 192.163088 -107.290369) (xy 192.139307 -107.373951)
			(xy 192.124753 -107.41152) (xy 221.678754 -107.41152) (xy 221.679217 -107.385206) (xy 221.686451 -107.333076)
			(xy 221.700769 -107.282433) (xy 221.721902 -107.234233) (xy 221.74945 -107.18939) (xy 221.782891 -107.148752)
			(xy 221.801944 -107.130596) (xy 221.809341 -107.12307) (xy 221.81787 -107.103794) (xy 221.818454 -107.093258)
			(xy 221.818454 -107.018582) (xy 221.817907 -107.008034) (xy 221.809386 -106.988738) (xy 221.801944 -106.981244)
			(xy 221.782858 -106.96312) (xy 221.749405 -106.922482) (xy 221.721852 -106.877635) (xy 221.700719 -106.829428)
			(xy 221.686408 -106.778776) (xy 221.679189 -106.726638) (xy 221.678754 -106.70032) (xy 221.679297 -106.673071)
			(xy 221.68705 -106.619127) (xy 221.7024 -106.566836) (xy 221.725036 -106.517261) (xy 221.754497 -106.471413)
			(xy 221.790182 -106.430223) (xy 221.831366 -106.394532) (xy 221.877211 -106.365064) (xy 221.926782 -106.34242)
			(xy 221.979071 -106.327062) (xy 222.033013 -106.319301) (xy 222.060262 -106.318812) (xy 222.087926 -106.319348)
			(xy 222.142675 -106.327343) (xy 222.195696 -106.343155) (xy 222.24588 -106.366454) (xy 222.292176 -106.396751)
			(xy 222.333615 -106.433413) (xy 222.369328 -106.475672) (xy 222.384366 -106.498898) (xy 222.391031 -106.508552)
			(xy 222.410871 -106.52101) (xy 222.422466 -106.522774) (xy 222.502476 -106.530648) (xy 222.514114 -106.531258)
			(xy 222.53595 -106.523193) (xy 222.544386 -106.515154) (xy 222.54464 -106.5149) (xy 222.562719 -106.496317)
			(xy 222.603052 -106.463739) (xy 222.647426 -106.436926) (xy 222.695025 -106.416374) (xy 222.74497 -106.402461)
			(xy 222.796339 -106.395444) (xy 222.822262 -106.395012) (xy 222.849515 -106.395491) (xy 222.903466 -106.403243)
			(xy 222.955765 -106.418595) (xy 223.005346 -106.441235) (xy 223.051201 -106.470701) (xy 223.092394 -106.506393)
			(xy 223.128089 -106.547585) (xy 223.157557 -106.593438) (xy 223.180198 -106.643018) (xy 223.195553 -106.695316)
			(xy 223.203308 -106.749267) (xy 223.20377 -106.77652) (xy 223.203323 -106.803891) (xy 223.195502 -106.858071)
			(xy 223.180009 -106.910575) (xy 223.157162 -106.960321) (xy 223.127433 -107.006287) (xy 223.10979 -107.027218)
			(xy 223.109536 -107.027472) (xy 223.103947 -107.034557) (xy 223.097704 -107.051475) (xy 223.097344 -107.060492)
			(xy 223.097344 -107.127548) (xy 223.097716 -107.136564) (xy 223.103952 -107.153481) (xy 223.109536 -107.160568)
			(xy 223.10979 -107.160568) (xy 223.10979 -107.160822) (xy 223.127404 -107.181774) (xy 223.15712 -107.227741)
			(xy 223.179961 -107.277484) (xy 223.195458 -107.32998) (xy 223.203293 -107.384152) (xy 223.20377 -107.41152)
			(xy 223.203364 -107.438775) (xy 223.195603 -107.49273) (xy 223.192225 -107.50423) (xy 226.110038 -107.50423)
			(xy 226.110447 -107.477914) (xy 226.117692 -107.425782) (xy 226.132022 -107.375138) (xy 226.153165 -107.326939)
			(xy 226.180722 -107.282097) (xy 226.214171 -107.24146) (xy 226.233228 -107.223306) (xy 226.240618 -107.215775)
			(xy 226.249152 -107.196502) (xy 226.249738 -107.185968) (xy 226.249738 -107.111292) (xy 226.249215 -107.100742)
			(xy 226.240674 -107.081447) (xy 226.233228 -107.073954) (xy 226.214162 -107.055808) (xy 226.180705 -107.015177)
			(xy 226.153147 -106.970335) (xy 226.13201 -106.922132) (xy 226.117695 -106.871483) (xy 226.110474 -106.819347)
			(xy 226.110038 -106.79303) (xy 226.110524 -106.765779) (xy 226.11828 -106.711831) (xy 226.133635 -106.659536)
			(xy 226.156277 -106.609959) (xy 226.185743 -106.564109) (xy 226.221434 -106.522918) (xy 226.262625 -106.487227)
			(xy 226.308475 -106.457761) (xy 226.358052 -106.435119) (xy 226.410347 -106.419764) (xy 226.464295 -106.412008)
			(xy 226.518797 -106.412008) (xy 226.572745 -106.419764) (xy 226.62504 -106.435119) (xy 226.655327 -106.448951)
			(xy 226.90936 -106.448951) (xy 226.90936 -106.394449) (xy 226.917116 -106.3405) (xy 226.932471 -106.288205)
			(xy 226.955111 -106.238627) (xy 226.984577 -106.192776) (xy 227.020267 -106.151584) (xy 227.061456 -106.115891)
			(xy 227.107306 -106.086423) (xy 227.156883 -106.063779) (xy 227.209177 -106.048421) (xy 227.263125 -106.040661)
			(xy 227.290376 -106.040174) (xy 227.317747 -106.040636) (xy 227.371927 -106.048452) (xy 227.42443 -106.063941)
			(xy 227.474177 -106.086784) (xy 227.520143 -106.116511) (xy 227.541074 -106.134154) (xy 227.541328 -106.134408)
			(xy 227.54843 -106.139971) (xy 227.565335 -106.146232) (xy 227.574348 -106.1466) (xy 227.641404 -106.1466)
			(xy 227.650421 -106.146245) (xy 227.667338 -106.139996) (xy 227.674424 -106.134408) (xy 227.674424 -106.134154)
			(xy 227.674678 -106.134154) (xy 227.695614 -106.11652) (xy 227.741585 -106.086806) (xy 227.791332 -106.063968)
			(xy 227.843832 -106.048476) (xy 227.898007 -106.040648) (xy 227.925376 -106.040174) (xy 227.952629 -106.040672)
			(xy 228.00658 -106.048425) (xy 228.058878 -106.063779) (xy 228.108459 -106.086419) (xy 228.154313 -106.115885)
			(xy 228.195506 -106.151577) (xy 228.213644 -106.172508) (xy 228.769418 -106.172508) (xy 228.769884 -106.145138)
			(xy 228.777701 -106.090958) (xy 228.79319 -106.038455) (xy 228.816032 -105.988708) (xy 228.845757 -105.942742)
			(xy 228.863398 -105.92181) (xy 228.863652 -105.921556) (xy 228.869227 -105.914462) (xy 228.87548 -105.897551)
			(xy 228.875844 -105.888536) (xy 228.875844 -105.82148) (xy 228.875508 -105.812461) (xy 228.869247 -105.795543)
			(xy 228.863652 -105.78846) (xy 228.863398 -105.78846) (xy 228.863398 -105.788206) (xy 228.845766 -105.767266)
			(xy 228.816043 -105.721299) (xy 228.793199 -105.671554) (xy 228.777704 -105.619053) (xy 228.769875 -105.564876)
			(xy 228.769874 -105.510136) (xy 228.777701 -105.455959) (xy 228.793195 -105.403458) (xy 228.816038 -105.353712)
			(xy 228.845759 -105.307743) (xy 228.863398 -105.28681) (xy 228.863652 -105.286556) (xy 228.869227 -105.279462)
			(xy 228.87548 -105.262551) (xy 228.875844 -105.253536) (xy 228.875844 -105.18648) (xy 228.875508 -105.177461)
			(xy 228.869247 -105.160543) (xy 228.863652 -105.15346) (xy 228.863398 -105.15346) (xy 228.863398 -105.153206)
			(xy 228.845748 -105.132283) (xy 228.816038 -105.086307) (xy 228.793204 -105.036558) (xy 228.777716 -104.984055)
			(xy 228.76989 -104.929878) (xy 228.769418 -104.902508) (xy 228.769904 -104.875257) (xy 228.77766 -104.821309)
			(xy 228.793015 -104.769014) (xy 228.815657 -104.719437) (xy 228.845123 -104.673587) (xy 228.880814 -104.632396)
			(xy 228.922005 -104.596705) (xy 228.967855 -104.567239) (xy 229.017432 -104.544597) (xy 229.069727 -104.529242)
			(xy 229.123675 -104.521486) (xy 229.178177 -104.521486) (xy 229.232125 -104.529242) (xy 229.28442 -104.544597)
			(xy 229.333997 -104.567239) (xy 229.379847 -104.596705) (xy 229.421038 -104.632396) (xy 229.456729 -104.673587)
			(xy 229.486195 -104.719437) (xy 229.508837 -104.769014) (xy 229.524192 -104.821309) (xy 229.531948 -104.875257)
			(xy 229.532434 -104.902508) (xy 229.531989 -104.929879) (xy 229.524168 -104.98406) (xy 229.508675 -105.036564)
			(xy 229.485829 -105.08631) (xy 229.456098 -105.132276) (xy 229.438454 -105.153206) (xy 229.4382 -105.15346)
			(xy 229.432624 -105.160554) (xy 229.426371 -105.177465) (xy 229.426008 -105.18648) (xy 229.426008 -105.253536)
			(xy 229.426346 -105.262555) (xy 229.432607 -105.279472) (xy 229.4382 -105.286556) (xy 229.438454 -105.286556)
			(xy 229.438454 -105.28681) (xy 229.456103 -105.307736) (xy 229.485829 -105.353704) (xy 229.508675 -105.403452)
			(xy 229.524172 -105.455955) (xy 229.532 -105.510135) (xy 229.531999 -105.564877) (xy 229.524169 -105.619057)
			(xy 229.508671 -105.67156) (xy 229.485823 -105.721306) (xy 229.456096 -105.767274) (xy 229.438454 -105.788206)
			(xy 229.4382 -105.78846) (xy 229.432624 -105.795554) (xy 229.426371 -105.812465) (xy 229.426008 -105.82148)
			(xy 229.426008 -105.888536) (xy 229.426346 -105.897555) (xy 229.432607 -105.914472) (xy 229.4382 -105.921556)
			(xy 229.438454 -105.921556) (xy 229.438454 -105.92181) (xy 229.456104 -105.942733) (xy 229.485816 -105.988708)
			(xy 229.50865 -106.038457) (xy 229.524139 -106.09096) (xy 229.531963 -106.145138) (xy 229.532434 -106.172508)
			(xy 231.8258 -106.172508) (xy 231.826271 -106.145138) (xy 231.834087 -106.090959) (xy 231.849575 -106.038456)
			(xy 231.872416 -105.988709) (xy 231.902139 -105.942742) (xy 231.91978 -105.92181) (xy 231.920034 -105.921556)
			(xy 231.925607 -105.91446) (xy 231.931861 -105.89755) (xy 231.932226 -105.888536) (xy 231.932226 -105.82148)
			(xy 231.931873 -105.812463) (xy 231.925622 -105.795546) (xy 231.920034 -105.78846) (xy 231.91978 -105.78846)
			(xy 231.91978 -105.788206) (xy 231.902149 -105.767266) (xy 231.872428 -105.721298) (xy 231.849585 -105.671553)
			(xy 231.83409 -105.619052) (xy 231.826261 -105.564876) (xy 231.826261 -105.510136) (xy 231.834087 -105.455959)
			(xy 231.84958 -105.403458) (xy 231.872422 -105.353712) (xy 231.902142 -105.307744) (xy 231.91978 -105.28681)
			(xy 231.920034 -105.286556) (xy 231.925607 -105.27946) (xy 231.931861 -105.26255) (xy 231.932226 -105.253536)
			(xy 231.932226 -105.18648) (xy 231.931873 -105.177463) (xy 231.925622 -105.160546) (xy 231.920034 -105.15346)
			(xy 231.91978 -105.15346) (xy 231.91978 -105.153206) (xy 231.902127 -105.132285) (xy 231.872418 -105.086309)
			(xy 231.849585 -105.036559) (xy 231.834097 -104.984055) (xy 231.826272 -104.929878) (xy 231.8258 -104.902508)
			(xy 231.826286 -104.875257) (xy 231.834042 -104.821309) (xy 231.849397 -104.769014) (xy 231.872039 -104.719437)
			(xy 231.901505 -104.673587) (xy 231.937196 -104.632396) (xy 231.978387 -104.596705) (xy 232.024237 -104.567239)
			(xy 232.073814 -104.544597) (xy 232.126109 -104.529242) (xy 232.180057 -104.521486) (xy 232.234559 -104.521486)
			(xy 232.288507 -104.529242) (xy 232.340802 -104.544597) (xy 232.356907 -104.551952) (xy 266.291007 -104.551952)
			(xy 266.291007 -104.494648) (xy 266.299162 -104.437928) (xy 266.315307 -104.382946) (xy 266.339112 -104.330821)
			(xy 266.370094 -104.282614) (xy 266.407621 -104.239308) (xy 266.450929 -104.201783) (xy 266.499136 -104.170804)
			(xy 266.551262 -104.147001) (xy 266.606245 -104.130858) (xy 266.662966 -104.122706) (xy 266.691618 -104.12222)
			(xy 266.718998 -104.122706) (xy 266.773246 -104.130175) (xy 266.825972 -104.144956) (xy 266.876197 -104.166776)
			(xy 266.922985 -104.195228) (xy 266.965466 -104.229782) (xy 267.002848 -104.269796) (xy 267.019024 -104.291892)
			(xy 267.024581 -104.299158) (xy 267.039694 -104.309439) (xy 267.048488 -104.311958) (xy 267.07846 -104.319324)
			(xy 267.087413 -104.321052) (xy 267.105499 -104.31885) (xy 267.113766 -104.315006) (xy 267.138373 -104.302632)
			(xy 267.189897 -104.283158) (xy 267.243384 -104.270006) (xy 267.298062 -104.263363) (xy 267.325602 -104.262936)
			(xy 267.353142 -104.263381) (xy 267.407822 -104.270012) (xy 267.461311 -104.283154) (xy 267.512838 -104.302617)
			(xy 267.537438 -104.315006) (xy 267.54569 -104.318903) (xy 267.563793 -104.321105) (xy 267.572744 -104.319324)
			(xy 267.602716 -104.311958) (xy 267.611498 -104.309416) (xy 267.626599 -104.299133) (xy 267.63218 -104.291892)
			(xy 267.648294 -104.269746) (xy 267.685676 -104.229716) (xy 267.728162 -104.195151) (xy 267.77496 -104.166696)
			(xy 267.825198 -104.144879) (xy 267.877939 -104.130109) (xy 267.932201 -104.122661) (xy 267.959586 -104.12222)
			(xy 267.988236 -104.122734) (xy 268.044952 -104.130886) (xy 268.099931 -104.147028) (xy 268.152052 -104.17083)
			(xy 268.200256 -104.201807) (xy 268.243561 -104.239329) (xy 268.281085 -104.282632) (xy 268.312064 -104.330835)
			(xy 268.335867 -104.382956) (xy 268.352011 -104.437934) (xy 268.360165 -104.49465) (xy 268.360165 -104.55195)
			(xy 268.352011 -104.608666) (xy 268.335867 -104.663644) (xy 268.312064 -104.715765) (xy 268.281085 -104.763968)
			(xy 268.243561 -104.807271) (xy 268.200256 -104.844793) (xy 268.152052 -104.87577) (xy 268.099931 -104.899572)
			(xy 268.044952 -104.915714) (xy 267.988236 -104.923866) (xy 267.959586 -104.924352) (xy 267.944668 -104.924179)
			(xy 267.914919 -104.921893) (xy 267.90015 -104.91978) (xy 267.888974 -104.918002) (xy 267.867892 -104.924098)
			(xy 267.80109 -104.981756) (xy 267.793142 -104.989365) (xy 267.784047 -105.009373) (xy 267.783564 -105.020364)
			(xy 267.783564 -105.285032) (xy 267.784063 -105.296021) (xy 267.793144 -105.316033) (xy 267.80109 -105.32364)
			(xy 267.867892 -105.381298) (xy 267.888974 -105.387394) (xy 267.90015 -105.385616) (xy 267.91492 -105.383511)
			(xy 267.944668 -105.381221) (xy 267.959586 -105.381044) (xy 267.988237 -105.38151) (xy 268.044957 -105.389663)
			(xy 268.099939 -105.405805) (xy 268.152064 -105.429609) (xy 268.200271 -105.460588) (xy 268.243578 -105.498112)
			(xy 268.281104 -105.541418) (xy 268.312085 -105.589624) (xy 268.33589 -105.641748) (xy 268.352034 -105.696729)
			(xy 268.360189 -105.753449) (xy 268.360189 -105.810751) (xy 268.352034 -105.867471) (xy 268.33589 -105.922452)
			(xy 268.312085 -105.974576) (xy 268.281104 -106.022782) (xy 268.243578 -106.066088) (xy 268.200271 -106.103612)
			(xy 268.152064 -106.134591) (xy 268.099939 -106.158395) (xy 268.044957 -106.174537) (xy 267.988237 -106.18269)
			(xy 267.959586 -106.183176) (xy 267.932206 -106.182688) (xy 267.877958 -106.175221) (xy 267.825232 -106.160439)
			(xy 267.775007 -106.13862) (xy 267.728219 -106.110168) (xy 267.685738 -106.075614) (xy 267.648356 -106.0356)
			(xy 267.63218 -106.013504) (xy 267.626623 -106.006239) (xy 267.61151 -105.995957) (xy 267.602716 -105.993438)
			(xy 267.572744 -105.986072) (xy 267.563791 -105.984346) (xy 267.545705 -105.986547) (xy 267.537438 -105.99039)
			(xy 267.51283 -106.002763) (xy 267.461307 -106.022236) (xy 267.40782 -106.03539) (xy 267.353142 -106.042032)
			(xy 267.325602 -106.04246) (xy 267.298062 -106.042014) (xy 267.243382 -106.035383) (xy 267.189893 -106.022242)
			(xy 267.138366 -106.002779) (xy 267.113766 -105.99039) (xy 267.105514 -105.986495) (xy 267.087411 -105.984292)
			(xy 267.07846 -105.986072) (xy 267.048488 -105.993438) (xy 267.039707 -105.995982) (xy 267.024606 -106.006264)
			(xy 267.019024 -106.013504) (xy 267.002907 -106.035648) (xy 266.965525 -106.075677) (xy 266.92304 -106.110243)
			(xy 266.876242 -106.138699) (xy 266.826005 -106.160515) (xy 266.773264 -106.175286) (xy 266.719003 -106.182735)
			(xy 266.691618 -106.183176) (xy 266.662968 -106.182671) (xy 266.606251 -106.174518) (xy 266.551271 -106.158377)
			(xy 266.499148 -106.134575) (xy 266.450943 -106.103598) (xy 266.407638 -106.066075) (xy 266.370113 -106.022771)
			(xy 266.339133 -105.974568) (xy 266.315329 -105.922446) (xy 266.299186 -105.867467) (xy 266.291031 -105.81075)
			(xy 266.291031 -105.75345) (xy 266.299186 -105.696733) (xy 266.315329 -105.641754) (xy 266.339133 -105.589632)
			(xy 266.370113 -105.541429) (xy 266.407638 -105.498125) (xy 266.450943 -105.460602) (xy 266.499148 -105.429625)
			(xy 266.551271 -105.405823) (xy 266.606251 -105.389682) (xy 266.662968 -105.381529) (xy 266.691618 -105.381044)
			(xy 266.706536 -105.381217) (xy 266.736285 -105.383503) (xy 266.751054 -105.385616) (xy 266.76223 -105.387394)
			(xy 266.783312 -105.381298) (xy 266.850114 -105.32364) (xy 266.858065 -105.316033) (xy 266.867158 -105.296024)
			(xy 266.86764 -105.285032) (xy 266.86764 -105.020364) (xy 266.867142 -105.009374) (xy 266.85806 -104.989363)
			(xy 266.850114 -104.981756) (xy 266.783312 -104.924098) (xy 266.76223 -104.918002) (xy 266.751054 -104.91978)
			(xy 266.736284 -104.921885) (xy 266.706536 -104.924175) (xy 266.691618 -104.924352) (xy 266.662966 -104.923894)
			(xy 266.606245 -104.915742) (xy 266.551262 -104.899599) (xy 266.499136 -104.875796) (xy 266.450929 -104.844817)
			(xy 266.407621 -104.807292) (xy 266.370094 -104.763986) (xy 266.339112 -104.715779) (xy 266.315307 -104.663654)
			(xy 266.299162 -104.608672) (xy 266.291007 -104.551952) (xy 232.356907 -104.551952) (xy 232.390379 -104.567239)
			(xy 232.436229 -104.596705) (xy 232.47742 -104.632396) (xy 232.513111 -104.673587) (xy 232.542577 -104.719437)
			(xy 232.565219 -104.769014) (xy 232.580574 -104.821309) (xy 232.58833 -104.875257) (xy 232.588816 -104.902508)
			(xy 232.588375 -104.929879) (xy 232.580554 -104.98406) (xy 232.565061 -105.036565) (xy 232.542213 -105.086311)
			(xy 232.512481 -105.132276) (xy 232.494836 -105.153206) (xy 232.494582 -105.15346) (xy 232.489004 -105.160552)
			(xy 232.482753 -105.177465) (xy 232.48239 -105.18648) (xy 232.48239 -105.253536) (xy 232.482732 -105.262554)
			(xy 232.48899 -105.279471) (xy 232.494582 -105.286556) (xy 232.494836 -105.286556) (xy 232.494836 -105.28681)
			(xy 232.512486 -105.307736) (xy 232.542213 -105.353704) (xy 232.565061 -105.403451) (xy 232.580558 -105.455954)
			(xy 232.588386 -105.510135) (xy 232.588386 -105.564877) (xy 232.580555 -105.619057) (xy 232.565056 -105.67156)
			(xy 232.542208 -105.721307) (xy 232.512479 -105.767274) (xy 232.494836 -105.788206) (xy 232.494582 -105.78846)
			(xy 232.489004 -105.795552) (xy 232.482753 -105.812465) (xy 232.48239 -105.82148) (xy 232.48239 -105.888536)
			(xy 232.482732 -105.897554) (xy 232.48899 -105.914471) (xy 232.494582 -105.921556) (xy 232.494836 -105.921556)
			(xy 232.494836 -105.92181) (xy 232.512499 -105.942723) (xy 232.542206 -105.988702) (xy 232.565037 -106.038454)
			(xy 232.580522 -106.090959) (xy 232.588345 -106.145138) (xy 232.588816 -106.172508) (xy 232.58833 -106.199759)
			(xy 232.580574 -106.253707) (xy 232.565219 -106.306002) (xy 232.54734 -106.345149) (xy 268.933147 -106.345149)
			(xy 268.933147 -106.287851) (xy 268.941302 -106.231135) (xy 268.957445 -106.176158) (xy 268.981249 -106.124038)
			(xy 269.012228 -106.075836) (xy 269.049752 -106.032533) (xy 269.093056 -105.995012) (xy 269.14126 -105.964036)
			(xy 269.193382 -105.940236) (xy 269.248361 -105.924096) (xy 269.305077 -105.915945) (xy 269.333726 -105.91546)
			(xy 269.361107 -105.915924) (xy 269.415356 -105.923394) (xy 269.468084 -105.938178) (xy 269.51831 -105.960001)
			(xy 269.565097 -105.988457) (xy 269.607577 -106.023015) (xy 269.644958 -106.063034) (xy 269.661132 -106.085132)
			(xy 269.666698 -106.09239) (xy 269.681804 -106.102677) (xy 269.690596 -106.105198) (xy 269.720568 -106.112564)
			(xy 269.72952 -106.114293) (xy 269.747606 -106.112089) (xy 269.755874 -106.108246) (xy 269.780478 -106.095864)
			(xy 269.832003 -106.076394) (xy 269.885491 -106.063243) (xy 269.94017 -106.056603) (xy 269.96771 -106.056176)
			(xy 269.99525 -106.056613) (xy 270.04993 -106.063246) (xy 270.10342 -106.07639) (xy 270.154947 -106.095856)
			(xy 270.179546 -106.108246) (xy 270.187797 -106.112146) (xy 270.205901 -106.114348) (xy 270.214852 -106.112564)
			(xy 270.244824 -106.105198) (xy 270.253603 -106.102647) (xy 270.268704 -106.09237) (xy 270.274288 -106.085132)
			(xy 270.29047 -106.063038) (xy 270.327839 -106.023005) (xy 270.370313 -105.988435) (xy 270.417099 -105.959972)
			(xy 270.467327 -105.938147) (xy 270.520058 -105.923367) (xy 270.574312 -105.915907) (xy 270.601694 -105.91546)
			(xy 270.630346 -105.915894) (xy 270.687067 -105.924049) (xy 270.74205 -105.940193) (xy 270.794176 -105.963997)
			(xy 270.842384 -105.994978) (xy 270.885692 -106.032504) (xy 270.923219 -106.075811) (xy 270.9542 -106.124018)
			(xy 270.978005 -106.176144) (xy 270.99415 -106.231127) (xy 271.002305 -106.287848) (xy 271.002305 -106.345152)
			(xy 270.99415 -106.401873) (xy 270.978005 -106.456856) (xy 270.9542 -106.508982) (xy 270.923219 -106.557189)
			(xy 270.885692 -106.600496) (xy 270.842384 -106.638022) (xy 270.794176 -106.669003) (xy 270.74205 -106.692807)
			(xy 270.687067 -106.708951) (xy 270.630346 -106.717106) (xy 270.601694 -106.717592) (xy 270.586776 -106.717418)
			(xy 270.557027 -106.715132) (xy 270.542258 -106.71302) (xy 270.531082 -106.711242) (xy 270.51 -106.717338)
			(xy 270.443198 -106.774996) (xy 270.435233 -106.78259) (xy 270.426147 -106.802609) (xy 270.425672 -106.813604)
			(xy 270.425672 -107.078272) (xy 270.426147 -107.089264) (xy 270.435244 -107.109276) (xy 270.443198 -107.11688)
			(xy 270.51 -107.174538) (xy 270.531082 -107.180634) (xy 270.542258 -107.178856) (xy 270.557027 -107.17675)
			(xy 270.586776 -107.17446) (xy 270.601694 -107.174284) (xy 270.630348 -107.17467) (xy 270.687072 -107.182825)
			(xy 270.742059 -107.19897) (xy 270.794188 -107.222776) (xy 270.842399 -107.253758) (xy 270.885709 -107.291287)
			(xy 270.923238 -107.334597) (xy 270.954221 -107.382807) (xy 270.978028 -107.434936) (xy 270.994173 -107.489922)
			(xy 271.002329 -107.546646) (xy 271.002329 -107.603954) (xy 270.994173 -107.660678) (xy 270.978028 -107.715664)
			(xy 270.954221 -107.767793) (xy 270.923238 -107.816003) (xy 270.885709 -107.859313) (xy 270.842399 -107.896842)
			(xy 270.794188 -107.927824) (xy 270.742059 -107.95163) (xy 270.687072 -107.967775) (xy 270.630348 -107.97593)
			(xy 270.601694 -107.976416) (xy 270.574313 -107.975948) (xy 270.520064 -107.96848) (xy 270.467335 -107.953697)
			(xy 270.41711 -107.931875) (xy 270.370322 -107.90342) (xy 270.327842 -107.868861) (xy 270.290462 -107.828842)
			(xy 270.274288 -107.806744) (xy 270.26872 -107.799488) (xy 270.253615 -107.789201) (xy 270.244824 -107.786678)
			(xy 270.214852 -107.779312) (xy 270.205898 -107.777596) (xy 270.187814 -107.779792) (xy 270.179546 -107.78363)
			(xy 270.154938 -107.796003) (xy 270.103415 -107.815476) (xy 270.049928 -107.828629) (xy 269.99525 -107.835272)
			(xy 269.96771 -107.8357) (xy 269.940169 -107.835298) (xy 269.885487 -107.828655) (xy 269.831998 -107.815501)
			(xy 269.780472 -107.796025) (xy 269.755874 -107.78363) (xy 269.74762 -107.77974) (xy 269.729518 -107.777532)
			(xy 269.720568 -107.779312) (xy 269.690596 -107.786678) (xy 269.681811 -107.789213) (xy 269.666712 -107.7995)
			(xy 269.661132 -107.806744) (xy 269.644992 -107.828871) (xy 269.607617 -107.868904) (xy 269.565136 -107.903472)
			(xy 269.518342 -107.931931) (xy 269.468108 -107.953751) (xy 269.415369 -107.968523) (xy 269.36111 -107.975974)
			(xy 269.333726 -107.976416) (xy 269.305078 -107.975831) (xy 269.248366 -107.967681) (xy 269.193391 -107.951542)
			(xy 269.141272 -107.927743) (xy 269.093071 -107.896769) (xy 269.049769 -107.85925) (xy 269.012247 -107.81595)
			(xy 268.98127 -107.767751) (xy 268.957468 -107.715634) (xy 268.941325 -107.66066) (xy 268.933171 -107.603948)
			(xy 268.933171 -107.546652) (xy 268.941325 -107.48994) (xy 268.957468 -107.434966) (xy 268.98127 -107.382849)
			(xy 269.012247 -107.33465) (xy 269.049769 -107.29135) (xy 269.093071 -107.253831) (xy 269.141272 -107.222857)
			(xy 269.193391 -107.199058) (xy 269.248366 -107.182919) (xy 269.305078 -107.174769) (xy 269.333726 -107.174284)
			(xy 269.348644 -107.174455) (xy 269.378393 -107.176743) (xy 269.393162 -107.178856) (xy 269.404338 -107.180634)
			(xy 269.42542 -107.174538) (xy 269.492222 -107.11688) (xy 269.500202 -107.109299) (xy 269.509279 -107.08927)
			(xy 269.509748 -107.078272) (xy 269.509748 -106.813604) (xy 269.509225 -106.802617) (xy 269.500161 -106.782606)
			(xy 269.492222 -106.774996) (xy 269.42542 -106.717338) (xy 269.404338 -106.711242) (xy 269.393162 -106.71302)
			(xy 269.378392 -106.715124) (xy 269.348644 -106.717415) (xy 269.333726 -106.717592) (xy 269.305077 -106.717055)
			(xy 269.248361 -106.708904) (xy 269.193382 -106.692764) (xy 269.14126 -106.668964) (xy 269.093056 -106.637988)
			(xy 269.049752 -106.600467) (xy 269.012228 -106.557164) (xy 268.981249 -106.508962) (xy 268.957445 -106.456842)
			(xy 268.941302 -106.401865) (xy 268.933147 -106.345149) (xy 232.54734 -106.345149) (xy 232.542577 -106.355579)
			(xy 232.513111 -106.401429) (xy 232.47742 -106.44262) (xy 232.436229 -106.478311) (xy 232.390379 -106.507777)
			(xy 232.340802 -106.530419) (xy 232.288507 -106.545774) (xy 232.234559 -106.55353) (xy 232.180057 -106.55353)
			(xy 232.126109 -106.545774) (xy 232.073814 -106.530419) (xy 232.024237 -106.507777) (xy 231.978387 -106.478311)
			(xy 231.937196 -106.44262) (xy 231.901505 -106.401429) (xy 231.872039 -106.355579) (xy 231.849397 -106.306002)
			(xy 231.834042 -106.253707) (xy 231.826286 -106.199759) (xy 231.8258 -106.172508) (xy 229.532434 -106.172508)
			(xy 229.531948 -106.199759) (xy 229.524192 -106.253707) (xy 229.508837 -106.306002) (xy 229.486195 -106.355579)
			(xy 229.456729 -106.401429) (xy 229.421038 -106.44262) (xy 229.379847 -106.478311) (xy 229.333997 -106.507777)
			(xy 229.28442 -106.530419) (xy 229.232125 -106.545774) (xy 229.178177 -106.55353) (xy 229.123675 -106.55353)
			(xy 229.069727 -106.545774) (xy 229.017432 -106.530419) (xy 228.967855 -106.507777) (xy 228.922005 -106.478311)
			(xy 228.880814 -106.44262) (xy 228.845123 -106.401429) (xy 228.815657 -106.355579) (xy 228.793015 -106.306002)
			(xy 228.77766 -106.253707) (xy 228.769904 -106.199759) (xy 228.769418 -106.172508) (xy 228.213644 -106.172508)
			(xy 228.231201 -106.192768) (xy 228.26067 -106.23862) (xy 228.283313 -106.2882) (xy 228.298669 -106.340497)
			(xy 228.306427 -106.394447) (xy 228.306427 -106.448953) (xy 228.298669 -106.502903) (xy 228.283313 -106.5552)
			(xy 228.26067 -106.60478) (xy 228.231201 -106.650632) (xy 228.195506 -106.691823) (xy 228.154313 -106.727515)
			(xy 228.108459 -106.756981) (xy 228.058878 -106.779621) (xy 228.00658 -106.794975) (xy 227.952629 -106.802728)
			(xy 227.925376 -106.80319) (xy 227.898005 -106.80274) (xy 227.843825 -106.794919) (xy 227.791322 -106.779426)
			(xy 227.741575 -106.756581) (xy 227.695609 -106.726853) (xy 227.674678 -106.70921) (xy 227.674424 -106.708956)
			(xy 227.667339 -106.703368) (xy 227.650421 -106.697123) (xy 227.641404 -106.696764) (xy 227.574348 -106.696764)
			(xy 227.565334 -106.697152) (xy 227.548418 -106.703379) (xy 227.541328 -106.708956) (xy 227.541328 -106.70921)
			(xy 227.541074 -106.70921) (xy 227.520126 -106.726829) (xy 227.474158 -106.756544) (xy 227.424414 -106.779383)
			(xy 227.371917 -106.794879) (xy 227.317744 -106.802713) (xy 227.290376 -106.80319) (xy 227.263125 -106.802739)
			(xy 227.209177 -106.794979) (xy 227.156883 -106.779621) (xy 227.107306 -106.756977) (xy 227.061456 -106.727509)
			(xy 227.020267 -106.691816) (xy 226.984577 -106.650624) (xy 226.955111 -106.604773) (xy 226.932471 -106.555195)
			(xy 226.917116 -106.5029) (xy 226.90936 -106.448951) (xy 226.655327 -106.448951) (xy 226.674617 -106.457761)
			(xy 226.720467 -106.487227) (xy 226.761658 -106.522918) (xy 226.797349 -106.564109) (xy 226.826815 -106.609959)
			(xy 226.849457 -106.659536) (xy 226.864812 -106.711831) (xy 226.872568 -106.765779) (xy 226.873054 -106.79303)
			(xy 226.872621 -106.819345) (xy 226.865381 -106.871476) (xy 226.851057 -106.92212) (xy 226.829918 -106.970319)
			(xy 226.802365 -107.015162) (xy 226.768919 -107.055799) (xy 226.749864 -107.073954) (xy 226.742446 -107.081462)
			(xy 226.733929 -107.100752) (xy 226.733354 -107.111292) (xy 226.733354 -107.185968) (xy 226.7339 -107.196515)
			(xy 226.742425 -107.21581) (xy 226.749864 -107.223306) (xy 226.768928 -107.241453) (xy 226.802382 -107.282086)
			(xy 226.829938 -107.326929) (xy 226.851075 -107.375131) (xy 226.865391 -107.425779) (xy 226.872615 -107.477914)
			(xy 226.873054 -107.50423) (xy 226.872568 -107.531481) (xy 226.864812 -107.585429) (xy 226.849457 -107.637724)
			(xy 226.826815 -107.687301) (xy 226.797349 -107.733151) (xy 226.761658 -107.774342) (xy 226.720467 -107.810033)
			(xy 226.674617 -107.839499) (xy 226.62504 -107.862141) (xy 226.595373 -107.870852) (xy 228.877852 -107.870852)
			(xy 228.877852 -107.816348) (xy 228.885608 -107.762399) (xy 228.900963 -107.710102) (xy 228.923604 -107.660523)
			(xy 228.95307 -107.614671) (xy 228.988762 -107.573479) (xy 229.029952 -107.537785) (xy 229.075802 -107.508316)
			(xy 229.12538 -107.485672) (xy 229.177675 -107.470313) (xy 229.231624 -107.462553) (xy 229.258876 -107.462066)
			(xy 229.286246 -107.46253) (xy 229.340426 -107.470346) (xy 229.39293 -107.485835) (xy 229.442677 -107.508677)
			(xy 229.488643 -107.538404) (xy 229.509574 -107.556046) (xy 229.509828 -107.5563) (xy 229.516931 -107.561863)
			(xy 229.533835 -107.568124) (xy 229.542848 -107.568492) (xy 229.609904 -107.568492) (xy 229.618921 -107.568139)
			(xy 229.635838 -107.561889) (xy 229.642924 -107.5563) (xy 229.642924 -107.556046) (xy 229.643178 -107.556046)
			(xy 229.664111 -107.538405) (xy 229.710079 -107.508681) (xy 229.759825 -107.485835) (xy 229.812327 -107.470339)
			(xy 229.866505 -107.46251) (xy 229.921247 -107.46251) (xy 229.975425 -107.470339) (xy 230.027927 -107.485835)
			(xy 230.077673 -107.508681) (xy 230.123641 -107.538405) (xy 230.144574 -107.556046) (xy 230.144828 -107.5563)
			(xy 230.151931 -107.561863) (xy 230.168835 -107.568124) (xy 230.177848 -107.568492) (xy 230.244904 -107.568492)
			(xy 230.253921 -107.568139) (xy 230.270838 -107.561889) (xy 230.277924 -107.5563) (xy 230.277924 -107.556046)
			(xy 230.278178 -107.556046) (xy 230.299113 -107.538411) (xy 230.345085 -107.508697) (xy 230.394831 -107.485859)
			(xy 230.447331 -107.470368) (xy 230.501507 -107.46254) (xy 230.528876 -107.462066) (xy 230.556128 -107.46258)
			(xy 230.610078 -107.470333) (xy 230.662375 -107.485686) (xy 230.711955 -107.508326) (xy 230.757808 -107.537791)
			(xy 230.799001 -107.573482) (xy 230.834694 -107.614673) (xy 230.864163 -107.660524) (xy 230.886805 -107.710102)
			(xy 230.902162 -107.762399) (xy 230.909919 -107.816348) (xy 230.909919 -107.836251) (xy 233.797585 -107.836251)
			(xy 233.797585 -107.781749) (xy 233.805342 -107.727802) (xy 233.820697 -107.675508) (xy 233.843337 -107.625932)
			(xy 233.872803 -107.580082) (xy 233.908494 -107.538893) (xy 233.949684 -107.503202) (xy 233.995534 -107.473737)
			(xy 234.04511 -107.451096) (xy 234.097404 -107.435741) (xy 234.151351 -107.427985) (xy 234.178602 -107.427522)
			(xy 234.204916 -107.427981) (xy 234.257045 -107.435217) (xy 234.307689 -107.449537) (xy 234.355888 -107.470671)
			(xy 234.400731 -107.498219) (xy 234.44137 -107.531659) (xy 234.459526 -107.550712) (xy 234.467034 -107.558129)
			(xy 234.486325 -107.566644) (xy 234.496864 -107.567222) (xy 234.57154 -107.567222) (xy 234.582087 -107.566667)
			(xy 234.601382 -107.558149) (xy 234.608878 -107.550712) (xy 234.628698 -107.529924) (xy 234.67347 -107.493949)
			(xy 234.723128 -107.465089) (xy 234.77655 -107.443996) (xy 234.832529 -107.431147) (xy 234.889802 -107.426832)
			(xy 234.947075 -107.431147) (xy 235.003054 -107.443996) (xy 235.056476 -107.465089) (xy 235.106134 -107.493949)
			(xy 235.150906 -107.529924) (xy 235.170726 -107.550712) (xy 235.178234 -107.558129) (xy 235.197525 -107.566644)
			(xy 235.208064 -107.567222) (xy 235.28274 -107.567222) (xy 235.293287 -107.566667) (xy 235.312582 -107.558149)
			(xy 235.320078 -107.550712) (xy 235.338254 -107.531676) (xy 235.378879 -107.498217) (xy 235.423715 -107.470655)
			(xy 235.471912 -107.449513) (xy 235.522556 -107.435192) (xy 235.574687 -107.427963) (xy 235.601002 -107.427522)
			(xy 235.628255 -107.427948) (xy 235.682207 -107.435705) (xy 235.734506 -107.451062) (xy 235.784087 -107.473705)
			(xy 235.82994 -107.503174) (xy 235.871134 -107.538868) (xy 235.906828 -107.580061) (xy 235.936296 -107.625915)
			(xy 235.958939 -107.675496) (xy 235.974295 -107.727795) (xy 235.982052 -107.781747) (xy 235.982052 -107.836253)
			(xy 235.974295 -107.890205) (xy 235.958939 -107.942504) (xy 235.936296 -107.992085) (xy 235.906828 -108.037939)
			(xy 235.871134 -108.079132) (xy 235.82994 -108.114826) (xy 235.784087 -108.144295) (xy 235.734506 -108.166938)
			(xy 235.682207 -108.182295) (xy 235.628255 -108.190052) (xy 235.601002 -108.190538) (xy 235.574687 -108.190089)
			(xy 235.522557 -108.182853) (xy 235.471913 -108.168532) (xy 235.423714 -108.147396) (xy 235.378871 -108.119846)
			(xy 235.338233 -108.086402) (xy 235.320078 -108.067348) (xy 235.31256 -108.059942) (xy 235.293278 -108.051419)
			(xy 235.28274 -108.050838) (xy 235.208064 -108.050838) (xy 235.197515 -108.051377) (xy 235.178219 -108.059904)
			(xy 235.170726 -108.067348) (xy 235.150906 -108.088136) (xy 235.106134 -108.124111) (xy 235.056476 -108.152971)
			(xy 235.003054 -108.174064) (xy 234.947075 -108.186913) (xy 234.889802 -108.191228) (xy 234.832529 -108.186913)
			(xy 234.77655 -108.174064) (xy 234.723128 -108.152971) (xy 234.67347 -108.124111) (xy 234.628698 -108.088136)
			(xy 234.608878 -108.067348) (xy 234.60136 -108.059942) (xy 234.582078 -108.051419) (xy 234.57154 -108.050838)
			(xy 234.496864 -108.050838) (xy 234.486315 -108.051377) (xy 234.467019 -108.059904) (xy 234.459526 -108.067348)
			(xy 234.44136 -108.086393) (xy 234.400732 -108.119849) (xy 234.355893 -108.147409) (xy 234.307695 -108.168548)
			(xy 234.257049 -108.182868) (xy 234.204917 -108.190097) (xy 234.178602 -108.190538) (xy 234.151351 -108.190015)
			(xy 234.097404 -108.182259) (xy 234.04511 -108.166904) (xy 233.995534 -108.144263) (xy 233.949684 -108.114798)
			(xy 233.908494 -108.079107) (xy 233.872803 -108.037918) (xy 233.843337 -107.992068) (xy 233.820697 -107.942492)
			(xy 233.805342 -107.890198) (xy 233.797585 -107.836251) (xy 230.909919 -107.836251) (xy 230.909919 -107.870852)
			(xy 230.902162 -107.924801) (xy 230.886805 -107.977098) (xy 230.864163 -108.026676) (xy 230.834694 -108.072527)
			(xy 230.799001 -108.113718) (xy 230.757808 -108.149409) (xy 230.711955 -108.178874) (xy 230.662375 -108.201514)
			(xy 230.610078 -108.216867) (xy 230.556128 -108.22462) (xy 230.528876 -108.225082) (xy 230.501505 -108.224634)
			(xy 230.447325 -108.216813) (xy 230.394822 -108.20132) (xy 230.345075 -108.178474) (xy 230.299109 -108.148745)
			(xy 230.278178 -108.131102) (xy 230.277924 -108.130848) (xy 230.270839 -108.125259) (xy 230.253921 -108.119015)
			(xy 230.244904 -108.118656) (xy 230.177848 -108.118656) (xy 230.168832 -108.119024) (xy 230.151914 -108.125262)
			(xy 230.144828 -108.130848) (xy 230.144574 -108.131102) (xy 230.123641 -108.148743) (xy 230.077673 -108.178467)
			(xy 230.027927 -108.201313) (xy 229.975425 -108.216809) (xy 229.921247 -108.224638) (xy 229.866505 -108.224638)
			(xy 229.812327 -108.216809) (xy 229.759825 -108.201313) (xy 229.710079 -108.178467) (xy 229.664111 -108.148743)
			(xy 229.643178 -108.131102) (xy 229.642924 -108.130848) (xy 229.635839 -108.125259) (xy 229.618921 -108.119015)
			(xy 229.609904 -108.118656) (xy 229.542848 -108.118656) (xy 229.533832 -108.119024) (xy 229.516914 -108.125262)
			(xy 229.509828 -108.130848) (xy 229.509828 -108.131102) (xy 229.509574 -108.131102) (xy 229.488625 -108.14872)
			(xy 229.442657 -108.178435) (xy 229.392914 -108.201275) (xy 229.340417 -108.216771) (xy 229.286244 -108.224605)
			(xy 229.258876 -108.225082) (xy 229.231624 -108.224647) (xy 229.177675 -108.216887) (xy 229.12538 -108.201528)
			(xy 229.075802 -108.178884) (xy 229.029952 -108.149415) (xy 228.988762 -108.113721) (xy 228.95307 -108.072529)
			(xy 228.923604 -108.026677) (xy 228.900963 -107.977098) (xy 228.885608 -107.924801) (xy 228.877852 -107.870852)
			(xy 226.595373 -107.870852) (xy 226.572745 -107.877496) (xy 226.518797 -107.885252) (xy 226.464295 -107.885252)
			(xy 226.410347 -107.877496) (xy 226.358052 -107.862141) (xy 226.308475 -107.839499) (xy 226.262625 -107.810033)
			(xy 226.221434 -107.774342) (xy 226.185743 -107.733151) (xy 226.156277 -107.687301) (xy 226.133635 -107.637724)
			(xy 226.11828 -107.585429) (xy 226.110524 -107.531481) (xy 226.110038 -107.50423) (xy 223.192225 -107.50423)
			(xy 223.180242 -107.545031) (xy 223.157595 -107.594614) (xy 223.128121 -107.640469) (xy 223.092421 -107.681663)
			(xy 223.051223 -107.717356) (xy 223.005363 -107.746823) (xy 222.955777 -107.769463) (xy 222.903473 -107.784815)
			(xy 222.849517 -107.792568) (xy 222.822262 -107.793028) (xy 222.793345 -107.792492) (xy 222.736174 -107.783771)
			(xy 222.680974 -107.766518) (xy 222.629012 -107.74113) (xy 222.581478 -107.708188) (xy 222.539462 -107.668447)
			(xy 222.521272 -107.645962) (xy 222.513674 -107.637146) (xy 222.492766 -107.626969) (xy 222.48114 -107.626404)
			(xy 222.401384 -107.626404) (xy 222.389753 -107.626947) (xy 222.368843 -107.637133) (xy 222.361252 -107.645962)
			(xy 222.343022 -107.668413) (xy 222.301012 -107.708152) (xy 222.253485 -107.741096) (xy 222.201531 -107.76649)
			(xy 222.14634 -107.783753) (xy 222.089176 -107.792489) (xy 222.060262 -107.793028) (xy 222.033011 -107.792558)
			(xy 221.979063 -107.784796) (xy 221.92677 -107.769437) (xy 221.877194 -107.746793) (xy 221.831344 -107.717325)
			(xy 221.790155 -107.681632) (xy 221.754464 -107.640441) (xy 221.724998 -107.594591) (xy 221.702356 -107.545013)
			(xy 221.687 -107.492719) (xy 221.679241 -107.438771) (xy 221.678754 -107.41152) (xy 192.124753 -107.41152)
			(xy 192.107915 -107.454983) (xy 192.069181 -107.532772) (xy 192.023434 -107.606656) (xy 191.971065 -107.676003)
			(xy 191.912521 -107.740223) (xy 191.848301 -107.798767) (xy 191.778954 -107.851136) (xy 191.70507 -107.896883)
			(xy 191.627281 -107.935617) (xy 191.546249 -107.967009) (xy 191.462667 -107.99079) (xy 191.377247 -108.006758)
			(xy 191.290718 -108.014776) (xy 191.203818 -108.014776) (xy 191.117289 -108.006758) (xy 191.031869 -107.99079)
			(xy 190.948287 -107.967009) (xy 190.867255 -107.935617) (xy 190.789466 -107.896883) (xy 190.715582 -107.851136)
			(xy 190.646235 -107.798767) (xy 190.582015 -107.740223) (xy 190.523471 -107.676003) (xy 190.471102 -107.606656)
			(xy 190.425355 -107.532772) (xy 190.386621 -107.454983) (xy 190.355229 -107.373951) (xy 190.331448 -107.290369)
			(xy 190.31548 -107.204949) (xy 190.307462 -107.11842) (xy 188.924122 -107.11842) (xy 188.916114 -107.204887)
			(xy 188.90016 -107.290267) (xy 188.876396 -107.373811) (xy 188.845028 -107.454807) (xy 188.80632 -107.532564)
			(xy 188.760605 -107.606418) (xy 188.708272 -107.67574) (xy 188.649766 -107.739938) (xy 188.585588 -107.798466)
			(xy 188.516284 -107.850823) (xy 188.442445 -107.896564) (xy 188.364702 -107.935297) (xy 188.283717 -107.966694)
			(xy 188.200181 -107.990486) (xy 188.114806 -108.00647) (xy 188.028321 -108.014509) (xy 187.984892 -108.015024)
			(xy 187.0837 -108.015024) (xy 187.05449 -108.044234) (xy 198.958708 -108.044234) (xy 198.959194 -108.016983)
			(xy 198.96695 -107.963035) (xy 198.982305 -107.91074) (xy 199.004947 -107.861163) (xy 199.034413 -107.815313)
			(xy 199.070104 -107.774122) (xy 199.111295 -107.738431) (xy 199.157145 -107.708965) (xy 199.206722 -107.686323)
			(xy 199.259017 -107.670968) (xy 199.312965 -107.663212) (xy 199.367467 -107.663212) (xy 199.421415 -107.670968)
			(xy 199.47371 -107.686323) (xy 199.523287 -107.708965) (xy 199.569137 -107.738431) (xy 199.610328 -107.774122)
			(xy 199.646019 -107.815313) (xy 199.675485 -107.861163) (xy 199.698127 -107.91074) (xy 199.713482 -107.963035)
			(xy 199.721238 -108.016983) (xy 199.721724 -108.044234) (xy 199.721188 -108.071805) (xy 199.713246 -108.126373)
			(xy 199.697531 -108.17923) (xy 199.674372 -108.229273) (xy 199.644251 -108.275463) (xy 199.607794 -108.316835)
			(xy 199.565762 -108.352529) (xy 199.542654 -108.367576) (xy 199.530079 -108.376034) (xy 199.510215 -108.398904)
			(xy 199.497933 -108.426595) (xy 199.494314 -108.45667) (xy 199.49726 -108.473054) (xy 221.556763 -108.473054)
			(xy 221.556763 -108.418546) (xy 221.564521 -108.364593) (xy 221.579879 -108.312294) (xy 221.602523 -108.262713)
			(xy 221.631994 -108.216859) (xy 221.66769 -108.175666) (xy 221.708886 -108.139973) (xy 221.754742 -108.110507)
			(xy 221.804326 -108.087867) (xy 221.856627 -108.072514) (xy 221.91058 -108.064761) (xy 221.937834 -108.0643)
			(xy 221.965205 -108.064746) (xy 222.019385 -108.072569) (xy 222.071888 -108.088063) (xy 222.121635 -108.110909)
			(xy 222.167601 -108.140637) (xy 222.188532 -108.15828) (xy 222.188786 -108.158534) (xy 222.19587 -108.164125)
			(xy 222.212789 -108.170368) (xy 222.221806 -108.170726) (xy 222.288862 -108.170726) (xy 222.297876 -108.170345)
			(xy 222.314793 -108.164114) (xy 222.321882 -108.158534) (xy 222.321882 -108.15828) (xy 222.322136 -108.15828)
			(xy 222.343069 -108.140639) (xy 222.389037 -108.110915) (xy 222.438783 -108.088069) (xy 222.491285 -108.072573)
			(xy 222.545463 -108.064744) (xy 222.600205 -108.064744) (xy 222.654383 -108.072573) (xy 222.706885 -108.088069)
			(xy 222.756631 -108.110915) (xy 222.802599 -108.140639) (xy 222.823532 -108.15828) (xy 222.823786 -108.158534)
			(xy 222.83087 -108.164125) (xy 222.847789 -108.170368) (xy 222.856806 -108.170726) (xy 222.923862 -108.170726)
			(xy 222.932876 -108.170345) (xy 222.949793 -108.164114) (xy 222.956882 -108.158534) (xy 222.956882 -108.15828)
			(xy 222.957136 -108.15828) (xy 222.978069 -108.140639) (xy 223.024037 -108.110915) (xy 223.073783 -108.088069)
			(xy 223.126285 -108.072573) (xy 223.180463 -108.064744) (xy 223.235205 -108.064744) (xy 223.289383 -108.072573)
			(xy 223.341885 -108.088069) (xy 223.391631 -108.110915) (xy 223.437599 -108.140639) (xy 223.458532 -108.15828)
			(xy 223.458786 -108.158534) (xy 223.46587 -108.164125) (xy 223.482789 -108.170368) (xy 223.491806 -108.170726)
			(xy 223.558862 -108.170726) (xy 223.567876 -108.170345) (xy 223.584793 -108.164114) (xy 223.591882 -108.158534)
			(xy 223.591882 -108.15828) (xy 223.592136 -108.15828) (xy 223.613079 -108.140654) (xy 223.659049 -108.110941)
			(xy 223.708794 -108.088103) (xy 223.761292 -108.072609) (xy 223.815466 -108.064776) (xy 223.842834 -108.0643)
			(xy 223.870084 -108.064772) (xy 223.924029 -108.072533) (xy 223.976321 -108.087891) (xy 224.025895 -108.110535)
			(xy 224.071742 -108.140002) (xy 224.112929 -108.175695) (xy 224.148618 -108.216885) (xy 224.178082 -108.262735)
			(xy 224.200721 -108.312311) (xy 224.216075 -108.364604) (xy 224.22383 -108.41855) (xy 224.22383 -108.47305)
			(xy 224.22383 -108.473053) (xy 225.480563 -108.473053) (xy 225.480563 -108.418547) (xy 225.488321 -108.364594)
			(xy 225.503678 -108.312296) (xy 225.526322 -108.262715) (xy 225.555792 -108.216861) (xy 225.591487 -108.175669)
			(xy 225.632682 -108.139976) (xy 225.678538 -108.110509) (xy 225.72812 -108.087869) (xy 225.78042 -108.072515)
			(xy 225.834373 -108.064762) (xy 225.861626 -108.0643) (xy 225.887941 -108.06475) (xy 225.94007 -108.071988)
			(xy 225.990713 -108.086311) (xy 226.038912 -108.107447) (xy 226.083755 -108.134996) (xy 226.124394 -108.168437)
			(xy 226.14255 -108.18749) (xy 226.150052 -108.194914) (xy 226.169347 -108.203426) (xy 226.179888 -108.204)
			(xy 226.254564 -108.204) (xy 226.265113 -108.203465) (xy 226.284408 -108.194934) (xy 226.291902 -108.18749)
			(xy 226.310062 -108.168439) (xy 226.350691 -108.134981) (xy 226.39553 -108.107422) (xy 226.44373 -108.086283)
			(xy 226.494377 -108.071965) (xy 226.54651 -108.064739) (xy 226.572826 -108.0643) (xy 226.600197 -108.064751)
			(xy 226.654377 -108.072572) (xy 226.70688 -108.088065) (xy 226.756626 -108.11091) (xy 226.802593 -108.140637)
			(xy 226.823524 -108.15828) (xy 226.823778 -108.158534) (xy 226.830864 -108.164121) (xy 226.847781 -108.170366)
			(xy 226.856798 -108.170726) (xy 226.923854 -108.170726) (xy 226.932868 -108.170341) (xy 226.949785 -108.164112)
			(xy 226.956874 -108.158534) (xy 226.956874 -108.15828) (xy 226.957128 -108.15828) (xy 226.978061 -108.140639)
			(xy 227.024029 -108.110915) (xy 227.073775 -108.088069) (xy 227.126277 -108.072573) (xy 227.180455 -108.064744)
			(xy 227.235197 -108.064744) (xy 227.289375 -108.072573) (xy 227.341877 -108.088069) (xy 227.391623 -108.110915)
			(xy 227.437591 -108.140639) (xy 227.458524 -108.15828) (xy 227.458778 -108.158534) (xy 227.465864 -108.164121)
			(xy 227.482781 -108.170366) (xy 227.491798 -108.170726) (xy 227.558854 -108.170726) (xy 227.567868 -108.170341)
			(xy 227.584785 -108.164112) (xy 227.591874 -108.158534) (xy 227.591874 -108.15828) (xy 227.592128 -108.15828)
			(xy 227.613074 -108.140658) (xy 227.659043 -108.110944) (xy 227.708787 -108.088105) (xy 227.761285 -108.07261)
			(xy 227.815458 -108.064777) (xy 227.842826 -108.0643) (xy 227.870077 -108.064772) (xy 227.924023 -108.072531)
			(xy 227.976315 -108.087889) (xy 228.02589 -108.110532) (xy 228.071738 -108.14) (xy 228.112926 -108.175692)
			(xy 228.148616 -108.216882) (xy 228.17808 -108.262732) (xy 228.20072 -108.312309) (xy 228.206075 -108.330548)
			(xy 244.367592 -108.330548) (xy 244.367592 -108.276052) (xy 244.375347 -108.22211) (xy 244.3907 -108.16982)
			(xy 244.413337 -108.120248) (xy 244.442798 -108.074401) (xy 244.478484 -108.033214) (xy 244.519667 -107.997523)
			(xy 244.565511 -107.968057) (xy 244.615081 -107.945414) (xy 244.667369 -107.930056) (xy 244.72131 -107.922295)
			(xy 244.748558 -107.921806) (xy 244.776103 -107.92236) (xy 244.830622 -107.930265) (xy 244.883436 -107.945932)
			(xy 244.933448 -107.969033) (xy 244.979615 -107.999089) (xy 245.020979 -108.035475) (xy 245.056677 -108.077432)
			(xy 245.085968 -108.124089) (xy 245.108242 -108.174475) (xy 245.123035 -108.227541) (xy 245.127018 -108.2548)
			(xy 245.128796 -108.26877) (xy 245.146068 -108.290614) (xy 245.255288 -108.333032) (xy 245.282974 -108.328206)
			(xy 245.293388 -108.319316) (xy 245.314181 -108.3023) (xy 245.359606 -108.27361) (xy 245.408609 -108.251578)
			(xy 245.460218 -108.236643) (xy 245.513413 -108.229099) (xy 245.540276 -108.228638) (xy 245.568957 -108.229202)
			(xy 245.625669 -108.237809) (xy 245.680456 -108.254802) (xy 245.732084 -108.2798) (xy 245.779392 -108.312239)
			(xy 245.821316 -108.351389) (xy 245.856911 -108.396371) (xy 245.885378 -108.446171) (xy 245.906074 -108.499669)
			(xy 245.918535 -108.55566) (xy 245.921022 -108.584238) (xy 245.922038 -108.593333) (xy 245.929585 -108.609991)
			(xy 245.935754 -108.61675) (xy 245.989602 -108.670598) (xy 246.006112 -108.678218) (xy 246.015256 -108.678726)
			(xy 246.043842 -108.681195) (xy 246.099854 -108.693625) (xy 246.153373 -108.7143) (xy 246.203194 -108.742756)
			(xy 246.248193 -108.778351) (xy 246.258577 -108.78947) (xy 257.477512 -108.78947) (xy 257.481583 -108.733848)
			(xy 257.493709 -108.679411) (xy 257.513632 -108.62732) (xy 257.540928 -108.578685) (xy 257.575014 -108.534542)
			(xy 257.615163 -108.495833) (xy 257.660521 -108.463382) (xy 257.710121 -108.437881) (xy 257.762905 -108.419874)
			(xy 257.817748 -108.409744) (xy 257.873482 -108.407707) (xy 257.928919 -108.413807) (xy 257.982876 -108.427913)
			(xy 258.034205 -108.449725) (xy 258.081811 -108.478779) (xy 258.124679 -108.514454) (xy 258.161896 -108.555991)
			(xy 258.192669 -108.602504) (xy 258.216341 -108.653001) (xy 258.232409 -108.706408) (xy 258.240529 -108.761584)
			(xy 258.241038 -108.78947) (xy 258.240529 -108.817356) (xy 258.232409 -108.872532) (xy 258.216341 -108.925939)
			(xy 258.192669 -108.976436) (xy 258.161896 -109.022949) (xy 258.124679 -109.064486) (xy 258.081811 -109.100161)
			(xy 258.034205 -109.129215) (xy 257.982876 -109.151027) (xy 257.928919 -109.165133) (xy 257.873482 -109.171233)
			(xy 257.817748 -109.169196) (xy 257.762905 -109.159066) (xy 257.710121 -109.141059) (xy 257.660521 -109.115558)
			(xy 257.615163 -109.083107) (xy 257.575014 -109.044398) (xy 257.540928 -109.000255) (xy 257.513632 -108.95162)
			(xy 257.493709 -108.899529) (xy 257.481583 -108.845092) (xy 257.477512 -108.78947) (xy 246.258577 -108.78947)
			(xy 246.287354 -108.820282) (xy 246.319797 -108.867604) (xy 246.344788 -108.91925) (xy 246.361765 -108.974055)
			(xy 246.370345 -109.030785) (xy 246.370856 -109.059472) (xy 246.370296 -109.08672) (xy 246.362544 -109.140663)
			(xy 246.347195 -109.192953) (xy 246.324561 -109.242527) (xy 246.308516 -109.267498) (xy 246.461786 -109.267498)
			(xy 246.465857 -109.211876) (xy 246.477983 -109.157439) (xy 246.497906 -109.105348) (xy 246.525202 -109.056713)
			(xy 246.559288 -109.01257) (xy 246.599437 -108.973861) (xy 246.644795 -108.94141) (xy 246.694395 -108.915909)
			(xy 246.747179 -108.897902) (xy 246.802022 -108.887772) (xy 246.857756 -108.885735) (xy 246.913193 -108.891835)
			(xy 246.96715 -108.905941) (xy 247.018479 -108.927753) (xy 247.066085 -108.956807) (xy 247.108953 -108.992482)
			(xy 247.14617 -109.034019) (xy 247.176943 -109.080532) (xy 247.200615 -109.131029) (xy 247.216683 -109.184436)
			(xy 247.224803 -109.239612) (xy 247.225312 -109.267498) (xy 247.224803 -109.295384) (xy 247.216683 -109.35056)
			(xy 247.200615 -109.403967) (xy 247.197442 -109.410736) (xy 266.291227 -109.410736) (xy 266.291227 -109.353464)
			(xy 266.299378 -109.296775) (xy 266.315514 -109.241823) (xy 266.339306 -109.189726) (xy 266.37027 -109.141546)
			(xy 266.407777 -109.098264) (xy 266.451061 -109.06076) (xy 266.499242 -109.029797) (xy 266.55134 -109.006007)
			(xy 266.606292 -108.989874) (xy 266.662982 -108.981725) (xy 266.691618 -108.98124) (xy 266.706532 -108.981352)
			(xy 266.736281 -108.983511) (xy 266.751054 -108.985558) (xy 266.76223 -108.987336) (xy 266.783312 -108.98124)
			(xy 266.850114 -108.923582) (xy 266.858091 -108.915999) (xy 266.86717 -108.895972) (xy 266.86764 -108.884974)
			(xy 266.86764 -108.620306) (xy 266.867119 -108.609319) (xy 266.858053 -108.589308) (xy 266.850114 -108.581698)
			(xy 266.783312 -108.52404) (xy 266.76223 -108.517944) (xy 266.751054 -108.519722) (xy 266.736281 -108.521771)
			(xy 266.706532 -108.523931) (xy 266.691618 -108.52404) (xy 266.662987 -108.523499) (xy 266.606309 -108.515352)
			(xy 266.551366 -108.499222) (xy 266.499279 -108.475436) (xy 266.451106 -108.44448) (xy 266.40783 -108.406982)
			(xy 266.370331 -108.363708) (xy 266.339373 -108.315537) (xy 266.315585 -108.263451) (xy 266.299452 -108.208509)
			(xy 266.291303 -108.151831) (xy 266.291303 -108.094569) (xy 266.299452 -108.037891) (xy 266.315585 -107.982949)
			(xy 266.339373 -107.930863) (xy 266.370331 -107.882692) (xy 266.40783 -107.839418) (xy 266.451106 -107.80192)
			(xy 266.499279 -107.770964) (xy 266.551366 -107.747178) (xy 266.606309 -107.731048) (xy 266.662987 -107.722901)
			(xy 266.691618 -107.722416) (xy 266.718988 -107.722874) (xy 266.77322 -107.730321) (xy 266.825936 -107.745075)
			(xy 266.876155 -107.766861) (xy 266.922944 -107.795275) (xy 266.965434 -107.829788) (xy 267.002835 -107.869759)
			(xy 267.019024 -107.891834) (xy 267.024592 -107.89909) (xy 267.039697 -107.909378) (xy 267.048488 -107.9119)
			(xy 267.07846 -107.919266) (xy 267.087413 -107.92099) (xy 267.105498 -107.91879) (xy 267.113766 -107.914948)
			(xy 267.138375 -107.902593) (xy 267.189909 -107.883191) (xy 267.243398 -107.870106) (xy 267.298069 -107.863529)
			(xy 267.325602 -107.863132) (xy 267.353136 -107.863527) (xy 267.40781 -107.870091) (xy 267.461301 -107.883173)
			(xy 267.512833 -107.902583) (xy 267.537438 -107.914948) (xy 267.54569 -107.918844) (xy 267.563793 -107.921048)
			(xy 267.572744 -107.919266) (xy 267.602716 -107.9119) (xy 267.611493 -107.909345) (xy 267.626595 -107.89907)
			(xy 267.63218 -107.891834) (xy 267.648373 -107.869763) (xy 267.685774 -107.829793) (xy 267.728264 -107.795281)
			(xy 267.775052 -107.766868) (xy 267.825271 -107.745082) (xy 267.877985 -107.730329) (xy 267.932216 -107.722882)
			(xy 267.959586 -107.722416) (xy 267.98822 -107.722846) (xy 268.044907 -107.730994) (xy 268.099856 -107.747127)
			(xy 268.151951 -107.770916) (xy 268.200129 -107.801877) (xy 268.243411 -107.839379) (xy 268.280915 -107.88266)
			(xy 268.311877 -107.930837) (xy 268.335668 -107.98293) (xy 268.351803 -108.03788) (xy 268.359953 -108.094566)
			(xy 268.359953 -108.151834) (xy 268.351803 -108.20852) (xy 268.335668 -108.26347) (xy 268.311877 -108.315563)
			(xy 268.280915 -108.36374) (xy 268.243411 -108.407021) (xy 268.200129 -108.444523) (xy 268.151951 -108.475484)
			(xy 268.099856 -108.499273) (xy 268.044907 -108.515406) (xy 267.98822 -108.523554) (xy 267.959586 -108.52404)
			(xy 267.944672 -108.523927) (xy 267.914923 -108.521768) (xy 267.90015 -108.519722) (xy 267.888974 -108.517944)
			(xy 267.867892 -108.52404) (xy 267.80109 -108.581698) (xy 267.793123 -108.58929) (xy 267.784038 -108.60931)
			(xy 267.783564 -108.620306) (xy 267.783564 -108.884974) (xy 267.78404 -108.895966) (xy 267.793137 -108.915977)
			(xy 267.80109 -108.923582) (xy 267.867892 -108.98124) (xy 267.888974 -108.987336) (xy 267.90015 -108.985558)
			(xy 267.914923 -108.983509) (xy 267.944672 -108.981348) (xy 267.959586 -108.98124) (xy 267.988215 -108.981822)
			(xy 268.044891 -108.989968) (xy 268.09983 -109.006098) (xy 268.151914 -109.029883) (xy 268.200083 -109.060838)
			(xy 268.243357 -109.098333) (xy 268.280854 -109.141605) (xy 268.31181 -109.189773) (xy 268.335597 -109.241857)
			(xy 268.351729 -109.296796) (xy 268.359877 -109.353471) (xy 268.359877 -109.410729) (xy 268.351729 -109.467404)
			(xy 268.335597 -109.522343) (xy 268.31181 -109.574427) (xy 268.280854 -109.622595) (xy 268.243357 -109.665867)
			(xy 268.200083 -109.703362) (xy 268.151914 -109.734317) (xy 268.09983 -109.758102) (xy 268.044891 -109.774232)
			(xy 267.988215 -109.782378) (xy 267.959586 -109.782864) (xy 267.932215 -109.782412) (xy 267.877983 -109.774965)
			(xy 267.825267 -109.76021) (xy 267.775048 -109.738423) (xy 267.728259 -109.710009) (xy 267.685769 -109.675494)
			(xy 267.648368 -109.635521) (xy 267.63218 -109.613446) (xy 267.626614 -109.606188) (xy 267.611508 -109.595902)
			(xy 267.602716 -109.59338) (xy 267.572744 -109.586014) (xy 267.563791 -109.584294) (xy 267.545706 -109.586492)
			(xy 267.537438 -109.590332) (xy 267.512828 -109.602684) (xy 267.461294 -109.622087) (xy 267.407806 -109.635173)
			(xy 267.353135 -109.641751) (xy 267.325602 -109.642148) (xy 267.298068 -109.641754) (xy 267.243394 -109.63519)
			(xy 267.189903 -109.622107) (xy 267.13837 -109.602697) (xy 267.113766 -109.590332) (xy 267.105513 -109.586438)
			(xy 267.087411 -109.584233) (xy 267.07846 -109.586014) (xy 267.048488 -109.59338) (xy 267.039702 -109.595911)
			(xy 267.024603 -109.606201) (xy 267.019024 -109.613446) (xy 267.002822 -109.63551) (xy 266.965423 -109.675482)
			(xy 266.922936 -109.709995) (xy 266.876148 -109.738409) (xy 266.825931 -109.760196) (xy 266.773218 -109.77495)
			(xy 266.718988 -109.782397) (xy 266.691618 -109.782864) (xy 266.662982 -109.782475) (xy 266.606292 -109.774326)
			(xy 266.55134 -109.758193) (xy 266.499242 -109.734403) (xy 266.451061 -109.70344) (xy 266.407777 -109.665936)
			(xy 266.37027 -109.622654) (xy 266.339306 -109.574474) (xy 266.315514 -109.522377) (xy 266.299378 -109.467425)
			(xy 266.291227 -109.410736) (xy 247.197442 -109.410736) (xy 247.176943 -109.454464) (xy 247.14617 -109.500977)
			(xy 247.108953 -109.542514) (xy 247.066085 -109.578189) (xy 247.018479 -109.607243) (xy 246.96715 -109.629055)
			(xy 246.913193 -109.643161) (xy 246.857756 -109.649261) (xy 246.802022 -109.647224) (xy 246.747179 -109.637094)
			(xy 246.694395 -109.619087) (xy 246.644795 -109.593586) (xy 246.599437 -109.561135) (xy 246.559288 -109.522426)
			(xy 246.525202 -109.478283) (xy 246.497906 -109.429648) (xy 246.477983 -109.377557) (xy 246.465857 -109.32312)
			(xy 246.461786 -109.267498) (xy 246.308516 -109.267498) (xy 246.295102 -109.288375) (xy 246.259418 -109.329565)
			(xy 246.218236 -109.365256) (xy 246.172394 -109.394724) (xy 246.122825 -109.417369) (xy 246.070537 -109.432728)
			(xy 246.016596 -109.44049) (xy 245.989348 -109.44098) (xy 245.960666 -109.440469) (xy 245.903953 -109.431852)
			(xy 245.849166 -109.41485) (xy 245.797538 -109.389845) (xy 245.750231 -109.357399) (xy 245.708309 -109.318243)
			(xy 245.672714 -109.273257) (xy 245.644249 -109.223454) (xy 245.623552 -109.169953) (xy 245.611089 -109.113959)
			(xy 245.608602 -109.08538) (xy 245.607572 -109.076288) (xy 245.600034 -109.059629) (xy 245.59387 -109.052868)
			(xy 245.540022 -108.99902) (xy 245.523512 -108.9914) (xy 245.514368 -108.990892) (xy 245.485303 -108.988355)
			(xy 245.428381 -108.975565) (xy 245.374069 -108.954261) (xy 245.323632 -108.92494) (xy 245.278244 -108.888286)
			(xy 245.238963 -108.84515) (xy 245.206704 -108.79654) (xy 245.182218 -108.743586) (xy 245.166076 -108.687523)
			(xy 245.161816 -108.65866) (xy 245.160038 -108.64469) (xy 245.142766 -108.622846) (xy 245.033546 -108.580428)
			(xy 245.00586 -108.585254) (xy 244.995446 -108.594144) (xy 244.974684 -108.611199) (xy 244.92925 -108.639882)
			(xy 244.880239 -108.661905) (xy 244.828623 -108.676831) (xy 244.775423 -108.684366) (xy 244.748558 -108.684822)
			(xy 244.72131 -108.684305) (xy 244.667369 -108.676544) (xy 244.615081 -108.661186) (xy 244.565511 -108.638543)
			(xy 244.519667 -108.609077) (xy 244.478484 -108.573386) (xy 244.442798 -108.532199) (xy 244.413337 -108.486352)
			(xy 244.3907 -108.43678) (xy 244.375347 -108.38449) (xy 244.367592 -108.330548) (xy 228.206075 -108.330548)
			(xy 228.216074 -108.364603) (xy 228.22383 -108.418549) (xy 228.22383 -108.473051) (xy 228.216074 -108.526997)
			(xy 228.20072 -108.579291) (xy 228.17808 -108.628868) (xy 228.148616 -108.674718) (xy 228.112926 -108.715908)
			(xy 228.071738 -108.7516) (xy 228.02589 -108.781068) (xy 227.976315 -108.803711) (xy 227.924023 -108.819069)
			(xy 227.870077 -108.826828) (xy 227.842826 -108.827316) (xy 227.815455 -108.826855) (xy 227.761275 -108.819039)
			(xy 227.708771 -108.80355) (xy 227.659024 -108.780707) (xy 227.613059 -108.750979) (xy 227.592128 -108.733336)
			(xy 227.591874 -108.733082) (xy 227.584772 -108.727518) (xy 227.567867 -108.721258) (xy 227.558854 -108.72089)
			(xy 227.491798 -108.72089) (xy 227.482781 -108.721248) (xy 227.465864 -108.727495) (xy 227.458778 -108.733082)
			(xy 227.458524 -108.733336) (xy 227.437591 -108.750977) (xy 227.391623 -108.780701) (xy 227.341877 -108.803547)
			(xy 227.289375 -108.819043) (xy 227.235197 -108.826872) (xy 227.180455 -108.826872) (xy 227.126277 -108.819043)
			(xy 227.073775 -108.803547) (xy 227.024029 -108.780701) (xy 226.978061 -108.750977) (xy 226.957128 -108.733336)
			(xy 226.956874 -108.733082) (xy 226.949772 -108.727518) (xy 226.932867 -108.721258) (xy 226.923854 -108.72089)
			(xy 226.856798 -108.72089) (xy 226.847781 -108.721248) (xy 226.830864 -108.727495) (xy 226.823778 -108.733082)
			(xy 226.823778 -108.733336) (xy 226.823524 -108.733336) (xy 226.802598 -108.750983) (xy 226.756623 -108.780692)
			(xy 226.706874 -108.803526) (xy 226.654372 -108.819016) (xy 226.600196 -108.826842) (xy 226.572826 -108.827316)
			(xy 226.546513 -108.826826) (xy 226.494386 -108.819595) (xy 226.443743 -108.80528) (xy 226.395544 -108.784152)
			(xy 226.3507 -108.75661) (xy 226.310059 -108.723176) (xy 226.291902 -108.704126) (xy 226.284378 -108.696727)
			(xy 226.2651 -108.6882) (xy 226.254564 -108.687616) (xy 226.179888 -108.687616) (xy 226.169335 -108.688121)
			(xy 226.15004 -108.696673) (xy 226.14255 -108.704126) (xy 226.124417 -108.723204) (xy 226.083782 -108.756658)
			(xy 226.038937 -108.784213) (xy 225.990732 -108.805348) (xy 225.94008 -108.81966) (xy 225.887943 -108.82688)
			(xy 225.861626 -108.827316) (xy 225.834373 -108.826838) (xy 225.78042 -108.819085) (xy 225.72812 -108.803731)
			(xy 225.678538 -108.781091) (xy 225.632682 -108.751624) (xy 225.591487 -108.715931) (xy 225.555792 -108.674739)
			(xy 225.526322 -108.628885) (xy 225.503678 -108.579304) (xy 225.488321 -108.527006) (xy 225.480563 -108.473053)
			(xy 224.22383 -108.473053) (xy 224.216075 -108.526996) (xy 224.200721 -108.579289) (xy 224.178082 -108.628865)
			(xy 224.148618 -108.674715) (xy 224.112929 -108.715905) (xy 224.071742 -108.751598) (xy 224.025895 -108.781065)
			(xy 223.976321 -108.803709) (xy 223.924029 -108.819067) (xy 223.870084 -108.826828) (xy 223.842834 -108.827316)
			(xy 223.815464 -108.82685) (xy 223.761284 -108.819036) (xy 223.70878 -108.803548) (xy 223.659033 -108.780705)
			(xy 223.613067 -108.750979) (xy 223.592136 -108.733336) (xy 223.591882 -108.733082) (xy 223.584806 -108.72748)
			(xy 223.567881 -108.721243) (xy 223.558862 -108.72089) (xy 223.491806 -108.72089) (xy 223.48279 -108.721252)
			(xy 223.465873 -108.727496) (xy 223.458786 -108.733082) (xy 223.458532 -108.733336) (xy 223.437599 -108.750977)
			(xy 223.391631 -108.780701) (xy 223.341885 -108.803547) (xy 223.289383 -108.819043) (xy 223.235205 -108.826872)
			(xy 223.180463 -108.826872) (xy 223.126285 -108.819043) (xy 223.073783 -108.803547) (xy 223.024037 -108.780701)
			(xy 222.978069 -108.750977) (xy 222.957136 -108.733336) (xy 222.956882 -108.733082) (xy 222.949806 -108.72748)
			(xy 222.932881 -108.721243) (xy 222.923862 -108.72089) (xy 222.856806 -108.72089) (xy 222.84779 -108.721252)
			(xy 222.830873 -108.727496) (xy 222.823786 -108.733082) (xy 222.823786 -108.733336) (xy 222.823532 -108.733336)
			(xy 222.802599 -108.750977) (xy 222.756631 -108.780701) (xy 222.706885 -108.803547) (xy 222.654383 -108.819043)
			(xy 222.600205 -108.826872) (xy 222.545463 -108.826872) (xy 222.491285 -108.819043) (xy 222.438783 -108.803547)
			(xy 222.389037 -108.780701) (xy 222.343069 -108.750977) (xy 222.322136 -108.733336) (xy 222.321882 -108.733082)
			(xy 222.314806 -108.72748) (xy 222.297881 -108.721243) (xy 222.288862 -108.72089) (xy 222.221806 -108.72089)
			(xy 222.21279 -108.721252) (xy 222.195873 -108.727496) (xy 222.188786 -108.733082) (xy 222.188786 -108.733336)
			(xy 222.188532 -108.733336) (xy 222.167603 -108.750979) (xy 222.121629 -108.780689) (xy 222.071881 -108.803524)
			(xy 222.019379 -108.819014) (xy 221.965203 -108.826842) (xy 221.937834 -108.827316) (xy 221.91058 -108.826839)
			(xy 221.856627 -108.819086) (xy 221.804326 -108.803733) (xy 221.754742 -108.781093) (xy 221.708886 -108.751627)
			(xy 221.66769 -108.715934) (xy 221.631994 -108.674741) (xy 221.602523 -108.628887) (xy 221.579879 -108.579306)
			(xy 221.564521 -108.527007) (xy 221.556763 -108.473054) (xy 199.49726 -108.473054) (xy 199.499675 -108.486484)
			(xy 199.513547 -108.513414) (xy 199.534707 -108.53509) (xy 199.547734 -108.542836) (xy 199.573125 -108.557309)
			(xy 199.619559 -108.592795) (xy 199.660042 -108.634944) (xy 199.693626 -108.682772) (xy 199.719528 -108.73516)
			(xy 199.737142 -108.790884) (xy 199.746056 -108.848641) (xy 199.746616 -108.877862) (xy 199.74613 -108.905113)
			(xy 199.738374 -108.959061) (xy 199.723019 -109.011356) (xy 199.700377 -109.060933) (xy 199.670911 -109.106783)
			(xy 199.63522 -109.147974) (xy 199.594029 -109.183665) (xy 199.548179 -109.213131) (xy 199.498602 -109.235773)
			(xy 199.446307 -109.251128) (xy 199.392359 -109.258884) (xy 199.337857 -109.258884) (xy 199.283909 -109.251128)
			(xy 199.231614 -109.235773) (xy 199.182037 -109.213131) (xy 199.136187 -109.183665) (xy 199.094996 -109.147974)
			(xy 199.059305 -109.106783) (xy 199.029839 -109.060933) (xy 199.007197 -109.011356) (xy 198.991842 -108.959061)
			(xy 198.984086 -108.905113) (xy 198.9836 -108.877862) (xy 198.984122 -108.85029) (xy 198.992065 -108.795721)
			(xy 199.007781 -108.742864) (xy 199.030943 -108.692819) (xy 199.061066 -108.64663) (xy 199.097525 -108.605259)
			(xy 199.13956 -108.569566) (xy 199.16267 -108.55452) (xy 199.175246 -108.546064) (xy 199.195105 -108.523192)
			(xy 199.207383 -108.495502) (xy 199.211001 -108.465428) (xy 199.20564 -108.435615) (xy 199.191772 -108.408686)
			(xy 199.170615 -108.387008) (xy 199.15759 -108.37926) (xy 199.132203 -108.36478) (xy 199.085768 -108.329297)
			(xy 199.045284 -108.287149) (xy 199.011698 -108.239323) (xy 198.985795 -108.186935) (xy 198.968181 -108.131212)
			(xy 198.959268 -108.073455) (xy 198.958708 -108.044234) (xy 187.05449 -108.044234) (xy 187.054236 -108.044488)
			(xy 187.054236 -108.047282) (xy 187.054744 -108.06557) (xy 187.054744 -108.066078) (xy 187.054744 -109.41304)
			(xy 187.929266 -109.41304) (xy 187.929752 -109.385789) (xy 187.937508 -109.331841) (xy 187.952863 -109.279546)
			(xy 187.975505 -109.229969) (xy 188.004971 -109.184119) (xy 188.040662 -109.142928) (xy 188.081853 -109.107237)
			(xy 188.127703 -109.077771) (xy 188.17728 -109.055129) (xy 188.229575 -109.039774) (xy 188.283523 -109.032018)
			(xy 188.338025 -109.032018) (xy 188.391973 -109.039774) (xy 188.444268 -109.055129) (xy 188.493845 -109.077771)
			(xy 188.539695 -109.107237) (xy 188.580886 -109.142928) (xy 188.616577 -109.184119) (xy 188.646043 -109.229969)
			(xy 188.668685 -109.279546) (xy 188.68404 -109.331841) (xy 188.691796 -109.385789) (xy 188.692282 -109.41304)
			(xy 188.691859 -109.439235) (xy 188.68469 -109.491133) (xy 188.670493 -109.541563) (xy 188.649533 -109.589579)
			(xy 188.622205 -109.634277) (xy 188.589021 -109.674819) (xy 188.570108 -109.692948) (xy 188.562754 -109.700564)
			(xy 188.554344 -109.719966) (xy 188.553852 -109.73054) (xy 188.55436 -109.816392) (xy 188.562996 -109.83595)
			(xy 188.571124 -109.843062) (xy 188.590683 -109.861205) (xy 188.625012 -109.902043) (xy 188.653313 -109.947267)
			(xy 188.675034 -109.995995) (xy 188.68975 -110.047275) (xy 188.697176 -110.100105) (xy 188.697616 -110.12678)
			(xy 188.69713 -110.154031) (xy 188.689374 -110.207979) (xy 188.674019 -110.260274) (xy 188.651377 -110.309851)
			(xy 188.621911 -110.355701) (xy 188.58622 -110.396892) (xy 188.545029 -110.432583) (xy 188.499179 -110.462049)
			(xy 188.449602 -110.484691) (xy 188.397307 -110.500046) (xy 188.343359 -110.507802) (xy 188.288857 -110.507802)
			(xy 188.234909 -110.500046) (xy 188.182614 -110.484691) (xy 188.133037 -110.462049) (xy 188.087187 -110.432583)
			(xy 188.045996 -110.396892) (xy 188.010305 -110.355701) (xy 187.980839 -110.309851) (xy 187.958197 -110.260274)
			(xy 187.942842 -110.207979) (xy 187.935086 -110.154031) (xy 187.9346 -110.12678) (xy 187.935042 -110.100585)
			(xy 187.942208 -110.048689) (xy 187.956402 -109.998259) (xy 187.977358 -109.950244) (xy 188.004683 -109.905545)
			(xy 188.037862 -109.865002) (xy 188.056774 -109.846872) (xy 188.064176 -109.839296) (xy 188.072556 -109.819863)
			(xy 188.07303 -109.80928) (xy 188.072522 -109.723428) (xy 188.063886 -109.70387) (xy 188.055758 -109.696758)
			(xy 188.036205 -109.678609) (xy 188.001877 -109.637772) (xy 187.973575 -109.592548) (xy 187.951854 -109.543822)
			(xy 187.937135 -109.492544) (xy 187.929708 -109.439714) (xy 187.929266 -109.41304) (xy 187.054744 -109.41304)
			(xy 187.054744 -111.016288) (xy 187.887864 -111.016288) (xy 187.88835 -110.989037) (xy 187.896106 -110.935089)
			(xy 187.911461 -110.882794) (xy 187.934103 -110.833217) (xy 187.963569 -110.787367) (xy 187.99926 -110.746176)
			(xy 188.040451 -110.710485) (xy 188.086301 -110.681019) (xy 188.135878 -110.658377) (xy 188.188173 -110.643022)
			(xy 188.242121 -110.635266) (xy 188.296623 -110.635266) (xy 188.350571 -110.643022) (xy 188.402866 -110.658377)
			(xy 188.452443 -110.681019) (xy 188.498293 -110.710485) (xy 188.539484 -110.746176) (xy 188.575175 -110.787367)
			(xy 188.604641 -110.833217) (xy 188.627283 -110.882794) (xy 188.642638 -110.935089) (xy 188.650394 -110.989037)
			(xy 188.65088 -111.016288) (xy 188.650415 -111.043308) (xy 188.642802 -111.09681) (xy 188.627713 -111.148701)
			(xy 188.60545 -111.197942) (xy 188.576459 -111.243548) (xy 188.541321 -111.284604) (xy 188.52134 -111.3028)
			(xy 188.513377 -111.310452) (xy 188.504433 -111.330622) (xy 188.504068 -111.341662) (xy 188.505338 -111.418878)
			(xy 188.506008 -111.429889) (xy 188.515494 -111.449778) (xy 188.523626 -111.457232) (xy 188.544755 -111.475468)
			(xy 188.582034 -111.517001) (xy 188.61286 -111.563525) (xy 188.636575 -111.614045) (xy 188.652672 -111.667483)
			(xy 188.660808 -111.722697) (xy 188.661294 -111.750602) (xy 188.660671 -111.780394) (xy 188.651421 -111.839255)
			(xy 188.633132 -111.895962) (xy 188.606248 -111.949135) (xy 188.583491 -111.980726) (xy 190.001398 -111.980726)
			(xy 190.001938 -111.951988) (xy 190.010557 -111.895161) (xy 190.027603 -111.840271) (xy 190.052691 -111.788559)
			(xy 190.085253 -111.741195) (xy 190.104522 -111.719868) (xy 190.111126 -111.71301) (xy 190.118238 -111.694976)
			(xy 190.118238 -111.606076) (xy 190.111126 -111.588042) (xy 190.104522 -111.581184) (xy 190.085277 -111.559835)
			(xy 190.052711 -111.512476) (xy 190.027618 -111.460768) (xy 190.010566 -111.405881) (xy 190.001941 -111.349056)
			(xy 190.001939 -111.291581) (xy 190.010558 -111.234756) (xy 190.027604 -111.179867) (xy 190.052692 -111.128157)
			(xy 190.085253 -111.080795) (xy 190.104522 -111.059468) (xy 190.111126 -111.05261) (xy 190.118238 -111.034576)
			(xy 190.118238 -110.945676) (xy 190.111126 -110.927642) (xy 190.104522 -110.920784) (xy 190.085277 -110.899435)
			(xy 190.052711 -110.852076) (xy 190.027618 -110.800368) (xy 190.010566 -110.745481) (xy 190.001941 -110.688656)
			(xy 190.001939 -110.631181) (xy 190.010558 -110.574356) (xy 190.027604 -110.519467) (xy 190.052692 -110.467757)
			(xy 190.085253 -110.420395) (xy 190.104522 -110.399068) (xy 190.111126 -110.39221) (xy 190.118238 -110.374176)
			(xy 190.118238 -110.285276) (xy 190.111126 -110.267242) (xy 190.104522 -110.260384) (xy 190.085277 -110.239035)
			(xy 190.052711 -110.191676) (xy 190.027618 -110.139968) (xy 190.010566 -110.085081) (xy 190.001941 -110.028256)
			(xy 190.001939 -109.970781) (xy 190.010558 -109.913956) (xy 190.027604 -109.859067) (xy 190.052692 -109.807357)
			(xy 190.085253 -109.759995) (xy 190.104522 -109.738668) (xy 190.111126 -109.73181) (xy 190.118238 -109.713776)
			(xy 190.118238 -109.624876) (xy 190.111126 -109.606842) (xy 190.104522 -109.599984) (xy 190.085261 -109.578649)
			(xy 190.052694 -109.531289) (xy 190.0276 -109.479579) (xy 190.010547 -109.42469) (xy 190.001921 -109.367864)
			(xy 190.001398 -109.339126) (xy 190.00188 -109.311874) (xy 190.009633 -109.257923) (xy 190.024986 -109.205625)
			(xy 190.047626 -109.156045) (xy 190.077092 -109.110191) (xy 190.112784 -109.068998) (xy 190.153975 -109.033304)
			(xy 190.199827 -109.003836) (xy 190.249406 -108.981193) (xy 190.301703 -108.965837) (xy 190.355654 -108.958081)
			(xy 190.382906 -108.957618) (xy 190.40922 -108.958076) (xy 190.46135 -108.965312) (xy 190.511993 -108.979632)
			(xy 190.560192 -109.000767) (xy 190.605035 -109.028315) (xy 190.645674 -109.061755) (xy 190.66383 -109.080808)
			(xy 190.671338 -109.088226) (xy 190.690628 -109.09674) (xy 190.701168 -109.097318) (xy 190.775844 -109.097318)
			(xy 190.786391 -109.096767) (xy 190.805686 -109.088247) (xy 190.813182 -109.080808) (xy 190.831355 -109.06177)
			(xy 190.871981 -109.028311) (xy 190.916817 -109.000749) (xy 190.965015 -108.979608) (xy 191.015659 -108.965287)
			(xy 191.067791 -108.958058) (xy 191.094106 -108.957618) (xy 191.12136 -108.95805) (xy 191.175314 -108.965808)
			(xy 191.227614 -108.981166) (xy 191.277195 -109.003811) (xy 191.32305 -109.033283) (xy 191.364243 -109.06898)
			(xy 191.399937 -109.110176) (xy 191.429404 -109.156033) (xy 191.452045 -109.205616) (xy 191.467399 -109.257918)
			(xy 191.475152 -109.311872) (xy 191.475614 -109.339126) (xy 191.475102 -109.367865) (xy 191.466476 -109.424693)
			(xy 191.449423 -109.479584) (xy 191.424329 -109.531295) (xy 191.391762 -109.578657) (xy 191.37249 -109.599984)
			(xy 191.365886 -109.606842) (xy 191.358774 -109.624876) (xy 191.358774 -109.713776) (xy 191.365886 -109.73181)
			(xy 191.37249 -109.738668) (xy 191.391786 -109.759973) (xy 191.424349 -109.807339) (xy 191.449438 -109.859055)
			(xy 191.466486 -109.913949) (xy 191.475106 -109.970779) (xy 191.475103 -110.028259) (xy 191.466477 -110.085088)
			(xy 191.449424 -110.13998) (xy 191.42433 -110.191693) (xy 191.391762 -110.239057) (xy 191.37249 -110.260384)
			(xy 191.365886 -110.267242) (xy 191.358774 -110.285276) (xy 191.358774 -110.374176) (xy 191.365886 -110.39221)
			(xy 191.37249 -110.399068) (xy 191.391786 -110.420373) (xy 191.424349 -110.467739) (xy 191.449438 -110.519455)
			(xy 191.466486 -110.574349) (xy 191.475106 -110.631179) (xy 191.475106 -110.631732) (xy 209.194654 -110.631732)
			(xy 209.195149 -110.602992) (xy 209.20378 -110.546164) (xy 209.220838 -110.491273) (xy 209.245935 -110.439562)
			(xy 209.278505 -110.392201) (xy 209.297778 -110.370874) (xy 209.304382 -110.364016) (xy 209.311494 -110.345982)
			(xy 209.311494 -110.257082) (xy 209.304382 -110.239048) (xy 209.297778 -110.23219) (xy 209.278541 -110.210835)
			(xy 209.245979 -110.163476) (xy 209.220888 -110.111768) (xy 209.203838 -110.056882) (xy 209.195214 -110.00006)
			(xy 209.19521 -109.942587) (xy 209.203828 -109.885763) (xy 209.220871 -109.830875) (xy 209.245955 -109.779165)
			(xy 209.278512 -109.731802) (xy 209.297778 -109.710474) (xy 209.304382 -109.703616) (xy 209.311494 -109.685582)
			(xy 209.311494 -109.596682) (xy 209.304382 -109.578648) (xy 209.297778 -109.57179) (xy 209.278529 -109.550444)
			(xy 209.245958 -109.503088) (xy 209.220861 -109.451381) (xy 209.203805 -109.396494) (xy 209.195177 -109.33967)
			(xy 209.194654 -109.310932) (xy 209.19514 -109.283681) (xy 209.202896 -109.229733) (xy 209.218251 -109.177438)
			(xy 209.240893 -109.127861) (xy 209.270359 -109.082011) (xy 209.30605 -109.04082) (xy 209.347241 -109.005129)
			(xy 209.393091 -108.975663) (xy 209.442668 -108.953021) (xy 209.494963 -108.937666) (xy 209.548911 -108.92991)
			(xy 209.603413 -108.92991) (xy 209.657361 -108.937666) (xy 209.709656 -108.953021) (xy 209.759233 -108.975663)
			(xy 209.805083 -109.005129) (xy 209.846274 -109.04082) (xy 209.881965 -109.082011) (xy 209.911431 -109.127861)
			(xy 209.934073 -109.177438) (xy 209.949428 -109.229733) (xy 209.957184 -109.283681) (xy 209.95767 -109.310932)
			(xy 209.957147 -109.339671) (xy 209.948521 -109.396497) (xy 209.93147 -109.451387) (xy 209.906379 -109.503099)
			(xy 209.873815 -109.550462) (xy 209.854546 -109.57179) (xy 209.847942 -109.578648) (xy 209.84083 -109.596682)
			(xy 209.84083 -109.685582) (xy 209.847942 -109.703616) (xy 209.854546 -109.710474) (xy 209.87385 -109.731773)
			(xy 209.906417 -109.779139) (xy 209.931508 -109.830855) (xy 209.948558 -109.885751) (xy 209.957178 -109.942582)
			(xy 209.957174 -110.000064) (xy 209.948547 -110.056895) (xy 209.931491 -110.111788) (xy 209.906393 -110.163501)
			(xy 209.873821 -110.210864) (xy 209.854546 -110.23219) (xy 209.847942 -110.239048) (xy 209.84083 -110.257082)
			(xy 209.84083 -110.345982) (xy 209.847942 -110.364016) (xy 209.854546 -110.370874) (xy 209.873829 -110.39219)
			(xy 209.906394 -110.439555) (xy 209.931485 -110.491269) (xy 209.948532 -110.546163) (xy 209.957151 -110.602992)
			(xy 209.95767 -110.631732) (xy 209.957184 -110.658983) (xy 209.956428 -110.664244) (xy 210.788504 -110.664244)
			(xy 210.788993 -110.635504) (xy 210.797624 -110.578675) (xy 210.814682 -110.523784) (xy 210.839781 -110.472072)
			(xy 210.872354 -110.424712) (xy 210.891628 -110.403386) (xy 210.898232 -110.396528) (xy 210.905344 -110.378494)
			(xy 210.905344 -110.289594) (xy 210.898232 -110.27156) (xy 210.891628 -110.264702) (xy 210.872401 -110.243337)
			(xy 210.839834 -110.195982) (xy 210.814739 -110.144276) (xy 210.797686 -110.089391) (xy 210.789059 -110.032569)
			(xy 210.789054 -109.975095) (xy 210.797671 -109.918272) (xy 210.814716 -109.863384) (xy 210.839801 -109.811674)
			(xy 210.87236 -109.764313) (xy 210.891628 -109.742986) (xy 210.898232 -109.736128) (xy 210.905344 -109.718094)
			(xy 210.905344 -109.629194) (xy 210.898232 -109.61116) (xy 210.891628 -109.604302) (xy 210.872329 -109.582999)
			(xy 210.839767 -109.535631) (xy 210.81468 -109.483913) (xy 210.797636 -109.429017) (xy 210.789021 -109.372185)
			(xy 210.788504 -109.343444) (xy 210.78899 -109.316193) (xy 210.796746 -109.262245) (xy 210.812101 -109.20995)
			(xy 210.834743 -109.160373) (xy 210.864209 -109.114523) (xy 210.8999 -109.073332) (xy 210.941091 -109.037641)
			(xy 210.986941 -109.008175) (xy 211.036518 -108.985533) (xy 211.088813 -108.970178) (xy 211.142761 -108.962422)
			(xy 211.197263 -108.962422) (xy 211.251211 -108.970178) (xy 211.303506 -108.985533) (xy 211.353083 -109.008175)
			(xy 211.398933 -109.037641) (xy 211.440124 -109.073332) (xy 211.475815 -109.114523) (xy 211.505281 -109.160373)
			(xy 211.527923 -109.20995) (xy 211.543278 -109.262245) (xy 211.551034 -109.316193) (xy 211.55152 -109.343444)
			(xy 211.551018 -109.372184) (xy 211.542389 -109.429012) (xy 211.525334 -109.483902) (xy 211.500238 -109.535614)
			(xy 211.467668 -109.582976) (xy 211.448396 -109.604302) (xy 211.441792 -109.61116) (xy 211.43468 -109.629194)
			(xy 211.43468 -109.718094) (xy 211.441792 -109.736128) (xy 211.448396 -109.742986) (xy 211.46771 -109.764275)
			(xy 211.500272 -109.811645) (xy 211.52536 -109.863363) (xy 211.542405 -109.918259) (xy 211.546513 -109.94535)
			(xy 268.933143 -109.94535) (xy 268.933143 -109.88805) (xy 268.941298 -109.831334) (xy 268.957441 -109.776356)
			(xy 268.981245 -109.724236) (xy 269.012225 -109.676033) (xy 269.049749 -109.63273) (xy 269.093054 -109.595209)
			(xy 269.141259 -109.564233) (xy 269.193381 -109.540432) (xy 269.24836 -109.524292) (xy 269.305076 -109.516141)
			(xy 269.333726 -109.515656) (xy 269.361107 -109.516121) (xy 269.415356 -109.523591) (xy 269.468084 -109.538375)
			(xy 269.518309 -109.560198) (xy 269.565097 -109.588653) (xy 269.607577 -109.623212) (xy 269.644958 -109.66323)
			(xy 269.661132 -109.685328) (xy 269.666699 -109.692585) (xy 269.681804 -109.702873) (xy 269.690596 -109.705394)
			(xy 269.720568 -109.71276) (xy 269.72952 -109.714489) (xy 269.747607 -109.712285) (xy 269.755874 -109.708442)
			(xy 269.780478 -109.69606) (xy 269.832002 -109.67659) (xy 269.885491 -109.663439) (xy 269.94017 -109.656799)
			(xy 269.96771 -109.656372) (xy 269.99525 -109.656809) (xy 270.04993 -109.663442) (xy 270.10342 -109.676586)
			(xy 270.154947 -109.696052) (xy 270.179546 -109.708442) (xy 270.187797 -109.712342) (xy 270.205901 -109.714544)
			(xy 270.214852 -109.71276) (xy 270.244824 -109.705394) (xy 270.253603 -109.702844) (xy 270.268704 -109.692566)
			(xy 270.274288 -109.685328) (xy 270.290469 -109.663233) (xy 270.327838 -109.6232) (xy 270.370312 -109.58863)
			(xy 270.417099 -109.560168) (xy 270.467326 -109.538343) (xy 270.520058 -109.523563) (xy 270.574312 -109.516103)
			(xy 270.601694 -109.515656) (xy 270.630346 -109.516098) (xy 270.687066 -109.524253) (xy 270.742049 -109.540396)
			(xy 270.794175 -109.564201) (xy 270.842382 -109.595181) (xy 270.885689 -109.632706) (xy 270.923216 -109.676013)
			(xy 270.954196 -109.72422) (xy 270.978001 -109.776345) (xy 270.994146 -109.831328) (xy 271.002301 -109.888048)
			(xy 271.002301 -109.945352) (xy 270.994146 -110.002072) (xy 270.978001 -110.057055) (xy 270.954196 -110.10918)
			(xy 270.923216 -110.157387) (xy 270.885689 -110.200694) (xy 270.842382 -110.238219) (xy 270.794175 -110.269199)
			(xy 270.742049 -110.293004) (xy 270.687066 -110.309147) (xy 270.630346 -110.317302) (xy 270.601694 -110.317788)
			(xy 270.586776 -110.317614) (xy 270.557027 -110.315328) (xy 270.542258 -110.313216) (xy 270.531082 -110.311438)
			(xy 270.51 -110.317534) (xy 270.443198 -110.375192) (xy 270.435234 -110.382788) (xy 270.426148 -110.402805)
			(xy 270.425672 -110.4138) (xy 270.425672 -110.678468) (xy 270.426149 -110.68946) (xy 270.435245 -110.709471)
			(xy 270.443198 -110.717076) (xy 270.51 -110.774734) (xy 270.531082 -110.78083) (xy 270.542258 -110.779052)
			(xy 270.557027 -110.776946) (xy 270.586776 -110.774656) (xy 270.601694 -110.77448) (xy 270.630348 -110.774874)
			(xy 270.687071 -110.783029) (xy 270.742057 -110.799174) (xy 270.794186 -110.82298) (xy 270.842396 -110.853962)
			(xy 270.885706 -110.891489) (xy 270.923235 -110.934799) (xy 270.954218 -110.983009) (xy 270.978024 -111.035137)
			(xy 270.994169 -111.090123) (xy 271.002325 -111.146846) (xy 271.002325 -111.204154) (xy 270.994169 -111.260877)
			(xy 270.978024 -111.315863) (xy 270.954218 -111.367991) (xy 270.923235 -111.416201) (xy 270.885706 -111.459511)
			(xy 270.842396 -111.497038) (xy 270.794186 -111.52802) (xy 270.742057 -111.551826) (xy 270.687071 -111.567971)
			(xy 270.630348 -111.576126) (xy 270.601694 -111.576612) (xy 270.574313 -111.576145) (xy 270.520063 -111.568677)
			(xy 270.467335 -111.553894) (xy 270.417109 -111.532072) (xy 270.370321 -111.503617) (xy 270.327842 -111.469058)
			(xy 270.290462 -111.429038) (xy 270.274288 -111.40694) (xy 270.268721 -111.399683) (xy 270.253616 -111.389396)
			(xy 270.244824 -111.386874) (xy 270.214852 -111.379508) (xy 270.205898 -111.377793) (xy 270.187814 -111.379988)
			(xy 270.179546 -111.383826) (xy 270.154938 -111.396198) (xy 270.103415 -111.415672) (xy 270.049928 -111.428825)
			(xy 269.99525 -111.435468) (xy 269.96771 -111.435896) (xy 269.940169 -111.435494) (xy 269.885487 -111.428852)
			(xy 269.831998 -111.415697) (xy 269.780472 -111.396221) (xy 269.755874 -111.383826) (xy 269.74762 -111.379936)
			(xy 269.729519 -111.377729) (xy 269.720568 -111.379508) (xy 269.690596 -111.386874) (xy 269.681812 -111.38941)
			(xy 269.666712 -111.399696) (xy 269.661132 -111.40694) (xy 269.644991 -111.429066) (xy 269.607616 -111.469099)
			(xy 269.565135 -111.503667) (xy 269.518342 -111.532127) (xy 269.468108 -111.553946) (xy 269.415369 -111.568719)
			(xy 269.36111 -111.57617) (xy 269.333726 -111.576612) (xy 269.305078 -111.576035) (xy 269.248365 -111.567884)
			(xy 269.193389 -111.551745) (xy 269.14127 -111.527946) (xy 269.093068 -111.496972) (xy 269.049766 -111.459453)
			(xy 269.012244 -111.416152) (xy 268.981266 -111.367953) (xy 268.957464 -111.315835) (xy 268.941321 -111.26086)
			(xy 268.933167 -111.204148) (xy 268.933167 -111.146852) (xy 268.941321 -111.09014) (xy 268.957464 -111.035165)
			(xy 268.981266 -110.983047) (xy 269.012244 -110.934848) (xy 269.049766 -110.891547) (xy 269.093068 -110.854028)
			(xy 269.14127 -110.823054) (xy 269.193389 -110.799255) (xy 269.248365 -110.783116) (xy 269.305078 -110.774965)
			(xy 269.333726 -110.77448) (xy 269.348644 -110.774651) (xy 269.378393 -110.776939) (xy 269.393162 -110.779052)
			(xy 269.404338 -110.78083) (xy 269.42542 -110.774734) (xy 269.492222 -110.717076) (xy 269.500203 -110.709496)
			(xy 269.509279 -110.689466) (xy 269.509748 -110.678468) (xy 269.509748 -110.4138) (xy 269.509227 -110.402813)
			(xy 269.500161 -110.382802) (xy 269.492222 -110.375192) (xy 269.42542 -110.317534) (xy 269.404338 -110.311438)
			(xy 269.393162 -110.313216) (xy 269.378392 -110.31532) (xy 269.348644 -110.317611) (xy 269.333726 -110.317788)
			(xy 269.305076 -110.317259) (xy 269.24836 -110.309108) (xy 269.193381 -110.292968) (xy 269.141259 -110.269167)
			(xy 269.093054 -110.238191) (xy 269.049749 -110.200669) (xy 269.012225 -110.157367) (xy 268.981245 -110.109164)
			(xy 268.957441 -110.057044) (xy 268.941298 -110.002066) (xy 268.933143 -109.94535) (xy 211.546513 -109.94535)
			(xy 211.551023 -109.975091) (xy 211.551018 -110.032573) (xy 211.542391 -110.089404) (xy 211.525336 -110.144297)
			(xy 211.500239 -110.196011) (xy 211.467669 -110.243375) (xy 211.448396 -110.264702) (xy 211.441792 -110.27156)
			(xy 211.43468 -110.289594) (xy 211.43468 -110.378494) (xy 211.441792 -110.396528) (xy 211.448396 -110.403386)
			(xy 211.467676 -110.424705) (xy 211.500244 -110.472068) (xy 211.525335 -110.523782) (xy 211.542383 -110.578675)
			(xy 211.551002 -110.635504) (xy 211.55152 -110.664244) (xy 211.551034 -110.691495) (xy 211.543278 -110.745443)
			(xy 211.527923 -110.797738) (xy 211.505281 -110.847315) (xy 211.475815 -110.893165) (xy 211.440124 -110.934356)
			(xy 211.398933 -110.970047) (xy 211.353083 -110.999513) (xy 211.303506 -111.022155) (xy 211.251211 -111.03751)
			(xy 211.197263 -111.045266) (xy 211.142761 -111.045266) (xy 211.088813 -111.03751) (xy 211.036518 -111.022155)
			(xy 210.986941 -110.999513) (xy 210.941091 -110.970047) (xy 210.8999 -110.934356) (xy 210.864209 -110.893165)
			(xy 210.834743 -110.847315) (xy 210.812101 -110.797738) (xy 210.796746 -110.745443) (xy 210.78899 -110.691495)
			(xy 210.788504 -110.664244) (xy 209.956428 -110.664244) (xy 209.949428 -110.712931) (xy 209.934073 -110.765226)
			(xy 209.911431 -110.814803) (xy 209.881965 -110.860653) (xy 209.846274 -110.901844) (xy 209.805083 -110.937535)
			(xy 209.759233 -110.967001) (xy 209.709656 -110.989643) (xy 209.657361 -111.004998) (xy 209.603413 -111.012754)
			(xy 209.548911 -111.012754) (xy 209.494963 -111.004998) (xy 209.442668 -110.989643) (xy 209.393091 -110.967001)
			(xy 209.347241 -110.937535) (xy 209.30605 -110.901844) (xy 209.270359 -110.860653) (xy 209.240893 -110.814803)
			(xy 209.218251 -110.765226) (xy 209.202896 -110.712931) (xy 209.19514 -110.658983) (xy 209.194654 -110.631732)
			(xy 191.475106 -110.631732) (xy 191.475103 -110.688659) (xy 191.466477 -110.745488) (xy 191.449424 -110.80038)
			(xy 191.42433 -110.852093) (xy 191.391762 -110.899457) (xy 191.37249 -110.920784) (xy 191.365886 -110.927642)
			(xy 191.358774 -110.945676) (xy 191.358774 -111.034576) (xy 191.365886 -111.05261) (xy 191.37249 -111.059468)
			(xy 191.391786 -111.080773) (xy 191.424349 -111.128139) (xy 191.424695 -111.128853) (xy 221.497087 -111.128853)
			(xy 221.497087 -111.074347) (xy 221.504845 -111.020397) (xy 221.520202 -110.9681) (xy 221.542846 -110.918521)
			(xy 221.572315 -110.87267) (xy 221.608011 -110.83148) (xy 221.649205 -110.795789) (xy 221.69506 -110.766325)
			(xy 221.744641 -110.743686) (xy 221.79694 -110.728335) (xy 221.850891 -110.720584) (xy 221.878144 -110.720124)
			(xy 221.905513 -110.720617) (xy 221.959691 -110.728427) (xy 222.012195 -110.74391) (xy 222.061942 -110.766746)
			(xy 222.10791 -110.796465) (xy 222.128842 -110.814104) (xy 222.129096 -110.814358) (xy 222.136175 -110.819956)
			(xy 222.153098 -110.826194) (xy 222.162116 -110.82655) (xy 222.229172 -110.82655) (xy 222.238189 -110.82619)
			(xy 222.255106 -110.819946) (xy 222.262192 -110.814358) (xy 222.262192 -110.814104) (xy 222.262446 -110.814104)
			(xy 222.283379 -110.796463) (xy 222.329347 -110.766739) (xy 222.379093 -110.743893) (xy 222.431595 -110.728397)
			(xy 222.485773 -110.720568) (xy 222.540515 -110.720568) (xy 222.594693 -110.728397) (xy 222.647195 -110.743893)
			(xy 222.696941 -110.766739) (xy 222.742909 -110.796463) (xy 222.763842 -110.814104) (xy 222.764096 -110.814358)
			(xy 222.771175 -110.819956) (xy 222.788098 -110.826194) (xy 222.797116 -110.82655) (xy 222.864172 -110.82655)
			(xy 222.873189 -110.82619) (xy 222.890106 -110.819946) (xy 222.897192 -110.814358) (xy 222.897192 -110.814104)
			(xy 222.897446 -110.814104) (xy 222.918379 -110.796463) (xy 222.964347 -110.766739) (xy 223.014093 -110.743893)
			(xy 223.066595 -110.728397) (xy 223.120773 -110.720568) (xy 223.175515 -110.720568) (xy 223.229693 -110.728397)
			(xy 223.282195 -110.743893) (xy 223.331941 -110.766739) (xy 223.377909 -110.796463) (xy 223.398842 -110.814104)
			(xy 223.399096 -110.814358) (xy 223.406175 -110.819956) (xy 223.423098 -110.826194) (xy 223.432116 -110.82655)
			(xy 223.499172 -110.82655) (xy 223.508189 -110.82619) (xy 223.525106 -110.819946) (xy 223.532192 -110.814358)
			(xy 223.532192 -110.814104) (xy 223.532446 -110.814104) (xy 223.553388 -110.796477) (xy 223.599358 -110.766764)
			(xy 223.649103 -110.743925) (xy 223.701602 -110.728431) (xy 223.755776 -110.7206) (xy 223.783144 -110.720124)
			(xy 223.810395 -110.720549) (xy 223.864343 -110.728311) (xy 223.916637 -110.743671) (xy 223.966213 -110.766317)
			(xy 224.012061 -110.795787) (xy 224.05325 -110.831481) (xy 224.08894 -110.872674) (xy 224.118404 -110.918526)
			(xy 224.141044 -110.968104) (xy 224.156398 -111.0204) (xy 224.164154 -111.074348) (xy 224.164154 -111.092354)
			(xy 224.941334 -111.092354) (xy 224.941334 -111.037846) (xy 224.949091 -110.983894) (xy 224.964447 -110.931594)
			(xy 224.98709 -110.882012) (xy 225.016558 -110.836158) (xy 225.052252 -110.794963) (xy 225.093445 -110.759267)
			(xy 225.139298 -110.729797) (xy 225.188879 -110.707153) (xy 225.241178 -110.691794) (xy 225.29513 -110.684035)
			(xy 225.322384 -110.683548) (xy 225.349754 -110.684012) (xy 225.403934 -110.691828) (xy 225.456438 -110.707317)
			(xy 225.506185 -110.73016) (xy 225.552151 -110.759886) (xy 225.573082 -110.777528) (xy 225.573336 -110.777782)
			(xy 225.580438 -110.783345) (xy 225.597343 -110.789606) (xy 225.606356 -110.789974) (xy 225.673412 -110.789974)
			(xy 225.68243 -110.789628) (xy 225.699347 -110.783374) (xy 225.706432 -110.777782) (xy 225.706432 -110.777528)
			(xy 225.706686 -110.777528) (xy 225.727616 -110.759886) (xy 225.773589 -110.730174) (xy 225.823337 -110.707338)
			(xy 225.875838 -110.691848) (xy 225.930015 -110.684021) (xy 225.957384 -110.683548) (xy 225.984634 -110.684098)
			(xy 226.038581 -110.691852) (xy 226.090875 -110.707205) (xy 226.140451 -110.729844) (xy 226.186301 -110.759308)
			(xy 226.227491 -110.794998) (xy 226.263182 -110.836186) (xy 226.292648 -110.882035) (xy 226.315289 -110.93161)
			(xy 226.330644 -110.983903) (xy 226.338401 -111.03785) (xy 226.338401 -111.09235) (xy 226.330644 -111.146297)
			(xy 226.32038 -111.181252) (xy 227.301534 -111.181252) (xy 227.301534 -111.126748) (xy 227.30929 -111.072798)
			(xy 227.324644 -111.020501) (xy 227.347285 -110.970921) (xy 227.37675 -110.925068) (xy 227.41244 -110.883874)
			(xy 227.45363 -110.848179) (xy 227.499479 -110.818708) (xy 227.549056 -110.796061) (xy 227.601351 -110.7807)
			(xy 227.6553 -110.772937) (xy 227.682552 -110.772448) (xy 227.709922 -110.772931) (xy 227.764101 -110.780743)
			(xy 227.816604 -110.796227) (xy 227.866351 -110.819066) (xy 227.912318 -110.848788) (xy 227.93325 -110.866428)
			(xy 227.933504 -110.866682) (xy 227.940587 -110.872274) (xy 227.957506 -110.878518) (xy 227.966524 -110.878874)
			(xy 228.03358 -110.878874) (xy 228.042597 -110.878513) (xy 228.059514 -110.872269) (xy 228.0666 -110.866682)
			(xy 228.0666 -110.866428) (xy 228.066854 -110.866428) (xy 228.087796 -110.848801) (xy 228.133766 -110.819087)
			(xy 228.183511 -110.796248) (xy 228.236009 -110.780754) (xy 228.290183 -110.772923) (xy 228.317552 -110.772448)
			(xy 228.344804 -110.772996) (xy 228.398754 -110.780746) (xy 228.451051 -110.796097) (xy 228.500632 -110.818734)
			(xy 228.546486 -110.848197) (xy 228.587679 -110.883887) (xy 228.623374 -110.925076) (xy 228.644311 -110.957652)
			(xy 228.907791 -110.957652) (xy 228.907791 -110.903148) (xy 228.915549 -110.849197) (xy 228.930906 -110.796901)
			(xy 228.95355 -110.747322) (xy 228.983019 -110.701471) (xy 229.018715 -110.660281) (xy 229.059909 -110.624591)
			(xy 229.105764 -110.595127) (xy 229.155346 -110.572489) (xy 229.207644 -110.557139) (xy 229.261595 -110.549388)
			(xy 229.288848 -110.548928) (xy 229.316217 -110.549418) (xy 229.370396 -110.557229) (xy 229.422899 -110.572712)
			(xy 229.472646 -110.595549) (xy 229.518614 -110.625269) (xy 229.539546 -110.642908) (xy 229.5398 -110.643162)
			(xy 229.546877 -110.648762) (xy 229.563801 -110.654999) (xy 229.57282 -110.655354) (xy 229.639876 -110.655354)
			(xy 229.648893 -110.654995) (xy 229.66581 -110.64875) (xy 229.672896 -110.643162) (xy 229.672896 -110.642908)
			(xy 229.67315 -110.642908) (xy 229.694083 -110.625267) (xy 229.740051 -110.595543) (xy 229.789797 -110.572697)
			(xy 229.842299 -110.557201) (xy 229.896477 -110.549372) (xy 229.951219 -110.549372) (xy 230.005397 -110.557201)
			(xy 230.057899 -110.572697) (xy 230.107645 -110.595543) (xy 230.153613 -110.625267) (xy 230.174546 -110.642908)
			(xy 230.1748 -110.643162) (xy 230.181877 -110.648762) (xy 230.198801 -110.654999) (xy 230.20782 -110.655354)
			(xy 230.274876 -110.655354) (xy 230.283893 -110.654995) (xy 230.30081 -110.64875) (xy 230.307896 -110.643162)
			(xy 230.307896 -110.642908) (xy 230.30815 -110.642908) (xy 230.329091 -110.62528) (xy 230.375061 -110.595566)
			(xy 230.424807 -110.572728) (xy 230.477305 -110.557234) (xy 230.531479 -110.549403) (xy 230.558848 -110.548928)
			(xy 230.5861 -110.549345) (xy 230.640047 -110.557108) (xy 230.692341 -110.572469) (xy 230.741917 -110.595115)
			(xy 230.787766 -110.624585) (xy 230.828954 -110.66028) (xy 230.864644 -110.701473) (xy 230.894108 -110.747325)
			(xy 230.916748 -110.796904) (xy 230.932102 -110.8492) (xy 230.939858 -110.903148) (xy 230.939858 -110.953156)
			(xy 233.725619 -110.953156) (xy 233.725619 -110.898644) (xy 233.733377 -110.844686) (xy 233.748736 -110.792381)
			(xy 233.771382 -110.742795) (xy 233.800855 -110.696937) (xy 233.836554 -110.65574) (xy 233.877753 -110.620043)
			(xy 233.923613 -110.590572) (xy 233.9732 -110.567929) (xy 234.025505 -110.552573) (xy 234.079464 -110.544818)
			(xy 234.10672 -110.544356) (xy 234.133035 -110.544792) (xy 234.185166 -110.552031) (xy 234.23581 -110.566355)
			(xy 234.284009 -110.587493) (xy 234.328852 -110.615046) (xy 234.369489 -110.648491) (xy 234.387644 -110.667546)
			(xy 234.395155 -110.674961) (xy 234.414443 -110.68348) (xy 234.424982 -110.684056) (xy 234.499658 -110.684056)
			(xy 234.510208 -110.683531) (xy 234.529505 -110.674994) (xy 234.536996 -110.667546) (xy 234.556816 -110.646758)
			(xy 234.601588 -110.610783) (xy 234.651246 -110.581923) (xy 234.704668 -110.56083) (xy 234.760647 -110.547981)
			(xy 234.81792 -110.543666) (xy 234.875193 -110.547981) (xy 234.931172 -110.56083) (xy 234.984594 -110.581923)
			(xy 235.034252 -110.610783) (xy 235.079024 -110.646758) (xy 235.098844 -110.667546) (xy 235.106355 -110.674961)
			(xy 235.125643 -110.68348) (xy 235.136182 -110.684056) (xy 235.210858 -110.684056) (xy 235.221408 -110.683531)
			(xy 235.240705 -110.674994) (xy 235.248196 -110.667546) (xy 235.26635 -110.648489) (xy 235.306981 -110.615034)
			(xy 235.351822 -110.587477) (xy 235.400023 -110.566339) (xy 235.45067 -110.552021) (xy 235.502804 -110.544795)
			(xy 235.52912 -110.544356) (xy 235.556368 -110.544916) (xy 235.610308 -110.552674) (xy 235.662595 -110.568029)
			(xy 235.712165 -110.590669) (xy 235.758009 -110.620133) (xy 235.799193 -110.655821) (xy 235.834879 -110.697007)
			(xy 235.86434 -110.742852) (xy 235.886978 -110.792423) (xy 235.902331 -110.844711) (xy 235.910086 -110.898652)
			(xy 235.910086 -110.953148) (xy 235.902331 -111.007089) (xy 235.886978 -111.059377) (xy 235.86434 -111.108948)
			(xy 235.852719 -111.127032) (xy 246.48871 -111.127032) (xy 246.492781 -111.07141) (xy 246.504907 -111.016973)
			(xy 246.52483 -110.964882) (xy 246.552126 -110.916247) (xy 246.586212 -110.872104) (xy 246.626361 -110.833395)
			(xy 246.671719 -110.800944) (xy 246.721319 -110.775443) (xy 246.774103 -110.757436) (xy 246.828946 -110.747306)
			(xy 246.88468 -110.745269) (xy 246.940117 -110.751369) (xy 246.994074 -110.765475) (xy 247.045403 -110.787287)
			(xy 247.093009 -110.816341) (xy 247.135877 -110.852016) (xy 247.173094 -110.893553) (xy 247.203867 -110.940066)
			(xy 247.227539 -110.990563) (xy 247.243607 -111.04397) (xy 247.251727 -111.099146) (xy 247.252236 -111.127032)
			(xy 247.50471 -111.127032) (xy 247.508781 -111.07141) (xy 247.520907 -111.016973) (xy 247.54083 -110.964882)
			(xy 247.568126 -110.916247) (xy 247.602212 -110.872104) (xy 247.642361 -110.833395) (xy 247.687719 -110.800944)
			(xy 247.737319 -110.775443) (xy 247.790103 -110.757436) (xy 247.844946 -110.747306) (xy 247.90068 -110.745269)
			(xy 247.956117 -110.751369) (xy 248.010074 -110.765475) (xy 248.061403 -110.787287) (xy 248.109009 -110.816341)
			(xy 248.151877 -110.852016) (xy 248.189094 -110.893553) (xy 248.219867 -110.940066) (xy 248.243539 -110.990563)
			(xy 248.259607 -111.04397) (xy 248.267727 -111.099146) (xy 248.268236 -111.127032) (xy 248.52071 -111.127032)
			(xy 248.524781 -111.07141) (xy 248.536907 -111.016973) (xy 248.55683 -110.964882) (xy 248.584126 -110.916247)
			(xy 248.618212 -110.872104) (xy 248.658361 -110.833395) (xy 248.703719 -110.800944) (xy 248.753319 -110.775443)
			(xy 248.806103 -110.757436) (xy 248.860946 -110.747306) (xy 248.91668 -110.745269) (xy 248.972117 -110.751369)
			(xy 249.026074 -110.765475) (xy 249.077403 -110.787287) (xy 249.125009 -110.816341) (xy 249.167877 -110.852016)
			(xy 249.205094 -110.893553) (xy 249.235867 -110.940066) (xy 249.259539 -110.990563) (xy 249.275607 -111.04397)
			(xy 249.283727 -111.099146) (xy 249.284236 -111.127032) (xy 249.283727 -111.154918) (xy 249.275607 -111.210094)
			(xy 249.259539 -111.263501) (xy 249.235867 -111.313998) (xy 249.205094 -111.360511) (xy 249.167877 -111.402048)
			(xy 249.125009 -111.437723) (xy 249.077403 -111.466777) (xy 249.026074 -111.488589) (xy 248.972117 -111.502695)
			(xy 248.91668 -111.508795) (xy 248.860946 -111.506758) (xy 248.806103 -111.496628) (xy 248.753319 -111.478621)
			(xy 248.703719 -111.45312) (xy 248.658361 -111.420669) (xy 248.618212 -111.38196) (xy 248.584126 -111.337817)
			(xy 248.55683 -111.289182) (xy 248.536907 -111.237091) (xy 248.524781 -111.182654) (xy 248.52071 -111.127032)
			(xy 248.268236 -111.127032) (xy 248.267727 -111.154918) (xy 248.259607 -111.210094) (xy 248.243539 -111.263501)
			(xy 248.219867 -111.313998) (xy 248.189094 -111.360511) (xy 248.151877 -111.402048) (xy 248.109009 -111.437723)
			(xy 248.061403 -111.466777) (xy 248.010074 -111.488589) (xy 247.956117 -111.502695) (xy 247.90068 -111.508795)
			(xy 247.844946 -111.506758) (xy 247.790103 -111.496628) (xy 247.737319 -111.478621) (xy 247.687719 -111.45312)
			(xy 247.642361 -111.420669) (xy 247.602212 -111.38196) (xy 247.568126 -111.337817) (xy 247.54083 -111.289182)
			(xy 247.520907 -111.237091) (xy 247.508781 -111.182654) (xy 247.50471 -111.127032) (xy 247.252236 -111.127032)
			(xy 247.251727 -111.154918) (xy 247.243607 -111.210094) (xy 247.227539 -111.263501) (xy 247.203867 -111.313998)
			(xy 247.173094 -111.360511) (xy 247.135877 -111.402048) (xy 247.093009 -111.437723) (xy 247.045403 -111.466777)
			(xy 246.994074 -111.488589) (xy 246.940117 -111.502695) (xy 246.88468 -111.508795) (xy 246.828946 -111.506758)
			(xy 246.774103 -111.496628) (xy 246.721319 -111.478621) (xy 246.671719 -111.45312) (xy 246.626361 -111.420669)
			(xy 246.586212 -111.38196) (xy 246.552126 -111.337817) (xy 246.52483 -111.289182) (xy 246.504907 -111.237091)
			(xy 246.492781 -111.182654) (xy 246.48871 -111.127032) (xy 235.852719 -111.127032) (xy 235.834879 -111.154793)
			(xy 235.799193 -111.195979) (xy 235.758009 -111.231667) (xy 235.712165 -111.261131) (xy 235.662595 -111.283771)
			(xy 235.610308 -111.299126) (xy 235.556368 -111.306884) (xy 235.52912 -111.307372) (xy 235.502806 -111.3069)
			(xy 235.450677 -111.299667) (xy 235.400034 -111.28535) (xy 235.351835 -111.264218) (xy 235.306992 -111.236673)
			(xy 235.266352 -111.203234) (xy 235.248196 -111.184182) (xy 235.24068 -111.176774) (xy 235.221396 -111.168254)
			(xy 235.210858 -111.167672) (xy 235.136182 -111.167672) (xy 235.125637 -111.16824) (xy 235.106342 -111.176749)
			(xy 235.098844 -111.184182) (xy 235.079024 -111.20497) (xy 235.034252 -111.240945) (xy 234.984594 -111.269805)
			(xy 234.931172 -111.290898) (xy 234.875193 -111.303747) (xy 234.81792 -111.308062) (xy 234.760647 -111.303747)
			(xy 234.704668 -111.290898) (xy 234.651246 -111.269805) (xy 234.601588 -111.240945) (xy 234.556816 -111.20497)
			(xy 234.536996 -111.184182) (xy 234.52948 -111.176774) (xy 234.510196 -111.168254) (xy 234.499658 -111.167672)
			(xy 234.424982 -111.167672) (xy 234.414437 -111.16824) (xy 234.395142 -111.176749) (xy 234.387644 -111.184182)
			(xy 234.369505 -111.203254) (xy 234.328872 -111.236711) (xy 234.284029 -111.264268) (xy 234.235824 -111.285404)
			(xy 234.185174 -111.299717) (xy 234.133037 -111.306936) (xy 234.10672 -111.307372) (xy 234.079464 -111.306982)
			(xy 234.025505 -111.299227) (xy 233.9732 -111.283871) (xy 233.923613 -111.261228) (xy 233.877753 -111.231757)
			(xy 233.836554 -111.19606) (xy 233.800855 -111.154863) (xy 233.771382 -111.109005) (xy 233.748736 -111.059419)
			(xy 233.733377 -111.007114) (xy 233.725619 -110.953156) (xy 230.939858 -110.953156) (xy 230.939858 -110.957652)
			(xy 230.932102 -111.0116) (xy 230.916748 -111.063896) (xy 230.894108 -111.113475) (xy 230.864644 -111.159327)
			(xy 230.828954 -111.20052) (xy 230.787766 -111.236215) (xy 230.741917 -111.265685) (xy 230.692341 -111.288331)
			(xy 230.640047 -111.303692) (xy 230.5861 -111.311455) (xy 230.558848 -111.311944) (xy 230.531478 -111.311463)
			(xy 230.477299 -111.303651) (xy 230.424796 -111.288166) (xy 230.375048 -111.265327) (xy 230.329082 -111.235605)
			(xy 230.30815 -111.217964) (xy 230.307896 -111.21771) (xy 230.300814 -111.212117) (xy 230.283894 -111.205874)
			(xy 230.274876 -111.205518) (xy 230.20782 -111.205518) (xy 230.198804 -111.20588) (xy 230.181886 -111.212124)
			(xy 230.1748 -111.21771) (xy 230.174546 -111.217964) (xy 230.153613 -111.235605) (xy 230.107645 -111.265329)
			(xy 230.057899 -111.288175) (xy 230.005397 -111.303671) (xy 229.951219 -111.3115) (xy 229.896477 -111.3115)
			(xy 229.842299 -111.303671) (xy 229.789797 -111.288175) (xy 229.740051 -111.265329) (xy 229.694083 -111.235605)
			(xy 229.67315 -111.217964) (xy 229.672896 -111.21771) (xy 229.665814 -111.212117) (xy 229.648894 -111.205874)
			(xy 229.639876 -111.205518) (xy 229.57282 -111.205518) (xy 229.563804 -111.20588) (xy 229.546886 -111.212124)
			(xy 229.5398 -111.21771) (xy 229.5398 -111.217964) (xy 229.539546 -111.217964) (xy 229.518603 -111.235589)
			(xy 229.472634 -111.265305) (xy 229.422889 -111.288144) (xy 229.370391 -111.303638) (xy 229.316217 -111.311469)
			(xy 229.288848 -111.311944) (xy 229.261595 -111.311412) (xy 229.207644 -111.303661) (xy 229.155346 -111.288311)
			(xy 229.105764 -111.265673) (xy 229.059909 -111.236209) (xy 229.018715 -111.200519) (xy 228.983019 -111.159329)
			(xy 228.95355 -111.113478) (xy 228.930906 -111.063899) (xy 228.915549 -111.011603) (xy 228.907791 -110.957652)
			(xy 228.644311 -110.957652) (xy 228.652843 -110.970926) (xy 228.675487 -111.020504) (xy 228.690843 -111.072799)
			(xy 228.698601 -111.126748) (xy 228.698601 -111.181252) (xy 228.690843 -111.235201) (xy 228.675487 -111.287496)
			(xy 228.652843 -111.337074) (xy 228.623374 -111.382924) (xy 228.587679 -111.424113) (xy 228.546486 -111.459803)
			(xy 228.500632 -111.489266) (xy 228.451051 -111.511903) (xy 228.398754 -111.527254) (xy 228.344804 -111.535004)
			(xy 228.317552 -111.535464) (xy 228.290182 -111.534976) (xy 228.236004 -111.527165) (xy 228.183501 -111.511681)
			(xy 228.133753 -111.488844) (xy 228.087786 -111.459124) (xy 228.066854 -111.441484) (xy 228.0666 -111.44123)
			(xy 228.059524 -111.435629) (xy 228.042599 -111.429393) (xy 228.03358 -111.429038) (xy 227.966524 -111.429038)
			(xy 227.957507 -111.429398) (xy 227.94059 -111.435643) (xy 227.933504 -111.44123) (xy 227.933504 -111.441484)
			(xy 227.93325 -111.441484) (xy 227.912308 -111.459111) (xy 227.866338 -111.488825) (xy 227.816593 -111.511663)
			(xy 227.764095 -111.527157) (xy 227.709921 -111.534989) (xy 227.682552 -111.535464) (xy 227.6553 -111.535063)
			(xy 227.601351 -111.5273) (xy 227.549056 -111.511939) (xy 227.499479 -111.489292) (xy 227.45363 -111.459821)
			(xy 227.41244 -111.424126) (xy 227.37675 -111.382932) (xy 227.347285 -111.337079) (xy 227.324644 -111.287499)
			(xy 227.30929 -111.235202) (xy 227.301534 -111.181252) (xy 226.32038 -111.181252) (xy 226.315289 -111.19859)
			(xy 226.292648 -111.248165) (xy 226.263182 -111.294014) (xy 226.227491 -111.335202) (xy 226.186301 -111.370892)
			(xy 226.140451 -111.400356) (xy 226.090875 -111.422995) (xy 226.038581 -111.438348) (xy 225.984634 -111.446102)
			(xy 225.957384 -111.446564) (xy 225.930013 -111.446116) (xy 225.875833 -111.438295) (xy 225.823329 -111.422802)
			(xy 225.773583 -111.399956) (xy 225.727617 -111.370227) (xy 225.706686 -111.352584) (xy 225.706432 -111.35233)
			(xy 225.699346 -111.346742) (xy 225.682429 -111.340498) (xy 225.673412 -111.340138) (xy 225.606356 -111.340138)
			(xy 225.597341 -111.340514) (xy 225.580423 -111.346747) (xy 225.573336 -111.35233) (xy 225.573336 -111.352584)
			(xy 225.573082 -111.352584) (xy 225.552128 -111.370196) (xy 225.506161 -111.399912) (xy 225.456419 -111.422754)
			(xy 225.403924 -111.438251) (xy 225.349752 -111.446086) (xy 225.322384 -111.446564) (xy 225.29513 -111.446165)
			(xy 225.241178 -111.438406) (xy 225.188879 -111.423047) (xy 225.139298 -111.400403) (xy 225.093445 -111.370933)
			(xy 225.052252 -111.335237) (xy 225.016558 -111.294042) (xy 224.98709 -111.248188) (xy 224.964447 -111.198606)
			(xy 224.949091 -111.146306) (xy 224.941334 -111.092354) (xy 224.164154 -111.092354) (xy 224.164154 -111.128852)
			(xy 224.156398 -111.1828) (xy 224.141044 -111.235096) (xy 224.118404 -111.284674) (xy 224.08894 -111.330526)
			(xy 224.05325 -111.371719) (xy 224.012061 -111.407413) (xy 223.966213 -111.436883) (xy 223.916637 -111.459529)
			(xy 223.864343 -111.474889) (xy 223.810395 -111.482651) (xy 223.783144 -111.48314) (xy 223.755774 -111.482663)
			(xy 223.701595 -111.47485) (xy 223.649091 -111.459364) (xy 223.599344 -111.436525) (xy 223.553377 -111.406801)
			(xy 223.532446 -111.38916) (xy 223.532192 -111.388906) (xy 223.525111 -111.383311) (xy 223.50819 -111.377069)
			(xy 223.499172 -111.376714) (xy 223.432116 -111.376714) (xy 223.4231 -111.377075) (xy 223.406182 -111.38332)
			(xy 223.399096 -111.388906) (xy 223.398842 -111.38916) (xy 223.377909 -111.406801) (xy 223.331941 -111.436525)
			(xy 223.282195 -111.459371) (xy 223.229693 -111.474867) (xy 223.175515 -111.482696) (xy 223.120773 -111.482696)
			(xy 223.066595 -111.474867) (xy 223.014093 -111.459371) (xy 222.964347 -111.436525) (xy 222.918379 -111.406801)
			(xy 222.897446 -111.38916) (xy 222.897192 -111.388906) (xy 222.890111 -111.383311) (xy 222.87319 -111.377069)
			(xy 222.864172 -111.376714) (xy 222.797116 -111.376714) (xy 222.7881 -111.377075) (xy 222.771182 -111.38332)
			(xy 222.764096 -111.388906) (xy 222.764096 -111.38916) (xy 222.763842 -111.38916) (xy 222.742909 -111.406801)
			(xy 222.696941 -111.436525) (xy 222.647195 -111.459371) (xy 222.594693 -111.474867) (xy 222.540515 -111.482696)
			(xy 222.485773 -111.482696) (xy 222.431595 -111.474867) (xy 222.379093 -111.459371) (xy 222.329347 -111.436525)
			(xy 222.283379 -111.406801) (xy 222.262446 -111.38916) (xy 222.262192 -111.388906) (xy 222.255111 -111.383311)
			(xy 222.23819 -111.377069) (xy 222.229172 -111.376714) (xy 222.162116 -111.376714) (xy 222.1531 -111.377075)
			(xy 222.136182 -111.38332) (xy 222.129096 -111.388906) (xy 222.129096 -111.38916) (xy 222.128842 -111.38916)
			(xy 222.1079 -111.406787) (xy 222.06193 -111.436502) (xy 222.012186 -111.459341) (xy 221.959687 -111.474835)
			(xy 221.905513 -111.482665) (xy 221.878144 -111.48314) (xy 221.850891 -111.482616) (xy 221.79694 -111.474865)
			(xy 221.744641 -111.459514) (xy 221.69506 -111.436875) (xy 221.649205 -111.407411) (xy 221.608011 -111.37172)
			(xy 221.572315 -111.33053) (xy 221.542846 -111.284679) (xy 221.520202 -111.2351) (xy 221.504845 -111.182803)
			(xy 221.497087 -111.128853) (xy 191.424695 -111.128853) (xy 191.449438 -111.179855) (xy 191.466486 -111.234749)
			(xy 191.475106 -111.291579) (xy 191.475103 -111.349059) (xy 191.466477 -111.405888) (xy 191.449424 -111.46078)
			(xy 191.42433 -111.512493) (xy 191.391762 -111.559857) (xy 191.37249 -111.581184) (xy 191.365886 -111.588042)
			(xy 191.358774 -111.606076) (xy 191.358774 -111.694976) (xy 191.365886 -111.71301) (xy 191.37249 -111.719868)
			(xy 191.391778 -111.74118) (xy 191.424341 -111.788547) (xy 191.449429 -111.840262) (xy 191.466476 -111.895156)
			(xy 191.475095 -111.951986) (xy 191.475614 -111.980726) (xy 191.475146 -112.007978) (xy 191.467387 -112.061926)
			(xy 191.452028 -112.11422) (xy 191.429385 -112.163797) (xy 191.399916 -112.209647) (xy 191.364223 -112.250837)
			(xy 191.323031 -112.286528) (xy 191.27718 -112.315994) (xy 191.227602 -112.338635) (xy 191.175306 -112.353991)
			(xy 191.121358 -112.361748) (xy 191.094106 -112.362234) (xy 191.067793 -112.361752) (xy 191.015665 -112.354518)
			(xy 190.965023 -112.340201) (xy 190.916824 -112.319072) (xy 190.87198 -112.291529) (xy 190.83134 -112.258094)
			(xy 190.813182 -112.239044) (xy 190.805663 -112.231639) (xy 190.786381 -112.223115) (xy 190.775844 -112.222534)
			(xy 190.701168 -112.222534) (xy 190.69062 -112.223076) (xy 190.671323 -112.231601) (xy 190.66383 -112.239044)
			(xy 190.645661 -112.258086) (xy 190.605034 -112.291543) (xy 190.560196 -112.319103) (xy 190.511998 -112.340243)
			(xy 190.461353 -112.354564) (xy 190.409221 -112.361793) (xy 190.382906 -112.362234) (xy 190.355656 -112.361717)
			(xy 190.301711 -112.353962) (xy 190.249418 -112.338609) (xy 190.199843 -112.31597) (xy 190.153994 -112.286507)
			(xy 190.112804 -112.250819) (xy 190.077112 -112.209632) (xy 190.047645 -112.163785) (xy 190.025003 -112.114212)
			(xy 190.009645 -112.06192) (xy 190.001886 -112.007976) (xy 190.001398 -111.980726) (xy 188.583491 -111.980726)
			(xy 188.571422 -111.997481) (xy 188.529503 -112.039825) (xy 188.505846 -112.057942) (xy 188.499066 -112.063299)
			(xy 188.489336 -112.077569) (xy 188.484917 -112.094265) (xy 188.485272 -112.1029) (xy 188.491876 -112.188752)
			(xy 188.492789 -112.197267) (xy 188.499564 -112.212984) (xy 188.511152 -112.225579) (xy 188.518546 -112.2299)
			(xy 188.5188 -112.2299) (xy 188.541614 -112.242281) (xy 188.583906 -112.272376) (xy 188.621726 -112.30793)
			(xy 188.654374 -112.348285) (xy 188.681247 -112.392695) (xy 188.682024 -112.394492) (xy 197.480172 -112.394492)
			(xy 197.484243 -112.33887) (xy 197.496369 -112.284433) (xy 197.516292 -112.232342) (xy 197.543588 -112.183707)
			(xy 197.577674 -112.139564) (xy 197.617823 -112.100855) (xy 197.663181 -112.068404) (xy 197.712781 -112.042903)
			(xy 197.765565 -112.024896) (xy 197.820408 -112.014766) (xy 197.876142 -112.012729) (xy 197.931579 -112.018829)
			(xy 197.985536 -112.032935) (xy 198.036865 -112.054747) (xy 198.084471 -112.083801) (xy 198.127339 -112.119476)
			(xy 198.143438 -112.137444) (xy 203.970126 -112.137444) (xy 203.974197 -112.081822) (xy 203.986323 -112.027385)
			(xy 204.006246 -111.975294) (xy 204.033542 -111.926659) (xy 204.067628 -111.882516) (xy 204.107777 -111.843807)
			(xy 204.153135 -111.811356) (xy 204.202735 -111.785855) (xy 204.255519 -111.767848) (xy 204.310362 -111.757718)
			(xy 204.366096 -111.755681) (xy 204.421533 -111.761781) (xy 204.47549 -111.775887) (xy 204.526819 -111.797699)
			(xy 204.574425 -111.826753) (xy 204.617293 -111.862428) (xy 204.65451 -111.903965) (xy 204.685283 -111.950478)
			(xy 204.708955 -112.000975) (xy 204.725023 -112.054382) (xy 204.733143 -112.109558) (xy 204.733652 -112.137444)
			(xy 204.733143 -112.16533) (xy 204.725023 -112.220506) (xy 204.708955 -112.273913) (xy 204.685283 -112.32441)
			(xy 204.65451 -112.370923) (xy 204.617293 -112.41246) (xy 204.574425 -112.448135) (xy 204.526819 -112.477189)
			(xy 204.47549 -112.499001) (xy 204.421533 -112.513107) (xy 204.366096 -112.519207) (xy 204.310362 -112.51717)
			(xy 204.255519 -112.50704) (xy 204.202735 -112.489033) (xy 204.153135 -112.463532) (xy 204.107777 -112.431081)
			(xy 204.067628 -112.392372) (xy 204.033542 -112.348229) (xy 204.006246 -112.299594) (xy 203.986323 -112.247503)
			(xy 203.974197 -112.193066) (xy 203.970126 -112.137444) (xy 198.143438 -112.137444) (xy 198.164556 -112.161013)
			(xy 198.195329 -112.207526) (xy 198.219001 -112.258023) (xy 198.235069 -112.31143) (xy 198.243189 -112.366606)
			(xy 198.243698 -112.394492) (xy 198.243189 -112.422378) (xy 198.235069 -112.477554) (xy 198.219001 -112.530961)
			(xy 198.205082 -112.560653) (xy 205.549185 -112.560653) (xy 205.549185 -112.506147) (xy 205.556943 -112.452196)
			(xy 205.5723 -112.399899) (xy 205.594944 -112.35032) (xy 205.624414 -112.304468) (xy 205.66011 -112.263277)
			(xy 205.701305 -112.227587) (xy 205.74716 -112.198122) (xy 205.796742 -112.175484) (xy 205.849041 -112.160133)
			(xy 205.902993 -112.152382) (xy 205.930246 -112.151922) (xy 205.9305 -112.151922) (xy 205.95846 -112.152404)
			(xy 206.013778 -112.160584) (xy 206.067304 -112.17677) (xy 206.092806 -112.188244) (xy 206.104265 -112.193019)
			(xy 206.12904 -112.191947) (xy 206.14005 -112.186212) (xy 206.21244 -112.144302) (xy 206.222682 -112.137528)
			(xy 206.235819 -112.116829) (xy 206.237586 -112.104678) (xy 206.237586 -112.10417) (xy 206.240354 -112.075838)
			(xy 206.253235 -112.020389) (xy 206.274214 -111.967471) (xy 206.302826 -111.918258) (xy 206.338433 -111.873844)
			(xy 206.380246 -111.835216) (xy 206.427336 -111.803231) (xy 206.478657 -111.7786) (xy 206.533068 -111.761871)
			(xy 206.589361 -111.753414) (xy 206.617824 -111.752888) (xy 206.647802 -111.753455) (xy 206.707019 -111.76285)
			(xy 206.764038 -111.78139) (xy 206.817456 -111.808618) (xy 206.865959 -111.843864) (xy 206.887572 -111.864648)
			(xy 206.887826 -111.864902) (xy 206.895317 -111.871548) (xy 206.913886 -111.878995) (xy 206.923894 -111.87938)
			(xy 207.007206 -111.878364) (xy 207.025748 -111.87049) (xy 207.03286 -111.86287) (xy 207.050958 -111.844577)
			(xy 207.09117 -111.812468) (xy 207.13533 -111.786052) (xy 207.182639 -111.765808) (xy 207.232238 -111.752102)
			(xy 207.283229 -111.745184) (xy 207.308958 -111.74476) (xy 207.336208 -111.745294) (xy 207.390155 -111.753045)
			(xy 207.44245 -111.768394) (xy 207.492028 -111.791029) (xy 207.537879 -111.82049) (xy 207.579072 -111.856176)
			(xy 207.614766 -111.897361) (xy 207.644235 -111.943207) (xy 207.66688 -111.992781) (xy 207.68224 -112.045073)
			(xy 207.69 -112.099018) (xy 207.690466 -112.126268) (xy 207.690035 -112.152714) (xy 207.682721 -112.205097)
			(xy 207.668242 -112.255968) (xy 207.646877 -112.304352) (xy 207.619034 -112.349322) (xy 207.585248 -112.390016)
			(xy 207.546165 -112.425653) (xy 207.524604 -112.440974) (xy 207.51593 -112.447449) (xy 207.504608 -112.46587)
			(xy 207.50276 -112.476534) (xy 207.49895 -112.508792) (xy 207.498044 -112.519483) (xy 207.504222 -112.540009)
			(xy 207.510888 -112.548416) (xy 207.52435 -112.564672) (xy 207.531976 -112.573458) (xy 207.552863 -112.58365)
			(xy 207.564482 -112.58423) (xy 207.644238 -112.58423) (xy 207.655875 -112.583723) (xy 207.676785 -112.573514)
			(xy 207.68437 -112.564672) (xy 207.702571 -112.542197) (xy 207.744589 -112.502463) (xy 207.792123 -112.469523)
			(xy 207.844082 -112.444134) (xy 207.899277 -112.426875) (xy 207.956445 -112.418143) (xy 207.98536 -112.417606)
			(xy 208.012605 -112.418051) (xy 208.066539 -112.425816) (xy 208.118819 -112.441179) (xy 208.16838 -112.463828)
			(xy 208.214212 -112.4933) (xy 208.255382 -112.528997) (xy 208.291051 -112.570191) (xy 208.306162 -112.592866)
			(xy 208.311039 -112.599868) (xy 208.324434 -112.610417) (xy 208.340561 -112.615954) (xy 208.349088 -112.616234)
			(xy 208.434432 -112.616234) (xy 208.442951 -112.615906) (xy 208.45906 -112.610359) (xy 208.472471 -112.599851)
			(xy 208.477358 -112.592866) (xy 208.492507 -112.570218) (xy 208.528167 -112.529022) (xy 208.56933 -112.493323)
			(xy 208.615156 -112.463848) (xy 208.664711 -112.441199) (xy 208.716987 -112.425836) (xy 208.770917 -112.418072)
			(xy 208.79816 -112.417606) (xy 208.825416 -112.418038) (xy 208.879373 -112.425791) (xy 208.931678 -112.441144)
			(xy 208.981265 -112.463785) (xy 209.027125 -112.493253) (xy 209.068324 -112.528948) (xy 209.080132 -112.542574)
			(xy 230.040434 -112.542574) (xy 230.040877 -112.515203) (xy 230.048699 -112.461022) (xy 230.064193 -112.408519)
			(xy 230.08704 -112.358772) (xy 230.11677 -112.312807) (xy 230.134414 -112.291876) (xy 230.134668 -112.291622)
			(xy 230.140259 -112.284539) (xy 230.146501 -112.267619) (xy 230.14686 -112.258602) (xy 230.14686 -112.191546)
			(xy 230.14649 -112.18253) (xy 230.140252 -112.165613) (xy 230.134668 -112.158526) (xy 230.134414 -112.158526)
			(xy 230.134414 -112.158272) (xy 230.116797 -112.137322) (xy 230.087082 -112.091354) (xy 230.064241 -112.041611)
			(xy 230.048745 -111.989115) (xy 230.040911 -111.934942) (xy 230.040434 -111.907574) (xy 230.04092 -111.880323)
			(xy 230.048676 -111.826375) (xy 230.064031 -111.77408) (xy 230.086673 -111.724503) (xy 230.116139 -111.678653)
			(xy 230.15183 -111.637462) (xy 230.193021 -111.601771) (xy 230.238871 -111.572305) (xy 230.288448 -111.549663)
			(xy 230.340743 -111.534308) (xy 230.394691 -111.526552) (xy 230.449193 -111.526552) (xy 230.503141 -111.534308)
			(xy 230.555436 -111.549663) (xy 230.605013 -111.572305) (xy 230.650863 -111.601771) (xy 230.692054 -111.637462)
			(xy 230.727745 -111.678653) (xy 230.757211 -111.724503) (xy 230.779853 -111.77408) (xy 230.795208 -111.826375)
			(xy 230.802964 -111.880323) (xy 230.80345 -111.907574) (xy 230.802981 -111.934944) (xy 230.795166 -111.989124)
			(xy 230.779678 -112.041627) (xy 230.756837 -112.091374) (xy 230.727112 -112.137341) (xy 230.70947 -112.158272)
			(xy 230.709216 -112.158526) (xy 230.703656 -112.165631) (xy 230.697393 -112.182534) (xy 230.697024 -112.191546)
			(xy 230.697024 -112.258602) (xy 230.697375 -112.26762) (xy 230.703626 -112.284537) (xy 230.709216 -112.291622)
			(xy 230.70947 -112.291622) (xy 230.70947 -112.291876) (xy 230.727107 -112.31281) (xy 230.75682 -112.358782)
			(xy 230.779657 -112.408529) (xy 230.795148 -112.461029) (xy 230.802976 -112.515205) (xy 230.80345 -112.542574)
			(xy 230.802964 -112.569825) (xy 230.795208 -112.623773) (xy 230.779853 -112.676068) (xy 230.759734 -112.72012)
			(xy 232.673906 -112.72012) (xy 232.674382 -112.69275) (xy 232.682197 -112.638571) (xy 232.697684 -112.586068)
			(xy 232.720524 -112.536321) (xy 232.750246 -112.490354) (xy 232.767886 -112.469422) (xy 232.76814 -112.469168)
			(xy 232.773709 -112.46207) (xy 232.779965 -112.445162) (xy 232.780332 -112.436148) (xy 232.780332 -112.369092)
			(xy 232.779972 -112.360076) (xy 232.773726 -112.343159) (xy 232.76814 -112.336072) (xy 232.767886 -112.336072)
			(xy 232.767886 -112.335818) (xy 232.75024 -112.314892) (xy 232.720529 -112.268917) (xy 232.697695 -112.219168)
			(xy 232.682206 -112.166666) (xy 232.674379 -112.11249) (xy 232.673906 -112.08512) (xy 232.674392 -112.057869)
			(xy 232.682148 -112.003921) (xy 232.697503 -111.951626) (xy 232.720145 -111.902049) (xy 232.749611 -111.856199)
			(xy 232.785302 -111.815008) (xy 232.826493 -111.779317) (xy 232.872343 -111.749851) (xy 232.92192 -111.727209)
			(xy 232.974215 -111.711854) (xy 233.028163 -111.704098) (xy 233.082665 -111.704098) (xy 233.136613 -111.711854)
			(xy 233.188908 -111.727209) (xy 233.238485 -111.749851) (xy 233.284335 -111.779317) (xy 233.325526 -111.815008)
			(xy 233.361217 -111.856199) (xy 233.390683 -111.902049) (xy 233.413325 -111.951626) (xy 233.427314 -111.999268)
			(xy 238.85347 -111.999268) (xy 238.857541 -111.943646) (xy 238.869667 -111.889209) (xy 238.88959 -111.837118)
			(xy 238.916886 -111.788483) (xy 238.950972 -111.74434) (xy 238.991121 -111.705631) (xy 239.036479 -111.67318)
			(xy 239.086079 -111.647679) (xy 239.138863 -111.629672) (xy 239.193706 -111.619542) (xy 239.24944 -111.617505)
			(xy 239.304877 -111.623605) (xy 239.358834 -111.637711) (xy 239.410163 -111.659523) (xy 239.457769 -111.688577)
			(xy 239.500637 -111.724252) (xy 239.525367 -111.751853) (xy 266.290991 -111.751853) (xy 266.290991 -111.694547)
			(xy 266.299147 -111.637824) (xy 266.315292 -111.58284) (xy 266.339098 -111.530713) (xy 266.370081 -111.482505)
			(xy 266.407609 -111.439197) (xy 266.450919 -111.40167) (xy 266.499129 -111.37069) (xy 266.551257 -111.346886)
			(xy 266.606242 -111.330743) (xy 266.662965 -111.32259) (xy 266.691618 -111.322104) (xy 266.718999 -111.322555)
			(xy 266.77325 -111.330025) (xy 266.825979 -111.34481) (xy 266.876205 -111.366635) (xy 266.922993 -111.395093)
			(xy 266.965472 -111.429654) (xy 267.002851 -111.469676) (xy 267.019024 -111.491776) (xy 267.024584 -111.499039)
			(xy 267.039695 -111.509322) (xy 267.048488 -111.511842) (xy 267.07846 -111.519208) (xy 267.087413 -111.520938)
			(xy 267.105499 -111.518735) (xy 267.113766 -111.51489) (xy 267.138373 -111.502514) (xy 267.189896 -111.483042)
			(xy 267.243383 -111.469889) (xy 267.298062 -111.463247) (xy 267.325602 -111.46282) (xy 267.353142 -111.463266)
			(xy 267.407822 -111.469897) (xy 267.461311 -111.483039) (xy 267.512838 -111.502502) (xy 267.537438 -111.51489)
			(xy 267.54569 -111.518786) (xy 267.563793 -111.520989) (xy 267.572744 -111.519208) (xy 267.602716 -111.511842)
			(xy 267.6115 -111.509306) (xy 267.6266 -111.499019) (xy 267.63218 -111.491776) (xy 267.648289 -111.469626)
			(xy 267.685672 -111.429597) (xy 267.728159 -111.395033) (xy 267.774958 -111.366578) (xy 267.825197 -111.344763)
			(xy 267.877939 -111.329993) (xy 267.932201 -111.322545) (xy 267.959586 -111.322104) (xy 267.988235 -111.32265)
			(xy 268.044949 -111.330802) (xy 268.099925 -111.346943) (xy 268.152045 -111.370744) (xy 268.200247 -111.40172)
			(xy 268.24355 -111.43924) (xy 268.281072 -111.482542) (xy 268.31205 -111.530743) (xy 268.335852 -111.582862)
			(xy 268.351995 -111.637838) (xy 268.360149 -111.694552) (xy 268.360149 -111.751848) (xy 268.351995 -111.808562)
			(xy 268.335852 -111.863538) (xy 268.31205 -111.915657) (xy 268.281072 -111.963858) (xy 268.24355 -112.00716)
			(xy 268.200247 -112.04468) (xy 268.152045 -112.075656) (xy 268.099925 -112.099457) (xy 268.044949 -112.115598)
			(xy 267.988235 -112.12375) (xy 267.959586 -112.124236) (xy 267.944668 -112.124063) (xy 267.914919 -112.121777)
			(xy 267.90015 -112.119664) (xy 267.888974 -112.117886) (xy 267.867892 -112.123982) (xy 267.80109 -112.18164)
			(xy 267.793149 -112.189255) (xy 267.78405 -112.209258) (xy 267.783564 -112.220248) (xy 267.783564 -112.484916)
			(xy 267.784072 -112.495904) (xy 267.793147 -112.515916) (xy 267.80109 -112.523524) (xy 267.867892 -112.581182)
			(xy 267.888974 -112.587278) (xy 267.90015 -112.5855) (xy 267.91492 -112.583395) (xy 267.944668 -112.581105)
			(xy 267.959586 -112.580928) (xy 267.988236 -112.581426) (xy 268.044954 -112.589579) (xy 268.099933 -112.60572)
			(xy 268.152056 -112.629523) (xy 268.200261 -112.6605) (xy 268.243567 -112.698023) (xy 268.281091 -112.741328)
			(xy 268.312071 -112.789531) (xy 268.335875 -112.841653) (xy 268.352018 -112.896633) (xy 268.360173 -112.95335)
			(xy 268.360173 -113.01065) (xy 268.352018 -113.067367) (xy 268.335875 -113.122347) (xy 268.312071 -113.174469)
			(xy 268.281091 -113.222672) (xy 268.243567 -113.265977) (xy 268.200261 -113.3035) (xy 268.152056 -113.334477)
			(xy 268.099933 -113.35828) (xy 268.044954 -113.374421) (xy 267.988236 -113.382574) (xy 267.959586 -113.38306)
			(xy 267.932206 -113.382579) (xy 267.877958 -113.375111) (xy 267.82523 -113.360329) (xy 267.775005 -113.338509)
			(xy 267.728217 -113.310056) (xy 267.685737 -113.2755) (xy 267.648355 -113.235484) (xy 267.63218 -113.213388)
			(xy 267.626626 -113.20612) (xy 267.611511 -113.195841) (xy 267.602716 -113.193322) (xy 267.572744 -113.185956)
			(xy 267.563791 -113.184231) (xy 267.545705 -113.186432) (xy 267.537438 -113.190274) (xy 267.512833 -113.202653)
			(xy 267.461308 -113.222124) (xy 267.407821 -113.235275) (xy 267.353142 -113.241916) (xy 267.325602 -113.242344)
			(xy 267.298062 -113.2419) (xy 267.243382 -113.235269) (xy 267.189893 -113.222127) (xy 267.138366 -113.202663)
			(xy 267.113766 -113.190274) (xy 267.105514 -113.186379) (xy 267.087411 -113.184176) (xy 267.07846 -113.185956)
			(xy 267.048488 -113.193322) (xy 267.039709 -113.195871) (xy 267.024607 -113.20615) (xy 267.019024 -113.213388)
			(xy 267.002902 -113.235528) (xy 266.965522 -113.275559) (xy 266.923038 -113.310125) (xy 266.876241 -113.338581)
			(xy 266.826004 -113.360399) (xy 266.773264 -113.37517) (xy 266.719003 -113.382619) (xy 266.691618 -113.38306)
			(xy 266.662967 -113.382586) (xy 266.606247 -113.374434) (xy 266.551265 -113.358292) (xy 266.49914 -113.334489)
			(xy 266.450934 -113.303511) (xy 266.407626 -113.265986) (xy 266.3701 -113.222681) (xy 266.339119 -113.174476)
			(xy 266.315314 -113.122352) (xy 266.29917 -113.06737) (xy 266.291015 -113.010651) (xy 266.291015 -112.953349)
			(xy 266.29917 -112.89663) (xy 266.315314 -112.841648) (xy 266.339119 -112.789524) (xy 266.3701 -112.741319)
			(xy 266.407626 -112.698014) (xy 266.450934 -112.660489) (xy 266.49914 -112.629511) (xy 266.551265 -112.605708)
			(xy 266.606247 -112.589566) (xy 266.662967 -112.581414) (xy 266.691618 -112.580928) (xy 266.706536 -112.581101)
			(xy 266.736285 -112.583387) (xy 266.751054 -112.5855) (xy 266.76223 -112.587278) (xy 266.783312 -112.581182)
			(xy 266.850114 -112.523524) (xy 266.858072 -112.515924) (xy 266.867161 -112.49591) (xy 266.86764 -112.484916)
			(xy 266.86764 -112.220248) (xy 266.867151 -112.209257) (xy 266.858063 -112.189246) (xy 266.850114 -112.18164)
			(xy 266.783312 -112.123982) (xy 266.76223 -112.117886) (xy 266.751054 -112.119664) (xy 266.736284 -112.121769)
			(xy 266.706536 -112.124059) (xy 266.691618 -112.124236) (xy 266.662965 -112.12381) (xy 266.606242 -112.115657)
			(xy 266.551257 -112.099514) (xy 266.499129 -112.07571) (xy 266.450919 -112.04473) (xy 266.407609 -112.007203)
			(xy 266.370081 -111.963895) (xy 266.339098 -111.915687) (xy 266.315292 -111.86356) (xy 266.299147 -111.808576)
			(xy 266.290991 -111.751853) (xy 239.525367 -111.751853) (xy 239.537854 -111.765789) (xy 239.568627 -111.812302)
			(xy 239.592299 -111.862799) (xy 239.608367 -111.916206) (xy 239.616487 -111.971382) (xy 239.616996 -111.999268)
			(xy 239.616487 -112.027154) (xy 239.608367 -112.08233) (xy 239.592299 -112.135737) (xy 239.568627 -112.186234)
			(xy 239.537854 -112.232747) (xy 239.500637 -112.274284) (xy 239.457769 -112.309959) (xy 239.410163 -112.339013)
			(xy 239.358834 -112.360825) (xy 239.304877 -112.374931) (xy 239.24944 -112.381031) (xy 239.193706 -112.378994)
			(xy 239.138863 -112.368864) (xy 239.086079 -112.350857) (xy 239.036479 -112.325356) (xy 238.991121 -112.292905)
			(xy 238.950972 -112.254196) (xy 238.916886 -112.210053) (xy 238.88959 -112.161418) (xy 238.869667 -112.109327)
			(xy 238.857541 -112.05489) (xy 238.85347 -111.999268) (xy 233.427314 -111.999268) (xy 233.42868 -112.003921)
			(xy 233.436436 -112.057869) (xy 233.436922 -112.08512) (xy 233.436487 -112.112492) (xy 233.428664 -112.166673)
			(xy 233.413169 -112.219177) (xy 233.39032 -112.268923) (xy 233.360587 -112.314888) (xy 233.342942 -112.335818)
			(xy 233.342688 -112.336072) (xy 233.337106 -112.343161) (xy 233.330857 -112.360076) (xy 233.330496 -112.369092)
			(xy 233.330496 -112.436148) (xy 233.330879 -112.445162) (xy 233.337109 -112.462079) (xy 233.342688 -112.469168)
			(xy 233.342942 -112.469168) (xy 233.342942 -112.469422) (xy 233.360565 -112.490367) (xy 233.367713 -112.501426)
			(xy 244.173246 -112.501426) (xy 244.177317 -112.445804) (xy 244.189443 -112.391367) (xy 244.209366 -112.339276)
			(xy 244.236662 -112.290641) (xy 244.270748 -112.246498) (xy 244.310897 -112.207789) (xy 244.356255 -112.175338)
			(xy 244.405855 -112.149837) (xy 244.458639 -112.13183) (xy 244.513482 -112.1217) (xy 244.569216 -112.119663)
			(xy 244.624653 -112.125763) (xy 244.67861 -112.139869) (xy 244.729939 -112.161681) (xy 244.777545 -112.190735)
			(xy 244.820413 -112.22641) (xy 244.85763 -112.267947) (xy 244.888403 -112.31446) (xy 244.912075 -112.364957)
			(xy 244.928143 -112.418364) (xy 244.936263 -112.47354) (xy 244.936772 -112.501426) (xy 244.936263 -112.529312)
			(xy 244.928143 -112.584488) (xy 244.912075 -112.637895) (xy 244.888403 -112.688392) (xy 244.85763 -112.734905)
			(xy 244.820413 -112.776442) (xy 244.777545 -112.812117) (xy 244.729939 -112.841171) (xy 244.67861 -112.862983)
			(xy 244.624653 -112.877089) (xy 244.569216 -112.883189) (xy 244.513482 -112.881152) (xy 244.458639 -112.871022)
			(xy 244.405855 -112.853015) (xy 244.356255 -112.827514) (xy 244.310897 -112.795063) (xy 244.270748 -112.756354)
			(xy 244.236662 -112.712211) (xy 244.209366 -112.663576) (xy 244.189443 -112.611485) (xy 244.177317 -112.557048)
			(xy 244.173246 -112.501426) (xy 233.367713 -112.501426) (xy 233.390278 -112.536337) (xy 233.413116 -112.586081)
			(xy 233.428611 -112.638579) (xy 233.436445 -112.692752) (xy 233.436922 -112.72012) (xy 233.436436 -112.747371)
			(xy 233.42868 -112.801319) (xy 233.413325 -112.853614) (xy 233.390683 -112.903191) (xy 233.361217 -112.949041)
			(xy 233.325526 -112.990232) (xy 233.284335 -113.025923) (xy 233.238485 -113.055389) (xy 233.188908 -113.078031)
			(xy 233.136613 -113.093386) (xy 233.082665 -113.101142) (xy 233.028163 -113.101142) (xy 232.974215 -113.093386)
			(xy 232.92192 -113.078031) (xy 232.872343 -113.055389) (xy 232.826493 -113.025923) (xy 232.785302 -112.990232)
			(xy 232.749611 -112.949041) (xy 232.720145 -112.903191) (xy 232.697503 -112.853614) (xy 232.682148 -112.801319)
			(xy 232.674392 -112.747371) (xy 232.673906 -112.72012) (xy 230.759734 -112.72012) (xy 230.757211 -112.725645)
			(xy 230.727745 -112.771495) (xy 230.692054 -112.812686) (xy 230.650863 -112.848377) (xy 230.605013 -112.877843)
			(xy 230.555436 -112.900485) (xy 230.503141 -112.91584) (xy 230.449193 -112.923596) (xy 230.394691 -112.923596)
			(xy 230.340743 -112.91584) (xy 230.288448 -112.900485) (xy 230.238871 -112.877843) (xy 230.193021 -112.848377)
			(xy 230.15183 -112.812686) (xy 230.116139 -112.771495) (xy 230.086673 -112.725645) (xy 230.064031 -112.676068)
			(xy 230.048676 -112.623773) (xy 230.04092 -112.569825) (xy 230.040434 -112.542574) (xy 209.080132 -112.542574)
			(xy 209.104023 -112.570143) (xy 209.133496 -112.616) (xy 209.156142 -112.665585) (xy 209.171501 -112.717888)
			(xy 209.179259 -112.771844) (xy 209.179259 -112.826356) (xy 209.171501 -112.880312) (xy 209.156142 -112.932615)
			(xy 209.133496 -112.9822) (xy 209.104023 -113.028057) (xy 209.068324 -113.069252) (xy 209.027125 -113.104947)
			(xy 208.981265 -113.134415) (xy 208.931678 -113.157056) (xy 208.879373 -113.172409) (xy 208.825416 -113.180162)
			(xy 208.79816 -113.180622) (xy 208.770916 -113.180149) (xy 208.716983 -113.172387) (xy 208.664705 -113.157028)
			(xy 208.615145 -113.134384) (xy 208.569313 -113.104916) (xy 208.528142 -113.069224) (xy 208.49247 -113.028035)
			(xy 208.477358 -113.005362) (xy 208.472521 -112.998329) (xy 208.459109 -112.987783) (xy 208.442965 -112.982262)
			(xy 208.434432 -112.981994) (xy 208.349088 -112.981994) (xy 208.340569 -112.982324) (xy 208.324459 -112.987868)
			(xy 208.311048 -112.998376) (xy 208.306162 -113.005362) (xy 208.291074 -113.028054) (xy 208.255403 -113.069247)
			(xy 208.21423 -113.104943) (xy 208.168393 -113.134412) (xy 208.118828 -113.157054) (xy 208.066544 -113.172408)
			(xy 208.012606 -113.180161) (xy 207.98536 -113.180622) (xy 207.956443 -113.18009) (xy 207.899271 -113.171368)
			(xy 207.844072 -113.154115) (xy 207.792109 -113.128726) (xy 207.744575 -113.095783) (xy 207.702559 -113.056042)
			(xy 207.68437 -113.033556) (xy 207.676774 -113.024738) (xy 207.655864 -113.014562) (xy 207.644238 -113.013998)
			(xy 207.564482 -113.013998) (xy 207.552851 -113.014542) (xy 207.531941 -113.024727) (xy 207.52435 -113.033556)
			(xy 207.50612 -113.056006) (xy 207.464109 -113.095746) (xy 207.416583 -113.12869) (xy 207.364629 -113.154084)
			(xy 207.309438 -113.171347) (xy 207.252274 -113.180083) (xy 207.22336 -113.180622) (xy 207.196108 -113.180159)
			(xy 207.142161 -113.172398) (xy 207.089866 -113.157038) (xy 207.04029 -113.134394) (xy 206.99444 -113.104924)
			(xy 206.953251 -113.069231) (xy 206.91756 -113.028039) (xy 206.888094 -112.982187) (xy 206.865453 -112.932609)
			(xy 206.850097 -112.880314) (xy 206.842339 -112.826366) (xy 206.841852 -112.799114) (xy 206.842337 -112.77267)
			(xy 206.849641 -112.720289) (xy 206.864109 -112.669418) (xy 206.885465 -112.621034) (xy 206.9133 -112.576063)
			(xy 206.94708 -112.535369) (xy 206.986156 -112.49973) (xy 207.007714 -112.484408) (xy 207.016398 -112.477945)
			(xy 207.027714 -112.459515) (xy 207.029558 -112.448848) (xy 207.033622 -112.41659) (xy 207.034441 -112.405878)
			(xy 207.028135 -112.38536) (xy 207.02143 -112.376966) (xy 207.021176 -112.376712) (xy 207.013541 -112.368696)
			(xy 206.993377 -112.359614) (xy 206.982314 -112.359186) (xy 206.949802 -112.359694) (xy 206.938787 -112.360335)
			(xy 206.918897 -112.36984) (xy 206.911448 -112.377982) (xy 206.893221 -112.399159) (xy 206.851659 -112.436499)
			(xy 206.805096 -112.467377) (xy 206.754527 -112.491135) (xy 206.701033 -112.507262) (xy 206.64576 -112.515414)
			(xy 206.617824 -112.515904) (xy 206.61757 -112.515904) (xy 206.58961 -112.515431) (xy 206.534291 -112.507246)
			(xy 206.480765 -112.491058) (xy 206.455264 -112.479582) (xy 206.44381 -112.474794) (xy 206.419032 -112.475877)
			(xy 206.40802 -112.481614) (xy 206.33563 -112.523524) (xy 206.325391 -112.530303) (xy 206.312249 -112.550997)
			(xy 206.310484 -112.563148) (xy 206.310484 -112.563656) (xy 206.307683 -112.591985) (xy 206.294811 -112.647435)
			(xy 206.273839 -112.700356) (xy 206.245234 -112.749571) (xy 206.20963 -112.793987) (xy 206.16782 -112.832616)
			(xy 206.120732 -112.864602) (xy 206.069412 -112.889232) (xy 206.015001 -112.90596) (xy 205.958708 -112.914414)
			(xy 205.930246 -112.914938) (xy 205.902993 -112.914418) (xy 205.849041 -112.906667) (xy 205.796742 -112.891316)
			(xy 205.74716 -112.868678) (xy 205.701305 -112.839213) (xy 205.66011 -112.803523) (xy 205.624414 -112.762332)
			(xy 205.594944 -112.71648) (xy 205.5723 -112.666901) (xy 205.556943 -112.614604) (xy 205.549185 -112.560653)
			(xy 198.205082 -112.560653) (xy 198.195329 -112.581458) (xy 198.164556 -112.627971) (xy 198.127339 -112.669508)
			(xy 198.084471 -112.705183) (xy 198.036865 -112.734237) (xy 197.985536 -112.756049) (xy 197.931579 -112.770155)
			(xy 197.876142 -112.776255) (xy 197.820408 -112.774218) (xy 197.765565 -112.764088) (xy 197.712781 -112.746081)
			(xy 197.663181 -112.72058) (xy 197.617823 -112.688129) (xy 197.577674 -112.64942) (xy 197.543588 -112.605277)
			(xy 197.516292 -112.556642) (xy 197.496369 -112.504551) (xy 197.484243 -112.450114) (xy 197.480172 -112.394492)
			(xy 188.682024 -112.394492) (xy 188.701848 -112.440339) (xy 188.715796 -112.490338) (xy 188.722834 -112.541766)
			(xy 188.72327 -112.56772) (xy 188.722784 -112.594971) (xy 188.715028 -112.648919) (xy 188.699673 -112.701214)
			(xy 188.677031 -112.750791) (xy 188.647565 -112.796641) (xy 188.611874 -112.837832) (xy 188.570683 -112.873523)
			(xy 188.524833 -112.902989) (xy 188.475256 -112.925631) (xy 188.422961 -112.940986) (xy 188.369013 -112.948742)
			(xy 188.314511 -112.948742) (xy 188.260563 -112.940986) (xy 188.208268 -112.925631) (xy 188.158691 -112.902989)
			(xy 188.112841 -112.873523) (xy 188.07165 -112.837832) (xy 188.035959 -112.796641) (xy 188.006493 -112.750791)
			(xy 187.983851 -112.701214) (xy 187.968496 -112.648919) (xy 187.96074 -112.594971) (xy 187.960254 -112.56772)
			(xy 187.9608 -112.537925) (xy 187.970063 -112.479059) (xy 187.988367 -112.42235) (xy 188.015265 -112.369177)
			(xy 188.050105 -112.320832) (xy 188.092038 -112.278494) (xy 188.115702 -112.26038) (xy 188.122461 -112.254998)
			(xy 188.1322 -112.240742) (xy 188.136627 -112.224054) (xy 188.136276 -112.215422) (xy 188.129672 -112.12957)
			(xy 188.12877 -112.121053) (xy 188.121994 -112.105333) (xy 188.1104 -112.09274) (xy 188.103002 -112.088422)
			(xy 188.102748 -112.088422) (xy 188.079955 -112.076005) (xy 188.037661 -112.045916) (xy 187.999839 -112.010369)
			(xy 187.967188 -111.97002) (xy 187.940312 -111.925615) (xy 187.919708 -111.877974) (xy 187.905757 -111.82798)
			(xy 187.898716 -111.776554) (xy 187.898278 -111.750602) (xy 187.898717 -111.723581) (xy 187.906332 -111.670077)
			(xy 187.921425 -111.618185) (xy 187.943693 -111.568943) (xy 187.972689 -111.523338) (xy 188.007834 -111.482284)
			(xy 188.027818 -111.46409) (xy 188.03578 -111.456436) (xy 188.044726 -111.436268) (xy 188.04509 -111.425228)
			(xy 188.04382 -111.348012) (xy 188.043169 -111.336998) (xy 188.033671 -111.317109) (xy 188.025532 -111.309658)
			(xy 188.00439 -111.291437) (xy 187.967114 -111.2499) (xy 187.93629 -111.203372) (xy 187.912578 -111.152849)
			(xy 187.896483 -111.099409) (xy 187.88835 -111.044194) (xy 187.887864 -111.016288) (xy 187.054744 -111.016288)
			(xy 187.054744 -112.767872) (xy 187.055173 -112.777941) (xy 187.06289 -112.79654) (xy 187.06973 -112.80394)
			(xy 187.410598 -113.145062) (xy 187.418009 -113.151888) (xy 187.4366 -113.159617) (xy 187.446666 -113.160048)
			(xy 191.546988 -113.160048) (xy 191.552068 -113.16208) (xy 191.559721 -113.135383) (xy 191.581691 -113.084378)
			(xy 191.610825 -113.037098) (xy 191.646507 -112.994543) (xy 191.687983 -112.957611) (xy 191.734375 -112.927083)
			(xy 191.784704 -112.903605) (xy 191.837905 -112.887673) (xy 191.892854 -112.879623) (xy 191.920622 -112.879124)
			(xy 191.947877 -112.879534) (xy 192.001831 -112.887295) (xy 192.054132 -112.902656) (xy 192.103715 -112.925303)
			(xy 192.149569 -112.954776) (xy 192.190763 -112.990476) (xy 192.226456 -113.031674) (xy 192.255923 -113.077533)
			(xy 192.278563 -113.127118) (xy 192.293916 -113.179421) (xy 192.301169 -113.229898) (xy 192.541904 -113.229898)
			(xy 192.545975 -113.174276) (xy 192.558101 -113.119839) (xy 192.578024 -113.067748) (xy 192.60532 -113.019113)
			(xy 192.639406 -112.97497) (xy 192.679555 -112.936261) (xy 192.724913 -112.90381) (xy 192.774513 -112.878309)
			(xy 192.827297 -112.860302) (xy 192.88214 -112.850172) (xy 192.937874 -112.848135) (xy 192.993311 -112.854235)
			(xy 193.047268 -112.868341) (xy 193.098597 -112.890153) (xy 193.146203 -112.919207) (xy 193.189071 -112.954882)
			(xy 193.226288 -112.996419) (xy 193.257061 -113.042932) (xy 193.280733 -113.093429) (xy 193.296801 -113.146836)
			(xy 193.304921 -113.202012) (xy 193.30543 -113.229898) (xy 193.304921 -113.257784) (xy 193.296801 -113.31296)
			(xy 193.280733 -113.366367) (xy 193.258619 -113.41354) (xy 197.453756 -113.41354) (xy 197.457827 -113.357918)
			(xy 197.469953 -113.303481) (xy 197.489876 -113.25139) (xy 197.517172 -113.202755) (xy 197.551258 -113.158612)
			(xy 197.591407 -113.119903) (xy 197.636765 -113.087452) (xy 197.686365 -113.061951) (xy 197.739149 -113.043944)
			(xy 197.793992 -113.033814) (xy 197.849726 -113.031777) (xy 197.905163 -113.037877) (xy 197.95912 -113.051983)
			(xy 198.010449 -113.073795) (xy 198.058055 -113.102849) (xy 198.100923 -113.138524) (xy 198.13814 -113.180061)
			(xy 198.168913 -113.226574) (xy 198.192585 -113.277071) (xy 198.208653 -113.330478) (xy 198.216773 -113.385654)
			(xy 198.217282 -113.41354) (xy 198.216773 -113.441426) (xy 198.208653 -113.496602) (xy 198.192585 -113.550009)
			(xy 198.168913 -113.600506) (xy 198.13814 -113.647019) (xy 198.100923 -113.688556) (xy 198.058055 -113.724231)
			(xy 198.010449 -113.753285) (xy 197.95912 -113.775097) (xy 197.905163 -113.789203) (xy 197.849726 -113.795303)
			(xy 197.793992 -113.793266) (xy 197.739149 -113.783136) (xy 197.686365 -113.765129) (xy 197.636765 -113.739628)
			(xy 197.591407 -113.707177) (xy 197.551258 -113.668468) (xy 197.517172 -113.624325) (xy 197.489876 -113.57569)
			(xy 197.469953 -113.523599) (xy 197.457827 -113.469162) (xy 197.453756 -113.41354) (xy 193.258619 -113.41354)
			(xy 193.257061 -113.416864) (xy 193.226288 -113.463377) (xy 193.189071 -113.504914) (xy 193.146203 -113.540589)
			(xy 193.098597 -113.569643) (xy 193.047268 -113.591455) (xy 192.993311 -113.605561) (xy 192.937874 -113.611661)
			(xy 192.88214 -113.609624) (xy 192.827297 -113.599494) (xy 192.774513 -113.581487) (xy 192.724913 -113.555986)
			(xy 192.679555 -113.523535) (xy 192.639406 -113.484826) (xy 192.60532 -113.440683) (xy 192.578024 -113.392048)
			(xy 192.558101 -113.339957) (xy 192.545975 -113.28552) (xy 192.541904 -113.229898) (xy 192.301169 -113.229898)
			(xy 192.301669 -113.233377) (xy 192.30213 -113.260632) (xy 192.301658 -113.288569) (xy 192.293504 -113.343845)
			(xy 192.277376 -113.397341) (xy 192.253618 -113.447913) (xy 192.222739 -113.494479) (xy 192.185398 -113.536044)
			(xy 192.164208 -113.554256) (xy 192.163954 -113.55451) (xy 192.156213 -113.561676) (xy 192.146907 -113.580583)
			(xy 192.14592 -113.591086) (xy 192.142364 -113.665254) (xy 192.142468 -113.675904) (xy 192.150195 -113.695721)
			(xy 192.15735 -113.703608) (xy 192.620138 -114.166142) (xy 192.627526 -114.172997) (xy 192.646135 -114.180707)
			(xy 192.656206 -114.181128) (xy 197.55993 -114.181128) (xy 197.560946 -114.182144) (xy 197.583044 -114.182144)
			(xy 197.601246 -114.161506) (xy 197.642569 -114.125167) (xy 197.688687 -114.095147) (xy 197.738642 -114.072068)
			(xy 197.791395 -114.056411) (xy 197.845852 -114.0485) (xy 197.90088 -114.0485) (xy 197.955337 -114.056411)
			(xy 198.00809 -114.072068) (xy 198.058045 -114.095147) (xy 198.104163 -114.125167) (xy 198.145486 -114.161506)
			(xy 198.163688 -114.182144) (xy 198.185786 -114.182144) (xy 198.186802 -114.181128) (xy 201.406506 -114.181128)
			(xy 201.407522 -114.182144) (xy 201.42962 -114.182144) (xy 201.447822 -114.161506) (xy 201.489145 -114.125167)
			(xy 201.535263 -114.095147) (xy 201.585218 -114.072068) (xy 201.637971 -114.056411) (xy 201.692428 -114.0485)
			(xy 201.747456 -114.0485) (xy 201.801913 -114.056411) (xy 201.854666 -114.072068) (xy 201.904621 -114.095147)
			(xy 201.950739 -114.125167) (xy 201.992062 -114.161506) (xy 202.010264 -114.182144) (xy 202.032362 -114.182144)
			(xy 202.033378 -114.181128) (xy 203.367894 -114.181128) (xy 203.373195 -114.181023) (xy 203.383571 -114.178843)
			(xy 203.388468 -114.17681) (xy 203.417424 -114.165634) (xy 203.42606 -114.162078) (xy 203.442062 -114.12347)
			(xy 203.432156 -114.098832) (xy 203.428854 -114.094006) (xy 203.412849 -114.069945) (xy 203.387509 -114.018012)
			(xy 203.370285 -113.962853) (xy 203.361571 -113.905729) (xy 203.361036 -113.876836) (xy 203.361522 -113.849585)
			(xy 203.369278 -113.795637) (xy 203.384633 -113.743342) (xy 203.407275 -113.693765) (xy 203.436741 -113.647915)
			(xy 203.472432 -113.606724) (xy 203.513623 -113.571033) (xy 203.559473 -113.541567) (xy 203.60905 -113.518925)
			(xy 203.661345 -113.50357) (xy 203.715293 -113.495814) (xy 203.769795 -113.495814) (xy 203.823743 -113.50357)
			(xy 203.876038 -113.518925) (xy 203.925615 -113.541567) (xy 203.971465 -113.571033) (xy 204.012656 -113.606724)
			(xy 204.048347 -113.647915) (xy 204.077813 -113.693765) (xy 204.100455 -113.743342) (xy 204.11581 -113.795637)
			(xy 204.123566 -113.849585) (xy 204.124052 -113.876836) (xy 204.123706 -113.900046) (xy 204.118056 -113.946122)
			(xy 204.106868 -113.991175) (xy 204.098906 -114.01298) (xy 204.095221 -114.024736) (xy 204.098143 -114.049159)
			(xy 204.104494 -114.059716) (xy 204.151484 -114.128042) (xy 204.159022 -114.137927) (xy 204.180979 -114.149519)
			(xy 204.193394 -114.15014) (xy 205.404974 -114.15014) (xy 205.413495 -114.149838) (xy 205.429605 -114.144279)
			(xy 205.443015 -114.133761) (xy 205.4479 -114.126772) (xy 205.500732 -114.044222) (xy 205.50251 -114.018314)
			(xy 205.496922 -114.00663) (xy 205.485764 -113.981402) (xy 205.470041 -113.928526) (xy 205.4621 -113.873938)
			(xy 205.461616 -113.846356) (xy 205.462102 -113.819105) (xy 205.469858 -113.765157) (xy 205.485213 -113.712862)
			(xy 205.507855 -113.663285) (xy 205.537321 -113.617435) (xy 205.573012 -113.576244) (xy 205.614203 -113.540553)
			(xy 205.660053 -113.511087) (xy 205.70963 -113.488445) (xy 205.761925 -113.47309) (xy 205.815873 -113.465334)
			(xy 205.870375 -113.465334) (xy 205.924323 -113.47309) (xy 205.976618 -113.488445) (xy 206.026195 -113.511087)
			(xy 206.072045 -113.540553) (xy 206.113236 -113.576244) (xy 206.148927 -113.617435) (xy 206.178393 -113.663285)
			(xy 206.201035 -113.712862) (xy 206.21639 -113.765157) (xy 206.224146 -113.819105) (xy 206.224632 -113.846356)
			(xy 206.224148 -113.873937) (xy 206.216198 -113.928523) (xy 206.200472 -113.981397) (xy 206.189326 -114.00663)
			(xy 206.183738 -114.018314) (xy 206.185516 -114.044222) (xy 206.238348 -114.126772) (xy 206.243173 -114.133815)
			(xy 206.256592 -114.144356) (xy 206.27274 -114.149873) (xy 206.281274 -114.15014) (xy 209.082894 -114.15014)
			(xy 209.091939 -114.149751) (xy 209.10891 -114.143489) (xy 209.122638 -114.131711) (xy 209.127344 -114.123978)
			(xy 209.140232 -114.101589) (xy 209.171136 -114.060193) (xy 209.207343 -114.023346) (xy 209.24819 -113.99172)
			(xy 209.270346 -113.978436) (xy 209.27787 -113.973689) (xy 209.289316 -113.960085) (xy 209.295406 -113.943383)
			(xy 209.295746 -113.934494) (xy 209.295746 -113.846102) (xy 209.295315 -113.837227) (xy 209.289233 -113.82055)
			(xy 209.277832 -113.806943) (xy 209.270346 -113.80216) (xy 209.245872 -113.787468) (xy 209.201225 -113.7519)
			(xy 209.162382 -113.710071) (xy 209.130212 -113.662916) (xy 209.105435 -113.611491) (xy 209.088604 -113.556946)
			(xy 209.080097 -113.500501) (xy 209.079592 -113.47196) (xy 209.080078 -113.444709) (xy 209.087834 -113.390761)
			(xy 209.103189 -113.338466) (xy 209.125831 -113.288889) (xy 209.155297 -113.243039) (xy 209.190988 -113.201848)
			(xy 209.232179 -113.166157) (xy 209.278029 -113.136691) (xy 209.327606 -113.114049) (xy 209.379901 -113.098694)
			(xy 209.433849 -113.090938) (xy 209.488351 -113.090938) (xy 209.542299 -113.098694) (xy 209.594594 -113.114049)
			(xy 209.644171 -113.136691) (xy 209.690021 -113.166157) (xy 209.731212 -113.201848) (xy 209.766903 -113.243039)
			(xy 209.796369 -113.288889) (xy 209.819011 -113.338466) (xy 209.834366 -113.390761) (xy 209.842122 -113.444709)
			(xy 209.842608 -113.47196) (xy 209.842083 -113.500497) (xy 209.833554 -113.556932) (xy 209.816712 -113.611465)
			(xy 209.791932 -113.66288) (xy 209.759767 -113.710029) (xy 209.720935 -113.751858) (xy 209.676305 -113.787434)
			(xy 209.651854 -113.80216) (xy 209.644332 -113.80691) (xy 209.632886 -113.820512) (xy 209.626794 -113.837213)
			(xy 209.626454 -113.846102) (xy 209.626454 -113.934494) (xy 209.626888 -113.943369) (xy 209.632968 -113.960046)
			(xy 209.644368 -113.973653) (xy 209.651854 -113.978436) (xy 209.674007 -113.991724) (xy 209.714854 -114.02335)
			(xy 209.75106 -114.060197) (xy 209.781963 -114.101592) (xy 209.794856 -114.123978) (xy 209.799562 -114.131713)
			(xy 209.813292 -114.143496) (xy 209.830259 -114.149777) (xy 209.839306 -114.15014) (xy 211.272628 -114.15014)
			(xy 211.282249 -114.14775) (xy 211.298826 -114.136931) (xy 211.310057 -114.120628) (xy 211.314259 -114.101283)
			(xy 211.310803 -114.08179) (xy 211.305902 -114.073178) (xy 211.292064 -114.050307) (xy 211.270244 -114.001507)
			(xy 211.255443 -113.950141) (xy 211.247949 -113.897214) (xy 211.247482 -113.870486) (xy 211.247968 -113.843235)
			(xy 211.255724 -113.789287) (xy 211.271079 -113.736992) (xy 211.293721 -113.687415) (xy 211.323187 -113.641565)
			(xy 211.358878 -113.600374) (xy 211.400069 -113.564683) (xy 211.445919 -113.535217) (xy 211.495496 -113.512575)
			(xy 211.547791 -113.49722) (xy 211.601739 -113.489464) (xy 211.656241 -113.489464) (xy 211.710189 -113.49722)
			(xy 211.762484 -113.512575) (xy 211.812061 -113.535217) (xy 211.857911 -113.564683) (xy 211.899102 -113.600374)
			(xy 211.934793 -113.641565) (xy 211.942182 -113.653062) (xy 235.227876 -113.653062) (xy 235.228362 -113.625811)
			(xy 235.236118 -113.571863) (xy 235.251473 -113.519568) (xy 235.274115 -113.469991) (xy 235.303581 -113.424141)
			(xy 235.339272 -113.38295) (xy 235.380463 -113.347259) (xy 235.426313 -113.317793) (xy 235.47589 -113.295151)
			(xy 235.528185 -113.279796) (xy 235.582133 -113.27204) (xy 235.636635 -113.27204) (xy 235.690583 -113.279796)
			(xy 235.742878 -113.295151) (xy 235.757949 -113.302034) (xy 246.514112 -113.302034) (xy 246.514598 -113.274783)
			(xy 246.522354 -113.220835) (xy 246.537709 -113.16854) (xy 246.560351 -113.118963) (xy 246.589817 -113.073113)
			(xy 246.625508 -113.031922) (xy 246.666699 -112.996231) (xy 246.712549 -112.966765) (xy 246.762126 -112.944123)
			(xy 246.814421 -112.928768) (xy 246.868369 -112.921012) (xy 246.922871 -112.921012) (xy 246.976819 -112.928768)
			(xy 247.029114 -112.944123) (xy 247.078691 -112.966765) (xy 247.124541 -112.996231) (xy 247.165732 -113.031922)
			(xy 247.201423 -113.073113) (xy 247.230889 -113.118963) (xy 247.247797 -113.155984) (xy 248.516012 -113.155984)
			(xy 248.523764 -113.102026) (xy 248.539117 -113.049721) (xy 248.561757 -113.000133) (xy 248.591223 -112.954272)
			(xy 248.626916 -112.913071) (xy 248.66811 -112.87737) (xy 248.713965 -112.847894) (xy 248.763548 -112.825244)
			(xy 248.81585 -112.809881) (xy 248.869806 -112.802118) (xy 248.924317 -112.802112) (xy 248.978275 -112.809865)
			(xy 249.03058 -112.825217) (xy 249.080167 -112.847857) (xy 249.126028 -112.877323) (xy 249.167229 -112.913017)
			(xy 249.202931 -112.95421) (xy 249.232406 -113.000065) (xy 249.255056 -113.049648) (xy 249.270419 -113.10195)
			(xy 249.278182 -113.155906) (xy 249.278648 -113.183162) (xy 249.278648 -113.190528) (xy 249.278394 -113.204244)
			(xy 249.291856 -113.228374) (xy 249.392948 -113.286794) (xy 249.420634 -113.28654) (xy 249.432572 -113.279428)
			(xy 249.454936 -113.266496) (xy 249.502383 -113.246066) (xy 249.552154 -113.232233) (xy 249.603339 -113.22525)
			(xy 249.629168 -113.224818) (xy 249.656421 -113.225285) (xy 249.710373 -113.233038) (xy 249.762673 -113.248392)
			(xy 249.812254 -113.271032) (xy 249.858109 -113.300499) (xy 249.899303 -113.336193) (xy 249.934997 -113.377386)
			(xy 249.964465 -113.42324) (xy 249.987106 -113.472822) (xy 250.00246 -113.525121) (xy 250.010214 -113.579073)
			(xy 250.010676 -113.606326) (xy 250.010117 -113.635663) (xy 250.001118 -113.693644) (xy 249.983351 -113.749564)
			(xy 249.957236 -113.802106) (xy 249.923387 -113.850033) (xy 249.882602 -113.892214) (xy 249.859546 -113.910364)
			(xy 249.850919 -113.917591) (xy 249.840506 -113.93751) (xy 249.83948 -113.948718) (xy 249.83567 -114.038634)
			(xy 249.844306 -114.059462) (xy 249.852942 -114.067082) (xy 249.872547 -114.08522) (xy 249.906937 -114.126086)
			(xy 249.935291 -114.171349) (xy 249.957054 -114.220125) (xy 249.971802 -114.271459) (xy 249.979244 -114.324349)
			(xy 249.979688 -114.351054) (xy 249.979202 -114.378305) (xy 249.971446 -114.432253) (xy 249.956091 -114.484548)
			(xy 249.953373 -114.4905) (xy 266.51534 -114.4905) (xy 266.519411 -114.434878) (xy 266.531537 -114.380441)
			(xy 266.55146 -114.32835) (xy 266.578756 -114.279715) (xy 266.612842 -114.235572) (xy 266.652991 -114.196863)
			(xy 266.698349 -114.164412) (xy 266.747949 -114.138911) (xy 266.800733 -114.120904) (xy 266.855576 -114.110774)
			(xy 266.91131 -114.108737) (xy 266.966747 -114.114837) (xy 267.020704 -114.128943) (xy 267.072033 -114.150755)
			(xy 267.119639 -114.179809) (xy 267.162507 -114.215484) (xy 267.199724 -114.257021) (xy 267.230497 -114.303534)
			(xy 267.254169 -114.354031) (xy 267.270237 -114.407438) (xy 267.278357 -114.462614) (xy 267.278866 -114.4905)
			(xy 267.278357 -114.518386) (xy 267.270237 -114.573562) (xy 267.254169 -114.626969) (xy 267.230497 -114.677466)
			(xy 267.199724 -114.723979) (xy 267.162507 -114.765516) (xy 267.119639 -114.801191) (xy 267.072033 -114.830245)
			(xy 267.020704 -114.852057) (xy 266.966747 -114.866163) (xy 266.91131 -114.872263) (xy 266.855576 -114.870226)
			(xy 266.800733 -114.860096) (xy 266.747949 -114.842089) (xy 266.698349 -114.816588) (xy 266.652991 -114.784137)
			(xy 266.612842 -114.745428) (xy 266.578756 -114.701285) (xy 266.55146 -114.65265) (xy 266.531537 -114.600559)
			(xy 266.519411 -114.546122) (xy 266.51534 -114.4905) (xy 249.953373 -114.4905) (xy 249.933449 -114.534125)
			(xy 249.903983 -114.579975) (xy 249.868292 -114.621166) (xy 249.827101 -114.656857) (xy 249.781251 -114.686323)
			(xy 249.731674 -114.708965) (xy 249.679379 -114.72432) (xy 249.625431 -114.732076) (xy 249.570929 -114.732076)
			(xy 249.516981 -114.72432) (xy 249.464686 -114.708965) (xy 249.415109 -114.686323) (xy 249.369259 -114.656857)
			(xy 249.328068 -114.621166) (xy 249.292377 -114.579975) (xy 249.262911 -114.534125) (xy 249.240269 -114.484548)
			(xy 249.224914 -114.432253) (xy 249.217158 -114.378305) (xy 249.216672 -114.351054) (xy 249.217237 -114.321717)
			(xy 249.226238 -114.263738) (xy 249.244005 -114.207819) (xy 249.270119 -114.155277) (xy 249.303966 -114.10735)
			(xy 249.344748 -114.065167) (xy 249.367802 -114.047016) (xy 249.376445 -114.039806) (xy 249.386848 -114.019874)
			(xy 249.387868 -114.008662) (xy 249.391678 -113.918746) (xy 249.383042 -113.897918) (xy 249.374406 -113.890298)
			(xy 249.354849 -113.87211) (xy 249.320453 -113.831256) (xy 249.292091 -113.786004) (xy 249.270319 -113.737238)
			(xy 249.255563 -113.685912) (xy 249.248109 -113.633029) (xy 249.24766 -113.606326) (xy 249.24766 -113.59896)
			(xy 249.247914 -113.585244) (xy 249.234452 -113.561114) (xy 249.13336 -113.502694) (xy 249.105674 -113.502948)
			(xy 249.093736 -113.51006) (xy 249.071392 -113.523027) (xy 249.023938 -113.543449) (xy 248.97416 -113.557272)
			(xy 248.922971 -113.564244) (xy 248.89714 -113.56467) (xy 248.869884 -113.564288) (xy 248.815927 -113.556536)
			(xy 248.763622 -113.541184) (xy 248.714034 -113.518544) (xy 248.668173 -113.489077) (xy 248.626972 -113.453384)
			(xy 248.59127 -113.412191) (xy 248.561794 -113.366336) (xy 248.539144 -113.316753) (xy 248.523781 -113.264451)
			(xy 248.516018 -113.210495) (xy 248.516012 -113.155984) (xy 247.247797 -113.155984) (xy 247.253531 -113.16854)
			(xy 247.268886 -113.220835) (xy 247.276642 -113.274783) (xy 247.277128 -113.302034) (xy 247.277128 -113.302542)
			(xy 247.27647 -113.333872) (xy 247.266181 -113.395683) (xy 247.245935 -113.454984) (xy 247.231662 -113.482882)
			(xy 247.225017 -113.496303) (xy 247.219079 -113.525643) (xy 247.221908 -113.555444) (xy 247.233263 -113.583142)
			(xy 247.252164 -113.606354) (xy 247.276988 -113.623084) (xy 247.305597 -113.631893) (xy 247.320562 -113.632488)
			(xy 247.347719 -113.633094) (xy 247.401446 -113.641088) (xy 247.453497 -113.656622) (xy 247.502819 -113.679381)
			(xy 247.548414 -113.708905) (xy 247.58936 -113.744597) (xy 247.624831 -113.785736) (xy 247.654109 -113.831489)
			(xy 247.676601 -113.880933) (xy 247.691854 -113.933066) (xy 247.699559 -113.986836) (xy 247.700038 -114.013996)
			(xy 247.699552 -114.041247) (xy 247.691796 -114.095195) (xy 247.676441 -114.14749) (xy 247.653799 -114.197067)
			(xy 247.624333 -114.242917) (xy 247.588642 -114.284108) (xy 247.547451 -114.319799) (xy 247.501601 -114.349265)
			(xy 247.452024 -114.371907) (xy 247.399729 -114.387262) (xy 247.345781 -114.395018) (xy 247.291279 -114.395018)
			(xy 247.237331 -114.387262) (xy 247.185036 -114.371907) (xy 247.135459 -114.349265) (xy 247.089609 -114.319799)
			(xy 247.048418 -114.284108) (xy 247.012727 -114.242917) (xy 246.983261 -114.197067) (xy 246.960619 -114.14749)
			(xy 246.945264 -114.095195) (xy 246.937508 -114.041247) (xy 246.937022 -114.013996) (xy 246.937022 -114.013488)
			(xy 246.937685 -113.982158) (xy 246.947971 -113.920347) (xy 246.968215 -113.861046) (xy 246.982488 -113.833148)
			(xy 246.98914 -113.819727) (xy 246.99509 -113.790384) (xy 246.992266 -113.760577) (xy 246.980912 -113.732874)
			(xy 246.962005 -113.709658) (xy 246.937174 -113.69293) (xy 246.908556 -113.68413) (xy 246.893588 -113.683542)
			(xy 246.866434 -113.68286) (xy 246.812711 -113.674873) (xy 246.760663 -113.659347) (xy 246.711344 -113.636596)
			(xy 246.66575 -113.60708) (xy 246.624804 -113.571396) (xy 246.589332 -113.530265) (xy 246.560053 -113.484519)
			(xy 246.537558 -113.435082) (xy 246.522302 -113.382955) (xy 246.514594 -113.329191) (xy 246.514112 -113.302034)
			(xy 235.757949 -113.302034) (xy 235.792455 -113.317793) (xy 235.838305 -113.347259) (xy 235.879496 -113.38295)
			(xy 235.915187 -113.424141) (xy 235.944653 -113.469991) (xy 235.967295 -113.519568) (xy 235.98265 -113.571863)
			(xy 235.990406 -113.625811) (xy 235.990892 -113.653062) (xy 235.99047 -113.678594) (xy 235.983663 -113.729201)
			(xy 235.970166 -113.778448) (xy 235.95022 -113.825455) (xy 235.937552 -113.847626) (xy 235.930948 -113.858802)
			(xy 235.929932 -113.88471) (xy 235.974636 -113.972848) (xy 235.978759 -113.980331) (xy 235.991063 -113.992176)
			(xy 236.006559 -113.999355) (xy 236.015022 -114.000534) (xy 236.015276 -114.000534) (xy 236.043255 -114.00365)
			(xy 236.097891 -114.017226) (xy 236.149939 -114.038683) (xy 236.198268 -114.067556) (xy 236.24183 -114.103217)
			(xy 236.271064 -114.135408) (xy 245.771668 -114.135408) (xy 245.775739 -114.079786) (xy 245.787865 -114.025349)
			(xy 245.807788 -113.973258) (xy 245.835084 -113.924623) (xy 245.86917 -113.88048) (xy 245.909319 -113.841771)
			(xy 245.954677 -113.80932) (xy 246.004277 -113.783819) (xy 246.057061 -113.765812) (xy 246.111904 -113.755682)
			(xy 246.167638 -113.753645) (xy 246.223075 -113.759745) (xy 246.277032 -113.773851) (xy 246.328361 -113.795663)
			(xy 246.375967 -113.824717) (xy 246.418835 -113.860392) (xy 246.456052 -113.901929) (xy 246.486825 -113.948442)
			(xy 246.510497 -113.998939) (xy 246.526565 -114.052346) (xy 246.534685 -114.107522) (xy 246.535194 -114.135408)
			(xy 246.534685 -114.163294) (xy 246.526565 -114.21847) (xy 246.510497 -114.271877) (xy 246.486825 -114.322374)
			(xy 246.456052 -114.368887) (xy 246.418835 -114.410424) (xy 246.375967 -114.446099) (xy 246.328361 -114.475153)
			(xy 246.277032 -114.496965) (xy 246.223075 -114.511071) (xy 246.167638 -114.517171) (xy 246.111904 -114.515134)
			(xy 246.057061 -114.505004) (xy 246.004277 -114.486997) (xy 245.954677 -114.461496) (xy 245.909319 -114.429045)
			(xy 245.86917 -114.390336) (xy 245.835084 -114.346193) (xy 245.807788 -114.297558) (xy 245.787865 -114.245467)
			(xy 245.775739 -114.19103) (xy 245.771668 -114.135408) (xy 236.271064 -114.135408) (xy 236.279678 -114.144894)
			(xy 236.31099 -114.19168) (xy 236.335087 -114.242559) (xy 236.351445 -114.296428) (xy 236.359709 -114.352115)
			(xy 236.360208 -114.380264) (xy 236.359678 -114.408426) (xy 236.351402 -114.464138) (xy 236.335023 -114.518028)
			(xy 236.310899 -114.568924) (xy 236.279554 -114.615719) (xy 236.241669 -114.657397) (xy 236.230821 -114.666268)
			(xy 236.640876 -114.666268) (xy 236.644947 -114.610646) (xy 236.657073 -114.556209) (xy 236.676996 -114.504118)
			(xy 236.704292 -114.455483) (xy 236.738378 -114.41134) (xy 236.778527 -114.372631) (xy 236.823885 -114.34018)
			(xy 236.873485 -114.314679) (xy 236.926269 -114.296672) (xy 236.981112 -114.286542) (xy 237.036846 -114.284505)
			(xy 237.092283 -114.290605) (xy 237.14624 -114.304711) (xy 237.197569 -114.326523) (xy 237.245175 -114.355577)
			(xy 237.288043 -114.391252) (xy 237.32526 -114.432789) (xy 237.356033 -114.479302) (xy 237.379705 -114.529799)
			(xy 237.395773 -114.583206) (xy 237.403893 -114.638382) (xy 237.404402 -114.666268) (xy 237.404291 -114.672364)
			(xy 242.661184 -114.672364) (xy 242.665255 -114.616742) (xy 242.677381 -114.562305) (xy 242.697304 -114.510214)
			(xy 242.7246 -114.461579) (xy 242.758686 -114.417436) (xy 242.798835 -114.378727) (xy 242.844193 -114.346276)
			(xy 242.893793 -114.320775) (xy 242.946577 -114.302768) (xy 243.00142 -114.292638) (xy 243.057154 -114.290601)
			(xy 243.112591 -114.296701) (xy 243.166548 -114.310807) (xy 243.217877 -114.332619) (xy 243.265483 -114.361673)
			(xy 243.308351 -114.397348) (xy 243.345568 -114.438885) (xy 243.376341 -114.485398) (xy 243.400013 -114.535895)
			(xy 243.416081 -114.589302) (xy 243.424201 -114.644478) (xy 243.424492 -114.660426) (xy 244.161308 -114.660426)
			(xy 244.165379 -114.604804) (xy 244.177505 -114.550367) (xy 244.197428 -114.498276) (xy 244.224724 -114.449641)
			(xy 244.25881 -114.405498) (xy 244.298959 -114.366789) (xy 244.344317 -114.334338) (xy 244.393917 -114.308837)
			(xy 244.446701 -114.29083) (xy 244.501544 -114.2807) (xy 244.557278 -114.278663) (xy 244.612715 -114.284763)
			(xy 244.666672 -114.298869) (xy 244.718001 -114.320681) (xy 244.765607 -114.349735) (xy 244.808475 -114.38541)
			(xy 244.845692 -114.426947) (xy 244.876465 -114.47346) (xy 244.900137 -114.523957) (xy 244.916205 -114.577364)
			(xy 244.924325 -114.63254) (xy 244.924834 -114.660426) (xy 244.924325 -114.688312) (xy 244.916205 -114.743488)
			(xy 244.900137 -114.796895) (xy 244.876465 -114.847392) (xy 244.845692 -114.893905) (xy 244.808475 -114.935442)
			(xy 244.765607 -114.971117) (xy 244.718001 -115.000171) (xy 244.666672 -115.021983) (xy 244.612715 -115.036089)
			(xy 244.557278 -115.042189) (xy 244.501544 -115.040152) (xy 244.446701 -115.030022) (xy 244.393917 -115.012015)
			(xy 244.344317 -114.986514) (xy 244.298959 -114.954063) (xy 244.25881 -114.915354) (xy 244.224724 -114.871211)
			(xy 244.197428 -114.822576) (xy 244.177505 -114.770485) (xy 244.165379 -114.716048) (xy 244.161308 -114.660426)
			(xy 243.424492 -114.660426) (xy 243.42471 -114.672364) (xy 243.424201 -114.70025) (xy 243.416081 -114.755426)
			(xy 243.400013 -114.808833) (xy 243.376341 -114.85933) (xy 243.345568 -114.905843) (xy 243.308351 -114.94738)
			(xy 243.265483 -114.983055) (xy 243.217877 -115.012109) (xy 243.166548 -115.033921) (xy 243.112591 -115.048027)
			(xy 243.057154 -115.054127) (xy 243.00142 -115.05209) (xy 242.946577 -115.04196) (xy 242.893793 -115.023953)
			(xy 242.844193 -114.998452) (xy 242.798835 -114.966001) (xy 242.758686 -114.927292) (xy 242.7246 -114.883149)
			(xy 242.697304 -114.834514) (xy 242.677381 -114.782423) (xy 242.665255 -114.727986) (xy 242.661184 -114.672364)
			(xy 237.404291 -114.672364) (xy 237.403893 -114.694154) (xy 237.395773 -114.74933) (xy 237.379705 -114.802737)
			(xy 237.356033 -114.853234) (xy 237.32526 -114.899747) (xy 237.288043 -114.941284) (xy 237.245175 -114.976959)
			(xy 237.197569 -115.006013) (xy 237.14624 -115.027825) (xy 237.092283 -115.041931) (xy 237.036846 -115.048031)
			(xy 236.981112 -115.045994) (xy 236.926269 -115.035864) (xy 236.873485 -115.017857) (xy 236.823885 -114.992356)
			(xy 236.778527 -114.959905) (xy 236.738378 -114.921196) (xy 236.704292 -114.877053) (xy 236.676996 -114.828418)
			(xy 236.657073 -114.776327) (xy 236.644947 -114.72189) (xy 236.640876 -114.666268) (xy 236.230821 -114.666268)
			(xy 236.198067 -114.693052) (xy 236.149696 -114.721907) (xy 236.097609 -114.743337) (xy 236.070394 -114.750596)
			(xy 236.061134 -114.753304) (xy 236.045472 -114.764552) (xy 236.039914 -114.77244) (xy 235.996734 -114.838988)
			(xy 235.992924 -114.85753) (xy 235.994702 -114.867436) (xy 235.997654 -114.884492) (xy 236.000834 -114.918962)
			(xy 236.001052 -114.93627) (xy 236.000566 -114.963521) (xy 235.99281 -115.017469) (xy 235.977455 -115.069764)
			(xy 235.954813 -115.119341) (xy 235.925347 -115.165191) (xy 235.889656 -115.206382) (xy 235.848465 -115.242073)
			(xy 235.802615 -115.271539) (xy 235.753038 -115.294181) (xy 235.700743 -115.309536) (xy 235.646795 -115.317292)
			(xy 235.592293 -115.317292) (xy 235.538345 -115.309536) (xy 235.48605 -115.294181) (xy 235.436473 -115.271539)
			(xy 235.390623 -115.242073) (xy 235.349432 -115.206382) (xy 235.313741 -115.165191) (xy 235.284275 -115.119341)
			(xy 235.261633 -115.069764) (xy 235.246278 -115.017469) (xy 235.238522 -114.963521) (xy 235.238036 -114.93627)
			(xy 235.238473 -114.908105) (xy 235.24676 -114.852387) (xy 235.26315 -114.798493) (xy 235.287285 -114.747595)
			(xy 235.318642 -114.700799) (xy 235.356539 -114.659122) (xy 235.400152 -114.62347) (xy 235.448533 -114.594618)
			(xy 235.500631 -114.573194) (xy 235.52785 -114.565938) (xy 235.537097 -114.563196) (xy 235.552765 -114.551972)
			(xy 235.55833 -114.544094) (xy 235.60151 -114.477546) (xy 235.60532 -114.459004) (xy 235.603542 -114.449098)
			(xy 235.600595 -114.432041) (xy 235.597412 -114.397572) (xy 235.597192 -114.380264) (xy 235.597583 -114.354731)
			(xy 235.604399 -114.304123) (xy 235.617906 -114.254876) (xy 235.63786 -114.20787) (xy 235.650532 -114.1857)
			(xy 235.657136 -114.174524) (xy 235.658152 -114.148616) (xy 235.613448 -114.060478) (xy 235.609325 -114.052995)
			(xy 235.597023 -114.041148) (xy 235.581526 -114.033969) (xy 235.573062 -114.032792) (xy 235.572808 -114.032792)
			(xy 235.544841 -114.029581) (xy 235.490209 -114.016019) (xy 235.438162 -113.994574) (xy 235.389833 -113.965713)
			(xy 235.346271 -113.930062) (xy 235.308421 -113.888396) (xy 235.277106 -113.84162) (xy 235.253006 -113.790749)
			(xy 235.236644 -113.736888) (xy 235.228377 -113.681208) (xy 235.227876 -113.653062) (xy 211.942182 -113.653062)
			(xy 211.964259 -113.687415) (xy 211.986901 -113.736992) (xy 212.002256 -113.789287) (xy 212.010012 -113.843235)
			(xy 212.010498 -113.870486) (xy 212.010077 -113.898127) (xy 212.002113 -113.952833) (xy 211.986336 -114.005816)
			(xy 211.963077 -114.055967) (xy 211.932821 -114.102235) (xy 211.896204 -114.143651) (xy 211.853991 -114.179348)
			(xy 211.807068 -114.208577) (xy 211.756418 -114.230727) (xy 211.7031 -114.245334) (xy 211.675726 -114.2492)
			(xy 211.663534 -114.250724) (xy 211.64296 -114.26444) (xy 211.585302 -114.371628) (xy 211.587334 -114.375692)
			(xy 211.598588 -114.395555) (xy 211.615698 -114.43788) (xy 211.626344 -114.482274) (xy 211.628736 -114.504978)
			(xy 211.629244 -114.504978) (xy 211.656482 -114.505505) (xy 211.710401 -114.513289) (xy 211.762664 -114.528664)
			(xy 211.812208 -114.551318) (xy 211.858026 -114.580788) (xy 211.899186 -114.616477) (xy 211.93485 -114.657658)
			(xy 211.964293 -114.703494) (xy 211.986916 -114.753052) (xy 212.00226 -114.805324) (xy 212.010012 -114.859247)
			(xy 212.010498 -114.886486) (xy 212.010076 -114.913398) (xy 212.002488 -114.966684) (xy 211.987488 -115.018376)
			(xy 211.965375 -115.067447) (xy 211.936586 -115.112925) (xy 211.901693 -115.153907) (xy 211.861389 -115.189579)
			(xy 211.816472 -115.219236) (xy 211.767834 -115.242287) (xy 211.742274 -115.250722) (xy 211.727034 -115.255548)
			(xy 211.707476 -115.282218) (xy 211.707476 -115.506754) (xy 211.727034 -115.533424) (xy 211.742274 -115.53825)
			(xy 211.768413 -115.546886) (xy 211.81809 -115.570601) (xy 211.863842 -115.601213) (xy 211.904715 -115.638086)
			(xy 211.939861 -115.680454) (xy 211.968549 -115.727436) (xy 211.990183 -115.778055) (xy 212.004312 -115.831258)
			(xy 212.007958 -115.858544) (xy 212.009482 -115.872006) (xy 212.026754 -115.894104) (xy 212.14842 -115.941094)
			(xy 212.172746 -115.951039) (xy 212.217807 -115.978081) (xy 212.257583 -116.012426) (xy 212.290905 -116.053062)
			(xy 212.316793 -116.098796) (xy 212.334484 -116.14828) (xy 212.341407 -116.188224) (xy 223.368955 -116.188224)
			(xy 223.373268 -116.130954) (xy 223.386114 -116.074977) (xy 223.407204 -116.021557) (xy 223.436062 -115.971901)
			(xy 223.472035 -115.927131) (xy 223.492822 -115.907312) (xy 223.500224 -115.899791) (xy 223.508747 -115.88051)
			(xy 223.509332 -115.869974) (xy 223.509332 -115.795298) (xy 223.508808 -115.784748) (xy 223.500268 -115.765453)
			(xy 223.492822 -115.75796) (xy 223.473758 -115.739813) (xy 223.440301 -115.699182) (xy 223.412743 -115.65434)
			(xy 223.391605 -115.606137) (xy 223.37729 -115.555488) (xy 223.370069 -115.503353) (xy 223.369632 -115.477036)
			(xy 223.370118 -115.449785) (xy 223.377874 -115.395837) (xy 223.393229 -115.343542) (xy 223.415871 -115.293965)
			(xy 223.445337 -115.248115) (xy 223.481028 -115.206924) (xy 223.522219 -115.171233) (xy 223.568069 -115.141767)
			(xy 223.617646 -115.119125) (xy 223.669941 -115.10377) (xy 223.723889 -115.096014) (xy 223.778391 -115.096014)
			(xy 223.832339 -115.10377) (xy 223.884634 -115.119125) (xy 223.934211 -115.141767) (xy 223.980061 -115.171233)
			(xy 224.021252 -115.206924) (xy 224.056943 -115.248115) (xy 224.086409 -115.293965) (xy 224.109051 -115.343542)
			(xy 224.124406 -115.395837) (xy 224.132162 -115.449785) (xy 224.132648 -115.477036) (xy 224.132221 -115.503352)
			(xy 224.12498 -115.555482) (xy 224.110654 -115.606127) (xy 224.089514 -115.654326) (xy 224.06196 -115.699168)
			(xy 224.028514 -115.739805) (xy 224.009458 -115.75796) (xy 224.002081 -115.765502) (xy 223.99354 -115.784766)
			(xy 223.992948 -115.795298) (xy 223.992948 -115.869974) (xy 223.993464 -115.880526) (xy 224.002007 -115.899822)
			(xy 224.009458 -115.907312) (xy 224.03028 -115.927097) (xy 224.066251 -115.971876) (xy 224.095107 -116.021539)
			(xy 224.116195 -116.074966) (xy 224.12904 -116.130949) (xy 224.133352 -116.188224) (xy 225.907203 -116.188224)
			(xy 225.911514 -116.130957) (xy 225.924357 -116.074981) (xy 225.945443 -116.021562) (xy 225.974294 -115.971906)
			(xy 226.010261 -115.927133) (xy 226.031044 -115.907312) (xy 226.038434 -115.89978) (xy 226.046967 -115.880508)
			(xy 226.047554 -115.869974) (xy 226.047554 -115.795298) (xy 226.047053 -115.784745) (xy 226.0385 -115.765449)
			(xy 226.031044 -115.75796) (xy 226.011965 -115.739828) (xy 225.978512 -115.699192) (xy 225.950958 -115.654346)
			(xy 225.929824 -115.606141) (xy 225.915511 -115.55549) (xy 225.90829 -115.503353) (xy 225.907854 -115.477036)
			(xy 225.90834 -115.449785) (xy 225.916096 -115.395837) (xy 225.931451 -115.343542) (xy 225.954093 -115.293965)
			(xy 225.983559 -115.248115) (xy 226.01925 -115.206924) (xy 226.060441 -115.171233) (xy 226.106291 -115.141767)
			(xy 226.155868 -115.119125) (xy 226.208163 -115.10377) (xy 226.262111 -115.096014) (xy 226.316613 -115.096014)
			(xy 226.370561 -115.10377) (xy 226.422856 -115.119125) (xy 226.472433 -115.141767) (xy 226.518283 -115.171233)
			(xy 226.559474 -115.206924) (xy 226.595165 -115.248115) (xy 226.624631 -115.293965) (xy 226.647273 -115.343542)
			(xy 226.662628 -115.395837) (xy 226.670384 -115.449785) (xy 226.67087 -115.477036) (xy 226.670436 -115.503351)
			(xy 226.663196 -115.555482) (xy 226.648871 -115.606125) (xy 226.627732 -115.654324) (xy 226.60018 -115.699167)
			(xy 226.566735 -115.739805) (xy 226.54768 -115.75796) (xy 226.540291 -115.765492) (xy 226.53176 -115.784764)
			(xy 226.53117 -115.795298) (xy 226.53117 -115.869974) (xy 226.531708 -115.880522) (xy 226.540238 -115.899817)
			(xy 226.54768 -115.907312) (xy 226.568506 -115.927095) (xy 226.604484 -115.971871) (xy 226.633345 -116.021534)
			(xy 226.654438 -116.074961) (xy 226.667286 -116.130946) (xy 226.668309 -116.144533) (xy 230.110137 -116.144533)
			(xy 230.114448 -116.087265) (xy 230.127291 -116.03129) (xy 230.148377 -115.977871) (xy 230.17723 -115.928215)
			(xy 230.213198 -115.883444) (xy 230.233982 -115.863624) (xy 230.241372 -115.856093) (xy 230.249904 -115.83682)
			(xy 230.250492 -115.826286) (xy 230.250492 -115.75161) (xy 230.249973 -115.741059) (xy 230.241431 -115.721764)
			(xy 230.233982 -115.714272) (xy 230.213242 -115.694404) (xy 230.177267 -115.649638) (xy 230.148405 -115.599988)
			(xy 230.12731 -115.546573) (xy 230.114457 -115.4906) (xy 230.110137 -115.433333) (xy 230.114448 -115.376065)
			(xy 230.127291 -115.32009) (xy 230.148377 -115.266671) (xy 230.17723 -115.217015) (xy 230.213198 -115.172244)
			(xy 230.233982 -115.152424) (xy 230.241372 -115.144893) (xy 230.249904 -115.12562) (xy 230.250492 -115.115086)
			(xy 230.250492 -115.04041) (xy 230.249973 -115.029859) (xy 230.241431 -115.010564) (xy 230.233982 -115.003072)
			(xy 230.214916 -114.984927) (xy 230.181461 -114.944294) (xy 230.153904 -114.899452) (xy 230.132767 -114.851249)
			(xy 230.118452 -114.8006) (xy 230.111229 -114.748465) (xy 230.110792 -114.722148) (xy 230.1113 -114.694896)
			(xy 230.11905 -114.640947) (xy 230.1344 -114.58865) (xy 230.157037 -114.53907) (xy 230.1865 -114.493217)
			(xy 230.222189 -114.452023) (xy 230.263378 -114.416329) (xy 230.309228 -114.38686) (xy 230.358805 -114.364217)
			(xy 230.4111 -114.348861) (xy 230.465048 -114.341103) (xy 230.4923 -114.34064) (xy 230.518615 -114.341095)
			(xy 230.570744 -114.34833) (xy 230.621388 -114.362651) (xy 230.669587 -114.383786) (xy 230.71443 -114.411335)
			(xy 230.755068 -114.444777) (xy 230.773224 -114.46383) (xy 230.780744 -114.471234) (xy 230.800025 -114.479759)
			(xy 230.810562 -114.48034) (xy 230.885238 -114.48034) (xy 230.895784 -114.479779) (xy 230.915079 -114.471265)
			(xy 230.922576 -114.46383) (xy 230.940756 -114.444799) (xy 230.98138 -114.411338) (xy 231.026215 -114.383775)
			(xy 231.074411 -114.362632) (xy 231.125054 -114.34831) (xy 231.177185 -114.341081) (xy 231.2035 -114.34064)
			(xy 231.230755 -114.341055) (xy 231.28471 -114.348814) (xy 231.337012 -114.364172) (xy 231.386595 -114.386818)
			(xy 231.426389 -114.412395) (xy 232.727135 -114.412395) (xy 232.727135 -114.360405) (xy 232.735269 -114.309056)
			(xy 232.751336 -114.259612) (xy 232.774941 -114.21329) (xy 232.805502 -114.171231) (xy 232.842266 -114.134472)
			(xy 232.884329 -114.103917) (xy 232.930654 -114.080318) (xy 232.980101 -114.064258) (xy 233.031451 -114.056132)
			(xy 233.057446 -114.055652) (xy 233.084091 -114.056131) (xy 233.136694 -114.064663) (xy 233.187244 -114.081529)
			(xy 233.234431 -114.106293) (xy 233.277029 -114.138312) (xy 233.313934 -114.176754) (xy 233.32948 -114.1984)
			(xy 233.337844 -114.209686) (xy 233.359517 -114.227541) (xy 233.385231 -114.238824) (xy 233.413046 -114.242682)
			(xy 233.440861 -114.238824) (xy 233.466575 -114.227541) (xy 233.488248 -114.209686) (xy 233.496612 -114.1984)
			(xy 233.512202 -114.176793) (xy 233.549115 -114.138375) (xy 233.59171 -114.106373) (xy 233.638886 -114.081616)
			(xy 233.689421 -114.064743) (xy 233.742007 -114.056191) (xy 233.768646 -114.055652) (xy 233.794628 -114.056245)
			(xy 233.84595 -114.064381) (xy 233.895369 -114.080444) (xy 233.941666 -114.104039) (xy 233.983703 -114.134586)
			(xy 234.020444 -114.171332) (xy 234.050985 -114.213373) (xy 234.074574 -114.259674) (xy 234.09063 -114.309095)
			(xy 234.098758 -114.360418) (xy 234.098758 -114.412382) (xy 234.09063 -114.463705) (xy 234.074574 -114.513126)
			(xy 234.050985 -114.559427) (xy 234.020444 -114.601468) (xy 233.983703 -114.638214) (xy 233.941666 -114.668761)
			(xy 233.895369 -114.692356) (xy 233.84595 -114.708419) (xy 233.794628 -114.716555) (xy 233.768646 -114.717068)
			(xy 233.742001 -114.716586) (xy 233.689399 -114.708054) (xy 233.638849 -114.691187) (xy 233.591663 -114.666424)
			(xy 233.549064 -114.634406) (xy 233.512158 -114.595965) (xy 233.496612 -114.57432) (xy 233.488248 -114.563034)
			(xy 233.466575 -114.545179) (xy 233.440861 -114.533896) (xy 233.413046 -114.530038) (xy 233.385231 -114.533896)
			(xy 233.359517 -114.545179) (xy 233.337844 -114.563034) (xy 233.32948 -114.57432) (xy 233.3139 -114.595935)
			(xy 233.276985 -114.634351) (xy 233.234387 -114.666352) (xy 233.18721 -114.691108) (xy 233.136673 -114.707979)
			(xy 233.084085 -114.716529) (xy 233.057446 -114.717068) (xy 233.031451 -114.716668) (xy 232.980101 -114.708542)
			(xy 232.930654 -114.692482) (xy 232.884329 -114.668883) (xy 232.842266 -114.638328) (xy 232.805502 -114.601569)
			(xy 232.774941 -114.55951) (xy 232.751336 -114.513188) (xy 232.735269 -114.463744) (xy 232.727135 -114.412395)
			(xy 231.426389 -114.412395) (xy 231.432451 -114.416291) (xy 231.473645 -114.451989) (xy 231.509338 -114.493188)
			(xy 231.538805 -114.539047) (xy 231.561445 -114.588633) (xy 231.576797 -114.640937) (xy 231.584548 -114.694893)
			(xy 231.585008 -114.722148) (xy 231.58457 -114.748463) (xy 231.577329 -114.800593) (xy 231.563004 -114.851236)
			(xy 231.541866 -114.899435) (xy 231.514315 -114.944277) (xy 231.480872 -114.984916) (xy 231.461818 -115.003072)
			(xy 231.454429 -115.010604) (xy 231.445897 -115.029876) (xy 231.445308 -115.04041) (xy 231.445308 -115.115086)
			(xy 231.445829 -115.125637) (xy 231.45437 -115.144932) (xy 231.461818 -115.152424) (xy 231.482654 -115.172196)
			(xy 231.518629 -115.216975) (xy 231.547487 -115.26664) (xy 231.565585 -115.312489) (xy 232.727211 -115.312489)
			(xy 232.727211 -115.260511) (xy 232.735343 -115.209174) (xy 232.751406 -115.159741) (xy 232.775005 -115.113429)
			(xy 232.805559 -115.071381) (xy 232.842316 -115.034629) (xy 232.884369 -115.004081) (xy 232.930683 -114.980489)
			(xy 232.980119 -114.964432) (xy 233.031457 -114.956308) (xy 233.057446 -114.955828) (xy 233.084091 -114.956318)
			(xy 233.136692 -114.964848) (xy 233.187242 -114.981713) (xy 233.234428 -115.006475) (xy 233.277027 -115.038492)
			(xy 233.313933 -115.076932) (xy 233.32948 -115.098576) (xy 233.337844 -115.109862) (xy 233.359517 -115.127717)
			(xy 233.385231 -115.139) (xy 233.413046 -115.142858) (xy 233.440861 -115.139) (xy 233.466575 -115.127717)
			(xy 233.488248 -115.109862) (xy 233.496612 -115.098576) (xy 233.512195 -115.076964) (xy 233.54911 -115.038547)
			(xy 233.591707 -115.006547) (xy 233.638884 -114.98179) (xy 233.68942 -114.964918) (xy 233.742007 -114.956367)
			(xy 233.768646 -114.955828) (xy 233.794634 -114.956269) (xy 233.845968 -114.964406) (xy 233.895398 -114.980473)
			(xy 233.941706 -115.004074) (xy 233.983753 -115.034628) (xy 234.020502 -115.071383) (xy 234.05105 -115.113433)
			(xy 234.074645 -115.159745) (xy 234.090705 -115.209177) (xy 234.098835 -115.260512) (xy 234.098835 -115.312488)
			(xy 234.090704 -115.363823) (xy 234.074645 -115.413255) (xy 234.05105 -115.459567) (xy 234.020502 -115.501617)
			(xy 233.983753 -115.538372) (xy 233.941706 -115.568926) (xy 233.895398 -115.592527) (xy 233.845968 -115.608594)
			(xy 233.794634 -115.616731) (xy 233.768646 -115.617244) (xy 233.742 -115.616772) (xy 233.689397 -115.608239)
			(xy 233.638847 -115.591372) (xy 233.59166 -115.566606) (xy 233.549062 -115.534586) (xy 233.512158 -115.496142)
			(xy 233.496612 -115.474496) (xy 233.488248 -115.46321) (xy 233.466575 -115.445355) (xy 233.440861 -115.434072)
			(xy 233.413046 -115.430214) (xy 233.385231 -115.434072) (xy 233.359517 -115.445355) (xy 233.337844 -115.46321)
			(xy 233.32948 -115.474496) (xy 233.313923 -115.496128) (xy 233.277 -115.53454) (xy 233.234397 -115.566536)
			(xy 233.187215 -115.591288) (xy 233.136676 -115.608157) (xy 233.084086 -115.616705) (xy 233.057446 -115.617244)
			(xy 233.031457 -115.616692) (xy 232.980119 -115.608568) (xy 232.930683 -115.592511) (xy 232.884369 -115.568919)
			(xy 232.842316 -115.538371) (xy 232.805559 -115.501619) (xy 232.775005 -115.45957) (xy 232.751406 -115.413259)
			(xy 232.735343 -115.363826) (xy 232.727211 -115.312489) (xy 231.565585 -115.312489) (xy 231.568577 -115.320069)
			(xy 231.581422 -115.376054) (xy 231.585733 -115.433333) (xy 231.581413 -115.49061) (xy 231.568557 -115.546594)
			(xy 231.547458 -115.600018) (xy 231.518592 -115.649678) (xy 231.482609 -115.694452) (xy 231.461818 -115.714272)
			(xy 231.454429 -115.721804) (xy 231.445897 -115.741076) (xy 231.445308 -115.75161) (xy 231.445308 -115.826286)
			(xy 231.445829 -115.836837) (xy 231.45437 -115.856132) (xy 231.461818 -115.863624) (xy 231.482654 -115.883396)
			(xy 231.518629 -115.928175) (xy 231.547487 -115.97784) (xy 231.568577 -116.031269) (xy 231.581422 -116.087254)
			(xy 231.585733 -116.144533) (xy 231.581413 -116.20181) (xy 231.578959 -116.212495) (xy 232.727133 -116.212495)
			(xy 232.727133 -116.160505) (xy 232.735267 -116.109156) (xy 232.751334 -116.059711) (xy 232.774939 -116.013389)
			(xy 232.8055 -115.97133) (xy 232.842265 -115.93457) (xy 232.884328 -115.904015) (xy 232.930653 -115.880417)
			(xy 232.9801 -115.864356) (xy 233.031451 -115.85623) (xy 233.057446 -115.85575) (xy 233.084091 -115.85623)
			(xy 233.136694 -115.864762) (xy 233.187244 -115.881628) (xy 233.23443 -115.906392) (xy 233.277029 -115.93841)
			(xy 233.313934 -115.976852) (xy 233.32948 -115.998498) (xy 233.337844 -116.009784) (xy 233.359517 -116.027639)
			(xy 233.385231 -116.038922) (xy 233.413046 -116.04278) (xy 233.440861 -116.038922) (xy 233.466575 -116.027639)
			(xy 233.488248 -116.009784) (xy 233.496612 -115.998498) (xy 233.512202 -115.976891) (xy 233.549115 -115.938473)
			(xy 233.59171 -115.906471) (xy 233.638886 -115.881714) (xy 233.689421 -115.864841) (xy 233.742007 -115.856289)
			(xy 233.768646 -115.85575) (xy 233.794627 -115.856347) (xy 233.84595 -115.864483) (xy 233.895368 -115.880546)
			(xy 233.941665 -115.904141) (xy 233.983702 -115.934687) (xy 233.985283 -115.936268) (xy 235.270546 -115.936268)
			(xy 235.274617 -115.880646) (xy 235.286743 -115.826209) (xy 235.306666 -115.774118) (xy 235.333962 -115.725483)
			(xy 235.368048 -115.68134) (xy 235.408197 -115.642631) (xy 235.453555 -115.61018) (xy 235.503155 -115.584679)
			(xy 235.555939 -115.566672) (xy 235.610782 -115.556542) (xy 235.666516 -115.554505) (xy 235.721953 -115.560605)
			(xy 235.77591 -115.574711) (xy 235.827239 -115.596523) (xy 235.874845 -115.625577) (xy 235.917713 -115.661252)
			(xy 235.95493 -115.702789) (xy 235.985703 -115.749302) (xy 236.009375 -115.799799) (xy 236.025443 -115.853206)
			(xy 236.033563 -115.908382) (xy 236.034072 -115.936268) (xy 236.033563 -115.964154) (xy 236.025443 -116.01933)
			(xy 236.009375 -116.072737) (xy 235.985703 -116.123234) (xy 235.95493 -116.169747) (xy 235.917713 -116.211284)
			(xy 235.874845 -116.246959) (xy 235.827239 -116.276013) (xy 235.77591 -116.297825) (xy 235.721953 -116.311931)
			(xy 235.666516 -116.318031) (xy 235.610782 -116.315994) (xy 235.555939 -116.305864) (xy 235.503155 -116.287857)
			(xy 235.453555 -116.262356) (xy 235.408197 -116.229905) (xy 235.368048 -116.191196) (xy 235.333962 -116.147053)
			(xy 235.306666 -116.098418) (xy 235.286743 -116.046327) (xy 235.274617 -115.99189) (xy 235.270546 -115.936268)
			(xy 233.985283 -115.936268) (xy 234.020442 -115.971434) (xy 234.050983 -116.013474) (xy 234.074572 -116.059775)
			(xy 234.090628 -116.109195) (xy 234.098756 -116.160518) (xy 234.098756 -116.212482) (xy 234.090628 -116.263805)
			(xy 234.074572 -116.313225) (xy 234.050983 -116.359526) (xy 234.020442 -116.401566) (xy 233.983702 -116.438313)
			(xy 233.970963 -116.44757) (xy 236.707678 -116.44757) (xy 236.711749 -116.391948) (xy 236.723875 -116.337511)
			(xy 236.743798 -116.28542) (xy 236.771094 -116.236785) (xy 236.80518 -116.192642) (xy 236.845329 -116.153933)
			(xy 236.890687 -116.121482) (xy 236.940287 -116.095981) (xy 236.993071 -116.077974) (xy 237.047914 -116.067844)
			(xy 237.103648 -116.065807) (xy 237.159085 -116.071907) (xy 237.213042 -116.086013) (xy 237.264371 -116.107825)
			(xy 237.311977 -116.136879) (xy 237.354845 -116.172554) (xy 237.392062 -116.214091) (xy 237.422835 -116.260604)
			(xy 237.446507 -116.311101) (xy 237.462575 -116.364508) (xy 237.470695 -116.419684) (xy 237.471204 -116.44757)
			(xy 237.471153 -116.450364) (xy 244.161308 -116.450364) (xy 244.165379 -116.394742) (xy 244.177505 -116.340305)
			(xy 244.197428 -116.288214) (xy 244.224724 -116.239579) (xy 244.25881 -116.195436) (xy 244.298959 -116.156727)
			(xy 244.344317 -116.124276) (xy 244.393917 -116.098775) (xy 244.446701 -116.080768) (xy 244.501544 -116.070638)
			(xy 244.557278 -116.068601) (xy 244.612715 -116.074701) (xy 244.666672 -116.088807) (xy 244.718001 -116.110619)
			(xy 244.765607 -116.139673) (xy 244.808475 -116.175348) (xy 244.845692 -116.216885) (xy 244.876465 -116.263398)
			(xy 244.900137 -116.313895) (xy 244.916205 -116.367302) (xy 244.924325 -116.422478) (xy 244.924834 -116.450364)
			(xy 244.924325 -116.47825) (xy 244.916205 -116.533426) (xy 244.900137 -116.586833) (xy 244.876465 -116.63733)
			(xy 244.845692 -116.683843) (xy 244.808475 -116.72538) (xy 244.765607 -116.761055) (xy 244.718001 -116.790109)
			(xy 244.666672 -116.811921) (xy 244.612715 -116.826027) (xy 244.557278 -116.832127) (xy 244.501544 -116.83009)
			(xy 244.446701 -116.81996) (xy 244.393917 -116.801953) (xy 244.344317 -116.776452) (xy 244.298959 -116.744001)
			(xy 244.25881 -116.705292) (xy 244.224724 -116.661149) (xy 244.197428 -116.612514) (xy 244.177505 -116.560423)
			(xy 244.165379 -116.505986) (xy 244.161308 -116.450364) (xy 237.471153 -116.450364) (xy 237.470695 -116.475456)
			(xy 237.462575 -116.530632) (xy 237.446507 -116.584039) (xy 237.422835 -116.634536) (xy 237.392062 -116.681049)
			(xy 237.354845 -116.722586) (xy 237.311977 -116.758261) (xy 237.264371 -116.787315) (xy 237.213042 -116.809127)
			(xy 237.159085 -116.823233) (xy 237.103648 -116.829333) (xy 237.047914 -116.827296) (xy 236.993071 -116.817166)
			(xy 236.940287 -116.799159) (xy 236.890687 -116.773658) (xy 236.845329 -116.741207) (xy 236.80518 -116.702498)
			(xy 236.771094 -116.658355) (xy 236.743798 -116.60972) (xy 236.723875 -116.557629) (xy 236.711749 -116.503192)
			(xy 236.707678 -116.44757) (xy 233.970963 -116.44757) (xy 233.941665 -116.468859) (xy 233.895368 -116.492454)
			(xy 233.84595 -116.508517) (xy 233.794627 -116.516653) (xy 233.768646 -116.517166) (xy 233.742001 -116.516685)
			(xy 233.689399 -116.508153) (xy 233.638849 -116.491286) (xy 233.591663 -116.466523) (xy 233.549064 -116.434505)
			(xy 233.512158 -116.396063) (xy 233.496612 -116.374418) (xy 233.488248 -116.363132) (xy 233.466575 -116.345277)
			(xy 233.440861 -116.333994) (xy 233.413046 -116.330136) (xy 233.385231 -116.333994) (xy 233.359517 -116.345277)
			(xy 233.337844 -116.363132) (xy 233.32948 -116.374418) (xy 233.3139 -116.396033) (xy 233.276984 -116.434449)
			(xy 233.234387 -116.46645) (xy 233.187209 -116.491206) (xy 233.136673 -116.508077) (xy 233.084085 -116.516627)
			(xy 233.057446 -116.517166) (xy 233.031451 -116.51677) (xy 232.9801 -116.508644) (xy 232.930654 -116.492583)
			(xy 232.884328 -116.468985) (xy 232.842265 -116.43843) (xy 232.8055 -116.40167) (xy 232.774939 -116.359611)
			(xy 232.751334 -116.313289) (xy 232.735267 -116.263844) (xy 232.727133 -116.212495) (xy 231.578959 -116.212495)
			(xy 231.568557 -116.257794) (xy 231.547458 -116.311218) (xy 231.518592 -116.360878) (xy 231.482609 -116.405652)
			(xy 231.461818 -116.425472) (xy 231.454429 -116.433004) (xy 231.445897 -116.452276) (xy 231.445308 -116.46281)
			(xy 231.445308 -116.537486) (xy 231.445829 -116.548037) (xy 231.45437 -116.567332) (xy 231.461818 -116.574824)
			(xy 231.480882 -116.592971) (xy 231.514337 -116.633603) (xy 231.541895 -116.678445) (xy 231.563032 -116.726648)
			(xy 231.577347 -116.777296) (xy 231.58457 -116.829431) (xy 231.585008 -116.855748) (xy 231.584567 -116.883)
			(xy 231.576804 -116.93695) (xy 231.561443 -116.989245) (xy 231.538796 -117.038823) (xy 231.509325 -117.084673)
			(xy 231.485302 -117.112393) (xy 232.727155 -117.112393) (xy 232.727155 -117.060407) (xy 232.735289 -117.009061)
			(xy 232.751355 -116.959619) (xy 232.774958 -116.9133) (xy 232.805517 -116.871244) (xy 232.842279 -116.834487)
			(xy 232.88434 -116.803934) (xy 232.930662 -116.780337) (xy 232.980106 -116.764278) (xy 233.031453 -116.756152)
			(xy 233.057446 -116.755672) (xy 233.084092 -116.756143) (xy 233.136695 -116.764675) (xy 233.187246 -116.781542)
			(xy 233.234433 -116.806308) (xy 233.277031 -116.838328) (xy 233.313935 -116.876773) (xy 233.32948 -116.89842)
			(xy 233.337844 -116.909706) (xy 233.359517 -116.927561) (xy 233.385231 -116.938844) (xy 233.413046 -116.942702)
			(xy 233.440861 -116.938844) (xy 233.466575 -116.927561) (xy 233.488248 -116.909706) (xy 233.496612 -116.89842)
			(xy 233.512179 -116.876796) (xy 233.549099 -116.838383) (xy 233.5917 -116.806385) (xy 233.63888 -116.781631)
			(xy 233.689418 -116.764761) (xy 233.742006 -116.756211) (xy 233.768646 -116.755672) (xy 233.794629 -116.756225)
			(xy 233.845955 -116.764361) (xy 233.895376 -116.780425) (xy 233.941677 -116.804022) (xy 233.983716 -116.83457)
			(xy 234.02046 -116.871319) (xy 234.051002 -116.913362) (xy 234.074593 -116.959666) (xy 234.09065 -117.00909)
			(xy 234.098779 -117.060417) (xy 234.098779 -117.112383) (xy 234.09065 -117.16371) (xy 234.074593 -117.213134)
			(xy 234.051002 -117.259438) (xy 234.02046 -117.301481) (xy 233.983716 -117.33823) (xy 233.941677 -117.368778)
			(xy 233.895376 -117.392375) (xy 233.845955 -117.408439) (xy 233.794629 -117.416575) (xy 233.768646 -117.417088)
			(xy 233.742001 -117.416597) (xy 233.6894 -117.408066) (xy 233.638851 -117.391201) (xy 233.591665 -117.366439)
			(xy 233.549066 -117.334423) (xy 233.512159 -117.295984) (xy 233.496612 -117.27434) (xy 233.488248 -117.263054)
			(xy 233.466575 -117.245199) (xy 233.440861 -117.233916) (xy 233.413046 -117.230058) (xy 233.385231 -117.233916)
			(xy 233.359517 -117.245199) (xy 233.337844 -117.263054) (xy 233.32948 -117.27434) (xy 233.313906 -117.295959)
			(xy 233.276989 -117.334375) (xy 233.23439 -117.366374) (xy 233.187211 -117.391129) (xy 233.136674 -117.408)
			(xy 233.084085 -117.416549) (xy 233.057446 -117.417088) (xy 233.031453 -117.416648) (xy 232.980106 -117.408522)
			(xy 232.930662 -117.392463) (xy 232.88434 -117.368866) (xy 232.842279 -117.338313) (xy 232.805517 -117.301556)
			(xy 232.774958 -117.2595) (xy 232.751355 -117.213181) (xy 232.735289 -117.163739) (xy 232.727155 -117.112393)
			(xy 231.485302 -117.112393) (xy 231.473629 -117.125863) (xy 231.432434 -117.161553) (xy 231.386581 -117.191019)
			(xy 231.337 -117.213659) (xy 231.284703 -117.229014) (xy 231.230752 -117.23677) (xy 231.2035 -117.237256)
			(xy 231.177185 -117.236803) (xy 231.125056 -117.229567) (xy 231.074412 -117.215246) (xy 231.026213 -117.194111)
			(xy 230.98137 -117.166562) (xy 230.940732 -117.133119) (xy 230.922576 -117.114066) (xy 230.915056 -117.106662)
			(xy 230.895775 -117.098136) (xy 230.885238 -117.097556) (xy 230.810562 -117.097556) (xy 230.800017 -117.098118)
			(xy 230.780722 -117.106632) (xy 230.773224 -117.114066) (xy 230.755063 -117.133116) (xy 230.714433 -117.166571)
			(xy 230.669593 -117.194129) (xy 230.621394 -117.215268) (xy 230.570748 -117.229587) (xy 230.518616 -117.236815)
			(xy 230.4923 -117.237256) (xy 230.465051 -117.236722) (xy 230.411107 -117.228967) (xy 230.358816 -117.213614)
			(xy 230.309242 -117.190977) (xy 230.263394 -117.161515) (xy 230.222205 -117.125829) (xy 230.186514 -117.084644)
			(xy 230.157046 -117.0388) (xy 230.134402 -116.989229) (xy 230.119043 -116.93694) (xy 230.111281 -116.882997)
			(xy 230.110792 -116.855748) (xy 230.111227 -116.829433) (xy 230.118469 -116.777303) (xy 230.132795 -116.72666)
			(xy 230.153933 -116.678461) (xy 230.181485 -116.633618) (xy 230.214928 -116.59298) (xy 230.233982 -116.574824)
			(xy 230.241372 -116.567293) (xy 230.249904 -116.54802) (xy 230.250492 -116.537486) (xy 230.250492 -116.46281)
			(xy 230.249973 -116.452259) (xy 230.241431 -116.432964) (xy 230.233982 -116.425472) (xy 230.213242 -116.405604)
			(xy 230.177267 -116.360838) (xy 230.148405 -116.311188) (xy 230.12731 -116.257773) (xy 230.114457 -116.2018)
			(xy 230.110137 -116.144533) (xy 226.668309 -116.144533) (xy 226.671599 -116.188224) (xy 226.667279 -116.245502)
			(xy 226.654424 -116.301485) (xy 226.633324 -116.35491) (xy 226.604456 -116.404569) (xy 226.568472 -116.449341)
			(xy 226.54768 -116.46916) (xy 226.540291 -116.476692) (xy 226.53176 -116.495964) (xy 226.53117 -116.506498)
			(xy 226.53117 -116.581174) (xy 226.531708 -116.591722) (xy 226.540238 -116.611017) (xy 226.54768 -116.618512)
			(xy 226.566731 -116.636673) (xy 226.600189 -116.677301) (xy 226.627749 -116.72214) (xy 226.648889 -116.77034)
			(xy 226.663207 -116.820987) (xy 226.670432 -116.87312) (xy 226.67087 -116.899436) (xy 226.670384 -116.926687)
			(xy 226.662628 -116.980635) (xy 226.647273 -117.03293) (xy 226.624631 -117.082507) (xy 226.595165 -117.128357)
			(xy 226.559474 -117.169548) (xy 226.518283 -117.205239) (xy 226.472433 -117.234705) (xy 226.422856 -117.257347)
			(xy 226.370561 -117.272702) (xy 226.316613 -117.280458) (xy 226.262111 -117.280458) (xy 226.208163 -117.272702)
			(xy 226.155868 -117.257347) (xy 226.106291 -117.234705) (xy 226.060441 -117.205239) (xy 226.01925 -117.169548)
			(xy 225.983559 -117.128357) (xy 225.954093 -117.082507) (xy 225.931451 -117.03293) (xy 225.916096 -116.980635)
			(xy 225.90834 -116.926687) (xy 225.907854 -116.899436) (xy 225.908262 -116.87312) (xy 225.915506 -116.820988)
			(xy 225.929836 -116.770343) (xy 225.950979 -116.722144) (xy 225.978537 -116.677302) (xy 226.011987 -116.636666)
			(xy 226.031044 -116.618512) (xy 226.038434 -116.61098) (xy 226.046967 -116.591708) (xy 226.047554 -116.581174)
			(xy 226.047554 -116.506498) (xy 226.047053 -116.495945) (xy 226.0385 -116.476649) (xy 226.031044 -116.46916)
			(xy 226.010294 -116.449303) (xy 225.974322 -116.404534) (xy 225.945464 -116.354882) (xy 225.924372 -116.301465)
			(xy 225.911521 -116.245492) (xy 225.907203 -116.188224) (xy 224.133352 -116.188224) (xy 224.129033 -116.2455)
			(xy 224.11618 -116.301481) (xy 224.095085 -116.354905) (xy 224.066223 -116.404564) (xy 224.030247 -116.449339)
			(xy 224.009458 -116.46916) (xy 224.002081 -116.476702) (xy 223.99354 -116.495966) (xy 223.992948 -116.506498)
			(xy 223.992948 -116.581174) (xy 223.993464 -116.591726) (xy 224.002007 -116.611022) (xy 224.009458 -116.618512)
			(xy 224.028523 -116.636657) (xy 224.061977 -116.677291) (xy 224.089534 -116.722133) (xy 224.11067 -116.770336)
			(xy 224.124986 -116.820985) (xy 224.13221 -116.873119) (xy 224.132648 -116.899436) (xy 224.132162 -116.926687)
			(xy 224.124406 -116.980635) (xy 224.109051 -117.03293) (xy 224.086409 -117.082507) (xy 224.056943 -117.128357)
			(xy 224.021252 -117.169548) (xy 223.980061 -117.205239) (xy 223.934211 -117.234705) (xy 223.884634 -117.257347)
			(xy 223.832339 -117.272702) (xy 223.778391 -117.280458) (xy 223.723889 -117.280458) (xy 223.669941 -117.272702)
			(xy 223.617646 -117.257347) (xy 223.568069 -117.234705) (xy 223.522219 -117.205239) (xy 223.481028 -117.169548)
			(xy 223.445337 -117.128357) (xy 223.415871 -117.082507) (xy 223.393229 -117.03293) (xy 223.377874 -116.980635)
			(xy 223.370118 -116.926687) (xy 223.369632 -116.899436) (xy 223.370047 -116.87312) (xy 223.377291 -116.820989)
			(xy 223.39162 -116.770345) (xy 223.412762 -116.722146) (xy 223.440318 -116.677304) (xy 223.473766 -116.636667)
			(xy 223.492822 -116.618512) (xy 223.500224 -116.610991) (xy 223.508747 -116.59171) (xy 223.509332 -116.581174)
			(xy 223.509332 -116.506498) (xy 223.508808 -116.495948) (xy 223.500268 -116.476653) (xy 223.492822 -116.46916)
			(xy 223.472068 -116.449305) (xy 223.436089 -116.404539) (xy 223.407225 -116.354887) (xy 223.386128 -116.30147)
			(xy 223.373275 -116.245494) (xy 223.368955 -116.188224) (xy 212.341407 -116.188224) (xy 212.343458 -116.20006)
			(xy 212.344 -116.226336) (xy 212.344 -117.191028) (xy 213.616792 -117.191028) (xy 213.620863 -117.135406)
			(xy 213.632989 -117.080969) (xy 213.652912 -117.028878) (xy 213.680208 -116.980243) (xy 213.714294 -116.9361)
			(xy 213.754443 -116.897391) (xy 213.799801 -116.86494) (xy 213.849401 -116.839439) (xy 213.902185 -116.821432)
			(xy 213.957028 -116.811302) (xy 214.012762 -116.809265) (xy 214.068199 -116.815365) (xy 214.122156 -116.829471)
			(xy 214.173485 -116.851283) (xy 214.221091 -116.880337) (xy 214.263959 -116.916012) (xy 214.301176 -116.957549)
			(xy 214.331949 -117.004062) (xy 214.355621 -117.054559) (xy 214.371689 -117.107966) (xy 214.379809 -117.163142)
			(xy 214.380318 -117.191028) (xy 215.704164 -117.191028) (xy 215.708235 -117.135406) (xy 215.720361 -117.080969)
			(xy 215.740284 -117.028878) (xy 215.76758 -116.980243) (xy 215.801666 -116.9361) (xy 215.841815 -116.897391)
			(xy 215.887173 -116.86494) (xy 215.936773 -116.839439) (xy 215.989557 -116.821432) (xy 216.0444 -116.811302)
			(xy 216.100134 -116.809265) (xy 216.155571 -116.815365) (xy 216.209528 -116.829471) (xy 216.260857 -116.851283)
			(xy 216.308463 -116.880337) (xy 216.351331 -116.916012) (xy 216.388548 -116.957549) (xy 216.419321 -117.004062)
			(xy 216.442993 -117.054559) (xy 216.459061 -117.107966) (xy 216.467181 -117.163142) (xy 216.46769 -117.191028)
			(xy 216.467181 -117.218914) (xy 216.459061 -117.27409) (xy 216.452796 -117.294914) (xy 216.75852 -117.294914)
			(xy 216.75899 -117.2686) (xy 216.766224 -117.216471) (xy 216.780542 -117.165828) (xy 216.801674 -117.117629)
			(xy 216.82922 -117.072786) (xy 216.862658 -117.032146) (xy 216.88171 -117.01399) (xy 216.88912 -117.006475)
			(xy 216.897639 -116.98719) (xy 216.89822 -116.976652) (xy 216.89822 -116.901976) (xy 216.897658 -116.89143)
			(xy 216.889145 -116.872135) (xy 216.88171 -116.864638) (xy 216.862633 -116.846504) (xy 216.829178 -116.80587)
			(xy 216.801621 -116.761025) (xy 216.780486 -116.71282) (xy 216.766174 -116.662169) (xy 216.758955 -116.610031)
			(xy 216.75852 -116.583714) (xy 216.759006 -116.556463) (xy 216.766762 -116.502515) (xy 216.782117 -116.45022)
			(xy 216.804759 -116.400643) (xy 216.834225 -116.354793) (xy 216.869916 -116.313602) (xy 216.911107 -116.277911)
			(xy 216.956957 -116.248445) (xy 217.006534 -116.225803) (xy 217.058829 -116.210448) (xy 217.112777 -116.202692)
			(xy 217.167279 -116.202692) (xy 217.221227 -116.210448) (xy 217.273522 -116.225803) (xy 217.323099 -116.248445)
			(xy 217.368949 -116.277911) (xy 217.41014 -116.313602) (xy 217.445831 -116.354793) (xy 217.475297 -116.400643)
			(xy 217.497939 -116.45022) (xy 217.513294 -116.502515) (xy 217.52105 -116.556463) (xy 217.521536 -116.583714)
			(xy 217.521066 -116.610028) (xy 217.51383 -116.662156) (xy 217.499511 -116.712798) (xy 217.478379 -116.760997)
			(xy 217.450834 -116.80584) (xy 217.417397 -116.846481) (xy 217.398346 -116.864638) (xy 217.390933 -116.87215)
			(xy 217.382413 -116.891437) (xy 217.381836 -116.901976) (xy 217.381836 -116.976652) (xy 217.382367 -116.987202)
			(xy 217.3909 -117.006498) (xy 217.398346 -117.01399) (xy 217.417398 -117.032148) (xy 217.450854 -117.072779)
			(xy 217.478412 -117.117619) (xy 217.499551 -117.165819) (xy 217.513869 -117.216465) (xy 217.521096 -117.268598)
			(xy 217.521536 -117.294914) (xy 218.79052 -117.294914) (xy 218.79099 -117.2686) (xy 218.798224 -117.216471)
			(xy 218.812542 -117.165828) (xy 218.833674 -117.117629) (xy 218.86122 -117.072786) (xy 218.894658 -117.032146)
			(xy 218.91371 -117.01399) (xy 218.92112 -117.006475) (xy 218.929639 -116.98719) (xy 218.93022 -116.976652)
			(xy 218.93022 -116.901976) (xy 218.929658 -116.89143) (xy 218.921145 -116.872135) (xy 218.91371 -116.864638)
			(xy 218.894633 -116.846504) (xy 218.861178 -116.80587) (xy 218.833621 -116.761025) (xy 218.812486 -116.71282)
			(xy 218.798174 -116.662169) (xy 218.790955 -116.610031) (xy 218.79052 -116.583714) (xy 218.791006 -116.556463)
			(xy 218.798762 -116.502515) (xy 218.814117 -116.45022) (xy 218.836759 -116.400643) (xy 218.866225 -116.354793)
			(xy 218.901916 -116.313602) (xy 218.943107 -116.277911) (xy 218.988957 -116.248445) (xy 219.038534 -116.225803)
			(xy 219.090829 -116.210448) (xy 219.144777 -116.202692) (xy 219.199279 -116.202692) (xy 219.253227 -116.210448)
			(xy 219.305522 -116.225803) (xy 219.355099 -116.248445) (xy 219.400949 -116.277911) (xy 219.44214 -116.313602)
			(xy 219.477831 -116.354793) (xy 219.507297 -116.400643) (xy 219.529939 -116.45022) (xy 219.545294 -116.502515)
			(xy 219.55305 -116.556463) (xy 219.553536 -116.583714) (xy 219.553066 -116.610028) (xy 219.54583 -116.662156)
			(xy 219.531511 -116.712798) (xy 219.510379 -116.760997) (xy 219.482834 -116.80584) (xy 219.449397 -116.846481)
			(xy 219.430346 -116.864638) (xy 219.422933 -116.87215) (xy 219.414413 -116.891437) (xy 219.413836 -116.901976)
			(xy 219.413836 -116.976652) (xy 219.414367 -116.987202) (xy 219.4229 -117.006498) (xy 219.430346 -117.01399)
			(xy 219.449398 -117.032148) (xy 219.482854 -117.072779) (xy 219.510412 -117.117619) (xy 219.531551 -117.165819)
			(xy 219.545869 -117.216465) (xy 219.553096 -117.268598) (xy 219.553536 -117.294914) (xy 220.82252 -117.294914)
			(xy 220.82299 -117.2686) (xy 220.830224 -117.216471) (xy 220.844542 -117.165828) (xy 220.865674 -117.117629)
			(xy 220.89322 -117.072786) (xy 220.926658 -117.032146) (xy 220.94571 -117.01399) (xy 220.95312 -117.006475)
			(xy 220.961639 -116.98719) (xy 220.96222 -116.976652) (xy 220.96222 -116.901976) (xy 220.961658 -116.89143)
			(xy 220.953145 -116.872135) (xy 220.94571 -116.864638) (xy 220.926633 -116.846504) (xy 220.893178 -116.80587)
			(xy 220.865621 -116.761025) (xy 220.844486 -116.71282) (xy 220.830174 -116.662169) (xy 220.822955 -116.610031)
			(xy 220.82252 -116.583714) (xy 220.823006 -116.556463) (xy 220.830762 -116.502515) (xy 220.846117 -116.45022)
			(xy 220.868759 -116.400643) (xy 220.898225 -116.354793) (xy 220.933916 -116.313602) (xy 220.975107 -116.277911)
			(xy 221.020957 -116.248445) (xy 221.070534 -116.225803) (xy 221.122829 -116.210448) (xy 221.176777 -116.202692)
			(xy 221.231279 -116.202692) (xy 221.285227 -116.210448) (xy 221.337522 -116.225803) (xy 221.387099 -116.248445)
			(xy 221.432949 -116.277911) (xy 221.47414 -116.313602) (xy 221.509831 -116.354793) (xy 221.539297 -116.400643)
			(xy 221.561939 -116.45022) (xy 221.577294 -116.502515) (xy 221.58505 -116.556463) (xy 221.585536 -116.583714)
			(xy 221.585066 -116.610028) (xy 221.57783 -116.662156) (xy 221.563511 -116.712798) (xy 221.542379 -116.760997)
			(xy 221.514834 -116.80584) (xy 221.481397 -116.846481) (xy 221.462346 -116.864638) (xy 221.454933 -116.87215)
			(xy 221.446413 -116.891437) (xy 221.445836 -116.901976) (xy 221.445836 -116.976652) (xy 221.446367 -116.987202)
			(xy 221.4549 -117.006498) (xy 221.462346 -117.01399) (xy 221.481398 -117.032148) (xy 221.514854 -117.072779)
			(xy 221.542412 -117.117619) (xy 221.563551 -117.165819) (xy 221.577869 -117.216465) (xy 221.585096 -117.268598)
			(xy 221.585536 -117.294914) (xy 221.58505 -117.322165) (xy 221.577294 -117.376113) (xy 221.561939 -117.428408)
			(xy 221.539297 -117.477985) (xy 221.509831 -117.523835) (xy 221.47414 -117.565026) (xy 221.432949 -117.600717)
			(xy 221.387099 -117.630183) (xy 221.337522 -117.652825) (xy 221.285227 -117.66818) (xy 221.231279 -117.675936)
			(xy 221.176777 -117.675936) (xy 221.122829 -117.66818) (xy 221.070534 -117.652825) (xy 221.020957 -117.630183)
			(xy 220.975107 -117.600717) (xy 220.933916 -117.565026) (xy 220.898225 -117.523835) (xy 220.868759 -117.477985)
			(xy 220.846117 -117.428408) (xy 220.830762 -117.376113) (xy 220.823006 -117.322165) (xy 220.82252 -117.294914)
			(xy 219.553536 -117.294914) (xy 219.55305 -117.322165) (xy 219.545294 -117.376113) (xy 219.529939 -117.428408)
			(xy 219.507297 -117.477985) (xy 219.477831 -117.523835) (xy 219.44214 -117.565026) (xy 219.400949 -117.600717)
			(xy 219.355099 -117.630183) (xy 219.305522 -117.652825) (xy 219.253227 -117.66818) (xy 219.199279 -117.675936)
			(xy 219.144777 -117.675936) (xy 219.090829 -117.66818) (xy 219.038534 -117.652825) (xy 218.988957 -117.630183)
			(xy 218.943107 -117.600717) (xy 218.901916 -117.565026) (xy 218.866225 -117.523835) (xy 218.836759 -117.477985)
			(xy 218.814117 -117.428408) (xy 218.798762 -117.376113) (xy 218.791006 -117.322165) (xy 218.79052 -117.294914)
			(xy 217.521536 -117.294914) (xy 217.52105 -117.322165) (xy 217.513294 -117.376113) (xy 217.497939 -117.428408)
			(xy 217.475297 -117.477985) (xy 217.445831 -117.523835) (xy 217.41014 -117.565026) (xy 217.368949 -117.600717)
			(xy 217.323099 -117.630183) (xy 217.273522 -117.652825) (xy 217.221227 -117.66818) (xy 217.167279 -117.675936)
			(xy 217.112777 -117.675936) (xy 217.058829 -117.66818) (xy 217.006534 -117.652825) (xy 216.956957 -117.630183)
			(xy 216.911107 -117.600717) (xy 216.869916 -117.565026) (xy 216.834225 -117.523835) (xy 216.804759 -117.477985)
			(xy 216.782117 -117.428408) (xy 216.766762 -117.376113) (xy 216.759006 -117.322165) (xy 216.75852 -117.294914)
			(xy 216.452796 -117.294914) (xy 216.442993 -117.327497) (xy 216.419321 -117.377994) (xy 216.388548 -117.424507)
			(xy 216.351331 -117.466044) (xy 216.308463 -117.501719) (xy 216.260857 -117.530773) (xy 216.209528 -117.552585)
			(xy 216.155571 -117.566691) (xy 216.100134 -117.572791) (xy 216.0444 -117.570754) (xy 215.989557 -117.560624)
			(xy 215.936773 -117.542617) (xy 215.887173 -117.517116) (xy 215.841815 -117.484665) (xy 215.801666 -117.445956)
			(xy 215.76758 -117.401813) (xy 215.740284 -117.353178) (xy 215.720361 -117.301087) (xy 215.708235 -117.24665)
			(xy 215.704164 -117.191028) (xy 214.380318 -117.191028) (xy 214.379809 -117.218914) (xy 214.371689 -117.27409)
			(xy 214.355621 -117.327497) (xy 214.331949 -117.377994) (xy 214.301176 -117.424507) (xy 214.263959 -117.466044)
			(xy 214.221091 -117.501719) (xy 214.173485 -117.530773) (xy 214.122156 -117.552585) (xy 214.068199 -117.566691)
			(xy 214.012762 -117.572791) (xy 213.957028 -117.570754) (xy 213.902185 -117.560624) (xy 213.849401 -117.542617)
			(xy 213.799801 -117.517116) (xy 213.754443 -117.484665) (xy 213.714294 -117.445956) (xy 213.680208 -117.401813)
			(xy 213.652912 -117.353178) (xy 213.632989 -117.301087) (xy 213.620863 -117.24665) (xy 213.616792 -117.191028)
			(xy 212.344 -117.191028) (xy 212.344 -117.595904) (xy 212.343551 -117.619634) (xy 212.336255 -117.66653)
			(xy 212.321791 -117.711732) (xy 212.31797 -117.719348) (xy 236.702598 -117.719348) (xy 236.706669 -117.663726)
			(xy 236.718795 -117.609289) (xy 236.738718 -117.557198) (xy 236.766014 -117.508563) (xy 236.8001 -117.46442)
			(xy 236.840249 -117.425711) (xy 236.885607 -117.39326) (xy 236.935207 -117.367759) (xy 236.987991 -117.349752)
			(xy 237.042834 -117.339622) (xy 237.098568 -117.337585) (xy 237.154005 -117.343685) (xy 237.207962 -117.357791)
			(xy 237.259291 -117.379603) (xy 237.306897 -117.408657) (xy 237.349765 -117.444332) (xy 237.386982 -117.485869)
			(xy 237.417755 -117.532382) (xy 237.441427 -117.582879) (xy 237.457495 -117.636286) (xy 237.465615 -117.691462)
			(xy 237.466031 -117.714268) (xy 238.760252 -117.714268) (xy 238.764323 -117.658646) (xy 238.776449 -117.604209)
			(xy 238.796372 -117.552118) (xy 238.823668 -117.503483) (xy 238.857754 -117.45934) (xy 238.897903 -117.420631)
			(xy 238.943261 -117.38818) (xy 238.992861 -117.362679) (xy 239.045645 -117.344672) (xy 239.100488 -117.334542)
			(xy 239.156222 -117.332505) (xy 239.211659 -117.338605) (xy 239.265616 -117.352711) (xy 239.316945 -117.374523)
			(xy 239.364551 -117.403577) (xy 239.401235 -117.434106) (xy 245.576852 -117.434106) (xy 245.577309 -117.406735)
			(xy 245.585127 -117.352555) (xy 245.600618 -117.300052) (xy 245.623462 -117.250305) (xy 245.653189 -117.204339)
			(xy 245.670832 -117.183408) (xy 245.671086 -117.183154) (xy 245.676655 -117.176055) (xy 245.682913 -117.159148)
			(xy 245.683278 -117.150134) (xy 245.683278 -117.083078) (xy 245.682936 -117.074059) (xy 245.676679 -117.057142)
			(xy 245.671086 -117.050058) (xy 245.670832 -117.050058) (xy 245.670832 -117.049804) (xy 245.653197 -117.028867)
			(xy 245.623472 -116.9829) (xy 245.600626 -116.933154) (xy 245.585129 -116.880653) (xy 245.577299 -116.826475)
			(xy 245.577299 -116.771734) (xy 245.585127 -116.717556) (xy 245.600622 -116.665054) (xy 245.623467 -116.615308)
			(xy 245.653192 -116.569341) (xy 245.670832 -116.548408) (xy 245.671086 -116.548154) (xy 245.676655 -116.541055)
			(xy 245.682913 -116.524148) (xy 245.683278 -116.515134) (xy 245.683278 -116.448078) (xy 245.682936 -116.439059)
			(xy 245.676679 -116.422142) (xy 245.671086 -116.415058) (xy 245.670832 -116.415058) (xy 245.670832 -116.414804)
			(xy 245.653186 -116.393877) (xy 245.623474 -116.347903) (xy 245.600639 -116.298155) (xy 245.58515 -116.245653)
			(xy 245.577324 -116.191476) (xy 245.576852 -116.164106) (xy 245.577383 -116.136857) (xy 245.585138 -116.082913)
			(xy 245.60049 -116.030621) (xy 245.623128 -115.981047) (xy 245.65259 -115.935198) (xy 245.688276 -115.894009)
			(xy 245.729461 -115.858317) (xy 245.775306 -115.82885) (xy 245.824878 -115.806206) (xy 245.877168 -115.790848)
			(xy 245.931111 -115.783087) (xy 245.95836 -115.782598) (xy 245.985729 -115.783088) (xy 246.039907 -115.7909)
			(xy 246.09241 -115.806384) (xy 246.142157 -115.82922) (xy 246.188125 -115.858939) (xy 246.209058 -115.876578)
			(xy 246.209312 -115.876832) (xy 246.216388 -115.882433) (xy 246.233313 -115.88867) (xy 246.242332 -115.889024)
			(xy 246.309388 -115.889024) (xy 246.318404 -115.888656) (xy 246.33532 -115.882415) (xy 246.342408 -115.876832)
			(xy 246.342408 -115.876578) (xy 246.342662 -115.876578) (xy 246.363595 -115.85894) (xy 246.409568 -115.829229)
			(xy 246.459315 -115.806393) (xy 246.511815 -115.790901) (xy 246.565991 -115.783073) (xy 246.59336 -115.782598)
			(xy 246.620612 -115.783093) (xy 246.674562 -115.790844) (xy 246.72686 -115.806195) (xy 246.77644 -115.828834)
			(xy 246.822294 -115.858298) (xy 246.863487 -115.893989) (xy 246.899181 -115.935179) (xy 246.92865 -115.98103)
			(xy 246.951293 -116.030608) (xy 246.966649 -116.082904) (xy 246.974405 -116.136854) (xy 246.974868 -116.164106)
			(xy 246.974413 -116.191477) (xy 246.966594 -116.245657) (xy 246.951103 -116.29816) (xy 246.928258 -116.347907)
			(xy 246.898531 -116.393873) (xy 246.880888 -116.414804) (xy 246.880634 -116.415058) (xy 246.875051 -116.422147)
			(xy 246.868804 -116.439062) (xy 246.868442 -116.448078) (xy 246.868442 -116.515134) (xy 246.868774 -116.524154)
			(xy 246.875038 -116.541071) (xy 246.880634 -116.548154) (xy 246.880888 -116.548154) (xy 246.880888 -116.548408)
			(xy 246.898534 -116.569336) (xy 246.928257 -116.615305) (xy 246.951101 -116.665052) (xy 246.966597 -116.717555)
			(xy 246.974424 -116.771734) (xy 246.974424 -116.826475) (xy 246.966595 -116.880654) (xy 246.951098 -116.933156)
			(xy 246.928253 -116.982903) (xy 246.898528 -117.028871) (xy 246.880888 -117.049804) (xy 246.880634 -117.050058)
			(xy 246.875051 -117.057147) (xy 246.868804 -117.074062) (xy 246.868442 -117.083078) (xy 246.868442 -117.150134)
			(xy 246.868774 -117.159154) (xy 246.875038 -117.176071) (xy 246.880634 -117.183154) (xy 246.880888 -117.183154)
			(xy 246.880888 -117.183408) (xy 246.898542 -117.204328) (xy 246.928252 -117.250304) (xy 246.951086 -117.300054)
			(xy 246.966573 -117.352558) (xy 246.974397 -117.406736) (xy 246.974868 -117.434106) (xy 246.97473 -117.442234)
			(xy 247.85904 -117.442234) (xy 247.863111 -117.386612) (xy 247.875237 -117.332175) (xy 247.89516 -117.280084)
			(xy 247.922456 -117.231449) (xy 247.956542 -117.187306) (xy 247.996691 -117.148597) (xy 248.042049 -117.116146)
			(xy 248.091649 -117.090645) (xy 248.144433 -117.072638) (xy 248.199276 -117.062508) (xy 248.25501 -117.060471)
			(xy 248.310447 -117.066571) (xy 248.364404 -117.080677) (xy 248.415733 -117.102489) (xy 248.463339 -117.131543)
			(xy 248.506207 -117.167218) (xy 248.543424 -117.208755) (xy 248.574197 -117.255268) (xy 248.597869 -117.305765)
			(xy 248.613937 -117.359172) (xy 248.622057 -117.414348) (xy 248.622566 -117.442234) (xy 248.622057 -117.47012)
			(xy 248.613937 -117.525296) (xy 248.597869 -117.578703) (xy 248.574197 -117.6292) (xy 248.543424 -117.675713)
			(xy 248.506207 -117.71725) (xy 248.463339 -117.752925) (xy 248.415733 -117.781979) (xy 248.364404 -117.803791)
			(xy 248.310447 -117.817897) (xy 248.25501 -117.823997) (xy 248.199276 -117.82196) (xy 248.144433 -117.81183)
			(xy 248.091649 -117.793823) (xy 248.042049 -117.768322) (xy 247.996691 -117.735871) (xy 247.956542 -117.697162)
			(xy 247.922456 -117.653019) (xy 247.89516 -117.604384) (xy 247.875237 -117.552293) (xy 247.863111 -117.497856)
			(xy 247.85904 -117.442234) (xy 246.97473 -117.442234) (xy 246.974416 -117.460663) (xy 246.967047 -117.513262)
			(xy 246.952452 -117.564331) (xy 246.942102 -117.588792) (xy 246.937753 -117.60016) (xy 246.939101 -117.624434)
			(xy 246.944642 -117.635274) (xy 246.986044 -117.706394) (xy 246.99276 -117.716478) (xy 247.013181 -117.729461)
			(xy 247.02516 -117.731286) (xy 247.053143 -117.73446) (xy 247.107807 -117.747998) (xy 247.159886 -117.769425)
			(xy 247.208249 -117.798277) (xy 247.251844 -117.833926) (xy 247.289724 -117.875598) (xy 247.321066 -117.922386)
			(xy 247.345188 -117.973274) (xy 247.361565 -118.027155) (xy 247.367007 -118.063772) (xy 249.006104 -118.063772)
			(xy 249.010175 -118.00815) (xy 249.022301 -117.953713) (xy 249.042224 -117.901622) (xy 249.06952 -117.852987)
			(xy 249.103606 -117.808844) (xy 249.143755 -117.770135) (xy 249.189113 -117.737684) (xy 249.238713 -117.712183)
			(xy 249.291497 -117.694176) (xy 249.34634 -117.684046) (xy 249.402074 -117.682009) (xy 249.457511 -117.688109)
			(xy 249.511468 -117.702215) (xy 249.562797 -117.724027) (xy 249.610403 -117.753081) (xy 249.653271 -117.788756)
			(xy 249.690488 -117.830293) (xy 249.721261 -117.876806) (xy 249.744933 -117.927303) (xy 249.761001 -117.98071)
			(xy 249.76702 -118.021608) (xy 249.885454 -118.021608) (xy 249.885912 -117.994237) (xy 249.893729 -117.940057)
			(xy 249.90922 -117.887554) (xy 249.932064 -117.837807) (xy 249.961791 -117.791841) (xy 249.979434 -117.77091)
			(xy 249.979688 -117.770656) (xy 249.985256 -117.763557) (xy 249.991514 -117.74665) (xy 249.99188 -117.737636)
			(xy 249.99188 -117.67058) (xy 249.991537 -117.661562) (xy 249.98528 -117.644645) (xy 249.979688 -117.63756)
			(xy 249.979434 -117.63756) (xy 249.979434 -117.637306) (xy 249.961801 -117.616367) (xy 249.932075 -117.570401)
			(xy 249.909229 -117.520655) (xy 249.893732 -117.468154) (xy 249.885902 -117.413976) (xy 249.885901 -117.359236)
			(xy 249.893729 -117.305058) (xy 249.909225 -117.252556) (xy 249.932069 -117.20281) (xy 249.961794 -117.156843)
			(xy 249.979434 -117.13591) (xy 249.979688 -117.135656) (xy 249.985256 -117.128557) (xy 249.991514 -117.11165)
			(xy 249.99188 -117.102636) (xy 249.99188 -117.03558) (xy 249.991537 -117.026562) (xy 249.98528 -117.009645)
			(xy 249.979688 -117.00256) (xy 249.979434 -117.00256) (xy 249.979434 -117.002306) (xy 249.96179 -116.981378)
			(xy 249.932077 -116.935405) (xy 249.909242 -116.885656) (xy 249.893752 -116.833154) (xy 249.885926 -116.778978)
			(xy 249.885454 -116.751608) (xy 249.885985 -116.724359) (xy 249.89374 -116.670415) (xy 249.909092 -116.618123)
			(xy 249.931729 -116.568548) (xy 249.961191 -116.5227) (xy 249.996878 -116.48151) (xy 250.038063 -116.445819)
			(xy 250.083908 -116.416351) (xy 250.13348 -116.393708) (xy 250.18577 -116.378349) (xy 250.239713 -116.370588)
			(xy 250.266962 -116.3701) (xy 250.294331 -116.370588) (xy 250.34851 -116.378401) (xy 250.401012 -116.393885)
			(xy 250.45076 -116.416721) (xy 250.496728 -116.446441) (xy 250.51766 -116.46408) (xy 250.517914 -116.464334)
			(xy 250.52499 -116.469936) (xy 250.541915 -116.476172) (xy 250.550934 -116.476526) (xy 250.61799 -116.476526)
			(xy 250.627006 -116.476158) (xy 250.643922 -116.469918) (xy 250.65101 -116.464334) (xy 250.65101 -116.46408)
			(xy 250.651264 -116.46408) (xy 250.672196 -116.446441) (xy 250.718169 -116.41673) (xy 250.767917 -116.393894)
			(xy 250.820417 -116.378403) (xy 250.874593 -116.370574) (xy 250.901962 -116.3701) (xy 250.929214 -116.370591)
			(xy 250.983165 -116.378343) (xy 251.035462 -116.393694) (xy 251.085043 -116.416333) (xy 251.130897 -116.445798)
			(xy 251.17209 -116.481489) (xy 251.207784 -116.522679) (xy 251.237253 -116.568531) (xy 251.259895 -116.618109)
			(xy 251.275251 -116.670406) (xy 251.283007 -116.724356) (xy 251.28347 -116.751608) (xy 251.283016 -116.778979)
			(xy 251.275196 -116.833159) (xy 251.259705 -116.885662) (xy 251.23686 -116.935409) (xy 251.207133 -116.981375)
			(xy 251.18949 -117.002306) (xy 251.189236 -117.00256) (xy 251.183652 -117.009648) (xy 251.177406 -117.026564)
			(xy 251.177044 -117.03558) (xy 251.177044 -117.102636) (xy 251.177374 -117.111656) (xy 251.183639 -117.128573)
			(xy 251.189236 -117.135656) (xy 251.18949 -117.135656) (xy 251.18949 -117.13591) (xy 251.207138 -117.156837)
			(xy 251.236861 -117.202806) (xy 251.259705 -117.252553) (xy 251.2752 -117.305056) (xy 251.283027 -117.359235)
			(xy 251.283026 -117.413977) (xy 251.275197 -117.468156) (xy 251.259701 -117.520658) (xy 251.236855 -117.570405)
			(xy 251.207131 -117.616373) (xy 251.18949 -117.637306) (xy 251.189236 -117.63756) (xy 251.183652 -117.644648)
			(xy 251.177406 -117.661564) (xy 251.177044 -117.67058) (xy 251.177044 -117.737636) (xy 251.177374 -117.746656)
			(xy 251.183639 -117.763573) (xy 251.189236 -117.770656) (xy 251.18949 -117.770656) (xy 251.18949 -117.77091)
			(xy 251.207146 -117.791829) (xy 251.236855 -117.837805) (xy 251.259688 -117.887556) (xy 251.275175 -117.94006)
			(xy 251.282999 -117.994238) (xy 251.28347 -118.021608) (xy 251.283052 -118.048863) (xy 251.275293 -118.102817)
			(xy 251.259934 -118.155118) (xy 251.237288 -118.204701) (xy 251.207815 -118.250556) (xy 251.172117 -118.291749)
			(xy 251.130919 -118.327443) (xy 251.085061 -118.35691) (xy 251.035475 -118.37955) (xy 250.983172 -118.394903)
			(xy 250.929217 -118.402655) (xy 250.901962 -118.403116) (xy 250.874592 -118.402634) (xy 250.820413 -118.394823)
			(xy 250.767909 -118.379339) (xy 250.718162 -118.3565) (xy 250.672195 -118.326777) (xy 250.651264 -118.309136)
			(xy 250.65101 -118.308882) (xy 250.643926 -118.303291) (xy 250.627007 -118.297048) (xy 250.61799 -118.29669)
			(xy 250.550934 -118.29669) (xy 250.541919 -118.297065) (xy 250.525002 -118.3033) (xy 250.517914 -118.308882)
			(xy 250.517914 -118.309136) (xy 250.51766 -118.309136) (xy 250.496721 -118.326766) (xy 250.450749 -118.356478)
			(xy 250.401004 -118.379315) (xy 250.348505 -118.394808) (xy 250.294331 -118.40264) (xy 250.266962 -118.403116)
			(xy 250.23971 -118.402658) (xy 250.185762 -118.394896) (xy 250.133467 -118.379537) (xy 250.08389 -118.356892)
			(xy 250.03804 -118.327422) (xy 249.996851 -118.291728) (xy 249.96116 -118.250535) (xy 249.931694 -118.204683)
			(xy 249.909053 -118.155105) (xy 249.893698 -118.102809) (xy 249.88594 -118.04886) (xy 249.885454 -118.021608)
			(xy 249.76702 -118.021608) (xy 249.769121 -118.035886) (xy 249.76963 -118.063772) (xy 249.769121 -118.091658)
			(xy 249.761001 -118.146834) (xy 249.744933 -118.200241) (xy 249.721261 -118.250738) (xy 249.690488 -118.297251)
			(xy 249.653271 -118.338788) (xy 249.610403 -118.374463) (xy 249.562797 -118.403517) (xy 249.511468 -118.425329)
			(xy 249.457511 -118.439435) (xy 249.402074 -118.445535) (xy 249.34634 -118.443498) (xy 249.291497 -118.433368)
			(xy 249.238713 -118.415361) (xy 249.189113 -118.38986) (xy 249.143755 -118.357409) (xy 249.103606 -118.3187)
			(xy 249.06952 -118.274557) (xy 249.042224 -118.225922) (xy 249.022301 -118.173831) (xy 249.010175 -118.119394)
			(xy 249.006104 -118.063772) (xy 247.367007 -118.063772) (xy 247.369843 -118.082858) (xy 247.370346 -118.111016)
			(xy 247.36986 -118.138267) (xy 247.362104 -118.192215) (xy 247.346749 -118.24451) (xy 247.324107 -118.294087)
			(xy 247.294641 -118.339937) (xy 247.25895 -118.381128) (xy 247.217759 -118.416819) (xy 247.171909 -118.446285)
			(xy 247.122332 -118.468927) (xy 247.070037 -118.484282) (xy 247.016089 -118.492038) (xy 246.961587 -118.492038)
			(xy 246.907639 -118.484282) (xy 246.855344 -118.468927) (xy 246.805767 -118.446285) (xy 246.759917 -118.416819)
			(xy 246.718726 -118.381128) (xy 246.683035 -118.339937) (xy 246.653569 -118.294087) (xy 246.630927 -118.24451)
			(xy 246.615572 -118.192215) (xy 246.607816 -118.138267) (xy 246.60733 -118.111016) (xy 246.60779 -118.08446)
			(xy 246.615156 -118.03186) (xy 246.629747 -117.980791) (xy 246.640096 -117.95633) (xy 246.644431 -117.944957)
			(xy 246.643093 -117.920688) (xy 246.637556 -117.909848) (xy 246.596154 -117.838728) (xy 246.58941 -117.828667)
			(xy 246.569009 -117.815676) (xy 246.557038 -117.813836) (xy 246.527564 -117.810453) (xy 246.470096 -117.795736)
			(xy 246.415599 -117.772298) (xy 246.365389 -117.740703) (xy 246.342662 -117.721634) (xy 246.342408 -117.72138)
			(xy 246.335325 -117.715788) (xy 246.318405 -117.709545) (xy 246.309388 -117.709188) (xy 246.242332 -117.709188)
			(xy 246.233317 -117.709563) (xy 246.2164 -117.715798) (xy 246.209312 -117.72138) (xy 246.209312 -117.721634)
			(xy 246.209058 -117.721634) (xy 246.188119 -117.739265) (xy 246.142148 -117.768977) (xy 246.092402 -117.791814)
			(xy 246.039903 -117.807307) (xy 245.985729 -117.815138) (xy 245.95836 -117.815614) (xy 245.931108 -117.815159)
			(xy 245.87716 -117.807398) (xy 245.824865 -117.792038) (xy 245.775288 -117.769392) (xy 245.729438 -117.739922)
			(xy 245.688248 -117.704228) (xy 245.652557 -117.663035) (xy 245.623091 -117.617183) (xy 245.60045 -117.567604)
			(xy 245.585095 -117.515307) (xy 245.577338 -117.461358) (xy 245.576852 -117.434106) (xy 239.401235 -117.434106)
			(xy 239.407419 -117.439252) (xy 239.444636 -117.480789) (xy 239.475409 -117.527302) (xy 239.499081 -117.577799)
			(xy 239.515149 -117.631206) (xy 239.523269 -117.686382) (xy 239.523778 -117.714268) (xy 239.523269 -117.742154)
			(xy 239.515149 -117.79733) (xy 239.499081 -117.850737) (xy 239.475409 -117.901234) (xy 239.444636 -117.947747)
			(xy 239.407419 -117.989284) (xy 239.364551 -118.024959) (xy 239.316945 -118.054013) (xy 239.274255 -118.072154)
			(xy 240.997992 -118.072154) (xy 241.002063 -118.016532) (xy 241.014189 -117.962095) (xy 241.034112 -117.910004)
			(xy 241.061408 -117.861369) (xy 241.095494 -117.817226) (xy 241.135643 -117.778517) (xy 241.181001 -117.746066)
			(xy 241.230601 -117.720565) (xy 241.283385 -117.702558) (xy 241.338228 -117.692428) (xy 241.393962 -117.690391)
			(xy 241.449399 -117.696491) (xy 241.503356 -117.710597) (xy 241.554685 -117.732409) (xy 241.602291 -117.761463)
			(xy 241.645159 -117.797138) (xy 241.682376 -117.838675) (xy 241.713149 -117.885188) (xy 241.736821 -117.935685)
			(xy 241.752889 -117.989092) (xy 241.761009 -118.044268) (xy 241.761518 -118.072154) (xy 241.761203 -118.089426)
			(xy 242.395246 -118.089426) (xy 242.399317 -118.033804) (xy 242.411443 -117.979367) (xy 242.431366 -117.927276)
			(xy 242.458662 -117.878641) (xy 242.492748 -117.834498) (xy 242.532897 -117.795789) (xy 242.578255 -117.763338)
			(xy 242.627855 -117.737837) (xy 242.680639 -117.71983) (xy 242.735482 -117.7097) (xy 242.791216 -117.707663)
			(xy 242.846653 -117.713763) (xy 242.90061 -117.727869) (xy 242.951939 -117.749681) (xy 242.999545 -117.778735)
			(xy 243.042413 -117.81441) (xy 243.07963 -117.855947) (xy 243.110403 -117.90246) (xy 243.134075 -117.952957)
			(xy 243.136924 -117.962426) (xy 244.427246 -117.962426) (xy 244.431317 -117.906804) (xy 244.443443 -117.852367)
			(xy 244.463366 -117.800276) (xy 244.490662 -117.751641) (xy 244.524748 -117.707498) (xy 244.564897 -117.668789)
			(xy 244.610255 -117.636338) (xy 244.659855 -117.610837) (xy 244.712639 -117.59283) (xy 244.767482 -117.5827)
			(xy 244.823216 -117.580663) (xy 244.878653 -117.586763) (xy 244.93261 -117.600869) (xy 244.983939 -117.622681)
			(xy 245.031545 -117.651735) (xy 245.074413 -117.68741) (xy 245.11163 -117.728947) (xy 245.142403 -117.77546)
			(xy 245.166075 -117.825957) (xy 245.182143 -117.879364) (xy 245.190263 -117.93454) (xy 245.190772 -117.962426)
			(xy 245.190263 -117.990312) (xy 245.182143 -118.045488) (xy 245.166075 -118.098895) (xy 245.142403 -118.149392)
			(xy 245.11163 -118.195905) (xy 245.074413 -118.237442) (xy 245.031545 -118.273117) (xy 244.983939 -118.302171)
			(xy 244.93261 -118.323983) (xy 244.878653 -118.338089) (xy 244.823216 -118.344189) (xy 244.767482 -118.342152)
			(xy 244.712639 -118.332022) (xy 244.659855 -118.314015) (xy 244.610255 -118.288514) (xy 244.564897 -118.256063)
			(xy 244.524748 -118.217354) (xy 244.490662 -118.173211) (xy 244.463366 -118.124576) (xy 244.443443 -118.072485)
			(xy 244.431317 -118.018048) (xy 244.427246 -117.962426) (xy 243.136924 -117.962426) (xy 243.150143 -118.006364)
			(xy 243.158263 -118.06154) (xy 243.158772 -118.089426) (xy 243.158263 -118.117312) (xy 243.150143 -118.172488)
			(xy 243.134075 -118.225895) (xy 243.110403 -118.276392) (xy 243.07963 -118.322905) (xy 243.042413 -118.364442)
			(xy 242.999545 -118.400117) (xy 242.951939 -118.429171) (xy 242.90061 -118.450983) (xy 242.846653 -118.465089)
			(xy 242.791216 -118.471189) (xy 242.735482 -118.469152) (xy 242.680639 -118.459022) (xy 242.627855 -118.441015)
			(xy 242.578255 -118.415514) (xy 242.532897 -118.383063) (xy 242.492748 -118.344354) (xy 242.458662 -118.300211)
			(xy 242.431366 -118.251576) (xy 242.411443 -118.199485) (xy 242.399317 -118.145048) (xy 242.395246 -118.089426)
			(xy 241.761203 -118.089426) (xy 241.761009 -118.10004) (xy 241.752889 -118.155216) (xy 241.736821 -118.208623)
			(xy 241.713149 -118.25912) (xy 241.682376 -118.305633) (xy 241.645159 -118.34717) (xy 241.602291 -118.382845)
			(xy 241.554685 -118.411899) (xy 241.503356 -118.433711) (xy 241.449399 -118.447817) (xy 241.393962 -118.453917)
			(xy 241.338228 -118.45188) (xy 241.283385 -118.44175) (xy 241.230601 -118.423743) (xy 241.181001 -118.398242)
			(xy 241.135643 -118.365791) (xy 241.095494 -118.327082) (xy 241.061408 -118.282939) (xy 241.034112 -118.234304)
			(xy 241.014189 -118.182213) (xy 241.002063 -118.127776) (xy 240.997992 -118.072154) (xy 239.274255 -118.072154)
			(xy 239.265616 -118.075825) (xy 239.211659 -118.089931) (xy 239.156222 -118.096031) (xy 239.100488 -118.093994)
			(xy 239.045645 -118.083864) (xy 238.992861 -118.065857) (xy 238.943261 -118.040356) (xy 238.897903 -118.007905)
			(xy 238.857754 -117.969196) (xy 238.823668 -117.925053) (xy 238.796372 -117.876418) (xy 238.776449 -117.824327)
			(xy 238.764323 -117.76989) (xy 238.760252 -117.714268) (xy 237.466031 -117.714268) (xy 237.466124 -117.719348)
			(xy 237.465615 -117.747234) (xy 237.457495 -117.80241) (xy 237.441427 -117.855817) (xy 237.417755 -117.906314)
			(xy 237.386982 -117.952827) (xy 237.349765 -117.994364) (xy 237.306897 -118.030039) (xy 237.259291 -118.059093)
			(xy 237.207962 -118.080905) (xy 237.154005 -118.095011) (xy 237.098568 -118.101111) (xy 237.042834 -118.099074)
			(xy 236.987991 -118.088944) (xy 236.935207 -118.070937) (xy 236.885607 -118.045436) (xy 236.840249 -118.012985)
			(xy 236.8001 -117.974276) (xy 236.766014 -117.930133) (xy 236.738718 -117.881498) (xy 236.718795 -117.829407)
			(xy 236.706669 -117.77497) (xy 236.702598 -117.719348) (xy 212.31797 -117.719348) (xy 212.300508 -117.754152)
			(xy 212.272918 -117.792769) (xy 212.256624 -117.810026) (xy 212.254084 -117.812566) (xy 212.124036 -117.942614)
			(xy 212.106717 -117.959309) (xy 212.067798 -117.987577) (xy 212.024937 -118.009412) (xy 211.979189 -118.024276)
			(xy 211.931679 -118.031803) (xy 211.907628 -118.032276) (xy 210.286854 -118.032276) (xy 210.263872 -118.031815)
			(xy 210.218426 -118.024938) (xy 210.174523 -118.011331) (xy 210.133154 -117.991301) (xy 210.095252 -117.9653)
			(xy 210.061672 -117.933915) (xy 210.033172 -117.897854) (xy 210.021424 -117.878098) (xy 209.986118 -117.816376)
			(xy 209.956654 -117.802914) (xy 209.941414 -117.805708) (xy 209.923863 -117.808816) (xy 209.888371 -117.81212)
			(xy 209.870548 -117.812312) (xy 209.852726 -117.812112) (xy 209.817235 -117.808803) (xy 209.799682 -117.805708)
			(xy 209.764884 -117.799104) (xy 209.763614 -117.80139) (xy 209.712306 -117.891052) (xy 209.70875 -117.896386)
			(xy 209.697574 -117.911372) (xy 209.683057 -117.929827) (xy 209.64928 -117.962441) (xy 209.610915 -117.989511)
			(xy 209.568864 -118.0104) (xy 209.524115 -118.024618) (xy 209.477718 -118.03183) (xy 209.454242 -118.032276)
			(xy 206.107284 -118.032276) (xy 206.097211 -118.032673) (xy 206.078613 -118.040412) (xy 206.071216 -118.047262)
			(xy 205.91145 -118.207028) (xy 215.707974 -118.207028) (xy 215.712045 -118.151406) (xy 215.724171 -118.096969)
			(xy 215.744094 -118.044878) (xy 215.77139 -117.996243) (xy 215.805476 -117.9521) (xy 215.845625 -117.913391)
			(xy 215.890983 -117.88094) (xy 215.940583 -117.855439) (xy 215.993367 -117.837432) (xy 216.04821 -117.827302)
			(xy 216.103944 -117.825265) (xy 216.159381 -117.831365) (xy 216.213338 -117.845471) (xy 216.264667 -117.867283)
			(xy 216.312273 -117.896337) (xy 216.355141 -117.932012) (xy 216.392358 -117.973549) (xy 216.423131 -118.020062)
			(xy 216.446803 -118.070559) (xy 216.462871 -118.123966) (xy 216.470991 -118.179142) (xy 216.4715 -118.207028)
			(xy 216.470991 -118.234914) (xy 216.462871 -118.29009) (xy 216.446803 -118.343497) (xy 216.423131 -118.393994)
			(xy 216.392358 -118.440507) (xy 216.355141 -118.482044) (xy 216.312273 -118.517719) (xy 216.264667 -118.546773)
			(xy 216.213338 -118.568585) (xy 216.159381 -118.582691) (xy 216.103944 -118.588791) (xy 216.04821 -118.586754)
			(xy 215.993367 -118.576624) (xy 215.940583 -118.558617) (xy 215.890983 -118.533116) (xy 215.845625 -118.500665)
			(xy 215.805476 -118.461956) (xy 215.77139 -118.417813) (xy 215.744094 -118.369178) (xy 215.724171 -118.317087)
			(xy 215.712045 -118.26265) (xy 215.707974 -118.207028) (xy 205.91145 -118.207028) (xy 205.203806 -118.914672)
			(xy 205.196987 -118.922088) (xy 205.189255 -118.940675) (xy 205.18882 -118.95074) (xy 205.18882 -120.922034)
			(xy 205.550516 -120.922034) (xy 205.550998 -120.894664) (xy 205.558811 -120.840486) (xy 205.574297 -120.787983)
			(xy 205.597135 -120.738236) (xy 205.626856 -120.692268) (xy 205.644496 -120.671336) (xy 205.64475 -120.671082)
			(xy 205.650356 -120.664009) (xy 205.65659 -120.647082) (xy 205.656942 -120.638062) (xy 205.656942 -120.571006)
			(xy 205.656595 -120.561988) (xy 205.650342 -120.54507) (xy 205.64475 -120.537986) (xy 205.644496 -120.537986)
			(xy 205.644496 -120.537732) (xy 205.62689 -120.516772) (xy 205.597166 -120.470808) (xy 205.574321 -120.421066)
			(xy 205.558823 -120.368568) (xy 205.550992 -120.314394) (xy 205.550988 -120.259657) (xy 205.558812 -120.205482)
			(xy 205.574303 -120.152982) (xy 205.597141 -120.103237) (xy 205.626859 -120.057269) (xy 205.644496 -120.036336)
			(xy 205.64475 -120.036082) (xy 205.650356 -120.029009) (xy 205.65659 -120.012082) (xy 205.656942 -120.003062)
			(xy 205.656942 -119.936006) (xy 205.656595 -119.926988) (xy 205.650342 -119.91007) (xy 205.64475 -119.902986)
			(xy 205.644496 -119.902986) (xy 205.644496 -119.902732) (xy 205.62689 -119.881772) (xy 205.597166 -119.835808)
			(xy 205.574321 -119.786066) (xy 205.558823 -119.733568) (xy 205.550992 -119.679394) (xy 205.550988 -119.624657)
			(xy 205.558812 -119.570482) (xy 205.574303 -119.517982) (xy 205.597141 -119.468237) (xy 205.626859 -119.422269)
			(xy 205.644496 -119.401336) (xy 205.64475 -119.401082) (xy 205.650356 -119.394009) (xy 205.65659 -119.377082)
			(xy 205.656942 -119.368062) (xy 205.656942 -119.301006) (xy 205.656595 -119.291988) (xy 205.650342 -119.27507)
			(xy 205.64475 -119.267986) (xy 205.644496 -119.267986) (xy 205.644496 -119.267732) (xy 205.626858 -119.246799)
			(xy 205.597146 -119.200827) (xy 205.57431 -119.151079) (xy 205.558819 -119.098579) (xy 205.55099 -119.044403)
			(xy 205.550516 -119.017034) (xy 205.551002 -118.989783) (xy 205.558758 -118.935835) (xy 205.574113 -118.88354)
			(xy 205.596755 -118.833963) (xy 205.626221 -118.788113) (xy 205.661912 -118.746922) (xy 205.703103 -118.711231)
			(xy 205.748953 -118.681765) (xy 205.79853 -118.659123) (xy 205.850825 -118.643768) (xy 205.904773 -118.636012)
			(xy 205.959275 -118.636012) (xy 206.013223 -118.643768) (xy 206.065518 -118.659123) (xy 206.080589 -118.666006)
			(xy 208.794348 -118.666006) (xy 208.798419 -118.610384) (xy 208.810545 -118.555947) (xy 208.830468 -118.503856)
			(xy 208.857764 -118.455221) (xy 208.89185 -118.411078) (xy 208.931999 -118.372369) (xy 208.977357 -118.339918)
			(xy 209.026957 -118.314417) (xy 209.079741 -118.29641) (xy 209.134584 -118.28628) (xy 209.190318 -118.284243)
			(xy 209.245755 -118.290343) (xy 209.299712 -118.304449) (xy 209.351041 -118.326261) (xy 209.398647 -118.355315)
			(xy 209.441515 -118.39099) (xy 209.478732 -118.432527) (xy 209.509505 -118.47904) (xy 209.533177 -118.529537)
			(xy 209.549245 -118.582944) (xy 209.55474 -118.620286) (xy 213.718646 -118.620286) (xy 213.722717 -118.564664)
			(xy 213.734843 -118.510227) (xy 213.754766 -118.458136) (xy 213.782062 -118.409501) (xy 213.816148 -118.365358)
			(xy 213.856297 -118.326649) (xy 213.901655 -118.294198) (xy 213.951255 -118.268697) (xy 214.004039 -118.25069)
			(xy 214.058882 -118.24056) (xy 214.114616 -118.238523) (xy 214.170053 -118.244623) (xy 214.22401 -118.258729)
			(xy 214.275339 -118.280541) (xy 214.322945 -118.309595) (xy 214.365813 -118.34527) (xy 214.40303 -118.386807)
			(xy 214.433803 -118.43332) (xy 214.457475 -118.483817) (xy 214.473543 -118.537224) (xy 214.481663 -118.5924)
			(xy 214.482172 -118.620286) (xy 214.481663 -118.648172) (xy 214.473543 -118.703348) (xy 214.457475 -118.756755)
			(xy 214.433803 -118.807252) (xy 214.40303 -118.853765) (xy 214.365813 -118.895302) (xy 214.322945 -118.930977)
			(xy 214.275339 -118.960031) (xy 214.22401 -118.981843) (xy 214.170053 -118.995949) (xy 214.114616 -119.002049)
			(xy 214.058882 -119.000012) (xy 214.004039 -118.989882) (xy 213.951255 -118.971875) (xy 213.901655 -118.946374)
			(xy 213.856297 -118.913923) (xy 213.816148 -118.875214) (xy 213.782062 -118.831071) (xy 213.754766 -118.782436)
			(xy 213.734843 -118.730345) (xy 213.722717 -118.675908) (xy 213.718646 -118.620286) (xy 209.55474 -118.620286)
			(xy 209.557365 -118.63812) (xy 209.557874 -118.666006) (xy 209.557365 -118.693892) (xy 209.549245 -118.749068)
			(xy 209.533177 -118.802475) (xy 209.509505 -118.852972) (xy 209.478732 -118.899485) (xy 209.441515 -118.941022)
			(xy 209.398647 -118.976697) (xy 209.351041 -119.005751) (xy 209.299712 -119.027563) (xy 209.245755 -119.041669)
			(xy 209.190318 -119.047769) (xy 209.134584 -119.045732) (xy 209.079741 -119.035602) (xy 209.026957 -119.017595)
			(xy 208.977357 -118.992094) (xy 208.931999 -118.959643) (xy 208.89185 -118.920934) (xy 208.857764 -118.876791)
			(xy 208.830468 -118.828156) (xy 208.810545 -118.776065) (xy 208.798419 -118.721628) (xy 208.794348 -118.666006)
			(xy 206.080589 -118.666006) (xy 206.115095 -118.681765) (xy 206.160945 -118.711231) (xy 206.202136 -118.746922)
			(xy 206.237827 -118.788113) (xy 206.267293 -118.833963) (xy 206.289935 -118.88354) (xy 206.30529 -118.935835)
			(xy 206.313046 -118.989783) (xy 206.313532 -119.017034) (xy 206.313102 -119.044406) (xy 206.308435 -119.076724)
			(xy 206.521812 -119.076724) (xy 206.522278 -119.049471) (xy 206.530032 -118.995519) (xy 206.545386 -118.94322)
			(xy 206.568027 -118.893639) (xy 206.597494 -118.847784) (xy 206.633188 -118.806591) (xy 206.674381 -118.770897)
			(xy 206.720235 -118.741429) (xy 206.769816 -118.718787) (xy 206.822115 -118.703433) (xy 206.876067 -118.695678)
			(xy 206.90332 -118.695216) (xy 206.929635 -118.695665) (xy 206.981764 -118.702903) (xy 207.032407 -118.717225)
			(xy 207.080606 -118.738361) (xy 207.125449 -118.765911) (xy 207.166088 -118.799353) (xy 207.184244 -118.818406)
			(xy 207.191747 -118.82583) (xy 207.211041 -118.834341) (xy 207.221582 -118.834916) (xy 207.296258 -118.834916)
			(xy 207.306806 -118.834373) (xy 207.326101 -118.825847) (xy 207.333596 -118.818406) (xy 207.351762 -118.799361)
			(xy 207.392389 -118.765902) (xy 207.437227 -118.738342) (xy 207.485426 -118.717201) (xy 207.536072 -118.702882)
			(xy 207.588204 -118.695656) (xy 207.61452 -118.695216) (xy 207.641774 -118.695636) (xy 207.695728 -118.703397)
			(xy 207.748028 -118.718756) (xy 207.79761 -118.741403) (xy 207.843464 -118.770875) (xy 207.884658 -118.806574)
			(xy 207.920351 -118.847771) (xy 207.949818 -118.893628) (xy 207.972459 -118.943213) (xy 207.987813 -118.995515)
			(xy 207.995567 -119.049469) (xy 207.996028 -119.076724) (xy 207.995484 -119.105052) (xy 207.987121 -119.161088)
			(xy 207.970565 -119.215272) (xy 207.966867 -119.223028) (xy 215.70391 -119.223028) (xy 215.707981 -119.167406)
			(xy 215.720107 -119.112969) (xy 215.74003 -119.060878) (xy 215.767326 -119.012243) (xy 215.801412 -118.9681)
			(xy 215.841561 -118.929391) (xy 215.886919 -118.89694) (xy 215.936519 -118.871439) (xy 215.989303 -118.853432)
			(xy 216.044146 -118.843302) (xy 216.09988 -118.841265) (xy 216.155317 -118.847365) (xy 216.209274 -118.861471)
			(xy 216.260603 -118.883283) (xy 216.308209 -118.912337) (xy 216.351077 -118.948012) (xy 216.388294 -118.989549)
			(xy 216.419067 -119.036062) (xy 216.436342 -119.072914) (xy 216.75852 -119.072914) (xy 216.75899 -119.0466)
			(xy 216.766224 -118.994471) (xy 216.780542 -118.943828) (xy 216.801674 -118.895629) (xy 216.82922 -118.850786)
			(xy 216.862658 -118.810146) (xy 216.88171 -118.79199) (xy 216.88912 -118.784475) (xy 216.897639 -118.76519)
			(xy 216.89822 -118.754652) (xy 216.89822 -118.679976) (xy 216.897658 -118.66943) (xy 216.889145 -118.650135)
			(xy 216.88171 -118.642638) (xy 216.862633 -118.624504) (xy 216.829178 -118.58387) (xy 216.801621 -118.539025)
			(xy 216.780486 -118.49082) (xy 216.766174 -118.440169) (xy 216.758955 -118.388031) (xy 216.75852 -118.361714)
			(xy 216.759006 -118.334463) (xy 216.766762 -118.280515) (xy 216.782117 -118.22822) (xy 216.804759 -118.178643)
			(xy 216.834225 -118.132793) (xy 216.869916 -118.091602) (xy 216.911107 -118.055911) (xy 216.956957 -118.026445)
			(xy 217.006534 -118.003803) (xy 217.058829 -117.988448) (xy 217.112777 -117.980692) (xy 217.167279 -117.980692)
			(xy 217.221227 -117.988448) (xy 217.273522 -118.003803) (xy 217.323099 -118.026445) (xy 217.368949 -118.055911)
			(xy 217.41014 -118.091602) (xy 217.445831 -118.132793) (xy 217.475297 -118.178643) (xy 217.497939 -118.22822)
			(xy 217.513294 -118.280515) (xy 217.52105 -118.334463) (xy 217.521536 -118.361714) (xy 217.521066 -118.388028)
			(xy 217.51383 -118.440156) (xy 217.499511 -118.490798) (xy 217.478379 -118.538997) (xy 217.450834 -118.58384)
			(xy 217.417397 -118.624481) (xy 217.398346 -118.642638) (xy 217.390933 -118.65015) (xy 217.382413 -118.669437)
			(xy 217.381836 -118.679976) (xy 217.381836 -118.754652) (xy 217.382367 -118.765202) (xy 217.3909 -118.784498)
			(xy 217.398346 -118.79199) (xy 217.417398 -118.810148) (xy 217.450854 -118.850779) (xy 217.478412 -118.895619)
			(xy 217.499551 -118.943819) (xy 217.513869 -118.994465) (xy 217.521096 -119.046598) (xy 217.521536 -119.072914)
			(xy 218.79052 -119.072914) (xy 218.79099 -119.0466) (xy 218.798224 -118.994471) (xy 218.812542 -118.943828)
			(xy 218.833674 -118.895629) (xy 218.86122 -118.850786) (xy 218.894658 -118.810146) (xy 218.91371 -118.79199)
			(xy 218.92112 -118.784475) (xy 218.929639 -118.76519) (xy 218.93022 -118.754652) (xy 218.93022 -118.679976)
			(xy 218.929658 -118.66943) (xy 218.921145 -118.650135) (xy 218.91371 -118.642638) (xy 218.894633 -118.624504)
			(xy 218.861178 -118.58387) (xy 218.833621 -118.539025) (xy 218.812486 -118.49082) (xy 218.798174 -118.440169)
			(xy 218.790955 -118.388031) (xy 218.79052 -118.361714) (xy 218.791006 -118.334463) (xy 218.798762 -118.280515)
			(xy 218.814117 -118.22822) (xy 218.836759 -118.178643) (xy 218.866225 -118.132793) (xy 218.901916 -118.091602)
			(xy 218.943107 -118.055911) (xy 218.988957 -118.026445) (xy 219.038534 -118.003803) (xy 219.090829 -117.988448)
			(xy 219.144777 -117.980692) (xy 219.199279 -117.980692) (xy 219.253227 -117.988448) (xy 219.305522 -118.003803)
			(xy 219.355099 -118.026445) (xy 219.400949 -118.055911) (xy 219.44214 -118.091602) (xy 219.477831 -118.132793)
			(xy 219.507297 -118.178643) (xy 219.529939 -118.22822) (xy 219.545294 -118.280515) (xy 219.55305 -118.334463)
			(xy 219.553536 -118.361714) (xy 219.553066 -118.388028) (xy 219.54583 -118.440156) (xy 219.531511 -118.490798)
			(xy 219.510379 -118.538997) (xy 219.482834 -118.58384) (xy 219.449397 -118.624481) (xy 219.430346 -118.642638)
			(xy 219.422933 -118.65015) (xy 219.414413 -118.669437) (xy 219.413836 -118.679976) (xy 219.413836 -118.754652)
			(xy 219.414367 -118.765202) (xy 219.4229 -118.784498) (xy 219.430346 -118.79199) (xy 219.449398 -118.810148)
			(xy 219.482854 -118.850779) (xy 219.510412 -118.895619) (xy 219.531551 -118.943819) (xy 219.545869 -118.994465)
			(xy 219.553096 -119.046598) (xy 219.553536 -119.072914) (xy 220.82252 -119.072914) (xy 220.82299 -119.0466)
			(xy 220.830224 -118.994471) (xy 220.844542 -118.943828) (xy 220.865674 -118.895629) (xy 220.89322 -118.850786)
			(xy 220.926658 -118.810146) (xy 220.94571 -118.79199) (xy 220.95312 -118.784475) (xy 220.961639 -118.76519)
			(xy 220.96222 -118.754652) (xy 220.96222 -118.679976) (xy 220.961658 -118.66943) (xy 220.953145 -118.650135)
			(xy 220.94571 -118.642638) (xy 220.926633 -118.624504) (xy 220.893178 -118.58387) (xy 220.865621 -118.539025)
			(xy 220.844486 -118.49082) (xy 220.830174 -118.440169) (xy 220.822955 -118.388031) (xy 220.82252 -118.361714)
			(xy 220.823006 -118.334463) (xy 220.830762 -118.280515) (xy 220.846117 -118.22822) (xy 220.868759 -118.178643)
			(xy 220.898225 -118.132793) (xy 220.933916 -118.091602) (xy 220.975107 -118.055911) (xy 221.020957 -118.026445)
			(xy 221.070534 -118.003803) (xy 221.122829 -117.988448) (xy 221.176777 -117.980692) (xy 221.231279 -117.980692)
			(xy 221.285227 -117.988448) (xy 221.337522 -118.003803) (xy 221.387099 -118.026445) (xy 221.432949 -118.055911)
			(xy 221.47414 -118.091602) (xy 221.509831 -118.132793) (xy 221.539297 -118.178643) (xy 221.561939 -118.22822)
			(xy 221.577294 -118.280515) (xy 221.58505 -118.334463) (xy 221.585536 -118.361714) (xy 221.585066 -118.388028)
			(xy 221.57783 -118.440156) (xy 221.563511 -118.490798) (xy 221.542379 -118.538997) (xy 221.514834 -118.58384)
			(xy 221.481397 -118.624481) (xy 221.462346 -118.642638) (xy 221.454933 -118.65015) (xy 221.446413 -118.669437)
			(xy 221.445836 -118.679976) (xy 221.445836 -118.754652) (xy 221.446367 -118.765202) (xy 221.4549 -118.784498)
			(xy 221.462346 -118.79199) (xy 221.481398 -118.810148) (xy 221.514854 -118.850779) (xy 221.542412 -118.895619)
			(xy 221.563551 -118.943819) (xy 221.577869 -118.994465) (xy 221.585096 -119.046598) (xy 221.585536 -119.072914)
			(xy 221.58505 -119.100165) (xy 221.577294 -119.154113) (xy 221.571978 -119.172219) (xy 223.36895 -119.172219)
			(xy 223.373263 -119.114948) (xy 223.38611 -119.05897) (xy 223.407201 -119.00555) (xy 223.43606 -118.955893)
			(xy 223.472034 -118.911123) (xy 223.492822 -118.891304) (xy 223.500227 -118.883786) (xy 223.508749 -118.864503)
			(xy 223.509332 -118.853966) (xy 223.509332 -118.77929) (xy 223.508812 -118.768739) (xy 223.500269 -118.749445)
			(xy 223.492822 -118.741952) (xy 223.473754 -118.723808) (xy 223.440297 -118.683177) (xy 223.41274 -118.638334)
			(xy 223.391603 -118.590131) (xy 223.377289 -118.539481) (xy 223.370068 -118.487345) (xy 223.369632 -118.461028)
			(xy 223.370118 -118.433777) (xy 223.377874 -118.379829) (xy 223.393229 -118.327534) (xy 223.415871 -118.277957)
			(xy 223.445337 -118.232107) (xy 223.481028 -118.190916) (xy 223.522219 -118.155225) (xy 223.568069 -118.125759)
			(xy 223.617646 -118.103117) (xy 223.669941 -118.087762) (xy 223.723889 -118.080006) (xy 223.778391 -118.080006)
			(xy 223.832339 -118.087762) (xy 223.884634 -118.103117) (xy 223.934211 -118.125759) (xy 223.980061 -118.155225)
			(xy 224.021252 -118.190916) (xy 224.056943 -118.232107) (xy 224.086409 -118.277957) (xy 224.109051 -118.327534)
			(xy 224.124406 -118.379829) (xy 224.132162 -118.433777) (xy 224.132648 -118.461028) (xy 224.132216 -118.487343)
			(xy 224.124976 -118.539474) (xy 224.110651 -118.590118) (xy 224.089512 -118.638317) (xy 224.061959 -118.68316)
			(xy 224.028513 -118.723797) (xy 224.009458 -118.741952) (xy 224.00204 -118.74946) (xy 223.993523 -118.76875)
			(xy 223.992948 -118.77929) (xy 223.992948 -118.853966) (xy 223.993468 -118.864517) (xy 224.002008 -118.883813)
			(xy 224.009458 -118.891304) (xy 224.030272 -118.911097) (xy 224.066243 -118.955875) (xy 224.095099 -119.005537)
			(xy 224.116188 -119.058962) (xy 224.129033 -119.114944) (xy 224.133346 -119.172219) (xy 225.907197 -119.172219)
			(xy 225.911509 -119.11495) (xy 225.924353 -119.058974) (xy 225.94544 -119.005555) (xy 225.974293 -118.955898)
			(xy 226.01026 -118.911125) (xy 226.031044 -118.891304) (xy 226.038438 -118.883775) (xy 226.046968 -118.864501)
			(xy 226.047554 -118.853966) (xy 226.047554 -118.77929) (xy 226.047057 -118.768736) (xy 226.038501 -118.74944)
			(xy 226.031044 -118.741952) (xy 226.011962 -118.723824) (xy 225.978509 -118.683187) (xy 225.950955 -118.638341)
			(xy 225.929821 -118.590135) (xy 225.915509 -118.539483) (xy 225.90829 -118.487346) (xy 225.907854 -118.461028)
			(xy 225.90834 -118.433777) (xy 225.916096 -118.379829) (xy 225.931451 -118.327534) (xy 225.954093 -118.277957)
			(xy 225.983559 -118.232107) (xy 226.01925 -118.190916) (xy 226.060441 -118.155225) (xy 226.106291 -118.125759)
			(xy 226.155868 -118.103117) (xy 226.208163 -118.087762) (xy 226.262111 -118.080006) (xy 226.316613 -118.080006)
			(xy 226.370561 -118.087762) (xy 226.422856 -118.103117) (xy 226.472433 -118.125759) (xy 226.518283 -118.155225)
			(xy 226.545823 -118.179088) (xy 230.817926 -118.179088) (xy 230.821997 -118.123466) (xy 230.834123 -118.069029)
			(xy 230.854046 -118.016938) (xy 230.881342 -117.968303) (xy 230.915428 -117.92416) (xy 230.955577 -117.885451)
			(xy 231.000935 -117.853) (xy 231.050535 -117.827499) (xy 231.103319 -117.809492) (xy 231.158162 -117.799362)
			(xy 231.213896 -117.797325) (xy 231.269333 -117.803425) (xy 231.32329 -117.817531) (xy 231.374619 -117.839343)
			(xy 231.422225 -117.868397) (xy 231.465093 -117.904072) (xy 231.50231 -117.945609) (xy 231.533083 -117.992122)
			(xy 231.556755 -118.042619) (xy 231.572823 -118.096026) (xy 231.580943 -118.151202) (xy 231.581452 -118.179088)
			(xy 231.580943 -118.206974) (xy 231.572823 -118.26215) (xy 231.556755 -118.315557) (xy 231.533083 -118.366054)
			(xy 231.50231 -118.412567) (xy 231.465093 -118.454104) (xy 231.422225 -118.489779) (xy 231.374619 -118.518833)
			(xy 231.32329 -118.540645) (xy 231.269333 -118.554751) (xy 231.213896 -118.560851) (xy 231.158162 -118.558814)
			(xy 231.103319 -118.548684) (xy 231.050535 -118.530677) (xy 231.000935 -118.505176) (xy 230.955577 -118.472725)
			(xy 230.915428 -118.434016) (xy 230.881342 -118.389873) (xy 230.854046 -118.341238) (xy 230.834123 -118.289147)
			(xy 230.821997 -118.23471) (xy 230.817926 -118.179088) (xy 226.545823 -118.179088) (xy 226.559474 -118.190916)
			(xy 226.595165 -118.232107) (xy 226.624631 -118.277957) (xy 226.647273 -118.327534) (xy 226.662628 -118.379829)
			(xy 226.670384 -118.433777) (xy 226.67087 -118.461028) (xy 226.670431 -118.487343) (xy 226.663192 -118.539473)
			(xy 226.648868 -118.590117) (xy 226.62773 -118.638316) (xy 226.600178 -118.683159) (xy 226.566734 -118.723797)
			(xy 226.54768 -118.741952) (xy 226.54025 -118.74945) (xy 226.531743 -118.768748) (xy 226.53117 -118.77929)
			(xy 226.53117 -118.853966) (xy 226.531713 -118.864514) (xy 226.54024 -118.883809) (xy 226.54768 -118.891304)
			(xy 226.568498 -118.911095) (xy 226.604476 -118.95587) (xy 226.633338 -119.005532) (xy 226.654431 -119.058958)
			(xy 226.66728 -119.114942) (xy 226.67079 -119.16156) (xy 232.432604 -119.16156) (xy 232.436675 -119.105938)
			(xy 232.448801 -119.051501) (xy 232.468724 -118.99941) (xy 232.49602 -118.950775) (xy 232.530106 -118.906632)
			(xy 232.570255 -118.867923) (xy 232.615613 -118.835472) (xy 232.665213 -118.809971) (xy 232.717997 -118.791964)
			(xy 232.77284 -118.781834) (xy 232.828574 -118.779797) (xy 232.884011 -118.785897) (xy 232.937968 -118.800003)
			(xy 232.989297 -118.821815) (xy 233.036903 -118.850869) (xy 233.079771 -118.886544) (xy 233.116988 -118.928081)
			(xy 233.147761 -118.974594) (xy 233.171433 -119.025091) (xy 233.187501 -119.078498) (xy 233.195621 -119.133674)
			(xy 233.19613 -119.16156) (xy 233.195621 -119.189446) (xy 233.192697 -119.209312) (xy 233.799124 -119.209312)
			(xy 233.803195 -119.15369) (xy 233.815321 -119.099253) (xy 233.835244 -119.047162) (xy 233.86254 -118.998527)
			(xy 233.896626 -118.954384) (xy 233.936775 -118.915675) (xy 233.982133 -118.883224) (xy 234.031733 -118.857723)
			(xy 234.084517 -118.839716) (xy 234.13936 -118.829586) (xy 234.195094 -118.827549) (xy 234.250531 -118.833649)
			(xy 234.304488 -118.847755) (xy 234.355817 -118.869567) (xy 234.403423 -118.898621) (xy 234.446291 -118.934296)
			(xy 234.483508 -118.975833) (xy 234.514281 -119.022346) (xy 234.537953 -119.072843) (xy 234.554021 -119.12625)
			(xy 234.55619 -119.140986) (xy 235.177836 -119.140986) (xy 235.181907 -119.085364) (xy 235.194033 -119.030927)
			(xy 235.213956 -118.978836) (xy 235.241252 -118.930201) (xy 235.275338 -118.886058) (xy 235.315487 -118.847349)
			(xy 235.360845 -118.814898) (xy 235.410445 -118.789397) (xy 235.463229 -118.77139) (xy 235.518072 -118.76126)
			(xy 235.573806 -118.759223) (xy 235.629243 -118.765323) (xy 235.6832 -118.779429) (xy 235.734529 -118.801241)
			(xy 235.782135 -118.830295) (xy 235.825003 -118.86597) (xy 235.86222 -118.907507) (xy 235.892993 -118.95402)
			(xy 235.916665 -119.004517) (xy 235.932733 -119.057924) (xy 235.940583 -119.111268) (xy 236.70463 -119.111268)
			(xy 236.708701 -119.055646) (xy 236.720827 -119.001209) (xy 236.74075 -118.949118) (xy 236.768046 -118.900483)
			(xy 236.802132 -118.85634) (xy 236.842281 -118.817631) (xy 236.887639 -118.78518) (xy 236.937239 -118.759679)
			(xy 236.990023 -118.741672) (xy 237.044866 -118.731542) (xy 237.1006 -118.729505) (xy 237.156037 -118.735605)
			(xy 237.209994 -118.749711) (xy 237.261323 -118.771523) (xy 237.308929 -118.800577) (xy 237.351797 -118.836252)
			(xy 237.389014 -118.877789) (xy 237.419787 -118.924302) (xy 237.443459 -118.974799) (xy 237.459527 -119.028206)
			(xy 237.467647 -119.083382) (xy 237.468156 -119.111268) (xy 237.467647 -119.139154) (xy 237.459527 -119.19433)
			(xy 237.443459 -119.247737) (xy 237.419787 -119.298234) (xy 237.389014 -119.344747) (xy 237.351797 -119.386284)
			(xy 237.308929 -119.421959) (xy 237.261323 -119.451013) (xy 237.209994 -119.472825) (xy 237.156037 -119.486931)
			(xy 237.1006 -119.493031) (xy 237.044866 -119.490994) (xy 236.990023 -119.480864) (xy 236.937239 -119.462857)
			(xy 236.887639 -119.437356) (xy 236.842281 -119.404905) (xy 236.802132 -119.366196) (xy 236.768046 -119.322053)
			(xy 236.74075 -119.273418) (xy 236.720827 -119.221327) (xy 236.708701 -119.16689) (xy 236.70463 -119.111268)
			(xy 235.940583 -119.111268) (xy 235.940853 -119.1131) (xy 235.941362 -119.140986) (xy 235.940853 -119.168872)
			(xy 235.932733 -119.224048) (xy 235.916665 -119.277455) (xy 235.892993 -119.327952) (xy 235.86222 -119.374465)
			(xy 235.825003 -119.416002) (xy 235.782135 -119.451677) (xy 235.734529 -119.480731) (xy 235.6832 -119.502543)
			(xy 235.629243 -119.516649) (xy 235.573806 -119.522749) (xy 235.518072 -119.520712) (xy 235.463229 -119.510582)
			(xy 235.410445 -119.492575) (xy 235.360845 -119.467074) (xy 235.315487 -119.434623) (xy 235.275338 -119.395914)
			(xy 235.241252 -119.351771) (xy 235.213956 -119.303136) (xy 235.194033 -119.251045) (xy 235.181907 -119.196608)
			(xy 235.177836 -119.140986) (xy 234.55619 -119.140986) (xy 234.562141 -119.181426) (xy 234.56265 -119.209312)
			(xy 234.562141 -119.237198) (xy 234.554021 -119.292374) (xy 234.537953 -119.345781) (xy 234.514281 -119.396278)
			(xy 234.483508 -119.442791) (xy 234.446291 -119.484328) (xy 234.403423 -119.520003) (xy 234.355817 -119.549057)
			(xy 234.304488 -119.570869) (xy 234.250531 -119.584975) (xy 234.195094 -119.591075) (xy 234.13936 -119.589038)
			(xy 234.084517 -119.578908) (xy 234.031733 -119.560901) (xy 233.982133 -119.5354) (xy 233.936775 -119.502949)
			(xy 233.896626 -119.46424) (xy 233.86254 -119.420097) (xy 233.835244 -119.371462) (xy 233.815321 -119.319371)
			(xy 233.803195 -119.264934) (xy 233.799124 -119.209312) (xy 233.192697 -119.209312) (xy 233.187501 -119.244622)
			(xy 233.171433 -119.298029) (xy 233.147761 -119.348526) (xy 233.116988 -119.395039) (xy 233.079771 -119.436576)
			(xy 233.036903 -119.472251) (xy 232.989297 -119.501305) (xy 232.937968 -119.523117) (xy 232.884011 -119.537223)
			(xy 232.828574 -119.543323) (xy 232.77284 -119.541286) (xy 232.717997 -119.531156) (xy 232.665213 -119.513149)
			(xy 232.615613 -119.487648) (xy 232.570255 -119.455197) (xy 232.530106 -119.416488) (xy 232.49602 -119.372345)
			(xy 232.468724 -119.32371) (xy 232.448801 -119.271619) (xy 232.436675 -119.217182) (xy 232.432604 -119.16156)
			(xy 226.67079 -119.16156) (xy 226.671593 -119.172219) (xy 226.667274 -119.229496) (xy 226.65442 -119.285478)
			(xy 226.633321 -119.338902) (xy 226.604454 -119.388561) (xy 226.568472 -119.433333) (xy 226.54768 -119.453152)
			(xy 226.54025 -119.46065) (xy 226.531743 -119.479948) (xy 226.53117 -119.49049) (xy 226.53117 -119.565166)
			(xy 226.531713 -119.575714) (xy 226.54024 -119.595009) (xy 226.54768 -119.602504) (xy 226.566727 -119.620669)
			(xy 226.600185 -119.661296) (xy 226.627746 -119.706134) (xy 226.638442 -119.73052) (xy 230.955848 -119.73052)
			(xy 230.959919 -119.674898) (xy 230.972045 -119.620461) (xy 230.991968 -119.56837) (xy 231.019264 -119.519735)
			(xy 231.05335 -119.475592) (xy 231.093499 -119.436883) (xy 231.138857 -119.404432) (xy 231.188457 -119.378931)
			(xy 231.241241 -119.360924) (xy 231.296084 -119.350794) (xy 231.351818 -119.348757) (xy 231.407255 -119.354857)
			(xy 231.461212 -119.368963) (xy 231.512541 -119.390775) (xy 231.560147 -119.419829) (xy 231.603015 -119.455504)
			(xy 231.640232 -119.497041) (xy 231.671005 -119.543554) (xy 231.694677 -119.594051) (xy 231.710745 -119.647458)
			(xy 231.718865 -119.702634) (xy 231.719374 -119.73052) (xy 231.718865 -119.758406) (xy 231.710745 -119.813582)
			(xy 231.694677 -119.866989) (xy 231.671005 -119.917486) (xy 231.640232 -119.963999) (xy 231.603015 -120.005536)
			(xy 231.560147 -120.041211) (xy 231.512541 -120.070265) (xy 231.461212 -120.092077) (xy 231.407255 -120.106183)
			(xy 231.351818 -120.112283) (xy 231.296084 -120.110246) (xy 231.241241 -120.100116) (xy 231.188457 -120.082109)
			(xy 231.138857 -120.056608) (xy 231.093499 -120.024157) (xy 231.05335 -119.985448) (xy 231.019264 -119.941305)
			(xy 230.991968 -119.89267) (xy 230.972045 -119.840579) (xy 230.959919 -119.786142) (xy 230.955848 -119.73052)
			(xy 226.638442 -119.73052) (xy 226.648886 -119.754333) (xy 226.663205 -119.804979) (xy 226.670431 -119.857112)
			(xy 226.67087 -119.883428) (xy 226.670384 -119.910679) (xy 226.662628 -119.964627) (xy 226.647273 -120.016922)
			(xy 226.624631 -120.066499) (xy 226.595165 -120.112349) (xy 226.559474 -120.15354) (xy 226.518283 -120.189231)
			(xy 226.472433 -120.218697) (xy 226.422856 -120.241339) (xy 226.370561 -120.256694) (xy 226.316613 -120.26445)
			(xy 226.262111 -120.26445) (xy 226.208163 -120.256694) (xy 226.155868 -120.241339) (xy 226.106291 -120.218697)
			(xy 226.060441 -120.189231) (xy 226.01925 -120.15354) (xy 225.983559 -120.112349) (xy 225.954093 -120.066499)
			(xy 225.931451 -120.016922) (xy 225.916096 -119.964627) (xy 225.90834 -119.910679) (xy 225.907854 -119.883428)
			(xy 225.908256 -119.857112) (xy 225.915502 -119.80498) (xy 225.929833 -119.754335) (xy 225.950977 -119.706136)
			(xy 225.978536 -119.661294) (xy 226.011987 -119.620658) (xy 226.031044 -119.602504) (xy 226.038438 -119.594975)
			(xy 226.046968 -119.575701) (xy 226.047554 -119.565166) (xy 226.047554 -119.49049) (xy 226.047057 -119.479936)
			(xy 226.038501 -119.46064) (xy 226.031044 -119.453152) (xy 226.010286 -119.433303) (xy 225.974314 -119.388533)
			(xy 225.945456 -119.338879) (xy 225.924364 -119.285462) (xy 225.911514 -119.229487) (xy 225.907197 -119.172219)
			(xy 224.133346 -119.172219) (xy 224.129028 -119.229493) (xy 224.116176 -119.285474) (xy 224.095082 -119.338897)
			(xy 224.066222 -119.388557) (xy 224.030246 -119.433331) (xy 224.009458 -119.453152) (xy 224.00204 -119.46066)
			(xy 223.993523 -119.47995) (xy 223.992948 -119.49049) (xy 223.992948 -119.565166) (xy 223.993468 -119.575717)
			(xy 224.002008 -119.595013) (xy 224.009458 -119.602504) (xy 224.02852 -119.620653) (xy 224.061974 -119.661286)
			(xy 224.089531 -119.706128) (xy 224.110668 -119.754329) (xy 224.124984 -119.804977) (xy 224.132209 -119.857112)
			(xy 224.132648 -119.883428) (xy 224.132162 -119.910679) (xy 224.124406 -119.964627) (xy 224.109051 -120.016922)
			(xy 224.086409 -120.066499) (xy 224.056943 -120.112349) (xy 224.021252 -120.15354) (xy 223.980061 -120.189231)
			(xy 223.934211 -120.218697) (xy 223.884634 -120.241339) (xy 223.832339 -120.256694) (xy 223.778391 -120.26445)
			(xy 223.723889 -120.26445) (xy 223.669941 -120.256694) (xy 223.617646 -120.241339) (xy 223.568069 -120.218697)
			(xy 223.522219 -120.189231) (xy 223.481028 -120.15354) (xy 223.445337 -120.112349) (xy 223.415871 -120.066499)
			(xy 223.393229 -120.016922) (xy 223.377874 -119.964627) (xy 223.370118 -119.910679) (xy 223.369632 -119.883428)
			(xy 223.370041 -119.857112) (xy 223.377287 -119.80498) (xy 223.391616 -119.754336) (xy 223.41276 -119.706137)
			(xy 223.440316 -119.661295) (xy 223.473765 -119.620659) (xy 223.492822 -119.602504) (xy 223.500227 -119.594986)
			(xy 223.508749 -119.575703) (xy 223.509332 -119.565166) (xy 223.509332 -119.49049) (xy 223.508812 -119.479939)
			(xy 223.500269 -119.460645) (xy 223.492822 -119.453152) (xy 223.47206 -119.433305) (xy 223.436081 -119.388538)
			(xy 223.407217 -119.338885) (xy 223.386121 -119.285466) (xy 223.373268 -119.22949) (xy 223.36895 -119.172219)
			(xy 221.571978 -119.172219) (xy 221.561939 -119.206408) (xy 221.539297 -119.255985) (xy 221.509831 -119.301835)
			(xy 221.47414 -119.343026) (xy 221.432949 -119.378717) (xy 221.387099 -119.408183) (xy 221.337522 -119.430825)
			(xy 221.285227 -119.44618) (xy 221.231279 -119.453936) (xy 221.176777 -119.453936) (xy 221.122829 -119.44618)
			(xy 221.070534 -119.430825) (xy 221.020957 -119.408183) (xy 220.975107 -119.378717) (xy 220.933916 -119.343026)
			(xy 220.898225 -119.301835) (xy 220.868759 -119.255985) (xy 220.846117 -119.206408) (xy 220.830762 -119.154113)
			(xy 220.823006 -119.100165) (xy 220.82252 -119.072914) (xy 219.553536 -119.072914) (xy 219.55305 -119.100165)
			(xy 219.545294 -119.154113) (xy 219.529939 -119.206408) (xy 219.507297 -119.255985) (xy 219.477831 -119.301835)
			(xy 219.44214 -119.343026) (xy 219.400949 -119.378717) (xy 219.355099 -119.408183) (xy 219.305522 -119.430825)
			(xy 219.253227 -119.44618) (xy 219.199279 -119.453936) (xy 219.144777 -119.453936) (xy 219.090829 -119.44618)
			(xy 219.038534 -119.430825) (xy 218.988957 -119.408183) (xy 218.943107 -119.378717) (xy 218.901916 -119.343026)
			(xy 218.866225 -119.301835) (xy 218.836759 -119.255985) (xy 218.814117 -119.206408) (xy 218.798762 -119.154113)
			(xy 218.791006 -119.100165) (xy 218.79052 -119.072914) (xy 217.521536 -119.072914) (xy 217.52105 -119.100165)
			(xy 217.513294 -119.154113) (xy 217.497939 -119.206408) (xy 217.475297 -119.255985) (xy 217.445831 -119.301835)
			(xy 217.41014 -119.343026) (xy 217.368949 -119.378717) (xy 217.323099 -119.408183) (xy 217.273522 -119.430825)
			(xy 217.221227 -119.44618) (xy 217.167279 -119.453936) (xy 217.112777 -119.453936) (xy 217.058829 -119.44618)
			(xy 217.006534 -119.430825) (xy 216.956957 -119.408183) (xy 216.911107 -119.378717) (xy 216.869916 -119.343026)
			(xy 216.834225 -119.301835) (xy 216.804759 -119.255985) (xy 216.782117 -119.206408) (xy 216.766762 -119.154113)
			(xy 216.759006 -119.100165) (xy 216.75852 -119.072914) (xy 216.436342 -119.072914) (xy 216.442739 -119.086559)
			(xy 216.458807 -119.139966) (xy 216.466927 -119.195142) (xy 216.467436 -119.223028) (xy 216.466927 -119.250914)
			(xy 216.458807 -119.30609) (xy 216.442739 -119.359497) (xy 216.419067 -119.409994) (xy 216.388294 -119.456507)
			(xy 216.351077 -119.498044) (xy 216.308209 -119.533719) (xy 216.260603 -119.562773) (xy 216.209274 -119.584585)
			(xy 216.155317 -119.598691) (xy 216.09988 -119.604791) (xy 216.044146 -119.602754) (xy 215.989303 -119.592624)
			(xy 215.936519 -119.574617) (xy 215.886919 -119.549116) (xy 215.841561 -119.516665) (xy 215.801412 -119.477956)
			(xy 215.767326 -119.433813) (xy 215.74003 -119.385178) (xy 215.720107 -119.333087) (xy 215.707981 -119.27865)
			(xy 215.70391 -119.223028) (xy 207.966867 -119.223028) (xy 207.946183 -119.266414) (xy 207.914508 -119.31339)
			(xy 207.876238 -119.355167) (xy 207.832213 -119.390828) (xy 207.808068 -119.405654) (xy 207.800771 -119.410375)
			(xy 207.789587 -119.423659) (xy 207.783456 -119.439907) (xy 207.782922 -119.44858) (xy 207.781652 -119.535194)
			(xy 207.781921 -119.543867) (xy 207.787448 -119.560299) (xy 207.798142 -119.573943) (xy 207.805274 -119.578882)
			(xy 207.828199 -119.593999) (xy 207.869907 -119.629718) (xy 207.906067 -119.671043) (xy 207.935935 -119.717122)
			(xy 207.958893 -119.767004) (xy 207.974469 -119.819661) (xy 207.982341 -119.874006) (xy 207.98282 -119.901462)
			(xy 207.982309 -119.928713) (xy 207.974558 -119.982662) (xy 207.959207 -120.034958) (xy 207.93657 -120.084537)
			(xy 207.907107 -120.13039) (xy 207.871418 -120.171583) (xy 207.83023 -120.207277) (xy 207.784381 -120.236746)
			(xy 207.734805 -120.25939) (xy 207.682511 -120.274747) (xy 207.628563 -120.282506) (xy 207.601312 -120.28297)
			(xy 207.573942 -120.282504) (xy 207.519762 -120.274687) (xy 207.467259 -120.259199) (xy 207.417512 -120.236357)
			(xy 207.371545 -120.206632) (xy 207.350614 -120.18899) (xy 207.35036 -120.188736) (xy 207.343266 -120.183161)
			(xy 207.326355 -120.176909) (xy 207.31734 -120.176544) (xy 207.250284 -120.176544) (xy 207.241265 -120.176884)
			(xy 207.224348 -120.183142) (xy 207.217264 -120.188736) (xy 207.217264 -120.18899) (xy 207.21701 -120.18899)
			(xy 207.196084 -120.206636) (xy 207.150109 -120.236347) (xy 207.100361 -120.259182) (xy 207.047858 -120.274671)
			(xy 206.993682 -120.282497) (xy 206.966312 -120.28297) (xy 206.939058 -120.282533) (xy 206.885104 -120.274777)
			(xy 206.832803 -120.259421) (xy 206.783221 -120.236777) (xy 206.737366 -120.207306) (xy 206.696172 -120.17161)
			(xy 206.660478 -120.130414) (xy 206.631011 -120.084557) (xy 206.60837 -120.034972) (xy 206.593017 -119.982671)
			(xy 206.585265 -119.928716) (xy 206.584804 -119.901462) (xy 206.585272 -119.875526) (xy 206.592293 -119.824132)
			(xy 206.606213 -119.774163) (xy 206.626776 -119.726542) (xy 206.653603 -119.682146) (xy 206.686198 -119.641795)
			(xy 206.723961 -119.606233) (xy 206.744824 -119.59082) (xy 206.755746 -119.5832) (xy 206.766922 -119.55907)
			(xy 206.759556 -119.458994) (xy 206.758535 -119.450283) (xy 206.751384 -119.43428) (xy 206.739282 -119.421601)
			(xy 206.731616 -119.417338) (xy 206.708293 -119.405108) (xy 206.664963 -119.375173) (xy 206.626166 -119.339561)
			(xy 206.592639 -119.298948) (xy 206.56502 -119.254107) (xy 206.543835 -119.205892) (xy 206.529488 -119.15522)
			(xy 206.52225 -119.103056) (xy 206.521812 -119.076724) (xy 206.308435 -119.076724) (xy 206.305278 -119.098587)
			(xy 206.289782 -119.151091) (xy 206.266931 -119.200838) (xy 206.237198 -119.246802) (xy 206.219552 -119.267732)
			(xy 206.219298 -119.267986) (xy 206.213711 -119.275072) (xy 206.207465 -119.291989) (xy 206.207106 -119.301006)
			(xy 206.207106 -119.368062) (xy 206.20748 -119.377077) (xy 206.213716 -119.393994) (xy 206.219298 -119.401082)
			(xy 206.219552 -119.401082) (xy 206.219552 -119.401336) (xy 206.237227 -119.422241) (xy 206.266952 -119.468213)
			(xy 206.289797 -119.517964) (xy 206.305291 -119.57047) (xy 206.313117 -119.624653) (xy 206.313113 -119.679398)
			(xy 206.30528 -119.73358) (xy 206.289779 -119.786084) (xy 206.266927 -119.835832) (xy 206.237196 -119.8818)
			(xy 206.219552 -119.902732) (xy 206.219298 -119.902986) (xy 206.213711 -119.910072) (xy 206.207465 -119.926989)
			(xy 206.207106 -119.936006) (xy 206.207106 -120.003062) (xy 206.20748 -120.012077) (xy 206.213716 -120.028994)
			(xy 206.219298 -120.036082) (xy 206.219552 -120.036082) (xy 206.219552 -120.036336) (xy 206.237227 -120.057241)
			(xy 206.266952 -120.103213) (xy 206.289797 -120.152964) (xy 206.305291 -120.20547) (xy 206.313117 -120.259653)
			(xy 206.313113 -120.314398) (xy 206.310753 -120.330722) (xy 208.104232 -120.330722) (xy 208.104703 -120.303352)
			(xy 208.112519 -120.249173) (xy 208.128006 -120.196669) (xy 208.150847 -120.146922) (xy 208.180571 -120.100956)
			(xy 208.198212 -120.080024) (xy 208.198466 -120.07977) (xy 208.204037 -120.072673) (xy 208.210291 -120.055764)
			(xy 208.210658 -120.04675) (xy 208.210658 -119.979694) (xy 208.210313 -119.970676) (xy 208.204058 -119.953759)
			(xy 208.198466 -119.946674) (xy 208.198212 -119.946674) (xy 208.198212 -119.94642) (xy 208.180571 -119.92549)
			(xy 208.150859 -119.879517) (xy 208.128023 -119.829769) (xy 208.112533 -119.777268) (xy 208.104705 -119.723091)
			(xy 208.104232 -119.695722) (xy 208.104676 -119.668468) (xy 208.112431 -119.614514) (xy 208.127786 -119.562214)
			(xy 208.150429 -119.512631) (xy 208.179898 -119.466776) (xy 208.215594 -119.425582) (xy 208.25679 -119.389888)
			(xy 208.302647 -119.36042) (xy 208.35223 -119.33778) (xy 208.404532 -119.322427) (xy 208.458486 -119.314675)
			(xy 208.48574 -119.314214) (xy 208.514863 -119.314748) (xy 208.572435 -119.32358) (xy 208.627995 -119.341064)
			(xy 208.680251 -119.366792) (xy 208.727987 -119.400166) (xy 208.770093 -119.440411) (xy 208.80559 -119.48659)
			(xy 208.833653 -119.53763) (xy 208.853629 -119.592343) (xy 208.859882 -119.620792) (xy 208.862168 -119.632476)
			(xy 208.876646 -119.651272) (xy 208.96072 -119.691658) (xy 208.971533 -119.696221) (xy 208.994973 -119.69596)
			(xy 209.005678 -119.69115) (xy 209.006186 -119.69115) (xy 209.033242 -119.677863) (xy 209.090519 -119.659086)
			(xy 209.150038 -119.649569) (xy 209.180176 -119.648986) (xy 209.207428 -119.649478) (xy 209.261378 -119.657231)
			(xy 209.313675 -119.672584) (xy 209.363254 -119.695223) (xy 209.409107 -119.724688) (xy 209.4503 -119.760379)
			(xy 209.485994 -119.801569) (xy 209.515462 -119.847419) (xy 209.538106 -119.896997) (xy 209.553462 -119.949293)
			(xy 209.56122 -120.003242) (xy 209.561684 -120.030494) (xy 209.561218 -120.057864) (xy 209.553401 -120.112044)
			(xy 209.538869 -120.161304) (xy 213.683848 -120.161304) (xy 213.687919 -120.105682) (xy 213.700045 -120.051245)
			(xy 213.719968 -119.999154) (xy 213.747264 -119.950519) (xy 213.78135 -119.906376) (xy 213.821499 -119.867667)
			(xy 213.866857 -119.835216) (xy 213.916457 -119.809715) (xy 213.969241 -119.791708) (xy 214.024084 -119.781578)
			(xy 214.079818 -119.779541) (xy 214.135255 -119.785641) (xy 214.189212 -119.799747) (xy 214.240541 -119.821559)
			(xy 214.288147 -119.850613) (xy 214.331015 -119.886288) (xy 214.368232 -119.927825) (xy 214.399005 -119.974338)
			(xy 214.422677 -120.024835) (xy 214.438745 -120.078242) (xy 214.446865 -120.133418) (xy 214.447374 -120.161304)
			(xy 214.446865 -120.18919) (xy 214.439531 -120.239028) (xy 215.72931 -120.239028) (xy 215.733381 -120.183406)
			(xy 215.745507 -120.128969) (xy 215.76543 -120.076878) (xy 215.792726 -120.028243) (xy 215.826812 -119.9841)
			(xy 215.866961 -119.945391) (xy 215.912319 -119.91294) (xy 215.961919 -119.887439) (xy 216.014703 -119.869432)
			(xy 216.069546 -119.859302) (xy 216.12528 -119.857265) (xy 216.180717 -119.863365) (xy 216.234674 -119.877471)
			(xy 216.286003 -119.899283) (xy 216.333609 -119.928337) (xy 216.376477 -119.964012) (xy 216.413694 -120.005549)
			(xy 216.444467 -120.052062) (xy 216.468139 -120.102559) (xy 216.484207 -120.155966) (xy 216.492327 -120.211142)
			(xy 216.492836 -120.239028) (xy 216.492327 -120.266914) (xy 216.484207 -120.32209) (xy 216.468139 -120.375497)
			(xy 216.444467 -120.425994) (xy 216.413694 -120.472507) (xy 216.376477 -120.514044) (xy 216.333609 -120.549719)
			(xy 216.286003 -120.578773) (xy 216.234674 -120.600585) (xy 216.180717 -120.614691) (xy 216.12528 -120.620791)
			(xy 216.069546 -120.618754) (xy 216.014703 -120.608624) (xy 215.961919 -120.590617) (xy 215.912319 -120.565116)
			(xy 215.866961 -120.532665) (xy 215.826812 -120.493956) (xy 215.792726 -120.449813) (xy 215.76543 -120.401178)
			(xy 215.745507 -120.349087) (xy 215.733381 -120.29465) (xy 215.72931 -120.239028) (xy 214.439531 -120.239028)
			(xy 214.438745 -120.244366) (xy 214.422677 -120.297773) (xy 214.399005 -120.34827) (xy 214.368232 -120.394783)
			(xy 214.331015 -120.43632) (xy 214.288147 -120.471995) (xy 214.240541 -120.501049) (xy 214.189212 -120.522861)
			(xy 214.135255 -120.536967) (xy 214.079818 -120.543067) (xy 214.024084 -120.54103) (xy 213.969241 -120.5309)
			(xy 213.916457 -120.512893) (xy 213.866857 -120.487392) (xy 213.821499 -120.454941) (xy 213.78135 -120.416232)
			(xy 213.747264 -120.372089) (xy 213.719968 -120.323454) (xy 213.700045 -120.271363) (xy 213.687919 -120.216926)
			(xy 213.683848 -120.161304) (xy 209.538869 -120.161304) (xy 209.537912 -120.164547) (xy 209.51507 -120.214294)
			(xy 209.485345 -120.26026) (xy 209.467704 -120.281192) (xy 209.46745 -120.281446) (xy 209.461874 -120.28854)
			(xy 209.455622 -120.305451) (xy 209.455258 -120.314466) (xy 209.455258 -120.381522) (xy 209.455592 -120.390541)
			(xy 209.461854 -120.407459) (xy 209.46745 -120.414542) (xy 209.467704 -120.414542) (xy 209.467704 -120.414796)
			(xy 209.485355 -120.435718) (xy 209.515065 -120.481694) (xy 209.537899 -120.531444) (xy 209.553387 -120.583947)
			(xy 209.561212 -120.638124) (xy 209.561684 -120.665494) (xy 209.561239 -120.692748) (xy 209.553482 -120.746701)
			(xy 209.543765 -120.779794) (xy 230.950768 -120.779794) (xy 230.954839 -120.724172) (xy 230.966965 -120.669735)
			(xy 230.986888 -120.617644) (xy 231.014184 -120.569009) (xy 231.04827 -120.524866) (xy 231.088419 -120.486157)
			(xy 231.133777 -120.453706) (xy 231.183377 -120.428205) (xy 231.236161 -120.410198) (xy 231.291004 -120.400068)
			(xy 231.346738 -120.398031) (xy 231.402175 -120.404131) (xy 231.456132 -120.418237) (xy 231.507461 -120.440049)
			(xy 231.555067 -120.469103) (xy 231.597935 -120.504778) (xy 231.635152 -120.546315) (xy 231.665925 -120.592828)
			(xy 231.689597 -120.643325) (xy 231.705665 -120.696732) (xy 231.713785 -120.751908) (xy 231.714294 -120.779794)
			(xy 231.713785 -120.80768) (xy 231.705665 -120.862856) (xy 231.689597 -120.916263) (xy 231.665925 -120.96676)
			(xy 231.635152 -121.013273) (xy 231.597935 -121.05481) (xy 231.555067 -121.090485) (xy 231.507461 -121.119539)
			(xy 231.456132 -121.141351) (xy 231.402175 -121.155457) (xy 231.346738 -121.161557) (xy 231.291004 -121.15952)
			(xy 231.236161 -121.14939) (xy 231.183377 -121.131383) (xy 231.133777 -121.105882) (xy 231.088419 -121.073431)
			(xy 231.04827 -121.034722) (xy 231.014184 -120.990579) (xy 230.986888 -120.941944) (xy 230.966965 -120.889853)
			(xy 230.954839 -120.835416) (xy 230.950768 -120.779794) (xy 209.543765 -120.779794) (xy 209.538126 -120.799)
			(xy 209.515482 -120.848582) (xy 209.486013 -120.894436) (xy 209.450317 -120.93563) (xy 209.409122 -120.971323)
			(xy 209.363266 -121.000791) (xy 209.313683 -121.023432) (xy 209.261383 -121.038786) (xy 209.20743 -121.04654)
			(xy 209.180176 -121.047002) (xy 209.151054 -121.046441) (xy 209.093484 -121.037611) (xy 209.037925 -121.020131)
			(xy 208.98567 -120.994406) (xy 208.937935 -120.961035) (xy 208.895828 -120.920794) (xy 208.86033 -120.874618)
			(xy 208.832266 -120.823582) (xy 208.812288 -120.768872) (xy 208.806034 -120.740424) (xy 208.803748 -120.72874)
			(xy 208.78927 -120.709944) (xy 208.705196 -120.669558) (xy 208.694379 -120.665004) (xy 208.670943 -120.665258)
			(xy 208.660238 -120.670066) (xy 208.65973 -120.670066) (xy 208.632671 -120.683349) (xy 208.575396 -120.702127)
			(xy 208.515877 -120.711646) (xy 208.48574 -120.71223) (xy 208.458489 -120.711708) (xy 208.404541 -120.703957)
			(xy 208.352246 -120.688607) (xy 208.302668 -120.665971) (xy 208.256815 -120.636509) (xy 208.215623 -120.600821)
			(xy 208.179928 -120.559634) (xy 208.150459 -120.513787) (xy 208.127815 -120.464212) (xy 208.112457 -120.411919)
			(xy 208.104697 -120.357973) (xy 208.104232 -120.330722) (xy 206.310753 -120.330722) (xy 206.30528 -120.36858)
			(xy 206.289779 -120.421084) (xy 206.266927 -120.470832) (xy 206.237196 -120.5168) (xy 206.219552 -120.537732)
			(xy 206.219298 -120.537986) (xy 206.213711 -120.545072) (xy 206.207465 -120.561989) (xy 206.207106 -120.571006)
			(xy 206.207106 -120.638062) (xy 206.20748 -120.647077) (xy 206.213716 -120.663994) (xy 206.219298 -120.671082)
			(xy 206.219552 -120.671082) (xy 206.219552 -120.671336) (xy 206.237167 -120.692288) (xy 206.266884 -120.738254)
			(xy 206.289726 -120.787997) (xy 206.305222 -120.840493) (xy 206.313055 -120.894666) (xy 206.313532 -120.922034)
			(xy 206.313046 -120.949285) (xy 206.30529 -121.003233) (xy 206.289935 -121.055528) (xy 206.267293 -121.105105)
			(xy 206.237827 -121.150955) (xy 206.202136 -121.192146) (xy 206.160945 -121.227837) (xy 206.118635 -121.255028)
			(xy 215.705434 -121.255028) (xy 215.709505 -121.199406) (xy 215.721631 -121.144969) (xy 215.741554 -121.092878)
			(xy 215.76885 -121.044243) (xy 215.802936 -121.0001) (xy 215.843085 -120.961391) (xy 215.888443 -120.92894)
			(xy 215.938043 -120.903439) (xy 215.990827 -120.885432) (xy 216.04567 -120.875302) (xy 216.101404 -120.873265)
			(xy 216.156841 -120.879365) (xy 216.210798 -120.893471) (xy 216.262127 -120.915283) (xy 216.309733 -120.944337)
			(xy 216.352601 -120.980012) (xy 216.389818 -121.021549) (xy 216.420591 -121.068062) (xy 216.444263 -121.118559)
			(xy 216.460331 -121.171966) (xy 216.468451 -121.227142) (xy 216.46896 -121.255028) (xy 216.468451 -121.282914)
			(xy 216.460331 -121.33809) (xy 216.444263 -121.391497) (xy 216.420591 -121.441994) (xy 216.389818 -121.488507)
			(xy 216.352601 -121.530044) (xy 216.309733 -121.565719) (xy 216.262127 -121.594773) (xy 216.210798 -121.616585)
			(xy 216.156841 -121.630691) (xy 216.101404 -121.636791) (xy 216.04567 -121.634754) (xy 215.990827 -121.624624)
			(xy 215.938043 -121.606617) (xy 215.888443 -121.581116) (xy 215.843085 -121.548665) (xy 215.802936 -121.509956)
			(xy 215.76885 -121.465813) (xy 215.741554 -121.417178) (xy 215.721631 -121.365087) (xy 215.709505 -121.31065)
			(xy 215.705434 -121.255028) (xy 206.118635 -121.255028) (xy 206.115095 -121.257303) (xy 206.065518 -121.279945)
			(xy 206.013223 -121.2953) (xy 205.959275 -121.303056) (xy 205.904773 -121.303056) (xy 205.850825 -121.2953)
			(xy 205.79853 -121.279945) (xy 205.748953 -121.257303) (xy 205.703103 -121.227837) (xy 205.661912 -121.192146)
			(xy 205.626221 -121.150955) (xy 205.596755 -121.105105) (xy 205.574113 -121.055528) (xy 205.558758 -121.003233)
			(xy 205.551002 -120.949285) (xy 205.550516 -120.922034) (xy 205.18882 -120.922034) (xy 205.18882 -121.664984)
			(xy 205.189248 -121.675053) (xy 205.196966 -121.693651) (xy 205.203806 -121.701052) (xy 205.576932 -122.074178)
			(xy 205.584329 -122.081022) (xy 205.602931 -122.08874) (xy 205.613 -122.089164) (xy 208.058512 -122.089164)
			(xy 208.063402 -122.089315) (xy 208.072994 -122.091224) (xy 208.077562 -122.092974) (xy 208.081479 -122.094549)
			(xy 210.164198 -122.094549) (xy 210.164198 -122.040051) (xy 210.171954 -121.986109) (xy 210.187306 -121.933819)
			(xy 210.209944 -121.884247) (xy 210.239406 -121.8384) (xy 210.275093 -121.797213) (xy 210.316278 -121.761523)
			(xy 210.362122 -121.732058) (xy 210.411693 -121.709416) (xy 210.463982 -121.694059) (xy 210.517924 -121.6863)
			(xy 210.545172 -121.685812) (xy 210.572542 -121.686292) (xy 210.62672 -121.694106) (xy 210.679223 -121.709591)
			(xy 210.728971 -121.73243) (xy 210.774938 -121.762152) (xy 210.79587 -121.779792) (xy 210.796124 -121.780046)
			(xy 210.803196 -121.785654) (xy 210.820124 -121.791887) (xy 210.829144 -121.792238) (xy 210.8962 -121.792238)
			(xy 210.905216 -121.791873) (xy 210.922132 -121.78563) (xy 210.92922 -121.780046) (xy 210.92922 -121.779792)
			(xy 210.929474 -121.779792) (xy 210.950407 -121.762151) (xy 210.996375 -121.732427) (xy 211.046121 -121.709581)
			(xy 211.098623 -121.694085) (xy 211.152801 -121.686256) (xy 211.207543 -121.686256) (xy 211.261721 -121.694085)
			(xy 211.314223 -121.709581) (xy 211.363969 -121.732427) (xy 211.409937 -121.762151) (xy 211.43087 -121.779792)
			(xy 211.431124 -121.780046) (xy 211.438196 -121.785654) (xy 211.455124 -121.791887) (xy 211.464144 -121.792238)
			(xy 211.5312 -121.792238) (xy 211.540216 -121.791873) (xy 211.557132 -121.78563) (xy 211.56422 -121.780046)
			(xy 211.56422 -121.779792) (xy 211.564474 -121.779792) (xy 211.585404 -121.76215) (xy 211.631378 -121.732439)
			(xy 211.681126 -121.709604) (xy 211.733627 -121.694113) (xy 211.787803 -121.686286) (xy 211.815172 -121.685812)
			(xy 211.842428 -121.686233) (xy 211.896384 -121.693987) (xy 211.948688 -121.709342) (xy 211.998275 -121.731984)
			(xy 212.044134 -121.761452) (xy 212.085332 -121.797148) (xy 212.121031 -121.838344) (xy 212.150503 -121.884201)
			(xy 212.173149 -121.933785) (xy 212.188507 -121.986088) (xy 212.196265 -122.040044) (xy 212.196265 -122.094556)
			(xy 212.188507 -122.148512) (xy 212.173149 -122.200815) (xy 212.150503 -122.250399) (xy 212.121031 -122.296256)
			(xy 212.085332 -122.337452) (xy 212.044134 -122.373148) (xy 211.998275 -122.402616) (xy 211.948688 -122.425258)
			(xy 211.896384 -122.440613) (xy 211.842428 -122.448367) (xy 211.815172 -122.448828) (xy 211.7878 -122.448396)
			(xy 211.733619 -122.440573) (xy 211.681115 -122.425077) (xy 211.631369 -122.402227) (xy 211.585404 -122.372494)
			(xy 211.564474 -122.354848) (xy 211.56422 -122.354594) (xy 211.557132 -122.349009) (xy 211.540216 -122.342762)
			(xy 211.5312 -122.342402) (xy 211.464144 -122.342402) (xy 211.455129 -122.34278) (xy 211.438212 -122.349013)
			(xy 211.431124 -122.354594) (xy 211.43087 -122.354848) (xy 211.409937 -122.372489) (xy 211.363969 -122.402213)
			(xy 211.314223 -122.425059) (xy 211.261721 -122.440555) (xy 211.207543 -122.448384) (xy 211.152801 -122.448384)
			(xy 211.098623 -122.440555) (xy 211.046121 -122.425059) (xy 210.996375 -122.402213) (xy 210.950407 -122.372489)
			(xy 210.929474 -122.354848) (xy 210.92922 -122.354594) (xy 210.922132 -122.349009) (xy 210.905216 -122.342762)
			(xy 210.8962 -122.342402) (xy 210.829144 -122.342402) (xy 210.820129 -122.34278) (xy 210.803212 -122.349013)
			(xy 210.796124 -122.354594) (xy 210.796124 -122.354848) (xy 210.79587 -122.354848) (xy 210.774916 -122.37246)
			(xy 210.72895 -122.402177) (xy 210.679208 -122.425019) (xy 210.626712 -122.440517) (xy 210.57254 -122.448351)
			(xy 210.545172 -122.448828) (xy 210.517924 -122.4483) (xy 210.463982 -122.440541) (xy 210.411693 -122.425184)
			(xy 210.362122 -122.402542) (xy 210.316278 -122.373077) (xy 210.275093 -122.337387) (xy 210.239406 -122.2962)
			(xy 210.209944 -122.250353) (xy 210.187306 -122.200781) (xy 210.171954 -122.148491) (xy 210.164198 -122.094549)
			(xy 208.081479 -122.094549) (xy 208.173574 -122.131582) (xy 208.178483 -122.133708) (xy 208.187321 -122.139733)
			(xy 208.1911 -122.14352) (xy 208.226406 -122.180096) (xy 208.226914 -122.180604) (xy 208.421732 -122.375676)
			(xy 208.43011 -122.383251) (xy 208.45134 -122.390887) (xy 208.462626 -122.390408) (xy 208.539842 -122.382788)
			(xy 208.551012 -122.3812) (xy 208.570397 -122.369708) (xy 208.57718 -122.36069) (xy 208.57718 -122.360436)
			(xy 208.592439 -122.33848) (xy 208.628115 -122.298654) (xy 208.669 -122.264198) (xy 208.714294 -122.235786)
			(xy 208.763111 -122.213974) (xy 208.814494 -122.19919) (xy 208.867438 -122.191723) (xy 208.894172 -122.191272)
			(xy 208.921423 -122.191781) (xy 208.975371 -122.199534) (xy 209.027667 -122.214885) (xy 209.077246 -122.237523)
			(xy 209.123098 -122.266986) (xy 209.164291 -122.302675) (xy 209.199985 -122.343863) (xy 209.229454 -122.389712)
			(xy 209.252098 -122.439288) (xy 209.267456 -122.491582) (xy 209.272266 -122.525028) (xy 213.607396 -122.525028)
			(xy 213.607877 -122.49828) (xy 213.615373 -122.44531) (xy 213.630194 -122.393907) (xy 213.65205 -122.345077)
			(xy 213.680512 -122.29978) (xy 213.715021 -122.258901) (xy 213.754902 -122.223244) (xy 213.799373 -122.193506)
			(xy 213.847561 -122.170271) (xy 213.898522 -122.153995) (xy 213.951257 -122.144996) (xy 213.977982 -122.143774)
			(xy 213.991505 -122.142968) (xy 214.017415 -122.135085) (xy 214.040341 -122.120668) (xy 214.058671 -122.100731)
			(xy 214.071115 -122.076676) (xy 214.076798 -122.050197) (xy 214.075319 -122.023155) (xy 214.071454 -122.01017)
			(xy 214.062467 -121.98108) (xy 214.052766 -121.920976) (xy 214.05215 -121.890536) (xy 214.05215 -121.890028)
			(xy 214.052636 -121.862777) (xy 214.060392 -121.808829) (xy 214.075747 -121.756534) (xy 214.098389 -121.706957)
			(xy 214.127855 -121.661107) (xy 214.163546 -121.619916) (xy 214.204737 -121.584225) (xy 214.250587 -121.554759)
			(xy 214.300164 -121.532117) (xy 214.352459 -121.516762) (xy 214.406407 -121.509006) (xy 214.460909 -121.509006)
			(xy 214.514857 -121.516762) (xy 214.567152 -121.532117) (xy 214.616729 -121.554759) (xy 214.662579 -121.584225)
			(xy 214.70377 -121.619916) (xy 214.739461 -121.661107) (xy 214.768927 -121.706957) (xy 214.785371 -121.742962)
			(xy 220.459298 -121.742962) (xy 220.463369 -121.68734) (xy 220.475495 -121.632903) (xy 220.495418 -121.580812)
			(xy 220.522714 -121.532177) (xy 220.5568 -121.488034) (xy 220.596949 -121.449325) (xy 220.642307 -121.416874)
			(xy 220.691907 -121.391373) (xy 220.744691 -121.373366) (xy 220.799534 -121.363236) (xy 220.855268 -121.361199)
			(xy 220.910705 -121.367299) (xy 220.964662 -121.381405) (xy 221.015991 -121.403217) (xy 221.063597 -121.432271)
			(xy 221.106465 -121.467946) (xy 221.143682 -121.509483) (xy 221.174455 -121.555996) (xy 221.198127 -121.606493)
			(xy 221.214195 -121.6599) (xy 221.222315 -121.715076) (xy 221.222824 -121.742962) (xy 221.222315 -121.770848)
			(xy 221.214195 -121.826024) (xy 221.198127 -121.879431) (xy 221.174455 -121.929928) (xy 221.143682 -121.976441)
			(xy 221.114599 -122.0089) (xy 223.87636 -122.0089) (xy 223.880431 -121.953278) (xy 223.892557 -121.898841)
			(xy 223.91248 -121.84675) (xy 223.939776 -121.798115) (xy 223.973862 -121.753972) (xy 224.014011 -121.715263)
			(xy 224.059369 -121.682812) (xy 224.108969 -121.657311) (xy 224.161753 -121.639304) (xy 224.216596 -121.629174)
			(xy 224.27233 -121.627137) (xy 224.327767 -121.633237) (xy 224.381724 -121.647343) (xy 224.433053 -121.669155)
			(xy 224.480659 -121.698209) (xy 224.523527 -121.733884) (xy 224.560744 -121.775421) (xy 224.591517 -121.821934)
			(xy 224.615189 -121.872431) (xy 224.631257 -121.925838) (xy 224.639377 -121.981014) (xy 224.639886 -122.0089)
			(xy 224.639377 -122.036786) (xy 224.631257 -122.091962) (xy 224.615189 -122.145369) (xy 224.591517 -122.195866)
			(xy 224.560744 -122.242379) (xy 224.523527 -122.283916) (xy 224.480659 -122.319591) (xy 224.433053 -122.348645)
			(xy 224.381724 -122.370457) (xy 224.327767 -122.384563) (xy 224.27233 -122.390663) (xy 224.216596 -122.388626)
			(xy 224.161753 -122.378496) (xy 224.108969 -122.360489) (xy 224.059369 -122.334988) (xy 224.014011 -122.302537)
			(xy 223.973862 -122.263828) (xy 223.939776 -122.219685) (xy 223.91248 -122.17105) (xy 223.892557 -122.118959)
			(xy 223.880431 -122.064522) (xy 223.87636 -122.0089) (xy 221.114599 -122.0089) (xy 221.106465 -122.017978)
			(xy 221.063597 -122.053653) (xy 221.015991 -122.082707) (xy 220.964662 -122.104519) (xy 220.910705 -122.118625)
			(xy 220.855268 -122.124725) (xy 220.799534 -122.122688) (xy 220.744691 -122.112558) (xy 220.691907 -122.094551)
			(xy 220.642307 -122.06905) (xy 220.596949 -122.036599) (xy 220.5568 -121.99789) (xy 220.522714 -121.953747)
			(xy 220.495418 -121.905112) (xy 220.475495 -121.853021) (xy 220.463369 -121.798584) (xy 220.459298 -121.742962)
			(xy 214.785371 -121.742962) (xy 214.791569 -121.756534) (xy 214.806924 -121.808829) (xy 214.81468 -121.862777)
			(xy 214.815166 -121.890028) (xy 214.814681 -121.916777) (xy 214.80719 -121.969748) (xy 214.792372 -122.021154)
			(xy 214.770519 -122.069985) (xy 214.742059 -122.115285) (xy 214.707549 -122.156165) (xy 214.667667 -122.191823)
			(xy 214.623195 -122.221561) (xy 214.575005 -122.244794) (xy 214.524042 -122.261067) (xy 214.471305 -122.270062)
			(xy 214.44458 -122.271282) (xy 214.431061 -122.272115) (xy 214.40516 -122.280002) (xy 214.382241 -122.294418)
			(xy 214.363916 -122.314349) (xy 214.351472 -122.338396) (xy 214.345783 -122.364867) (xy 214.34725 -122.391903)
			(xy 214.351108 -122.404886) (xy 214.360107 -122.433973) (xy 214.3698 -122.494079) (xy 214.370412 -122.52452)
			(xy 214.370412 -122.525028) (xy 215.748868 -122.525028) (xy 215.752939 -122.469406) (xy 215.765065 -122.414969)
			(xy 215.784988 -122.362878) (xy 215.812284 -122.314243) (xy 215.84637 -122.2701) (xy 215.886519 -122.231391)
			(xy 215.931877 -122.19894) (xy 215.981477 -122.173439) (xy 216.034261 -122.155432) (xy 216.089104 -122.145302)
			(xy 216.144838 -122.143265) (xy 216.200275 -122.149365) (xy 216.254232 -122.163471) (xy 216.305561 -122.185283)
			(xy 216.353167 -122.214337) (xy 216.396035 -122.250012) (xy 216.433252 -122.291549) (xy 216.464025 -122.338062)
			(xy 216.487697 -122.388559) (xy 216.503765 -122.441966) (xy 216.511885 -122.497142) (xy 216.512394 -122.525028)
			(xy 216.511885 -122.552914) (xy 216.503765 -122.60809) (xy 216.487697 -122.661497) (xy 216.464025 -122.711994)
			(xy 216.433252 -122.758507) (xy 216.432844 -122.758962) (xy 218.430854 -122.758962) (xy 218.434925 -122.70334)
			(xy 218.447051 -122.648903) (xy 218.466974 -122.596812) (xy 218.49427 -122.548177) (xy 218.528356 -122.504034)
			(xy 218.568505 -122.465325) (xy 218.613863 -122.432874) (xy 218.663463 -122.407373) (xy 218.716247 -122.389366)
			(xy 218.77109 -122.379236) (xy 218.826824 -122.377199) (xy 218.882261 -122.383299) (xy 218.936218 -122.397405)
			(xy 218.987547 -122.419217) (xy 219.035153 -122.448271) (xy 219.078021 -122.483946) (xy 219.115238 -122.525483)
			(xy 219.146011 -122.571996) (xy 219.169683 -122.622493) (xy 219.185751 -122.6759) (xy 219.193871 -122.731076)
			(xy 219.19438 -122.758962) (xy 219.193871 -122.786848) (xy 219.185751 -122.842024) (xy 219.169683 -122.895431)
			(xy 219.146011 -122.945928) (xy 219.115238 -122.992441) (xy 219.078021 -123.033978) (xy 219.035153 -123.069653)
			(xy 218.987547 -123.098707) (xy 218.936218 -123.120519) (xy 218.882261 -123.134625) (xy 218.826824 -123.140725)
			(xy 218.77109 -123.138688) (xy 218.716247 -123.128558) (xy 218.663463 -123.110551) (xy 218.613863 -123.08505)
			(xy 218.568505 -123.052599) (xy 218.528356 -123.01389) (xy 218.49427 -122.969747) (xy 218.466974 -122.921112)
			(xy 218.447051 -122.869021) (xy 218.434925 -122.814584) (xy 218.430854 -122.758962) (xy 216.432844 -122.758962)
			(xy 216.396035 -122.800044) (xy 216.353167 -122.835719) (xy 216.305561 -122.864773) (xy 216.254232 -122.886585)
			(xy 216.200275 -122.900691) (xy 216.144838 -122.906791) (xy 216.089104 -122.904754) (xy 216.034261 -122.894624)
			(xy 215.981477 -122.876617) (xy 215.931877 -122.851116) (xy 215.886519 -122.818665) (xy 215.84637 -122.779956)
			(xy 215.812284 -122.735813) (xy 215.784988 -122.687178) (xy 215.765065 -122.635087) (xy 215.752939 -122.58065)
			(xy 215.748868 -122.525028) (xy 214.370412 -122.525028) (xy 214.369926 -122.552279) (xy 214.36217 -122.606227)
			(xy 214.346815 -122.658522) (xy 214.324173 -122.708099) (xy 214.294707 -122.753949) (xy 214.259016 -122.79514)
			(xy 214.217825 -122.830831) (xy 214.171975 -122.860297) (xy 214.122398 -122.882939) (xy 214.070103 -122.898294)
			(xy 214.016155 -122.90605) (xy 213.961653 -122.90605) (xy 213.907705 -122.898294) (xy 213.85541 -122.882939)
			(xy 213.805833 -122.860297) (xy 213.759983 -122.830831) (xy 213.718792 -122.79514) (xy 213.683101 -122.753949)
			(xy 213.653635 -122.708099) (xy 213.630993 -122.658522) (xy 213.615638 -122.606227) (xy 213.607882 -122.552279)
			(xy 213.607396 -122.525028) (xy 209.272266 -122.525028) (xy 209.275215 -122.545529) (xy 209.27568 -122.57278)
			(xy 209.275207 -122.60015) (xy 209.267392 -122.654329) (xy 209.251904 -122.706832) (xy 209.229064 -122.756579)
			(xy 209.199341 -122.802546) (xy 209.1817 -122.823478) (xy 209.181446 -122.823732) (xy 209.175875 -122.830829)
			(xy 209.16962 -122.847738) (xy 209.169254 -122.856752) (xy 209.169254 -122.923808) (xy 209.169596 -122.932827)
			(xy 209.175853 -122.949744) (xy 209.181446 -122.956828) (xy 209.1817 -122.956828) (xy 209.1817 -122.957082)
			(xy 209.19457 -122.972347) (xy 210.707522 -122.972347) (xy 210.707522 -122.917853) (xy 210.715277 -122.863913)
			(xy 210.730629 -122.811626) (xy 210.753266 -122.762057) (xy 210.782727 -122.716213) (xy 210.818412 -122.675028)
			(xy 210.859595 -122.63934) (xy 210.905437 -122.609877) (xy 210.955006 -122.587237) (xy 211.007292 -122.571882)
			(xy 211.061231 -122.564124) (xy 211.088478 -122.563636) (xy 211.116082 -122.564094) (xy 211.170715 -122.572036)
			(xy 211.223632 -122.587773) (xy 211.273727 -122.610975) (xy 211.319953 -122.641157) (xy 211.361345 -122.677689)
			(xy 211.397036 -122.719807) (xy 211.412074 -122.74296) (xy 211.420048 -122.754782) (xy 211.441213 -122.773872)
			(xy 211.466832 -122.786362) (xy 211.494906 -122.791279) (xy 211.523245 -122.78824) (xy 211.549637 -122.77748)
			(xy 211.572024 -122.759841) (xy 211.58073 -122.748548) (xy 211.596147 -122.7278) (xy 211.631687 -122.690264)
			(xy 211.67197 -122.657871) (xy 211.716258 -122.631215) (xy 211.76374 -122.610784) (xy 211.813546 -122.596953)
			(xy 211.864764 -122.589973) (xy 211.89061 -122.589544) (xy 211.917857 -122.590127) (xy 211.971797 -122.597884)
			(xy 212.024084 -122.613238) (xy 212.073654 -122.635876) (xy 212.119497 -122.665339) (xy 212.160681 -122.701026)
			(xy 212.196367 -122.742211) (xy 212.225828 -122.788055) (xy 212.248466 -122.837625) (xy 212.263819 -122.889913)
			(xy 212.271574 -122.943853) (xy 212.271574 -122.998347) (xy 212.263819 -123.052287) (xy 212.248466 -123.104575)
			(xy 212.225828 -123.154145) (xy 212.196367 -123.199989) (xy 212.160681 -123.241174) (xy 212.119497 -123.276861)
			(xy 212.073654 -123.306324) (xy 212.024084 -123.328962) (xy 211.971797 -123.344316) (xy 211.917857 -123.352073)
			(xy 211.89061 -123.35256) (xy 211.863008 -123.352036) (xy 211.808378 -123.344106) (xy 211.755463 -123.328381)
			(xy 211.705368 -123.30519) (xy 211.659141 -123.275018) (xy 211.617747 -123.238495) (xy 211.582053 -123.196385)
			(xy 211.567014 -123.173236) (xy 211.559055 -123.161403) (xy 211.537887 -123.142314) (xy 211.512265 -123.129824)
			(xy 211.484188 -123.124908) (xy 211.455847 -123.12795) (xy 211.429452 -123.138712) (xy 211.407064 -123.156354)
			(xy 211.398358 -123.167648) (xy 211.382947 -123.188401) (xy 211.347407 -123.225937) (xy 211.307123 -123.258329)
			(xy 211.262833 -123.284985) (xy 211.21535 -123.305415) (xy 211.165543 -123.319246) (xy 211.114324 -123.326223)
			(xy 211.088478 -123.326652) (xy 211.061231 -123.326076) (xy 211.007292 -123.318318) (xy 210.955006 -123.302963)
			(xy 210.905437 -123.280323) (xy 210.859595 -123.25086) (xy 210.818412 -123.215172) (xy 210.782727 -123.173987)
			(xy 210.753266 -123.128143) (xy 210.730629 -123.078574) (xy 210.715277 -123.026287) (xy 210.707522 -122.972347)
			(xy 209.19457 -122.972347) (xy 209.199344 -122.97801) (xy 209.229055 -123.023984) (xy 209.25189 -123.073732)
			(xy 209.26738 -123.126234) (xy 209.275207 -123.180411) (xy 209.27568 -123.20778) (xy 209.275226 -123.235034)
			(xy 209.267471 -123.288986) (xy 209.252116 -123.341286) (xy 209.229474 -123.390868) (xy 209.200005 -123.436723)
			(xy 209.164311 -123.477916) (xy 209.123116 -123.51361) (xy 209.077261 -123.543078) (xy 209.027679 -123.565719)
			(xy 208.975379 -123.581073) (xy 208.921426 -123.588827) (xy 208.894172 -123.589288) (xy 208.861576 -123.588624)
			(xy 208.797338 -123.577506) (xy 208.76641 -123.56719) (xy 208.754726 -123.563126) (xy 208.730596 -123.566428)
			(xy 208.653126 -123.621038) (xy 208.643539 -123.628696) (xy 208.632261 -123.650446) (xy 208.631536 -123.662694)
			(xy 208.631536 -123.735084) (xy 208.631093 -123.758292) (xy 208.624062 -123.804172) (xy 208.610174 -123.848461)
			(xy 208.589749 -123.890141) (xy 208.563257 -123.928254) (xy 208.531306 -123.961922) (xy 208.494631 -123.990372)
			(xy 208.474564 -124.002038) (xy 208.397094 -124.044964) (xy 208.389982 -124.048774) (xy 208.395824 -124.083318)
			(xy 208.398118 -124.098517) (xy 208.400532 -124.129162) (xy 208.40065 -124.144532) (xy 208.400215 -124.171903)
			(xy 208.392391 -124.226084) (xy 208.376896 -124.278588) (xy 208.354047 -124.328335) (xy 208.324315 -124.3743)
			(xy 208.30667 -124.39523) (xy 208.306416 -124.395484) (xy 208.300832 -124.402572) (xy 208.294583 -124.419488)
			(xy 208.294224 -124.428504) (xy 208.294224 -124.49556) (xy 208.294595 -124.504576) (xy 208.300832 -124.521493)
			(xy 208.306416 -124.52858) (xy 208.30667 -124.52858) (xy 208.30667 -124.528834) (xy 208.324287 -124.549784)
			(xy 208.354003 -124.595751) (xy 208.365847 -124.621544) (xy 211.274914 -124.621544) (xy 211.27534 -124.595229)
			(xy 211.282582 -124.543098) (xy 211.296909 -124.492454) (xy 211.31805 -124.444255) (xy 211.345603 -124.399413)
			(xy 211.379049 -124.358775) (xy 211.398104 -124.34062) (xy 211.405499 -124.333093) (xy 211.414027 -124.313817)
			(xy 211.414614 -124.303282) (xy 211.414614 -124.228606) (xy 211.414091 -124.218056) (xy 211.405551 -124.198761)
			(xy 211.398104 -124.191268) (xy 211.379041 -124.17312) (xy 211.345584 -124.132489) (xy 211.318026 -124.087647)
			(xy 211.296889 -124.039445) (xy 211.282573 -123.988796) (xy 211.275351 -123.936661) (xy 211.274914 -123.910344)
			(xy 211.2754 -123.883093) (xy 211.283156 -123.829145) (xy 211.298511 -123.77685) (xy 211.321153 -123.727273)
			(xy 211.350619 -123.681423) (xy 211.38631 -123.640232) (xy 211.427501 -123.604541) (xy 211.473351 -123.575075)
			(xy 211.522928 -123.552433) (xy 211.575223 -123.537078) (xy 211.629171 -123.529322) (xy 211.683673 -123.529322)
			(xy 211.737621 -123.537078) (xy 211.789916 -123.552433) (xy 211.839493 -123.575075) (xy 211.885343 -123.604541)
			(xy 211.926534 -123.640232) (xy 211.962225 -123.681423) (xy 211.991691 -123.727273) (xy 212.013471 -123.774962)
			(xy 218.430854 -123.774962) (xy 218.434925 -123.71934) (xy 218.447051 -123.664903) (xy 218.466974 -123.612812)
			(xy 218.49427 -123.564177) (xy 218.528356 -123.520034) (xy 218.568505 -123.481325) (xy 218.613863 -123.448874)
			(xy 218.663463 -123.423373) (xy 218.716247 -123.405366) (xy 218.77109 -123.395236) (xy 218.826824 -123.393199)
			(xy 218.882261 -123.399299) (xy 218.936218 -123.413405) (xy 218.987547 -123.435217) (xy 219.035153 -123.464271)
			(xy 219.078021 -123.499946) (xy 219.115238 -123.541483) (xy 219.146011 -123.587996) (xy 219.169683 -123.638493)
			(xy 219.185751 -123.6919) (xy 219.193871 -123.747076) (xy 219.19438 -123.774962) (xy 220.586298 -123.774962)
			(xy 220.590369 -123.71934) (xy 220.602495 -123.664903) (xy 220.622418 -123.612812) (xy 220.649714 -123.564177)
			(xy 220.6838 -123.520034) (xy 220.723949 -123.481325) (xy 220.769307 -123.448874) (xy 220.818907 -123.423373)
			(xy 220.871691 -123.405366) (xy 220.926534 -123.395236) (xy 220.982268 -123.393199) (xy 221.037705 -123.399299)
			(xy 221.091662 -123.413405) (xy 221.142991 -123.435217) (xy 221.190597 -123.464271) (xy 221.233465 -123.499946)
			(xy 221.241599 -123.509024) (xy 222.09836 -123.509024) (xy 222.102431 -123.453402) (xy 222.114557 -123.398965)
			(xy 222.13448 -123.346874) (xy 222.161776 -123.298239) (xy 222.195862 -123.254096) (xy 222.236011 -123.215387)
			(xy 222.281369 -123.182936) (xy 222.330969 -123.157435) (xy 222.383753 -123.139428) (xy 222.438596 -123.129298)
			(xy 222.49433 -123.127261) (xy 222.549767 -123.133361) (xy 222.603724 -123.147467) (xy 222.655053 -123.169279)
			(xy 222.702659 -123.198333) (xy 222.745527 -123.234008) (xy 222.782744 -123.275545) (xy 222.813517 -123.322058)
			(xy 222.837189 -123.372555) (xy 222.853257 -123.425962) (xy 222.861377 -123.481138) (xy 222.861886 -123.509024)
			(xy 223.888298 -123.509024) (xy 223.892369 -123.453402) (xy 223.904495 -123.398965) (xy 223.924418 -123.346874)
			(xy 223.951714 -123.298239) (xy 223.9858 -123.254096) (xy 224.025949 -123.215387) (xy 224.071307 -123.182936)
			(xy 224.120907 -123.157435) (xy 224.173691 -123.139428) (xy 224.228534 -123.129298) (xy 224.284268 -123.127261)
			(xy 224.339705 -123.133361) (xy 224.393662 -123.147467) (xy 224.444991 -123.169279) (xy 224.492597 -123.198333)
			(xy 224.535465 -123.234008) (xy 224.572682 -123.275545) (xy 224.603455 -123.322058) (xy 224.627127 -123.372555)
			(xy 224.643195 -123.425962) (xy 224.651315 -123.481138) (xy 224.651824 -123.509024) (xy 224.651606 -123.520962)
			(xy 226.047298 -123.520962) (xy 226.051369 -123.46534) (xy 226.063495 -123.410903) (xy 226.083418 -123.358812)
			(xy 226.110714 -123.310177) (xy 226.1448 -123.266034) (xy 226.184949 -123.227325) (xy 226.230307 -123.194874)
			(xy 226.279907 -123.169373) (xy 226.332691 -123.151366) (xy 226.387534 -123.141236) (xy 226.443268 -123.139199)
			(xy 226.498705 -123.145299) (xy 226.552662 -123.159405) (xy 226.603991 -123.181217) (xy 226.651597 -123.210271)
			(xy 226.694465 -123.245946) (xy 226.731682 -123.287483) (xy 226.762455 -123.333996) (xy 226.786127 -123.384493)
			(xy 226.802195 -123.4379) (xy 226.810315 -123.493076) (xy 226.810824 -123.520962) (xy 226.810315 -123.548848)
			(xy 226.802195 -123.604024) (xy 226.786127 -123.657431) (xy 226.762455 -123.707928) (xy 226.731682 -123.754441)
			(xy 226.694465 -123.795978) (xy 226.651597 -123.831653) (xy 226.603991 -123.860707) (xy 226.552662 -123.882519)
			(xy 226.498705 -123.896625) (xy 226.443268 -123.902725) (xy 226.387534 -123.900688) (xy 226.332691 -123.890558)
			(xy 226.279907 -123.872551) (xy 226.230307 -123.84705) (xy 226.184949 -123.814599) (xy 226.1448 -123.77589)
			(xy 226.110714 -123.731747) (xy 226.083418 -123.683112) (xy 226.063495 -123.631021) (xy 226.051369 -123.576584)
			(xy 226.047298 -123.520962) (xy 224.651606 -123.520962) (xy 224.651315 -123.53691) (xy 224.643195 -123.592086)
			(xy 224.627127 -123.645493) (xy 224.603455 -123.69599) (xy 224.572682 -123.742503) (xy 224.535465 -123.78404)
			(xy 224.492597 -123.819715) (xy 224.444991 -123.848769) (xy 224.393662 -123.870581) (xy 224.339705 -123.884687)
			(xy 224.284268 -123.890787) (xy 224.228534 -123.88875) (xy 224.173691 -123.87862) (xy 224.120907 -123.860613)
			(xy 224.071307 -123.835112) (xy 224.025949 -123.802661) (xy 223.9858 -123.763952) (xy 223.951714 -123.719809)
			(xy 223.924418 -123.671174) (xy 223.904495 -123.619083) (xy 223.892369 -123.564646) (xy 223.888298 -123.509024)
			(xy 222.861886 -123.509024) (xy 222.861377 -123.53691) (xy 222.853257 -123.592086) (xy 222.837189 -123.645493)
			(xy 222.813517 -123.69599) (xy 222.782744 -123.742503) (xy 222.745527 -123.78404) (xy 222.702659 -123.819715)
			(xy 222.655053 -123.848769) (xy 222.603724 -123.870581) (xy 222.549767 -123.884687) (xy 222.49433 -123.890787)
			(xy 222.438596 -123.88875) (xy 222.383753 -123.87862) (xy 222.330969 -123.860613) (xy 222.281369 -123.835112)
			(xy 222.236011 -123.802661) (xy 222.195862 -123.763952) (xy 222.161776 -123.719809) (xy 222.13448 -123.671174)
			(xy 222.114557 -123.619083) (xy 222.102431 -123.564646) (xy 222.09836 -123.509024) (xy 221.241599 -123.509024)
			(xy 221.270682 -123.541483) (xy 221.301455 -123.587996) (xy 221.325127 -123.638493) (xy 221.341195 -123.6919)
			(xy 221.349315 -123.747076) (xy 221.349824 -123.774962) (xy 221.349315 -123.802848) (xy 221.341195 -123.858024)
			(xy 221.325127 -123.911431) (xy 221.301455 -123.961928) (xy 221.270682 -124.008441) (xy 221.233465 -124.049978)
			(xy 221.190597 -124.085653) (xy 221.142991 -124.114707) (xy 221.091662 -124.136519) (xy 221.037705 -124.150625)
			(xy 220.982268 -124.156725) (xy 220.926534 -124.154688) (xy 220.871691 -124.144558) (xy 220.818907 -124.126551)
			(xy 220.769307 -124.10105) (xy 220.723949 -124.068599) (xy 220.6838 -124.02989) (xy 220.649714 -123.985747)
			(xy 220.622418 -123.937112) (xy 220.602495 -123.885021) (xy 220.590369 -123.830584) (xy 220.586298 -123.774962)
			(xy 219.19438 -123.774962) (xy 219.193871 -123.802848) (xy 219.185751 -123.858024) (xy 219.169683 -123.911431)
			(xy 219.146011 -123.961928) (xy 219.115238 -124.008441) (xy 219.078021 -124.049978) (xy 219.035153 -124.085653)
			(xy 218.987547 -124.114707) (xy 218.936218 -124.136519) (xy 218.882261 -124.150625) (xy 218.826824 -124.156725)
			(xy 218.77109 -124.154688) (xy 218.716247 -124.144558) (xy 218.663463 -124.126551) (xy 218.613863 -124.10105)
			(xy 218.568505 -124.068599) (xy 218.528356 -124.02989) (xy 218.49427 -123.985747) (xy 218.466974 -123.937112)
			(xy 218.447051 -123.885021) (xy 218.434925 -123.830584) (xy 218.430854 -123.774962) (xy 212.013471 -123.774962)
			(xy 212.014333 -123.77685) (xy 212.029688 -123.829145) (xy 212.037444 -123.883093) (xy 212.03793 -123.910344)
			(xy 212.037482 -123.936659) (xy 212.030242 -123.988788) (xy 212.015918 -124.03943) (xy 211.994782 -124.087629)
			(xy 211.967233 -124.132472) (xy 211.933792 -124.173111) (xy 211.91474 -124.191268) (xy 211.907357 -124.198805)
			(xy 211.898821 -124.218073) (xy 211.89823 -124.228606) (xy 211.89823 -124.303282) (xy 211.898746 -124.313833)
			(xy 211.90729 -124.333129) (xy 211.91474 -124.34062) (xy 211.933806 -124.358765) (xy 211.967261 -124.399398)
			(xy 211.994817 -124.444241) (xy 212.015954 -124.492443) (xy 212.030269 -124.543092) (xy 212.037492 -124.595227)
			(xy 212.03793 -124.621544) (xy 212.037444 -124.648795) (xy 212.029688 -124.702743) (xy 212.014333 -124.755038)
			(xy 211.997926 -124.790962) (xy 218.430854 -124.790962) (xy 218.434925 -124.73534) (xy 218.447051 -124.680903)
			(xy 218.466974 -124.628812) (xy 218.49427 -124.580177) (xy 218.528356 -124.536034) (xy 218.568505 -124.497325)
			(xy 218.613863 -124.464874) (xy 218.663463 -124.439373) (xy 218.716247 -124.421366) (xy 218.77109 -124.411236)
			(xy 218.826824 -124.409199) (xy 218.882261 -124.415299) (xy 218.936218 -124.429405) (xy 218.987547 -124.451217)
			(xy 219.035153 -124.480271) (xy 219.078021 -124.515946) (xy 219.115238 -124.557483) (xy 219.146011 -124.603996)
			(xy 219.169683 -124.654493) (xy 219.185751 -124.7079) (xy 219.193871 -124.763076) (xy 219.19438 -124.790962)
			(xy 219.193871 -124.818848) (xy 219.185751 -124.874024) (xy 219.169683 -124.927431) (xy 219.146011 -124.977928)
			(xy 219.115238 -125.024441) (xy 219.078021 -125.065978) (xy 219.035153 -125.101653) (xy 218.987547 -125.130707)
			(xy 218.936218 -125.152519) (xy 218.882261 -125.166625) (xy 218.826824 -125.172725) (xy 218.77109 -125.170688)
			(xy 218.716247 -125.160558) (xy 218.663463 -125.142551) (xy 218.613863 -125.11705) (xy 218.568505 -125.084599)
			(xy 218.528356 -125.04589) (xy 218.49427 -125.001747) (xy 218.466974 -124.953112) (xy 218.447051 -124.901021)
			(xy 218.434925 -124.846584) (xy 218.430854 -124.790962) (xy 211.997926 -124.790962) (xy 211.991691 -124.804615)
			(xy 211.962225 -124.850465) (xy 211.926534 -124.891656) (xy 211.885343 -124.927347) (xy 211.839493 -124.956813)
			(xy 211.789916 -124.979455) (xy 211.737621 -124.99481) (xy 211.683673 -125.002566) (xy 211.629171 -125.002566)
			(xy 211.575223 -124.99481) (xy 211.522928 -124.979455) (xy 211.473351 -124.956813) (xy 211.427501 -124.927347)
			(xy 211.38631 -124.891656) (xy 211.350619 -124.850465) (xy 211.321153 -124.804615) (xy 211.298511 -124.755038)
			(xy 211.283156 -124.702743) (xy 211.2754 -124.648795) (xy 211.274914 -124.621544) (xy 208.365847 -124.621544)
			(xy 208.376844 -124.645494) (xy 208.39234 -124.697991) (xy 208.400173 -124.752164) (xy 208.40065 -124.779532)
			(xy 208.40065 -124.78004) (xy 208.400196 -124.806845) (xy 208.392657 -124.859922) (xy 208.37776 -124.911421)
			(xy 208.3558 -124.960327) (xy 208.327209 -125.005676) (xy 208.310226 -125.02642) (xy 208.298034 -125.040898)
			(xy 208.299558 -125.080522) (xy 208.319878 -125.100842) (xy 208.336556 -125.118176) (xy 208.364828 -125.157091)
			(xy 208.386667 -125.199948) (xy 208.401535 -125.245693) (xy 208.409065 -125.2932) (xy 208.40954 -125.31725)
			(xy 208.40954 -125.765352) (xy 217.593883 -125.765352) (xy 217.593883 -125.710848) (xy 217.60164 -125.656899)
			(xy 217.616997 -125.604603) (xy 217.639639 -125.555024) (xy 217.669108 -125.509173) (xy 217.704801 -125.467983)
			(xy 217.745994 -125.432292) (xy 217.791847 -125.402827) (xy 217.841427 -125.380188) (xy 217.893724 -125.364835)
			(xy 217.947674 -125.357081) (xy 217.974926 -125.35662) (xy 218.005729 -125.357224) (xy 218.06653 -125.367151)
			(xy 218.124944 -125.386728) (xy 218.152472 -125.400562) (xy 218.157999 -125.403271) (xy 218.169942 -125.40623)
			(xy 218.176094 -125.406404) (xy 225.368866 -125.406404) (xy 225.378937 -125.405986) (xy 225.397536 -125.398263)
			(xy 225.404934 -125.391418) (xy 228.732588 -122.06351) (xy 228.751372 -122.045401) (xy 228.79357 -122.014718)
			(xy 228.84005 -121.991017) (xy 228.889667 -121.974884) (xy 228.941197 -121.966715) (xy 228.967284 -121.966228)
			(xy 233.891836 -121.966228) (xy 233.90191 -121.965841) (xy 233.920509 -121.958095) (xy 233.927904 -121.951242)
			(xy 233.931206 -121.94794) (xy 233.937549 -121.941024) (xy 233.945178 -121.923895) (xy 233.946155 -121.905169)
			(xy 233.943652 -121.896124) (xy 233.91114 -121.796556) (xy 233.889296 -121.778014) (xy 233.875072 -121.775728)
			(xy 233.848436 -121.77111) (xy 233.796728 -121.755344) (xy 233.747764 -121.732436) (xy 233.702524 -121.702844)
			(xy 233.661915 -121.667162) (xy 233.62675 -121.626104) (xy 233.597735 -121.580493) (xy 233.575448 -121.531242)
			(xy 233.560339 -121.479338) (xy 233.552708 -121.425821) (xy 233.552238 -121.398792) (xy 233.552648 -121.371537)
			(xy 233.560407 -121.317582) (xy 233.575767 -121.26528) (xy 233.598413 -121.215697) (xy 233.627887 -121.169841)
			(xy 233.663586 -121.128648) (xy 233.704785 -121.092954) (xy 233.750644 -121.063488) (xy 233.800231 -121.040848)
			(xy 233.852534 -121.025496) (xy 233.906491 -121.017744) (xy 233.933746 -121.017284) (xy 233.960774 -121.017751)
			(xy 234.014289 -121.025388) (xy 234.06619 -121.040502) (xy 234.115438 -121.062791) (xy 234.161047 -121.091807)
			(xy 234.202104 -121.126972) (xy 234.237786 -121.167579) (xy 234.267379 -121.212817) (xy 234.29029 -121.261778)
			(xy 234.30606 -121.313483) (xy 234.310682 -121.340118) (xy 234.312968 -121.354342) (xy 234.33151 -121.376186)
			(xy 234.431078 -121.408698) (xy 234.440116 -121.411249) (xy 234.458857 -121.410282) (xy 234.475986 -121.402616)
			(xy 234.482894 -121.396252) (xy 234.573064 -121.306082) (xy 234.577171 -121.301681) (xy 234.583462 -121.291422)
			(xy 234.58551 -121.285762) (xy 234.58551 -121.285254) (xy 234.594011 -121.259729) (xy 234.617076 -121.211127)
			(xy 234.646739 -121.166247) (xy 234.682413 -121.12598) (xy 234.72339 -121.091123) (xy 234.768858 -121.062368)
			(xy 234.817913 -121.040286) (xy 234.869585 -121.025313) (xy 234.922848 -121.017749) (xy 234.949746 -121.017284)
			(xy 234.976998 -121.017735) (xy 235.030947 -121.025498) (xy 235.083241 -121.040858) (xy 235.132818 -121.063504)
			(xy 235.178668 -121.092974) (xy 235.219858 -121.128669) (xy 235.255548 -121.169862) (xy 235.285014 -121.215715)
			(xy 235.307655 -121.265294) (xy 235.323011 -121.317591) (xy 235.330768 -121.37154) (xy 235.331254 -121.398792)
			(xy 235.583728 -121.398792) (xy 235.587799 -121.34317) (xy 235.599925 -121.288733) (xy 235.619848 -121.236642)
			(xy 235.647144 -121.188007) (xy 235.68123 -121.143864) (xy 235.721379 -121.105155) (xy 235.766737 -121.072704)
			(xy 235.816337 -121.047203) (xy 235.869121 -121.029196) (xy 235.923964 -121.019066) (xy 235.979698 -121.017029)
			(xy 236.035135 -121.023129) (xy 236.089092 -121.037235) (xy 236.140421 -121.059047) (xy 236.188027 -121.088101)
			(xy 236.230895 -121.123776) (xy 236.268112 -121.165313) (xy 236.298885 -121.211826) (xy 236.322557 -121.262323)
			(xy 236.338625 -121.31573) (xy 236.346745 -121.370906) (xy 236.347254 -121.398792) (xy 236.346745 -121.426678)
			(xy 236.338625 -121.481854) (xy 236.322557 -121.535261) (xy 236.298885 -121.585758) (xy 236.268112 -121.632271)
			(xy 236.230895 -121.673808) (xy 236.188027 -121.709483) (xy 236.140421 -121.738537) (xy 236.089092 -121.760349)
			(xy 236.035135 -121.774455) (xy 235.979698 -121.780555) (xy 235.923964 -121.778518) (xy 235.869121 -121.768388)
			(xy 235.816337 -121.750381) (xy 235.766737 -121.72488) (xy 235.721379 -121.692429) (xy 235.68123 -121.65372)
			(xy 235.647144 -121.609577) (xy 235.619848 -121.560942) (xy 235.599925 -121.508851) (xy 235.587799 -121.454414)
			(xy 235.583728 -121.398792) (xy 235.331254 -121.398792) (xy 235.33071 -121.425699) (xy 235.323136 -121.478979)
			(xy 235.308151 -121.530665) (xy 235.286053 -121.579734) (xy 235.257279 -121.625211) (xy 235.222402 -121.666194)
			(xy 235.182112 -121.70187) (xy 235.137209 -121.731531) (xy 235.088584 -121.754589) (xy 235.06303 -121.763028)
			(xy 235.062776 -121.763028) (xy 235.057087 -121.765017) (xy 235.04681 -121.771307) (xy 235.042456 -121.775474)
			(xy 234.285028 -122.532902) (xy 234.266239 -122.551005) (xy 234.224042 -122.581689) (xy 234.177563 -122.60539)
			(xy 234.127948 -122.621525) (xy 234.076419 -122.629696) (xy 234.050332 -122.630184) (xy 229.12578 -122.630184)
			(xy 229.115707 -122.630577) (xy 229.097108 -122.638318) (xy 229.089712 -122.64517) (xy 226.771454 -124.963428)
			(xy 240.873534 -124.963428) (xy 240.873946 -124.936516) (xy 240.881533 -124.883228) (xy 240.896532 -124.831535)
			(xy 240.918646 -124.782462) (xy 240.947436 -124.736984) (xy 240.982331 -124.696002) (xy 241.022637 -124.660329)
			(xy 241.067556 -124.630675) (xy 241.116197 -124.607626) (xy 241.141758 -124.599192) (xy 241.142012 -124.599192)
			(xy 241.147699 -124.597196) (xy 241.157977 -124.590911) (xy 241.162332 -124.586746) (xy 241.252502 -124.496576)
			(xy 241.25882 -124.489639) (xy 241.266456 -124.472521) (xy 241.267443 -124.453803) (xy 241.264948 -124.44476)
			(xy 241.232436 -124.345192) (xy 241.210592 -124.32665) (xy 241.196368 -124.324364) (xy 241.169719 -124.319811)
			(xy 241.118007 -124.30404) (xy 241.069039 -124.281126) (xy 241.023797 -124.251528) (xy 240.983187 -124.215839)
			(xy 240.948023 -124.174773) (xy 240.919009 -124.129154) (xy 240.896727 -124.079895) (xy 240.881623 -124.027984)
			(xy 240.874 -123.97446) (xy 240.873534 -123.947428) (xy 240.873981 -123.920174) (xy 240.881736 -123.86622)
			(xy 240.89709 -123.81392) (xy 240.919733 -123.764337) (xy 240.949202 -123.718481) (xy 240.984897 -123.677287)
			(xy 241.026093 -123.641593) (xy 241.071949 -123.612126) (xy 241.121533 -123.589485) (xy 241.173834 -123.574133)
			(xy 241.227788 -123.56638) (xy 241.255042 -123.56592) (xy 241.287231 -123.566616) (xy 241.350689 -123.577469)
			(xy 241.38128 -123.58751) (xy 241.381534 -123.58751) (xy 241.393216 -123.590849) (xy 241.41723 -123.587387)
			(xy 241.427508 -123.580906) (xy 241.495072 -123.533154) (xy 241.504562 -123.525522) (xy 241.515707 -123.50391)
			(xy 241.516408 -123.491752) (xy 241.516408 -123.387104) (xy 241.515762 -123.374935) (xy 241.504592 -123.353313)
			(xy 241.495072 -123.345702) (xy 241.427508 -123.29795) (xy 241.417231 -123.291482) (xy 241.393223 -123.288048)
			(xy 241.381534 -123.291346) (xy 241.38128 -123.291346) (xy 241.350689 -123.301388) (xy 241.287231 -123.312245)
			(xy 241.255042 -123.312936) (xy 241.227789 -123.31242) (xy 241.173838 -123.304668) (xy 241.121539 -123.289317)
			(xy 241.071957 -123.266678) (xy 241.026102 -123.237214) (xy 240.984907 -123.201523) (xy 240.949212 -123.160332)
			(xy 240.919742 -123.11448) (xy 240.897098 -123.064901) (xy 240.881741 -123.012603) (xy 240.873983 -122.958653)
			(xy 240.873983 -122.904147) (xy 240.881741 -122.850197) (xy 240.897098 -122.797899) (xy 240.919742 -122.74832)
			(xy 240.949212 -122.702468) (xy 240.984907 -122.661277) (xy 241.026102 -122.625586) (xy 241.071957 -122.596122)
			(xy 241.121539 -122.573483) (xy 241.173838 -122.558132) (xy 241.227789 -122.55038) (xy 241.255042 -122.54992)
			(xy 241.287231 -122.550616) (xy 241.350689 -122.561469) (xy 241.38128 -122.57151) (xy 241.381534 -122.57151)
			(xy 241.393216 -122.574849) (xy 241.41723 -122.571387) (xy 241.427508 -122.564906) (xy 241.495072 -122.517154)
			(xy 241.504562 -122.509522) (xy 241.515707 -122.48791) (xy 241.516408 -122.475752) (xy 241.516408 -121.995946)
			(xy 241.515733 -121.98392) (xy 241.504877 -121.962455) (xy 241.49558 -121.954798) (xy 241.429286 -121.906284)
			(xy 241.4193 -121.899812) (xy 241.395852 -121.895957) (xy 241.384328 -121.898918) (xy 241.38382 -121.898918)
			(xy 241.355734 -121.907323) (xy 241.297815 -121.91638) (xy 241.268504 -121.916952) (xy 241.241254 -121.916401)
			(xy 241.187309 -121.908645) (xy 241.135017 -121.893292) (xy 241.085442 -121.870652) (xy 241.039593 -121.841187)
			(xy 240.998405 -121.805498) (xy 240.962715 -121.76431) (xy 240.93325 -121.718462) (xy 240.91061 -121.668887)
			(xy 240.895255 -121.616595) (xy 240.887499 -121.56265) (xy 240.887499 -121.50815) (xy 240.895255 -121.454205)
			(xy 240.91061 -121.401913) (xy 240.93325 -121.352338) (xy 240.962715 -121.30649) (xy 240.998405 -121.265302)
			(xy 241.039593 -121.229613) (xy 241.085442 -121.200148) (xy 241.135017 -121.177508) (xy 241.187309 -121.162155)
			(xy 241.241254 -121.154399) (xy 241.268504 -121.153936) (xy 241.269266 -121.153936) (xy 241.300854 -121.154566)
			(xy 241.363157 -121.16504) (xy 241.393218 -121.174764) (xy 241.403632 -121.17832) (xy 241.424714 -121.176542)
			(xy 241.500406 -121.134886) (xy 241.509524 -121.129356) (xy 241.52241 -121.112386) (xy 241.525298 -121.10212)
			(xy 241.525298 -121.101612) (xy 241.530921 -121.079259) (xy 241.547507 -121.036255) (xy 241.569901 -120.995968)
			(xy 241.597669 -120.95918) (xy 241.61369 -120.942608) (xy 242.400582 -120.155716) (xy 242.404684 -120.151311)
			(xy 242.410978 -120.141055) (xy 242.413028 -120.135396) (xy 242.413028 -120.134888) (xy 242.421473 -120.109344)
			(xy 242.444548 -120.060742) (xy 242.47422 -120.015864) (xy 242.509902 -119.975598) (xy 242.550886 -119.940744)
			(xy 242.596359 -119.911992) (xy 242.645421 -119.889913) (xy 242.697097 -119.874943) (xy 242.750364 -119.867381)
			(xy 242.777264 -119.866918) (xy 242.804517 -119.867389) (xy 242.858469 -119.875142) (xy 242.910768 -119.890494)
			(xy 242.96035 -119.913135) (xy 243.006205 -119.942601) (xy 243.047399 -119.978294) (xy 243.083093 -120.019487)
			(xy 243.112561 -120.065341) (xy 243.135202 -120.114922) (xy 243.150556 -120.167221) (xy 243.15831 -120.221173)
			(xy 243.158772 -120.248426) (xy 243.158315 -120.275337) (xy 243.150734 -120.328623) (xy 243.135741 -120.380314)
			(xy 243.113633 -120.429386) (xy 243.084849 -120.474865) (xy 243.04996 -120.515847) (xy 243.009658 -120.551521)
			(xy 242.964744 -120.581177) (xy 242.916107 -120.604228) (xy 242.890548 -120.612662) (xy 242.890294 -120.612662)
			(xy 242.884604 -120.614649) (xy 242.874327 -120.62094) (xy 242.869974 -120.625108) (xy 242.19535 -121.299732)
			(xy 242.18851 -121.307133) (xy 242.180789 -121.325731) (xy 242.180364 -121.3358) (xy 242.180364 -121.816114)
			(xy 242.180888 -121.82723) (xy 242.190255 -121.847389) (xy 242.198398 -121.854976) (xy 242.266216 -121.91238)
			(xy 242.287552 -121.918222) (xy 242.298728 -121.916444) (xy 242.314484 -121.913946) (xy 242.346276 -121.911272)
			(xy 242.362228 -121.91111) (xy 242.389479 -121.911562) (xy 242.443426 -121.919322) (xy 242.49572 -121.93468)
			(xy 242.545296 -121.957324) (xy 242.591145 -121.986792) (xy 242.632334 -122.022486) (xy 242.668024 -122.063677)
			(xy 242.697489 -122.109528) (xy 242.72013 -122.159106) (xy 242.735484 -122.211401) (xy 242.74324 -122.265349)
			(xy 242.74324 -122.319851) (xy 242.735484 -122.373799) (xy 242.72013 -122.426094) (xy 242.70012 -122.46991)
			(xy 243.137436 -122.46991) (xy 243.137919 -122.443) (xy 243.145495 -122.389715) (xy 243.160484 -122.338024)
			(xy 243.182588 -122.288952) (xy 243.211369 -122.243473) (xy 243.246255 -122.20249) (xy 243.286554 -122.166816)
			(xy 243.331467 -122.137159) (xy 243.380101 -122.114108) (xy 243.40566 -122.105674) (xy 243.405914 -122.105674)
			(xy 243.411602 -122.103682) (xy 243.42188 -122.097394) (xy 243.426234 -122.093228) (xy 243.95049 -121.569226)
			(xy 243.95731 -121.56181) (xy 243.965042 -121.543223) (xy 243.965476 -121.533158) (xy 243.965476 -120.595898)
			(xy 243.964979 -120.584908) (xy 243.955899 -120.564895) (xy 243.94795 -120.55729) (xy 243.88953 -120.506998)
			(xy 243.880923 -120.500302) (xy 243.859996 -120.494245) (xy 243.849144 -120.495314) (xy 243.84889 -120.495314)
			(xy 243.835126 -120.497212) (xy 243.807412 -120.499243) (xy 243.793518 -120.499378) (xy 243.793264 -120.499378)
			(xy 243.766012 -120.49895) (xy 243.712064 -120.491188) (xy 243.65977 -120.475829) (xy 243.610193 -120.453184)
			(xy 243.564344 -120.423714) (xy 243.523154 -120.38802) (xy 243.487464 -120.346828) (xy 243.457999 -120.300975)
			(xy 243.435358 -120.251397) (xy 243.420004 -120.199101) (xy 243.412248 -120.145152) (xy 243.412248 -120.090648)
			(xy 243.420004 -120.036699) (xy 243.435358 -119.984403) (xy 243.457999 -119.934825) (xy 243.487464 -119.888972)
			(xy 243.523154 -119.84778) (xy 243.564344 -119.812086) (xy 243.610193 -119.782616) (xy 243.65977 -119.759971)
			(xy 243.712064 -119.744612) (xy 243.766012 -119.73685) (xy 243.793264 -119.736362) (xy 243.793518 -119.736362)
			(xy 243.807412 -119.736484) (xy 243.835126 -119.73852) (xy 243.84889 -119.740426) (xy 243.849144 -119.740426)
			(xy 243.859995 -119.741506) (xy 243.880921 -119.735437) (xy 243.88953 -119.728742) (xy 243.94795 -119.67845)
			(xy 243.955902 -119.670844) (xy 243.964993 -119.650834) (xy 243.965476 -119.639842) (xy 243.965476 -119.509794)
			(xy 243.966027 -119.483771) (xy 243.974188 -119.432369) (xy 243.990277 -119.382872) (xy 244.013899 -119.336496)
			(xy 244.044474 -119.294378) (xy 244.062504 -119.275606) (xy 244.25656 -119.08155) (xy 244.275363 -119.063462)
			(xy 244.317555 -119.032774) (xy 244.36403 -119.009069) (xy 244.413643 -118.992931) (xy 244.46517 -118.984758)
			(xy 244.491256 -118.984268) (xy 247.167654 -118.984268) (xy 247.19374 -118.984779) (xy 247.245271 -118.992939)
			(xy 247.294888 -119.009065) (xy 247.341369 -119.032761) (xy 247.383568 -119.06344) (xy 247.40235 -119.08155)
			(xy 247.969024 -119.648224) (xy 247.976436 -119.654908) (xy 247.994869 -119.662505) (xy 248.014807 -119.662505)
			(xy 248.03324 -119.654908) (xy 248.040652 -119.648224) (xy 248.773442 -118.915434) (xy 248.792206 -118.897304)
			(xy 248.834409 -118.866622) (xy 248.880894 -118.842925) (xy 248.930515 -118.826797) (xy 248.98205 -118.818635)
			(xy 249.008138 -118.818152) (xy 250.961144 -118.818152) (xy 250.971217 -118.817762) (xy 250.989816 -118.810018)
			(xy 250.997212 -118.803166) (xy 253.77521 -116.025168) (xy 253.794 -116.007157) (xy 253.836113 -115.976575)
			(xy 253.882484 -115.952945) (xy 253.931976 -115.936845) (xy 253.983376 -115.928671) (xy 254.009398 -115.92814)
			(xy 268.09446 -115.92814) (xy 268.104529 -115.92771) (xy 268.123128 -115.919994) (xy 268.130528 -115.913154)
			(xy 268.47419 -115.569238) (xy 268.492978 -115.551133) (xy 268.535174 -115.520448) (xy 268.581653 -115.496746)
			(xy 268.631269 -115.480612) (xy 268.682799 -115.472443) (xy 268.708886 -115.471956) (xy 269.836138 -115.471956)
			(xy 269.847314 -115.469416) (xy 269.852648 -115.466622) (xy 269.853664 -115.466114) (xy 269.877831 -115.453922)
			(xy 269.928822 -115.435762) (xy 269.981868 -115.42499) (xy 270.008858 -115.422934) (xy 270.01978 -115.422426)
			(xy 270.039084 -115.412266) (xy 270.09979 -115.335304) (xy 270.105124 -115.314222) (xy 270.103092 -115.303554)
			(xy 270.100249 -115.286807) (xy 270.097194 -115.252975) (xy 270.096996 -115.23599) (xy 270.096996 -115.235228)
			(xy 270.097482 -115.207977) (xy 270.105238 -115.154029) (xy 270.120593 -115.101734) (xy 270.143235 -115.052157)
			(xy 270.172701 -115.006307) (xy 270.208392 -114.965116) (xy 270.249583 -114.929425) (xy 270.295433 -114.899959)
			(xy 270.34501 -114.877317) (xy 270.397305 -114.861962) (xy 270.451253 -114.854206) (xy 270.505755 -114.854206)
			(xy 270.559703 -114.861962) (xy 270.611998 -114.877317) (xy 270.661575 -114.899959) (xy 270.707425 -114.929425)
			(xy 270.748616 -114.965116) (xy 270.784307 -115.006307) (xy 270.813773 -115.052157) (xy 270.836415 -115.101734)
			(xy 270.85177 -115.154029) (xy 270.859526 -115.207977) (xy 270.860012 -115.235228) (xy 270.859529 -115.264123)
			(xy 270.850837 -115.321254) (xy 270.833628 -115.376421) (xy 270.808294 -115.42836) (xy 270.775415 -115.475884)
			(xy 270.735743 -115.517905) (xy 270.690187 -115.55346) (xy 270.639789 -115.581737) (xy 270.585703 -115.602089)
			(xy 270.529165 -115.614049) (xy 270.500348 -115.616228) (xy 270.489426 -115.616736) (xy 270.470122 -115.626896)
			(xy 270.409416 -115.703858) (xy 270.404082 -115.72494) (xy 270.406114 -115.735608) (xy 270.408965 -115.752353)
			(xy 270.412015 -115.786187) (xy 270.41221 -115.803172) (xy 270.41221 -115.803934) (xy 270.411729 -115.830916)
			(xy 270.404107 -115.884341) (xy 270.389035 -115.936158) (xy 270.366813 -115.985336) (xy 270.337884 -116.030892)
			(xy 270.302826 -116.071918) (xy 270.262338 -116.107596) (xy 270.217226 -116.137214) (xy 270.193008 -116.14912)
			(xy 270.182848 -116.153946) (xy 270.168624 -116.17071) (xy 270.142208 -116.267484) (xy 270.145764 -116.28882)
			(xy 270.152114 -116.297964) (xy 270.152114 -116.298218) (xy 270.167693 -116.322057) (xy 270.192347 -116.373389)
			(xy 270.209108 -116.427813) (xy 270.217606 -116.484121) (xy 270.218154 -116.512594) (xy 270.217617 -116.539843)
			(xy 270.209862 -116.593787) (xy 270.19451 -116.646077) (xy 270.171873 -116.695652) (xy 270.142412 -116.7415)
			(xy 270.106726 -116.782689) (xy 270.065542 -116.818381) (xy 270.019697 -116.847848) (xy 269.970126 -116.870492)
			(xy 269.917837 -116.885851) (xy 269.863895 -116.893613) (xy 269.836646 -116.894102) (xy 269.810331 -116.89367)
			(xy 269.758201 -116.886428) (xy 269.707557 -116.872102) (xy 269.659359 -116.850963) (xy 269.614516 -116.82341)
			(xy 269.573878 -116.789966) (xy 269.555722 -116.770912) (xy 269.548193 -116.76352) (xy 269.528919 -116.75499)
			(xy 269.518384 -116.754402) (xy 269.443708 -116.754402) (xy 269.433157 -116.754922) (xy 269.413862 -116.763464)
			(xy 269.40637 -116.770912) (xy 269.388224 -116.789977) (xy 269.347592 -116.823433) (xy 269.30275 -116.850991)
			(xy 269.254547 -116.872127) (xy 269.203898 -116.886442) (xy 269.151763 -116.893665) (xy 269.125446 -116.894102)
			(xy 269.098194 -116.893602) (xy 269.044244 -116.885851) (xy 268.991947 -116.870501) (xy 268.942366 -116.847863)
			(xy 268.896513 -116.818399) (xy 268.855319 -116.782709) (xy 268.819625 -116.74152) (xy 268.790156 -116.695669)
			(xy 268.767513 -116.646091) (xy 268.752157 -116.593795) (xy 268.744401 -116.539846) (xy 268.743938 -116.512594)
			(xy 268.7447 -116.488718) (xy 268.745716 -116.473224) (xy 268.72946 -116.446046) (xy 268.628368 -116.400326)
			(xy 268.618802 -116.396446) (xy 268.598181 -116.395995) (xy 268.579064 -116.403743) (xy 268.571472 -116.41074)
			(xy 268.487652 -116.49456) (xy 268.468883 -116.512594) (xy 268.426764 -116.543172) (xy 268.380388 -116.566797)
			(xy 268.33089 -116.582892) (xy 268.279488 -116.59106) (xy 268.253464 -116.591588) (xy 254.168402 -116.591588)
			(xy 254.15833 -116.591991) (xy 254.139731 -116.599725) (xy 254.132334 -116.606574) (xy 252.984613 -117.7544)
			(xy 269.288004 -117.7544) (xy 269.292075 -117.698778) (xy 269.304201 -117.644341) (xy 269.324124 -117.59225)
			(xy 269.35142 -117.543615) (xy 269.385506 -117.499472) (xy 269.425655 -117.460763) (xy 269.471013 -117.428312)
			(xy 269.520613 -117.402811) (xy 269.573397 -117.384804) (xy 269.62824 -117.374674) (xy 269.683974 -117.372637)
			(xy 269.739411 -117.378737) (xy 269.793368 -117.392843) (xy 269.844697 -117.414655) (xy 269.892303 -117.443709)
			(xy 269.935171 -117.479384) (xy 269.972388 -117.520921) (xy 270.003161 -117.567434) (xy 270.026833 -117.617931)
			(xy 270.042901 -117.671338) (xy 270.051021 -117.726514) (xy 270.05153 -117.7544) (xy 270.051021 -117.782286)
			(xy 270.042901 -117.837462) (xy 270.026833 -117.890869) (xy 270.003161 -117.941366) (xy 269.972388 -117.987879)
			(xy 269.935171 -118.029416) (xy 269.892303 -118.065091) (xy 269.844697 -118.094145) (xy 269.793368 -118.115957)
			(xy 269.739411 -118.130063) (xy 269.683974 -118.136163) (xy 269.62824 -118.134126) (xy 269.573397 -118.123996)
			(xy 269.520613 -118.105989) (xy 269.471013 -118.080488) (xy 269.425655 -118.048037) (xy 269.385506 -118.009328)
			(xy 269.35142 -117.965185) (xy 269.324124 -117.91655) (xy 269.304201 -117.864459) (xy 269.292075 -117.810022)
			(xy 269.288004 -117.7544) (xy 252.984613 -117.7544) (xy 251.68378 -119.055352) (xy 266.291007 -119.055352)
			(xy 266.291007 -118.998048) (xy 266.299162 -118.941328) (xy 266.315307 -118.886346) (xy 266.339112 -118.834221)
			(xy 266.370094 -118.786014) (xy 266.407621 -118.742708) (xy 266.450929 -118.705183) (xy 266.499136 -118.674204)
			(xy 266.551262 -118.650401) (xy 266.606245 -118.634258) (xy 266.662966 -118.626106) (xy 266.691618 -118.62562)
			(xy 266.718998 -118.626106) (xy 266.773246 -118.633575) (xy 266.825972 -118.648356) (xy 266.876197 -118.670176)
			(xy 266.922985 -118.698628) (xy 266.965466 -118.733182) (xy 267.002848 -118.773196) (xy 267.019024 -118.795292)
			(xy 267.024581 -118.802558) (xy 267.039694 -118.812839) (xy 267.048488 -118.815358) (xy 267.07846 -118.822724)
			(xy 267.087413 -118.824452) (xy 267.105499 -118.82225) (xy 267.113766 -118.818406) (xy 267.138373 -118.806032)
			(xy 267.189897 -118.786558) (xy 267.243384 -118.773406) (xy 267.298062 -118.766763) (xy 267.325602 -118.766336)
			(xy 267.353142 -118.766781) (xy 267.407822 -118.773412) (xy 267.461311 -118.786554) (xy 267.512838 -118.806017)
			(xy 267.537438 -118.818406) (xy 267.54569 -118.822303) (xy 267.563793 -118.824505) (xy 267.572744 -118.822724)
			(xy 267.602716 -118.815358) (xy 267.611498 -118.812816) (xy 267.626599 -118.802533) (xy 267.63218 -118.795292)
			(xy 267.648294 -118.773146) (xy 267.685676 -118.733116) (xy 267.728162 -118.698551) (xy 267.77496 -118.670096)
			(xy 267.825198 -118.648279) (xy 267.877939 -118.633509) (xy 267.932201 -118.626061) (xy 267.959586 -118.62562)
			(xy 267.988236 -118.626134) (xy 268.044952 -118.634286) (xy 268.099931 -118.650428) (xy 268.152052 -118.67423)
			(xy 268.200256 -118.705207) (xy 268.243561 -118.742729) (xy 268.281085 -118.786032) (xy 268.312064 -118.834235)
			(xy 268.335867 -118.886356) (xy 268.352011 -118.941334) (xy 268.360165 -118.99805) (xy 268.360165 -119.05535)
			(xy 268.352011 -119.112066) (xy 268.335867 -119.167044) (xy 268.312064 -119.219165) (xy 268.281085 -119.267368)
			(xy 268.243561 -119.310671) (xy 268.200256 -119.348193) (xy 268.152052 -119.37917) (xy 268.099931 -119.402972)
			(xy 268.044952 -119.419114) (xy 267.988236 -119.427266) (xy 267.959586 -119.427752) (xy 267.944668 -119.427579)
			(xy 267.914919 -119.425293) (xy 267.90015 -119.42318) (xy 267.888974 -119.421402) (xy 267.867892 -119.427498)
			(xy 267.80109 -119.485156) (xy 267.793142 -119.492765) (xy 267.784047 -119.512773) (xy 267.783564 -119.523764)
			(xy 267.783564 -119.788432) (xy 267.784063 -119.799421) (xy 267.793144 -119.819433) (xy 267.80109 -119.82704)
			(xy 267.867892 -119.884698) (xy 267.888974 -119.890794) (xy 267.90015 -119.889016) (xy 267.91492 -119.886911)
			(xy 267.944668 -119.884621) (xy 267.959586 -119.884444) (xy 267.988237 -119.88491) (xy 268.044957 -119.893063)
			(xy 268.099939 -119.909205) (xy 268.152064 -119.933009) (xy 268.200271 -119.963988) (xy 268.243578 -120.001512)
			(xy 268.281104 -120.044818) (xy 268.312085 -120.093024) (xy 268.33589 -120.145148) (xy 268.352034 -120.200129)
			(xy 268.360189 -120.256849) (xy 268.360189 -120.314151) (xy 268.352034 -120.370871) (xy 268.33589 -120.425852)
			(xy 268.312085 -120.477976) (xy 268.281104 -120.526182) (xy 268.243578 -120.569488) (xy 268.200271 -120.607012)
			(xy 268.152064 -120.637991) (xy 268.099939 -120.661795) (xy 268.044957 -120.677937) (xy 267.988237 -120.68609)
			(xy 267.959586 -120.686576) (xy 267.932206 -120.686088) (xy 267.877958 -120.678621) (xy 267.825232 -120.663839)
			(xy 267.775007 -120.64202) (xy 267.728219 -120.613568) (xy 267.685738 -120.579014) (xy 267.648356 -120.539)
			(xy 267.63218 -120.516904) (xy 267.626623 -120.509639) (xy 267.61151 -120.499357) (xy 267.602716 -120.496838)
			(xy 267.572744 -120.489472) (xy 267.563791 -120.487746) (xy 267.545705 -120.489947) (xy 267.537438 -120.49379)
			(xy 267.51283 -120.506163) (xy 267.461307 -120.525636) (xy 267.40782 -120.53879) (xy 267.353142 -120.545432)
			(xy 267.325602 -120.54586) (xy 267.298062 -120.545414) (xy 267.243382 -120.538783) (xy 267.189893 -120.525642)
			(xy 267.138366 -120.506179) (xy 267.113766 -120.49379) (xy 267.105514 -120.489895) (xy 267.087411 -120.487692)
			(xy 267.07846 -120.489472) (xy 267.048488 -120.496838) (xy 267.039707 -120.499382) (xy 267.024606 -120.509664)
			(xy 267.019024 -120.516904) (xy 267.002907 -120.539048) (xy 266.965525 -120.579077) (xy 266.92304 -120.613643)
			(xy 266.876242 -120.642099) (xy 266.826005 -120.663915) (xy 266.773264 -120.678686) (xy 266.719003 -120.686135)
			(xy 266.691618 -120.686576) (xy 266.662968 -120.686071) (xy 266.606251 -120.677918) (xy 266.551271 -120.661777)
			(xy 266.499148 -120.637975) (xy 266.450943 -120.606998) (xy 266.407638 -120.569475) (xy 266.370113 -120.526171)
			(xy 266.339133 -120.477968) (xy 266.315329 -120.425846) (xy 266.299186 -120.370867) (xy 266.291031 -120.31415)
			(xy 266.291031 -120.25685) (xy 266.299186 -120.200133) (xy 266.315329 -120.145154) (xy 266.339133 -120.093032)
			(xy 266.370113 -120.044829) (xy 266.407638 -120.001525) (xy 266.450943 -119.964002) (xy 266.499148 -119.933025)
			(xy 266.551271 -119.909223) (xy 266.606251 -119.893082) (xy 266.662968 -119.884929) (xy 266.691618 -119.884444)
			(xy 266.706536 -119.884617) (xy 266.736285 -119.886903) (xy 266.751054 -119.889016) (xy 266.76223 -119.890794)
			(xy 266.783312 -119.884698) (xy 266.850114 -119.82704) (xy 266.858065 -119.819433) (xy 266.867158 -119.799424)
			(xy 266.86764 -119.788432) (xy 266.86764 -119.523764) (xy 266.867142 -119.512774) (xy 266.85806 -119.492763)
			(xy 266.850114 -119.485156) (xy 266.783312 -119.427498) (xy 266.76223 -119.421402) (xy 266.751054 -119.42318)
			(xy 266.736284 -119.425285) (xy 266.706536 -119.427575) (xy 266.691618 -119.427752) (xy 266.662966 -119.427294)
			(xy 266.606245 -119.419142) (xy 266.551262 -119.402999) (xy 266.499136 -119.379196) (xy 266.450929 -119.348217)
			(xy 266.407621 -119.310692) (xy 266.370094 -119.267386) (xy 266.339112 -119.219179) (xy 266.315307 -119.167054)
			(xy 266.299162 -119.112072) (xy 266.291007 -119.055352) (xy 251.68378 -119.055352) (xy 251.354336 -119.384826)
			(xy 251.335547 -119.402929) (xy 251.29335 -119.433612) (xy 251.246871 -119.457313) (xy 251.197256 -119.473448)
			(xy 251.145726 -119.481619) (xy 251.11964 -119.482108) (xy 249.166634 -119.482108) (xy 249.156566 -119.482549)
			(xy 249.137968 -119.490258) (xy 249.130566 -119.497094) (xy 249.023378 -119.604282) (xy 249.017018 -119.611184)
			(xy 249.009396 -119.628321) (xy 249.008426 -119.647051) (xy 249.010932 -119.656098) (xy 249.043444 -119.755666)
			(xy 249.065288 -119.774208) (xy 249.079512 -119.776494) (xy 249.10615 -119.781103) (xy 249.157859 -119.796868)
			(xy 249.206825 -119.819776) (xy 249.252066 -119.849369) (xy 249.292676 -119.885052) (xy 249.327841 -119.926111)
			(xy 249.356856 -119.971724) (xy 249.379141 -120.020976) (xy 249.394249 -120.072882) (xy 249.401877 -120.1264)
			(xy 249.402346 -120.15343) (xy 249.40185 -120.18068) (xy 249.394091 -120.234626) (xy 249.378734 -120.286918)
			(xy 249.356092 -120.336493) (xy 249.326626 -120.382341) (xy 249.290936 -120.42353) (xy 249.249748 -120.459221)
			(xy 249.2039 -120.488688) (xy 249.154325 -120.511331) (xy 249.102033 -120.526689) (xy 249.048088 -120.53445)
			(xy 249.020838 -120.534938) (xy 248.99381 -120.534467) (xy 248.940296 -120.526829) (xy 248.888396 -120.511714)
			(xy 248.839149 -120.489425) (xy 248.793541 -120.460408) (xy 248.752485 -120.425244) (xy 248.716803 -120.384638)
			(xy 248.68721 -120.339402) (xy 248.664297 -120.290442) (xy 248.648525 -120.238738) (xy 248.643902 -120.212104)
			(xy 248.641616 -120.19788) (xy 248.623074 -120.176036) (xy 248.523506 -120.143524) (xy 248.514461 -120.14098)
			(xy 248.495711 -120.141921) (xy 248.478567 -120.14957) (xy 248.47169 -120.15597) (xy 248.38152 -120.24614)
			(xy 248.377405 -120.250534) (xy 248.371119 -120.260798) (xy 248.369074 -120.26646) (xy 248.369074 -120.266968)
			(xy 248.360674 -120.292539) (xy 248.33761 -120.341172) (xy 248.307939 -120.38608) (xy 248.272249 -120.426371)
			(xy 248.23125 -120.461245) (xy 248.185755 -120.490009) (xy 248.136669 -120.512092) (xy 248.084966 -120.527056)
			(xy 248.031673 -120.534602) (xy 247.977848 -120.534583) (xy 247.92456 -120.526997) (xy 247.872868 -120.511995)
			(xy 247.823798 -120.489876) (xy 247.778325 -120.461079) (xy 247.737351 -120.426175) (xy 247.701691 -120.385858)
			(xy 247.672052 -120.340929) (xy 247.649024 -120.292279) (xy 247.640602 -120.266714) (xy 247.640602 -120.26646)
			(xy 247.638612 -120.260771) (xy 247.632323 -120.250494) (xy 247.628156 -120.24614) (xy 247.534684 -120.152414)
			(xy 247.527881 -120.146223) (xy 247.511133 -120.138654) (xy 247.492795 -120.137436) (xy 247.483884 -120.139714)
			(xy 247.384316 -120.170194) (xy 247.365774 -120.190514) (xy 247.36298 -120.20423) (xy 247.36298 -120.204738)
			(xy 247.356786 -120.233224) (xy 247.336856 -120.288004) (xy 247.308823 -120.339115) (xy 247.27334 -120.385364)
			(xy 247.231232 -120.425676) (xy 247.18348 -120.459111) (xy 247.131197 -120.484891) (xy 247.075601 -120.502416)
			(xy 247.017985 -120.511276) (xy 246.988838 -120.511824) (xy 246.961587 -120.511309) (xy 246.907639 -120.503558)
			(xy 246.855343 -120.488208) (xy 246.805764 -120.465571) (xy 246.759911 -120.436108) (xy 246.718718 -120.40042)
			(xy 246.683024 -120.359232) (xy 246.653555 -120.313384) (xy 246.630911 -120.263808) (xy 246.615553 -120.211514)
			(xy 246.607794 -120.157567) (xy 246.60733 -120.130316) (xy 246.607889 -120.101462) (xy 246.616572 -120.044411)
			(xy 246.633756 -119.989321) (xy 246.659048 -119.937451) (xy 246.691872 -119.889987) (xy 246.731476 -119.848014)
			(xy 246.753888 -119.829834) (xy 246.761852 -119.822908) (xy 246.771844 -119.804344) (xy 246.773573 -119.783333)
			(xy 246.770652 -119.773192) (xy 246.739156 -119.682514) (xy 246.735247 -119.672716) (xy 246.720985 -119.657204)
			(xy 246.701686 -119.648742) (xy 246.69115 -119.648224) (xy 246.138192 -119.648224) (xy 246.127817 -119.648713)
			(xy 246.108743 -119.656871) (xy 246.09447 -119.671927) (xy 246.09044 -119.681498) (xy 246.051832 -119.786146)
			(xy 246.05996 -119.816626) (xy 246.072152 -119.82704) (xy 246.092828 -119.84529) (xy 246.129303 -119.886649)
			(xy 246.159441 -119.932831) (xy 246.182613 -119.982871) (xy 246.198336 -120.035728) (xy 246.206283 -120.090297)
			(xy 246.206772 -120.11787) (xy 246.206306 -120.144929) (xy 246.198665 -120.198506) (xy 246.183534 -120.250466)
			(xy 246.161214 -120.299767) (xy 246.147082 -120.322848) (xy 246.139716 -120.334278) (xy 246.138446 -120.360948)
			(xy 246.190008 -120.46331) (xy 246.212614 -120.478042) (xy 246.226076 -120.478804) (xy 246.254724 -120.481231)
			(xy 246.310886 -120.493514) (xy 246.364569 -120.514083) (xy 246.414559 -120.542473) (xy 246.459724 -120.578042)
			(xy 246.499042 -120.619985) (xy 246.531622 -120.667351) (xy 246.556727 -120.719069) (xy 246.573789 -120.773968)
			(xy 246.582421 -120.830805) (xy 246.582946 -120.85955) (xy 246.582529 -120.885866) (xy 246.575286 -120.937997)
			(xy 246.560959 -120.988642) (xy 246.539817 -121.036841) (xy 246.512261 -121.081683) (xy 246.478812 -121.12232)
			(xy 246.459756 -121.140474) (xy 246.452372 -121.148011) (xy 246.443836 -121.167279) (xy 246.443246 -121.177812)
			(xy 246.443246 -121.252488) (xy 246.443754 -121.26304) (xy 246.452303 -121.282337) (xy 246.459756 -121.289826)
			(xy 246.478828 -121.307965) (xy 246.512281 -121.348599) (xy 246.539837 -121.393444) (xy 246.560972 -121.441647)
			(xy 246.575286 -121.492297) (xy 246.579856 -121.525284) (xy 249.551698 -121.525284) (xy 249.552155 -121.497913)
			(xy 249.559975 -121.443734) (xy 249.575466 -121.391231) (xy 249.59831 -121.341484) (xy 249.628036 -121.295518)
			(xy 249.645678 -121.274586) (xy 249.645932 -121.274332) (xy 249.651515 -121.267243) (xy 249.657763 -121.250328)
			(xy 249.658124 -121.241312) (xy 249.658124 -121.174256) (xy 249.657735 -121.165242) (xy 249.651509 -121.148325)
			(xy 249.645932 -121.141236) (xy 249.645678 -121.141236) (xy 249.645678 -121.140982) (xy 249.62806 -121.120033)
			(xy 249.598346 -121.074064) (xy 249.575506 -121.024321) (xy 249.56001 -120.971824) (xy 249.552176 -120.917652)
			(xy 249.551698 -120.890284) (xy 249.552184 -120.863033) (xy 249.55994 -120.809085) (xy 249.575295 -120.75679)
			(xy 249.597937 -120.707213) (xy 249.627403 -120.661363) (xy 249.663094 -120.620172) (xy 249.704285 -120.584481)
			(xy 249.750135 -120.555015) (xy 249.799712 -120.532373) (xy 249.852007 -120.517018) (xy 249.905955 -120.509262)
			(xy 249.960457 -120.509262) (xy 250.014405 -120.517018) (xy 250.0667 -120.532373) (xy 250.116277 -120.555015)
			(xy 250.162127 -120.584481) (xy 250.203318 -120.620172) (xy 250.239009 -120.661363) (xy 250.268475 -120.707213)
			(xy 250.291117 -120.75679) (xy 250.306472 -120.809085) (xy 250.314228 -120.863033) (xy 250.314714 -120.890284)
			(xy 250.314235 -120.917654) (xy 250.30642 -120.971832) (xy 250.290934 -121.024335) (xy 250.268095 -121.074082)
			(xy 250.238374 -121.12005) (xy 250.220734 -121.140982) (xy 250.22048 -121.141236) (xy 250.214912 -121.148335)
			(xy 250.208655 -121.165242) (xy 250.208288 -121.174256) (xy 250.208288 -121.241312) (xy 250.208642 -121.250329)
			(xy 250.214892 -121.267246) (xy 250.22048 -121.274332) (xy 250.220734 -121.274332) (xy 250.220734 -121.274586)
			(xy 250.238385 -121.295508) (xy 250.268094 -121.341484) (xy 250.290927 -121.391234) (xy 250.306416 -121.443737)
			(xy 250.314241 -121.497914) (xy 250.314714 -121.525284) (xy 250.314482 -121.543627) (xy 250.310919 -121.58014)
			(xy 250.307602 -121.598182) (xy 250.305996 -121.608812) (xy 250.310874 -121.629732) (xy 250.317 -121.638568)
			(xy 250.369324 -121.707656) (xy 250.38812 -121.71807) (xy 250.399042 -121.718832) (xy 250.427328 -121.721711)
			(xy 250.482666 -121.734752) (xy 250.535459 -121.755852) (xy 250.584541 -121.784544) (xy 250.628829 -121.820195)
			(xy 250.64847 -121.840752) (xy 250.656007 -121.848135) (xy 250.675275 -121.856672) (xy 250.685808 -121.857262)
			(xy 250.760484 -121.857262) (xy 250.771036 -121.856749) (xy 250.790332 -121.848204) (xy 250.797822 -121.840752)
			(xy 250.815964 -121.821684) (xy 250.856598 -121.788229) (xy 250.901441 -121.760673) (xy 250.949645 -121.739537)
			(xy 251.000294 -121.725222) (xy 251.052429 -121.718) (xy 251.078746 -121.717562) (xy 251.105993 -121.718111)
			(xy 251.159931 -121.725873) (xy 251.212216 -121.74123) (xy 251.261784 -121.763872) (xy 251.307625 -121.793338)
			(xy 251.348806 -121.829026) (xy 251.38449 -121.870212) (xy 251.41395 -121.916057) (xy 251.436586 -121.965627)
			(xy 251.451937 -122.017914) (xy 251.459692 -122.071853) (xy 251.459692 -122.126347) (xy 251.451937 -122.180286)
			(xy 251.436586 -122.232573) (xy 251.41395 -122.282143) (xy 251.38449 -122.327988) (xy 251.348806 -122.369174)
			(xy 251.307625 -122.404862) (xy 251.261784 -122.434328) (xy 251.212216 -122.45697) (xy 251.159931 -122.472327)
			(xy 251.105993 -122.480089) (xy 251.078746 -122.480578) (xy 251.05243 -122.480154) (xy 251.0003 -122.472911)
			(xy 250.949656 -122.458584) (xy 250.901457 -122.437443) (xy 250.856615 -122.409889) (xy 250.815977 -122.376443)
			(xy 250.797822 -122.357388) (xy 250.790296 -122.349992) (xy 250.771019 -122.341465) (xy 250.760484 -122.340878)
			(xy 250.685808 -122.340878) (xy 250.675258 -122.341404) (xy 250.655963 -122.349942) (xy 250.64847 -122.357388)
			(xy 250.63032 -122.376449) (xy 250.589689 -122.409906) (xy 250.544848 -122.437465) (xy 250.496646 -122.458602)
			(xy 250.445997 -122.472918) (xy 250.393862 -122.480141) (xy 250.367546 -122.480578) (xy 250.340293 -122.480102)
			(xy 250.286341 -122.47235) (xy 250.234041 -122.456999) (xy 250.184459 -122.434359) (xy 250.138605 -122.404893)
			(xy 250.097411 -122.369201) (xy 250.061716 -122.328008) (xy 250.032248 -122.282155) (xy 250.009607 -122.232574)
			(xy 249.994253 -122.180275) (xy 249.986499 -122.126323) (xy 249.986038 -122.09907) (xy 249.986276 -122.080727)
			(xy 249.989835 -122.044214) (xy 249.99315 -122.026172) (xy 249.994733 -122.01554) (xy 249.989872 -121.994622)
			(xy 249.983752 -121.985786) (xy 249.931428 -121.916698) (xy 249.912632 -121.906284) (xy 249.90171 -121.905522)
			(xy 249.873441 -121.90272) (xy 249.818152 -121.889676) (xy 249.765407 -121.868579) (xy 249.716372 -121.839896)
			(xy 249.672131 -121.804262) (xy 249.633662 -121.762462) (xy 249.601815 -121.715421) (xy 249.577293 -121.664179)
			(xy 249.560638 -121.609868) (xy 249.552219 -121.553688) (xy 249.551698 -121.525284) (xy 246.579856 -121.525284)
			(xy 246.582509 -121.544433) (xy 246.582946 -121.57075) (xy 246.58246 -121.598001) (xy 246.574704 -121.651949)
			(xy 246.559349 -121.704244) (xy 246.536707 -121.753821) (xy 246.507241 -121.799671) (xy 246.47155 -121.840862)
			(xy 246.430359 -121.876553) (xy 246.384509 -121.906019) (xy 246.334932 -121.928661) (xy 246.282637 -121.944016)
			(xy 246.228689 -121.951772) (xy 246.174187 -121.951772) (xy 246.120239 -121.944016) (xy 246.067944 -121.928661)
			(xy 246.018367 -121.906019) (xy 245.972517 -121.876553) (xy 245.931326 -121.840862) (xy 245.895635 -121.799671)
			(xy 245.866169 -121.753821) (xy 245.843527 -121.704244) (xy 245.828172 -121.651949) (xy 245.820416 -121.598001)
			(xy 245.81993 -121.57075) (xy 245.820355 -121.544434) (xy 245.827597 -121.492304) (xy 245.841924 -121.44166)
			(xy 245.863064 -121.393461) (xy 245.890618 -121.348618) (xy 245.924065 -121.307981) (xy 245.94312 -121.289826)
			(xy 245.950515 -121.282299) (xy 245.959043 -121.263023) (xy 245.95963 -121.252488) (xy 245.95963 -121.177812)
			(xy 245.959099 -121.167263) (xy 245.950564 -121.147968) (xy 245.94312 -121.140474) (xy 245.924063 -121.12232)
			(xy 245.890605 -121.081691) (xy 245.863046 -121.03685) (xy 245.841907 -120.988649) (xy 245.827591 -120.938001)
			(xy 245.820368 -120.885866) (xy 245.81993 -120.85955) (xy 245.820405 -120.832491) (xy 245.828043 -120.778915)
			(xy 245.843172 -120.726955) (xy 245.865489 -120.677653) (xy 245.87962 -120.654572) (xy 245.886986 -120.643142)
			(xy 245.888256 -120.616472) (xy 245.836694 -120.51411) (xy 245.814088 -120.499378) (xy 245.800626 -120.498616)
			(xy 245.771981 -120.496167) (xy 245.715821 -120.483886) (xy 245.662138 -120.463318) (xy 245.612149 -120.43493)
			(xy 245.566985 -120.399364) (xy 245.527668 -120.357424) (xy 245.495087 -120.31006) (xy 245.469981 -120.258345)
			(xy 245.452917 -120.203449) (xy 245.444282 -120.146614) (xy 245.443756 -120.11787) (xy 245.44425 -120.090296)
			(xy 245.452194 -120.035724) (xy 245.467912 -119.982864) (xy 245.491077 -119.932817) (xy 245.521205 -119.886627)
			(xy 245.55767 -119.845256) (xy 245.578376 -119.82704) (xy 245.590568 -119.816626) (xy 245.598696 -119.786146)
			(xy 245.560088 -119.681498) (xy 245.556046 -119.671937) (xy 245.54176 -119.656903) (xy 245.522705 -119.648716)
			(xy 245.512336 -119.648224) (xy 245.122192 -119.648224) (xy 245.111817 -119.648713) (xy 245.092743 -119.656871)
			(xy 245.07847 -119.671927) (xy 245.07444 -119.681498) (xy 245.035832 -119.786146) (xy 245.04396 -119.816626)
			(xy 245.056152 -119.82704) (xy 245.076828 -119.84529) (xy 245.113303 -119.886649) (xy 245.143441 -119.932831)
			(xy 245.166613 -119.982871) (xy 245.182336 -120.035728) (xy 245.190283 -120.090297) (xy 245.190772 -120.11787)
			(xy 245.190317 -120.145124) (xy 245.182563 -120.199077) (xy 245.167209 -120.251377) (xy 245.144567 -120.300959)
			(xy 245.115099 -120.346814) (xy 245.079404 -120.388008) (xy 245.03821 -120.423703) (xy 244.992354 -120.45317)
			(xy 244.942771 -120.475811) (xy 244.890471 -120.491164) (xy 244.836518 -120.498917) (xy 244.809264 -120.499378)
			(xy 244.793699 -120.499214) (xy 244.762672 -120.49667) (xy 244.747288 -120.494298) (xy 244.747034 -120.494298)
			(xy 244.736082 -120.493068) (xy 244.714881 -120.499014) (xy 244.70614 -120.505728) (xy 244.646958 -120.555766)
			(xy 244.638853 -120.56338) (xy 244.629493 -120.583523) (xy 244.628924 -120.594628) (xy 244.628924 -121.692162)
			(xy 244.628408 -121.718186) (xy 244.620239 -121.76959) (xy 244.604142 -121.819087) (xy 244.580512 -121.865463)
			(xy 244.549929 -121.907579) (xy 244.531896 -121.92635) (xy 243.895626 -122.56262) (xy 243.891516 -122.567019)
			(xy 243.885227 -122.577279) (xy 243.88318 -122.58294) (xy 243.88318 -122.583448) (xy 243.874689 -122.608977)
			(xy 243.851623 -122.657579) (xy 243.821959 -122.702459) (xy 243.786283 -122.742727) (xy 243.745305 -122.777583)
			(xy 243.699836 -122.806338) (xy 243.650779 -122.828419) (xy 243.599106 -122.84339) (xy 243.545843 -122.850954)
			(xy 243.518944 -122.851418) (xy 243.491693 -122.850904) (xy 243.437744 -122.843153) (xy 243.385448 -122.827803)
			(xy 243.335869 -122.805166) (xy 243.290016 -122.775704) (xy 243.248823 -122.740016) (xy 243.213128 -122.698828)
			(xy 243.183659 -122.652979) (xy 243.161016 -122.603403) (xy 243.145658 -122.551109) (xy 243.1379 -122.497161)
			(xy 243.137436 -122.46991) (xy 242.70012 -122.46991) (xy 242.697489 -122.475672) (xy 242.668024 -122.521523)
			(xy 242.632334 -122.562714) (xy 242.591145 -122.598408) (xy 242.545296 -122.627876) (xy 242.49572 -122.65052)
			(xy 242.443426 -122.665878) (xy 242.389479 -122.673638) (xy 242.362228 -122.674126) (xy 242.346277 -122.673947)
			(xy 242.314485 -122.671281) (xy 242.298728 -122.668792) (xy 242.287552 -122.667014) (xy 242.266216 -122.672856)
			(xy 242.198398 -122.73026) (xy 242.190302 -122.737883) (xy 242.180935 -122.758019) (xy 242.180364 -122.769122)
			(xy 242.180364 -123.249752) (xy 244.109967 -123.249752) (xy 244.109967 -123.195248) (xy 244.117724 -123.141299)
			(xy 244.13308 -123.089002) (xy 244.155722 -123.039423) (xy 244.185189 -122.993572) (xy 244.220882 -122.95238)
			(xy 244.262073 -122.916688) (xy 244.307925 -122.887221) (xy 244.357504 -122.864579) (xy 244.4098 -122.849224)
			(xy 244.46375 -122.841467) (xy 244.491002 -122.841004) (xy 244.518032 -122.841498) (xy 244.571549 -122.849136)
			(xy 244.623451 -122.864259) (xy 244.672695 -122.886564) (xy 244.718294 -122.915602) (xy 244.759332 -122.950791)
			(xy 244.777514 -122.970798) (xy 244.777768 -122.971052) (xy 244.785208 -122.978703) (xy 244.804695 -122.987369)
			(xy 244.81536 -122.987816) (xy 244.90299 -122.988324) (xy 244.922548 -122.979688) (xy 244.929914 -122.971306)
			(xy 244.948074 -122.951582) (xy 244.988975 -122.916918) (xy 245.034331 -122.88833) (xy 245.083246 -122.866381)
			(xy 245.134755 -122.851505) (xy 245.187841 -122.843997) (xy 245.214648 -122.843544) (xy 245.242018 -122.84403)
			(xy 245.296196 -122.851841) (xy 245.3487 -122.867325) (xy 245.398447 -122.890163) (xy 245.444414 -122.919884)
			(xy 245.465346 -122.937524) (xy 245.4656 -122.937778) (xy 245.472676 -122.94338) (xy 245.489601 -122.949615)
			(xy 245.49862 -122.94997) (xy 245.565676 -122.94997) (xy 245.574692 -122.949608) (xy 245.59161 -122.943364)
			(xy 245.598696 -122.937778) (xy 245.598696 -122.937524) (xy 245.59895 -122.937524) (xy 245.619883 -122.919883)
			(xy 245.665851 -122.890159) (xy 245.715597 -122.867313) (xy 245.768099 -122.851817) (xy 245.822277 -122.843988)
			(xy 245.877019 -122.843988) (xy 245.931197 -122.851817) (xy 245.983699 -122.867313) (xy 246.033445 -122.890159)
			(xy 246.079413 -122.919883) (xy 246.100346 -122.937524) (xy 246.1006 -122.937778) (xy 246.107676 -122.94338)
			(xy 246.124601 -122.949615) (xy 246.13362 -122.94997) (xy 246.200676 -122.94997) (xy 246.209692 -122.949608)
			(xy 246.22661 -122.943364) (xy 246.233696 -122.937778) (xy 246.234204 -122.937524) (xy 246.246938 -122.926579)
			(xy 246.274029 -122.906738) (xy 246.288306 -122.8979) (xy 246.297196 -122.892566) (xy 246.309388 -122.875548)
			(xy 246.329708 -122.78233) (xy 246.32539 -122.761756) (xy 246.319548 -122.75312) (xy 246.303548 -122.729056)
			(xy 246.278207 -122.677124) (xy 246.260982 -122.621966) (xy 246.252266 -122.564842) (xy 246.25173 -122.53595)
			(xy 246.252216 -122.508699) (xy 246.259972 -122.454751) (xy 246.275327 -122.402456) (xy 246.297969 -122.352879)
			(xy 246.327435 -122.307029) (xy 246.363126 -122.265838) (xy 246.404317 -122.230147) (xy 246.450167 -122.200681)
			(xy 246.499744 -122.178039) (xy 246.552039 -122.162684) (xy 246.605987 -122.154928) (xy 246.660489 -122.154928)
			(xy 246.714437 -122.162684) (xy 246.766732 -122.178039) (xy 246.816309 -122.200681) (xy 246.862159 -122.230147)
			(xy 246.90335 -122.265838) (xy 246.939041 -122.307029) (xy 246.968507 -122.352879) (xy 246.991149 -122.402456)
			(xy 247.006504 -122.454751) (xy 247.01426 -122.508699) (xy 247.014746 -122.53595) (xy 247.014198 -122.56404)
			(xy 247.005979 -122.619614) (xy 246.989696 -122.673381) (xy 246.965702 -122.724178) (xy 246.934515 -122.770905)
			(xy 246.896812 -122.812552) (xy 246.853407 -122.848217) (xy 246.82958 -122.863102) (xy 246.82069 -122.868436)
			(xy 246.808498 -122.885454) (xy 246.788178 -122.978672) (xy 246.792496 -122.999246) (xy 246.798338 -123.007882)
			(xy 246.814337 -123.031946) (xy 246.839679 -123.083878) (xy 246.843788 -123.097036) (xy 248.676668 -123.097036)
			(xy 248.677139 -123.069666) (xy 248.684953 -123.015486) (xy 248.70044 -122.962982) (xy 248.723281 -122.913235)
			(xy 248.753006 -122.867269) (xy 248.770648 -122.846338) (xy 248.770902 -122.846084) (xy 248.776502 -122.839006)
			(xy 248.78274 -122.822083) (xy 248.783094 -122.813064) (xy 248.783094 -122.746008) (xy 248.782735 -122.736991)
			(xy 248.776489 -122.720074) (xy 248.770902 -122.712988) (xy 248.770648 -122.712988) (xy 248.770648 -122.712734)
			(xy 248.753019 -122.691794) (xy 248.723304 -122.645824) (xy 248.700465 -122.596079) (xy 248.684972 -122.543579)
			(xy 248.677142 -122.489405) (xy 248.676668 -122.462036) (xy 248.677154 -122.434785) (xy 248.68491 -122.380837)
			(xy 248.700265 -122.328542) (xy 248.722907 -122.278965) (xy 248.752373 -122.233115) (xy 248.788064 -122.191924)
			(xy 248.829255 -122.156233) (xy 248.875105 -122.126767) (xy 248.924682 -122.104125) (xy 248.976977 -122.08877)
			(xy 249.030925 -122.081014) (xy 249.085427 -122.081014) (xy 249.139375 -122.08877) (xy 249.19167 -122.104125)
			(xy 249.241247 -122.126767) (xy 249.287097 -122.156233) (xy 249.328288 -122.191924) (xy 249.363979 -122.233115)
			(xy 249.393445 -122.278965) (xy 249.416087 -122.328542) (xy 249.431442 -122.380837) (xy 249.439198 -122.434785)
			(xy 249.439684 -122.462036) (xy 249.439243 -122.489407) (xy 249.43142 -122.543587) (xy 249.415925 -122.596091)
			(xy 249.393078 -122.645837) (xy 249.363348 -122.691803) (xy 249.345704 -122.712734) (xy 249.34545 -122.712988)
			(xy 249.339856 -122.720069) (xy 249.333615 -122.73699) (xy 249.333258 -122.746008) (xy 249.333258 -122.813064)
			(xy 249.33362 -122.822081) (xy 249.339863 -122.838998) (xy 249.34545 -122.846084) (xy 249.345704 -122.846084)
			(xy 249.345704 -122.846338) (xy 249.363328 -122.867282) (xy 249.389029 -122.907044) (xy 251.638816 -122.907044)
			(xy 251.639241 -122.880729) (xy 251.646484 -122.828598) (xy 251.660811 -122.777954) (xy 251.681951 -122.729755)
			(xy 251.709505 -122.684913) (xy 251.742951 -122.644275) (xy 251.762006 -122.62612) (xy 251.769401 -122.618594)
			(xy 251.777929 -122.599317) (xy 251.778516 -122.588782) (xy 251.778516 -122.514106) (xy 251.777993 -122.503556)
			(xy 251.769453 -122.484261) (xy 251.762006 -122.476768) (xy 251.742943 -122.45862) (xy 251.709486 -122.417989)
			(xy 251.681928 -122.373147) (xy 251.660791 -122.324945) (xy 251.646475 -122.274296) (xy 251.639253 -122.222161)
			(xy 251.638816 -122.195844) (xy 251.639304 -122.168475) (xy 251.647116 -122.114296) (xy 251.6626 -122.061793)
			(xy 251.685437 -122.012046) (xy 251.715157 -121.966078) (xy 251.732796 -121.945146) (xy 251.73305 -121.944892)
			(xy 251.738652 -121.937816) (xy 251.744888 -121.920891) (xy 251.745242 -121.911872) (xy 251.745242 -121.844816)
			(xy 251.74489 -121.835798) (xy 251.73864 -121.818881) (xy 251.73305 -121.811796) (xy 251.732796 -121.811796)
			(xy 251.732796 -121.811542) (xy 251.7152 -121.790574) (xy 251.685475 -121.744611) (xy 251.662629 -121.694871)
			(xy 251.647131 -121.642374) (xy 251.639299 -121.588201) (xy 251.639294 -121.533465) (xy 251.647117 -121.47929)
			(xy 251.662606 -121.426791) (xy 251.685444 -121.377047) (xy 251.71516 -121.331079) (xy 251.732796 -121.310146)
			(xy 251.73305 -121.309892) (xy 251.738652 -121.302816) (xy 251.744888 -121.285891) (xy 251.745242 -121.276872)
			(xy 251.745242 -121.209816) (xy 251.74489 -121.200798) (xy 251.73864 -121.183881) (xy 251.73305 -121.176796)
			(xy 251.732796 -121.176796) (xy 251.732796 -121.176542) (xy 251.715163 -121.155605) (xy 251.68545 -121.109634)
			(xy 251.662613 -121.059887) (xy 251.647121 -121.007388) (xy 251.639291 -120.953213) (xy 251.638816 -120.925844)
			(xy 251.639302 -120.898593) (xy 251.647058 -120.844645) (xy 251.662413 -120.79235) (xy 251.685055 -120.742773)
			(xy 251.714521 -120.696923) (xy 251.750212 -120.655732) (xy 251.791403 -120.620041) (xy 251.837253 -120.590575)
			(xy 251.88683 -120.567933) (xy 251.939125 -120.552578) (xy 251.993073 -120.544822) (xy 252.047575 -120.544822)
			(xy 252.101523 -120.552578) (xy 252.153818 -120.567933) (xy 252.203395 -120.590575) (xy 252.249245 -120.620041)
			(xy 252.290436 -120.655732) (xy 252.326127 -120.696923) (xy 252.355593 -120.742773) (xy 252.378235 -120.79235)
			(xy 252.39359 -120.844645) (xy 252.401346 -120.898593) (xy 252.401832 -120.925844) (xy 252.40135 -120.953214)
			(xy 252.393538 -121.007393) (xy 252.378054 -121.059896) (xy 252.355215 -121.109644) (xy 252.325493 -121.155611)
			(xy 252.307852 -121.176542) (xy 252.307598 -121.176796) (xy 252.302007 -121.183879) (xy 252.295763 -121.200799)
			(xy 252.295406 -121.209816) (xy 252.295406 -121.276872) (xy 252.295775 -121.285888) (xy 252.302014 -121.302805)
			(xy 252.307598 -121.309892) (xy 252.307852 -121.309892) (xy 252.307852 -121.310146) (xy 252.325537 -121.331043)
			(xy 252.355261 -121.377017) (xy 252.378105 -121.426769) (xy 252.393599 -121.479276) (xy 252.401424 -121.53346)
			(xy 252.401419 -121.588206) (xy 252.393585 -121.642388) (xy 252.378082 -121.694893) (xy 252.355229 -121.744641)
			(xy 252.325497 -121.79061) (xy 252.307852 -121.811542) (xy 252.307598 -121.811796) (xy 252.302007 -121.818879)
			(xy 252.295763 -121.835799) (xy 252.295406 -121.844816) (xy 252.295406 -121.911872) (xy 252.295775 -121.920888)
			(xy 252.302014 -121.937805) (xy 252.307598 -121.944892) (xy 252.307852 -121.944892) (xy 252.307852 -121.945146)
			(xy 252.325472 -121.966094) (xy 252.355188 -122.012062) (xy 252.378029 -122.061805) (xy 252.393524 -122.114302)
			(xy 252.394442 -122.120654) (xy 268.933079 -122.120654) (xy 268.933079 -122.063346) (xy 268.941235 -122.006621)
			(xy 268.957381 -121.951634) (xy 268.981189 -121.899505) (xy 269.012173 -121.851295) (xy 269.049704 -121.807985)
			(xy 269.093016 -121.770458) (xy 269.141228 -121.739477) (xy 269.193358 -121.715672) (xy 269.248346 -121.69953)
			(xy 269.305072 -121.691377) (xy 269.333726 -121.690892) (xy 269.348644 -121.691064) (xy 269.378393 -121.693351)
			(xy 269.393162 -121.695464) (xy 269.404338 -121.697242) (xy 269.42542 -121.691146) (xy 269.492222 -121.633488)
			(xy 269.500198 -121.625904) (xy 269.509277 -121.605877) (xy 269.509748 -121.59488) (xy 269.509748 -121.330212)
			(xy 269.509221 -121.319226) (xy 269.500159 -121.299215) (xy 269.492222 -121.291604) (xy 269.42542 -121.233946)
			(xy 269.404338 -121.22785) (xy 269.393162 -121.229628) (xy 269.378392 -121.231732) (xy 269.348644 -121.234023)
			(xy 269.333726 -121.2342) (xy 269.305077 -121.233647) (xy 269.248362 -121.225496) (xy 269.193385 -121.209357)
			(xy 269.141264 -121.185557) (xy 269.093061 -121.154581) (xy 269.049757 -121.117061) (xy 269.012234 -121.07376)
			(xy 268.981256 -121.025559) (xy 268.957453 -120.973439) (xy 268.941309 -120.918463) (xy 268.933155 -120.861749)
			(xy 268.933155 -120.804451) (xy 268.941309 -120.747737) (xy 268.957453 -120.692761) (xy 268.981256 -120.640641)
			(xy 269.012234 -120.59244) (xy 269.049757 -120.549139) (xy 269.093061 -120.511619) (xy 269.141264 -120.480643)
			(xy 269.193385 -120.456843) (xy 269.248362 -120.440704) (xy 269.305077 -120.432553) (xy 269.333726 -120.432068)
			(xy 269.361107 -120.432528) (xy 269.415357 -120.439999) (xy 269.468085 -120.454783) (xy 269.51831 -120.476606)
			(xy 269.565098 -120.505063) (xy 269.607578 -120.539622) (xy 269.644958 -120.579642) (xy 269.661132 -120.60174)
			(xy 269.666696 -120.608999) (xy 269.681803 -120.619286) (xy 269.690596 -120.621806) (xy 269.720568 -120.629172)
			(xy 269.729521 -120.6309) (xy 269.747606 -120.628697) (xy 269.755874 -120.624854) (xy 269.780478 -120.612473)
			(xy 269.832003 -120.593002) (xy 269.885491 -120.579852) (xy 269.94017 -120.573211) (xy 269.96771 -120.572784)
			(xy 269.99525 -120.57322) (xy 270.049931 -120.579853) (xy 270.10342 -120.592997) (xy 270.154947 -120.612464)
			(xy 270.179546 -120.624854) (xy 270.187797 -120.628754) (xy 270.205901 -120.630956) (xy 270.214852 -120.629172)
			(xy 270.244824 -120.621806) (xy 270.253613 -120.619284) (xy 270.268711 -120.608988) (xy 270.274288 -120.60174)
			(xy 270.290473 -120.579648) (xy 270.327841 -120.539614) (xy 270.370314 -120.505044) (xy 270.4171 -120.476581)
			(xy 270.467327 -120.454756) (xy 270.520059 -120.439975) (xy 270.574312 -120.432515) (xy 270.601694 -120.432068)
			(xy 270.630347 -120.432486) (xy 270.687069 -120.440641) (xy 270.742053 -120.456785) (xy 270.79418 -120.48059)
			(xy 270.842389 -120.511571) (xy 270.885698 -120.549098) (xy 270.923225 -120.592406) (xy 270.954207 -120.640614)
			(xy 270.978013 -120.692741) (xy 270.994158 -120.747725) (xy 271.002313 -120.804447) (xy 271.002313 -120.861753)
			(xy 270.994158 -120.918475) (xy 270.978013 -120.973459) (xy 270.954207 -121.025586) (xy 270.923225 -121.073794)
			(xy 270.885698 -121.117102) (xy 270.842389 -121.154629) (xy 270.79418 -121.18561) (xy 270.742053 -121.209415)
			(xy 270.687069 -121.225559) (xy 270.630347 -121.233714) (xy 270.601694 -121.2342) (xy 270.586776 -121.234026)
			(xy 270.557027 -121.23174) (xy 270.542258 -121.229628) (xy 270.531082 -121.22785) (xy 270.51 -121.233946)
			(xy 270.443198 -121.291604) (xy 270.435229 -121.299195) (xy 270.426145 -121.319216) (xy 270.425672 -121.330212)
			(xy 270.425672 -121.59488) (xy 270.426197 -121.605866) (xy 270.435259 -121.625878) (xy 270.443198 -121.633488)
			(xy 270.51 -121.691146) (xy 270.531082 -121.697242) (xy 270.542258 -121.695464) (xy 270.557027 -121.693358)
			(xy 270.586776 -121.691068) (xy 270.601694 -121.690892) (xy 270.630341 -121.691462) (xy 270.687053 -121.699615)
			(xy 270.742027 -121.715756) (xy 270.794144 -121.739557) (xy 270.842343 -121.770532) (xy 270.885644 -121.808052)
			(xy 270.923164 -121.851352) (xy 270.95414 -121.899551) (xy 270.977942 -121.951668) (xy 270.994083 -122.006641)
			(xy 271.002237 -122.063353) (xy 271.002237 -122.120647) (xy 270.994083 -122.177359) (xy 270.977942 -122.232332)
			(xy 270.95414 -122.284449) (xy 270.923164 -122.332648) (xy 270.885644 -122.375948) (xy 270.842343 -122.413468)
			(xy 270.794144 -122.444443) (xy 270.742027 -122.468244) (xy 270.687053 -122.484385) (xy 270.630341 -122.492538)
			(xy 270.601694 -122.493024) (xy 270.574314 -122.492552) (xy 270.520064 -122.485084) (xy 270.467336 -122.470302)
			(xy 270.41711 -122.448481) (xy 270.370322 -122.420026) (xy 270.327843 -122.385468) (xy 270.290462 -122.34545)
			(xy 270.274288 -122.323352) (xy 270.268718 -122.316098) (xy 270.253615 -122.305809) (xy 270.244824 -122.303286)
			(xy 270.214852 -122.29592) (xy 270.205898 -122.294203) (xy 270.187814 -122.296399) (xy 270.179546 -122.300238)
			(xy 270.154938 -122.312611) (xy 270.103415 -122.332084) (xy 270.049928 -122.345237) (xy 269.99525 -122.35188)
			(xy 269.96771 -122.352308) (xy 269.940169 -122.351905) (xy 269.885487 -122.345263) (xy 269.831998 -122.332109)
			(xy 269.780472 -122.312633) (xy 269.755874 -122.300238) (xy 269.747619 -122.296348) (xy 269.729518 -122.29414)
			(xy 269.720568 -122.29592) (xy 269.690596 -122.303286) (xy 269.68181 -122.305819) (xy 269.666711 -122.316107)
			(xy 269.661132 -122.323352) (xy 269.644994 -122.34548) (xy 269.607618 -122.385513) (xy 269.565137 -122.420081)
			(xy 269.518343 -122.44854) (xy 269.468108 -122.470359) (xy 269.41537 -122.485131) (xy 269.36111 -122.492582)
			(xy 269.333726 -122.493024) (xy 269.305072 -122.492623) (xy 269.248346 -122.48447) (xy 269.193358 -122.468328)
			(xy 269.141228 -122.444523) (xy 269.093016 -122.413542) (xy 269.049704 -122.376015) (xy 269.012173 -122.332705)
			(xy 268.981189 -122.284495) (xy 268.957381 -122.232366) (xy 268.941235 -122.177379) (xy 268.933079 -122.120654)
			(xy 252.394442 -122.120654) (xy 252.401356 -122.168476) (xy 252.401832 -122.195844) (xy 252.401384 -122.222158)
			(xy 252.394144 -122.274287) (xy 252.37982 -122.32493) (xy 252.358684 -122.373129) (xy 252.331135 -122.417972)
			(xy 252.297694 -122.458611) (xy 252.278642 -122.476768) (xy 252.271259 -122.484305) (xy 252.262723 -122.503573)
			(xy 252.262132 -122.514106) (xy 252.262132 -122.588782) (xy 252.262648 -122.599334) (xy 252.271191 -122.618629)
			(xy 252.278642 -122.62612) (xy 252.297708 -122.644265) (xy 252.331163 -122.684898) (xy 252.358719 -122.72974)
			(xy 252.379856 -122.777943) (xy 252.394171 -122.828592) (xy 252.401394 -122.880727) (xy 252.401832 -122.907044)
			(xy 252.401346 -122.934295) (xy 252.39359 -122.988243) (xy 252.378235 -123.040538) (xy 252.355593 -123.090115)
			(xy 252.326127 -123.135965) (xy 252.290436 -123.177156) (xy 252.249245 -123.212847) (xy 252.203395 -123.242313)
			(xy 252.153818 -123.264955) (xy 252.101523 -123.28031) (xy 252.047575 -123.288066) (xy 251.993073 -123.288066)
			(xy 251.939125 -123.28031) (xy 251.88683 -123.264955) (xy 251.837253 -123.242313) (xy 251.791403 -123.212847)
			(xy 251.750212 -123.177156) (xy 251.714521 -123.135965) (xy 251.685055 -123.090115) (xy 251.662413 -123.040538)
			(xy 251.647058 -122.988243) (xy 251.639302 -122.934295) (xy 251.638816 -122.907044) (xy 249.389029 -122.907044)
			(xy 249.393042 -122.913252) (xy 249.415881 -122.962996) (xy 249.431375 -123.015494) (xy 249.439208 -123.069668)
			(xy 249.439684 -123.097036) (xy 249.439198 -123.124287) (xy 249.431442 -123.178235) (xy 249.416087 -123.23053)
			(xy 249.393445 -123.280107) (xy 249.363979 -123.325957) (xy 249.328288 -123.367148) (xy 249.287097 -123.402839)
			(xy 249.241247 -123.432305) (xy 249.19167 -123.454947) (xy 249.139375 -123.470302) (xy 249.085427 -123.478058)
			(xy 249.030925 -123.478058) (xy 248.976977 -123.470302) (xy 248.924682 -123.454947) (xy 248.875105 -123.432305)
			(xy 248.829255 -123.402839) (xy 248.788064 -123.367148) (xy 248.752373 -123.325957) (xy 248.722907 -123.280107)
			(xy 248.700265 -123.23053) (xy 248.68491 -123.178235) (xy 248.677154 -123.124287) (xy 248.676668 -123.097036)
			(xy 246.843788 -123.097036) (xy 246.856905 -123.139036) (xy 246.865621 -123.19616) (xy 246.866156 -123.225052)
			(xy 246.865577 -123.2523) (xy 246.857829 -123.306242) (xy 246.842482 -123.358532) (xy 246.81985 -123.408106)
			(xy 246.790393 -123.453954) (xy 246.754711 -123.495143) (xy 246.713531 -123.530836) (xy 246.66769 -123.560304)
			(xy 246.618122 -123.582948) (xy 246.565836 -123.598308) (xy 246.511896 -123.60607) (xy 246.484648 -123.60656)
			(xy 246.457278 -123.606076) (xy 246.4031 -123.598264) (xy 246.350596 -123.582779) (xy 246.300849 -123.559942)
			(xy 246.254882 -123.53022) (xy 246.23395 -123.51258) (xy 246.233696 -123.512326) (xy 246.226621 -123.506723)
			(xy 246.209695 -123.500488) (xy 246.200676 -123.500134) (xy 246.13362 -123.500134) (xy 246.124603 -123.500493)
			(xy 246.107686 -123.506739) (xy 246.1006 -123.512326) (xy 246.100346 -123.51258) (xy 246.079413 -123.530221)
			(xy 246.033445 -123.559945) (xy 245.983699 -123.582791) (xy 245.931197 -123.598287) (xy 245.877019 -123.606116)
			(xy 245.822277 -123.606116) (xy 245.768099 -123.598287) (xy 245.715597 -123.582791) (xy 245.665851 -123.559945)
			(xy 245.619883 -123.530221) (xy 245.59895 -123.51258) (xy 245.598696 -123.512326) (xy 245.591621 -123.506723)
			(xy 245.574695 -123.500488) (xy 245.565676 -123.500134) (xy 245.49862 -123.500134) (xy 245.489603 -123.500493)
			(xy 245.472686 -123.506739) (xy 245.4656 -123.512326) (xy 245.4656 -123.51258) (xy 245.465346 -123.51258)
			(xy 245.444405 -123.530208) (xy 245.398435 -123.559922) (xy 245.34869 -123.582761) (xy 245.296191 -123.598254)
			(xy 245.242017 -123.606085) (xy 245.214648 -123.60656) (xy 245.187618 -123.606078) (xy 245.134101 -123.598435)
			(xy 245.0822 -123.583308) (xy 245.032957 -123.561001) (xy 244.987358 -123.531961) (xy 244.946319 -123.496772)
			(xy 244.928136 -123.476766) (xy 244.927882 -123.476512) (xy 244.920414 -123.468893) (xy 244.900949 -123.460207)
			(xy 244.89029 -123.459748) (xy 244.80266 -123.45924) (xy 244.783102 -123.467876) (xy 244.775736 -123.476258)
			(xy 244.757564 -123.49597) (xy 244.716664 -123.530633) (xy 244.67131 -123.559221) (xy 244.622398 -123.581172)
			(xy 244.570891 -123.59605) (xy 244.517808 -123.603564) (xy 244.491002 -123.60402) (xy 244.46375 -123.603533)
			(xy 244.4098 -123.595776) (xy 244.357504 -123.580421) (xy 244.307925 -123.557779) (xy 244.262073 -123.528312)
			(xy 244.220882 -123.49262) (xy 244.185189 -123.451428) (xy 244.155722 -123.405577) (xy 244.13308 -123.355998)
			(xy 244.117724 -123.303701) (xy 244.109967 -123.249752) (xy 242.180364 -123.249752) (xy 242.180364 -123.914136)
			(xy 266.291227 -123.914136) (xy 266.291227 -123.856864) (xy 266.299378 -123.800175) (xy 266.315514 -123.745223)
			(xy 266.339306 -123.693126) (xy 266.37027 -123.644946) (xy 266.407777 -123.601664) (xy 266.451061 -123.56416)
			(xy 266.499242 -123.533197) (xy 266.55134 -123.509407) (xy 266.606292 -123.493274) (xy 266.662982 -123.485125)
			(xy 266.691618 -123.48464) (xy 266.706532 -123.484752) (xy 266.736281 -123.486911) (xy 266.751054 -123.488958)
			(xy 266.76223 -123.490736) (xy 266.783312 -123.48464) (xy 266.850114 -123.426982) (xy 266.858091 -123.419399)
			(xy 266.86717 -123.399372) (xy 266.86764 -123.388374) (xy 266.86764 -123.123706) (xy 266.867119 -123.112719)
			(xy 266.858053 -123.092708) (xy 266.850114 -123.085098) (xy 266.783312 -123.02744) (xy 266.76223 -123.021344)
			(xy 266.751054 -123.023122) (xy 266.736281 -123.025171) (xy 266.706532 -123.027331) (xy 266.691618 -123.02744)
			(xy 266.662987 -123.026899) (xy 266.606309 -123.018752) (xy 266.551366 -123.002622) (xy 266.499279 -122.978836)
			(xy 266.451106 -122.94788) (xy 266.40783 -122.910382) (xy 266.370331 -122.867108) (xy 266.339373 -122.818937)
			(xy 266.315585 -122.766851) (xy 266.299452 -122.711909) (xy 266.291303 -122.655231) (xy 266.291303 -122.597969)
			(xy 266.299452 -122.541291) (xy 266.315585 -122.486349) (xy 266.339373 -122.434263) (xy 266.370331 -122.386092)
			(xy 266.40783 -122.342818) (xy 266.451106 -122.30532) (xy 266.499279 -122.274364) (xy 266.551366 -122.250578)
			(xy 266.606309 -122.234448) (xy 266.662987 -122.226301) (xy 266.691618 -122.225816) (xy 266.718988 -122.226274)
			(xy 266.77322 -122.233721) (xy 266.825936 -122.248475) (xy 266.876155 -122.270261) (xy 266.922944 -122.298675)
			(xy 266.965434 -122.333188) (xy 267.002835 -122.373159) (xy 267.019024 -122.395234) (xy 267.024592 -122.40249)
			(xy 267.039697 -122.412778) (xy 267.048488 -122.4153) (xy 267.07846 -122.422666) (xy 267.087413 -122.42439)
			(xy 267.105498 -122.42219) (xy 267.113766 -122.418348) (xy 267.138375 -122.405993) (xy 267.189909 -122.386591)
			(xy 267.243398 -122.373506) (xy 267.298069 -122.366929) (xy 267.325602 -122.366532) (xy 267.353136 -122.366927)
			(xy 267.40781 -122.373491) (xy 267.461301 -122.386573) (xy 267.512833 -122.405983) (xy 267.537438 -122.418348)
			(xy 267.54569 -122.422244) (xy 267.563793 -122.424448) (xy 267.572744 -122.422666) (xy 267.602716 -122.4153)
			(xy 267.611493 -122.412745) (xy 267.626595 -122.40247) (xy 267.63218 -122.395234) (xy 267.648373 -122.373163)
			(xy 267.685774 -122.333193) (xy 267.728264 -122.298681) (xy 267.775052 -122.270268) (xy 267.825271 -122.248482)
			(xy 267.877985 -122.233729) (xy 267.932216 -122.226282) (xy 267.959586 -122.225816) (xy 267.98822 -122.226246)
			(xy 268.044907 -122.234394) (xy 268.099856 -122.250527) (xy 268.151951 -122.274316) (xy 268.200129 -122.305277)
			(xy 268.243411 -122.342779) (xy 268.280915 -122.38606) (xy 268.311877 -122.434237) (xy 268.335668 -122.48633)
			(xy 268.351803 -122.54128) (xy 268.359953 -122.597966) (xy 268.359953 -122.655234) (xy 268.351803 -122.71192)
			(xy 268.335668 -122.76687) (xy 268.311877 -122.818963) (xy 268.280915 -122.86714) (xy 268.243411 -122.910421)
			(xy 268.200129 -122.947923) (xy 268.151951 -122.978884) (xy 268.099856 -123.002673) (xy 268.044907 -123.018806)
			(xy 267.98822 -123.026954) (xy 267.959586 -123.02744) (xy 267.944672 -123.027327) (xy 267.914923 -123.025168)
			(xy 267.90015 -123.023122) (xy 267.888974 -123.021344) (xy 267.867892 -123.02744) (xy 267.80109 -123.085098)
			(xy 267.793123 -123.09269) (xy 267.784038 -123.11271) (xy 267.783564 -123.123706) (xy 267.783564 -123.388374)
			(xy 267.78404 -123.399366) (xy 267.793137 -123.419377) (xy 267.80109 -123.426982) (xy 267.867892 -123.48464)
			(xy 267.888974 -123.490736) (xy 267.90015 -123.488958) (xy 267.914923 -123.486909) (xy 267.944672 -123.484748)
			(xy 267.959586 -123.48464) (xy 267.988215 -123.485222) (xy 268.044891 -123.493368) (xy 268.09983 -123.509498)
			(xy 268.151914 -123.533283) (xy 268.200083 -123.564238) (xy 268.243357 -123.601733) (xy 268.280854 -123.645005)
			(xy 268.31181 -123.693173) (xy 268.335597 -123.745257) (xy 268.351729 -123.800196) (xy 268.359877 -123.856871)
			(xy 268.359877 -123.914129) (xy 268.351729 -123.970804) (xy 268.335597 -124.025743) (xy 268.31181 -124.077827)
			(xy 268.280854 -124.125995) (xy 268.243357 -124.169267) (xy 268.200083 -124.206762) (xy 268.151914 -124.237717)
			(xy 268.09983 -124.261502) (xy 268.044891 -124.277632) (xy 267.988215 -124.285778) (xy 267.959586 -124.286264)
			(xy 267.932215 -124.285812) (xy 267.877983 -124.278365) (xy 267.825267 -124.26361) (xy 267.775048 -124.241823)
			(xy 267.728259 -124.213409) (xy 267.685769 -124.178894) (xy 267.648368 -124.138921) (xy 267.63218 -124.116846)
			(xy 267.626614 -124.109588) (xy 267.611508 -124.099302) (xy 267.602716 -124.09678) (xy 267.572744 -124.089414)
			(xy 267.563791 -124.087694) (xy 267.545706 -124.089892) (xy 267.537438 -124.093732) (xy 267.512828 -124.106084)
			(xy 267.461294 -124.125487) (xy 267.407806 -124.138573) (xy 267.353135 -124.145151) (xy 267.325602 -124.145548)
			(xy 267.298068 -124.145154) (xy 267.243394 -124.13859) (xy 267.189903 -124.125507) (xy 267.13837 -124.106097)
			(xy 267.113766 -124.093732) (xy 267.105513 -124.089838) (xy 267.087411 -124.087633) (xy 267.07846 -124.089414)
			(xy 267.048488 -124.09678) (xy 267.039702 -124.099311) (xy 267.024603 -124.109601) (xy 267.019024 -124.116846)
			(xy 267.002822 -124.13891) (xy 266.965423 -124.178882) (xy 266.922936 -124.213395) (xy 266.876148 -124.241809)
			(xy 266.825931 -124.263596) (xy 266.773218 -124.27835) (xy 266.718988 -124.285797) (xy 266.691618 -124.286264)
			(xy 266.662982 -124.285875) (xy 266.606292 -124.277726) (xy 266.55134 -124.261593) (xy 266.499242 -124.237803)
			(xy 266.451061 -124.20684) (xy 266.407777 -124.169336) (xy 266.37027 -124.126054) (xy 266.339306 -124.077874)
			(xy 266.315514 -124.025777) (xy 266.299378 -123.970825) (xy 266.291227 -123.914136) (xy 242.180364 -123.914136)
			(xy 242.180364 -124.370084) (xy 242.179892 -124.396172) (xy 242.171725 -124.447705) (xy 242.155591 -124.497324)
			(xy 242.131886 -124.543804) (xy 242.101197 -124.586001) (xy 242.083082 -124.60478) (xy 241.631724 -125.056138)
			(xy 241.63006 -125.057916) (xy 242.981478 -125.057916) (xy 242.985549 -125.002294) (xy 242.997675 -124.947857)
			(xy 243.017598 -124.895766) (xy 243.044894 -124.847131) (xy 243.07898 -124.802988) (xy 243.119129 -124.764279)
			(xy 243.164487 -124.731828) (xy 243.214087 -124.706327) (xy 243.266871 -124.68832) (xy 243.321714 -124.67819)
			(xy 243.377448 -124.676153) (xy 243.432885 -124.682253) (xy 243.486842 -124.696359) (xy 243.538171 -124.718171)
			(xy 243.585777 -124.747225) (xy 243.628645 -124.7829) (xy 243.665862 -124.824437) (xy 243.696635 -124.87095)
			(xy 243.720307 -124.921447) (xy 243.736375 -124.974854) (xy 243.744495 -125.03003) (xy 243.745004 -125.057916)
			(xy 243.744495 -125.085802) (xy 243.736375 -125.140978) (xy 243.720307 -125.194385) (xy 243.696635 -125.244882)
			(xy 243.665862 -125.291395) (xy 243.628645 -125.332932) (xy 243.585777 -125.368607) (xy 243.538171 -125.397661)
			(xy 243.524769 -125.403356) (xy 247.744234 -125.403356) (xy 247.744725 -125.375987) (xy 247.752535 -125.321808)
			(xy 247.768018 -125.269305) (xy 247.790855 -125.219558) (xy 247.820575 -125.17359) (xy 247.838214 -125.152658)
			(xy 247.838468 -125.152404) (xy 247.844067 -125.145326) (xy 247.850304 -125.128402) (xy 247.85066 -125.119384)
			(xy 247.85066 -125.052328) (xy 247.850298 -125.043311) (xy 247.844055 -125.026394) (xy 247.838468 -125.019308)
			(xy 247.838214 -125.019308) (xy 247.838214 -125.019054) (xy 247.820589 -124.998111) (xy 247.790875 -124.952141)
			(xy 247.768036 -124.902397) (xy 247.752541 -124.849898) (xy 247.74471 -124.795724) (xy 247.744234 -124.768356)
			(xy 247.74472 -124.741105) (xy 247.752476 -124.687157) (xy 247.767831 -124.634862) (xy 247.790473 -124.585285)
			(xy 247.819939 -124.539435) (xy 247.85563 -124.498244) (xy 247.896821 -124.462553) (xy 247.942671 -124.433087)
			(xy 247.992248 -124.410445) (xy 248.044543 -124.39509) (xy 248.098491 -124.387334) (xy 248.152993 -124.387334)
			(xy 248.206941 -124.39509) (xy 248.259236 -124.410445) (xy 248.308813 -124.433087) (xy 248.354663 -124.462553)
			(xy 248.395854 -124.498244) (xy 248.431545 -124.539435) (xy 248.461011 -124.585285) (xy 248.483653 -124.634862)
			(xy 248.499008 -124.687157) (xy 248.506764 -124.741105) (xy 248.50725 -124.768356) (xy 248.50677 -124.795726)
			(xy 248.498958 -124.849905) (xy 248.483472 -124.902408) (xy 248.460633 -124.952155) (xy 248.430911 -124.998122)
			(xy 248.41327 -125.019054) (xy 248.413016 -125.019308) (xy 248.407422 -125.026389) (xy 248.401179 -125.04331)
			(xy 248.400824 -125.052328) (xy 248.400824 -125.119384) (xy 248.401184 -125.128401) (xy 248.407429 -125.145318)
			(xy 248.413016 -125.152404) (xy 248.41327 -125.152404) (xy 248.41327 -125.152658) (xy 248.430898 -125.173599)
			(xy 248.460613 -125.219569) (xy 248.483451 -125.269314) (xy 248.498945 -125.321813) (xy 248.506775 -125.375987)
			(xy 248.50725 -125.403356) (xy 248.506764 -125.430607) (xy 248.499008 -125.484555) (xy 248.483653 -125.53685)
			(xy 248.461011 -125.586427) (xy 248.431545 -125.632277) (xy 248.395854 -125.673468) (xy 248.354663 -125.709159)
			(xy 248.308813 -125.738625) (xy 248.259236 -125.761267) (xy 248.206941 -125.776622) (xy 248.152993 -125.784378)
			(xy 248.098491 -125.784378) (xy 248.044543 -125.776622) (xy 247.992248 -125.761267) (xy 247.942671 -125.738625)
			(xy 247.896821 -125.709159) (xy 247.85563 -125.673468) (xy 247.819939 -125.632277) (xy 247.790473 -125.586427)
			(xy 247.767831 -125.53685) (xy 247.752476 -125.484555) (xy 247.74472 -125.430607) (xy 247.744234 -125.403356)
			(xy 243.524769 -125.403356) (xy 243.486842 -125.419473) (xy 243.432885 -125.433579) (xy 243.377448 -125.439679)
			(xy 243.321714 -125.437642) (xy 243.266871 -125.427512) (xy 243.214087 -125.409505) (xy 243.164487 -125.384004)
			(xy 243.119129 -125.351553) (xy 243.07898 -125.312844) (xy 243.044894 -125.268701) (xy 243.017598 -125.220066)
			(xy 242.997675 -125.167975) (xy 242.985549 -125.113538) (xy 242.981478 -125.057916) (xy 241.63006 -125.057916)
			(xy 241.62761 -125.060533) (xy 241.621323 -125.070796) (xy 241.619278 -125.076458) (xy 241.619278 -125.076966)
			(xy 241.6108 -125.102499) (xy 241.587732 -125.151101) (xy 241.558065 -125.195981) (xy 241.522388 -125.236248)
			(xy 241.481408 -125.271104) (xy 241.435938 -125.299857) (xy 241.386879 -125.321938) (xy 241.335206 -125.336909)
			(xy 241.281941 -125.344472) (xy 241.255042 -125.344936) (xy 241.227791 -125.344406) (xy 241.173844 -125.336655)
			(xy 241.121549 -125.321306) (xy 241.071971 -125.29867) (xy 241.026119 -125.269209) (xy 240.984927 -125.233523)
			(xy 240.949233 -125.192337) (xy 240.919763 -125.14649) (xy 240.897119 -125.096916) (xy 240.88176 -125.044624)
			(xy 240.873999 -124.990678) (xy 240.873534 -124.963428) (xy 226.771454 -124.963428) (xy 225.762058 -125.972824)
			(xy 225.755178 -125.979428) (xy 240.873024 -125.979428) (xy 240.877095 -125.923806) (xy 240.889221 -125.869369)
			(xy 240.909144 -125.817278) (xy 240.93644 -125.768643) (xy 240.970526 -125.7245) (xy 241.010675 -125.685791)
			(xy 241.056033 -125.65334) (xy 241.105633 -125.627839) (xy 241.158417 -125.609832) (xy 241.21326 -125.599702)
			(xy 241.268994 -125.597665) (xy 241.324431 -125.603765) (xy 241.378388 -125.617871) (xy 241.429717 -125.639683)
			(xy 241.477323 -125.668737) (xy 241.520191 -125.704412) (xy 241.557408 -125.745949) (xy 241.588181 -125.792462)
			(xy 241.611853 -125.842959) (xy 241.627921 -125.896366) (xy 241.636041 -125.951542) (xy 241.63655 -125.979428)
			(xy 241.636041 -126.007314) (xy 241.627921 -126.06249) (xy 241.614396 -126.107444) (xy 243.356382 -126.107444)
			(xy 243.360453 -126.051822) (xy 243.372579 -125.997385) (xy 243.392502 -125.945294) (xy 243.419798 -125.896659)
			(xy 243.453884 -125.852516) (xy 243.494033 -125.813807) (xy 243.539391 -125.781356) (xy 243.588991 -125.755855)
			(xy 243.641775 -125.737848) (xy 243.696618 -125.727718) (xy 243.752352 -125.725681) (xy 243.807789 -125.731781)
			(xy 243.861746 -125.745887) (xy 243.913075 -125.767699) (xy 243.960681 -125.796753) (xy 244.003549 -125.832428)
			(xy 244.022607 -125.853698) (xy 248.684796 -125.853698) (xy 248.685262 -125.826328) (xy 248.69308 -125.772149)
			(xy 248.708569 -125.719646) (xy 248.731411 -125.669899) (xy 248.761135 -125.623932) (xy 248.778776 -125.603)
			(xy 248.77903 -125.602746) (xy 248.784607 -125.595653) (xy 248.790858 -125.578741) (xy 248.791222 -125.569726)
			(xy 248.791222 -125.50267) (xy 248.790875 -125.493652) (xy 248.78462 -125.476736) (xy 248.77903 -125.46965)
			(xy 248.778776 -125.46965) (xy 248.778776 -125.469396) (xy 248.761118 -125.448479) (xy 248.73141 -125.402502)
			(xy 248.708578 -125.35275) (xy 248.693091 -125.300247) (xy 248.685268 -125.246068) (xy 248.684796 -125.218698)
			(xy 248.685282 -125.191447) (xy 248.693038 -125.137499) (xy 248.708393 -125.085204) (xy 248.731035 -125.035627)
			(xy 248.760501 -124.989777) (xy 248.796192 -124.948586) (xy 248.837383 -124.912895) (xy 248.883233 -124.883429)
			(xy 248.93281 -124.860787) (xy 248.985105 -124.845432) (xy 249.039053 -124.837676) (xy 249.093555 -124.837676)
			(xy 249.147503 -124.845432) (xy 249.199798 -124.860787) (xy 249.249375 -124.883429) (xy 249.295225 -124.912895)
			(xy 249.336416 -124.948586) (xy 249.372107 -124.989777) (xy 249.401573 -125.035627) (xy 249.424215 -125.085204)
			(xy 249.43957 -125.137499) (xy 249.447326 -125.191447) (xy 249.447812 -125.218698) (xy 249.447342 -125.246068)
			(xy 249.439525 -125.300247) (xy 249.424036 -125.35275) (xy 249.401196 -125.402497) (xy 249.371472 -125.448464)
			(xy 249.353832 -125.469396) (xy 249.353578 -125.46965) (xy 249.348004 -125.476745) (xy 249.34175 -125.493655)
			(xy 249.341386 -125.50267) (xy 249.341386 -125.569726) (xy 249.341734 -125.578744) (xy 249.347988 -125.59566)
			(xy 249.353578 -125.602746) (xy 249.353832 -125.602746) (xy 249.353832 -125.603) (xy 249.37149 -125.623917)
			(xy 249.401198 -125.669895) (xy 249.424029 -125.719646) (xy 249.439516 -125.77215) (xy 249.44734 -125.826328)
			(xy 249.447812 -125.853698) (xy 249.447326 -125.880949) (xy 249.43957 -125.934897) (xy 249.424215 -125.987192)
			(xy 249.401573 -126.036769) (xy 249.372107 -126.082619) (xy 249.336416 -126.12381) (xy 249.295225 -126.159501)
			(xy 249.249375 -126.188967) (xy 249.199798 -126.211609) (xy 249.147503 -126.226964) (xy 249.093555 -126.23472)
			(xy 249.039053 -126.23472) (xy 248.985105 -126.226964) (xy 248.93281 -126.211609) (xy 248.883233 -126.188967)
			(xy 248.837383 -126.159501) (xy 248.796192 -126.12381) (xy 248.760501 -126.082619) (xy 248.731035 -126.036769)
			(xy 248.708393 -125.987192) (xy 248.693038 -125.934897) (xy 248.685282 -125.880949) (xy 248.684796 -125.853698)
			(xy 244.022607 -125.853698) (xy 244.040766 -125.873965) (xy 244.071539 -125.920478) (xy 244.095211 -125.970975)
			(xy 244.111279 -126.024382) (xy 244.119399 -126.079558) (xy 244.119908 -126.107444) (xy 244.119399 -126.13533)
			(xy 244.111279 -126.190506) (xy 244.095211 -126.243913) (xy 244.071539 -126.29441) (xy 244.040766 -126.340923)
			(xy 244.003549 -126.38246) (xy 243.960681 -126.418135) (xy 243.913075 -126.447189) (xy 243.861746 -126.469001)
			(xy 243.807789 -126.483107) (xy 243.752352 -126.489207) (xy 243.696618 -126.48717) (xy 243.641775 -126.47704)
			(xy 243.588991 -126.459033) (xy 243.539391 -126.433532) (xy 243.494033 -126.401081) (xy 243.453884 -126.362372)
			(xy 243.419798 -126.318229) (xy 243.392502 -126.269594) (xy 243.372579 -126.217503) (xy 243.360453 -126.163066)
			(xy 243.356382 -126.107444) (xy 241.614396 -126.107444) (xy 241.611853 -126.115897) (xy 241.588181 -126.166394)
			(xy 241.557408 -126.212907) (xy 241.520191 -126.254444) (xy 241.477323 -126.290119) (xy 241.429717 -126.319173)
			(xy 241.378388 -126.340985) (xy 241.324431 -126.355091) (xy 241.268994 -126.361191) (xy 241.21326 -126.359154)
			(xy 241.158417 -126.349024) (xy 241.105633 -126.331017) (xy 241.056033 -126.305516) (xy 241.010675 -126.273065)
			(xy 240.970526 -126.234356) (xy 240.93644 -126.190213) (xy 240.909144 -126.141578) (xy 240.889221 -126.089487)
			(xy 240.877095 -126.03505) (xy 240.873024 -125.979428) (xy 225.755178 -125.979428) (xy 225.743281 -125.990849)
			(xy 225.701165 -126.021429) (xy 225.65479 -126.045057) (xy 225.605295 -126.061154) (xy 225.553893 -126.069323)
			(xy 225.52787 -126.069852) (xy 218.176094 -126.069852) (xy 218.169944 -126.070041) (xy 218.158003 -126.072997)
			(xy 218.152472 -126.075694) (xy 218.124935 -126.089508) (xy 218.066523 -126.10908) (xy 218.005727 -126.119022)
			(xy 217.974926 -126.119636) (xy 217.947674 -126.119119) (xy 217.893724 -126.111365) (xy 217.841427 -126.096012)
			(xy 217.791847 -126.073373) (xy 217.745994 -126.043908) (xy 217.704801 -126.008217) (xy 217.669108 -125.967027)
			(xy 217.639639 -125.921176) (xy 217.616997 -125.871597) (xy 217.60164 -125.819301) (xy 217.593883 -125.765352)
			(xy 208.40954 -125.765352) (xy 208.40954 -126.530354) (xy 249.893328 -126.530354) (xy 249.893869 -126.50269)
			(xy 249.901862 -126.447941) (xy 249.917672 -126.39492) (xy 249.94097 -126.344735) (xy 249.971267 -126.298439)
			(xy 250.007929 -126.257001) (xy 250.050188 -126.221287) (xy 250.073414 -126.20625) (xy 250.083065 -126.199582)
			(xy 250.095524 -126.179744) (xy 250.09729 -126.16815) (xy 250.105164 -126.08814) (xy 250.105759 -126.076503)
			(xy 250.097704 -126.054668) (xy 250.08967 -126.04623) (xy 250.089416 -126.045976) (xy 250.070844 -126.027886)
			(xy 250.038264 -125.987556) (xy 250.011449 -125.943184) (xy 249.990895 -125.895587) (xy 249.97698 -125.845644)
			(xy 249.969961 -125.794277) (xy 249.969528 -125.768354) (xy 249.969935 -125.7411) (xy 249.977699 -125.687148)
			(xy 249.993062 -125.634849) (xy 250.015711 -125.585269) (xy 250.045185 -125.539417) (xy 250.080885 -125.498227)
			(xy 250.122083 -125.462536) (xy 250.167941 -125.433071) (xy 250.217526 -125.410433) (xy 250.269828 -125.395081)
			(xy 250.323782 -125.387329) (xy 250.351036 -125.386846) (xy 250.378408 -125.38728) (xy 250.432588 -125.395104)
			(xy 250.485092 -125.4106) (xy 250.534839 -125.433449) (xy 250.580804 -125.463181) (xy 250.601734 -125.480826)
			(xy 250.601988 -125.48108) (xy 250.609067 -125.486677) (xy 250.62599 -125.492915) (xy 250.635008 -125.493272)
			(xy 250.702064 -125.493272) (xy 250.71108 -125.492904) (xy 250.727997 -125.486665) (xy 250.735084 -125.48108)
			(xy 250.735084 -125.480826) (xy 250.735338 -125.480826) (xy 250.756286 -125.463207) (xy 250.802254 -125.433491)
			(xy 250.851997 -125.410651) (xy 250.904495 -125.395155) (xy 250.958668 -125.387322) (xy 250.986036 -125.386846)
			(xy 251.013286 -125.387344) (xy 251.067231 -125.395104) (xy 251.119523 -125.410462) (xy 251.169097 -125.433104)
			(xy 251.214945 -125.462569) (xy 251.256134 -125.498259) (xy 251.291824 -125.539447) (xy 251.321291 -125.585294)
			(xy 251.343935 -125.634868) (xy 251.359293 -125.687159) (xy 251.367055 -125.741104) (xy 251.367544 -125.768354)
			(xy 251.367014 -125.797271) (xy 251.35829 -125.854442) (xy 251.341036 -125.909642) (xy 251.315647 -125.961604)
			(xy 251.282704 -126.009138) (xy 251.242964 -126.051155) (xy 251.220478 -126.069344) (xy 251.211657 -126.076938)
			(xy 251.201482 -126.097849) (xy 251.20092 -126.109476) (xy 251.20092 -126.189232) (xy 251.201448 -126.200865)
			(xy 251.211644 -126.221775) (xy 251.220478 -126.229364) (xy 251.24294 -126.247581) (xy 251.282677 -126.289595)
			(xy 251.315619 -126.337124) (xy 251.341012 -126.38908) (xy 251.358273 -126.444273) (xy 251.367006 -126.501439)
			(xy 251.367544 -126.530354) (xy 251.367002 -126.557604) (xy 251.359252 -126.61155) (xy 251.347151 -126.652782)
			(xy 251.638816 -126.652782) (xy 251.639268 -126.625411) (xy 251.647088 -126.571231) (xy 251.662581 -126.518728)
			(xy 251.685426 -126.468981) (xy 251.715153 -126.423015) (xy 251.732796 -126.402084) (xy 251.73305 -126.40183)
			(xy 251.738636 -126.394743) (xy 251.744882 -126.377826) (xy 251.745242 -126.36881) (xy 251.745242 -126.301754)
			(xy 251.744872 -126.292738) (xy 251.738635 -126.27582) (xy 251.73305 -126.268734) (xy 251.732796 -126.268734)
			(xy 251.732796 -126.26848) (xy 251.715139 -126.247561) (xy 251.685417 -126.20159) (xy 251.662575 -126.151841)
			(xy 251.647081 -126.099337) (xy 251.639255 -126.045158) (xy 251.639257 -125.990415) (xy 251.647087 -125.936236)
			(xy 251.662584 -125.883733) (xy 251.68543 -125.833986) (xy 251.715155 -125.788017) (xy 251.732796 -125.767084)
			(xy 251.73305 -125.76683) (xy 251.738636 -125.759743) (xy 251.744882 -125.742826) (xy 251.745242 -125.73381)
			(xy 251.745242 -125.666754) (xy 251.744872 -125.657738) (xy 251.738635 -125.64082) (xy 251.73305 -125.633734)
			(xy 251.732796 -125.633734) (xy 251.732796 -125.63348) (xy 251.715139 -125.612561) (xy 251.685417 -125.56659)
			(xy 251.662575 -125.516841) (xy 251.647081 -125.464337) (xy 251.639255 -125.410158) (xy 251.639257 -125.355415)
			(xy 251.647087 -125.301236) (xy 251.662584 -125.248733) (xy 251.68543 -125.198986) (xy 251.715155 -125.153017)
			(xy 251.732796 -125.132084) (xy 251.73305 -125.13183) (xy 251.738636 -125.124743) (xy 251.744882 -125.107826)
			(xy 251.745242 -125.09881) (xy 251.745242 -125.031754) (xy 251.744872 -125.022738) (xy 251.738635 -125.00582)
			(xy 251.73305 -124.998734) (xy 251.732796 -124.998734) (xy 251.732796 -124.99848) (xy 251.71518 -124.977529)
			(xy 251.685465 -124.931561) (xy 251.662625 -124.881819) (xy 251.647128 -124.829322) (xy 251.639294 -124.77515)
			(xy 251.638816 -124.747782) (xy 251.639302 -124.720531) (xy 251.647058 -124.666583) (xy 251.662413 -124.614288)
			(xy 251.685055 -124.564711) (xy 251.714521 -124.518861) (xy 251.750212 -124.47767) (xy 251.791403 -124.441979)
			(xy 251.837253 -124.412513) (xy 251.88683 -124.389871) (xy 251.939125 -124.374516) (xy 251.993073 -124.36676)
			(xy 252.047575 -124.36676) (xy 252.101523 -124.374516) (xy 252.153818 -124.389871) (xy 252.203395 -124.412513)
			(xy 252.249245 -124.441979) (xy 252.290436 -124.47767) (xy 252.326127 -124.518861) (xy 252.355593 -124.564711)
			(xy 252.378235 -124.614288) (xy 252.39359 -124.666583) (xy 252.401346 -124.720531) (xy 252.401832 -124.747782)
			(xy 252.401372 -124.775153) (xy 252.393555 -124.829333) (xy 252.378066 -124.881836) (xy 252.355222 -124.931583)
			(xy 252.325495 -124.977549) (xy 252.307852 -124.99848) (xy 252.307598 -124.998734) (xy 252.302033 -125.005835)
			(xy 252.295773 -125.022741) (xy 252.295406 -125.031754) (xy 252.295406 -125.09881) (xy 252.295757 -125.107828)
			(xy 252.302009 -125.124744) (xy 252.307598 -125.13183) (xy 252.307852 -125.13183) (xy 252.307852 -125.132084)
			(xy 252.325476 -125.153031) (xy 252.355203 -125.198995) (xy 252.378051 -125.248739) (xy 252.393549 -125.301239)
			(xy 252.40138 -125.355416) (xy 252.401382 -125.410156) (xy 252.393555 -125.464334) (xy 252.37806 -125.516835)
			(xy 252.355216 -125.566581) (xy 252.325492 -125.612548) (xy 252.307852 -125.63348) (xy 252.307598 -125.633734)
			(xy 252.302033 -125.640835) (xy 252.295773 -125.657741) (xy 252.295406 -125.666754) (xy 252.295406 -125.720854)
			(xy 268.933075 -125.720854) (xy 268.933075 -125.663546) (xy 268.941231 -125.60682) (xy 268.957378 -125.551833)
			(xy 268.981186 -125.499703) (xy 269.01217 -125.451492) (xy 269.049701 -125.408182) (xy 269.093013 -125.370655)
			(xy 269.141226 -125.339673) (xy 269.193357 -125.315869) (xy 269.248345 -125.299726) (xy 269.305072 -125.291573)
			(xy 269.333726 -125.291088) (xy 269.348644 -125.291259) (xy 269.378393 -125.293547) (xy 269.393162 -125.29566)
			(xy 269.404338 -125.297438) (xy 269.42542 -125.291342) (xy 269.492222 -125.233684) (xy 269.5002 -125.226101)
			(xy 269.509278 -125.206074) (xy 269.509748 -125.195076) (xy 269.509748 -124.930408) (xy 269.509223 -124.919422)
			(xy 269.50016 -124.89941) (xy 269.492222 -124.8918) (xy 269.42542 -124.834142) (xy 269.404338 -124.828046)
			(xy 269.393162 -124.829824) (xy 269.378392 -124.831928) (xy 269.348644 -124.834219) (xy 269.333726 -124.834396)
			(xy 269.305077 -124.833851) (xy 269.248362 -124.8257) (xy 269.193384 -124.80956) (xy 269.141262 -124.78576)
			(xy 269.093059 -124.754785) (xy 269.049755 -124.717264) (xy 269.012231 -124.673962) (xy 268.981252 -124.62576)
			(xy 268.957449 -124.573641) (xy 268.941305 -124.518664) (xy 268.933151 -124.461949) (xy 268.933151 -124.404651)
			(xy 268.941305 -124.347936) (xy 268.957449 -124.292959) (xy 268.981252 -124.24084) (xy 269.012231 -124.192638)
			(xy 269.049755 -124.149336) (xy 269.093059 -124.111815) (xy 269.141262 -124.08084) (xy 269.193384 -124.05704)
			(xy 269.248362 -124.0409) (xy 269.305077 -124.032749) (xy 269.333726 -124.032264) (xy 269.361107 -124.032726)
			(xy 269.415356 -124.040196) (xy 269.468085 -124.05498) (xy 269.51831 -124.076804) (xy 269.565098 -124.10526)
			(xy 269.607577 -124.139819) (xy 269.644958 -124.179838) (xy 269.661132 -124.201936) (xy 269.666697 -124.209194)
			(xy 269.681804 -124.219481) (xy 269.690596 -124.222002) (xy 269.720568 -124.229368) (xy 269.729521 -124.231096)
			(xy 269.747606 -124.228893) (xy 269.755874 -124.22505) (xy 269.780478 -124.212668) (xy 269.832003 -124.193198)
			(xy 269.885491 -124.180048) (xy 269.94017 -124.173407) (xy 269.96771 -124.17298) (xy 269.99525 -124.173417)
			(xy 270.04993 -124.180049) (xy 270.10342 -124.193194) (xy 270.154947 -124.21266) (xy 270.179546 -124.22505)
			(xy 270.187797 -124.22895) (xy 270.205901 -124.231152) (xy 270.214852 -124.229368) (xy 270.244824 -124.222002)
			(xy 270.253602 -124.21945) (xy 270.268704 -124.209173) (xy 270.274288 -124.201936) (xy 270.290471 -124.179843)
			(xy 270.32784 -124.13981) (xy 270.370314 -124.105239) (xy 270.4171 -124.076776) (xy 270.467327 -124.054951)
			(xy 270.520059 -124.040171) (xy 270.574312 -124.032711) (xy 270.601694 -124.032264) (xy 270.630346 -124.03269)
			(xy 270.687068 -124.040845) (xy 270.742052 -124.056989) (xy 270.794178 -124.080794) (xy 270.842387 -124.111774)
			(xy 270.885695 -124.149301) (xy 270.923222 -124.192609) (xy 270.954203 -124.240816) (xy 270.978009 -124.292943)
			(xy 270.994154 -124.347926) (xy 271.002309 -124.404648) (xy 271.002309 -124.461952) (xy 270.994154 -124.518674)
			(xy 270.978009 -124.573657) (xy 270.954203 -124.625784) (xy 270.923222 -124.673991) (xy 270.885695 -124.717299)
			(xy 270.842387 -124.754826) (xy 270.794178 -124.785806) (xy 270.742052 -124.809611) (xy 270.687068 -124.825755)
			(xy 270.630346 -124.83391) (xy 270.601694 -124.834396) (xy 270.586776 -124.834222) (xy 270.557027 -124.831936)
			(xy 270.542258 -124.829824) (xy 270.531082 -124.828046) (xy 270.51 -124.834142) (xy 270.443198 -124.8918)
			(xy 270.435231 -124.899392) (xy 270.426146 -124.919412) (xy 270.425672 -124.930408) (xy 270.425672 -125.195076)
			(xy 270.426144 -125.206069) (xy 270.435244 -125.22608) (xy 270.443198 -125.233684) (xy 270.51 -125.291342)
			(xy 270.531082 -125.297438) (xy 270.542258 -125.29566) (xy 270.557027 -125.293554) (xy 270.586776 -125.291264)
			(xy 270.601694 -125.291088) (xy 270.630341 -125.291666) (xy 270.687052 -125.299819) (xy 270.742025 -125.31596)
			(xy 270.794142 -125.33976) (xy 270.842341 -125.370735) (xy 270.885641 -125.408255) (xy 270.923161 -125.451554)
			(xy 270.954137 -125.499753) (xy 270.977938 -125.551869) (xy 270.99408 -125.606842) (xy 271.002233 -125.663553)
			(xy 271.002233 -125.720847) (xy 270.99408 -125.777558) (xy 270.977938 -125.832531) (xy 270.954137 -125.884647)
			(xy 270.923161 -125.932846) (xy 270.885641 -125.976145) (xy 270.842341 -126.013665) (xy 270.794142 -126.04464)
			(xy 270.742025 -126.06844) (xy 270.687052 -126.084581) (xy 270.630341 -126.092734) (xy 270.601694 -126.09322)
			(xy 270.574313 -126.09275) (xy 270.520064 -126.085282) (xy 270.467336 -126.0705) (xy 270.41711 -126.048678)
			(xy 270.370322 -126.020223) (xy 270.327842 -125.985665) (xy 270.290462 -125.945646) (xy 270.274288 -125.923548)
			(xy 270.268719 -125.916293) (xy 270.253615 -125.906005) (xy 270.244824 -125.903482) (xy 270.214852 -125.896116)
			(xy 270.205898 -125.8944) (xy 270.187814 -125.896595) (xy 270.179546 -125.900434) (xy 270.154938 -125.912807)
			(xy 270.103415 -125.93228) (xy 270.049928 -125.945433) (xy 269.99525 -125.952076) (xy 269.96771 -125.952504)
			(xy 269.940169 -125.952101) (xy 269.885487 -125.945459) (xy 269.831998 -125.932305) (xy 269.780472 -125.912829)
			(xy 269.755874 -125.900434) (xy 269.747619 -125.896544) (xy 269.729518 -125.894336) (xy 269.720568 -125.896116)
			(xy 269.690596 -125.903482) (xy 269.681811 -125.906016) (xy 269.666711 -125.916304) (xy 269.661132 -125.923548)
			(xy 269.644993 -125.945675) (xy 269.607617 -125.985708) (xy 269.565137 -126.020276) (xy 269.518343 -126.048735)
			(xy 269.468108 -126.070555) (xy 269.41537 -126.085327) (xy 269.36111 -126.092778) (xy 269.333726 -126.09322)
			(xy 269.305072 -126.092827) (xy 269.248345 -126.084674) (xy 269.193357 -126.068531) (xy 269.141226 -126.044727)
			(xy 269.093013 -126.013745) (xy 269.049701 -125.976218) (xy 269.01217 -125.932908) (xy 268.981186 -125.884697)
			(xy 268.957378 -125.832567) (xy 268.941231 -125.77758) (xy 268.933075 -125.720854) (xy 252.295406 -125.720854)
			(xy 252.295406 -125.73381) (xy 252.295757 -125.742828) (xy 252.302009 -125.759744) (xy 252.307598 -125.76683)
			(xy 252.307852 -125.76683) (xy 252.307852 -125.767084) (xy 252.325476 -125.788031) (xy 252.355203 -125.833995)
			(xy 252.378051 -125.883739) (xy 252.393549 -125.936239) (xy 252.40138 -125.990416) (xy 252.401382 -126.045156)
			(xy 252.393555 -126.099334) (xy 252.37806 -126.151835) (xy 252.355216 -126.201581) (xy 252.325492 -126.247548)
			(xy 252.307852 -126.26848) (xy 252.307598 -126.268734) (xy 252.302033 -126.275835) (xy 252.295773 -126.292741)
			(xy 252.295406 -126.301754) (xy 252.295406 -126.36881) (xy 252.295757 -126.377828) (xy 252.302009 -126.394744)
			(xy 252.307598 -126.40183) (xy 252.307852 -126.40183) (xy 252.307852 -126.402084) (xy 252.32549 -126.423017)
			(xy 252.355203 -126.468989) (xy 252.37804 -126.518736) (xy 252.393532 -126.571237) (xy 252.401359 -126.625413)
			(xy 252.401832 -126.652782) (xy 252.401346 -126.680033) (xy 252.39359 -126.733981) (xy 252.378235 -126.786276)
			(xy 252.355593 -126.835853) (xy 252.326127 -126.881703) (xy 252.290436 -126.922894) (xy 252.249245 -126.958585)
			(xy 252.203395 -126.988051) (xy 252.153818 -127.010693) (xy 252.101523 -127.026048) (xy 252.047575 -127.033804)
			(xy 251.993073 -127.033804) (xy 251.939125 -127.026048) (xy 251.88683 -127.010693) (xy 251.837253 -126.988051)
			(xy 251.791403 -126.958585) (xy 251.750212 -126.922894) (xy 251.714521 -126.881703) (xy 251.685055 -126.835853)
			(xy 251.662413 -126.786276) (xy 251.647058 -126.733981) (xy 251.639302 -126.680033) (xy 251.638816 -126.652782)
			(xy 251.347151 -126.652782) (xy 251.343904 -126.663845) (xy 251.321269 -126.713422) (xy 251.291809 -126.759274)
			(xy 251.256124 -126.800466) (xy 251.214939 -126.83616) (xy 251.169094 -126.86563) (xy 251.119521 -126.888275)
			(xy 251.067231 -126.903635) (xy 251.013286 -126.911396) (xy 250.986036 -126.911862) (xy 250.95972 -126.911449)
			(xy 250.907589 -126.904205) (xy 250.856944 -126.889876) (xy 250.808745 -126.868733) (xy 250.763903 -126.841177)
			(xy 250.723267 -126.807728) (xy 250.705112 -126.788672) (xy 250.697578 -126.781284) (xy 250.678308 -126.772749)
			(xy 250.667774 -126.772162) (xy 250.593098 -126.772162) (xy 250.582548 -126.772688) (xy 250.563254 -126.781227)
			(xy 250.55576 -126.788672) (xy 250.537611 -126.807735) (xy 250.496981 -126.841192) (xy 250.452139 -126.868751)
			(xy 250.403937 -126.889888) (xy 250.353288 -126.904204) (xy 250.301153 -126.911425) (xy 250.274836 -126.911862)
			(xy 250.247582 -126.911411) (xy 250.193628 -126.903658) (xy 250.141327 -126.888304) (xy 250.091744 -126.865662)
			(xy 250.045889 -126.836194) (xy 250.004694 -126.800499) (xy 249.969 -126.759303) (xy 249.939533 -126.713447)
			(xy 249.916892 -126.663863) (xy 249.90154 -126.611562) (xy 249.893788 -126.557608) (xy 249.893328 -126.530354)
			(xy 208.40954 -126.530354) (xy 208.40954 -126.727458) (xy 208.409225 -126.747831) (xy 208.403876 -126.788224)
			(xy 208.398872 -126.807976) (xy 208.398364 -126.810262) (xy 208.463388 -126.88951) (xy 208.471049 -126.89782)
			(xy 208.491472 -126.907442) (xy 208.502758 -126.908052) (xy 209.04962 -126.908052) (xy 209.082474 -126.908502)
			(xy 209.147768 -126.915867) (xy 209.211827 -126.930492) (xy 209.273849 -126.952193) (xy 209.333052 -126.980697)
			(xy 209.356504 -126.995428) (xy 240.873024 -126.995428) (xy 240.877095 -126.939806) (xy 240.889221 -126.885369)
			(xy 240.909144 -126.833278) (xy 240.93644 -126.784643) (xy 240.970526 -126.7405) (xy 241.010675 -126.701791)
			(xy 241.056033 -126.66934) (xy 241.105633 -126.643839) (xy 241.158417 -126.625832) (xy 241.21326 -126.615702)
			(xy 241.268994 -126.613665) (xy 241.324431 -126.619765) (xy 241.378388 -126.633871) (xy 241.429717 -126.655683)
			(xy 241.477323 -126.684737) (xy 241.520191 -126.720412) (xy 241.557408 -126.761949) (xy 241.588181 -126.808462)
			(xy 241.611853 -126.858959) (xy 241.627921 -126.912366) (xy 241.636041 -126.967542) (xy 241.63655 -126.995428)
			(xy 241.636041 -127.023314) (xy 241.631921 -127.051308) (xy 242.94414 -127.051308) (xy 242.948211 -126.995686)
			(xy 242.960337 -126.941249) (xy 242.98026 -126.889158) (xy 243.007556 -126.840523) (xy 243.041642 -126.79638)
			(xy 243.081791 -126.757671) (xy 243.127149 -126.72522) (xy 243.176749 -126.699719) (xy 243.229533 -126.681712)
			(xy 243.284376 -126.671582) (xy 243.34011 -126.669545) (xy 243.395547 -126.675645) (xy 243.449504 -126.689751)
			(xy 243.500833 -126.711563) (xy 243.548439 -126.740617) (xy 243.591307 -126.776292) (xy 243.628524 -126.817829)
			(xy 243.659297 -126.864342) (xy 243.682969 -126.914839) (xy 243.699037 -126.968246) (xy 243.706925 -127.021844)
			(xy 246.974104 -127.021844) (xy 246.978175 -126.966222) (xy 246.990301 -126.911785) (xy 247.010224 -126.859694)
			(xy 247.03752 -126.811059) (xy 247.071606 -126.766916) (xy 247.111755 -126.728207) (xy 247.157113 -126.695756)
			(xy 247.206713 -126.670255) (xy 247.259497 -126.652248) (xy 247.31434 -126.642118) (xy 247.370074 -126.640081)
			(xy 247.425511 -126.646181) (xy 247.479468 -126.660287) (xy 247.530797 -126.682099) (xy 247.578403 -126.711153)
			(xy 247.621271 -126.746828) (xy 247.658488 -126.788365) (xy 247.689261 -126.834878) (xy 247.712933 -126.885375)
			(xy 247.729001 -126.938782) (xy 247.737121 -126.993958) (xy 247.73763 -127.021844) (xy 247.737121 -127.04973)
			(xy 247.729001 -127.104906) (xy 247.712933 -127.158313) (xy 247.689261 -127.20881) (xy 247.658488 -127.255323)
			(xy 247.621271 -127.29686) (xy 247.578403 -127.332535) (xy 247.530797 -127.361589) (xy 247.479468 -127.383401)
			(xy 247.425511 -127.397507) (xy 247.370074 -127.403607) (xy 247.31434 -127.40157) (xy 247.259497 -127.39144)
			(xy 247.206713 -127.373433) (xy 247.157113 -127.347932) (xy 247.111755 -127.315481) (xy 247.071606 -127.276772)
			(xy 247.03752 -127.232629) (xy 247.010224 -127.183994) (xy 246.990301 -127.131903) (xy 246.978175 -127.077466)
			(xy 246.974104 -127.021844) (xy 243.706925 -127.021844) (xy 243.707157 -127.023422) (xy 243.707666 -127.051308)
			(xy 243.707157 -127.079194) (xy 243.699037 -127.13437) (xy 243.682969 -127.187777) (xy 243.659297 -127.238274)
			(xy 243.628524 -127.284787) (xy 243.591307 -127.326324) (xy 243.548439 -127.361999) (xy 243.500833 -127.391053)
			(xy 243.449504 -127.412865) (xy 243.395547 -127.426971) (xy 243.34011 -127.433071) (xy 243.284376 -127.431034)
			(xy 243.229533 -127.420904) (xy 243.176749 -127.402897) (xy 243.127149 -127.377396) (xy 243.081791 -127.344945)
			(xy 243.041642 -127.306236) (xy 243.007556 -127.262093) (xy 242.98026 -127.213458) (xy 242.960337 -127.161367)
			(xy 242.948211 -127.10693) (xy 242.94414 -127.051308) (xy 241.631921 -127.051308) (xy 241.627921 -127.07849)
			(xy 241.611853 -127.131897) (xy 241.588181 -127.182394) (xy 241.557408 -127.228907) (xy 241.520191 -127.270444)
			(xy 241.477323 -127.306119) (xy 241.429717 -127.335173) (xy 241.378388 -127.356985) (xy 241.324431 -127.371091)
			(xy 241.268994 -127.377191) (xy 241.21326 -127.375154) (xy 241.158417 -127.365024) (xy 241.105633 -127.347017)
			(xy 241.056033 -127.321516) (xy 241.010675 -127.289065) (xy 240.970526 -127.250356) (xy 240.93644 -127.206213)
			(xy 240.909144 -127.157578) (xy 240.889221 -127.105487) (xy 240.877095 -127.05105) (xy 240.873024 -126.995428)
			(xy 209.356504 -126.995428) (xy 209.388694 -127.015647) (xy 209.440077 -127.056603) (xy 209.46364 -127.079502)
			(xy 210.480656 -128.096518) (xy 210.488075 -128.103334) (xy 210.50666 -128.111067) (xy 210.516724 -128.111504)
			(xy 211.650326 -128.111504) (xy 211.684424 -128.112037) (xy 211.75216 -128.119957) (xy 211.818518 -128.135687)
			(xy 211.882601 -128.159014) (xy 211.943543 -128.189622) (xy 212.00052 -128.227099) (xy 212.031085 -128.252747)
			(xy 241.928428 -128.252747) (xy 241.928428 -128.198253) (xy 241.936184 -128.144312) (xy 241.951536 -128.092025)
			(xy 241.974174 -128.042454) (xy 242.003636 -127.99661) (xy 242.039323 -127.955426) (xy 242.080507 -127.919739)
			(xy 242.126351 -127.890276) (xy 242.175921 -127.867638) (xy 242.228208 -127.852284) (xy 242.282149 -127.844528)
			(xy 242.309396 -127.844042) (xy 242.336767 -127.8445) (xy 242.390946 -127.852318) (xy 242.44345 -127.867809)
			(xy 242.493197 -127.890652) (xy 242.539163 -127.920379) (xy 242.560094 -127.938022) (xy 242.560348 -127.938276)
			(xy 242.567439 -127.943856) (xy 242.584353 -127.950105) (xy 242.593368 -127.950468) (xy 242.660424 -127.950468)
			(xy 242.669443 -127.950129) (xy 242.68636 -127.94387) (xy 242.693444 -127.938276) (xy 242.693444 -127.938022)
			(xy 242.693698 -127.938022) (xy 242.714631 -127.920381) (xy 242.760599 -127.890657) (xy 242.810345 -127.867811)
			(xy 242.862847 -127.852315) (xy 242.917025 -127.844486) (xy 242.971767 -127.844486) (xy 243.025945 -127.852315)
			(xy 243.078447 -127.867811) (xy 243.128193 -127.890657) (xy 243.174161 -127.920381) (xy 243.195094 -127.938022)
			(xy 243.195348 -127.938276) (xy 243.202439 -127.943856) (xy 243.219353 -127.950105) (xy 243.228368 -127.950468)
			(xy 243.295424 -127.950468) (xy 243.304443 -127.950129) (xy 243.32136 -127.94387) (xy 243.328444 -127.938276)
			(xy 243.328444 -127.938022) (xy 243.328698 -127.938022) (xy 243.349623 -127.920374) (xy 243.395597 -127.890663)
			(xy 243.445347 -127.867828) (xy 243.497849 -127.852339) (xy 243.552026 -127.844514) (xy 243.579396 -127.844042)
			(xy 243.606653 -127.844405) (xy 243.660611 -127.852162) (xy 243.712916 -127.86752) (xy 243.762504 -127.890165)
			(xy 243.808363 -127.919637) (xy 243.849562 -127.955335) (xy 243.885261 -127.996534) (xy 243.914733 -128.042393)
			(xy 243.937379 -128.09198) (xy 243.952737 -128.144285) (xy 243.960495 -128.198243) (xy 243.960495 -128.220751)
			(xy 246.944601 -128.220751) (xy 246.944601 -128.166249) (xy 246.952358 -128.1123) (xy 246.967715 -128.060006)
			(xy 246.990358 -128.010429) (xy 247.019826 -127.964579) (xy 247.05552 -127.92339) (xy 247.096713 -127.887701)
			(xy 247.142565 -127.858237) (xy 247.192145 -127.8356) (xy 247.244442 -127.82025) (xy 247.29839 -127.812498)
			(xy 247.325642 -127.812038) (xy 247.353011 -127.812529) (xy 247.40719 -127.820339) (xy 247.459693 -127.835822)
			(xy 247.50944 -127.858659) (xy 247.555408 -127.888379) (xy 247.57634 -127.906018) (xy 247.576594 -127.906272)
			(xy 247.583672 -127.911871) (xy 247.600596 -127.918108) (xy 247.609614 -127.918464) (xy 247.67667 -127.918464)
			(xy 247.685686 -127.9181) (xy 247.702604 -127.911858) (xy 247.70969 -127.906272) (xy 247.70969 -127.906018)
			(xy 247.709944 -127.906018) (xy 247.730877 -127.888377) (xy 247.776845 -127.858653) (xy 247.826591 -127.835807)
			(xy 247.879093 -127.820311) (xy 247.933271 -127.812482) (xy 247.988013 -127.812482) (xy 248.042191 -127.820311)
			(xy 248.094693 -127.835807) (xy 248.144439 -127.858653) (xy 248.190407 -127.888377) (xy 248.21134 -127.906018)
			(xy 248.211594 -127.906272) (xy 248.218672 -127.911871) (xy 248.235596 -127.918108) (xy 248.244614 -127.918464)
			(xy 248.31167 -127.918464) (xy 248.320686 -127.9181) (xy 248.337604 -127.911858) (xy 248.34469 -127.906272)
			(xy 248.34469 -127.906018) (xy 248.344944 -127.906018) (xy 248.365889 -127.888394) (xy 248.411858 -127.85868)
			(xy 248.461602 -127.83584) (xy 248.5141 -127.820346) (xy 248.568274 -127.812514) (xy 248.595642 -127.812038)
			(xy 248.622895 -127.812435) (xy 248.676844 -127.820197) (xy 248.72914 -127.835558) (xy 248.778718 -127.858204)
			(xy 248.824569 -127.887675) (xy 248.865759 -127.923371) (xy 248.90145 -127.964565) (xy 248.930916 -128.010419)
			(xy 248.953557 -128.059999) (xy 248.968912 -128.112297) (xy 248.976668 -128.166247) (xy 248.976668 -128.220753)
			(xy 248.968912 -128.274703) (xy 248.953557 -128.327001) (xy 248.930916 -128.376581) (xy 248.90145 -128.422435)
			(xy 248.865759 -128.463629) (xy 248.824569 -128.499325) (xy 248.778718 -128.528796) (xy 248.72914 -128.551442)
			(xy 248.676844 -128.566803) (xy 248.622895 -128.574565) (xy 248.595642 -128.575054) (xy 248.568272 -128.574575)
			(xy 248.514093 -128.566762) (xy 248.46159 -128.551276) (xy 248.411843 -128.528437) (xy 248.365876 -128.498715)
			(xy 248.344944 -128.481074) (xy 248.34469 -128.48082) (xy 248.337617 -128.475214) (xy 248.32069 -128.468981)
			(xy 248.31167 -128.468628) (xy 248.244614 -128.468628) (xy 248.235597 -128.468986) (xy 248.21868 -128.475232)
			(xy 248.211594 -128.48082) (xy 248.21134 -128.481074) (xy 248.190407 -128.498715) (xy 248.144439 -128.528439)
			(xy 248.094693 -128.551285) (xy 248.042191 -128.566781) (xy 247.988013 -128.57461) (xy 247.933271 -128.57461)
			(xy 247.879093 -128.566781) (xy 247.826591 -128.551285) (xy 247.776845 -128.528439) (xy 247.730877 -128.498715)
			(xy 247.709944 -128.481074) (xy 247.70969 -128.48082) (xy 247.702617 -128.475214) (xy 247.68569 -128.468981)
			(xy 247.67667 -128.468628) (xy 247.609614 -128.468628) (xy 247.600597 -128.468986) (xy 247.58368 -128.475232)
			(xy 247.576594 -128.48082) (xy 247.576594 -128.481074) (xy 247.57634 -128.481074) (xy 247.5554 -128.498704)
			(xy 247.50943 -128.528418) (xy 247.459684 -128.551256) (xy 247.407185 -128.566749) (xy 247.353011 -128.574579)
			(xy 247.325642 -128.575054) (xy 247.29839 -128.574502) (xy 247.244441 -128.56675) (xy 247.192145 -128.5514)
			(xy 247.142565 -128.528763) (xy 247.096713 -128.499299) (xy 247.05552 -128.46361) (xy 247.019826 -128.422421)
			(xy 246.990358 -128.376571) (xy 246.967715 -128.326994) (xy 246.952358 -128.2747) (xy 246.944601 -128.220751)
			(xy 243.960495 -128.220751) (xy 243.960495 -128.252757) (xy 243.952737 -128.306715) (xy 243.937379 -128.35902)
			(xy 243.914733 -128.408607) (xy 243.885261 -128.454466) (xy 243.849562 -128.495665) (xy 243.808363 -128.531363)
			(xy 243.762504 -128.560835) (xy 243.712916 -128.58348) (xy 243.660611 -128.598838) (xy 243.606653 -128.606595)
			(xy 243.579396 -128.607058) (xy 243.552025 -128.606605) (xy 243.497845 -128.598785) (xy 243.445342 -128.583294)
			(xy 243.395595 -128.560449) (xy 243.349629 -128.530721) (xy 243.328698 -128.513078) (xy 243.328444 -128.512824)
			(xy 243.321355 -128.507241) (xy 243.30444 -128.500994) (xy 243.295424 -128.500632) (xy 243.228368 -128.500632)
			(xy 243.219349 -128.500967) (xy 243.202432 -128.507229) (xy 243.195348 -128.512824) (xy 243.195094 -128.513078)
			(xy 243.174161 -128.530719) (xy 243.128193 -128.560443) (xy 243.078447 -128.583289) (xy 243.025945 -128.598785)
			(xy 242.971767 -128.606614) (xy 242.917025 -128.606614) (xy 242.862847 -128.598785) (xy 242.810345 -128.583289)
			(xy 242.760599 -128.560443) (xy 242.714631 -128.530719) (xy 242.693698 -128.513078) (xy 242.693444 -128.512824)
			(xy 242.686355 -128.507241) (xy 242.66944 -128.500994) (xy 242.660424 -128.500632) (xy 242.593368 -128.500632)
			(xy 242.584349 -128.500967) (xy 242.567432 -128.507229) (xy 242.560348 -128.512824) (xy 242.560348 -128.513078)
			(xy 242.560094 -128.513078) (xy 242.539172 -128.53073) (xy 242.493197 -128.560441) (xy 242.443447 -128.583274)
			(xy 242.390944 -128.598762) (xy 242.336766 -128.606586) (xy 242.309396 -128.607058) (xy 242.282149 -128.606472)
			(xy 242.228208 -128.598716) (xy 242.175921 -128.583362) (xy 242.126351 -128.560724) (xy 242.080507 -128.531261)
			(xy 242.039323 -128.495574) (xy 242.003636 -128.45439) (xy 241.974174 -128.408546) (xy 241.951536 -128.358975)
			(xy 241.936184 -128.306688) (xy 241.928428 -128.252747) (xy 212.031085 -128.252747) (xy 212.052761 -128.270936)
			(xy 212.099559 -128.320542) (xy 212.140283 -128.375245) (xy 212.17438 -128.434306) (xy 212.201391 -128.496925)
			(xy 212.220949 -128.562258) (xy 212.232791 -128.629418) (xy 212.236757 -128.6975) (xy 212.232791 -128.765582)
			(xy 212.220949 -128.832742) (xy 212.201391 -128.898075) (xy 212.17438 -128.960694) (xy 212.140283 -129.019755)
			(xy 212.099559 -129.074458) (xy 212.052761 -129.124064) (xy 212.00052 -129.167901) (xy 211.943543 -129.205378)
			(xy 211.882601 -129.235986) (xy 211.818518 -129.259313) (xy 211.75216 -129.275043) (xy 211.684424 -129.282963)
			(xy 211.650326 -129.28346) (xy 210.253072 -129.28346) (xy 210.22019 -129.28305) (xy 210.15484 -129.275679)
			(xy 210.090728 -129.261033) (xy 210.02866 -129.239297) (xy 209.969418 -129.210743) (xy 209.913748 -129.175733)
			(xy 209.862351 -129.134705) (xy 209.838798 -129.111756) (xy 208.821782 -128.094486) (xy 208.814384 -128.087644)
			(xy 208.795783 -128.079926) (xy 208.785714 -128.0795) (xy 190.009526 -128.0795) (xy 189.999455 -128.079913)
			(xy 189.980856 -128.087639) (xy 189.973458 -128.094486) (xy 188.83884 -129.229358) (xy 188.819842 -129.24797)
			(xy 188.779009 -129.282056) (xy 188.757306 -129.29743) (xy 188.749054 -129.303628) (xy 188.738018 -129.321051)
			(xy 188.734714 -129.341408) (xy 188.736732 -129.351532) (xy 188.742185 -129.374515) (xy 188.748045 -129.421386)
			(xy 188.748416 -129.445004) (xy 189.96609 -129.445004) (xy 189.970161 -129.389382) (xy 189.982287 -129.334945)
			(xy 190.00221 -129.282854) (xy 190.029506 -129.234219) (xy 190.063592 -129.190076) (xy 190.103741 -129.151367)
			(xy 190.149099 -129.118916) (xy 190.198699 -129.093415) (xy 190.251483 -129.075408) (xy 190.306326 -129.065278)
			(xy 190.36206 -129.063241) (xy 190.417497 -129.069341) (xy 190.471454 -129.083447) (xy 190.522783 -129.105259)
			(xy 190.570389 -129.134313) (xy 190.613257 -129.169988) (xy 190.650474 -129.211525) (xy 190.681247 -129.258038)
			(xy 190.704919 -129.308535) (xy 190.720987 -129.361942) (xy 190.729107 -129.417118) (xy 190.729616 -129.445004)
			(xy 190.729107 -129.47289) (xy 190.720987 -129.528066) (xy 190.704919 -129.581473) (xy 190.681247 -129.63197)
			(xy 190.650474 -129.678483) (xy 190.613257 -129.72002) (xy 190.593392 -129.736552) (xy 196.597715 -129.736552)
			(xy 196.597715 -129.679248) (xy 196.605871 -129.622527) (xy 196.622016 -129.567545) (xy 196.645822 -129.515419)
			(xy 196.676805 -129.467213) (xy 196.714333 -129.423907) (xy 196.757642 -129.386383) (xy 196.805851 -129.355405)
			(xy 196.857978 -129.331603) (xy 196.912962 -129.315463) (xy 196.969684 -129.307312) (xy 196.998336 -129.306828)
			(xy 197.025716 -129.307298) (xy 197.079965 -129.314768) (xy 197.132692 -129.329553) (xy 197.182917 -129.351375)
			(xy 197.229705 -129.379829) (xy 197.272185 -129.414386) (xy 197.309567 -129.454403) (xy 197.325742 -129.4765)
			(xy 197.331291 -129.483773) (xy 197.34641 -129.49405) (xy 197.355206 -129.496566) (xy 197.385178 -129.503932)
			(xy 197.39413 -129.505669) (xy 197.412217 -129.503461) (xy 197.420484 -129.499614) (xy 197.445089 -129.487234)
			(xy 197.496613 -129.467762) (xy 197.550101 -129.454611) (xy 197.60478 -129.44797) (xy 197.63232 -129.447544)
			(xy 197.65986 -129.447981) (xy 197.71454 -129.454614) (xy 197.76803 -129.467758) (xy 197.819556 -129.487224)
			(xy 197.844156 -129.499614) (xy 197.852424 -129.50347) (xy 197.870513 -129.505698) (xy 197.879462 -129.503932)
			(xy 197.909434 -129.496566) (xy 197.918218 -129.494029) (xy 197.933317 -129.483742) (xy 197.938898 -129.4765)
			(xy 197.955064 -129.454394) (xy 197.992437 -129.414363) (xy 198.034914 -129.379795) (xy 198.081703 -129.351334)
			(xy 198.131933 -129.329511) (xy 198.184666 -129.314733) (xy 198.238921 -129.307274) (xy 198.266304 -129.306828)
			(xy 198.294952 -129.307351) (xy 198.351664 -129.315506) (xy 198.406638 -129.331648) (xy 198.458755 -129.35545)
			(xy 198.506955 -129.386426) (xy 198.550256 -129.423947) (xy 198.587776 -129.467248) (xy 198.618752 -129.515448)
			(xy 198.642553 -129.567566) (xy 198.658695 -129.62254) (xy 198.666849 -129.679252) (xy 198.666849 -129.736548)
			(xy 198.658695 -129.79326) (xy 198.642553 -129.848234) (xy 198.618752 -129.900352) (xy 198.587776 -129.948552)
			(xy 198.550256 -129.991853) (xy 198.506955 -130.029374) (xy 198.458755 -130.06035) (xy 198.406638 -130.084152)
			(xy 198.351664 -130.100294) (xy 198.294952 -130.108449) (xy 198.266304 -130.10896) (xy 198.251386 -130.108785)
			(xy 198.221637 -130.1065) (xy 198.206868 -130.104388) (xy 198.195692 -130.10261) (xy 198.17461 -130.108706)
			(xy 198.107554 -130.166364) (xy 198.099596 -130.173964) (xy 198.090508 -130.193979) (xy 198.090028 -130.204972)
			(xy 198.090028 -130.265349) (xy 266.291043 -130.265349) (xy 266.291043 -130.208051) (xy 266.299197 -130.151336)
			(xy 266.315341 -130.096358) (xy 266.339144 -130.044238) (xy 266.370123 -129.996036) (xy 266.407646 -129.952733)
			(xy 266.45095 -129.915212) (xy 266.499154 -129.884235) (xy 266.551275 -129.860434) (xy 266.606253 -129.844294)
			(xy 266.662969 -129.836141) (xy 266.691618 -129.835656) (xy 266.718998 -129.836127) (xy 266.773248 -129.843596)
			(xy 266.825975 -129.858379) (xy 266.876201 -129.880201) (xy 266.922989 -129.908655) (xy 266.965468 -129.943213)
			(xy 267.00285 -129.983231) (xy 267.019024 -130.005328) (xy 267.024594 -130.012583) (xy 267.039697 -130.022872)
			(xy 267.048488 -130.025394) (xy 267.07846 -130.03276) (xy 267.087413 -130.034485) (xy 267.105498 -130.032284)
			(xy 267.113766 -130.028442) (xy 267.138371 -130.016063) (xy 267.189895 -129.996592) (xy 267.243383 -129.983441)
			(xy 267.298062 -129.976799) (xy 267.325602 -129.976372) (xy 267.353142 -129.976813) (xy 267.407822 -129.983444)
			(xy 267.461312 -129.996587) (xy 267.512838 -130.016052) (xy 267.537438 -130.028442) (xy 267.54569 -130.032338)
			(xy 267.563793 -130.034542) (xy 267.572744 -130.03276) (xy 267.602716 -130.025394) (xy 267.611494 -130.022841)
			(xy 267.626596 -130.012565) (xy 267.63218 -130.005328) (xy 267.648304 -129.98319) (xy 267.685683 -129.943158)
			(xy 267.728167 -129.908592) (xy 267.774963 -129.880134) (xy 267.8252 -129.858317) (xy 267.87794 -129.843546)
			(xy 267.932201 -129.836097) (xy 267.959586 -129.835656) (xy 267.988238 -129.836098) (xy 268.04496 -129.844251)
			(xy 268.099943 -129.860394) (xy 268.15207 -129.884198) (xy 268.200278 -129.915178) (xy 268.243586 -129.952704)
			(xy 268.281114 -129.996011) (xy 268.312095 -130.044218) (xy 268.335901 -130.096344) (xy 268.352046 -130.151327)
			(xy 268.360201 -130.208048) (xy 268.360201 -130.265352) (xy 268.352046 -130.322073) (xy 268.335901 -130.377056)
			(xy 268.312095 -130.429182) (xy 268.281114 -130.477389) (xy 268.243586 -130.520696) (xy 268.200278 -130.558222)
			(xy 268.15207 -130.589202) (xy 268.099943 -130.613006) (xy 268.04496 -130.629149) (xy 267.988238 -130.637302)
			(xy 267.959586 -130.637788) (xy 267.944668 -130.637615) (xy 267.914919 -130.635329) (xy 267.90015 -130.633216)
			(xy 267.888974 -130.631438) (xy 267.867892 -130.637534) (xy 267.80109 -130.695192) (xy 267.793125 -130.702786)
			(xy 267.78404 -130.722805) (xy 267.783564 -130.7338) (xy 267.783564 -130.998468) (xy 267.784043 -131.00946)
			(xy 267.793138 -131.029471) (xy 267.80109 -131.037076) (xy 267.867892 -131.094734) (xy 267.888974 -131.10083)
			(xy 267.90015 -131.099052) (xy 267.91492 -131.096946) (xy 267.944668 -131.094656) (xy 267.959586 -131.09448)
			(xy 267.98824 -131.094874) (xy 268.044965 -131.103028) (xy 268.099952 -131.119172) (xy 268.152081 -131.142977)
			(xy 268.200292 -131.173959) (xy 268.243603 -131.211487) (xy 268.281133 -131.254796) (xy 268.312116 -131.303006)
			(xy 268.335923 -131.355135) (xy 268.352069 -131.410122) (xy 268.360225 -131.466846) (xy 268.360225 -131.524154)
			(xy 268.352069 -131.580878) (xy 268.335923 -131.635865) (xy 268.312116 -131.687994) (xy 268.281133 -131.736204)
			(xy 268.243603 -131.779513) (xy 268.200292 -131.817041) (xy 268.152081 -131.848023) (xy 268.099952 -131.871828)
			(xy 268.044965 -131.887972) (xy 267.98824 -131.896126) (xy 267.959586 -131.896612) (xy 267.932205 -131.896151)
			(xy 267.877955 -131.888682) (xy 267.825226 -131.873898) (xy 267.775001 -131.852075) (xy 267.728213 -131.823619)
			(xy 267.685733 -131.789059) (xy 267.648353 -131.749039) (xy 267.63218 -131.72694) (xy 267.626616 -131.719681)
			(xy 267.611508 -131.709395) (xy 267.602716 -131.706874) (xy 267.572744 -131.699508) (xy 267.56379 -131.697789)
			(xy 267.545706 -131.699987) (xy 267.537438 -131.703826) (xy 267.512831 -131.716201) (xy 267.461308 -131.735674)
			(xy 267.40782 -131.748826) (xy 267.353142 -131.755468) (xy 267.325602 -131.755896) (xy 267.298062 -131.755457)
			(xy 267.243382 -131.748826) (xy 267.189892 -131.735682) (xy 267.138365 -131.716216) (xy 267.113766 -131.703826)
			(xy 267.105513 -131.699932) (xy 267.087411 -131.697727) (xy 267.07846 -131.699508) (xy 267.048488 -131.706874)
			(xy 267.039703 -131.709407) (xy 267.024603 -131.719696) (xy 267.019024 -131.72694) (xy 267.002888 -131.749069)
			(xy 266.965512 -131.789103) (xy 266.923031 -131.823671) (xy 266.876236 -131.85213) (xy 266.826001 -131.873949)
			(xy 266.773262 -131.888721) (xy 266.719002 -131.896171) (xy 266.691618 -131.896612) (xy 266.66297 -131.896035)
			(xy 266.606258 -131.887883) (xy 266.551283 -131.871743) (xy 266.499165 -131.847944) (xy 266.450965 -131.816969)
			(xy 266.407663 -131.77945) (xy 266.370142 -131.73615) (xy 266.339165 -131.687951) (xy 266.315363 -131.635833)
			(xy 266.299221 -131.580859) (xy 266.291067 -131.524148) (xy 266.291067 -131.466852) (xy 266.299221 -131.410141)
			(xy 266.315363 -131.355167) (xy 266.339165 -131.303049) (xy 266.370142 -131.25485) (xy 266.407663 -131.21155)
			(xy 266.450965 -131.174031) (xy 266.499165 -131.143056) (xy 266.551283 -131.119257) (xy 266.606258 -131.103117)
			(xy 266.66297 -131.094965) (xy 266.691618 -131.09448) (xy 266.706536 -131.094652) (xy 266.736285 -131.096939)
			(xy 266.751054 -131.099052) (xy 266.76223 -131.10083) (xy 266.783312 -131.094734) (xy 266.850114 -131.037076)
			(xy 266.858094 -131.029495) (xy 266.867171 -131.009466) (xy 266.86764 -130.998468) (xy 266.86764 -130.7338)
			(xy 266.867122 -130.722813) (xy 266.858054 -130.702801) (xy 266.850114 -130.695192) (xy 266.783312 -130.637534)
			(xy 266.76223 -130.631438) (xy 266.751054 -130.633216) (xy 266.736284 -130.635321) (xy 266.706536 -130.637611)
			(xy 266.691618 -130.637788) (xy 266.662969 -130.637259) (xy 266.606253 -130.629106) (xy 266.551275 -130.612966)
			(xy 266.499154 -130.589165) (xy 266.45095 -130.558188) (xy 266.407646 -130.520667) (xy 266.370123 -130.477364)
			(xy 266.339144 -130.429162) (xy 266.315341 -130.377042) (xy 266.299197 -130.322064) (xy 266.291043 -130.265349)
			(xy 198.090028 -130.265349) (xy 198.090028 -130.46964) (xy 198.090503 -130.480633) (xy 198.099598 -130.500645)
			(xy 198.107554 -130.508248) (xy 198.17461 -130.565906) (xy 198.195692 -130.572002) (xy 198.206868 -130.570224)
			(xy 198.221637 -130.568116) (xy 198.251386 -130.565828) (xy 198.266304 -130.565652) (xy 198.294953 -130.566127)
			(xy 198.351669 -130.574282) (xy 198.406646 -130.590425) (xy 198.458767 -130.614228) (xy 198.50697 -130.645207)
			(xy 198.550273 -130.68273) (xy 198.587796 -130.726033) (xy 198.618773 -130.774236) (xy 198.642576 -130.826357)
			(xy 198.658719 -130.881335) (xy 198.666873 -130.938051) (xy 198.666873 -130.995349) (xy 198.658719 -131.052065)
			(xy 198.642576 -131.107043) (xy 198.618773 -131.159164) (xy 198.587796 -131.207367) (xy 198.550273 -131.25067)
			(xy 198.50697 -131.288193) (xy 198.458767 -131.319172) (xy 198.406646 -131.342975) (xy 198.351669 -131.359118)
			(xy 198.294953 -131.367273) (xy 198.266304 -131.367784) (xy 198.238925 -131.36728) (xy 198.184678 -131.359814)
			(xy 198.131952 -131.345036) (xy 198.081727 -131.323219) (xy 198.034939 -131.29477) (xy 197.992458 -131.260218)
			(xy 197.955074 -131.220207) (xy 197.938898 -131.198112) (xy 197.933333 -131.190854) (xy 197.918226 -131.180568)
			(xy 197.909434 -131.178046) (xy 197.879462 -131.17068) (xy 197.870515 -131.168911) (xy 197.852422 -131.17114)
			(xy 197.844156 -131.174998) (xy 197.819563 -131.187401) (xy 197.768034 -131.206867) (xy 197.714543 -131.220012)
			(xy 197.659861 -131.226645) (xy 197.63232 -131.227068) (xy 197.604779 -131.226654) (xy 197.550098 -131.220014)
			(xy 197.496609 -131.206863) (xy 197.445083 -131.187391) (xy 197.420484 -131.174998) (xy 197.412228 -131.171112)
			(xy 197.394128 -131.168903) (xy 197.385178 -131.17068) (xy 197.355206 -131.178046) (xy 197.346426 -131.180595)
			(xy 197.331324 -131.190873) (xy 197.325742 -131.198112) (xy 197.309616 -131.220249) (xy 197.272236 -131.260279)
			(xy 197.229752 -131.294844) (xy 197.182956 -131.323301) (xy 197.13272 -131.345118) (xy 197.079981 -131.359891)
			(xy 197.025721 -131.367342) (xy 196.998336 -131.367784) (xy 196.969686 -131.367264) (xy 196.912967 -131.359114)
			(xy 196.857987 -131.342974) (xy 196.805863 -131.319174) (xy 196.757656 -131.288198) (xy 196.71435 -131.250676)
			(xy 196.676824 -131.207372) (xy 196.645843 -131.159169) (xy 196.622038 -131.107047) (xy 196.605894 -131.052068)
			(xy 196.597739 -130.99535) (xy 196.597739 -130.93805) (xy 196.605894 -130.881332) (xy 196.622038 -130.826353)
			(xy 196.645843 -130.774231) (xy 196.676824 -130.726028) (xy 196.71435 -130.682724) (xy 196.757656 -130.645202)
			(xy 196.805863 -130.614226) (xy 196.857987 -130.590426) (xy 196.912967 -130.574286) (xy 196.969686 -130.566136)
			(xy 196.998336 -130.565652) (xy 197.013254 -130.565822) (xy 197.043003 -130.56811) (xy 197.057772 -130.570224)
			(xy 197.068948 -130.572002) (xy 197.09003 -130.565906) (xy 197.157086 -130.508248) (xy 197.165044 -130.500649)
			(xy 197.174131 -130.480633) (xy 197.174612 -130.46964) (xy 197.174612 -130.204972) (xy 197.174118 -130.193982)
			(xy 197.165034 -130.17397) (xy 197.157086 -130.166364) (xy 197.09003 -130.108706) (xy 197.068948 -130.10261)
			(xy 197.057772 -130.104388) (xy 197.043002 -130.106491) (xy 197.013254 -130.108783) (xy 196.998336 -130.10896)
			(xy 196.969684 -130.108488) (xy 196.912962 -130.100337) (xy 196.857978 -130.084197) (xy 196.805851 -130.060395)
			(xy 196.757642 -130.029417) (xy 196.714333 -129.991893) (xy 196.676805 -129.948587) (xy 196.645822 -129.900381)
			(xy 196.622016 -129.848255) (xy 196.605871 -129.793273) (xy 196.597715 -129.736552) (xy 190.593392 -129.736552)
			(xy 190.570389 -129.755695) (xy 190.522783 -129.784749) (xy 190.471454 -129.806561) (xy 190.417497 -129.820667)
			(xy 190.36206 -129.826767) (xy 190.306326 -129.82473) (xy 190.251483 -129.8146) (xy 190.198699 -129.796593)
			(xy 190.149099 -129.771092) (xy 190.103741 -129.738641) (xy 190.063592 -129.699932) (xy 190.029506 -129.655789)
			(xy 190.00221 -129.607154) (xy 189.982287 -129.555063) (xy 189.970161 -129.500626) (xy 189.96609 -129.445004)
			(xy 188.748416 -129.445004) (xy 188.747926 -129.472255) (xy 188.740169 -129.526202) (xy 188.724814 -129.578496)
			(xy 188.702173 -129.628073) (xy 188.672707 -129.673923) (xy 188.637016 -129.715113) (xy 188.595826 -129.750804)
			(xy 188.549977 -129.780271) (xy 188.5004 -129.802912) (xy 188.448106 -129.818268) (xy 188.394159 -129.826026)
			(xy 188.366908 -129.826512) (xy 188.339922 -129.825985) (xy 188.286486 -129.818392) (xy 188.234654 -129.803343)
			(xy 188.185461 -129.781137) (xy 188.13989 -129.752219) (xy 188.098849 -129.717166) (xy 188.06316 -129.676678)
			(xy 188.033534 -129.631563) (xy 188.010564 -129.582723) (xy 187.994707 -129.531132) (xy 187.986281 -129.477822)
			(xy 187.9854 -129.450846) (xy 187.98477 -129.440942) (xy 187.97698 -129.422711) (xy 187.962857 -129.408796)
			(xy 187.944513 -129.401278) (xy 187.9346 -129.400808) (xy 186.180222 -129.400808) (xy 186.170308 -129.401282)
			(xy 186.151959 -129.408796) (xy 186.137832 -129.422708) (xy 186.130039 -129.44094) (xy 186.129422 -129.450846)
			(xy 186.128476 -129.47911) (xy 186.119274 -129.534908) (xy 186.101937 -129.588736) (xy 186.076844 -129.639416)
			(xy 186.044546 -129.685836) (xy 186.005751 -129.726982) (xy 185.961307 -129.76195) (xy 185.912188 -129.789975)
			(xy 185.859471 -129.810444) (xy 185.80431 -129.822907) (xy 185.747914 -129.827092) (xy 185.691518 -129.822907)
			(xy 185.636357 -129.810444) (xy 185.58364 -129.789975) (xy 185.534521 -129.76195) (xy 185.490077 -129.726982)
			(xy 185.451282 -129.685836) (xy 185.418984 -129.639416) (xy 185.393891 -129.588736) (xy 185.376554 -129.534908)
			(xy 185.367352 -129.47911) (xy 185.366406 -129.450846) (xy 185.36577 -129.440942) (xy 185.357981 -129.422713)
			(xy 185.34386 -129.408799) (xy 185.325518 -129.401279) (xy 185.315606 -129.400808) (xy 184.60085 -129.400808)
			(xy 184.569286 -129.400389) (xy 184.506526 -129.393589) (xy 184.444862 -129.380073) (xy 184.385011 -129.359998)
			(xy 184.327668 -129.333598) (xy 184.300368 -129.31775) (xy 184.29213 -129.313336) (xy 184.273744 -129.310096)
			(xy 184.255418 -129.313663) (xy 184.247282 -129.318258) (xy 184.170828 -129.365756) (xy 184.163118 -129.371063)
			(xy 184.151808 -129.38595) (xy 184.146588 -129.403903) (xy 184.146952 -129.413254) (xy 184.148222 -129.445004)
			(xy 184.147726 -129.472255) (xy 184.139969 -129.526201) (xy 184.124614 -129.578495) (xy 184.101974 -129.628071)
			(xy 184.072508 -129.673921) (xy 184.036818 -129.715111) (xy 183.995629 -129.750802) (xy 183.94978 -129.780269)
			(xy 183.900204 -129.802911) (xy 183.847911 -129.818267) (xy 183.793965 -129.826025) (xy 183.766714 -129.826512)
			(xy 183.766206 -129.826512) (xy 183.749286 -129.826284) (xy 183.715581 -129.823236) (xy 183.698896 -129.820416)
			(xy 183.687604 -129.819081) (xy 183.665718 -129.825134) (xy 183.656732 -129.8321) (xy 183.632348 -129.853182)
			(xy 183.623931 -129.861109) (xy 183.614661 -129.882262) (xy 183.614568 -129.893822) (xy 183.615076 -129.913634)
			(xy 183.615076 -130.710432) (xy 185.541918 -130.710432) (xy 185.545989 -130.65481) (xy 185.558115 -130.600373)
			(xy 185.578038 -130.548282) (xy 185.605334 -130.499647) (xy 185.63942 -130.455504) (xy 185.679569 -130.416795)
			(xy 185.724927 -130.384344) (xy 185.774527 -130.358843) (xy 185.827311 -130.340836) (xy 185.882154 -130.330706)
			(xy 185.937888 -130.328669) (xy 185.993325 -130.334769) (xy 186.047282 -130.348875) (xy 186.098611 -130.370687)
			(xy 186.146217 -130.399741) (xy 186.189085 -130.435416) (xy 186.226302 -130.476953) (xy 186.257075 -130.523466)
			(xy 186.280747 -130.573963) (xy 186.296815 -130.62737) (xy 186.304935 -130.682546) (xy 186.305444 -130.710432)
			(xy 186.304935 -130.738318) (xy 186.296815 -130.793494) (xy 186.280747 -130.846901) (xy 186.257075 -130.897398)
			(xy 186.226302 -130.943911) (xy 186.189085 -130.985448) (xy 186.146217 -131.021123) (xy 186.098611 -131.050177)
			(xy 186.047282 -131.071989) (xy 185.993325 -131.086095) (xy 185.937888 -131.092195) (xy 185.882154 -131.090158)
			(xy 185.827311 -131.080028) (xy 185.774527 -131.062021) (xy 185.724927 -131.03652) (xy 185.679569 -131.004069)
			(xy 185.63942 -130.96536) (xy 185.605334 -130.921217) (xy 185.578038 -130.872582) (xy 185.558115 -130.820491)
			(xy 185.545989 -130.766054) (xy 185.541918 -130.710432) (xy 183.615076 -130.710432) (xy 183.615076 -130.777488)
			(xy 183.614568 -130.796284) (xy 183.614667 -130.807844) (xy 183.623928 -130.829002) (xy 183.632348 -130.836924)
			(xy 183.656732 -130.858006) (xy 183.665706 -130.865002) (xy 183.687602 -130.871073) (xy 183.698896 -130.86969)
			(xy 183.715579 -130.86685) (xy 183.749284 -130.863798) (xy 183.766206 -130.863594) (xy 183.766714 -130.863594)
			(xy 183.793965 -130.864077) (xy 183.847911 -130.871835) (xy 183.900205 -130.887191) (xy 183.94978 -130.909833)
			(xy 183.995629 -130.9393) (xy 184.036818 -130.974992) (xy 184.072508 -131.016182) (xy 184.101973 -131.062032)
			(xy 184.124614 -131.111609) (xy 184.139968 -131.163902) (xy 184.147724 -131.217849) (xy 184.147724 -131.245102)
			(xy 187.98489 -131.245102) (xy 187.988961 -131.18948) (xy 188.001087 -131.135043) (xy 188.02101 -131.082952)
			(xy 188.048306 -131.034317) (xy 188.082392 -130.990174) (xy 188.122541 -130.951465) (xy 188.167899 -130.919014)
			(xy 188.217499 -130.893513) (xy 188.270283 -130.875506) (xy 188.325126 -130.865376) (xy 188.38086 -130.863339)
			(xy 188.436297 -130.869439) (xy 188.490254 -130.883545) (xy 188.541583 -130.905357) (xy 188.589189 -130.934411)
			(xy 188.632057 -130.970086) (xy 188.669274 -131.011623) (xy 188.700047 -131.058136) (xy 188.723719 -131.108633)
			(xy 188.739787 -131.16204) (xy 188.747907 -131.217216) (xy 188.748416 -131.245102) (xy 189.96609 -131.245102)
			(xy 189.970161 -131.18948) (xy 189.982287 -131.135043) (xy 190.00221 -131.082952) (xy 190.029506 -131.034317)
			(xy 190.063592 -130.990174) (xy 190.103741 -130.951465) (xy 190.149099 -130.919014) (xy 190.198699 -130.893513)
			(xy 190.251483 -130.875506) (xy 190.306326 -130.865376) (xy 190.36206 -130.863339) (xy 190.417497 -130.869439)
			(xy 190.471454 -130.883545) (xy 190.522783 -130.905357) (xy 190.570389 -130.934411) (xy 190.613257 -130.970086)
			(xy 190.650474 -131.011623) (xy 190.681247 -131.058136) (xy 190.704919 -131.108633) (xy 190.720987 -131.16204)
			(xy 190.729107 -131.217216) (xy 190.729616 -131.245102) (xy 190.729107 -131.272988) (xy 190.720987 -131.328164)
			(xy 190.704919 -131.381571) (xy 190.681247 -131.432068) (xy 190.650474 -131.478581) (xy 190.613257 -131.520118)
			(xy 190.58548 -131.543234) (xy 199.240071 -131.543234) (xy 199.240071 -131.485966) (xy 199.248221 -131.429281)
			(xy 199.264357 -131.374332) (xy 199.288148 -131.32224) (xy 199.319112 -131.274064) (xy 199.356617 -131.230786)
			(xy 199.3999 -131.193286) (xy 199.448079 -131.162327) (xy 199.500174 -131.138541) (xy 199.555124 -131.122412)
			(xy 199.61181 -131.114268) (xy 199.640444 -131.113784) (xy 199.667814 -131.114268) (xy 199.722046 -131.121707)
			(xy 199.774762 -131.136454) (xy 199.824981 -131.158236) (xy 199.871771 -131.186646) (xy 199.914262 -131.221157)
			(xy 199.951662 -131.261128) (xy 199.96785 -131.283202) (xy 199.973395 -131.290478) (xy 199.988517 -131.300753)
			(xy 199.997314 -131.303268) (xy 200.027286 -131.310634) (xy 200.036237 -131.312375) (xy 200.054325 -131.310164)
			(xy 200.062592 -131.306316) (xy 200.087195 -131.293949) (xy 200.138731 -131.27455) (xy 200.192222 -131.261469)
			(xy 200.246895 -131.254895) (xy 200.274428 -131.2545) (xy 200.301962 -131.254888) (xy 200.356637 -131.261455)
			(xy 200.410127 -131.274539) (xy 200.46166 -131.293951) (xy 200.486264 -131.306316) (xy 200.49453 -131.310176)
			(xy 200.512621 -131.312402) (xy 200.52157 -131.310634) (xy 200.551542 -131.303268) (xy 200.560327 -131.300733)
			(xy 200.575425 -131.290445) (xy 200.581006 -131.283202) (xy 200.597174 -131.261112) (xy 200.63458 -131.221144)
			(xy 200.677075 -131.186634) (xy 200.723868 -131.158224) (xy 200.774089 -131.136442) (xy 200.826807 -131.121692)
			(xy 200.881041 -131.114249) (xy 200.908412 -131.113784) (xy 200.937041 -131.114303) (xy 200.993717 -131.122454)
			(xy 201.048656 -131.138587) (xy 201.100739 -131.162374) (xy 201.148908 -131.193331) (xy 201.19218 -131.230828)
			(xy 201.229676 -131.274102) (xy 201.260632 -131.322271) (xy 201.284418 -131.374356) (xy 201.300549 -131.429295)
			(xy 201.303117 -131.447157) (xy 241.913309 -131.447157) (xy 241.913309 -131.392643) (xy 241.921067 -131.338685)
			(xy 241.936426 -131.28638) (xy 241.959072 -131.236793) (xy 241.988544 -131.190934) (xy 242.024243 -131.149736)
			(xy 242.065442 -131.114038) (xy 242.111302 -131.084567) (xy 242.160889 -131.061922) (xy 242.213195 -131.046565)
			(xy 242.267153 -131.038808) (xy 242.29441 -131.038346) (xy 242.321781 -131.038795) (xy 242.375961 -131.046615)
			(xy 242.428465 -131.062108) (xy 242.478212 -131.084953) (xy 242.524177 -131.114682) (xy 242.545108 -131.132326)
			(xy 242.545362 -131.13258) (xy 242.552448 -131.138166) (xy 242.569366 -131.144411) (xy 242.578382 -131.144772)
			(xy 242.645438 -131.144772) (xy 242.654457 -131.144439) (xy 242.671375 -131.138175) (xy 242.678458 -131.13258)
			(xy 242.678458 -131.132326) (xy 242.678712 -131.132326) (xy 242.699645 -131.114685) (xy 242.745613 -131.084961)
			(xy 242.795359 -131.062115) (xy 242.847861 -131.046619) (xy 242.902039 -131.03879) (xy 242.956781 -131.03879)
			(xy 243.010959 -131.046619) (xy 243.063461 -131.062115) (xy 243.113207 -131.084961) (xy 243.159175 -131.114685)
			(xy 243.180108 -131.132326) (xy 243.180362 -131.13258) (xy 243.187448 -131.138166) (xy 243.204366 -131.144411)
			(xy 243.213382 -131.144772) (xy 243.280438 -131.144772) (xy 243.289457 -131.144439) (xy 243.306375 -131.138175)
			(xy 243.313458 -131.13258) (xy 243.313458 -131.132326) (xy 243.313712 -131.132326) (xy 243.33467 -131.114719)
			(xy 243.380635 -131.085001) (xy 243.430376 -131.062159) (xy 243.482871 -131.04666) (xy 243.537043 -131.038824)
			(xy 243.56441 -131.038346) (xy 243.591657 -131.038925) (xy 243.645598 -131.046682) (xy 243.697885 -131.062036)
			(xy 243.747455 -131.084675) (xy 243.793298 -131.114138) (xy 243.834482 -131.149825) (xy 243.870168 -131.19101)
			(xy 243.89963 -131.236854) (xy 243.922268 -131.286425) (xy 243.937621 -131.338712) (xy 243.937799 -131.339951)
			(xy 246.868944 -131.339951) (xy 246.868944 -131.285449) (xy 246.8767 -131.2315) (xy 246.892054 -131.179205)
			(xy 246.914693 -131.129627) (xy 246.944157 -131.083775) (xy 246.979847 -131.042582) (xy 247.021035 -131.006887)
			(xy 247.066883 -130.977417) (xy 247.116458 -130.954771) (xy 247.168752 -130.93941) (xy 247.222699 -130.931647)
			(xy 247.24995 -130.931158) (xy 247.27732 -130.931639) (xy 247.331499 -130.939451) (xy 247.384002 -130.954936)
			(xy 247.43375 -130.977775) (xy 247.479716 -131.007497) (xy 247.500648 -131.025138) (xy 247.500902 -131.025392)
			(xy 247.507984 -131.030985) (xy 247.524904 -131.037228) (xy 247.533922 -131.037584) (xy 247.600978 -131.037584)
			(xy 247.609994 -131.03722) (xy 247.626912 -131.030978) (xy 247.633998 -131.025392) (xy 247.633998 -131.025138)
			(xy 247.634252 -131.025138) (xy 247.655185 -131.007497) (xy 247.701153 -130.977773) (xy 247.750899 -130.954927)
			(xy 247.803401 -130.939431) (xy 247.857579 -130.931602) (xy 247.912321 -130.931602) (xy 247.966499 -130.939431)
			(xy 248.019001 -130.954927) (xy 248.068747 -130.977773) (xy 248.114715 -131.007497) (xy 248.135648 -131.025138)
			(xy 248.135902 -131.025392) (xy 248.142984 -131.030985) (xy 248.159904 -131.037228) (xy 248.168922 -131.037584)
			(xy 248.235978 -131.037584) (xy 248.244994 -131.03722) (xy 248.261912 -131.030978) (xy 248.268998 -131.025392)
			(xy 248.268998 -131.025138) (xy 248.269252 -131.025138) (xy 248.290196 -131.007514) (xy 248.336165 -130.977798)
			(xy 248.385909 -130.954959) (xy 248.438408 -130.939465) (xy 248.492582 -130.931633) (xy 248.51995 -130.931158)
			(xy 248.547203 -130.931686) (xy 248.601154 -130.939436) (xy 248.653453 -130.954787) (xy 248.703035 -130.977424)
			(xy 248.748891 -131.006888) (xy 248.790086 -131.042579) (xy 248.825782 -131.083769) (xy 248.855252 -131.129621)
			(xy 248.877896 -131.1792) (xy 248.893253 -131.231497) (xy 248.901011 -131.285447) (xy 248.901011 -131.339953)
			(xy 248.893253 -131.393903) (xy 248.877896 -131.4462) (xy 248.855252 -131.495779) (xy 248.825782 -131.541631)
			(xy 248.790086 -131.582821) (xy 248.748891 -131.618512) (xy 248.703035 -131.647976) (xy 248.653453 -131.670613)
			(xy 248.601154 -131.685964) (xy 248.547203 -131.693714) (xy 248.51995 -131.694174) (xy 248.492581 -131.693685)
			(xy 248.438402 -131.685874) (xy 248.385899 -131.67039) (xy 248.336152 -131.647554) (xy 248.290184 -131.617833)
			(xy 248.269252 -131.600194) (xy 248.268998 -131.59994) (xy 248.261921 -131.594339) (xy 248.244997 -131.588103)
			(xy 248.235978 -131.587748) (xy 248.168922 -131.587748) (xy 248.159905 -131.588105) (xy 248.142987 -131.594352)
			(xy 248.135902 -131.59994) (xy 248.135648 -131.600194) (xy 248.114715 -131.617835) (xy 248.068747 -131.647559)
			(xy 248.019001 -131.670405) (xy 247.966499 -131.685901) (xy 247.912321 -131.69373) (xy 247.857579 -131.69373)
			(xy 247.803401 -131.685901) (xy 247.750899 -131.670405) (xy 247.701153 -131.647559) (xy 247.655185 -131.617835)
			(xy 247.634252 -131.600194) (xy 247.633998 -131.59994) (xy 247.626921 -131.594339) (xy 247.609997 -131.588103)
			(xy 247.600978 -131.587748) (xy 247.533922 -131.587748) (xy 247.524905 -131.588105) (xy 247.507987 -131.594352)
			(xy 247.500902 -131.59994) (xy 247.500902 -131.600194) (xy 247.500648 -131.600194) (xy 247.479708 -131.617823)
			(xy 247.433737 -131.647537) (xy 247.383992 -131.670375) (xy 247.331493 -131.685868) (xy 247.277319 -131.693699)
			(xy 247.24995 -131.694174) (xy 247.222699 -131.693753) (xy 247.168752 -131.68599) (xy 247.116458 -131.670629)
			(xy 247.066883 -131.647983) (xy 247.021035 -131.618513) (xy 246.979847 -131.582818) (xy 246.944157 -131.541625)
			(xy 246.914693 -131.495773) (xy 246.892054 -131.446195) (xy 246.8767 -131.3939) (xy 246.868944 -131.339951)
			(xy 243.937799 -131.339951) (xy 243.945376 -131.392653) (xy 243.945376 -131.447147) (xy 243.937621 -131.501088)
			(xy 243.922268 -131.553375) (xy 243.89963 -131.602946) (xy 243.870168 -131.64879) (xy 243.834482 -131.689975)
			(xy 243.793298 -131.725662) (xy 243.747455 -131.755125) (xy 243.697885 -131.777764) (xy 243.645598 -131.793118)
			(xy 243.591657 -131.800875) (xy 243.56441 -131.801362) (xy 243.53704 -131.800899) (xy 243.48286 -131.793082)
			(xy 243.430356 -131.777593) (xy 243.38061 -131.75475) (xy 243.334643 -131.725024) (xy 243.313712 -131.707382)
			(xy 243.313458 -131.707128) (xy 243.306365 -131.701551) (xy 243.289453 -131.695301) (xy 243.280438 -131.694936)
			(xy 243.213382 -131.694936) (xy 243.204363 -131.695276) (xy 243.187446 -131.701535) (xy 243.180362 -131.707128)
			(xy 243.180108 -131.707382) (xy 243.159175 -131.725023) (xy 243.113207 -131.754747) (xy 243.063461 -131.777593)
			(xy 243.010959 -131.793089) (xy 242.956781 -131.800918) (xy 242.902039 -131.800918) (xy 242.847861 -131.793089)
			(xy 242.795359 -131.777593) (xy 242.745613 -131.754747) (xy 242.699645 -131.725023) (xy 242.678712 -131.707382)
			(xy 242.678458 -131.707128) (xy 242.671365 -131.701551) (xy 242.654453 -131.695301) (xy 242.645438 -131.694936)
			(xy 242.578382 -131.694936) (xy 242.569363 -131.695276) (xy 242.552446 -131.701535) (xy 242.545362 -131.707128)
			(xy 242.545362 -131.707382) (xy 242.545108 -131.707382) (xy 242.524181 -131.725028) (xy 242.478207 -131.754739)
			(xy 242.428459 -131.777574) (xy 242.375957 -131.793064) (xy 242.32178 -131.800889) (xy 242.29441 -131.801362)
			(xy 242.267153 -131.800992) (xy 242.213195 -131.793235) (xy 242.160889 -131.777878) (xy 242.111302 -131.755233)
			(xy 242.065442 -131.725762) (xy 242.024243 -131.690064) (xy 241.988544 -131.648866) (xy 241.959072 -131.603007)
			(xy 241.936426 -131.55342) (xy 241.921067 -131.501115) (xy 241.913309 -131.447157) (xy 201.303117 -131.447157)
			(xy 201.308698 -131.485971) (xy 201.308698 -131.543229) (xy 201.300549 -131.599905) (xy 201.284418 -131.654844)
			(xy 201.260632 -131.706929) (xy 201.229676 -131.755098) (xy 201.19218 -131.798372) (xy 201.148908 -131.835869)
			(xy 201.100739 -131.866826) (xy 201.048656 -131.890613) (xy 200.993717 -131.906746) (xy 200.937041 -131.914897)
			(xy 200.908412 -131.915408) (xy 200.893498 -131.915303) (xy 200.863749 -131.913139) (xy 200.848976 -131.91109)
			(xy 200.8378 -131.909312) (xy 200.816718 -131.915408) (xy 200.749662 -131.973066) (xy 200.741705 -131.980667)
			(xy 200.732616 -132.000681) (xy 200.732136 -132.011674) (xy 200.732136 -132.276342) (xy 200.732607 -132.287335)
			(xy 200.741705 -132.307348) (xy 200.749662 -132.31495) (xy 200.816718 -132.372608) (xy 200.8378 -132.378704)
			(xy 200.848976 -132.376926) (xy 200.863749 -132.374874) (xy 200.893498 -132.372715) (xy 200.908412 -132.372608)
			(xy 200.937043 -132.373079) (xy 200.993722 -132.38123) (xy 201.048664 -132.397364) (xy 201.100751 -132.421153)
			(xy 201.148922 -132.452112) (xy 201.192197 -132.489611) (xy 201.229695 -132.532887) (xy 201.260653 -132.58106)
			(xy 201.28444 -132.633147) (xy 201.300572 -132.68809) (xy 201.308721 -132.744769) (xy 201.308721 -132.802031)
			(xy 201.300572 -132.85871) (xy 201.28444 -132.913653) (xy 201.260653 -132.96574) (xy 201.229695 -133.013913)
			(xy 201.192197 -133.057189) (xy 201.148922 -133.094688) (xy 201.100751 -133.125647) (xy 201.048664 -133.149436)
			(xy 200.993722 -133.16557) (xy 200.937043 -133.173721) (xy 200.908412 -133.174232) (xy 200.881041 -133.173774)
			(xy 200.826808 -133.166329) (xy 200.774092 -133.151577) (xy 200.723873 -133.129792) (xy 200.677083 -133.101377)
			(xy 200.634594 -133.066863) (xy 200.597194 -133.02689) (xy 200.581006 -133.004814) (xy 200.575438 -132.997559)
			(xy 200.560333 -132.987271) (xy 200.551542 -132.984748) (xy 200.52157 -132.977382) (xy 200.512622 -132.975617)
			(xy 200.49453 -132.977843) (xy 200.486264 -132.9817) (xy 200.461648 -132.994039) (xy 200.410117 -133.013447)
			(xy 200.35663 -133.026536) (xy 200.30196 -133.033117) (xy 200.274428 -133.033516) (xy 200.246895 -133.033104)
			(xy 200.192221 -133.026544) (xy 200.138731 -133.013467) (xy 200.087197 -132.994062) (xy 200.062592 -132.9817)
			(xy 200.054334 -132.977818) (xy 200.036236 -132.975606) (xy 200.027286 -132.977382) (xy 199.997314 -132.984748)
			(xy 199.988535 -132.987299) (xy 199.973433 -132.997575) (xy 199.96785 -133.004814) (xy 199.951623 -133.026859)
			(xy 199.914229 -133.066833) (xy 199.871746 -133.101349) (xy 199.824964 -133.129765) (xy 199.77475 -133.151555)
			(xy 199.72204 -133.166313) (xy 199.667813 -133.173764) (xy 199.640444 -133.174232) (xy 199.611812 -133.173708)
			(xy 199.555129 -133.165564) (xy 199.500182 -133.149436) (xy 199.44809 -133.125652) (xy 199.399914 -133.094695)
			(xy 199.356634 -133.057197) (xy 199.319131 -133.013921) (xy 199.28817 -132.965748) (xy 199.264379 -132.913659)
			(xy 199.248245 -132.858714) (xy 199.240095 -132.802032) (xy 199.240095 -132.744768) (xy 199.248245 -132.688086)
			(xy 199.264379 -132.633141) (xy 199.28817 -132.581052) (xy 199.319131 -132.532879) (xy 199.356634 -132.489603)
			(xy 199.399914 -132.452105) (xy 199.44809 -132.421148) (xy 199.500182 -132.397364) (xy 199.555129 -132.381236)
			(xy 199.611812 -132.373092) (xy 199.640444 -132.372608) (xy 199.655358 -132.372718) (xy 199.685107 -132.374878)
			(xy 199.69988 -132.376926) (xy 199.711056 -132.378704) (xy 199.732138 -132.372608) (xy 199.799194 -132.31495)
			(xy 199.807137 -132.307336) (xy 199.816236 -132.287333) (xy 199.81672 -132.276342) (xy 199.81672 -132.011674)
			(xy 199.816222 -132.000684) (xy 199.807141 -131.980673) (xy 199.799194 -131.973066) (xy 199.732138 -131.915408)
			(xy 199.711056 -131.909312) (xy 199.69988 -131.91109) (xy 199.685107 -131.913136) (xy 199.655358 -131.915298)
			(xy 199.640444 -131.915408) (xy 199.61181 -131.914932) (xy 199.555124 -131.906788) (xy 199.500174 -131.890659)
			(xy 199.448079 -131.866873) (xy 199.3999 -131.835914) (xy 199.356617 -131.798414) (xy 199.319112 -131.755136)
			(xy 199.288148 -131.70696) (xy 199.264357 -131.654868) (xy 199.248221 -131.599919) (xy 199.240071 -131.543234)
			(xy 190.58548 -131.543234) (xy 190.570389 -131.555793) (xy 190.522783 -131.584847) (xy 190.471454 -131.606659)
			(xy 190.417497 -131.620765) (xy 190.36206 -131.626865) (xy 190.306326 -131.624828) (xy 190.251483 -131.614698)
			(xy 190.198699 -131.596691) (xy 190.149099 -131.57119) (xy 190.103741 -131.538739) (xy 190.063592 -131.50003)
			(xy 190.029506 -131.455887) (xy 190.00221 -131.407252) (xy 189.982287 -131.355161) (xy 189.970161 -131.300724)
			(xy 189.96609 -131.245102) (xy 188.748416 -131.245102) (xy 188.747907 -131.272988) (xy 188.739787 -131.328164)
			(xy 188.723719 -131.381571) (xy 188.700047 -131.432068) (xy 188.669274 -131.478581) (xy 188.632057 -131.520118)
			(xy 188.589189 -131.555793) (xy 188.541583 -131.584847) (xy 188.490254 -131.606659) (xy 188.436297 -131.620765)
			(xy 188.38086 -131.626865) (xy 188.325126 -131.624828) (xy 188.270283 -131.614698) (xy 188.217499 -131.596691)
			(xy 188.167899 -131.57119) (xy 188.122541 -131.538739) (xy 188.082392 -131.50003) (xy 188.048306 -131.455887)
			(xy 188.02101 -131.407252) (xy 188.001087 -131.355161) (xy 187.988961 -131.300724) (xy 187.98489 -131.245102)
			(xy 184.147724 -131.245102) (xy 184.147724 -131.272351) (xy 184.139968 -131.326298) (xy 184.124614 -131.378591)
			(xy 184.101973 -131.428168) (xy 184.072508 -131.474018) (xy 184.036818 -131.515208) (xy 183.995629 -131.5509)
			(xy 183.94978 -131.580367) (xy 183.900205 -131.603009) (xy 183.847911 -131.618365) (xy 183.793965 -131.626123)
			(xy 183.766714 -131.62661) (xy 183.739736 -131.626155) (xy 183.686315 -131.618575) (xy 183.634497 -131.603536)
			(xy 183.585318 -131.581339) (xy 183.539761 -131.552427) (xy 183.498738 -131.517379) (xy 183.463068 -131.476896)
			(xy 183.433465 -131.431786) (xy 183.41052 -131.382951) (xy 183.394692 -131.331369) (xy 183.390032 -131.304792)
			(xy 183.388254 -131.294124) (xy 183.377078 -131.276598) (xy 183.29656 -131.223258) (xy 183.275986 -131.219448)
			(xy 183.265826 -131.221988) (xy 183.265318 -131.221988) (xy 183.23875 -131.228113) (xy 183.184629 -131.234729)
			(xy 183.157368 -131.235196) (xy 183.133957 -131.234862) (xy 183.087383 -131.230031) (xy 183.064404 -131.225544)
			(xy 183.054244 -131.223512) (xy 183.034178 -131.227576) (xy 182.9562 -131.28117) (xy 182.945278 -131.298442)
			(xy 182.9435 -131.308856) (xy 182.938491 -131.336692) (xy 182.921685 -131.390696) (xy 182.897458 -131.441802)
			(xy 182.866289 -131.488996) (xy 182.828798 -131.531342) (xy 182.785728 -131.568) (xy 182.737933 -131.598241)
			(xy 182.686364 -131.621465) (xy 182.632042 -131.637213) (xy 182.576047 -131.64517) (xy 182.547768 -131.64566)
			(xy 182.51841 -131.645135) (xy 182.460323 -131.636565) (xy 182.404103 -131.619628) (xy 182.350949 -131.594684)
			(xy 182.301995 -131.562265) (xy 182.279798 -131.543044) (xy 182.272626 -131.53714) (xy 182.255297 -131.530495)
			(xy 182.246016 -131.53009) (xy 182.21452 -131.53009) (xy 182.20525 -131.530547) (xy 182.187932 -131.537181)
			(xy 182.180738 -131.543044) (xy 182.158541 -131.562267) (xy 182.109595 -131.594704) (xy 182.056442 -131.619657)
			(xy 182.000219 -131.636593) (xy 181.942127 -131.64515) (xy 181.912768 -131.64566) (xy 181.895732 -131.64554)
			(xy 181.861776 -131.642739) (xy 181.84495 -131.640072) (xy 181.833895 -131.638704) (xy 181.812415 -131.644505)
			(xy 181.803548 -131.651248) (xy 181.77891 -131.672076) (xy 181.770808 -131.679694) (xy 181.761444 -131.699834)
			(xy 181.760876 -131.710938) (xy 181.760876 -131.713478) (xy 181.760876 -131.713986) (xy 181.760876 -132.578856)
			(xy 181.761429 -132.589968) (xy 181.770776 -132.610128) (xy 181.77891 -132.617718) (xy 181.784071 -132.622036)
			(xy 185.522106 -132.622036) (xy 185.526177 -132.566414) (xy 185.538303 -132.511977) (xy 185.558226 -132.459886)
			(xy 185.585522 -132.411251) (xy 185.619608 -132.367108) (xy 185.659757 -132.328399) (xy 185.705115 -132.295948)
			(xy 185.754715 -132.270447) (xy 185.807499 -132.25244) (xy 185.862342 -132.24231) (xy 185.918076 -132.240273)
			(xy 185.973513 -132.246373) (xy 186.02747 -132.260479) (xy 186.078799 -132.282291) (xy 186.126405 -132.311345)
			(xy 186.169273 -132.34702) (xy 186.20649 -132.388557) (xy 186.237263 -132.43507) (xy 186.260935 -132.485567)
			(xy 186.277003 -132.538974) (xy 186.285123 -132.59415) (xy 186.285632 -132.622036) (xy 186.285123 -132.649922)
			(xy 186.277003 -132.705098) (xy 186.260935 -132.758505) (xy 186.237263 -132.809002) (xy 186.20649 -132.855515)
			(xy 186.169273 -132.897052) (xy 186.126405 -132.932727) (xy 186.078799 -132.961781) (xy 186.02747 -132.983593)
			(xy 185.973513 -132.997699) (xy 185.918076 -133.003799) (xy 185.862342 -133.001762) (xy 185.807499 -132.991632)
			(xy 185.754715 -132.973625) (xy 185.705115 -132.948124) (xy 185.659757 -132.915673) (xy 185.619608 -132.876964)
			(xy 185.585522 -132.832821) (xy 185.558226 -132.784186) (xy 185.538303 -132.732095) (xy 185.526177 -132.677658)
			(xy 185.522106 -132.622036) (xy 181.784071 -132.622036) (xy 181.803802 -132.638546) (xy 181.81269 -132.645248)
			(xy 181.834153 -132.651051) (xy 181.845204 -132.649722) (xy 181.861964 -132.647011) (xy 181.895792 -132.64409)
			(xy 181.912768 -132.64388) (xy 181.942136 -132.644438) (xy 182.000241 -132.653031) (xy 182.056471 -132.670009)
			(xy 182.109622 -132.695008) (xy 182.158558 -132.727493) (xy 182.180738 -132.74675) (xy 182.187899 -132.752669)
			(xy 182.205237 -132.759305) (xy 182.21452 -132.759704) (xy 182.246016 -132.759704) (xy 182.255288 -132.759265)
			(xy 182.272606 -132.752619) (xy 182.279798 -132.74675) (xy 182.301956 -132.727466) (xy 182.3509 -132.694985)
			(xy 182.404056 -132.669987) (xy 182.46029 -132.653008) (xy 182.518398 -132.644409) (xy 182.547768 -132.64388)
			(xy 182.5761 -132.644412) (xy 182.632198 -132.652397) (xy 182.686614 -132.668198) (xy 182.738264 -132.6915)
			(xy 182.786121 -132.72184) (xy 182.829231 -132.758613) (xy 182.866736 -132.801088) (xy 182.89789 -132.848418)
			(xy 182.922072 -132.899663) (xy 182.938801 -132.9538) (xy 182.943754 -132.9817) (xy 182.945278 -132.992114)
			(xy 182.956454 -133.009894) (xy 183.025542 -133.057392) (xy 183.034227 -133.06282) (xy 183.054287 -133.06687)
			(xy 183.064404 -133.065266) (xy 183.064658 -133.065266) (xy 183.087579 -133.060843) (xy 183.134025 -133.056133)
			(xy 183.157368 -133.055868) (xy 183.184679 -133.056191) (xy 183.238928 -133.06256) (xy 183.265572 -133.068568)
			(xy 183.275986 -133.071108) (xy 183.29656 -133.067552) (xy 183.376824 -133.014212) (xy 183.388254 -132.996432)
			(xy 183.389778 -132.985764) (xy 183.39442 -132.959155) (xy 183.410246 -132.907513) (xy 183.433198 -132.858619)
			(xy 183.462815 -132.81345) (xy 183.498506 -132.772909) (xy 183.539557 -132.737806) (xy 183.585148 -132.708844)
			(xy 183.634369 -132.6866) (xy 183.686234 -132.67152) (xy 183.739707 -132.663905) (xy 183.766714 -132.663438)
			(xy 183.793968 -132.663833) (xy 183.847921 -132.671592) (xy 183.90022 -132.68695) (xy 183.949801 -132.709595)
			(xy 183.995656 -132.739065) (xy 184.036849 -132.774761) (xy 184.072543 -132.815956) (xy 184.102012 -132.861811)
			(xy 184.124655 -132.911393) (xy 184.140011 -132.963693) (xy 184.147768 -133.017646) (xy 184.147768 -133.044946)
			(xy 189.96609 -133.044946) (xy 189.970161 -132.989324) (xy 189.982287 -132.934887) (xy 190.00221 -132.882796)
			(xy 190.029506 -132.834161) (xy 190.063592 -132.790018) (xy 190.103741 -132.751309) (xy 190.149099 -132.718858)
			(xy 190.198699 -132.693357) (xy 190.251483 -132.67535) (xy 190.306326 -132.66522) (xy 190.36206 -132.663183)
			(xy 190.417497 -132.669283) (xy 190.471454 -132.683389) (xy 190.522783 -132.705201) (xy 190.570389 -132.734255)
			(xy 190.613257 -132.76993) (xy 190.650474 -132.811467) (xy 190.681247 -132.85798) (xy 190.704919 -132.908477)
			(xy 190.720987 -132.961884) (xy 190.729107 -133.01706) (xy 190.729616 -133.044946) (xy 190.729107 -133.072832)
			(xy 190.720987 -133.128008) (xy 190.704919 -133.181415) (xy 190.681247 -133.231912) (xy 190.650474 -133.278425)
			(xy 190.613257 -133.319962) (xy 190.593082 -133.336752) (xy 196.597711 -133.336752) (xy 196.597711 -133.279448)
			(xy 196.605867 -133.222726) (xy 196.622012 -133.167743) (xy 196.645819 -133.115618) (xy 196.676801 -133.067411)
			(xy 196.71433 -133.024104) (xy 196.75764 -132.98658) (xy 196.805849 -132.955601) (xy 196.857977 -132.9318)
			(xy 196.912962 -132.915659) (xy 196.969684 -132.907508) (xy 196.998336 -132.907024) (xy 197.025716 -132.907495)
			(xy 197.079965 -132.914966) (xy 197.132692 -132.92975) (xy 197.182917 -132.951572) (xy 197.229705 -132.980026)
			(xy 197.272185 -133.014583) (xy 197.309567 -133.054599) (xy 197.325742 -133.076696) (xy 197.331291 -133.083968)
			(xy 197.34641 -133.094246) (xy 197.355206 -133.096762) (xy 197.385178 -133.104128) (xy 197.394129 -133.105866)
			(xy 197.412217 -133.103657) (xy 197.420484 -133.09981) (xy 197.445088 -133.087429) (xy 197.496613 -133.067958)
			(xy 197.550101 -133.054807) (xy 197.60478 -133.048166) (xy 197.63232 -133.04774) (xy 197.65986 -133.048177)
			(xy 197.71454 -133.05481) (xy 197.76803 -133.067955) (xy 197.819556 -133.08742) (xy 197.844156 -133.09981)
			(xy 197.852424 -133.103666) (xy 197.870513 -133.105894) (xy 197.879462 -133.104128) (xy 197.909434 -133.096762)
			(xy 197.918218 -133.094226) (xy 197.933317 -133.083939) (xy 197.938898 -133.076696) (xy 197.955063 -133.054589)
			(xy 197.992436 -133.014558) (xy 198.034914 -132.97999) (xy 198.081703 -132.95153) (xy 198.131932 -132.929707)
			(xy 198.184666 -132.914929) (xy 198.238921 -132.90747) (xy 198.266304 -132.907024) (xy 198.294951 -132.907555)
			(xy 198.351663 -132.91571) (xy 198.406637 -132.931852) (xy 198.458753 -132.955654) (xy 198.506953 -132.98663)
			(xy 198.550253 -133.02415) (xy 198.587773 -133.067451) (xy 198.618748 -133.11565) (xy 198.642549 -133.167767)
			(xy 198.658691 -133.222741) (xy 198.666845 -133.279453) (xy 198.666845 -133.336747) (xy 198.658691 -133.393459)
			(xy 198.642549 -133.448433) (xy 198.618748 -133.50055) (xy 198.587773 -133.548749) (xy 198.550253 -133.59205)
			(xy 198.506953 -133.62957) (xy 198.458753 -133.660546) (xy 198.406637 -133.684348) (xy 198.351663 -133.70049)
			(xy 198.294951 -133.708645) (xy 198.266304 -133.709156) (xy 198.251386 -133.708981) (xy 198.221637 -133.706696)
			(xy 198.206868 -133.704584) (xy 198.195692 -133.702806) (xy 198.17461 -133.708902) (xy 198.107554 -133.76656)
			(xy 198.099598 -133.774162) (xy 198.090509 -133.794175) (xy 198.090028 -133.805168) (xy 198.090028 -133.816344)
			(xy 237.527844 -133.816344) (xy 237.531915 -133.760722) (xy 237.544041 -133.706285) (xy 237.563964 -133.654194)
			(xy 237.59126 -133.605559) (xy 237.625346 -133.561416) (xy 237.665495 -133.522707) (xy 237.710853 -133.490256)
			(xy 237.760453 -133.464755) (xy 237.813237 -133.446748) (xy 237.86808 -133.436618) (xy 237.923814 -133.434581)
			(xy 237.979251 -133.440681) (xy 237.990898 -133.443726) (xy 243.322856 -133.443726) (xy 243.323323 -133.417412)
			(xy 243.330555 -133.365283) (xy 243.344873 -133.314639) (xy 243.366006 -133.26644) (xy 243.393553 -133.221596)
			(xy 243.426993 -133.180958) (xy 243.446046 -133.162802) (xy 243.453441 -133.155274) (xy 243.461971 -133.135999)
			(xy 243.462556 -133.125464) (xy 243.462556 -133.050788) (xy 243.46206 -133.040234) (xy 243.453503 -133.020938)
			(xy 243.446046 -133.01345) (xy 243.426963 -132.995322) (xy 243.39351 -132.954685) (xy 243.365956 -132.909839)
			(xy 243.344823 -132.861633) (xy 243.330511 -132.810981) (xy 243.323292 -132.758844) (xy 243.322856 -132.732526)
			(xy 243.323342 -132.705275) (xy 243.331098 -132.651327) (xy 243.346453 -132.599032) (xy 243.369095 -132.549455)
			(xy 243.398561 -132.503605) (xy 243.434252 -132.462414) (xy 243.475443 -132.426723) (xy 243.521293 -132.397257)
			(xy 243.57087 -132.374615) (xy 243.623165 -132.35926) (xy 243.677113 -132.351504) (xy 243.731615 -132.351504)
			(xy 243.785563 -132.35926) (xy 243.837858 -132.374615) (xy 243.887435 -132.397257) (xy 243.933285 -132.426723)
			(xy 243.974476 -132.462414) (xy 244.010167 -132.503605) (xy 244.039633 -132.549455) (xy 244.062275 -132.599032)
			(xy 244.07763 -132.651327) (xy 244.085386 -132.705275) (xy 244.085872 -132.732526) (xy 244.085431 -132.758841)
			(xy 244.078192 -132.810971) (xy 244.063868 -132.861615) (xy 244.042731 -132.909814) (xy 244.01518 -132.954656)
			(xy 243.981736 -132.995295) (xy 243.962682 -133.01345) (xy 243.955254 -133.020949) (xy 243.946745 -133.040246)
			(xy 243.946172 -133.050788) (xy 243.946172 -133.125464) (xy 243.946716 -133.136012) (xy 243.955242 -133.155307)
			(xy 243.962682 -133.162802) (xy 243.973601 -133.173216) (xy 247.117616 -133.173216) (xy 247.118088 -133.145846)
			(xy 247.125903 -133.091667) (xy 247.141391 -133.039164) (xy 247.164232 -132.989417) (xy 247.193955 -132.94345)
			(xy 247.211596 -132.922518) (xy 247.21185 -132.922264) (xy 247.217422 -132.915168) (xy 247.223676 -132.898258)
			(xy 247.224042 -132.889244) (xy 247.224042 -132.822188) (xy 247.223703 -132.813169) (xy 247.217444 -132.796252)
			(xy 247.21185 -132.789168) (xy 247.211596 -132.789168) (xy 247.211596 -132.788914) (xy 247.193949 -132.767988)
			(xy 247.164239 -132.722013) (xy 247.141404 -132.672264) (xy 247.125915 -132.619762) (xy 247.118089 -132.565586)
			(xy 247.117616 -132.538216) (xy 247.118102 -132.510965) (xy 247.125858 -132.457017) (xy 247.141213 -132.404722)
			(xy 247.163855 -132.355145) (xy 247.193321 -132.309295) (xy 247.229012 -132.268104) (xy 247.270203 -132.232413)
			(xy 247.316053 -132.202947) (xy 247.36563 -132.180305) (xy 247.417925 -132.16495) (xy 247.471873 -132.157194)
			(xy 247.526375 -132.157194) (xy 247.580323 -132.16495) (xy 247.632618 -132.180305) (xy 247.682195 -132.202947)
			(xy 247.728045 -132.232413) (xy 247.769236 -132.268104) (xy 247.804927 -132.309295) (xy 247.834393 -132.355145)
			(xy 247.857035 -132.404722) (xy 247.87239 -132.457017) (xy 247.880146 -132.510965) (xy 247.880632 -132.538216)
			(xy 247.880192 -132.565587) (xy 247.87237 -132.619768) (xy 247.856876 -132.672272) (xy 247.834028 -132.722019)
			(xy 247.804297 -132.767984) (xy 247.786652 -132.788914) (xy 247.786398 -132.789168) (xy 247.780818 -132.796259)
			(xy 247.774568 -132.813172) (xy 247.774206 -132.822188) (xy 247.774206 -132.889244) (xy 247.774589 -132.898258)
			(xy 247.780818 -132.915175) (xy 247.786398 -132.922264) (xy 247.786652 -132.922264) (xy 247.786652 -132.922518)
			(xy 247.804259 -132.943476) (xy 247.833977 -132.989441) (xy 247.85682 -133.039182) (xy 247.872318 -133.091677)
			(xy 247.880154 -133.145848) (xy 247.880632 -133.173216) (xy 247.880146 -133.200467) (xy 247.87239 -133.254415)
			(xy 247.857035 -133.30671) (xy 247.834393 -133.356287) (xy 247.804927 -133.402137) (xy 247.769236 -133.443328)
			(xy 247.728045 -133.479019) (xy 247.682195 -133.508485) (xy 247.632618 -133.531127) (xy 247.580323 -133.546482)
			(xy 247.526375 -133.554238) (xy 247.471873 -133.554238) (xy 247.417925 -133.546482) (xy 247.36563 -133.531127)
			(xy 247.316053 -133.508485) (xy 247.270203 -133.479019) (xy 247.229012 -133.443328) (xy 247.193321 -133.402137)
			(xy 247.163855 -133.356287) (xy 247.141213 -133.30671) (xy 247.125858 -133.254415) (xy 247.118102 -133.200467)
			(xy 247.117616 -133.173216) (xy 243.973601 -133.173216) (xy 243.981728 -133.180967) (xy 244.015187 -133.221594)
			(xy 244.042747 -133.266433) (xy 244.063888 -133.314631) (xy 244.078207 -133.365277) (xy 244.085433 -133.41741)
			(xy 244.085872 -133.443726) (xy 244.085386 -133.470977) (xy 244.07763 -133.524925) (xy 244.062275 -133.57722)
			(xy 244.039633 -133.626797) (xy 244.010167 -133.672647) (xy 243.974476 -133.713838) (xy 243.933285 -133.749529)
			(xy 243.887435 -133.778995) (xy 243.837858 -133.801637) (xy 243.785563 -133.816992) (xy 243.731615 -133.824748)
			(xy 243.677113 -133.824748) (xy 243.623165 -133.816992) (xy 243.57087 -133.801637) (xy 243.521293 -133.778995)
			(xy 243.475443 -133.749529) (xy 243.434252 -133.713838) (xy 243.398561 -133.672647) (xy 243.369095 -133.626797)
			(xy 243.346453 -133.57722) (xy 243.331098 -133.524925) (xy 243.323342 -133.470977) (xy 243.322856 -133.443726)
			(xy 237.990898 -133.443726) (xy 238.033208 -133.454787) (xy 238.084537 -133.476599) (xy 238.132143 -133.505653)
			(xy 238.175011 -133.541328) (xy 238.212228 -133.582865) (xy 238.243001 -133.629378) (xy 238.266673 -133.679875)
			(xy 238.282741 -133.733282) (xy 238.290861 -133.788458) (xy 238.29137 -133.816344) (xy 238.290861 -133.84423)
			(xy 238.282741 -133.899406) (xy 238.266673 -133.952813) (xy 238.243001 -134.00331) (xy 238.212228 -134.049823)
			(xy 238.175011 -134.09136) (xy 238.132143 -134.127035) (xy 238.084537 -134.156089) (xy 238.033208 -134.177901)
			(xy 237.979251 -134.192007) (xy 237.923814 -134.198107) (xy 237.86808 -134.19607) (xy 237.813237 -134.18594)
			(xy 237.760453 -134.167933) (xy 237.710853 -134.142432) (xy 237.665495 -134.109981) (xy 237.625346 -134.071272)
			(xy 237.59126 -134.027129) (xy 237.563964 -133.978494) (xy 237.544041 -133.926403) (xy 237.531915 -133.871966)
			(xy 237.527844 -133.816344) (xy 198.090028 -133.816344) (xy 198.090028 -134.069836) (xy 198.090505 -134.080829)
			(xy 198.099599 -134.100841) (xy 198.107554 -134.108444) (xy 198.17461 -134.166102) (xy 198.195692 -134.172198)
			(xy 198.206868 -134.17042) (xy 198.221637 -134.168313) (xy 198.251386 -134.166024) (xy 198.266304 -134.165848)
			(xy 198.294953 -134.166331) (xy 198.351668 -134.174486) (xy 198.406645 -134.190629) (xy 198.458765 -134.214432)
			(xy 198.506967 -134.24541) (xy 198.55027 -134.282933) (xy 198.587792 -134.326236) (xy 198.61877 -134.374438)
			(xy 198.642572 -134.426559) (xy 198.658715 -134.481536) (xy 198.666869 -134.538251) (xy 198.666869 -134.595549)
			(xy 198.658715 -134.652264) (xy 198.642572 -134.707241) (xy 198.61877 -134.759362) (xy 198.587792 -134.807564)
			(xy 198.55027 -134.850867) (xy 198.506967 -134.88839) (xy 198.458765 -134.919368) (xy 198.406645 -134.943171)
			(xy 198.351668 -134.959314) (xy 198.294953 -134.967469) (xy 198.266304 -134.96798) (xy 198.238925 -134.967477)
			(xy 198.184678 -134.960012) (xy 198.131951 -134.945233) (xy 198.081727 -134.923416) (xy 198.034938 -134.894967)
			(xy 197.992457 -134.860415) (xy 197.955074 -134.820403) (xy 197.938898 -134.798308) (xy 197.933334 -134.791049)
			(xy 197.918226 -134.780764) (xy 197.909434 -134.778242) (xy 197.879462 -134.770876) (xy 197.870515 -134.769107)
			(xy 197.852422 -134.771336) (xy 197.844156 -134.775194) (xy 197.819562 -134.787597) (xy 197.768034 -134.807063)
			(xy 197.714543 -134.820208) (xy 197.659861 -134.826841) (xy 197.63232 -134.827264) (xy 197.604779 -134.826851)
			(xy 197.550098 -134.82021) (xy 197.496609 -134.807059) (xy 197.445083 -134.787587) (xy 197.420484 -134.775194)
			(xy 197.412228 -134.771308) (xy 197.394128 -134.769099) (xy 197.385178 -134.770876) (xy 197.355206 -134.778242)
			(xy 197.346427 -134.780792) (xy 197.331325 -134.791069) (xy 197.325742 -134.798308) (xy 197.309615 -134.820444)
			(xy 197.272235 -134.860474) (xy 197.229751 -134.895039) (xy 197.182955 -134.923496) (xy 197.13272 -134.945314)
			(xy 197.07998 -134.960086) (xy 197.025721 -134.967538) (xy 196.998336 -134.96798) (xy 196.969685 -134.967468)
			(xy 196.912967 -134.959318) (xy 196.857985 -134.943178) (xy 196.805861 -134.919378) (xy 196.757654 -134.888401)
			(xy 196.714347 -134.850879) (xy 196.676821 -134.807575) (xy 196.64584 -134.759371) (xy 196.622035 -134.707248)
			(xy 196.60589 -134.652269) (xy 196.597735 -134.595551) (xy 196.597735 -134.538249) (xy 196.60589 -134.481531)
			(xy 196.622035 -134.426552) (xy 196.64584 -134.374429) (xy 196.676821 -134.326225) (xy 196.714347 -134.282921)
			(xy 196.757654 -134.245399) (xy 196.805861 -134.214422) (xy 196.857985 -134.190622) (xy 196.912967 -134.174482)
			(xy 196.969685 -134.166332) (xy 196.998336 -134.165848) (xy 197.013254 -134.166018) (xy 197.043003 -134.168306)
			(xy 197.057772 -134.17042) (xy 197.068948 -134.172198) (xy 197.09003 -134.166102) (xy 197.157086 -134.108444)
			(xy 197.165046 -134.100846) (xy 197.174132 -134.08083) (xy 197.174612 -134.069836) (xy 197.174612 -133.805168)
			(xy 197.17412 -133.794178) (xy 197.165035 -133.774166) (xy 197.157086 -133.76656) (xy 197.09003 -133.708902)
			(xy 197.068948 -133.702806) (xy 197.057772 -133.704584) (xy 197.043002 -133.706687) (xy 197.013254 -133.708979)
			(xy 196.998336 -133.709156) (xy 196.969684 -133.708692) (xy 196.912962 -133.700541) (xy 196.857977 -133.6844)
			(xy 196.805849 -133.660599) (xy 196.75764 -133.62962) (xy 196.71433 -133.592096) (xy 196.676801 -133.548789)
			(xy 196.645819 -133.500582) (xy 196.622012 -133.448457) (xy 196.605867 -133.393474) (xy 196.597711 -133.336752)
			(xy 190.593082 -133.336752) (xy 190.570389 -133.355637) (xy 190.522783 -133.384691) (xy 190.471454 -133.406503)
			(xy 190.417497 -133.420609) (xy 190.36206 -133.426709) (xy 190.306326 -133.424672) (xy 190.251483 -133.414542)
			(xy 190.198699 -133.396535) (xy 190.149099 -133.371034) (xy 190.103741 -133.338583) (xy 190.063592 -133.299874)
			(xy 190.029506 -133.255731) (xy 190.00221 -133.207096) (xy 189.982287 -133.155005) (xy 189.970161 -133.100568)
			(xy 189.96609 -133.044946) (xy 184.147768 -133.044946) (xy 184.147768 -133.072154) (xy 184.140011 -133.126107)
			(xy 184.124655 -133.178407) (xy 184.102012 -133.227989) (xy 184.072543 -133.273844) (xy 184.036849 -133.315039)
			(xy 183.995656 -133.350735) (xy 183.949801 -133.380205) (xy 183.90022 -133.40285) (xy 183.847921 -133.418208)
			(xy 183.793968 -133.425967) (xy 183.766714 -133.426454) (xy 183.766206 -133.426454) (xy 183.749286 -133.426226)
			(xy 183.715581 -133.423177) (xy 183.698896 -133.420358) (xy 183.687604 -133.419013) (xy 183.665716 -133.425071)
			(xy 183.656732 -133.432042) (xy 183.632348 -133.453124) (xy 183.62391 -133.461033) (xy 183.618816 -133.472682)
			(xy 187.71565 -133.472682) (xy 187.719721 -133.41706) (xy 187.731847 -133.362623) (xy 187.75177 -133.310532)
			(xy 187.779066 -133.261897) (xy 187.813152 -133.217754) (xy 187.853301 -133.179045) (xy 187.898659 -133.146594)
			(xy 187.948259 -133.121093) (xy 188.001043 -133.103086) (xy 188.055886 -133.092956) (xy 188.11162 -133.090919)
			(xy 188.167057 -133.097019) (xy 188.221014 -133.111125) (xy 188.272343 -133.132937) (xy 188.319949 -133.161991)
			(xy 188.362817 -133.197666) (xy 188.400034 -133.239203) (xy 188.430807 -133.285716) (xy 188.454479 -133.336213)
			(xy 188.470547 -133.38962) (xy 188.478667 -133.444796) (xy 188.479176 -133.472682) (xy 188.478667 -133.500568)
			(xy 188.470547 -133.555744) (xy 188.454479 -133.609151) (xy 188.430807 -133.659648) (xy 188.400034 -133.706161)
			(xy 188.362817 -133.747698) (xy 188.319949 -133.783373) (xy 188.272343 -133.812427) (xy 188.221014 -133.834239)
			(xy 188.167057 -133.848345) (xy 188.11162 -133.854445) (xy 188.055886 -133.852408) (xy 188.001043 -133.842278)
			(xy 187.948259 -133.824271) (xy 187.898659 -133.79877) (xy 187.853301 -133.766319) (xy 187.813152 -133.72761)
			(xy 187.779066 -133.683467) (xy 187.75177 -133.634832) (xy 187.731847 -133.582741) (xy 187.719721 -133.528304)
			(xy 187.71565 -133.472682) (xy 183.618816 -133.472682) (xy 183.614653 -133.4822) (xy 183.614568 -133.493764)
			(xy 183.615076 -133.513576) (xy 183.615076 -134.37743) (xy 183.614568 -134.396226) (xy 183.614596 -134.400544)
			(xy 185.685428 -134.400544) (xy 185.689499 -134.344922) (xy 185.701625 -134.290485) (xy 185.721548 -134.238394)
			(xy 185.748844 -134.189759) (xy 185.78293 -134.145616) (xy 185.823079 -134.106907) (xy 185.868437 -134.074456)
			(xy 185.918037 -134.048955) (xy 185.970821 -134.030948) (xy 186.025664 -134.020818) (xy 186.081398 -134.018781)
			(xy 186.136835 -134.024881) (xy 186.190792 -134.038987) (xy 186.242121 -134.060799) (xy 186.289727 -134.089853)
			(xy 186.332595 -134.125528) (xy 186.369812 -134.167065) (xy 186.400585 -134.213578) (xy 186.424257 -134.264075)
			(xy 186.440325 -134.317482) (xy 186.448445 -134.372658) (xy 186.448954 -134.400544) (xy 186.448445 -134.42843)
			(xy 186.440325 -134.483606) (xy 186.424257 -134.537013) (xy 186.400585 -134.58751) (xy 186.369812 -134.634023)
			(xy 186.332595 -134.67556) (xy 186.289727 -134.711235) (xy 186.242121 -134.740289) (xy 186.190792 -134.762101)
			(xy 186.136835 -134.776207) (xy 186.081398 -134.782307) (xy 186.025664 -134.78027) (xy 185.970821 -134.77014)
			(xy 185.918037 -134.752133) (xy 185.868437 -134.726632) (xy 185.823079 -134.694181) (xy 185.78293 -134.655472)
			(xy 185.748844 -134.611329) (xy 185.721548 -134.562694) (xy 185.701625 -134.510603) (xy 185.689499 -134.456166)
			(xy 185.685428 -134.400544) (xy 183.614596 -134.400544) (xy 183.614643 -134.407788) (xy 183.623921 -134.428947)
			(xy 183.632348 -134.436866) (xy 183.656732 -134.457948) (xy 183.665703 -134.464948) (xy 183.687601 -134.471015)
			(xy 183.698896 -134.469632) (xy 183.715579 -134.466792) (xy 183.749284 -134.46374) (xy 183.766206 -134.463536)
			(xy 183.766714 -134.463536) (xy 183.793968 -134.463935) (xy 183.84792 -134.471694) (xy 183.900219 -134.487052)
			(xy 183.9498 -134.509697) (xy 183.995654 -134.539167) (xy 184.036848 -134.574862) (xy 184.072542 -134.616057)
			(xy 184.10201 -134.661912) (xy 184.124653 -134.711494) (xy 184.140009 -134.763794) (xy 184.147766 -134.817746)
			(xy 184.147766 -134.845044) (xy 189.96609 -134.845044) (xy 189.970161 -134.789422) (xy 189.982287 -134.734985)
			(xy 190.00221 -134.682894) (xy 190.029506 -134.634259) (xy 190.063592 -134.590116) (xy 190.103741 -134.551407)
			(xy 190.149099 -134.518956) (xy 190.198699 -134.493455) (xy 190.251483 -134.475448) (xy 190.306326 -134.465318)
			(xy 190.36206 -134.463281) (xy 190.417497 -134.469381) (xy 190.471454 -134.483487) (xy 190.522783 -134.505299)
			(xy 190.570389 -134.534353) (xy 190.613257 -134.570028) (xy 190.650474 -134.611565) (xy 190.681247 -134.658078)
			(xy 190.704919 -134.708575) (xy 190.720987 -134.761982) (xy 190.729107 -134.817158) (xy 190.729616 -134.845044)
			(xy 190.729107 -134.87293) (xy 190.720987 -134.928106) (xy 190.704919 -134.981513) (xy 190.681247 -135.03201)
			(xy 190.650474 -135.078523) (xy 190.613257 -135.12006) (xy 190.570389 -135.155735) (xy 190.522783 -135.184789)
			(xy 190.471454 -135.206601) (xy 190.417497 -135.220707) (xy 190.36206 -135.226807) (xy 190.306326 -135.22477)
			(xy 190.251483 -135.21464) (xy 190.198699 -135.196633) (xy 190.149099 -135.171132) (xy 190.103741 -135.138681)
			(xy 190.063592 -135.099972) (xy 190.029506 -135.055829) (xy 190.00221 -135.007194) (xy 189.982287 -134.955103)
			(xy 189.970161 -134.900666) (xy 189.96609 -134.845044) (xy 184.147766 -134.845044) (xy 184.147766 -134.872254)
			(xy 184.140009 -134.926206) (xy 184.124653 -134.978506) (xy 184.10201 -135.028088) (xy 184.072542 -135.073943)
			(xy 184.036848 -135.115138) (xy 183.995654 -135.150833) (xy 183.9498 -135.180303) (xy 183.900219 -135.202948)
			(xy 183.84792 -135.218306) (xy 183.793968 -135.226065) (xy 183.766714 -135.226552) (xy 183.739737 -135.226062)
			(xy 183.686319 -135.218483) (xy 183.634504 -135.203446) (xy 183.585327 -135.181252) (xy 183.539772 -135.152344)
			(xy 183.498749 -135.1173) (xy 183.463079 -135.076821) (xy 183.433474 -135.031716) (xy 183.410526 -134.982887)
			(xy 183.394694 -134.931309) (xy 183.390032 -134.904734) (xy 183.388254 -134.894066) (xy 183.377078 -134.87654)
			(xy 183.29656 -134.8232) (xy 183.275986 -134.81939) (xy 183.265826 -134.82193) (xy 183.265318 -134.82193)
			(xy 183.23874 -134.827975) (xy 183.184621 -134.834473) (xy 183.157368 -134.834884) (xy 183.133962 -134.834617)
			(xy 183.087389 -134.829911) (xy 183.064404 -134.825486) (xy 183.054244 -134.823454) (xy 183.034178 -134.827518)
			(xy 182.9562 -134.881112) (xy 182.945278 -134.898384) (xy 182.9435 -134.908544) (xy 182.9435 -134.908798)
			(xy 182.938562 -134.936661) (xy 182.921787 -134.990704) (xy 182.897579 -135.041852) (xy 182.866419 -135.089086)
			(xy 182.828925 -135.131469) (xy 182.785844 -135.168158) (xy 182.738031 -135.198424) (xy 182.686437 -135.221664)
			(xy 182.632087 -135.237418) (xy 182.576062 -135.245372) (xy 182.547768 -135.245856) (xy 182.518398 -135.245353)
			(xy 182.46029 -135.236749) (xy 182.404059 -135.219759) (xy 182.350908 -135.194748) (xy 182.301975 -135.162249)
			(xy 182.279798 -135.142986) (xy 182.272623 -135.137087) (xy 182.255296 -135.130437) (xy 182.246016 -135.130032)
			(xy 182.21452 -135.130032) (xy 182.205249 -135.13048) (xy 182.187931 -135.137119) (xy 182.180738 -135.142986)
			(xy 182.158557 -135.162243) (xy 182.109621 -135.19473) (xy 182.05647 -135.219734) (xy 182.000241 -135.236719)
			(xy 181.942137 -135.245324) (xy 181.912768 -135.245856) (xy 181.895727 -135.245665) (xy 181.861772 -135.242743)
			(xy 181.84495 -135.240014) (xy 181.833895 -135.238636) (xy 181.812414 -135.244443) (xy 181.803548 -135.25119)
			(xy 181.77891 -135.272018) (xy 181.770789 -135.279619) (xy 181.761436 -135.299771) (xy 181.760876 -135.31088)
			(xy 181.760876 -135.31342) (xy 181.760876 -135.313928) (xy 181.760876 -135.320024) (xy 187.695584 -135.320024)
			(xy 187.699655 -135.264402) (xy 187.711781 -135.209965) (xy 187.731704 -135.157874) (xy 187.759 -135.109239)
			(xy 187.793086 -135.065096) (xy 187.833235 -135.026387) (xy 187.878593 -134.993936) (xy 187.928193 -134.968435)
			(xy 187.980977 -134.950428) (xy 188.03582 -134.940298) (xy 188.091554 -134.938261) (xy 188.146991 -134.944361)
			(xy 188.200948 -134.958467) (xy 188.252277 -134.980279) (xy 188.299883 -135.009333) (xy 188.342751 -135.045008)
			(xy 188.379968 -135.086545) (xy 188.410741 -135.133058) (xy 188.434413 -135.183555) (xy 188.450481 -135.236962)
			(xy 188.458601 -135.292138) (xy 188.45911 -135.320024) (xy 188.458601 -135.34791) (xy 188.450481 -135.403086)
			(xy 188.434413 -135.456493) (xy 188.410741 -135.50699) (xy 188.379968 -135.553503) (xy 188.342751 -135.59504)
			(xy 188.299883 -135.630715) (xy 188.252277 -135.659769) (xy 188.200948 -135.681581) (xy 188.146991 -135.695687)
			(xy 188.091554 -135.701787) (xy 188.03582 -135.69975) (xy 187.980977 -135.68962) (xy 187.928193 -135.671613)
			(xy 187.878593 -135.646112) (xy 187.833235 -135.613661) (xy 187.793086 -135.574952) (xy 187.759 -135.530809)
			(xy 187.731704 -135.482174) (xy 187.711781 -135.430083) (xy 187.699655 -135.375646) (xy 187.695584 -135.320024)
			(xy 181.760876 -135.320024) (xy 181.760876 -136.061958) (xy 185.644534 -136.061958) (xy 185.648605 -136.006336)
			(xy 185.660731 -135.951899) (xy 185.680654 -135.899808) (xy 185.70795 -135.851173) (xy 185.742036 -135.80703)
			(xy 185.782185 -135.768321) (xy 185.827543 -135.73587) (xy 185.877143 -135.710369) (xy 185.929927 -135.692362)
			(xy 185.98477 -135.682232) (xy 186.040504 -135.680195) (xy 186.095941 -135.686295) (xy 186.149898 -135.700401)
			(xy 186.201227 -135.722213) (xy 186.248833 -135.751267) (xy 186.291701 -135.786942) (xy 186.328918 -135.828479)
			(xy 186.359691 -135.874992) (xy 186.383363 -135.925489) (xy 186.399431 -135.978896) (xy 186.407551 -136.034072)
			(xy 186.40806 -136.061958) (xy 186.407551 -136.089844) (xy 186.399431 -136.14502) (xy 186.383363 -136.198427)
			(xy 186.359691 -136.248924) (xy 186.328918 -136.295437) (xy 186.291701 -136.336974) (xy 186.248833 -136.372649)
			(xy 186.201227 -136.401703) (xy 186.149898 -136.423515) (xy 186.095941 -136.437621) (xy 186.040504 -136.443721)
			(xy 185.98477 -136.441684) (xy 185.929927 -136.431554) (xy 185.877143 -136.413547) (xy 185.827543 -136.388046)
			(xy 185.782185 -136.355595) (xy 185.742036 -136.316886) (xy 185.70795 -136.272743) (xy 185.680654 -136.224108)
			(xy 185.660731 -136.172017) (xy 185.648605 -136.11758) (xy 185.644534 -136.061958) (xy 181.760876 -136.061958)
			(xy 181.760876 -136.178798) (xy 181.761405 -136.189913) (xy 181.770769 -136.210073) (xy 181.77891 -136.21766)
			(xy 181.804056 -136.238488) (xy 181.812873 -136.245174) (xy 181.834212 -136.250952) (xy 181.845204 -136.249664)
			(xy 181.861969 -136.247021) (xy 181.895796 -136.244223) (xy 181.912768 -136.244076) (xy 181.9414 -136.244584)
			(xy 181.998083 -136.25273) (xy 182.053029 -136.26886) (xy 182.105121 -136.292645) (xy 182.153297 -136.323603)
			(xy 182.196576 -136.361101) (xy 182.234078 -136.404378) (xy 182.265039 -136.452551) (xy 182.288829 -136.504641)
			(xy 182.304963 -136.559586) (xy 182.313113 -136.616268) (xy 182.313113 -136.645142) (xy 183.384696 -136.645142)
			(xy 183.388767 -136.58952) (xy 183.400893 -136.535083) (xy 183.420816 -136.482992) (xy 183.448112 -136.434357)
			(xy 183.482198 -136.390214) (xy 183.522347 -136.351505) (xy 183.567705 -136.319054) (xy 183.617305 -136.293553)
			(xy 183.670089 -136.275546) (xy 183.724932 -136.265416) (xy 183.780666 -136.263379) (xy 183.836103 -136.269479)
			(xy 183.89006 -136.283585) (xy 183.941389 -136.305397) (xy 183.988995 -136.334451) (xy 184.031863 -136.370126)
			(xy 184.06908 -136.411663) (xy 184.099853 -136.458176) (xy 184.123525 -136.508673) (xy 184.139593 -136.56208)
			(xy 184.147713 -136.617256) (xy 184.148222 -136.645142) (xy 187.08573 -136.645142) (xy 187.089801 -136.58952)
			(xy 187.101927 -136.535083) (xy 187.12185 -136.482992) (xy 187.149146 -136.434357) (xy 187.183232 -136.390214)
			(xy 187.223381 -136.351505) (xy 187.268739 -136.319054) (xy 187.318339 -136.293553) (xy 187.371123 -136.275546)
			(xy 187.425966 -136.265416) (xy 187.4817 -136.263379) (xy 187.537137 -136.269479) (xy 187.591094 -136.283585)
			(xy 187.642423 -136.305397) (xy 187.690029 -136.334451) (xy 187.732897 -136.370126) (xy 187.770114 -136.411663)
			(xy 187.800887 -136.458176) (xy 187.824559 -136.508673) (xy 187.840627 -136.56208) (xy 187.848747 -136.617256)
			(xy 187.849256 -136.645142) (xy 189.96609 -136.645142) (xy 189.970161 -136.58952) (xy 189.982287 -136.535083)
			(xy 190.00221 -136.482992) (xy 190.029506 -136.434357) (xy 190.063592 -136.390214) (xy 190.103741 -136.351505)
			(xy 190.149099 -136.319054) (xy 190.198699 -136.293553) (xy 190.251483 -136.275546) (xy 190.306326 -136.265416)
			(xy 190.36206 -136.263379) (xy 190.417497 -136.269479) (xy 190.471454 -136.283585) (xy 190.522783 -136.305397)
			(xy 190.570389 -136.334451) (xy 190.613257 -136.370126) (xy 190.641865 -136.402055) (xy 199.239783 -136.402055)
			(xy 199.239783 -136.344745) (xy 199.24794 -136.288019) (xy 199.264087 -136.233032) (xy 199.287895 -136.180902)
			(xy 199.318881 -136.132691) (xy 199.356413 -136.089382) (xy 199.399727 -136.051855) (xy 199.447941 -136.020874)
			(xy 199.500073 -135.997071) (xy 199.555062 -135.98093) (xy 199.611789 -135.97278) (xy 199.640444 -135.972296)
			(xy 199.655362 -135.972466) (xy 199.685111 -135.974754) (xy 199.69988 -135.976868) (xy 199.711056 -135.978646)
			(xy 199.732138 -135.97255) (xy 199.799194 -135.914892) (xy 199.807164 -135.907302) (xy 199.816247 -135.88728)
			(xy 199.81672 -135.876284) (xy 199.81672 -135.611616) (xy 199.8162 -135.600629) (xy 199.807134 -135.580617)
			(xy 199.799194 -135.573008) (xy 199.732138 -135.51535) (xy 199.711056 -135.509254) (xy 199.69988 -135.511032)
			(xy 199.685111 -135.513145) (xy 199.655362 -135.51543) (xy 199.640444 -135.515604) (xy 199.611795 -135.515044)
			(xy 199.555078 -135.506896) (xy 199.500099 -135.490758) (xy 199.447977 -135.466959) (xy 199.399772 -135.435985)
			(xy 199.356467 -135.398465) (xy 199.318942 -135.355163) (xy 199.287962 -135.306962) (xy 199.264158 -135.254842)
			(xy 199.248014 -135.199865) (xy 199.239859 -135.143149) (xy 199.239859 -135.085851) (xy 199.248014 -135.029135)
			(xy 199.264158 -134.974158) (xy 199.287962 -134.922038) (xy 199.318942 -134.873837) (xy 199.356467 -134.830535)
			(xy 199.399772 -134.793015) (xy 199.447977 -134.762041) (xy 199.500099 -134.738242) (xy 199.555079 -134.722104)
			(xy 199.611795 -134.713956) (xy 199.640444 -134.713472) (xy 199.667825 -134.713917) (xy 199.722076 -134.72139)
			(xy 199.774805 -134.736177) (xy 199.82503 -134.758003) (xy 199.871818 -134.786461) (xy 199.914297 -134.821023)
			(xy 199.951677 -134.861045) (xy 199.96785 -134.883144) (xy 199.973407 -134.890409) (xy 199.98852 -134.900692)
			(xy 199.997314 -134.90321) (xy 200.027286 -134.910576) (xy 200.036237 -134.912312) (xy 200.054325 -134.910103)
			(xy 200.062592 -134.906258) (xy 200.087193 -134.89387) (xy 200.138719 -134.874401) (xy 200.192208 -134.861253)
			(xy 200.246888 -134.854614) (xy 200.274428 -134.854188) (xy 200.301969 -134.854616) (xy 200.356649 -134.861251)
			(xy 200.410139 -134.874398) (xy 200.461665 -134.893867) (xy 200.486264 -134.906258) (xy 200.494531 -134.910117)
			(xy 200.512621 -134.912345) (xy 200.52157 -134.910576) (xy 200.551542 -134.90321) (xy 200.560333 -134.900694)
			(xy 200.57543 -134.890393) (xy 200.581006 -134.883144) (xy 200.597181 -134.861044) (xy 200.634551 -134.821011)
			(xy 200.677025 -134.786441) (xy 200.723813 -134.757978) (xy 200.774042 -134.736155) (xy 200.826775 -134.721376)
			(xy 200.88103 -134.713918) (xy 200.908412 -134.713472) (xy 200.937062 -134.713908) (xy 200.99378 -134.722064)
			(xy 201.048759 -134.738209) (xy 201.100881 -134.762014) (xy 201.125341 -134.777734) (xy 211.442554 -134.777734)
			(xy 211.44304 -134.750483) (xy 211.450796 -134.696535) (xy 211.466151 -134.64424) (xy 211.488793 -134.594663)
			(xy 211.518259 -134.548813) (xy 211.55395 -134.507622) (xy 211.595141 -134.471931) (xy 211.640991 -134.442465)
			(xy 211.690568 -134.419823) (xy 211.742863 -134.404468) (xy 211.796811 -134.396712) (xy 211.851313 -134.396712)
			(xy 211.905261 -134.404468) (xy 211.957556 -134.419823) (xy 212.007133 -134.442465) (xy 212.052983 -134.471931)
			(xy 212.094174 -134.507622) (xy 212.129865 -134.548813) (xy 212.159331 -134.594663) (xy 212.181973 -134.64424)
			(xy 212.197328 -134.696535) (xy 212.205084 -134.750483) (xy 212.20557 -134.777734) (xy 212.20557 -134.778242)
			(xy 212.205172 -134.802592) (xy 212.200546 -134.838557) (xy 228.099517 -134.838557) (xy 228.099517 -134.784043)
			(xy 228.107275 -134.730085) (xy 228.122634 -134.677781) (xy 228.14528 -134.628194) (xy 228.174753 -134.582336)
			(xy 228.210452 -134.541138) (xy 228.251652 -134.505441) (xy 228.297512 -134.47597) (xy 228.347099 -134.453327)
			(xy 228.399405 -134.437971) (xy 228.453363 -134.430216) (xy 228.48062 -134.429754) (xy 228.50859 -134.430208)
			(xy 228.56393 -134.438367) (xy 228.617486 -134.454524) (xy 228.668106 -134.47833) (xy 228.714706 -134.509276)
			(xy 228.756286 -134.546696) (xy 228.774498 -134.56793) (xy 228.781864 -134.57682) (xy 228.802184 -134.586472)
			(xy 228.903276 -134.586472) (xy 228.923596 -134.57682) (xy 228.930962 -134.568184) (xy 228.949176 -134.546996)
			(xy 228.990741 -134.509658) (xy 229.037307 -134.478782) (xy 229.087879 -134.455027) (xy 229.141374 -134.438902)
			(xy 229.19665 -134.430751) (xy 229.224586 -134.430262) (xy 229.251837 -134.430784) (xy 229.305786 -134.438539)
			(xy 229.358081 -134.453893) (xy 229.407659 -134.476533) (xy 229.45351 -134.505998) (xy 229.494701 -134.541689)
			(xy 229.530394 -134.582879) (xy 229.559861 -134.628729) (xy 229.582502 -134.678306) (xy 229.597858 -134.730601)
			(xy 229.605615 -134.784549) (xy 229.605615 -134.839051) (xy 229.597858 -134.892999) (xy 229.582502 -134.945294)
			(xy 229.559861 -134.994871) (xy 229.530394 -135.040721) (xy 229.494701 -135.081911) (xy 229.45351 -135.117602)
			(xy 229.407659 -135.147067) (xy 229.358081 -135.169707) (xy 229.305786 -135.185061) (xy 229.251837 -135.192816)
			(xy 229.224586 -135.193278) (xy 229.196617 -135.192809) (xy 229.141277 -135.184651) (xy 229.087723 -135.168496)
			(xy 229.037103 -135.144693) (xy 228.990502 -135.113751) (xy 228.948921 -135.076334) (xy 228.930708 -135.055102)
			(xy 228.923342 -135.046212) (xy 228.903022 -135.03656) (xy 228.80193 -135.03656) (xy 228.78161 -135.046212)
			(xy 228.774244 -135.054848) (xy 228.756011 -135.07602) (xy 228.714452 -135.113361) (xy 228.66789 -135.144242)
			(xy 228.617322 -135.168) (xy 228.563829 -135.184128) (xy 228.508556 -135.192281) (xy 228.48062 -135.19277)
			(xy 228.453363 -135.192384) (xy 228.399405 -135.184629) (xy 228.347099 -135.169273) (xy 228.297512 -135.14663)
			(xy 228.251652 -135.117159) (xy 228.210452 -135.081462) (xy 228.174753 -135.040264) (xy 228.14528 -134.994406)
			(xy 228.122634 -134.944819) (xy 228.107275 -134.892515) (xy 228.099517 -134.838557) (xy 212.200546 -134.838557)
			(xy 212.198959 -134.850895) (xy 212.186639 -134.898011) (xy 212.177884 -134.920736) (xy 212.174281 -134.931001)
			(xy 212.175213 -134.952717) (xy 212.179662 -134.962646) (xy 212.218778 -135.040624) (xy 212.235542 -135.05434)
			(xy 212.24621 -135.057134) (xy 212.273069 -135.064681) (xy 212.324428 -135.086463) (xy 212.372067 -135.115494)
			(xy 212.414969 -135.151154) (xy 212.45222 -135.192682) (xy 212.483025 -135.239194) (xy 212.506726 -135.289696)
			(xy 212.522819 -135.343112) (xy 212.53096 -135.398302) (xy 212.531452 -135.426196) (xy 212.530963 -135.45277)
			(xy 212.523598 -135.505406) (xy 212.508997 -135.556509) (xy 212.487443 -135.60509) (xy 212.459352 -135.650208)
			(xy 212.451484 -135.659622) (xy 224.644456 -135.659622) (xy 224.648527 -135.604) (xy 224.660653 -135.549563)
			(xy 224.680576 -135.497472) (xy 224.707872 -135.448837) (xy 224.741958 -135.404694) (xy 224.782107 -135.365985)
			(xy 224.827465 -135.333534) (xy 224.877065 -135.308033) (xy 224.929849 -135.290026) (xy 224.984692 -135.279896)
			(xy 225.040426 -135.277859) (xy 225.095863 -135.283959) (xy 225.14982 -135.298065) (xy 225.201149 -135.319877)
			(xy 225.248755 -135.348931) (xy 225.291623 -135.384606) (xy 225.32884 -135.426143) (xy 225.359613 -135.472656)
			(xy 225.383285 -135.523153) (xy 225.399353 -135.57656) (xy 225.407473 -135.631736) (xy 225.407982 -135.659622)
			(xy 227.311456 -135.659622) (xy 227.315527 -135.604) (xy 227.327653 -135.549563) (xy 227.347576 -135.497472)
			(xy 227.374872 -135.448837) (xy 227.408958 -135.404694) (xy 227.449107 -135.365985) (xy 227.494465 -135.333534)
			(xy 227.544065 -135.308033) (xy 227.596849 -135.290026) (xy 227.651692 -135.279896) (xy 227.707426 -135.277859)
			(xy 227.762863 -135.283959) (xy 227.81682 -135.298065) (xy 227.868149 -135.319877) (xy 227.915755 -135.348931)
			(xy 227.958623 -135.384606) (xy 227.99584 -135.426143) (xy 228.026613 -135.472656) (xy 228.050285 -135.523153)
			(xy 228.066353 -135.57656) (xy 228.074473 -135.631736) (xy 228.074982 -135.659622) (xy 228.074485 -135.686848)
			(xy 229.0905 -135.686848) (xy 229.0905 -135.632352) (xy 229.098256 -135.578409) (xy 229.113608 -135.52612)
			(xy 229.136246 -135.476547) (xy 229.165708 -135.430701) (xy 229.201395 -135.389514) (xy 229.24258 -135.353824)
			(xy 229.288424 -135.324359) (xy 229.337995 -135.301718) (xy 229.390284 -135.286361) (xy 229.444226 -135.278602)
			(xy 229.471474 -135.278114) (xy 229.499863 -135.278653) (xy 229.556017 -135.287059) (xy 229.610306 -135.303688)
			(xy 229.661533 -135.328175) (xy 229.685342 -135.343646) (xy 229.693244 -135.348463) (xy 229.711227 -135.352754)
			(xy 229.729568 -135.350421) (xy 229.73792 -135.34644) (xy 229.817168 -135.304276) (xy 229.825107 -135.299665)
			(xy 229.837248 -135.285913) (xy 229.843717 -135.268746) (xy 229.844092 -135.259572) (xy 229.844092 -134.607808)
			(xy 229.844497 -134.597736) (xy 229.852229 -134.579137) (xy 229.859078 -134.57174) (xy 230.228394 -134.20217)
			(xy 230.235798 -134.195336) (xy 230.254394 -134.187613) (xy 230.264462 -134.187184) (xy 234.89158 -134.187184)
			(xy 234.901651 -134.187597) (xy 234.92025 -134.195324) (xy 234.927648 -134.20217) (xy 235.333794 -134.608316)
			(xy 235.340633 -134.615717) (xy 235.348353 -134.634316) (xy 235.34878 -134.644384) (xy 235.34878 -134.900416)
			(xy 238.33455 -134.900416) (xy 238.335006 -134.873132) (xy 238.342791 -134.819121) (xy 238.358192 -134.76677)
			(xy 238.380893 -134.717147) (xy 238.410432 -134.671264) (xy 238.446206 -134.630057) (xy 238.487485 -134.594367)
			(xy 238.533428 -134.564921) (xy 238.55807 -134.553198) (xy 238.570602 -134.547017) (xy 238.592008 -134.529078)
			(xy 238.607746 -134.506006) (xy 238.616637 -134.47953) (xy 238.618014 -134.451635) (xy 238.611774 -134.424412)
			(xy 238.598385 -134.399901) (xy 238.57885 -134.379941) (xy 238.56696 -134.372604) (xy 238.542552 -134.35783)
			(xy 238.497962 -134.322243) (xy 238.459171 -134.28041) (xy 238.427045 -134.233265) (xy 238.402302 -134.18186)
			(xy 238.385492 -134.127343) (xy 238.376993 -134.070929) (xy 238.37646 -134.042404) (xy 238.376946 -134.015153)
			(xy 238.384702 -133.961205) (xy 238.400057 -133.90891) (xy 238.422699 -133.859333) (xy 238.452165 -133.813483)
			(xy 238.487856 -133.772292) (xy 238.529047 -133.736601) (xy 238.574897 -133.707135) (xy 238.624474 -133.684493)
			(xy 238.676769 -133.669138) (xy 238.730717 -133.661382) (xy 238.785219 -133.661382) (xy 238.839167 -133.669138)
			(xy 238.891462 -133.684493) (xy 238.941039 -133.707135) (xy 238.986889 -133.736601) (xy 239.02808 -133.772292)
			(xy 239.063771 -133.813483) (xy 239.093237 -133.859333) (xy 239.115879 -133.90891) (xy 239.131234 -133.961205)
			(xy 239.13899 -134.015153) (xy 239.139476 -134.042404) (xy 239.139022 -134.069688) (xy 239.131234 -134.123698)
			(xy 239.115832 -134.176049) (xy 239.09313 -134.225671) (xy 239.063591 -134.271553) (xy 239.027818 -134.31276)
			(xy 238.986539 -134.348451) (xy 238.940597 -134.377898) (xy 238.915956 -134.389622) (xy 238.903412 -134.395773)
			(xy 238.882017 -134.413724) (xy 238.866289 -134.436802) (xy 238.857406 -134.463279) (xy 238.856032 -134.491173)
			(xy 238.86227 -134.518395) (xy 238.875654 -134.542907) (xy 238.89518 -134.562873) (xy 238.907066 -134.570216)
			(xy 238.931489 -134.584966) (xy 238.976078 -134.620558) (xy 239.014867 -134.662395) (xy 239.04699 -134.709545)
			(xy 239.071731 -134.760953) (xy 239.088538 -134.815474) (xy 239.097035 -134.87189) (xy 239.097566 -134.900416)
			(xy 239.09708 -134.927667) (xy 239.089324 -134.981615) (xy 239.073969 -135.03391) (xy 239.051327 -135.083487)
			(xy 239.021861 -135.129337) (xy 239.010845 -135.142051) (xy 241.56187 -135.142051) (xy 241.56187 -135.087549)
			(xy 241.569626 -135.033603) (xy 241.58498 -134.981309) (xy 241.60762 -134.931732) (xy 241.637084 -134.885882)
			(xy 241.672774 -134.844692) (xy 241.713962 -134.809) (xy 241.75981 -134.779532) (xy 241.809385 -134.756889)
			(xy 241.861677 -134.741531) (xy 241.915623 -134.733772) (xy 241.942874 -134.733284) (xy 241.971792 -134.733789)
			(xy 242.028965 -134.742516) (xy 242.084166 -134.759775) (xy 242.136128 -134.785169) (xy 242.183661 -134.818116)
			(xy 242.225676 -134.857862) (xy 242.243864 -134.88035) (xy 242.251656 -134.889338) (xy 242.273122 -134.899526)
			(xy 242.285012 -134.899908) (xy 242.378484 -134.897876) (xy 242.39982 -134.8867) (xy 242.406678 -134.876794)
			(xy 242.422076 -134.855884) (xy 242.457654 -134.818057) (xy 242.498033 -134.785405) (xy 242.542468 -134.75853)
			(xy 242.590136 -134.73793) (xy 242.640158 -134.723985) (xy 242.691609 -134.716952) (xy 242.717574 -134.71652)
			(xy 242.744944 -134.716996) (xy 242.799123 -134.724811) (xy 242.851626 -134.740297) (xy 242.901373 -134.763137)
			(xy 242.94734 -134.79286) (xy 242.968272 -134.8105) (xy 242.968526 -134.810754) (xy 242.975625 -134.816322)
			(xy 242.992532 -134.822579) (xy 243.001546 -134.822946) (xy 243.068602 -134.822946) (xy 243.07762 -134.822601)
			(xy 243.094538 -134.816346) (xy 243.101622 -134.810754) (xy 243.101622 -134.8105) (xy 243.101876 -134.8105)
			(xy 243.122809 -134.792859) (xy 243.168777 -134.763135) (xy 243.218523 -134.740289) (xy 243.271025 -134.724793)
			(xy 243.325203 -134.716964) (xy 243.379945 -134.716964) (xy 243.434123 -134.724793) (xy 243.486625 -134.740289)
			(xy 243.536371 -134.763135) (xy 243.582339 -134.792859) (xy 243.603272 -134.8105) (xy 243.603526 -134.810754)
			(xy 243.610625 -134.816322) (xy 243.627532 -134.822579) (xy 243.636546 -134.822946) (xy 243.703602 -134.822946)
			(xy 243.71262 -134.822601) (xy 243.729538 -134.816346) (xy 243.736622 -134.810754) (xy 243.73713 -134.8105)
			(xy 243.749868 -134.79956) (xy 243.776957 -134.779716) (xy 243.791232 -134.770876) (xy 243.800122 -134.765542)
			(xy 243.812314 -134.748524) (xy 243.832634 -134.655306) (xy 243.828316 -134.634732) (xy 243.822474 -134.626096)
			(xy 243.806467 -134.602037) (xy 243.781127 -134.550103) (xy 243.763903 -134.494944) (xy 243.75519 -134.437819)
			(xy 243.754656 -134.408926) (xy 243.755142 -134.381675) (xy 243.762898 -134.327727) (xy 243.778253 -134.275432)
			(xy 243.800895 -134.225855) (xy 243.830361 -134.180005) (xy 243.866052 -134.138814) (xy 243.907243 -134.103123)
			(xy 243.953093 -134.073657) (xy 244.00267 -134.051015) (xy 244.054965 -134.03566) (xy 244.108913 -134.027904)
			(xy 244.163415 -134.027904) (xy 244.217363 -134.03566) (xy 244.269658 -134.051015) (xy 244.319235 -134.073657)
			(xy 244.365085 -134.103123) (xy 244.406276 -134.138814) (xy 244.441967 -134.180005) (xy 244.471433 -134.225855)
			(xy 244.494075 -134.275432) (xy 244.50943 -134.327727) (xy 244.517186 -134.381675) (xy 244.517672 -134.408926)
			(xy 244.51722 -134.437019) (xy 244.508988 -134.492599) (xy 244.492691 -134.546371) (xy 244.468682 -134.597169)
			(xy 244.43748 -134.643895) (xy 244.399761 -134.685539) (xy 244.35634 -134.721198) (xy 244.332506 -134.736078)
			(xy 244.323616 -134.741412) (xy 244.311424 -134.75843) (xy 244.291104 -134.851648) (xy 244.295422 -134.872222)
			(xy 244.301264 -134.880858) (xy 244.317244 -134.904934) (xy 244.342592 -134.956861) (xy 244.346701 -134.970012)
			(xy 246.179594 -134.970012) (xy 246.180069 -134.942642) (xy 246.187885 -134.888463) (xy 246.203372 -134.83596)
			(xy 246.226212 -134.786213) (xy 246.255934 -134.740246) (xy 246.273574 -134.719314) (xy 246.273828 -134.71906)
			(xy 246.279399 -134.711963) (xy 246.285654 -134.695054) (xy 246.28602 -134.68604) (xy 246.28602 -134.618984)
			(xy 246.285666 -134.609967) (xy 246.279416 -134.59305) (xy 246.273828 -134.585964) (xy 246.273574 -134.585964)
			(xy 246.273574 -134.58571) (xy 246.255922 -134.564788) (xy 246.226213 -134.518812) (xy 246.20338 -134.469062)
			(xy 246.187892 -134.416559) (xy 246.180067 -134.362382) (xy 246.179594 -134.335012) (xy 246.18008 -134.307761)
			(xy 246.187836 -134.253813) (xy 246.203191 -134.201518) (xy 246.225833 -134.151941) (xy 246.255299 -134.106091)
			(xy 246.29099 -134.0649) (xy 246.332181 -134.029209) (xy 246.378031 -133.999743) (xy 246.427608 -133.977101)
			(xy 246.479903 -133.961746) (xy 246.533851 -133.95399) (xy 246.588353 -133.95399) (xy 246.642301 -133.961746)
			(xy 246.694596 -133.977101) (xy 246.743087 -133.999247) (xy 247.489524 -133.999247) (xy 247.489524 -133.944753)
			(xy 247.497279 -133.890815) (xy 247.512631 -133.838528) (xy 247.535267 -133.788959) (xy 247.564727 -133.743116)
			(xy 247.600411 -133.701931) (xy 247.641593 -133.666244) (xy 247.687435 -133.636781) (xy 247.737002 -133.614141)
			(xy 247.789287 -133.598785) (xy 247.843225 -133.591026) (xy 247.870472 -133.590538) (xy 247.896788 -133.590945)
			(xy 247.94892 -133.598191) (xy 247.999564 -133.612521) (xy 248.047763 -133.633664) (xy 248.092605 -133.661222)
			(xy 248.133242 -133.694671) (xy 248.151396 -133.713728) (xy 248.158927 -133.721119) (xy 248.178199 -133.729652)
			(xy 248.188734 -133.730238) (xy 248.26341 -133.730238) (xy 248.27396 -133.729716) (xy 248.293255 -133.721175)
			(xy 248.300748 -133.713728) (xy 248.318893 -133.694661) (xy 248.359524 -133.661204) (xy 248.404366 -133.633646)
			(xy 248.452569 -133.612509) (xy 248.503219 -133.598195) (xy 248.555355 -133.590974) (xy 248.581672 -133.590538)
			(xy 248.608929 -133.590907) (xy 248.66289 -133.598662) (xy 248.715198 -133.614017) (xy 248.764787 -133.636661)
			(xy 248.810649 -133.666132) (xy 248.85185 -133.70183) (xy 248.887552 -133.743028) (xy 248.917026 -133.788888)
			(xy 248.939673 -133.838476) (xy 248.955032 -133.890783) (xy 248.962791 -133.944743) (xy 248.962791 -133.999257)
			(xy 248.955032 -134.053217) (xy 248.939673 -134.105524) (xy 248.917026 -134.155112) (xy 248.887552 -134.200972)
			(xy 248.85185 -134.24217) (xy 248.810649 -134.277868) (xy 248.764787 -134.307339) (xy 248.715198 -134.329983)
			(xy 248.66289 -134.345338) (xy 248.608929 -134.353093) (xy 248.581672 -134.353554) (xy 248.555357 -134.35312)
			(xy 248.503226 -134.34588) (xy 248.452582 -134.331556) (xy 248.404383 -134.310417) (xy 248.35954 -134.282864)
			(xy 248.318903 -134.249419) (xy 248.300748 -134.230364) (xy 248.293239 -134.222947) (xy 248.27395 -134.214429)
			(xy 248.26341 -134.213854) (xy 248.188734 -134.213854) (xy 248.178187 -134.214401) (xy 248.158892 -134.222925)
			(xy 248.151396 -134.230364) (xy 248.133248 -134.249427) (xy 248.092615 -134.282881) (xy 248.047773 -134.310437)
			(xy 247.999571 -134.331574) (xy 247.948923 -134.34589) (xy 247.896788 -134.353115) (xy 247.870472 -134.353554)
			(xy 247.843225 -134.352974) (xy 247.789287 -134.345215) (xy 247.737002 -134.329859) (xy 247.687435 -134.307219)
			(xy 247.641593 -134.277756) (xy 247.600411 -134.242069) (xy 247.564727 -134.200884) (xy 247.535267 -134.155041)
			(xy 247.512631 -134.105472) (xy 247.497279 -134.053185) (xy 247.489524 -133.999247) (xy 246.743087 -133.999247)
			(xy 246.744173 -133.999743) (xy 246.790023 -134.029209) (xy 246.831214 -134.0649) (xy 246.866905 -134.106091)
			(xy 246.896371 -134.151941) (xy 246.919013 -134.201518) (xy 246.934368 -134.253813) (xy 246.942124 -134.307761)
			(xy 246.94261 -134.335012) (xy 246.942149 -134.362382) (xy 246.934329 -134.416562) (xy 246.918839 -134.469065)
			(xy 246.895996 -134.518811) (xy 246.866271 -134.564778) (xy 246.84863 -134.58571) (xy 246.848376 -134.585964)
			(xy 246.842796 -134.593055) (xy 246.839503 -134.601966) (xy 249.141742 -134.601966) (xy 249.142173 -134.575651)
			(xy 249.149414 -134.52352) (xy 249.163739 -134.472876) (xy 249.184878 -134.424677) (xy 249.212431 -134.379834)
			(xy 249.245877 -134.339197) (xy 249.264932 -134.321042) (xy 249.272307 -134.313498) (xy 249.280849 -134.294235)
			(xy 249.281442 -134.283704) (xy 249.281442 -134.209028) (xy 249.280899 -134.19848) (xy 249.272372 -134.179185)
			(xy 249.264932 -134.17169) (xy 249.245885 -134.153526) (xy 249.212426 -134.112899) (xy 249.184865 -134.068061)
			(xy 249.163725 -134.019861) (xy 249.149406 -133.969215) (xy 249.142181 -133.917082) (xy 249.141742 -133.890766)
			(xy 249.142178 -133.863395) (xy 249.150001 -133.809214) (xy 249.165497 -133.75671) (xy 249.188346 -133.706964)
			(xy 249.218077 -133.660998) (xy 249.235722 -133.640068) (xy 249.235976 -133.639814) (xy 249.241572 -133.632734)
			(xy 249.247811 -133.615812) (xy 249.248168 -133.606794) (xy 249.248168 -133.539738) (xy 249.2478 -133.530722)
			(xy 249.241561 -133.513805) (xy 249.235976 -133.506718) (xy 249.235722 -133.506718) (xy 249.235722 -133.506464)
			(xy 249.218048 -133.485558) (xy 249.188325 -133.439586) (xy 249.165482 -133.389835) (xy 249.149989 -133.337329)
			(xy 249.142163 -133.283147) (xy 249.142167 -133.228402) (xy 249.15 -133.174221) (xy 249.1655 -133.121717)
			(xy 249.18835 -133.071969) (xy 249.218079 -133.026001) (xy 249.235722 -133.005068) (xy 249.235976 -133.004814)
			(xy 249.241572 -132.997734) (xy 249.247811 -132.980812) (xy 249.248168 -132.971794) (xy 249.248168 -132.904738)
			(xy 249.2478 -132.895722) (xy 249.241561 -132.878805) (xy 249.235976 -132.871718) (xy 249.235722 -132.871718)
			(xy 249.235722 -132.871464) (xy 249.218103 -132.850516) (xy 249.188387 -132.804548) (xy 249.165547 -132.754804)
			(xy 249.150051 -132.702307) (xy 249.142218 -132.648134) (xy 249.141742 -132.620766) (xy 249.142305 -132.591146)
			(xy 249.151465 -132.532619) (xy 249.169561 -132.476211) (xy 249.196158 -132.423278) (xy 249.230616 -132.375091)
			(xy 249.250962 -132.353558) (xy 249.25782 -132.3467) (xy 249.265186 -132.329174) (xy 249.267218 -132.240274)
			(xy 249.260614 -132.221986) (xy 249.25401 -132.214874) (xy 249.235881 -132.193788) (xy 249.205292 -132.147349)
			(xy 249.181767 -132.096963) (xy 249.165802 -132.043697) (xy 249.157736 -131.988678) (xy 249.157236 -131.960874)
			(xy 249.157631 -131.933618) (xy 249.165392 -131.879663) (xy 249.180754 -131.827361) (xy 249.203403 -131.777778)
			(xy 249.232878 -131.731923) (xy 249.268579 -131.690729) (xy 249.309779 -131.655036) (xy 249.355639 -131.625569)
			(xy 249.405227 -131.60293) (xy 249.457531 -131.587578) (xy 249.511488 -131.579826) (xy 249.538744 -131.579366)
			(xy 249.566114 -131.579849) (xy 249.620293 -131.58766) (xy 249.672796 -131.603144) (xy 249.722544 -131.625983)
			(xy 249.76851 -131.655705) (xy 249.789442 -131.673346) (xy 249.789696 -131.6736) (xy 249.79678 -131.679191)
			(xy 249.813699 -131.685435) (xy 249.822716 -131.685792) (xy 249.889772 -131.685792) (xy 249.898788 -131.685424)
			(xy 249.915705 -131.679184) (xy 249.922792 -131.6736) (xy 249.922792 -131.673346) (xy 249.923046 -131.673346)
			(xy 249.943979 -131.655705) (xy 249.989947 -131.625981) (xy 250.039693 -131.603135) (xy 250.092195 -131.587639)
			(xy 250.146373 -131.57981) (xy 250.201115 -131.57981) (xy 250.255293 -131.587639) (xy 250.307795 -131.603135)
			(xy 250.357541 -131.625981) (xy 250.403509 -131.655705) (xy 250.424442 -131.673346) (xy 250.424696 -131.6736)
			(xy 250.43178 -131.679191) (xy 250.448699 -131.685435) (xy 250.457716 -131.685792) (xy 250.524772 -131.685792)
			(xy 250.533788 -131.685424) (xy 250.550705 -131.679184) (xy 250.557792 -131.6736) (xy 250.557792 -131.673346)
			(xy 250.558046 -131.673346) (xy 250.578979 -131.655705) (xy 250.624947 -131.625981) (xy 250.674693 -131.603135)
			(xy 250.727195 -131.587639) (xy 250.781373 -131.57981) (xy 250.836115 -131.57981) (xy 250.890293 -131.587639)
			(xy 250.942795 -131.603135) (xy 250.992541 -131.625981) (xy 251.038509 -131.655705) (xy 251.059442 -131.673346)
			(xy 251.059696 -131.6736) (xy 251.06678 -131.679191) (xy 251.083699 -131.685435) (xy 251.092716 -131.685792)
			(xy 251.159772 -131.685792) (xy 251.168788 -131.685424) (xy 251.185705 -131.679184) (xy 251.192792 -131.6736)
			(xy 251.192792 -131.673346) (xy 251.193046 -131.673346) (xy 251.213994 -131.655726) (xy 251.259961 -131.62601)
			(xy 251.309705 -131.603169) (xy 251.362202 -131.587674) (xy 251.416376 -131.579842) (xy 251.443744 -131.579366)
			(xy 251.470991 -131.579907) (xy 251.524931 -131.587668) (xy 251.577216 -131.603026) (xy 251.626785 -131.625668)
			(xy 251.672626 -131.655134) (xy 251.713808 -131.690823) (xy 251.749493 -131.732009) (xy 251.778953 -131.777854)
			(xy 251.801589 -131.827425) (xy 251.816941 -131.879713) (xy 251.824696 -131.933653) (xy 251.824696 -131.988147)
			(xy 251.816941 -132.042087) (xy 251.808202 -132.071853) (xy 268.933091 -132.071853) (xy 268.933091 -132.014547)
			(xy 268.941247 -131.957823) (xy 268.957393 -131.902838) (xy 268.9812 -131.850711) (xy 269.012183 -131.802502)
			(xy 269.049712 -131.759194) (xy 269.093023 -131.721667) (xy 269.141234 -131.690687) (xy 269.193363 -131.666884)
			(xy 269.248349 -131.650741) (xy 269.305073 -131.642589) (xy 269.333726 -131.642104) (xy 269.361107 -131.642549)
			(xy 269.415359 -131.65002) (xy 269.468088 -131.664806) (xy 269.518314 -131.686632) (xy 269.565102 -131.715091)
			(xy 269.60758 -131.749653) (xy 269.644959 -131.789676) (xy 269.661132 -131.811776) (xy 269.666689 -131.819042)
			(xy 269.681802 -131.829324) (xy 269.690596 -131.831842) (xy 269.720568 -131.839208) (xy 269.72952 -131.840942)
			(xy 269.747607 -131.838736) (xy 269.755874 -131.83489) (xy 269.780479 -131.822511) (xy 269.832003 -131.80304)
			(xy 269.885491 -131.789888) (xy 269.94017 -131.783247) (xy 269.96771 -131.78282) (xy 269.99525 -131.783263)
			(xy 270.04993 -131.789895) (xy 270.103419 -131.803038) (xy 270.154946 -131.822501) (xy 270.179546 -131.83489)
			(xy 270.187796 -131.83879) (xy 270.205901 -131.840991) (xy 270.214852 -131.839208) (xy 270.244824 -131.831842)
			(xy 270.253609 -131.829309) (xy 270.268708 -131.81902) (xy 270.274288 -131.811776) (xy 270.290454 -131.78967)
			(xy 270.327827 -131.749639) (xy 270.370305 -131.715072) (xy 270.417094 -131.686612) (xy 270.467323 -131.664789)
			(xy 270.520057 -131.65001) (xy 270.574311 -131.642551) (xy 270.601694 -131.642104) (xy 270.630342 -131.64265)
			(xy 270.687055 -131.650804) (xy 270.742031 -131.666945) (xy 270.79415 -131.690746) (xy 270.842351 -131.721723)
			(xy 270.885653 -131.759243) (xy 270.923174 -131.802545) (xy 270.954151 -131.850745) (xy 270.977953 -131.902864)
			(xy 270.994095 -131.957839) (xy 271.002249 -132.014552) (xy 271.002249 -132.071848) (xy 270.994095 -132.128561)
			(xy 270.977953 -132.183536) (xy 270.954151 -132.235655) (xy 270.923174 -132.283855) (xy 270.885653 -132.327157)
			(xy 270.842351 -132.364677) (xy 270.79415 -132.395654) (xy 270.742031 -132.419455) (xy 270.687055 -132.435596)
			(xy 270.630342 -132.44375) (xy 270.601694 -132.444236) (xy 270.586776 -132.444062) (xy 270.557027 -132.441776)
			(xy 270.542258 -132.439664) (xy 270.531082 -132.437886) (xy 270.51 -132.443982) (xy 270.443198 -132.50164)
			(xy 270.435258 -132.509257) (xy 270.426158 -132.529258) (xy 270.425672 -132.540248) (xy 270.425672 -132.804916)
			(xy 270.426177 -132.815905) (xy 270.435254 -132.835916) (xy 270.443198 -132.843524) (xy 270.51 -132.901182)
			(xy 270.531082 -132.907278) (xy 270.542258 -132.9055) (xy 270.557028 -132.903394) (xy 270.586776 -132.901104)
			(xy 270.601694 -132.900928) (xy 270.630344 -132.901426) (xy 270.68706 -132.90958) (xy 270.742039 -132.925723)
			(xy 270.794161 -132.949525) (xy 270.842365 -132.980503) (xy 270.885669 -133.018026) (xy 270.923193 -133.06133)
			(xy 270.954172 -133.109534) (xy 270.977975 -133.161655) (xy 270.994119 -133.216634) (xy 271.002273 -133.27335)
			(xy 271.002273 -133.33065) (xy 270.994119 -133.387366) (xy 270.977975 -133.442345) (xy 270.954172 -133.494466)
			(xy 270.923193 -133.54267) (xy 270.885669 -133.585974) (xy 270.842365 -133.623497) (xy 270.794161 -133.654475)
			(xy 270.742039 -133.678277) (xy 270.68706 -133.69442) (xy 270.630344 -133.702574) (xy 270.601694 -133.70306)
			(xy 270.574314 -133.702573) (xy 270.520066 -133.695106) (xy 270.467339 -133.680325) (xy 270.417114 -133.658506)
			(xy 270.370326 -133.630054) (xy 270.327845 -133.595499) (xy 270.290463 -133.555484) (xy 270.274288 -133.533388)
			(xy 270.268731 -133.526123) (xy 270.253618 -133.515842) (xy 270.244824 -133.513322) (xy 270.214852 -133.505956)
			(xy 270.205898 -133.504235) (xy 270.187813 -133.506433) (xy 270.179546 -133.510274) (xy 270.15494 -133.52265)
			(xy 270.103416 -133.542122) (xy 270.049928 -133.555273) (xy 269.99525 -133.561916) (xy 269.96771 -133.562344)
			(xy 269.940169 -133.561937) (xy 269.885488 -133.555295) (xy 269.831998 -133.542142) (xy 269.780473 -133.522668)
			(xy 269.755874 -133.510274) (xy 269.74762 -133.506383) (xy 269.729519 -133.504177) (xy 269.720568 -133.505956)
			(xy 269.690596 -133.513322) (xy 269.681818 -133.515874) (xy 269.666716 -133.52615) (xy 269.661132 -133.533388)
			(xy 269.645005 -133.555524) (xy 269.607626 -133.595555) (xy 269.565142 -133.630121) (xy 269.518346 -133.658578)
			(xy 269.468111 -133.680396) (xy 269.415371 -133.695168) (xy 269.361111 -133.702618) (xy 269.333726 -133.70306)
			(xy 269.305074 -133.702587) (xy 269.248354 -133.694435) (xy 269.193371 -133.678294) (xy 269.141245 -133.654492)
			(xy 269.093037 -133.623513) (xy 269.049729 -133.585989) (xy 269.012202 -133.542684) (xy 268.981221 -133.494478)
			(xy 268.957415 -133.442353) (xy 268.94127 -133.387371) (xy 268.933115 -133.330652) (xy 268.933115 -133.273348)
			(xy 268.94127 -133.216629) (xy 268.957415 -133.161647) (xy 268.981221 -133.109522) (xy 269.012202 -133.061316)
			(xy 269.049729 -133.018011) (xy 269.093037 -132.980487) (xy 269.141245 -132.949508) (xy 269.193371 -132.925706)
			(xy 269.248354 -132.909565) (xy 269.305074 -132.901413) (xy 269.333726 -132.900928) (xy 269.348644 -132.9011)
			(xy 269.378393 -132.903387) (xy 269.393162 -132.9055) (xy 269.404338 -132.907278) (xy 269.42542 -132.901182)
			(xy 269.492222 -132.843524) (xy 269.500182 -132.835925) (xy 269.50927 -132.81591) (xy 269.509748 -132.804916)
			(xy 269.509748 -132.540248) (xy 269.509256 -132.529258) (xy 269.50017 -132.509247) (xy 269.492222 -132.50164)
			(xy 269.42542 -132.443982) (xy 269.404338 -132.437886) (xy 269.393162 -132.439664) (xy 269.378392 -132.441768)
			(xy 269.348644 -132.444059) (xy 269.333726 -132.444236) (xy 269.305073 -132.443811) (xy 269.248349 -132.435659)
			(xy 269.193363 -132.419516) (xy 269.141234 -132.395713) (xy 269.093023 -132.364733) (xy 269.049712 -132.327206)
			(xy 269.012183 -132.283898) (xy 268.9812 -132.235689) (xy 268.957393 -132.183562) (xy 268.941247 -132.128577)
			(xy 268.933091 -132.071853) (xy 251.808202 -132.071853) (xy 251.801589 -132.094375) (xy 251.778953 -132.143946)
			(xy 251.749493 -132.189791) (xy 251.713808 -132.230977) (xy 251.672626 -132.266666) (xy 251.626785 -132.296132)
			(xy 251.577216 -132.318774) (xy 251.524931 -132.334132) (xy 251.470991 -132.341893) (xy 251.443744 -132.342382)
			(xy 251.416374 -132.341895) (xy 251.362196 -132.334083) (xy 251.309693 -132.318599) (xy 251.259946 -132.295762)
			(xy 251.213978 -132.266041) (xy 251.193046 -132.248402) (xy 251.192792 -132.248148) (xy 251.185716 -132.242546)
			(xy 251.168791 -132.23631) (xy 251.159772 -132.235956) (xy 251.092716 -132.235956) (xy 251.083698 -132.236309)
			(xy 251.066781 -132.242558) (xy 251.059696 -132.248148) (xy 251.059696 -132.248402) (xy 251.059442 -132.248402)
			(xy 251.038509 -132.266043) (xy 250.992541 -132.295767) (xy 250.942795 -132.318613) (xy 250.890293 -132.334109)
			(xy 250.836115 -132.341938) (xy 250.781373 -132.341938) (xy 250.727195 -132.334109) (xy 250.674693 -132.318613)
			(xy 250.624947 -132.295767) (xy 250.578979 -132.266043) (xy 250.558046 -132.248402) (xy 250.557792 -132.248148)
			(xy 250.550716 -132.242546) (xy 250.533791 -132.23631) (xy 250.524772 -132.235956) (xy 250.457716 -132.235956)
			(xy 250.448698 -132.236309) (xy 250.431781 -132.242558) (xy 250.424696 -132.248148) (xy 250.424696 -132.248402)
			(xy 250.424442 -132.248402) (xy 250.403505 -132.266035) (xy 250.357534 -132.295748) (xy 250.307787 -132.318585)
			(xy 250.255288 -132.334077) (xy 250.201113 -132.341907) (xy 250.173744 -132.342382) (xy 250.144267 -132.34182)
			(xy 250.086015 -132.332757) (xy 250.02985 -132.31484) (xy 249.97711 -132.288495) (xy 249.929052 -132.254351)
			(xy 249.907552 -132.234178) (xy 249.90023 -132.227627) (xy 249.88206 -132.220192) (xy 249.872246 -132.2197)
			(xy 249.818906 -132.2197) (xy 249.811032 -132.228082) (xy 249.804174 -132.23494) (xy 249.796808 -132.252466)
			(xy 249.794776 -132.341366) (xy 249.80138 -132.359654) (xy 249.807984 -132.366766) (xy 249.826084 -132.387876)
			(xy 249.856677 -132.434308) (xy 249.880208 -132.484688) (xy 249.89618 -132.537949) (xy 249.904253 -132.592964)
			(xy 249.904758 -132.620766) (xy 249.904282 -132.648136) (xy 249.896468 -132.702315) (xy 249.880982 -132.754818)
			(xy 249.858142 -132.804566) (xy 249.828419 -132.850532) (xy 249.810778 -132.871464) (xy 249.810524 -132.871718)
			(xy 249.804915 -132.878789) (xy 249.798684 -132.895718) (xy 249.798332 -132.904738) (xy 249.798332 -132.971794)
			(xy 249.798685 -132.980811) (xy 249.804935 -132.997729) (xy 249.810524 -133.004814) (xy 249.810778 -133.004814)
			(xy 249.810778 -133.005068) (xy 249.828385 -133.026028) (xy 249.858111 -133.071991) (xy 249.880958 -133.121733)
			(xy 249.896457 -133.174231) (xy 249.904288 -133.228405) (xy 249.904292 -133.283143) (xy 249.896468 -133.337319)
			(xy 249.880976 -133.389819) (xy 249.858136 -133.439564) (xy 249.828416 -133.485531) (xy 249.810778 -133.506464)
			(xy 249.810524 -133.506718) (xy 249.804915 -133.513789) (xy 249.798684 -133.530718) (xy 249.798332 -133.539738)
			(xy 249.798332 -133.606794) (xy 249.798685 -133.615811) (xy 249.804935 -133.632729) (xy 249.810524 -133.639814)
			(xy 249.810778 -133.639814) (xy 249.810778 -133.640068) (xy 249.828412 -133.661004) (xy 249.858125 -133.706975)
			(xy 249.880963 -133.756722) (xy 249.896455 -133.809222) (xy 249.904284 -133.863397) (xy 249.904318 -133.865335)
			(xy 266.291239 -133.865335) (xy 266.291239 -133.808065) (xy 266.299389 -133.751377) (xy 266.315525 -133.696427)
			(xy 266.339316 -133.644332) (xy 266.37028 -133.596154) (xy 266.407785 -133.552872) (xy 266.451068 -133.515369)
			(xy 266.499248 -133.484408) (xy 266.551344 -133.460619) (xy 266.606295 -133.444486) (xy 266.662983 -133.436337)
			(xy 266.691618 -133.435852) (xy 266.718989 -133.436294) (xy 266.773222 -133.443743) (xy 266.825939 -133.458498)
			(xy 266.876158 -133.480286) (xy 266.922947 -133.508703) (xy 266.965437 -133.543219) (xy 267.002836 -133.583194)
			(xy 267.019024 -133.60527) (xy 267.024585 -133.612532) (xy 267.039695 -133.622816) (xy 267.048488 -133.625336)
			(xy 267.07846 -133.632702) (xy 267.087413 -133.634423) (xy 267.105498 -133.632224) (xy 267.113766 -133.628384)
			(xy 267.138376 -133.616032) (xy 267.18991 -133.596628) (xy 267.243398 -133.583543) (xy 267.298069 -133.576965)
			(xy 267.325602 -133.576568) (xy 267.353136 -133.576959) (xy 267.407811 -133.583524) (xy 267.461301 -133.596607)
			(xy 267.512834 -133.616019) (xy 267.537438 -133.628384) (xy 267.54569 -133.63228) (xy 267.563793 -133.634483)
			(xy 267.572744 -133.632702) (xy 267.602716 -133.625336) (xy 267.611501 -133.622801) (xy 267.6266 -133.612514)
			(xy 267.63218 -133.60527) (xy 267.648384 -133.583207) (xy 267.685782 -133.543235) (xy 267.728269 -133.508721)
			(xy 267.775056 -133.480306) (xy 267.825273 -133.45852) (xy 267.877986 -133.443766) (xy 267.932216 -133.436318)
			(xy 267.959586 -133.435852) (xy 267.988216 -133.43641) (xy 268.044893 -133.444557) (xy 268.099834 -133.460687)
			(xy 268.15192 -133.484472) (xy 268.200091 -133.515428) (xy 268.243365 -133.552925) (xy 268.280863 -133.596198)
			(xy 268.311821 -133.644368) (xy 268.335608 -133.696453) (xy 268.35174 -133.751393) (xy 268.359889 -133.80807)
			(xy 268.359889 -133.86533) (xy 268.35174 -133.922007) (xy 268.335608 -133.976947) (xy 268.311821 -134.029032)
			(xy 268.280863 -134.077202) (xy 268.243365 -134.120475) (xy 268.200091 -134.157972) (xy 268.15192 -134.188928)
			(xy 268.099834 -134.212713) (xy 268.044893 -134.228843) (xy 267.988216 -134.23699) (xy 267.959586 -134.237476)
			(xy 267.944672 -134.237363) (xy 267.914923 -134.235205) (xy 267.90015 -134.233158) (xy 267.888974 -134.23138)
			(xy 267.867892 -134.237476) (xy 267.80109 -134.295134) (xy 267.793152 -134.302752) (xy 267.784051 -134.322753)
			(xy 267.783564 -134.333742) (xy 267.783564 -134.59841) (xy 267.784075 -134.609398) (xy 267.793148 -134.629409)
			(xy 267.80109 -134.637018) (xy 267.867892 -134.694676) (xy 267.888974 -134.700772) (xy 267.90015 -134.698994)
			(xy 267.914923 -134.696945) (xy 267.944672 -134.694784) (xy 267.959586 -134.694676) (xy 267.988218 -134.695186)
			(xy 268.044898 -134.703333) (xy 268.099842 -134.719465) (xy 268.151931 -134.743251) (xy 268.200105 -134.774209)
			(xy 268.243382 -134.811708) (xy 268.280883 -134.854984) (xy 268.311842 -134.903156) (xy 268.335631 -134.955244)
			(xy 268.351764 -135.010188) (xy 268.359913 -135.066868) (xy 268.359913 -135.124132) (xy 268.351764 -135.180812)
			(xy 268.335631 -135.235756) (xy 268.311842 -135.287844) (xy 268.280883 -135.336016) (xy 268.243382 -135.379292)
			(xy 268.200105 -135.416791) (xy 268.151931 -135.447749) (xy 268.099842 -135.471535) (xy 268.044898 -135.487667)
			(xy 267.988218 -135.495814) (xy 267.959586 -135.4963) (xy 267.932216 -135.495833) (xy 267.877985 -135.488386)
			(xy 267.82527 -135.473633) (xy 267.775051 -135.451849) (xy 267.728262 -135.423437) (xy 267.685772 -135.388925)
			(xy 267.648369 -135.348956) (xy 267.63218 -135.326882) (xy 267.626628 -135.319613) (xy 267.611511 -135.309334)
			(xy 267.602716 -135.306816) (xy 267.572744 -135.29945) (xy 267.563791 -135.297726) (xy 267.545705 -135.299926)
			(xy 267.537438 -135.303768) (xy 267.512829 -135.316122) (xy 267.461295 -135.335525) (xy 267.407806 -135.348609)
			(xy 267.353135 -135.355187) (xy 267.325602 -135.355584) (xy 267.298068 -135.355186) (xy 267.243394 -135.348622)
			(xy 267.189904 -135.335541) (xy 267.138371 -135.316132) (xy 267.113766 -135.303768) (xy 267.105514 -135.299873)
			(xy 267.087411 -135.29767) (xy 267.07846 -135.29945) (xy 267.048488 -135.306816) (xy 267.039709 -135.309367)
			(xy 267.024608 -135.319644) (xy 267.019024 -135.326882) (xy 267.002833 -135.348954) (xy 266.965431 -135.388924)
			(xy 266.922941 -135.423436) (xy 266.876152 -135.451848) (xy 266.825934 -135.473633) (xy 266.773219 -135.488386)
			(xy 266.718988 -135.495833) (xy 266.691618 -135.4963) (xy 266.662984 -135.495839) (xy 266.6063 -135.487691)
			(xy 266.551352 -135.471559) (xy 266.499259 -135.447771) (xy 266.451082 -135.416812) (xy 266.407802 -135.379311)
			(xy 266.370299 -135.336032) (xy 266.339338 -135.287856) (xy 266.315547 -135.235765) (xy 266.299413 -135.180818)
			(xy 266.291263 -135.124134) (xy 266.291263 -135.066866) (xy 266.299413 -135.010182) (xy 266.315547 -134.955235)
			(xy 266.339338 -134.903144) (xy 266.370299 -134.854968) (xy 266.407802 -134.811689) (xy 266.451082 -134.774188)
			(xy 266.499259 -134.743229) (xy 266.551352 -134.719441) (xy 266.6063 -134.703309) (xy 266.662984 -134.695161)
			(xy 266.691618 -134.694676) (xy 266.706532 -134.694788) (xy 266.736281 -134.696948) (xy 266.751054 -134.698994)
			(xy 266.76223 -134.700772) (xy 266.783312 -134.694676) (xy 266.850114 -134.637018) (xy 266.858075 -134.62942)
			(xy 266.867162 -134.609404) (xy 266.86764 -134.59841) (xy 266.86764 -134.333742) (xy 266.867154 -134.322751)
			(xy 266.858064 -134.30274) (xy 266.850114 -134.295134) (xy 266.783312 -134.237476) (xy 266.76223 -134.23138)
			(xy 266.751054 -134.233158) (xy 266.736281 -134.235206) (xy 266.706532 -134.237367) (xy 266.691618 -134.237476)
			(xy 266.662983 -134.237063) (xy 266.606295 -134.228914) (xy 266.551344 -134.212781) (xy 266.499248 -134.188992)
			(xy 266.451068 -134.158031) (xy 266.407785 -134.120528) (xy 266.37028 -134.077246) (xy 266.339316 -134.029068)
			(xy 266.315525 -133.976973) (xy 266.299389 -133.922023) (xy 266.291239 -133.865335) (xy 249.904318 -133.865335)
			(xy 249.904758 -133.890766) (xy 249.904348 -133.917082) (xy 249.897103 -133.969214) (xy 249.882774 -134.019858)
			(xy 249.861631 -134.068057) (xy 249.834074 -134.112899) (xy 249.800625 -134.153536) (xy 249.781568 -134.17169)
			(xy 249.774179 -134.179222) (xy 249.765645 -134.198494) (xy 249.765058 -134.209028) (xy 249.765058 -134.283704)
			(xy 249.765584 -134.294254) (xy 249.774123 -134.313548) (xy 249.781568 -134.321042) (xy 249.800631 -134.33919)
			(xy 249.834089 -134.379821) (xy 249.861647 -134.424662) (xy 249.882785 -134.472865) (xy 249.8971 -134.523514)
			(xy 249.904322 -134.575649) (xy 249.904758 -134.601966) (xy 249.904272 -134.629217) (xy 249.896516 -134.683165)
			(xy 249.881161 -134.73546) (xy 249.858519 -134.785037) (xy 249.829053 -134.830887) (xy 249.793362 -134.872078)
			(xy 249.752171 -134.907769) (xy 249.706321 -134.937235) (xy 249.656744 -134.959877) (xy 249.604449 -134.975232)
			(xy 249.550501 -134.982988) (xy 249.495999 -134.982988) (xy 249.442051 -134.975232) (xy 249.389756 -134.959877)
			(xy 249.340179 -134.937235) (xy 249.294329 -134.907769) (xy 249.253138 -134.872078) (xy 249.217447 -134.830887)
			(xy 249.187981 -134.785037) (xy 249.165339 -134.73546) (xy 249.149984 -134.683165) (xy 249.142228 -134.629217)
			(xy 249.141742 -134.601966) (xy 246.839503 -134.601966) (xy 246.836546 -134.609968) (xy 246.836184 -134.618984)
			(xy 246.836184 -134.68604) (xy 246.836525 -134.695058) (xy 246.842784 -134.711975) (xy 246.848376 -134.71906)
			(xy 246.84863 -134.71906) (xy 246.84863 -134.719314) (xy 246.866247 -134.740264) (xy 246.895961 -134.786232)
			(xy 246.918801 -134.835975) (xy 246.934297 -134.888472) (xy 246.942132 -134.942644) (xy 246.94261 -134.970012)
			(xy 246.942124 -134.997263) (xy 246.934368 -135.051211) (xy 246.919013 -135.103506) (xy 246.896371 -135.153083)
			(xy 246.866905 -135.198933) (xy 246.831214 -135.240124) (xy 246.790023 -135.275815) (xy 246.744173 -135.305281)
			(xy 246.694596 -135.327923) (xy 246.642301 -135.343278) (xy 246.588353 -135.351034) (xy 246.533851 -135.351034)
			(xy 246.479903 -135.343278) (xy 246.427608 -135.327923) (xy 246.378031 -135.305281) (xy 246.332181 -135.275815)
			(xy 246.29099 -135.240124) (xy 246.255299 -135.198933) (xy 246.225833 -135.153083) (xy 246.203191 -135.103506)
			(xy 246.187836 -135.051211) (xy 246.18008 -134.997263) (xy 246.179594 -134.970012) (xy 244.346701 -134.970012)
			(xy 244.359824 -135.012015) (xy 244.368545 -135.069136) (xy 244.369082 -135.098028) (xy 244.368648 -135.125281)
			(xy 244.360887 -135.179232) (xy 244.345527 -135.231529) (xy 244.322881 -135.281108) (xy 244.293409 -135.32696)
			(xy 244.257712 -135.368151) (xy 244.225283 -135.396247) (xy 250.131124 -135.396247) (xy 250.131124 -135.341753)
			(xy 250.138879 -135.287815) (xy 250.154231 -135.235528) (xy 250.176867 -135.185959) (xy 250.206327 -135.140116)
			(xy 250.242011 -135.098931) (xy 250.283193 -135.063244) (xy 250.329035 -135.033781) (xy 250.378602 -135.011141)
			(xy 250.430887 -134.995785) (xy 250.484825 -134.988026) (xy 250.512072 -134.987538) (xy 250.538388 -134.987945)
			(xy 250.59052 -134.995191) (xy 250.641164 -135.009521) (xy 250.689363 -135.030664) (xy 250.734205 -135.058222)
			(xy 250.774842 -135.091671) (xy 250.792996 -135.110728) (xy 250.800527 -135.118119) (xy 250.819799 -135.126652)
			(xy 250.830334 -135.127238) (xy 250.90501 -135.127238) (xy 250.91556 -135.126716) (xy 250.934855 -135.118175)
			(xy 250.942348 -135.110728) (xy 250.960493 -135.091661) (xy 251.001124 -135.058204) (xy 251.045966 -135.030646)
			(xy 251.094169 -135.009509) (xy 251.144819 -134.995195) (xy 251.196955 -134.987974) (xy 251.223272 -134.987538)
			(xy 251.250529 -134.987907) (xy 251.30449 -134.995662) (xy 251.356798 -135.011017) (xy 251.406387 -135.033661)
			(xy 251.452249 -135.063132) (xy 251.49345 -135.09883) (xy 251.529152 -135.140028) (xy 251.558626 -135.185888)
			(xy 251.581273 -135.235476) (xy 251.596632 -135.287783) (xy 251.604391 -135.341743) (xy 251.604391 -135.396257)
			(xy 251.596632 -135.450217) (xy 251.581273 -135.502524) (xy 251.558626 -135.552112) (xy 251.529152 -135.597972)
			(xy 251.49345 -135.63917) (xy 251.455868 -135.671732) (xy 268.933387 -135.671732) (xy 268.933387 -135.614468)
			(xy 268.941537 -135.557786) (xy 268.95767 -135.502842) (xy 268.98146 -135.450753) (xy 269.01242 -135.40258)
			(xy 269.049922 -135.359303) (xy 269.093201 -135.321805) (xy 269.141376 -135.290847) (xy 269.193466 -135.267061)
			(xy 269.248412 -135.250931) (xy 269.305094 -135.242785) (xy 269.333726 -135.2423) (xy 269.361096 -135.242758)
			(xy 269.415328 -135.250206) (xy 269.468043 -135.264961) (xy 269.518262 -135.286747) (xy 269.565051 -135.315161)
			(xy 269.607541 -135.349673) (xy 269.644943 -135.389644) (xy 269.661132 -135.411718) (xy 269.666681 -135.418991)
			(xy 269.6818 -135.429267) (xy 269.690596 -135.431784) (xy 269.720568 -135.43915) (xy 269.72952 -135.44088)
			(xy 269.747607 -135.438676) (xy 269.755874 -135.434832) (xy 269.780481 -135.422473) (xy 269.832016 -135.403072)
			(xy 269.885505 -135.389989) (xy 269.940177 -135.383412) (xy 269.96771 -135.383016) (xy 269.995244 -135.383409)
			(xy 270.049918 -135.389974) (xy 270.103409 -135.403057) (xy 270.154941 -135.422467) (xy 270.179546 -135.434832)
			(xy 270.187796 -135.438733) (xy 270.205901 -135.440932) (xy 270.214852 -135.43915) (xy 270.244824 -135.431784)
			(xy 270.253604 -135.429237) (xy 270.268705 -135.418957) (xy 270.274288 -135.411718) (xy 270.290472 -135.38964)
			(xy 270.327875 -135.349671) (xy 270.370366 -135.315159) (xy 270.417156 -135.286748) (xy 270.467376 -135.264963)
			(xy 270.520092 -135.250211) (xy 270.574324 -135.242766) (xy 270.601694 -135.2423) (xy 270.630327 -135.242762)
			(xy 270.68701 -135.250911) (xy 270.741957 -135.267044) (xy 270.794048 -135.290833) (xy 270.842223 -135.321793)
			(xy 270.885502 -135.359293) (xy 270.923004 -135.402572) (xy 270.953964 -135.450747) (xy 270.977754 -135.502838)
			(xy 270.993887 -135.557784) (xy 271.002037 -135.614467) (xy 271.002037 -135.671733) (xy 270.993887 -135.728416)
			(xy 270.977754 -135.783362) (xy 270.953964 -135.835453) (xy 270.923004 -135.883628) (xy 270.885502 -135.926907)
			(xy 270.842223 -135.964407) (xy 270.794048 -135.995367) (xy 270.741957 -136.019156) (xy 270.68701 -136.035289)
			(xy 270.630327 -136.043438) (xy 270.601694 -136.043924) (xy 270.58678 -136.04381) (xy 270.557031 -136.041652)
			(xy 270.542258 -136.039606) (xy 270.531082 -136.037828) (xy 270.51 -136.043924) (xy 270.443198 -136.101582)
			(xy 270.435239 -136.109182) (xy 270.42615 -136.129196) (xy 270.425672 -136.14019) (xy 270.425672 -136.404858)
			(xy 270.426154 -136.415849) (xy 270.435247 -136.435861) (xy 270.443198 -136.443466) (xy 270.51 -136.501124)
			(xy 270.531082 -136.50722) (xy 270.542258 -136.505442) (xy 270.557031 -136.503392) (xy 270.58678 -136.501232)
			(xy 270.601694 -136.501124) (xy 270.630329 -136.501538) (xy 270.687015 -136.509688) (xy 270.741965 -136.525822)
			(xy 270.794059 -136.549612) (xy 270.842238 -136.580573) (xy 270.885519 -136.618077) (xy 270.923023 -136.661358)
			(xy 270.953985 -136.709535) (xy 270.977776 -136.761629) (xy 270.993911 -136.816579) (xy 271.002061 -136.873265)
			(xy 271.002061 -136.930535) (xy 270.993911 -136.987221) (xy 270.977776 -137.042171) (xy 270.953985 -137.094265)
			(xy 270.923023 -137.142442) (xy 270.885519 -137.185723) (xy 270.842238 -137.223227) (xy 270.794059 -137.254188)
			(xy 270.741965 -137.277978) (xy 270.687015 -137.294112) (xy 270.630329 -137.302262) (xy 270.601694 -137.302748)
			(xy 270.574323 -137.302297) (xy 270.52009 -137.29485) (xy 270.467374 -137.280096) (xy 270.417155 -137.258309)
			(xy 270.370366 -137.229894) (xy 270.327876 -137.195379) (xy 270.290476 -137.155406) (xy 270.274288 -137.13333)
			(xy 270.268723 -137.126072) (xy 270.253616 -137.115786) (xy 270.244824 -137.113264) (xy 270.214852 -137.105898)
			(xy 270.205898 -137.104183) (xy 270.187814 -137.106378) (xy 270.179546 -137.110216) (xy 270.154934 -137.122563)
			(xy 270.103401 -137.141968) (xy 270.049913 -137.155055) (xy 269.995243 -137.161634) (xy 269.96771 -137.162032)
			(xy 269.940176 -137.161637) (xy 269.885502 -137.155073) (xy 269.832011 -137.141991) (xy 269.780478 -137.122581)
			(xy 269.755874 -137.110216) (xy 269.74762 -137.106326) (xy 269.729519 -137.104119) (xy 269.720568 -137.105898)
			(xy 269.690596 -137.113264) (xy 269.681813 -137.115803) (xy 269.666712 -137.126088) (xy 269.661132 -137.13333)
			(xy 269.644921 -137.155387) (xy 269.607524 -137.19536) (xy 269.565038 -137.229874) (xy 269.518253 -137.258289)
			(xy 269.468037 -137.280077) (xy 269.415325 -137.294832) (xy 269.361095 -137.302281) (xy 269.333726 -137.302748)
			(xy 269.305096 -137.302191) (xy 269.248417 -137.294046) (xy 269.193475 -137.277916) (xy 269.141387 -137.254132)
			(xy 269.093215 -137.223176) (xy 269.049939 -137.18568) (xy 269.01244 -137.142406) (xy 268.981481 -137.094236)
			(xy 268.957693 -137.04215) (xy 268.94156 -136.987208) (xy 268.933411 -136.93053) (xy 268.933411 -136.87327)
			(xy 268.94156 -136.816592) (xy 268.957693 -136.76165) (xy 268.981481 -136.709564) (xy 269.01244 -136.661394)
			(xy 269.049939 -136.61812) (xy 269.093215 -136.580624) (xy 269.141387 -136.549668) (xy 269.193475 -136.525884)
			(xy 269.248417 -136.509754) (xy 269.305096 -136.501609) (xy 269.333726 -136.501124) (xy 269.34864 -136.501235)
			(xy 269.378389 -136.503395) (xy 269.393162 -136.505442) (xy 269.404338 -136.50722) (xy 269.42542 -136.501124)
			(xy 269.492222 -136.443466) (xy 269.500162 -136.43585) (xy 269.509262 -136.415848) (xy 269.509748 -136.404858)
			(xy 269.509748 -136.14019) (xy 269.509233 -136.129202) (xy 269.500163 -136.109191) (xy 269.492222 -136.101582)
			(xy 269.42542 -136.043924) (xy 269.404338 -136.037828) (xy 269.393162 -136.039606) (xy 269.378389 -136.041654)
			(xy 269.34864 -136.043815) (xy 269.333726 -136.043924) (xy 269.305094 -136.043415) (xy 269.248412 -136.035269)
			(xy 269.193466 -136.019139) (xy 269.141376 -135.995353) (xy 269.093201 -135.964395) (xy 269.049922 -135.926897)
			(xy 269.01242 -135.88362) (xy 268.98146 -135.835447) (xy 268.95767 -135.783358) (xy 268.941537 -135.728414)
			(xy 268.933387 -135.671732) (xy 251.455868 -135.671732) (xy 251.452249 -135.674868) (xy 251.406387 -135.704339)
			(xy 251.356798 -135.726983) (xy 251.30449 -135.742338) (xy 251.250529 -135.750093) (xy 251.223272 -135.750554)
			(xy 251.196957 -135.75012) (xy 251.144826 -135.74288) (xy 251.094182 -135.728556) (xy 251.045983 -135.707417)
			(xy 251.00114 -135.679864) (xy 250.960503 -135.646419) (xy 250.942348 -135.627364) (xy 250.934839 -135.619947)
			(xy 250.91555 -135.611429) (xy 250.90501 -135.610854) (xy 250.830334 -135.610854) (xy 250.819787 -135.611401)
			(xy 250.800492 -135.619925) (xy 250.792996 -135.627364) (xy 250.774848 -135.646427) (xy 250.734215 -135.679881)
			(xy 250.689373 -135.707437) (xy 250.641171 -135.728574) (xy 250.590523 -135.74289) (xy 250.538388 -135.750115)
			(xy 250.512072 -135.750554) (xy 250.484825 -135.749974) (xy 250.430887 -135.742215) (xy 250.378602 -135.726859)
			(xy 250.329035 -135.704219) (xy 250.283193 -135.674756) (xy 250.242011 -135.639069) (xy 250.206327 -135.597884)
			(xy 250.176867 -135.552041) (xy 250.154231 -135.502472) (xy 250.138879 -135.450185) (xy 250.131124 -135.396247)
			(xy 244.225283 -135.396247) (xy 244.216517 -135.403842) (xy 244.170661 -135.433307) (xy 244.121079 -135.455946)
			(xy 244.068779 -135.471299) (xy 244.014827 -135.479052) (xy 243.987574 -135.479536) (xy 243.960202 -135.479101)
			(xy 243.906021 -135.471278) (xy 243.853517 -135.455782) (xy 243.803771 -135.432933) (xy 243.757806 -135.403201)
			(xy 243.736876 -135.385556) (xy 243.736622 -135.385302) (xy 243.729533 -135.379719) (xy 243.712618 -135.37347)
			(xy 243.703602 -135.37311) (xy 243.636546 -135.37311) (xy 243.627531 -135.373487) (xy 243.610614 -135.379721)
			(xy 243.603526 -135.385302) (xy 243.603526 -135.385556) (xy 243.603272 -135.385556) (xy 243.582339 -135.403197)
			(xy 243.536371 -135.432921) (xy 243.486625 -135.455767) (xy 243.434123 -135.471263) (xy 243.379945 -135.479092)
			(xy 243.325203 -135.479092) (xy 243.271025 -135.471263) (xy 243.218523 -135.455767) (xy 243.168777 -135.432921)
			(xy 243.122809 -135.403197) (xy 243.101876 -135.385556) (xy 243.101622 -135.385302) (xy 243.094533 -135.379719)
			(xy 243.077618 -135.37347) (xy 243.068602 -135.37311) (xy 243.001546 -135.37311) (xy 242.992531 -135.373487)
			(xy 242.975614 -135.379721) (xy 242.968526 -135.385302) (xy 242.968526 -135.385556) (xy 242.968272 -135.385556)
			(xy 242.947318 -135.403168) (xy 242.901352 -135.432885) (xy 242.85161 -135.455727) (xy 242.799114 -135.471225)
			(xy 242.744942 -135.479059) (xy 242.717574 -135.479536) (xy 242.688658 -135.478989) (xy 242.631487 -135.470269)
			(xy 242.576288 -135.453018) (xy 242.524325 -135.427632) (xy 242.476791 -135.394693) (xy 242.434774 -135.354954)
			(xy 242.416584 -135.33247) (xy 242.408767 -135.323508) (xy 242.38732 -135.313305) (xy 242.375436 -135.312912)
			(xy 242.281964 -135.314944) (xy 242.260628 -135.32612) (xy 242.25377 -135.336026) (xy 242.238348 -135.356918)
			(xy 242.202774 -135.394744) (xy 242.162398 -135.427397) (xy 242.117968 -135.454274) (xy 242.070303 -135.474877)
			(xy 242.020285 -135.488827) (xy 241.968837 -135.495865) (xy 241.942874 -135.4963) (xy 241.915623 -135.495828)
			(xy 241.861677 -135.488069) (xy 241.809385 -135.472711) (xy 241.75981 -135.450068) (xy 241.713962 -135.4206)
			(xy 241.672774 -135.384908) (xy 241.637084 -135.343718) (xy 241.60762 -135.297868) (xy 241.58498 -135.248291)
			(xy 241.569626 -135.195997) (xy 241.56187 -135.142051) (xy 239.010845 -135.142051) (xy 238.98617 -135.170528)
			(xy 238.944979 -135.206219) (xy 238.899129 -135.235685) (xy 238.849552 -135.258327) (xy 238.797257 -135.273682)
			(xy 238.743309 -135.281438) (xy 238.688807 -135.281438) (xy 238.634859 -135.273682) (xy 238.582564 -135.258327)
			(xy 238.532987 -135.235685) (xy 238.487137 -135.206219) (xy 238.445946 -135.170528) (xy 238.410255 -135.129337)
			(xy 238.380789 -135.083487) (xy 238.358147 -135.03391) (xy 238.342792 -134.981615) (xy 238.335036 -134.927667)
			(xy 238.33455 -134.900416) (xy 235.34878 -134.900416) (xy 235.34878 -135.689594) (xy 239.483136 -135.689594)
			(xy 239.487207 -135.633972) (xy 239.499333 -135.579535) (xy 239.519256 -135.527444) (xy 239.546552 -135.478809)
			(xy 239.580638 -135.434666) (xy 239.620787 -135.395957) (xy 239.666145 -135.363506) (xy 239.715745 -135.338005)
			(xy 239.768529 -135.319998) (xy 239.823372 -135.309868) (xy 239.879106 -135.307831) (xy 239.934543 -135.313931)
			(xy 239.9885 -135.328037) (xy 240.039829 -135.349849) (xy 240.087435 -135.378903) (xy 240.130303 -135.414578)
			(xy 240.16752 -135.456115) (xy 240.198293 -135.502628) (xy 240.221965 -135.553125) (xy 240.238033 -135.606532)
			(xy 240.246153 -135.661708) (xy 240.246662 -135.689594) (xy 240.246153 -135.71748) (xy 240.238033 -135.772656)
			(xy 240.221965 -135.826063) (xy 240.202828 -135.866886) (xy 240.639852 -135.866886) (xy 240.643923 -135.811264)
			(xy 240.656049 -135.756827) (xy 240.675972 -135.704736) (xy 240.703268 -135.656101) (xy 240.737354 -135.611958)
			(xy 240.777503 -135.573249) (xy 240.822861 -135.540798) (xy 240.872461 -135.515297) (xy 240.925245 -135.49729)
			(xy 240.980088 -135.48716) (xy 241.035822 -135.485123) (xy 241.091259 -135.491223) (xy 241.145216 -135.505329)
			(xy 241.196545 -135.527141) (xy 241.244151 -135.556195) (xy 241.287019 -135.59187) (xy 241.324236 -135.633407)
			(xy 241.355009 -135.67992) (xy 241.378681 -135.730417) (xy 241.394749 -135.783824) (xy 241.402869 -135.839)
			(xy 241.403378 -135.866886) (xy 241.402869 -135.894772) (xy 241.394749 -135.949948) (xy 241.378681 -136.003355)
			(xy 241.355009 -136.053852) (xy 241.324236 -136.100365) (xy 241.287019 -136.141902) (xy 241.244151 -136.177577)
			(xy 241.196545 -136.206631) (xy 241.145216 -136.228443) (xy 241.091259 -136.242549) (xy 241.035822 -136.248649)
			(xy 240.980088 -136.246612) (xy 240.925245 -136.236482) (xy 240.872461 -136.218475) (xy 240.822861 -136.192974)
			(xy 240.777503 -136.160523) (xy 240.737354 -136.121814) (xy 240.703268 -136.077671) (xy 240.675972 -136.029036)
			(xy 240.656049 -135.976945) (xy 240.643923 -135.922508) (xy 240.639852 -135.866886) (xy 240.202828 -135.866886)
			(xy 240.198293 -135.87656) (xy 240.16752 -135.923073) (xy 240.130303 -135.96461) (xy 240.087435 -136.000285)
			(xy 240.039829 -136.029339) (xy 239.9885 -136.051151) (xy 239.934543 -136.065257) (xy 239.879106 -136.071357)
			(xy 239.823372 -136.06932) (xy 239.768529 -136.05919) (xy 239.715745 -136.041183) (xy 239.666145 -136.015682)
			(xy 239.620787 -135.983231) (xy 239.580638 -135.944522) (xy 239.546552 -135.900379) (xy 239.519256 -135.851744)
			(xy 239.499333 -135.799653) (xy 239.487207 -135.745216) (xy 239.483136 -135.689594) (xy 235.34878 -135.689594)
			(xy 235.34878 -136.328404) (xy 238.37595 -136.328404) (xy 238.380021 -136.272782) (xy 238.392147 -136.218345)
			(xy 238.41207 -136.166254) (xy 238.439366 -136.117619) (xy 238.473452 -136.073476) (xy 238.513601 -136.034767)
			(xy 238.558959 -136.002316) (xy 238.608559 -135.976815) (xy 238.661343 -135.958808) (xy 238.716186 -135.948678)
			(xy 238.77192 -135.946641) (xy 238.827357 -135.952741) (xy 238.881314 -135.966847) (xy 238.932643 -135.988659)
			(xy 238.980249 -136.017713) (xy 239.023117 -136.053388) (xy 239.060334 -136.094925) (xy 239.091107 -136.141438)
			(xy 239.114779 -136.191935) (xy 239.130847 -136.245342) (xy 239.138967 -136.300518) (xy 239.139476 -136.328404)
			(xy 239.138967 -136.35629) (xy 239.130847 -136.411466) (xy 239.114779 -136.464873) (xy 239.091107 -136.51537)
			(xy 239.060334 -136.561883) (xy 239.023117 -136.60342) (xy 238.980249 -136.639095) (xy 238.932643 -136.668149)
			(xy 238.881314 -136.689961) (xy 238.827357 -136.704067) (xy 238.77192 -136.710167) (xy 238.716186 -136.70813)
			(xy 238.661343 -136.698) (xy 238.608559 -136.679993) (xy 238.558959 -136.654492) (xy 238.513601 -136.622041)
			(xy 238.473452 -136.583332) (xy 238.439366 -136.539189) (xy 238.41207 -136.490554) (xy 238.392147 -136.438463)
			(xy 238.380021 -136.384026) (xy 238.37595 -136.328404) (xy 235.34878 -136.328404) (xy 235.34878 -137.344404)
			(xy 238.37595 -137.344404) (xy 238.380021 -137.288782) (xy 238.392147 -137.234345) (xy 238.41207 -137.182254)
			(xy 238.439366 -137.133619) (xy 238.473452 -137.089476) (xy 238.513601 -137.050767) (xy 238.558959 -137.018316)
			(xy 238.608559 -136.992815) (xy 238.661343 -136.974808) (xy 238.716186 -136.964678) (xy 238.77192 -136.962641)
			(xy 238.827357 -136.968741) (xy 238.881314 -136.982847) (xy 238.932643 -137.004659) (xy 238.980249 -137.033713)
			(xy 239.023117 -137.069388) (xy 239.060334 -137.110925) (xy 239.091107 -137.157438) (xy 239.114779 -137.207935)
			(xy 239.130847 -137.261342) (xy 239.138967 -137.316518) (xy 239.139476 -137.344404) (xy 239.138967 -137.37229)
			(xy 239.130847 -137.427466) (xy 239.124582 -137.44829) (xy 240.54511 -137.44829) (xy 240.549181 -137.392668)
			(xy 240.561307 -137.338231) (xy 240.58123 -137.28614) (xy 240.608526 -137.237505) (xy 240.642612 -137.193362)
			(xy 240.682761 -137.154653) (xy 240.728119 -137.122202) (xy 240.777719 -137.096701) (xy 240.830503 -137.078694)
			(xy 240.885346 -137.068564) (xy 240.94108 -137.066527) (xy 240.996517 -137.072627) (xy 241.050474 -137.086733)
			(xy 241.101803 -137.108545) (xy 241.149409 -137.137599) (xy 241.192277 -137.173274) (xy 241.229494 -137.214811)
			(xy 241.260267 -137.261324) (xy 241.267302 -137.276332) (xy 245.24716 -137.276332) (xy 245.247563 -137.250016)
			(xy 245.254808 -137.197884) (xy 245.269139 -137.147239) (xy 245.290283 -137.09904) (xy 245.317842 -137.054198)
			(xy 245.351292 -137.013562) (xy 245.37035 -136.995408) (xy 245.377743 -136.987879) (xy 245.386274 -136.968605)
			(xy 245.38686 -136.95807) (xy 245.38686 -136.883394) (xy 245.386359 -136.872841) (xy 245.377805 -136.853545)
			(xy 245.37035 -136.846056) (xy 245.351271 -136.827925) (xy 245.317818 -136.787289) (xy 245.290263 -136.742443)
			(xy 245.269129 -136.694238) (xy 245.254816 -136.643586) (xy 245.247596 -136.591449) (xy 245.24716 -136.565132)
			(xy 245.247646 -136.537881) (xy 245.255402 -136.483933) (xy 245.270757 -136.431638) (xy 245.293399 -136.382061)
			(xy 245.322865 -136.336211) (xy 245.358556 -136.29502) (xy 245.399747 -136.259329) (xy 245.445597 -136.229863)
			(xy 245.495174 -136.207221) (xy 245.547469 -136.191866) (xy 245.601417 -136.18411) (xy 245.655919 -136.18411)
			(xy 245.709867 -136.191866) (xy 245.762162 -136.207221) (xy 245.811739 -136.229863) (xy 245.857589 -136.259329)
			(xy 245.89878 -136.29502) (xy 245.934471 -136.336211) (xy 245.963937 -136.382061) (xy 245.986579 -136.431638)
			(xy 246.001934 -136.483933) (xy 246.00969 -136.537881) (xy 246.010176 -136.565132) (xy 246.009738 -136.591447)
			(xy 246.002498 -136.643577) (xy 245.988174 -136.694221) (xy 245.967036 -136.74242) (xy 245.939484 -136.787262)
			(xy 245.90604 -136.827901) (xy 245.886986 -136.846056) (xy 245.8796 -136.85359) (xy 245.871067 -136.872861)
			(xy 245.870476 -136.883394) (xy 245.870476 -136.95807) (xy 245.871015 -136.968618) (xy 245.879544 -136.987913)
			(xy 245.886986 -136.995408) (xy 245.906036 -137.013569) (xy 245.939494 -137.054198) (xy 245.967054 -137.099036)
			(xy 245.988194 -137.147236) (xy 246.002512 -137.197883) (xy 246.009737 -137.250016) (xy 246.010176 -137.276332)
			(xy 246.00969 -137.303583) (xy 246.001934 -137.357531) (xy 245.986579 -137.409826) (xy 245.963937 -137.459403)
			(xy 245.934471 -137.505253) (xy 245.89878 -137.546444) (xy 245.857589 -137.582135) (xy 245.811739 -137.611601)
			(xy 245.762162 -137.634243) (xy 245.709867 -137.649598) (xy 245.655919 -137.657354) (xy 245.601417 -137.657354)
			(xy 245.547469 -137.649598) (xy 245.495174 -137.634243) (xy 245.445597 -137.611601) (xy 245.399747 -137.582135)
			(xy 245.358556 -137.546444) (xy 245.322865 -137.505253) (xy 245.293399 -137.459403) (xy 245.270757 -137.409826)
			(xy 245.255402 -137.357531) (xy 245.247646 -137.303583) (xy 245.24716 -137.276332) (xy 241.267302 -137.276332)
			(xy 241.283939 -137.311821) (xy 241.300007 -137.365228) (xy 241.308127 -137.420404) (xy 241.308636 -137.44829)
			(xy 241.308127 -137.476176) (xy 241.300007 -137.531352) (xy 241.283939 -137.584759) (xy 241.260267 -137.635256)
			(xy 241.229494 -137.681769) (xy 241.192277 -137.723306) (xy 241.18823 -137.726674) (xy 246.187722 -137.726674)
			(xy 246.188167 -137.699303) (xy 246.195989 -137.645123) (xy 246.211483 -137.592619) (xy 246.234329 -137.542873)
			(xy 246.264059 -137.496907) (xy 246.281702 -137.475976) (xy 246.281956 -137.475722) (xy 246.287546 -137.468638)
			(xy 246.293789 -137.451719) (xy 246.294148 -137.442702) (xy 246.294148 -137.375646) (xy 246.29378 -137.36663)
			(xy 246.287541 -137.349712) (xy 246.281956 -137.342626) (xy 246.281702 -137.342626) (xy 246.281702 -137.342372)
			(xy 246.264084 -137.321423) (xy 246.234369 -137.275455) (xy 246.211529 -137.225712) (xy 246.196033 -137.173215)
			(xy 246.188199 -137.119042) (xy 246.187722 -137.091674) (xy 246.188208 -137.064423) (xy 246.195964 -137.010475)
			(xy 246.211319 -136.95818) (xy 246.233961 -136.908603) (xy 246.263427 -136.862753) (xy 246.299118 -136.821562)
			(xy 246.340309 -136.785871) (xy 246.386159 -136.756405) (xy 246.435736 -136.733763) (xy 246.488031 -136.718408)
			(xy 246.541979 -136.710652) (xy 246.596481 -136.710652) (xy 246.650429 -136.718408) (xy 246.702724 -136.733763)
			(xy 246.752301 -136.756405) (xy 246.798151 -136.785871) (xy 246.839342 -136.821562) (xy 246.875033 -136.862753)
			(xy 246.904499 -136.908603) (xy 246.927141 -136.95818) (xy 246.942496 -137.010475) (xy 246.950252 -137.064423)
			(xy 246.950738 -137.091674) (xy 246.950272 -137.119044) (xy 246.942456 -137.173224) (xy 246.926968 -137.225728)
			(xy 246.904126 -137.275475) (xy 246.8744 -137.321441) (xy 246.856758 -137.342372) (xy 246.856504 -137.342626)
			(xy 246.850943 -137.34973) (xy 246.844681 -137.366633) (xy 246.844312 -137.375646) (xy 246.844312 -137.442702)
			(xy 246.844665 -137.451719) (xy 246.850915 -137.468636) (xy 246.856504 -137.475722) (xy 246.856758 -137.475722)
			(xy 246.856758 -137.475976) (xy 246.874393 -137.496912) (xy 246.904107 -137.542883) (xy 246.926944 -137.592629)
			(xy 246.942436 -137.645129) (xy 246.950264 -137.699305) (xy 246.950738 -137.726674) (xy 246.950252 -137.753925)
			(xy 246.942496 -137.807873) (xy 246.927141 -137.860168) (xy 246.904499 -137.909745) (xy 246.875033 -137.955595)
			(xy 246.839342 -137.996786) (xy 246.798151 -138.032477) (xy 246.752301 -138.061943) (xy 246.702724 -138.084585)
			(xy 246.650429 -138.09994) (xy 246.596481 -138.107696) (xy 246.541979 -138.107696) (xy 246.488031 -138.09994)
			(xy 246.435736 -138.084585) (xy 246.386159 -138.061943) (xy 246.340309 -138.032477) (xy 246.299118 -137.996786)
			(xy 246.263427 -137.955595) (xy 246.233961 -137.909745) (xy 246.211319 -137.860168) (xy 246.195964 -137.807873)
			(xy 246.188208 -137.753925) (xy 246.187722 -137.726674) (xy 241.18823 -137.726674) (xy 241.149409 -137.758981)
			(xy 241.101803 -137.788035) (xy 241.050474 -137.809847) (xy 240.996517 -137.823953) (xy 240.94108 -137.830053)
			(xy 240.885346 -137.828016) (xy 240.830503 -137.817886) (xy 240.777719 -137.799879) (xy 240.728119 -137.774378)
			(xy 240.682761 -137.741927) (xy 240.642612 -137.703218) (xy 240.608526 -137.659075) (xy 240.58123 -137.61044)
			(xy 240.561307 -137.558349) (xy 240.549181 -137.503912) (xy 240.54511 -137.44829) (xy 239.124582 -137.44829)
			(xy 239.114779 -137.480873) (xy 239.091107 -137.53137) (xy 239.060334 -137.577883) (xy 239.023117 -137.61942)
			(xy 238.980249 -137.655095) (xy 238.932643 -137.684149) (xy 238.881314 -137.705961) (xy 238.827357 -137.720067)
			(xy 238.77192 -137.726167) (xy 238.716186 -137.72413) (xy 238.661343 -137.714) (xy 238.608559 -137.695993)
			(xy 238.558959 -137.670492) (xy 238.513601 -137.638041) (xy 238.473452 -137.599332) (xy 238.439366 -137.555189)
			(xy 238.41207 -137.506554) (xy 238.392147 -137.454463) (xy 238.380021 -137.400026) (xy 238.37595 -137.344404)
			(xy 235.34878 -137.344404) (xy 235.34878 -137.875518) (xy 235.348369 -137.885589) (xy 235.340639 -137.904187)
			(xy 235.333794 -137.911586) (xy 234.884976 -138.360404) (xy 238.37595 -138.360404) (xy 238.380021 -138.304782)
			(xy 238.392147 -138.250345) (xy 238.41207 -138.198254) (xy 238.439366 -138.149619) (xy 238.473452 -138.105476)
			(xy 238.513601 -138.066767) (xy 238.558959 -138.034316) (xy 238.608559 -138.008815) (xy 238.661343 -137.990808)
			(xy 238.716186 -137.980678) (xy 238.77192 -137.978641) (xy 238.827357 -137.984741) (xy 238.881314 -137.998847)
			(xy 238.932643 -138.020659) (xy 238.980249 -138.049713) (xy 239.023117 -138.085388) (xy 239.060334 -138.126925)
			(xy 239.091107 -138.173438) (xy 239.114779 -138.223935) (xy 239.130847 -138.277342) (xy 239.138967 -138.332518)
			(xy 239.139476 -138.360404) (xy 239.138967 -138.38829) (xy 239.136754 -138.40333) (xy 247.396254 -138.40333)
			(xy 247.396765 -138.375665) (xy 247.404761 -138.320914) (xy 247.420576 -138.267891) (xy 247.443879 -138.217707)
			(xy 247.474181 -138.171411) (xy 247.510848 -138.129973) (xy 247.553112 -138.094262) (xy 247.57634 -138.079226)
			(xy 247.586005 -138.072575) (xy 247.598456 -138.052725) (xy 247.600216 -138.041126) (xy 247.60809 -137.961116)
			(xy 247.608693 -137.949479) (xy 247.600631 -137.927644) (xy 247.592596 -137.919206) (xy 247.592342 -137.918952)
			(xy 247.573763 -137.900868) (xy 247.541183 -137.860538) (xy 247.514369 -137.816164) (xy 247.493815 -137.768566)
			(xy 247.479902 -137.718622) (xy 247.472885 -137.667253) (xy 247.472454 -137.64133) (xy 247.473006 -137.614081)
			(xy 247.480757 -137.560138) (xy 247.496107 -137.507847) (xy 247.518742 -137.458272) (xy 247.548201 -137.412424)
			(xy 247.583886 -137.371234) (xy 247.625069 -137.335542) (xy 247.670913 -137.306074) (xy 247.720483 -137.283431)
			(xy 247.772771 -137.268072) (xy 247.826713 -137.260311) (xy 247.853962 -137.259822) (xy 247.881332 -137.260305)
			(xy 247.93551 -137.268118) (xy 247.988013 -137.283603) (xy 248.037761 -137.306441) (xy 248.083728 -137.336162)
			(xy 248.10466 -137.353802) (xy 248.104914 -137.354056) (xy 248.111988 -137.359661) (xy 248.128915 -137.365895)
			(xy 248.137934 -137.366248) (xy 248.20499 -137.366248) (xy 248.214008 -137.365897) (xy 248.230925 -137.359647)
			(xy 248.23801 -137.354056) (xy 248.23801 -137.353802) (xy 248.238264 -137.353802) (xy 248.259199 -137.336167)
			(xy 248.305171 -137.306454) (xy 248.354918 -137.283617) (xy 248.407418 -137.268126) (xy 248.461593 -137.260296)
			(xy 248.488962 -137.259822) (xy 248.516215 -137.260291) (xy 248.570168 -137.268043) (xy 248.622467 -137.283396)
			(xy 248.672049 -137.306036) (xy 248.717904 -137.335503) (xy 248.759098 -137.371197) (xy 248.794792 -137.41239)
			(xy 248.82426 -137.458244) (xy 248.846901 -137.507825) (xy 248.862255 -137.560125) (xy 248.870009 -137.614077)
			(xy 248.87047 -137.64133) (xy 248.869913 -137.670246) (xy 248.861194 -137.727416) (xy 248.843944 -137.782614)
			(xy 248.81856 -137.834576) (xy 248.785623 -137.882111) (xy 248.745887 -137.924129) (xy 248.723404 -137.94232)
			(xy 248.714598 -137.949929) (xy 248.704414 -137.970828) (xy 248.703846 -137.982452) (xy 248.703846 -138.062208)
			(xy 248.704379 -138.073841) (xy 248.71457 -138.094752) (xy 248.723404 -138.10234) (xy 248.745907 -138.120507)
			(xy 248.785641 -138.162532) (xy 248.818578 -138.210072) (xy 248.843963 -138.262038) (xy 248.861215 -138.31724)
			(xy 248.869938 -138.374413) (xy 248.87047 -138.40333) (xy 248.870073 -138.430585) (xy 248.862311 -138.484541)
			(xy 248.850205 -138.525758) (xy 249.141742 -138.525758) (xy 249.142232 -138.498389) (xy 249.150042 -138.44421)
			(xy 249.165525 -138.391707) (xy 249.188362 -138.341959) (xy 249.218082 -138.295992) (xy 249.235722 -138.27506)
			(xy 249.235976 -138.274806) (xy 249.241575 -138.267728) (xy 249.247812 -138.250804) (xy 249.248168 -138.241786)
			(xy 249.248168 -138.17473) (xy 249.247803 -138.165714) (xy 249.241562 -138.148796) (xy 249.235976 -138.14171)
			(xy 249.235722 -138.14171) (xy 249.235722 -138.141456) (xy 249.21804 -138.120556) (xy 249.188318 -138.074583)
			(xy 249.165475 -138.024831) (xy 249.149982 -137.972324) (xy 249.142158 -137.918141) (xy 249.142162 -137.863396)
			(xy 249.149996 -137.809214) (xy 249.165497 -137.75671) (xy 249.188348 -137.706962) (xy 249.218079 -137.660993)
			(xy 249.235722 -137.64006) (xy 249.235976 -137.639806) (xy 249.241575 -137.632728) (xy 249.247812 -137.615804)
			(xy 249.248168 -137.606786) (xy 249.248168 -137.53973) (xy 249.247803 -137.530714) (xy 249.241562 -137.513796)
			(xy 249.235976 -137.50671) (xy 249.235722 -137.50671) (xy 249.235722 -137.506456) (xy 249.21804 -137.485556)
			(xy 249.188318 -137.439583) (xy 249.165475 -137.389831) (xy 249.149982 -137.337324) (xy 249.142158 -137.283141)
			(xy 249.142162 -137.228396) (xy 249.149996 -137.174214) (xy 249.165497 -137.12171) (xy 249.188348 -137.071962)
			(xy 249.218079 -137.025993) (xy 249.235722 -137.00506) (xy 249.235976 -137.004806) (xy 249.241575 -136.997728)
			(xy 249.247812 -136.980804) (xy 249.248168 -136.971786) (xy 249.248168 -136.90473) (xy 249.247803 -136.895714)
			(xy 249.241562 -136.878796) (xy 249.235976 -136.87171) (xy 249.235722 -136.87171) (xy 249.235722 -136.871456)
			(xy 249.218099 -136.850511) (xy 249.188384 -136.804542) (xy 249.165545 -136.754798) (xy 249.15005 -136.7023)
			(xy 249.142218 -136.648126) (xy 249.141742 -136.620758) (xy 249.142228 -136.593507) (xy 249.149984 -136.539559)
			(xy 249.165339 -136.487264) (xy 249.187981 -136.437687) (xy 249.217447 -136.391837) (xy 249.253138 -136.350646)
			(xy 249.294329 -136.314955) (xy 249.340179 -136.285489) (xy 249.389756 -136.262847) (xy 249.442051 -136.247492)
			(xy 249.495999 -136.239736) (xy 249.550501 -136.239736) (xy 249.559488 -136.241028) (xy 267.556486 -136.241028)
			(xy 267.560557 -136.185406) (xy 267.572683 -136.130969) (xy 267.592606 -136.078878) (xy 267.619902 -136.030243)
			(xy 267.653988 -135.9861) (xy 267.694137 -135.947391) (xy 267.739495 -135.91494) (xy 267.789095 -135.889439)
			(xy 267.841879 -135.871432) (xy 267.896722 -135.861302) (xy 267.952456 -135.859265) (xy 268.007893 -135.865365)
			(xy 268.06185 -135.879471) (xy 268.113179 -135.901283) (xy 268.160785 -135.930337) (xy 268.203653 -135.966012)
			(xy 268.24087 -136.007549) (xy 268.271643 -136.054062) (xy 268.295315 -136.104559) (xy 268.311383 -136.157966)
			(xy 268.319503 -136.213142) (xy 268.320012 -136.241028) (xy 268.319503 -136.268914) (xy 268.311383 -136.32409)
			(xy 268.295315 -136.377497) (xy 268.271643 -136.427994) (xy 268.24087 -136.474507) (xy 268.203653 -136.516044)
			(xy 268.160785 -136.551719) (xy 268.113179 -136.580773) (xy 268.06185 -136.602585) (xy 268.007893 -136.616691)
			(xy 267.952456 -136.622791) (xy 267.896722 -136.620754) (xy 267.841879 -136.610624) (xy 267.789095 -136.592617)
			(xy 267.739495 -136.567116) (xy 267.694137 -136.534665) (xy 267.653988 -136.495956) (xy 267.619902 -136.451813)
			(xy 267.592606 -136.403178) (xy 267.572683 -136.351087) (xy 267.560557 -136.29665) (xy 267.556486 -136.241028)
			(xy 249.559488 -136.241028) (xy 249.604449 -136.247492) (xy 249.656744 -136.262847) (xy 249.706321 -136.285489)
			(xy 249.752171 -136.314955) (xy 249.793362 -136.350646) (xy 249.829053 -136.391837) (xy 249.858519 -136.437687)
			(xy 249.881161 -136.487264) (xy 249.896516 -136.539559) (xy 249.904272 -136.593507) (xy 249.904758 -136.620758)
			(xy 249.904278 -136.648128) (xy 249.896465 -136.702307) (xy 249.88098 -136.75481) (xy 249.858141 -136.804557)
			(xy 249.828418 -136.850524) (xy 249.810778 -136.871456) (xy 249.810524 -136.87171) (xy 249.804918 -136.878783)
			(xy 249.798685 -136.895711) (xy 249.798332 -136.90473) (xy 249.798332 -136.971786) (xy 249.798689 -136.980803)
			(xy 249.804936 -136.99772) (xy 249.810524 -137.004806) (xy 249.810778 -137.004806) (xy 249.810778 -137.00506)
			(xy 249.828377 -137.026026) (xy 249.858103 -137.071988) (xy 249.880951 -137.121729) (xy 249.89645 -137.174226)
			(xy 249.904283 -137.2284) (xy 249.904287 -137.283137) (xy 249.896464 -137.337312) (xy 249.880973 -137.389812)
			(xy 249.858134 -137.439556) (xy 249.828415 -137.485523) (xy 249.810778 -137.506456) (xy 249.810524 -137.50671)
			(xy 249.804918 -137.513783) (xy 249.798685 -137.530711) (xy 249.798332 -137.53973) (xy 249.798332 -137.606786)
			(xy 249.798689 -137.615803) (xy 249.804936 -137.63272) (xy 249.810524 -137.639806) (xy 249.810778 -137.639806)
			(xy 249.810778 -137.64006) (xy 249.828377 -137.661026) (xy 249.858103 -137.706988) (xy 249.880951 -137.756729)
			(xy 249.89645 -137.809226) (xy 249.904283 -137.8634) (xy 249.904287 -137.918137) (xy 249.896464 -137.972312)
			(xy 249.880973 -138.024812) (xy 249.858134 -138.074556) (xy 249.828415 -138.120523) (xy 249.810778 -138.141456)
			(xy 249.810524 -138.14171) (xy 249.804918 -138.148783) (xy 249.798685 -138.165711) (xy 249.798332 -138.17473)
			(xy 249.798332 -138.241786) (xy 249.798689 -138.250803) (xy 249.804936 -138.26772) (xy 249.810524 -138.274806)
			(xy 249.810778 -138.274806) (xy 249.810778 -138.27506) (xy 249.828408 -138.295999) (xy 249.858122 -138.34197)
			(xy 249.88096 -138.391715) (xy 249.896453 -138.444215) (xy 249.904283 -138.498389) (xy 249.904758 -138.525758)
			(xy 249.904257 -138.554374) (xy 249.895719 -138.610964) (xy 249.878815 -138.665642) (xy 249.853924 -138.717177)
			(xy 249.821605 -138.764409) (xy 249.782587 -138.806278) (xy 249.760486 -138.824462) (xy 249.760232 -138.824716)
			(xy 249.751694 -138.832326) (xy 249.741807 -138.852918) (xy 249.741182 -138.86434) (xy 249.74169 -138.94435)
			(xy 249.742292 -138.955914) (xy 249.752465 -138.976685) (xy 249.761248 -138.984228) (xy 249.77725 -138.997436)
			(xy 249.777504 -138.99769) (xy 249.784586 -139.003283) (xy 249.801506 -139.009526) (xy 249.810524 -139.009882)
			(xy 249.87758 -139.009882) (xy 249.886596 -139.00952) (xy 249.903514 -139.003276) (xy 249.9106 -138.99769)
			(xy 249.9106 -138.997436) (xy 249.910854 -138.997436) (xy 249.931787 -138.979795) (xy 249.977755 -138.950071)
			(xy 250.027501 -138.927225) (xy 250.080003 -138.911729) (xy 250.134181 -138.9039) (xy 250.188923 -138.9039)
			(xy 250.243101 -138.911729) (xy 250.295603 -138.927225) (xy 250.345349 -138.950071) (xy 250.391317 -138.979795)
			(xy 250.41225 -138.997436) (xy 250.412504 -138.99769) (xy 250.419586 -139.003283) (xy 250.436506 -139.009526)
			(xy 250.445524 -139.009882) (xy 250.51258 -139.009882) (xy 250.521596 -139.00952) (xy 250.538514 -139.003276)
			(xy 250.5456 -138.99769) (xy 250.5456 -138.997436) (xy 250.545854 -138.997436) (xy 250.566787 -138.979795)
			(xy 250.612755 -138.950071) (xy 250.662501 -138.927225) (xy 250.715003 -138.911729) (xy 250.769181 -138.9039)
			(xy 250.823923 -138.9039) (xy 250.878101 -138.911729) (xy 250.930603 -138.927225) (xy 250.980349 -138.950071)
			(xy 251.026317 -138.979795) (xy 251.04725 -138.997436) (xy 251.047504 -138.99769) (xy 251.054586 -139.003283)
			(xy 251.071506 -139.009526) (xy 251.080524 -139.009882) (xy 251.14758 -139.009882) (xy 251.156596 -139.00952)
			(xy 251.173514 -139.003276) (xy 251.1806 -138.99769) (xy 251.1806 -138.997436) (xy 251.180854 -138.997436)
			(xy 251.201797 -138.979811) (xy 251.247766 -138.950095) (xy 251.297511 -138.927256) (xy 251.350009 -138.911762)
			(xy 251.404183 -138.903931) (xy 251.431552 -138.903456) (xy 251.458805 -138.903988) (xy 251.512756 -138.911739)
			(xy 251.565054 -138.927089) (xy 251.614636 -138.949727) (xy 251.660491 -138.979191) (xy 251.701685 -139.014881)
			(xy 251.737381 -139.056071) (xy 251.76685 -139.101922) (xy 251.789494 -139.151501) (xy 251.804851 -139.203797)
			(xy 251.812609 -139.257748) (xy 251.812609 -139.312252) (xy 251.804851 -139.366203) (xy 251.789494 -139.418499)
			(xy 251.76685 -139.468078) (xy 251.737381 -139.513929) (xy 251.701685 -139.555119) (xy 251.660491 -139.590809)
			(xy 251.614636 -139.620273) (xy 251.565054 -139.642911) (xy 251.512756 -139.658261) (xy 251.458805 -139.666012)
			(xy 251.431552 -139.666472) (xy 251.404183 -139.665982) (xy 251.350004 -139.658171) (xy 251.297501 -139.642688)
			(xy 251.247754 -139.619851) (xy 251.201786 -139.590131) (xy 251.180854 -139.572492) (xy 251.1806 -139.572238)
			(xy 251.173523 -139.566638) (xy 251.156599 -139.560401) (xy 251.14758 -139.560046) (xy 251.080524 -139.560046)
			(xy 251.071507 -139.560405) (xy 251.05459 -139.56665) (xy 251.047504 -139.572238) (xy 251.04725 -139.572492)
			(xy 251.026317 -139.590133) (xy 250.980349 -139.619857) (xy 250.930603 -139.642703) (xy 250.878101 -139.658199)
			(xy 250.823923 -139.666028) (xy 250.769181 -139.666028) (xy 250.715003 -139.658199) (xy 250.662501 -139.642703)
			(xy 250.612755 -139.619857) (xy 250.566787 -139.590133) (xy 250.545854 -139.572492) (xy 250.5456 -139.572238)
			(xy 250.538523 -139.566638) (xy 250.521599 -139.560401) (xy 250.51258 -139.560046) (xy 250.445524 -139.560046)
			(xy 250.436507 -139.560405) (xy 250.41959 -139.56665) (xy 250.412504 -139.572238) (xy 250.412504 -139.572492)
			(xy 250.41225 -139.572492) (xy 250.391317 -139.590133) (xy 250.345349 -139.619857) (xy 250.295603 -139.642703)
			(xy 250.243101 -139.658199) (xy 250.188923 -139.666028) (xy 250.134181 -139.666028) (xy 250.080003 -139.658199)
			(xy 250.027501 -139.642703) (xy 249.977755 -139.619857) (xy 249.931787 -139.590133) (xy 249.910854 -139.572492)
			(xy 249.9106 -139.572238) (xy 249.903523 -139.566638) (xy 249.886599 -139.560401) (xy 249.87758 -139.560046)
			(xy 249.810524 -139.560046) (xy 249.801507 -139.560405) (xy 249.78459 -139.56665) (xy 249.777504 -139.572238)
			(xy 249.777504 -139.572492) (xy 249.77725 -139.572492) (xy 249.756309 -139.59012) (xy 249.710339 -139.619834)
			(xy 249.660593 -139.642672) (xy 249.608095 -139.658166) (xy 249.553921 -139.665997) (xy 249.526552 -139.666472)
			(xy 249.499298 -139.666067) (xy 249.445345 -139.658303) (xy 249.393047 -139.64294) (xy 249.343467 -139.62029)
			(xy 249.297615 -139.590816) (xy 249.256425 -139.555116) (xy 249.220734 -139.513917) (xy 249.191269 -139.468059)
			(xy 249.168631 -139.418474) (xy 249.153279 -139.366172) (xy 249.145527 -139.312218) (xy 249.145044 -139.284964)
			(xy 249.14556 -139.256349) (xy 249.154094 -139.199759) (xy 249.170996 -139.145081) (xy 249.195884 -139.093547)
			(xy 249.2282 -139.046313) (xy 249.267216 -139.004444) (xy 249.289316 -138.98626) (xy 249.28957 -138.986006)
			(xy 249.298099 -138.978387) (xy 249.307991 -138.957802) (xy 249.30862 -138.946382) (xy 249.308112 -138.866372)
			(xy 249.307496 -138.85481) (xy 249.297333 -138.834039) (xy 249.288554 -138.826494) (xy 249.266101 -138.808313)
			(xy 249.226429 -138.766317) (xy 249.193545 -138.718817) (xy 249.168202 -138.666901) (xy 249.150979 -138.611756)
			(xy 249.142272 -138.554644) (xy 249.141742 -138.525758) (xy 248.850205 -138.525758) (xy 248.846949 -138.536842)
			(xy 248.8243 -138.586425) (xy 248.794826 -138.63228) (xy 248.759125 -138.673473) (xy 248.717925 -138.709166)
			(xy 248.672065 -138.738633) (xy 248.622478 -138.761273) (xy 248.570174 -138.776625) (xy 248.516217 -138.784378)
			(xy 248.488962 -138.784838) (xy 248.462646 -138.784416) (xy 248.410515 -138.777174) (xy 248.359871 -138.762848)
			(xy 248.311671 -138.741707) (xy 248.266829 -138.714152) (xy 248.226192 -138.680704) (xy 248.208038 -138.661648)
			(xy 248.200498 -138.654268) (xy 248.181232 -138.64573) (xy 248.1707 -138.645138) (xy 248.096024 -138.645138)
			(xy 248.085473 -138.645655) (xy 248.066177 -138.654197) (xy 248.058686 -138.661648) (xy 248.04054 -138.680712)
			(xy 247.999907 -138.714167) (xy 247.955064 -138.741724) (xy 247.906862 -138.76286) (xy 247.856213 -138.777176)
			(xy 247.804079 -138.7844) (xy 247.777762 -138.784838) (xy 247.750511 -138.784358) (xy 247.696565 -138.776597)
			(xy 247.644272 -138.761238) (xy 247.594696 -138.738595) (xy 247.548848 -138.709127) (xy 247.507659 -138.673436)
			(xy 247.471968 -138.632246) (xy 247.442501 -138.586397) (xy 247.419859 -138.536821) (xy 247.404502 -138.484527)
			(xy 247.396742 -138.430581) (xy 247.396254 -138.40333) (xy 239.136754 -138.40333) (xy 239.130847 -138.443466)
			(xy 239.114779 -138.496873) (xy 239.091107 -138.54737) (xy 239.060334 -138.593883) (xy 239.023117 -138.63542)
			(xy 238.980249 -138.671095) (xy 238.932643 -138.700149) (xy 238.881314 -138.721961) (xy 238.827357 -138.736067)
			(xy 238.77192 -138.742167) (xy 238.716186 -138.74013) (xy 238.661343 -138.73) (xy 238.608559 -138.711993)
			(xy 238.558959 -138.686492) (xy 238.513601 -138.654041) (xy 238.473452 -138.615332) (xy 238.439366 -138.571189)
			(xy 238.41207 -138.522554) (xy 238.392147 -138.470463) (xy 238.380021 -138.416026) (xy 238.37595 -138.360404)
			(xy 234.884976 -138.360404) (xy 234.551982 -138.693398) (xy 234.544582 -138.700238) (xy 234.525983 -138.707958)
			(xy 234.515914 -138.708384) (xy 233.675174 -138.708384) (xy 233.64861 -138.707821) (xy 233.596289 -138.698601)
			(xy 233.546354 -138.680462) (xy 233.500314 -138.65395) (xy 233.45956 -138.619868) (xy 233.442002 -138.599926)
			(xy 233.40695 -138.55827) (xy 233.366818 -138.553444) (xy 233.350816 -138.565382) (xy 233.328822 -138.581047)
			(xy 233.281302 -138.606688) (xy 233.230643 -138.625377) (xy 233.177856 -138.636742) (xy 233.123994 -138.640556)
			(xy 233.070132 -138.636742) (xy 233.017345 -138.625377) (xy 232.966686 -138.606688) (xy 232.919166 -138.581047)
			(xy 232.897172 -138.565382) (xy 232.88117 -138.553444) (xy 232.841038 -138.55827) (xy 232.805986 -138.599926)
			(xy 232.788403 -138.619841) (xy 232.747643 -138.653903) (xy 232.701607 -138.680405) (xy 232.651682 -138.698548)
			(xy 232.599373 -138.707786) (xy 232.572814 -138.708384) (xy 230.837486 -138.708384) (xy 230.827415 -138.70797)
			(xy 230.808818 -138.700242) (xy 230.801418 -138.693398) (xy 230.394002 -138.285982) (xy 230.387162 -138.278582)
			(xy 230.379442 -138.259983) (xy 230.379016 -138.249914) (xy 230.379016 -136.139682) (xy 230.378622 -136.129609)
			(xy 230.370882 -136.11101) (xy 230.36403 -136.103614) (xy 230.001572 -135.740902) (xy 229.995229 -135.734981)
			(xy 229.979578 -135.72751) (xy 229.962328 -135.725728) (xy 229.95382 -135.72744) (xy 229.856792 -135.750046)
			(xy 229.837742 -135.767826) (xy 229.833424 -135.780526) (xy 229.824548 -135.805471) (xy 229.800987 -135.852885)
			(xy 229.771097 -135.896586) (xy 229.735452 -135.935734) (xy 229.694737 -135.969578) (xy 229.649733 -135.997467)
			(xy 229.601305 -136.018865) (xy 229.550383 -136.033362) (xy 229.497946 -136.040679) (xy 229.471474 -136.04113)
			(xy 229.444226 -136.040598) (xy 229.390284 -136.032839) (xy 229.337995 -136.017482) (xy 229.288424 -135.994841)
			(xy 229.24258 -135.965376) (xy 229.201395 -135.929686) (xy 229.165708 -135.888499) (xy 229.136246 -135.842653)
			(xy 229.113608 -135.79308) (xy 229.098256 -135.740791) (xy 229.0905 -135.686848) (xy 228.074485 -135.686848)
			(xy 228.074473 -135.687508) (xy 228.066353 -135.742684) (xy 228.050285 -135.796091) (xy 228.026613 -135.846588)
			(xy 227.99584 -135.893101) (xy 227.958623 -135.934638) (xy 227.915755 -135.970313) (xy 227.868149 -135.999367)
			(xy 227.81682 -136.021179) (xy 227.762863 -136.035285) (xy 227.707426 -136.041385) (xy 227.651692 -136.039348)
			(xy 227.596849 -136.029218) (xy 227.544065 -136.011211) (xy 227.494465 -135.98571) (xy 227.449107 -135.953259)
			(xy 227.408958 -135.91455) (xy 227.374872 -135.870407) (xy 227.347576 -135.821772) (xy 227.327653 -135.769681)
			(xy 227.315527 -135.715244) (xy 227.311456 -135.659622) (xy 225.407982 -135.659622) (xy 225.407473 -135.687508)
			(xy 225.399353 -135.742684) (xy 225.383285 -135.796091) (xy 225.359613 -135.846588) (xy 225.32884 -135.893101)
			(xy 225.291623 -135.934638) (xy 225.248755 -135.970313) (xy 225.201149 -135.999367) (xy 225.14982 -136.021179)
			(xy 225.095863 -136.035285) (xy 225.040426 -136.041385) (xy 224.984692 -136.039348) (xy 224.929849 -136.029218)
			(xy 224.877065 -136.011211) (xy 224.827465 -135.98571) (xy 224.782107 -135.953259) (xy 224.741958 -135.91455)
			(xy 224.707872 -135.870407) (xy 224.680576 -135.821772) (xy 224.660653 -135.769681) (xy 224.648527 -135.715244)
			(xy 224.644456 -135.659622) (xy 212.451484 -135.659622) (xy 212.425269 -135.690989) (xy 212.385855 -135.726643)
			(xy 212.341872 -135.75648) (xy 212.294172 -135.779921) (xy 212.26907 -135.788654) (xy 212.257386 -135.792464)
			(xy 212.240622 -135.809228) (xy 212.207348 -135.910574) (xy 212.211158 -135.934196) (xy 212.21827 -135.944102)
			(xy 212.234979 -135.968486) (xy 212.261455 -136.021334) (xy 212.279466 -136.077633) (xy 212.288581 -136.136035)
			(xy 212.289136 -136.16559) (xy 212.28865 -136.192841) (xy 212.280894 -136.246789) (xy 212.265539 -136.299084)
			(xy 212.242897 -136.348661) (xy 212.213431 -136.394511) (xy 212.17774 -136.435702) (xy 212.136549 -136.471393)
			(xy 212.090699 -136.500859) (xy 212.041122 -136.523501) (xy 211.988827 -136.538856) (xy 211.934879 -136.546612)
			(xy 211.880377 -136.546612) (xy 211.826429 -136.538856) (xy 211.774134 -136.523501) (xy 211.724557 -136.500859)
			(xy 211.678707 -136.471393) (xy 211.637516 -136.435702) (xy 211.601825 -136.394511) (xy 211.572359 -136.348661)
			(xy 211.549717 -136.299084) (xy 211.534362 -136.246789) (xy 211.526606 -136.192841) (xy 211.52612 -136.16559)
			(xy 211.526616 -136.139016) (xy 211.533982 -136.086382) (xy 211.548583 -136.03528) (xy 211.570138 -135.9867)
			(xy 211.598228 -135.941582) (xy 211.632309 -135.900802) (xy 211.671722 -135.865147) (xy 211.715703 -135.835309)
			(xy 211.763401 -135.811866) (xy 211.788502 -135.803132) (xy 211.800186 -135.799322) (xy 211.81695 -135.782558)
			(xy 211.850224 -135.681212) (xy 211.846414 -135.65759) (xy 211.839302 -135.647684) (xy 211.822595 -135.623298)
			(xy 211.796117 -135.570451) (xy 211.778105 -135.514153) (xy 211.76899 -135.455751) (xy 211.768436 -135.426196)
			(xy 211.768436 -135.425688) (xy 211.768843 -135.401338) (xy 211.775052 -135.353036) (xy 211.787369 -135.30592)
			(xy 211.796122 -135.283194) (xy 211.799706 -135.272924) (xy 211.798787 -135.251213) (xy 211.794344 -135.241284)
			(xy 211.755228 -135.163306) (xy 211.738464 -135.14959) (xy 211.727796 -135.146796) (xy 211.700919 -135.139308)
			(xy 211.649556 -135.117522) (xy 211.601914 -135.088485) (xy 211.55901 -135.052818) (xy 211.52176 -135.011282)
			(xy 211.490957 -134.964762) (xy 211.46726 -134.914251) (xy 211.451174 -134.860828) (xy 211.443042 -134.80563)
			(xy 211.442554 -134.777734) (xy 201.125341 -134.777734) (xy 201.149085 -134.792994) (xy 201.19239 -134.830518)
			(xy 201.229914 -134.873824) (xy 201.260892 -134.922029) (xy 201.284695 -134.974152) (xy 201.300839 -135.029132)
			(xy 201.308993 -135.08585) (xy 201.308993 -135.14315) (xy 201.300839 -135.199868) (xy 201.284695 -135.254848)
			(xy 201.260892 -135.306971) (xy 201.229914 -135.355176) (xy 201.19239 -135.398482) (xy 201.182098 -135.4074)
			(xy 209.750406 -135.4074) (xy 209.750892 -135.380149) (xy 209.758648 -135.326201) (xy 209.774003 -135.273906)
			(xy 209.796645 -135.224329) (xy 209.826111 -135.178479) (xy 209.861802 -135.137288) (xy 209.902993 -135.101597)
			(xy 209.948843 -135.072131) (xy 209.99842 -135.049489) (xy 210.050715 -135.034134) (xy 210.104663 -135.026378)
			(xy 210.159165 -135.026378) (xy 210.213113 -135.034134) (xy 210.265408 -135.049489) (xy 210.314985 -135.072131)
			(xy 210.360835 -135.101597) (xy 210.402026 -135.137288) (xy 210.437717 -135.178479) (xy 210.467183 -135.224329)
			(xy 210.489825 -135.273906) (xy 210.50518 -135.326201) (xy 210.512936 -135.380149) (xy 210.513422 -135.4074)
			(xy 210.512735 -135.440197) (xy 210.5015 -135.504822) (xy 210.49107 -135.535924) (xy 210.488341 -135.544914)
			(xy 210.488861 -135.563676) (xy 210.492086 -135.5725) (xy 210.522058 -135.644636) (xy 210.534758 -135.658098)
			(xy 210.54314 -135.662162) (xy 210.543648 -135.662162) (xy 210.567833 -135.674112) (xy 210.612907 -135.703744)
			(xy 210.65336 -135.73943) (xy 210.688383 -135.780456) (xy 210.71728 -135.826006) (xy 210.739474 -135.875172)
			(xy 210.754523 -135.926973) (xy 210.762127 -135.980377) (xy 210.762596 -136.007348) (xy 210.76211 -136.034599)
			(xy 210.754354 -136.088547) (xy 210.738999 -136.140842) (xy 210.716357 -136.190419) (xy 210.686891 -136.236269)
			(xy 210.6512 -136.27746) (xy 210.610009 -136.313151) (xy 210.564159 -136.342617) (xy 210.514582 -136.365259)
			(xy 210.462287 -136.380614) (xy 210.408339 -136.38837) (xy 210.353837 -136.38837) (xy 210.299889 -136.380614)
			(xy 210.247594 -136.365259) (xy 210.198017 -136.342617) (xy 210.152167 -136.313151) (xy 210.110976 -136.27746)
			(xy 210.075285 -136.236269) (xy 210.045819 -136.190419) (xy 210.023177 -136.140842) (xy 210.007822 -136.088547)
			(xy 210.000066 -136.034599) (xy 209.99958 -136.007348) (xy 210.000253 -135.97455) (xy 210.011498 -135.909925)
			(xy 210.021932 -135.878824) (xy 210.024688 -135.869841) (xy 210.02415 -135.851072) (xy 210.020916 -135.842248)
			(xy 209.990944 -135.770112) (xy 209.978244 -135.75665) (xy 209.969862 -135.752586) (xy 209.969354 -135.752586)
			(xy 209.945148 -135.740676) (xy 209.900073 -135.711038) (xy 209.859621 -135.675347) (xy 209.824598 -135.634315)
			(xy 209.795704 -135.588759) (xy 209.773514 -135.539588) (xy 209.75847 -135.487782) (xy 209.750872 -135.434373)
			(xy 209.750406 -135.4074) (xy 201.182098 -135.4074) (xy 201.149085 -135.436006) (xy 201.100881 -135.466986)
			(xy 201.048759 -135.490791) (xy 200.99378 -135.506936) (xy 200.937062 -135.515092) (xy 200.908412 -135.515604)
			(xy 200.893494 -135.515439) (xy 200.863745 -135.513147) (xy 200.848976 -135.511032) (xy 200.8378 -135.509254)
			(xy 200.816718 -135.51535) (xy 200.749662 -135.573008) (xy 200.741686 -135.580592) (xy 200.732607 -135.600619)
			(xy 200.732136 -135.611616) (xy 200.732136 -135.876284) (xy 200.732639 -135.887274) (xy 200.741715 -135.907287)
			(xy 200.749662 -135.914892) (xy 200.816718 -135.97255) (xy 200.8378 -135.978646) (xy 200.848976 -135.976868)
			(xy 200.863745 -135.97476) (xy 200.893494 -135.972472) (xy 200.908412 -135.972296) (xy 200.937057 -135.972884)
			(xy 200.993764 -135.981039) (xy 201.048733 -135.99718) (xy 201.100845 -136.020981) (xy 201.14904 -136.051955)
			(xy 201.192336 -136.089473) (xy 201.229852 -136.13277) (xy 201.260825 -136.180966) (xy 201.284624 -136.233079)
			(xy 201.300764 -136.288048) (xy 201.308917 -136.344755) (xy 201.308917 -136.402045) (xy 201.300764 -136.458752)
			(xy 201.284624 -136.513721) (xy 201.260825 -136.565834) (xy 201.229852 -136.61403) (xy 201.192336 -136.657327)
			(xy 201.14904 -136.694845) (xy 201.100845 -136.725819) (xy 201.048733 -136.74962) (xy 200.993764 -136.765761)
			(xy 200.937057 -136.773916) (xy 200.908412 -136.774428) (xy 200.881032 -136.773941) (xy 200.826783 -136.766476)
			(xy 200.774056 -136.751696) (xy 200.72383 -136.729877) (xy 200.677042 -136.701425) (xy 200.634562 -136.666869)
			(xy 200.59718 -136.626853) (xy 200.581006 -136.604756) (xy 200.575429 -136.597508) (xy 200.560331 -136.587216)
			(xy 200.551542 -136.58469) (xy 200.52157 -136.577324) (xy 200.512622 -136.575565) (xy 200.494531 -136.577789)
			(xy 200.486264 -136.581642) (xy 200.461671 -136.594046) (xy 200.410142 -136.613511) (xy 200.356651 -136.626655)
			(xy 200.301969 -136.633289) (xy 200.274428 -136.633712) (xy 200.246887 -136.633301) (xy 200.192206 -136.626661)
			(xy 200.138716 -136.613509) (xy 200.087191 -136.594036) (xy 200.062592 -136.581642) (xy 200.054334 -136.577761)
			(xy 200.036236 -136.575547) (xy 200.027286 -136.577324) (xy 199.997314 -136.58469) (xy 199.98853 -136.587228)
			(xy 199.97343 -136.597513) (xy 199.96785 -136.604756) (xy 199.951703 -136.626877) (xy 199.914328 -136.666909)
			(xy 199.871848 -136.701478) (xy 199.825056 -136.729938) (xy 199.774823 -136.751758) (xy 199.722086 -136.766532)
			(xy 199.667828 -136.773985) (xy 199.640444 -136.774428) (xy 199.611789 -136.77402) (xy 199.555062 -136.76587)
			(xy 199.500073 -136.749729) (xy 199.447941 -136.725926) (xy 199.399727 -136.694945) (xy 199.356413 -136.657418)
			(xy 199.318881 -136.614109) (xy 199.287895 -136.565898) (xy 199.264087 -136.513768) (xy 199.24794 -136.458781)
			(xy 199.239783 -136.402055) (xy 190.641865 -136.402055) (xy 190.650474 -136.411663) (xy 190.681247 -136.458176)
			(xy 190.704919 -136.508673) (xy 190.720987 -136.56208) (xy 190.729107 -136.617256) (xy 190.729616 -136.645142)
			(xy 190.729107 -136.673028) (xy 190.720987 -136.728204) (xy 190.704919 -136.781611) (xy 190.681247 -136.832108)
			(xy 190.650474 -136.878621) (xy 190.613257 -136.920158) (xy 190.570389 -136.955833) (xy 190.522783 -136.984887)
			(xy 190.52014 -136.98601) (xy 196.657466 -136.98601) (xy 196.661537 -136.930388) (xy 196.673663 -136.875951)
			(xy 196.693586 -136.82386) (xy 196.720882 -136.775225) (xy 196.754968 -136.731082) (xy 196.795117 -136.692373)
			(xy 196.840475 -136.659922) (xy 196.890075 -136.634421) (xy 196.942859 -136.616414) (xy 196.997702 -136.606284)
			(xy 197.053436 -136.604247) (xy 197.108873 -136.610347) (xy 197.16283 -136.624453) (xy 197.214159 -136.646265)
			(xy 197.261765 -136.675319) (xy 197.304633 -136.710994) (xy 197.34185 -136.752531) (xy 197.372623 -136.799044)
			(xy 197.396295 -136.849541) (xy 197.412363 -136.902948) (xy 197.420438 -136.957816) (xy 223.696022 -136.957816)
			(xy 223.696555 -136.929136) (xy 223.705153 -136.872425) (xy 223.722143 -136.817639) (xy 223.747142 -136.766014)
			(xy 223.779587 -136.718712) (xy 223.818746 -136.6768) (xy 223.863738 -136.641221) (xy 223.913549 -136.612777)
			(xy 223.940116 -136.601962) (xy 223.953208 -136.596325) (xy 223.975908 -136.579112) (xy 223.992965 -136.556294)
			(xy 224.00305 -136.529651) (xy 224.005377 -136.501258) (xy 223.999765 -136.473328) (xy 223.986651 -136.448038)
			(xy 223.9772 -136.43737) (xy 223.957715 -136.415996) (xy 223.924747 -136.368479) (xy 223.899337 -136.316526)
			(xy 223.882068 -136.261331) (xy 223.873338 -136.204159) (xy 223.872806 -136.175242) (xy 223.872806 -136.174988)
			(xy 223.873292 -136.147737) (xy 223.881048 -136.093789) (xy 223.896403 -136.041494) (xy 223.919045 -135.991917)
			(xy 223.948511 -135.946067) (xy 223.984202 -135.904876) (xy 224.025393 -135.869185) (xy 224.071243 -135.839719)
			(xy 224.12082 -135.817077) (xy 224.173115 -135.801722) (xy 224.227063 -135.793966) (xy 224.281565 -135.793966)
			(xy 224.335513 -135.801722) (xy 224.387808 -135.817077) (xy 224.437385 -135.839719) (xy 224.483235 -135.869185)
			(xy 224.524426 -135.904876) (xy 224.560117 -135.946067) (xy 224.589583 -135.991917) (xy 224.612225 -136.041494)
			(xy 224.62758 -136.093789) (xy 224.635336 -136.147737) (xy 224.635822 -136.174988) (xy 224.635264 -136.203666)
			(xy 224.626667 -136.260375) (xy 224.609678 -136.315159) (xy 224.584682 -136.366783) (xy 224.552241 -136.414084)
			(xy 224.513086 -136.455997) (xy 224.468099 -136.491578) (xy 224.418293 -136.520025) (xy 224.391728 -136.530842)
			(xy 224.378629 -136.53646) (xy 224.355937 -136.553682) (xy 224.338887 -136.576504) (xy 224.328806 -136.603148)
			(xy 224.32648 -136.631541) (xy 224.332089 -136.659471) (xy 224.345197 -136.684763) (xy 224.354644 -136.695434)
			(xy 224.374121 -136.716814) (xy 224.407093 -136.764329) (xy 224.432506 -136.81628) (xy 224.449775 -136.871474)
			(xy 224.458506 -136.928645) (xy 224.459038 -136.957562) (xy 224.459038 -136.957816) (xy 224.458552 -136.985067)
			(xy 224.450796 -137.039015) (xy 224.435441 -137.09131) (xy 224.412799 -137.140887) (xy 224.383333 -137.186737)
			(xy 224.347642 -137.227928) (xy 224.306451 -137.263619) (xy 224.260601 -137.293085) (xy 224.211024 -137.315727)
			(xy 224.158729 -137.331082) (xy 224.104781 -137.338838) (xy 224.050279 -137.338838) (xy 223.996331 -137.331082)
			(xy 223.944036 -137.315727) (xy 223.894459 -137.293085) (xy 223.848609 -137.263619) (xy 223.807418 -137.227928)
			(xy 223.771727 -137.186737) (xy 223.742261 -137.140887) (xy 223.719619 -137.09131) (xy 223.704264 -137.039015)
			(xy 223.696508 -136.985067) (xy 223.696022 -136.957816) (xy 197.420438 -136.957816) (xy 197.420483 -136.958124)
			(xy 197.420992 -136.98601) (xy 197.420483 -137.013896) (xy 197.412363 -137.069072) (xy 197.396295 -137.122479)
			(xy 197.372623 -137.172976) (xy 197.34185 -137.219489) (xy 197.304633 -137.261026) (xy 197.261765 -137.296701)
			(xy 197.214159 -137.325755) (xy 197.16283 -137.347567) (xy 197.108873 -137.361673) (xy 197.053436 -137.367773)
			(xy 196.997702 -137.365736) (xy 196.942859 -137.355606) (xy 196.890075 -137.337599) (xy 196.840475 -137.312098)
			(xy 196.795117 -137.279647) (xy 196.754968 -137.240938) (xy 196.720882 -137.196795) (xy 196.693586 -137.14816)
			(xy 196.673663 -137.096069) (xy 196.661537 -137.041632) (xy 196.657466 -136.98601) (xy 190.52014 -136.98601)
			(xy 190.471454 -137.006699) (xy 190.417497 -137.020805) (xy 190.36206 -137.026905) (xy 190.306326 -137.024868)
			(xy 190.251483 -137.014738) (xy 190.198699 -136.996731) (xy 190.149099 -136.97123) (xy 190.103741 -136.938779)
			(xy 190.063592 -136.90007) (xy 190.029506 -136.855927) (xy 190.00221 -136.807292) (xy 189.982287 -136.755201)
			(xy 189.970161 -136.700764) (xy 189.96609 -136.645142) (xy 187.849256 -136.645142) (xy 187.848747 -136.673028)
			(xy 187.840627 -136.728204) (xy 187.824559 -136.781611) (xy 187.800887 -136.832108) (xy 187.770114 -136.878621)
			(xy 187.732897 -136.920158) (xy 187.690029 -136.955833) (xy 187.642423 -136.984887) (xy 187.591094 -137.006699)
			(xy 187.537137 -137.020805) (xy 187.4817 -137.026905) (xy 187.425966 -137.024868) (xy 187.371123 -137.014738)
			(xy 187.318339 -136.996731) (xy 187.268739 -136.97123) (xy 187.223381 -136.938779) (xy 187.183232 -136.90007)
			(xy 187.149146 -136.855927) (xy 187.12185 -136.807292) (xy 187.101927 -136.755201) (xy 187.089801 -136.700764)
			(xy 187.08573 -136.645142) (xy 184.148222 -136.645142) (xy 184.147713 -136.673028) (xy 184.139593 -136.728204)
			(xy 184.123525 -136.781611) (xy 184.099853 -136.832108) (xy 184.06908 -136.878621) (xy 184.031863 -136.920158)
			(xy 183.988995 -136.955833) (xy 183.941389 -136.984887) (xy 183.89006 -137.006699) (xy 183.836103 -137.020805)
			(xy 183.780666 -137.026905) (xy 183.724932 -137.024868) (xy 183.670089 -137.014738) (xy 183.617305 -136.996731)
			(xy 183.567705 -136.97123) (xy 183.522347 -136.938779) (xy 183.482198 -136.90007) (xy 183.448112 -136.855927)
			(xy 183.420816 -136.807292) (xy 183.400893 -136.755201) (xy 183.388767 -136.700764) (xy 183.384696 -136.645142)
			(xy 182.313113 -136.645142) (xy 182.313113 -136.673532) (xy 182.304963 -136.730214) (xy 182.288829 -136.785159)
			(xy 182.265039 -136.837249) (xy 182.234078 -136.885422) (xy 182.196576 -136.928699) (xy 182.153297 -136.966197)
			(xy 182.105121 -136.997155) (xy 182.053029 -137.02094) (xy 181.998083 -137.03707) (xy 181.9414 -137.045216)
			(xy 181.912768 -137.0457) (xy 181.884485 -137.045217) (xy 181.828478 -137.037285) (xy 181.774144 -137.021555)
			(xy 181.722562 -136.998341) (xy 181.674757 -136.968102) (xy 181.63168 -136.931441) (xy 181.594188 -136.889085)
			(xy 181.563024 -136.841878) (xy 181.53881 -136.790757) (xy 181.522026 -136.736739) (xy 181.517036 -136.708896)
			(xy 181.514917 -136.698849) (xy 181.503902 -136.681544) (xy 181.4957 -136.675368) (xy 181.426358 -136.627616)
			(xy 181.406292 -136.623552) (xy 181.396132 -136.625584) (xy 181.373153 -136.630076) (xy 181.32658 -136.634915)
			(xy 181.303168 -136.635236) (xy 181.279757 -136.634902) (xy 181.233183 -136.630071) (xy 181.210204 -136.625584)
			(xy 181.200044 -136.623552) (xy 181.179978 -136.627616) (xy 181.102 -136.68121) (xy 181.091078 -136.698482)
			(xy 181.0893 -136.708896) (xy 181.084245 -136.736723) (xy 181.067448 -136.790727) (xy 181.043228 -136.841834)
			(xy 181.012065 -136.889029) (xy 180.974579 -136.931377) (xy 180.931513 -136.968036) (xy 180.883723 -136.998278)
			(xy 180.832157 -137.021504) (xy 180.777838 -137.037252) (xy 180.721846 -137.04521) (xy 180.693568 -137.0457)
			(xy 180.664939 -137.045211) (xy 180.608263 -137.037058) (xy 180.553324 -137.020923) (xy 180.501241 -136.997134)
			(xy 180.453073 -136.966175) (xy 180.409801 -136.928676) (xy 180.372306 -136.885401) (xy 180.341351 -136.837231)
			(xy 180.317566 -136.785146) (xy 180.301435 -136.730206) (xy 180.293286 -136.67353) (xy 180.293286 -136.61627)
			(xy 180.301435 -136.559594) (xy 180.317566 -136.504654) (xy 180.341351 -136.452569) (xy 180.372306 -136.404399)
			(xy 180.409801 -136.361124) (xy 180.453073 -136.323625) (xy 180.501241 -136.292666) (xy 180.553324 -136.268877)
			(xy 180.608263 -136.252742) (xy 180.664939 -136.244589) (xy 180.693568 -136.244076) (xy 180.71054 -136.244203)
			(xy 180.744369 -136.247004) (xy 180.761132 -136.249664) (xy 180.772127 -136.250978) (xy 180.793472 -136.245196)
			(xy 180.80228 -136.238488) (xy 180.827426 -136.21766) (xy 180.835562 -136.210074) (xy 180.844906 -136.18991)
			(xy 180.84546 -136.178798) (xy 180.84546 -136.177528) (xy 180.84546 -136.17702) (xy 180.84546 -135.31088)
			(xy 180.844932 -135.299765) (xy 180.835566 -135.279606) (xy 180.827426 -135.272018) (xy 180.802788 -135.25119)
			(xy 180.793901 -135.244485) (xy 180.772437 -135.238683) (xy 180.761386 -135.240014) (xy 180.744562 -135.242723)
			(xy 180.710608 -135.24565) (xy 180.693568 -135.245856) (xy 180.66492 -135.245363) (xy 180.608209 -135.237205)
			(xy 180.553236 -135.22106) (xy 180.50112 -135.197255) (xy 180.452922 -135.166277) (xy 180.409623 -135.128755)
			(xy 180.372104 -135.085453) (xy 180.341129 -135.037252) (xy 180.317329 -134.985134) (xy 180.301188 -134.93016)
			(xy 180.293035 -134.873448) (xy 180.293035 -134.816152) (xy 180.301188 -134.75944) (xy 180.317329 -134.704466)
			(xy 180.341129 -134.652348) (xy 180.372104 -134.604147) (xy 180.409623 -134.560845) (xy 180.452922 -134.523323)
			(xy 180.50112 -134.492345) (xy 180.553236 -134.46854) (xy 180.608209 -134.452395) (xy 180.66492 -134.444237)
			(xy 180.693568 -134.443724) (xy 180.72191 -134.444252) (xy 180.778026 -134.452255) (xy 180.832457 -134.468079)
			(xy 180.884118 -134.491406) (xy 180.931982 -134.521774) (xy 180.975093 -134.558578) (xy 181.012594 -134.601084)
			(xy 181.043738 -134.648446) (xy 181.067905 -134.69972) (xy 181.084613 -134.753886) (xy 181.089554 -134.781798)
			(xy 181.091078 -134.792212) (xy 181.102254 -134.809992) (xy 181.171342 -134.85749) (xy 181.180027 -134.862918)
			(xy 181.200087 -134.866968) (xy 181.210204 -134.865364) (xy 181.210712 -134.865364) (xy 181.233564 -134.860883)
			(xy 181.279883 -134.85605) (xy 181.303168 -134.855712) (xy 181.326516 -134.856044) (xy 181.372962 -134.860882)
			(xy 181.395878 -134.865364) (xy 181.396132 -134.865364) (xy 181.406249 -134.866926) (xy 181.426293 -134.86288)
			(xy 181.434994 -134.85749) (xy 181.504082 -134.809992) (xy 181.515258 -134.792212) (xy 181.516782 -134.781798)
			(xy 181.521699 -134.753876) (xy 181.538382 -134.699691) (xy 181.562533 -134.648397) (xy 181.59367 -134.601018)
			(xy 181.631172 -134.558498) (xy 181.674291 -134.521686) (xy 181.722166 -134.491317) (xy 181.773843 -134.467995)
			(xy 181.828289 -134.452188) (xy 181.88442 -134.444209) (xy 181.912768 -134.443724) (xy 181.942137 -134.444271)
			(xy 182.000243 -134.452865) (xy 182.056473 -134.469844) (xy 182.109624 -134.494846) (xy 182.158559 -134.527335)
			(xy 182.180738 -134.546594) (xy 182.187904 -134.552506) (xy 182.205238 -134.559148) (xy 182.21452 -134.559548)
			(xy 182.246016 -134.559548) (xy 182.25529 -134.559122) (xy 182.272608 -134.552468) (xy 182.279798 -134.546594)
			(xy 182.301962 -134.527317) (xy 182.350903 -134.494833) (xy 182.404058 -134.469834) (xy 182.460291 -134.452853)
			(xy 182.518398 -134.444254) (xy 182.547768 -134.443724) (xy 182.564745 -134.443922) (xy 182.598573 -134.446844)
			(xy 182.615332 -134.449566) (xy 182.626387 -134.450938) (xy 182.647868 -134.445136) (xy 182.656734 -134.43839)
			(xy 182.681626 -134.417562) (xy 182.689761 -134.409975) (xy 182.699105 -134.389812) (xy 182.69966 -134.3787)
			(xy 182.69966 -134.37743) (xy 182.69966 -134.376922) (xy 182.69966 -133.511036) (xy 182.6991 -133.499925)
			(xy 182.689757 -133.479765) (xy 182.681626 -133.472174) (xy 182.656988 -133.451346) (xy 182.648104 -133.444638)
			(xy 182.626638 -133.438839) (xy 182.615586 -133.44017) (xy 182.598762 -133.442879) (xy 182.564808 -133.445806)
			(xy 182.547768 -133.446012) (xy 182.518398 -133.445494) (xy 182.460291 -133.436892) (xy 182.404061 -133.419905)
			(xy 182.350911 -133.394897) (xy 182.301977 -133.362403) (xy 182.279798 -133.343142) (xy 182.272627 -133.337237)
			(xy 182.255297 -133.330593) (xy 182.246016 -133.330188) (xy 182.21452 -133.330188) (xy 182.20525 -133.330646)
			(xy 182.187932 -133.337279) (xy 182.180738 -133.343142) (xy 182.158565 -133.362408) (xy 182.109626 -133.394892)
			(xy 182.056473 -133.419893) (xy 182.000243 -133.436877) (xy 181.942137 -133.44548) (xy 181.912768 -133.446012)
			(xy 181.884477 -133.445486) (xy 181.828456 -133.437537) (xy 181.77411 -133.421788) (xy 181.72252 -133.398551)
			(xy 181.674711 -133.368289) (xy 181.631633 -133.331603) (xy 181.594144 -133.289223) (xy 181.562988 -133.241992)
			(xy 181.538785 -133.190847) (xy 181.522017 -133.136807) (xy 181.517036 -133.108954) (xy 181.514937 -133.098902)
			(xy 181.503908 -133.081599) (xy 181.4957 -133.075426) (xy 181.426358 -133.027674) (xy 181.406292 -133.02361)
			(xy 181.396132 -133.025642) (xy 181.373148 -133.030077) (xy 181.326574 -133.034785) (xy 181.303168 -133.03504)
			(xy 181.279762 -133.034772) (xy 181.233189 -133.030066) (xy 181.210204 -133.025642) (xy 181.200044 -133.02361)
			(xy 181.179978 -133.027674) (xy 181.102 -133.081268) (xy 181.091078 -133.09854) (xy 181.0893 -133.1087)
			(xy 181.0893 -133.108954) (xy 181.084328 -133.13681) (xy 181.06756 -133.190854) (xy 181.043357 -133.242002)
			(xy 181.012201 -133.289237) (xy 180.974712 -133.331621) (xy 180.931634 -133.368311) (xy 180.883823 -133.398578)
			(xy 180.832232 -133.421819) (xy 180.777884 -133.437574) (xy 180.721861 -133.445528) (xy 180.693568 -133.446012)
			(xy 180.664925 -133.445407) (xy 180.608221 -133.43725) (xy 180.553256 -133.421107) (xy 180.501147 -133.397306)
			(xy 180.452956 -133.366332) (xy 180.409663 -133.328815) (xy 180.372149 -133.285519) (xy 180.341179 -133.237325)
			(xy 180.317382 -133.185214) (xy 180.301243 -133.130248) (xy 180.293091 -133.073544) (xy 180.293091 -133.016256)
			(xy 180.301243 -132.959553) (xy 180.317382 -132.904586) (xy 180.341179 -132.852475) (xy 180.372149 -132.804281)
			(xy 180.409663 -132.760985) (xy 180.452956 -132.723468) (xy 180.501147 -132.692494) (xy 180.553256 -132.668693)
			(xy 180.608221 -132.65255) (xy 180.664925 -132.644393) (xy 180.693568 -132.64388) (xy 180.710545 -132.644078)
			(xy 180.744373 -132.647001) (xy 180.761132 -132.649722) (xy 180.772187 -132.651081) (xy 180.793666 -132.645286)
			(xy 180.802534 -132.638546) (xy 180.827426 -132.617718) (xy 180.835536 -132.610108) (xy 180.844894 -132.589962)
			(xy 180.84546 -132.578856) (xy 180.84546 -132.577586) (xy 180.84546 -132.577078) (xy 180.84546 -131.710938)
			(xy 180.844899 -131.699827) (xy 180.835557 -131.679668) (xy 180.827426 -131.672076) (xy 180.802788 -131.651248)
			(xy 180.793904 -131.64454) (xy 180.772438 -131.638741) (xy 180.761386 -131.640072) (xy 180.744558 -131.642723)
			(xy 180.710603 -131.645521) (xy 180.693568 -131.64566) (xy 180.664943 -131.645051) (xy 180.608276 -131.6369)
			(xy 180.553345 -131.620767) (xy 180.50127 -131.596981) (xy 180.453109 -131.566027) (xy 180.409844 -131.528534)
			(xy 180.372354 -131.485265) (xy 180.341404 -131.437102) (xy 180.317622 -131.385025) (xy 180.301493 -131.330093)
			(xy 180.293346 -131.273425) (xy 180.293346 -131.216175) (xy 180.301493 -131.159507) (xy 180.317622 -131.104575)
			(xy 180.341404 -131.052498) (xy 180.372354 -131.004335) (xy 180.409844 -130.961066) (xy 180.453109 -130.923573)
			(xy 180.50127 -130.892619) (xy 180.553345 -130.868833) (xy 180.608276 -130.8527) (xy 180.664943 -130.844549)
			(xy 180.693568 -130.844036) (xy 180.721898 -130.844605) (xy 180.777993 -130.852589) (xy 180.832406 -130.868387)
			(xy 180.884054 -130.891686) (xy 180.931909 -130.922022) (xy 180.975018 -130.958791) (xy 181.012524 -131.001261)
			(xy 181.04368 -131.048587) (xy 181.067865 -131.099826) (xy 181.084598 -131.153959) (xy 181.089554 -131.181856)
			(xy 181.091078 -131.19227) (xy 181.102254 -131.21005) (xy 181.171342 -131.257548) (xy 181.180025 -131.262979)
			(xy 181.200087 -131.267025) (xy 181.210204 -131.265422) (xy 181.210458 -131.265422) (xy 181.233379 -131.260998)
			(xy 181.279825 -131.256289) (xy 181.303168 -131.256024) (xy 181.32651 -131.256305) (xy 181.372956 -131.261008)
			(xy 181.395878 -131.265422) (xy 181.396132 -131.265422) (xy 181.406248 -131.266991) (xy 181.426294 -131.262941)
			(xy 181.434994 -131.257548) (xy 181.504082 -131.21005) (xy 181.515258 -131.19227) (xy 181.516782 -131.181856)
			(xy 181.521686 -131.153943) (xy 181.538404 -131.099791) (xy 181.562581 -131.048533) (xy 181.593734 -131.00119)
			(xy 181.631243 -130.958705) (xy 181.674361 -130.921925) (xy 181.722229 -130.891583) (xy 181.773892 -130.868284)
			(xy 181.828321 -130.852491) (xy 181.884431 -130.84452) (xy 181.912768 -130.844036) (xy 181.942126 -130.844541)
			(xy 182.000214 -130.853115) (xy 182.056434 -130.870058) (xy 182.109588 -130.895006) (xy 182.158542 -130.927429)
			(xy 182.180738 -130.946652) (xy 182.187899 -130.952571) (xy 182.205237 -130.959207) (xy 182.21452 -130.959606)
			(xy 182.246016 -130.959606) (xy 182.255288 -130.959167) (xy 182.272606 -130.952521) (xy 182.279798 -130.946652)
			(xy 182.301981 -130.927412) (xy 182.350931 -130.894977) (xy 182.404087 -130.870028) (xy 182.460313 -130.853096)
			(xy 182.518408 -130.844543) (xy 182.547768 -130.844036) (xy 182.56474 -130.844163) (xy 182.598569 -130.846964)
			(xy 182.615332 -130.849624) (xy 182.626327 -130.850947) (xy 182.647673 -130.84516) (xy 182.65648 -130.838448)
			(xy 182.681626 -130.81762) (xy 182.689735 -130.810009) (xy 182.699094 -130.789864) (xy 182.69966 -130.778758)
			(xy 182.69966 -130.777488) (xy 182.69966 -130.77698) (xy 182.69966 -129.91084) (xy 182.699098 -129.899729)
			(xy 182.689757 -129.87957) (xy 182.681626 -129.871978) (xy 182.656988 -129.85115) (xy 182.648104 -129.844442)
			(xy 182.626638 -129.838643) (xy 182.615586 -129.839974) (xy 182.598762 -129.842683) (xy 182.564808 -129.84561)
			(xy 182.547768 -129.845816) (xy 182.519125 -129.845203) (xy 182.462422 -129.837046) (xy 182.407457 -129.820903)
			(xy 182.355349 -129.797102) (xy 182.307158 -129.766128) (xy 182.263866 -129.728612) (xy 182.226352 -129.685316)
			(xy 182.195382 -129.637123) (xy 182.171586 -129.585013) (xy 182.155447 -129.530047) (xy 182.147295 -129.473343)
			(xy 182.147295 -129.416057) (xy 182.155447 -129.359353) (xy 182.171586 -129.304387) (xy 182.195382 -129.252277)
			(xy 182.226352 -129.204084) (xy 182.263865 -129.160788) (xy 182.307158 -129.123272) (xy 182.355349 -129.092298)
			(xy 182.407457 -129.068497) (xy 182.462422 -129.052354) (xy 182.519125 -129.044197) (xy 182.547768 -129.043684)
			(xy 182.576108 -129.044246) (xy 182.632222 -129.052248) (xy 182.68665 -129.068069) (xy 182.738309 -129.091394)
			(xy 182.786171 -129.121759) (xy 182.829282 -129.158558) (xy 182.866784 -129.20106) (xy 182.897929 -129.248417)
			(xy 182.922099 -129.299686) (xy 182.938811 -129.353848) (xy 182.943754 -129.381758) (xy 182.945278 -129.392172)
			(xy 182.956454 -129.409952) (xy 183.025542 -129.45745) (xy 183.034225 -129.462881) (xy 183.054287 -129.466927)
			(xy 183.064404 -129.465324) (xy 183.064912 -129.465324) (xy 183.087764 -129.460842) (xy 183.134083 -129.456009)
			(xy 183.157368 -129.455672) (xy 183.184686 -129.456058) (xy 183.238934 -129.462555) (xy 183.265572 -129.468626)
			(xy 183.275986 -129.471166) (xy 183.29656 -129.46761) (xy 183.376824 -129.41427) (xy 183.388254 -129.39649)
			(xy 183.389778 -129.385822) (xy 183.394388 -129.359208) (xy 183.41022 -129.307565) (xy 183.433176 -129.258671)
			(xy 183.462798 -129.213503) (xy 183.498492 -129.172963) (xy 183.539547 -129.137862) (xy 183.585141 -129.1089)
			(xy 183.634364 -129.086657) (xy 183.686231 -129.071578) (xy 183.739707 -129.063963) (xy 183.766714 -129.063496)
			(xy 183.77408 -129.063496) (xy 183.789574 -129.06375) (xy 183.815736 -129.046986) (xy 183.858662 -128.945894)
			(xy 183.86223 -128.936473) (xy 183.862394 -128.916344) (xy 183.854788 -128.897707) (xy 183.847994 -128.890268)
			(xy 183.573674 -128.615948) (xy 183.55075 -128.592406) (xy 183.509785 -128.541027) (xy 183.47483 -128.485383)
			(xy 183.446325 -128.426176) (xy 183.424628 -128.364149) (xy 183.410013 -128.300083) (xy 183.402664 -128.234784)
			(xy 183.402224 -128.201928) (xy 183.402224 -128.201674) (xy 183.402731 -128.16627) (xy 183.411267 -128.095979)
			(xy 183.42821 -128.027229) (xy 183.453315 -127.961021) (xy 183.486214 -127.898321) (xy 183.526429 -127.840042)
			(xy 183.573374 -127.787034) (xy 183.626364 -127.740069) (xy 183.684627 -127.699831) (xy 183.747315 -127.666907)
			(xy 183.813513 -127.641778) (xy 183.882257 -127.624808) (xy 183.952545 -127.616245) (xy 183.987948 -127.615696)
			(xy 184.020828 -127.616171) (xy 184.086175 -127.623532) (xy 184.150285 -127.638168) (xy 184.212353 -127.659895)
			(xy 184.271595 -127.688438) (xy 184.327267 -127.723438) (xy 184.378667 -127.764456) (xy 184.402222 -127.7874)
			(xy 184.828942 -128.214374) (xy 184.836337 -128.221221) (xy 184.85494 -128.228937) (xy 184.86501 -128.22936)
			(xy 185.343038 -128.22936) (xy 185.352751 -128.228915) (xy 185.370788 -128.221706) (xy 185.384845 -128.2083)
			(xy 185.389266 -128.199642) (xy 185.427874 -128.115314) (xy 185.431456 -128.106347) (xy 185.432418 -128.08708)
			(xy 185.426198 -128.068819) (xy 185.420254 -128.061212) (xy 185.42 -128.060958) (xy 185.392845 -128.028926)
			(xy 185.343666 -127.960852) (xy 185.300756 -127.88866) (xy 185.26446 -127.812928) (xy 185.235065 -127.73426)
			(xy 185.212806 -127.653283) (xy 185.197861 -127.570642) (xy 185.19035 -127.486998) (xy 185.189876 -127.445008)
			(xy 185.190575 -127.39431) (xy 185.201521 -127.293506) (xy 185.21172 -127.24384) (xy 185.21426 -127.23241)
			(xy 185.20918 -127.210058) (xy 185.152792 -127.140208) (xy 185.145218 -127.131651) (xy 185.124587 -127.121869)
			(xy 185.113168 -127.121412) (xy 176.501044 -127.121412) (xy 176.477307 -127.120925) (xy 176.430407 -127.113555)
			(xy 176.385208 -127.099034) (xy 176.342793 -127.077707) (xy 176.304179 -127.050088) (xy 176.286922 -127.033782)
			(xy 176.284382 -127.031242) (xy 173.015656 -123.762516) (xy 172.999197 -123.745221) (xy 172.971321 -123.706463)
			(xy 172.949797 -123.663848) (xy 172.935148 -123.61841) (xy 172.927727 -123.571249) (xy 172.927264 -123.547378)
			(xy 170.65498 -123.547378) (xy 170.65498 -123.688348) (xy 170.655464 -123.699529) (xy 170.664832 -123.719826)
			(xy 170.673014 -123.727464) (xy 170.697398 -123.748292) (xy 170.706284 -123.754996) (xy 170.727749 -123.760796)
			(xy 170.7388 -123.759468) (xy 170.755628 -123.756819) (xy 170.789583 -123.75402) (xy 170.806618 -123.75388)
			(xy 170.835247 -123.754408) (xy 170.891921 -123.762559) (xy 170.946859 -123.778692) (xy 170.998941 -123.802479)
			(xy 171.047108 -123.833436) (xy 171.09038 -123.870933) (xy 171.127874 -123.914206) (xy 171.158829 -123.962375)
			(xy 171.182614 -124.014458) (xy 171.198745 -124.069397) (xy 171.206894 -124.126071) (xy 171.206894 -124.183329)
			(xy 171.198745 -124.240003) (xy 171.182614 -124.294942) (xy 171.158829 -124.347025) (xy 171.127874 -124.395194)
			(xy 171.09038 -124.438467) (xy 171.047108 -124.475964) (xy 170.998941 -124.506921) (xy 170.946859 -124.530708)
			(xy 170.891921 -124.546841) (xy 170.835247 -124.554992) (xy 170.806618 -124.555504) (xy 170.778304 -124.555072)
			(xy 170.722238 -124.547108) (xy 170.667849 -124.531337) (xy 170.61622 -124.508073) (xy 170.568377 -124.477777)
			(xy 170.525271 -124.441052) (xy 170.48776 -124.398629) (xy 170.456589 -124.351351) (xy 170.432378 -124.300159)
			(xy 170.41561 -124.24607) (xy 170.410632 -124.218192) (xy 170.409108 -124.207778) (xy 170.397932 -124.189998)
			(xy 170.328844 -124.1425) (xy 170.320135 -124.137117) (xy 170.300095 -124.13304) (xy 170.289982 -124.134626)
			(xy 170.289728 -124.134626) (xy 170.266807 -124.139051) (xy 170.220361 -124.14376) (xy 170.197018 -124.144024)
			(xy 170.173676 -124.143746) (xy 170.12723 -124.139041) (xy 170.104308 -124.134626) (xy 170.104054 -124.134626)
			(xy 170.093938 -124.133058) (xy 170.073892 -124.137108) (xy 170.065192 -124.1425) (xy 169.996104 -124.189998)
			(xy 169.984928 -124.207778) (xy 169.983404 -124.218192) (xy 169.978416 -124.246065) (xy 169.961638 -124.300144)
			(xy 169.937422 -124.351327) (xy 169.906248 -124.398596) (xy 169.868737 -124.44101) (xy 169.825633 -124.477728)
			(xy 169.777794 -124.508018) (xy 169.726171 -124.53128) (xy 169.671789 -124.54705) (xy 169.615729 -124.555016)
			(xy 169.587418 -124.555504) (xy 169.558061 -124.554963) (xy 169.499974 -124.5464) (xy 169.443754 -124.529467)
			(xy 169.390599 -124.504526) (xy 169.341644 -124.472109) (xy 169.319448 -124.452888) (xy 169.312288 -124.446967)
			(xy 169.29495 -124.440331) (xy 169.285666 -124.439934) (xy 169.25417 -124.439934) (xy 169.244896 -124.440357)
			(xy 169.227578 -124.447013) (xy 169.220388 -124.452888) (xy 169.198216 -124.472141) (xy 169.149262 -124.504572)
			(xy 169.096103 -124.529519) (xy 169.039875 -124.546448) (xy 168.981779 -124.554998) (xy 168.952418 -124.555504)
			(xy 168.935382 -124.555377) (xy 168.901427 -124.552581) (xy 168.8846 -124.549916) (xy 168.873544 -124.548568)
			(xy 168.852066 -124.554355) (xy 168.843198 -124.561092) (xy 168.818814 -124.58192) (xy 168.810654 -124.589571)
			(xy 168.801298 -124.609862) (xy 168.80078 -124.621036) (xy 168.80078 -124.622814) (xy 168.80078 -125.488446)
			(xy 168.801265 -125.499627) (xy 168.810633 -125.519924) (xy 168.818814 -125.527562) (xy 168.843198 -125.54839)
			(xy 168.852084 -125.555094) (xy 168.873549 -125.560894) (xy 168.8846 -125.559566) (xy 168.901425 -125.556859)
			(xy 168.935378 -125.55393) (xy 168.952418 -125.553724) (xy 168.981065 -125.554256) (xy 169.037775 -125.562412)
			(xy 169.092747 -125.578556) (xy 169.144862 -125.602358) (xy 169.193059 -125.633335) (xy 169.236358 -125.670855)
			(xy 169.273876 -125.714155) (xy 169.304851 -125.762354) (xy 169.32865 -125.81447) (xy 169.344791 -125.869443)
			(xy 169.352945 -125.926153) (xy 169.352945 -125.983447) (xy 169.344791 -126.040157) (xy 169.32865 -126.09513)
			(xy 169.304851 -126.147246) (xy 169.273876 -126.195445) (xy 169.236358 -126.238745) (xy 169.193059 -126.276265)
			(xy 169.144862 -126.307242) (xy 169.092747 -126.331044) (xy 169.037775 -126.347188) (xy 168.981065 -126.355344)
			(xy 168.952418 -126.355856) (xy 168.924093 -126.355431) (xy 168.868009 -126.347449) (xy 168.813605 -126.331656)
			(xy 168.761964 -126.308365) (xy 168.714114 -126.278041) (xy 168.671007 -126.241286) (xy 168.6335 -126.198831)
			(xy 168.602339 -126.151521) (xy 168.578144 -126.100298) (xy 168.561397 -126.046181) (xy 168.556432 -126.01829)
			(xy 168.554908 -126.007876) (xy 168.543732 -125.990096) (xy 168.474644 -125.942598) (xy 168.465935 -125.937215)
			(xy 168.445895 -125.933138) (xy 168.435782 -125.934724) (xy 168.435274 -125.934724) (xy 168.412422 -125.939207)
			(xy 168.366103 -125.944039) (xy 168.342818 -125.944376) (xy 168.31543 -125.943932) (xy 168.261054 -125.937311)
			(xy 168.23436 -125.931168) (xy 168.223946 -125.928628) (xy 168.203372 -125.932184) (xy 168.122854 -125.985778)
			(xy 168.111424 -126.003558) (xy 168.1099 -126.014226) (xy 168.105252 -126.040832) (xy 168.089418 -126.092469)
			(xy 168.066462 -126.141358) (xy 168.036843 -126.186523) (xy 168.001153 -126.22706) (xy 167.960103 -126.262161)
			(xy 167.914515 -126.291124) (xy 167.865299 -126.31337) (xy 167.813439 -126.328456) (xy 167.759969 -126.33608)
			(xy 167.732964 -126.336552) (xy 167.705718 -126.335975) (xy 167.65178 -126.328216) (xy 167.599496 -126.312859)
			(xy 167.549929 -126.290219) (xy 167.504088 -126.260755) (xy 167.462907 -126.225067) (xy 167.427224 -126.183883)
			(xy 167.397764 -126.13804) (xy 167.375128 -126.088471) (xy 167.359777 -126.036185) (xy 167.352022 -125.982246)
			(xy 167.352022 -125.927754) (xy 167.359777 -125.873815) (xy 167.375128 -125.821529) (xy 167.397764 -125.77196)
			(xy 167.427224 -125.726117) (xy 167.462907 -125.684933) (xy 167.504088 -125.649245) (xy 167.549929 -125.619781)
			(xy 167.599496 -125.597141) (xy 167.65178 -125.581784) (xy 167.705718 -125.574025) (xy 167.732964 -125.573536)
			(xy 167.750076 -125.573727) (xy 167.784163 -125.57678) (xy 167.801036 -125.579632) (xy 167.812364 -125.581045)
			(xy 167.834379 -125.575126) (xy 167.843454 -125.568202) (xy 167.867838 -125.54712) (xy 167.876239 -125.539118)
			(xy 167.885382 -125.517826) (xy 167.885364 -125.506226) (xy 167.884856 -125.486414) (xy 167.884856 -124.622814)
			(xy 167.885364 -124.60351) (xy 167.885319 -124.591919) (xy 167.87621 -124.570631) (xy 167.867838 -124.562616)
			(xy 167.843454 -124.541788) (xy 167.834442 -124.534874) (xy 167.812556 -124.528926) (xy 167.80129 -124.530358)
			(xy 167.784356 -124.533238) (xy 167.75014 -124.53629) (xy 167.732964 -124.536454) (xy 167.705718 -124.535873)
			(xy 167.65178 -124.528114) (xy 167.599496 -124.512757) (xy 167.54993 -124.490117) (xy 167.504089 -124.460653)
			(xy 167.462909 -124.424966) (xy 167.427225 -124.383782) (xy 167.397766 -124.337939) (xy 167.37513 -124.28837)
			(xy 167.359779 -124.236084) (xy 167.352024 -124.182146) (xy 167.352024 -124.127654) (xy 167.359779 -124.073716)
			(xy 167.37513 -124.02143) (xy 167.397766 -123.971861) (xy 167.427225 -123.926018) (xy 167.462909 -123.884834)
			(xy 167.504089 -123.849147) (xy 167.54993 -123.819683) (xy 167.599496 -123.797043) (xy 167.65178 -123.781686)
			(xy 167.705718 -123.773927) (xy 167.732964 -123.773438) (xy 167.759942 -123.773864) (xy 167.813363 -123.781454)
			(xy 167.865179 -123.7965) (xy 167.914355 -123.818703) (xy 167.95991 -123.847619) (xy 168.000932 -123.882669)
			(xy 168.036601 -123.923154) (xy 168.066205 -123.968264) (xy 168.089152 -124.017098) (xy 168.104984 -124.068679)
			(xy 168.109646 -124.095256) (xy 168.109646 -124.09551) (xy 168.111853 -124.105771) (xy 168.123269 -124.123355)
			(xy 168.131744 -124.129546) (xy 168.203118 -124.177044) (xy 168.223692 -124.1806) (xy 168.234106 -124.17806)
			(xy 168.260865 -124.171916) (xy 168.315367 -124.16529) (xy 168.342818 -124.164852) (xy 168.366166 -124.165191)
			(xy 168.412611 -124.170025) (xy 168.435528 -124.174504) (xy 168.435782 -124.174504) (xy 168.445896 -124.176088)
			(xy 168.465944 -124.172026) (xy 168.474644 -124.16663) (xy 168.543986 -124.118878) (xy 168.554908 -124.101606)
			(xy 168.556432 -124.091192) (xy 168.561374 -124.06331) (xy 168.578155 -124.009228) (xy 168.602376 -123.958043)
			(xy 168.633555 -123.910774) (xy 168.671072 -123.868359) (xy 168.714181 -123.831642) (xy 168.762026 -123.801353)
			(xy 168.813654 -123.778094) (xy 168.868041 -123.762327) (xy 168.924105 -123.754365) (xy 168.952418 -123.75388)
			(xy 168.981776 -123.754403) (xy 169.039863 -123.762972) (xy 169.096084 -123.779909) (xy 169.149238 -123.804854)
			(xy 169.198192 -123.837274) (xy 169.220388 -123.856496) (xy 169.22757 -123.862387) (xy 169.244891 -123.869042)
			(xy 169.25417 -123.86945) (xy 169.285666 -123.86945) (xy 169.294937 -123.869) (xy 169.312255 -123.862363)
			(xy 169.319448 -123.856496) (xy 169.341643 -123.83727) (xy 169.390591 -123.804836) (xy 169.443744 -123.779884)
			(xy 169.499967 -123.762949) (xy 169.558059 -123.754391) (xy 169.587418 -123.75388) (xy 169.604454 -123.754001)
			(xy 169.63841 -123.756801) (xy 169.655236 -123.759468) (xy 169.666291 -123.760842) (xy 169.687773 -123.755038)
			(xy 169.696638 -123.748292) (xy 169.721022 -123.727464) (xy 169.729195 -123.719824) (xy 169.738542 -123.699525)
			(xy 169.739056 -123.688348) (xy 169.739056 -123.686316) (xy 169.739056 -122.820938) (xy 169.738568 -122.809758)
			(xy 169.729201 -122.789461) (xy 169.721022 -122.781822) (xy 169.696638 -122.760994) (xy 169.687775 -122.754254)
			(xy 169.666292 -122.748476) (xy 169.655236 -122.749818) (xy 169.638413 -122.752533) (xy 169.604458 -122.755457)
			(xy 169.587418 -122.75566) (xy 169.558049 -122.755126) (xy 169.499942 -122.746529) (xy 169.443712 -122.729547)
			(xy 169.39056 -122.704542) (xy 169.341626 -122.67205) (xy 169.319448 -122.65279) (xy 169.312288 -122.64687)
			(xy 169.29495 -122.640233) (xy 169.285666 -122.639836) (xy 169.25417 -122.639836) (xy 169.244896 -122.640259)
			(xy 169.227578 -122.646915) (xy 169.220388 -122.65279) (xy 169.198188 -122.672024) (xy 169.149257 -122.704514)
			(xy 169.096111 -122.729522) (xy 169.039887 -122.746513) (xy 168.981785 -122.755124) (xy 168.952418 -122.75566)
			(xy 168.924093 -122.755232) (xy 168.868009 -122.74725) (xy 168.813606 -122.731457) (xy 168.761965 -122.708167)
			(xy 168.714116 -122.677842) (xy 168.671008 -122.641088) (xy 168.633501 -122.598633) (xy 168.60234 -122.551324)
			(xy 168.578145 -122.500102) (xy 168.561397 -122.445984) (xy 168.556432 -122.418094) (xy 168.554908 -122.40768)
			(xy 168.543986 -122.390408) (xy 168.474644 -122.342656) (xy 168.465937 -122.337271) (xy 168.445895 -122.333196)
			(xy 168.435782 -122.334782) (xy 168.435528 -122.334782) (xy 168.412607 -122.339208) (xy 168.366161 -122.343916)
			(xy 168.342818 -122.34418) (xy 168.315436 -122.343798) (xy 168.26106 -122.337308) (xy 168.23436 -122.331226)
			(xy 168.223946 -122.328686) (xy 168.203372 -122.332242) (xy 168.122854 -122.385836) (xy 168.111424 -122.403616)
			(xy 168.1099 -122.414284) (xy 168.10522 -122.440884) (xy 168.089392 -122.492521) (xy 168.066441 -122.541411)
			(xy 168.036826 -122.586576) (xy 168.001139 -122.627114) (xy 167.960093 -122.662216) (xy 167.914508 -122.69118)
			(xy 167.865295 -122.713427) (xy 167.813436 -122.728514) (xy 167.759968 -122.736138) (xy 167.732964 -122.73661)
			(xy 167.705715 -122.736118) (xy 167.651771 -122.728357) (xy 167.599481 -122.712999) (xy 167.549908 -122.690356)
			(xy 167.504063 -122.660889) (xy 167.462877 -122.625197) (xy 167.42719 -122.584008) (xy 167.397727 -122.53816)
			(xy 167.375088 -122.488585) (xy 167.359735 -122.436294) (xy 167.35198 -122.382349) (xy 163.484802 -122.382349)
			(xy 163.464213 -122.405328) (xy 163.421345 -122.441003) (xy 163.373739 -122.470057) (xy 163.32241 -122.491869)
			(xy 163.268453 -122.505975) (xy 163.213016 -122.512075) (xy 163.157282 -122.510038) (xy 163.102439 -122.499908)
			(xy 163.049655 -122.481901) (xy 163.000055 -122.4564) (xy 162.954697 -122.423949) (xy 162.914548 -122.38524)
			(xy 162.880462 -122.341097) (xy 162.853166 -122.292462) (xy 162.833243 -122.240371) (xy 162.821117 -122.185934)
			(xy 162.817046 -122.130312) (xy 161.459685 -122.130312) (xy 161.484709 -122.168136) (xy 161.508381 -122.218633)
			(xy 161.524449 -122.27204) (xy 161.532569 -122.327216) (xy 161.533078 -122.355102) (xy 161.532569 -122.382988)
			(xy 161.524449 -122.438164) (xy 161.508381 -122.491571) (xy 161.484709 -122.542068) (xy 161.453936 -122.588581)
			(xy 161.416719 -122.630118) (xy 161.373851 -122.665793) (xy 161.326245 -122.694847) (xy 161.274916 -122.716659)
			(xy 161.220959 -122.730765) (xy 161.165522 -122.736865) (xy 161.109788 -122.734828) (xy 161.054945 -122.724698)
			(xy 161.002161 -122.706691) (xy 160.952561 -122.68119) (xy 160.907203 -122.648739) (xy 160.867054 -122.61003)
			(xy 160.832968 -122.565887) (xy 160.805672 -122.517252) (xy 160.785749 -122.465161) (xy 160.773623 -122.410724)
			(xy 160.769552 -122.355102) (xy 154.803907 -122.355102) (xy 154.785828 -122.375964) (xy 154.742523 -122.413483)
			(xy 154.694318 -122.444458) (xy 154.642195 -122.468256) (xy 154.587216 -122.484393) (xy 154.530499 -122.492541)
			(xy 154.50185 -122.493024) (xy 154.474468 -122.492585) (xy 154.420218 -122.485111) (xy 154.367489 -122.470323)
			(xy 154.317263 -122.448497) (xy 154.270475 -122.420037) (xy 154.227997 -122.385474) (xy 154.190617 -122.345452)
			(xy 154.174444 -122.323352) (xy 154.16889 -122.316084) (xy 154.153775 -122.305803) (xy 154.14498 -122.303286)
			(xy 154.115008 -122.29592) (xy 154.106057 -122.29418) (xy 154.087969 -122.296391) (xy 154.079702 -122.300238)
			(xy 154.055102 -122.312628) (xy 154.003576 -122.332096) (xy 153.950087 -122.345244) (xy 153.895407 -122.351882)
			(xy 153.867866 -122.352308) (xy 153.840325 -122.351882) (xy 153.785645 -122.345247) (xy 153.732155 -122.332099)
			(xy 153.680629 -122.31263) (xy 153.65603 -122.300238) (xy 153.647764 -122.296376) (xy 153.629673 -122.29415)
			(xy 153.620724 -122.29592) (xy 153.590752 -122.303286) (xy 153.58196 -122.305801) (xy 153.566864 -122.316103)
			(xy 153.561288 -122.323352) (xy 153.545116 -122.345454) (xy 153.507746 -122.385487) (xy 153.46527 -122.420057)
			(xy 153.418482 -122.448519) (xy 153.368253 -122.470343) (xy 153.31552 -122.485121) (xy 153.261265 -122.492578)
			(xy 153.233882 -122.493024) (xy 153.205232 -122.492596) (xy 153.148514 -122.484439) (xy 153.093535 -122.468293)
			(xy 153.041413 -122.444488) (xy 152.993209 -122.413507) (xy 152.949905 -122.375982) (xy 152.912382 -122.332676)
			(xy 152.881403 -122.284471) (xy 152.8576 -122.232348) (xy 152.841457 -122.177368) (xy 152.833303 -122.12065)
			(xy 140.456412 -122.12065) (xy 140.456412 -123.914132) (xy 150.191451 -123.914132) (xy 150.191451 -123.856868)
			(xy 150.1996 -123.800186) (xy 150.215733 -123.74524) (xy 150.23952 -123.69315) (xy 150.270479 -123.644975)
			(xy 150.307978 -123.601696) (xy 150.351254 -123.564194) (xy 150.399427 -123.533233) (xy 150.451516 -123.509442)
			(xy 150.50646 -123.493305) (xy 150.563142 -123.485152) (xy 150.591774 -123.48464) (xy 150.606688 -123.484746)
			(xy 150.636437 -123.486909) (xy 150.65121 -123.488958) (xy 150.662386 -123.490736) (xy 150.683468 -123.48464)
			(xy 150.75027 -123.426982) (xy 150.758256 -123.419407) (xy 150.767328 -123.399373) (xy 150.767796 -123.388374)
			(xy 150.767796 -123.123706) (xy 150.767288 -123.112717) (xy 150.758215 -123.092705) (xy 150.75027 -123.085098)
			(xy 150.683468 -123.02744) (xy 150.662386 -123.021344) (xy 150.65121 -123.023122) (xy 150.636438 -123.025176)
			(xy 150.606688 -123.027333) (xy 150.591774 -123.02744) (xy 150.563147 -123.026872) (xy 150.506476 -123.01872)
			(xy 150.451543 -123.002587) (xy 150.399464 -122.978801) (xy 150.3513 -122.947845) (xy 150.308032 -122.91035)
			(xy 150.27054 -122.867079) (xy 150.239587 -122.818913) (xy 150.215804 -122.766833) (xy 150.199674 -122.711898)
			(xy 150.191526 -122.655227) (xy 150.191526 -122.597973) (xy 150.199674 -122.541302) (xy 150.215804 -122.486367)
			(xy 150.239587 -122.434287) (xy 150.27054 -122.386121) (xy 150.308032 -122.34285) (xy 150.3513 -122.305355)
			(xy 150.399464 -122.274399) (xy 150.451543 -122.250613) (xy 150.506476 -122.23448) (xy 150.563147 -122.226328)
			(xy 150.591774 -122.225816) (xy 150.619143 -122.226307) (xy 150.673374 -122.233748) (xy 150.726088 -122.248496)
			(xy 150.776307 -122.270277) (xy 150.823097 -122.298686) (xy 150.865588 -122.333194) (xy 150.902991 -122.373161)
			(xy 150.91918 -122.395234) (xy 150.924764 -122.402476) (xy 150.939857 -122.412772) (xy 150.948644 -122.4153)
			(xy 150.978616 -122.422666) (xy 150.987565 -122.424419) (xy 151.005655 -122.422199) (xy 151.013922 -122.418348)
			(xy 151.038521 -122.405973) (xy 151.090059 -122.386575) (xy 151.14355 -122.373497) (xy 151.198224 -122.366925)
			(xy 151.225758 -122.366532) (xy 151.253293 -122.366904) (xy 151.307968 -122.373475) (xy 151.361458 -122.386564)
			(xy 151.41299 -122.40598) (xy 151.437594 -122.418348) (xy 151.445855 -122.422222) (xy 151.463951 -122.42444)
			(xy 151.4729 -122.422666) (xy 151.502872 -122.4153) (xy 151.511643 -122.412728) (xy 151.526749 -122.402466)
			(xy 151.532336 -122.395234) (xy 151.548495 -122.373137) (xy 151.585902 -122.333167) (xy 151.628397 -122.298657)
			(xy 151.675192 -122.270247) (xy 151.725415 -122.248466) (xy 151.778135 -122.233719) (xy 151.83237 -122.226279)
			(xy 151.859742 -122.225816) (xy 151.888372 -122.226273) (xy 151.945049 -122.234428) (xy 151.999989 -122.250565)
			(xy 152.052073 -122.274356) (xy 152.100241 -122.305316) (xy 152.143514 -122.342816) (xy 152.181009 -122.386092)
			(xy 152.211965 -122.434264) (xy 152.23575 -122.486351) (xy 152.251881 -122.541292) (xy 152.26003 -122.59797)
			(xy 152.26003 -122.65523) (xy 152.251881 -122.711908) (xy 152.23575 -122.766849) (xy 152.211965 -122.818936)
			(xy 152.181009 -122.867108) (xy 152.143514 -122.910384) (xy 152.100241 -122.947884) (xy 152.052073 -122.978844)
			(xy 151.999989 -123.002635) (xy 151.945049 -123.018772) (xy 151.888372 -123.026927) (xy 151.859742 -123.02744)
			(xy 151.844828 -123.027332) (xy 151.815079 -123.02517) (xy 151.800306 -123.023122) (xy 151.78913 -123.021344)
			(xy 151.768048 -123.02744) (xy 151.701246 -123.085098) (xy 151.693272 -123.092684) (xy 151.684193 -123.112709)
			(xy 151.68372 -123.123706) (xy 151.68372 -123.388374) (xy 151.684178 -123.399369) (xy 151.693286 -123.419381)
			(xy 151.701246 -123.426982) (xy 151.768048 -123.48464) (xy 151.78913 -123.490736) (xy 151.800306 -123.488958)
			(xy 151.81508 -123.486914) (xy 151.844828 -123.48475) (xy 151.859742 -123.48464) (xy 151.888367 -123.485249)
			(xy 151.945033 -123.493402) (xy 151.999962 -123.509536) (xy 152.052036 -123.533322) (xy 152.100196 -123.564277)
			(xy 152.14346 -123.60177) (xy 152.180948 -123.645038) (xy 152.211898 -123.693201) (xy 152.235679 -123.745277)
			(xy 152.251807 -123.800208) (xy 152.259954 -123.856875) (xy 152.259954 -123.914125) (xy 152.251807 -123.970792)
			(xy 152.235679 -124.025723) (xy 152.211898 -124.077799) (xy 152.180948 -124.125962) (xy 152.14346 -124.16923)
			(xy 152.100196 -124.206723) (xy 152.052036 -124.237678) (xy 151.999962 -124.261464) (xy 151.945033 -124.277598)
			(xy 151.888367 -124.285751) (xy 151.859742 -124.286264) (xy 151.832373 -124.28577) (xy 151.778142 -124.27833)
			(xy 151.725427 -124.263583) (xy 151.675208 -124.241803) (xy 151.628418 -124.213395) (xy 151.585927 -124.178886)
			(xy 151.548525 -124.138919) (xy 151.532336 -124.116846) (xy 151.526751 -124.109605) (xy 151.511658 -124.099309)
			(xy 151.502872 -124.09678) (xy 151.4729 -124.089414) (xy 151.463949 -124.087671) (xy 151.445861 -124.089884)
			(xy 151.437594 -124.093732) (xy 151.412992 -124.1061) (xy 151.361455 -124.125499) (xy 151.307965 -124.13858)
			(xy 151.253292 -124.145154) (xy 151.225758 -124.145548) (xy 151.198224 -124.145172) (xy 151.143549 -124.138602)
			(xy 151.090058 -124.125515) (xy 151.038526 -124.106099) (xy 151.013922 -124.093732) (xy 151.005658 -124.089866)
			(xy 150.987565 -124.087643) (xy 150.978616 -124.089414) (xy 150.948644 -124.09678) (xy 150.939852 -124.099294)
			(xy 150.924756 -124.109596) (xy 150.91918 -124.116846) (xy 150.903005 -124.138931) (xy 150.865602 -124.178902)
			(xy 150.823109 -124.213414) (xy 150.776318 -124.241825) (xy 150.726096 -124.263608) (xy 150.673379 -124.278358)
			(xy 150.619145 -124.2858) (xy 150.591774 -124.286264) (xy 150.563142 -124.285848) (xy 150.50646 -124.277695)
			(xy 150.451516 -124.261558) (xy 150.399427 -124.237767) (xy 150.351254 -124.206806) (xy 150.307978 -124.169304)
			(xy 150.270479 -124.126025) (xy 150.23952 -124.07785) (xy 150.215733 -124.02576) (xy 150.1996 -123.970814)
			(xy 150.191451 -123.914132) (xy 140.456412 -123.914132) (xy 140.456412 -125.720851) (xy 152.833299 -125.720851)
			(xy 152.833299 -125.663549) (xy 152.841453 -125.606831) (xy 152.857597 -125.55185) (xy 152.8814 -125.499727)
			(xy 152.912379 -125.451521) (xy 152.949902 -125.408215) (xy 152.993207 -125.370689) (xy 153.041411 -125.339709)
			(xy 153.093534 -125.315903) (xy 153.148513 -125.299757) (xy 153.205231 -125.2916) (xy 153.233882 -125.291088)
			(xy 153.2488 -125.291253) (xy 153.278549 -125.293545) (xy 153.293318 -125.29566) (xy 153.304494 -125.297438)
			(xy 153.325576 -125.291342) (xy 153.392378 -125.233684) (xy 153.400364 -125.226109) (xy 153.409435 -125.206075)
			(xy 153.409904 -125.195076) (xy 153.409904 -124.930408) (xy 153.409393 -124.91942) (xy 153.400321 -124.899408)
			(xy 153.392378 -124.8918) (xy 153.325576 -124.834142) (xy 153.304494 -124.828046) (xy 153.293318 -124.829824)
			(xy 153.278549 -124.831933) (xy 153.2488 -124.834221) (xy 153.233882 -124.834396) (xy 153.205237 -124.833824)
			(xy 153.14853 -124.825668) (xy 153.09356 -124.809525) (xy 153.041448 -124.785724) (xy 152.993253 -124.754749)
			(xy 152.949956 -124.717231) (xy 152.91244 -124.673933) (xy 152.881467 -124.625736) (xy 152.857668 -124.573623)
			(xy 152.841528 -124.518653) (xy 152.833375 -124.461945) (xy 152.833375 -124.404655) (xy 152.841528 -124.347947)
			(xy 152.857668 -124.292977) (xy 152.881467 -124.240864) (xy 152.91244 -124.192667) (xy 152.949956 -124.149369)
			(xy 152.993253 -124.111851) (xy 153.041448 -124.080876) (xy 153.09356 -124.057075) (xy 153.14853 -124.040932)
			(xy 153.205237 -124.032776) (xy 153.233882 -124.032264) (xy 153.261262 -124.032759) (xy 153.31551 -124.040223)
			(xy 153.368237 -124.055002) (xy 153.418463 -124.07682) (xy 153.465251 -124.10527) (xy 153.507731 -124.139825)
			(xy 153.545113 -124.17984) (xy 153.561288 -124.201936) (xy 153.566869 -124.209181) (xy 153.581964 -124.219475)
			(xy 153.590752 -124.222002) (xy 153.620724 -124.229368) (xy 153.629673 -124.231125) (xy 153.647763 -124.228903)
			(xy 153.65603 -124.22505) (xy 153.680624 -124.212648) (xy 153.732152 -124.193183) (xy 153.785643 -124.180038)
			(xy 153.840325 -124.173404) (xy 153.867866 -124.17298) (xy 153.895407 -124.173394) (xy 153.950088 -124.180033)
			(xy 154.003578 -124.193184) (xy 154.055103 -124.212657) (xy 154.079702 -124.22505) (xy 154.087961 -124.228928)
			(xy 154.106058 -124.231144) (xy 154.115008 -124.229368) (xy 154.14498 -124.222002) (xy 154.153752 -124.219433)
			(xy 154.168857 -124.209168) (xy 154.174444 -124.201936) (xy 154.190593 -124.179816) (xy 154.227967 -124.139784)
			(xy 154.270447 -124.105216) (xy 154.317239 -124.076756) (xy 154.367472 -124.054935) (xy 154.420208 -124.040161)
			(xy 154.474466 -124.032707) (xy 154.50185 -124.032264) (xy 154.530504 -124.032687) (xy 154.587231 -124.040837)
			(xy 154.64222 -124.056977) (xy 154.694352 -124.080779) (xy 154.742566 -124.111759) (xy 154.785879 -124.149285)
			(xy 154.790785 -124.154946) (xy 160.769552 -124.154946) (xy 160.773623 -124.099324) (xy 160.785749 -124.044887)
			(xy 160.805672 -123.992796) (xy 160.832968 -123.944161) (xy 160.867054 -123.900018) (xy 160.907203 -123.861309)
			(xy 160.952561 -123.828858) (xy 161.002161 -123.803357) (xy 161.054945 -123.78535) (xy 161.109788 -123.77522)
			(xy 161.165522 -123.773183) (xy 161.220959 -123.779283) (xy 161.274916 -123.793389) (xy 161.326245 -123.815201)
			(xy 161.373851 -123.844255) (xy 161.415114 -123.878594) (xy 165.23665 -123.878594) (xy 165.240721 -123.822972)
			(xy 165.252847 -123.768535) (xy 165.27277 -123.716444) (xy 165.300066 -123.667809) (xy 165.334152 -123.623666)
			(xy 165.374301 -123.584957) (xy 165.419659 -123.552506) (xy 165.469259 -123.527005) (xy 165.522043 -123.508998)
			(xy 165.576886 -123.498868) (xy 165.63262 -123.496831) (xy 165.688057 -123.502931) (xy 165.742014 -123.517037)
			(xy 165.793343 -123.538849) (xy 165.840949 -123.567903) (xy 165.883817 -123.603578) (xy 165.921034 -123.645115)
			(xy 165.951807 -123.691628) (xy 165.975479 -123.742125) (xy 165.991547 -123.795532) (xy 165.999667 -123.850708)
			(xy 166.000176 -123.878594) (xy 165.999667 -123.90648) (xy 165.991547 -123.961656) (xy 165.975479 -124.015063)
			(xy 165.951807 -124.06556) (xy 165.921034 -124.112073) (xy 165.883817 -124.15361) (xy 165.840949 -124.189285)
			(xy 165.793343 -124.218339) (xy 165.742014 -124.240151) (xy 165.688057 -124.254257) (xy 165.63262 -124.260357)
			(xy 165.576886 -124.25832) (xy 165.522043 -124.24819) (xy 165.469259 -124.230183) (xy 165.419659 -124.204682)
			(xy 165.374301 -124.172231) (xy 165.334152 -124.133522) (xy 165.300066 -124.089379) (xy 165.27277 -124.040744)
			(xy 165.252847 -123.988653) (xy 165.240721 -123.934216) (xy 165.23665 -123.878594) (xy 161.415114 -123.878594)
			(xy 161.416719 -123.87993) (xy 161.453936 -123.921467) (xy 161.484709 -123.96798) (xy 161.508381 -124.018477)
			(xy 161.524449 -124.071884) (xy 161.532569 -124.12706) (xy 161.533078 -124.154946) (xy 161.532569 -124.182832)
			(xy 161.524449 -124.238008) (xy 161.508381 -124.291415) (xy 161.484709 -124.341912) (xy 161.453936 -124.388425)
			(xy 161.416719 -124.429962) (xy 161.373851 -124.465637) (xy 161.326245 -124.494691) (xy 161.274916 -124.516503)
			(xy 161.220959 -124.530609) (xy 161.165522 -124.536709) (xy 161.109788 -124.534672) (xy 161.054945 -124.524542)
			(xy 161.002161 -124.506535) (xy 160.952561 -124.481034) (xy 160.907203 -124.448583) (xy 160.867054 -124.409874)
			(xy 160.832968 -124.365731) (xy 160.805672 -124.317096) (xy 160.785749 -124.265005) (xy 160.773623 -124.210568)
			(xy 160.769552 -124.154946) (xy 154.790785 -124.154946) (xy 154.823411 -124.192594) (xy 154.854397 -124.240804)
			(xy 154.878205 -124.292933) (xy 154.894352 -124.34792) (xy 154.902509 -124.404646) (xy 154.902509 -124.461954)
			(xy 154.894352 -124.51868) (xy 154.878205 -124.573667) (xy 154.854397 -124.625796) (xy 154.823411 -124.674006)
			(xy 154.785879 -124.717315) (xy 154.742566 -124.754841) (xy 154.694352 -124.785821) (xy 154.64222 -124.809623)
			(xy 154.587231 -124.825763) (xy 154.530504 -124.833913) (xy 154.50185 -124.834396) (xy 154.486932 -124.834227)
			(xy 154.457183 -124.831938) (xy 154.442414 -124.829824) (xy 154.431238 -124.828046) (xy 154.410156 -124.834142)
			(xy 154.343354 -124.8918) (xy 154.33538 -124.899386) (xy 154.326301 -124.919411) (xy 154.325828 -124.930408)
			(xy 154.325828 -125.195076) (xy 154.326282 -125.206071) (xy 154.335392 -125.226084) (xy 154.343354 -125.233684)
			(xy 154.410156 -125.291342) (xy 154.431238 -125.297438) (xy 154.442414 -125.29566) (xy 154.457183 -125.293547)
			(xy 154.486932 -125.291262) (xy 154.50185 -125.291088) (xy 154.530499 -125.291663) (xy 154.587215 -125.299811)
			(xy 154.642193 -125.315948) (xy 154.694316 -125.339746) (xy 154.74252 -125.37072) (xy 154.785826 -125.408239)
			(xy 154.82335 -125.45154) (xy 154.85433 -125.49974) (xy 154.878134 -125.55186) (xy 154.894278 -125.606836)
			(xy 154.902433 -125.663551) (xy 154.902433 -125.720849) (xy 154.894278 -125.777564) (xy 154.878134 -125.83254)
			(xy 154.85433 -125.88466) (xy 154.82335 -125.93286) (xy 154.804126 -125.955044) (xy 160.769552 -125.955044)
			(xy 160.773623 -125.899422) (xy 160.785749 -125.844985) (xy 160.805672 -125.792894) (xy 160.832968 -125.744259)
			(xy 160.867054 -125.700116) (xy 160.907203 -125.661407) (xy 160.952561 -125.628956) (xy 161.002161 -125.603455)
			(xy 161.054945 -125.585448) (xy 161.109788 -125.575318) (xy 161.165522 -125.573281) (xy 161.220959 -125.579381)
			(xy 161.274916 -125.593487) (xy 161.326245 -125.615299) (xy 161.373851 -125.644353) (xy 161.416719 -125.680028)
			(xy 161.453936 -125.721565) (xy 161.484709 -125.768078) (xy 161.508381 -125.818575) (xy 161.524449 -125.871982)
			(xy 161.532569 -125.927158) (xy 161.533078 -125.955044) (xy 165.369746 -125.955044) (xy 165.373817 -125.899422)
			(xy 165.385943 -125.844985) (xy 165.405866 -125.792894) (xy 165.433162 -125.744259) (xy 165.467248 -125.700116)
			(xy 165.507397 -125.661407) (xy 165.552755 -125.628956) (xy 165.602355 -125.603455) (xy 165.655139 -125.585448)
			(xy 165.709982 -125.575318) (xy 165.765716 -125.573281) (xy 165.821153 -125.579381) (xy 165.87511 -125.593487)
			(xy 165.926439 -125.615299) (xy 165.974045 -125.644353) (xy 166.016913 -125.680028) (xy 166.05413 -125.721565)
			(xy 166.084903 -125.768078) (xy 166.108575 -125.818575) (xy 166.124643 -125.871982) (xy 166.132763 -125.927158)
			(xy 166.133272 -125.955044) (xy 166.132763 -125.98293) (xy 166.124643 -126.038106) (xy 166.108575 -126.091513)
			(xy 166.084903 -126.14201) (xy 166.05413 -126.188523) (xy 166.016913 -126.23006) (xy 165.974045 -126.265735)
			(xy 165.926439 -126.294789) (xy 165.87511 -126.316601) (xy 165.821153 -126.330707) (xy 165.765716 -126.336807)
			(xy 165.709982 -126.33477) (xy 165.655139 -126.32464) (xy 165.602355 -126.306633) (xy 165.552755 -126.281132)
			(xy 165.507397 -126.248681) (xy 165.467248 -126.209972) (xy 165.433162 -126.165829) (xy 165.405866 -126.117194)
			(xy 165.385943 -126.065103) (xy 165.373817 -126.010666) (xy 165.369746 -125.955044) (xy 161.533078 -125.955044)
			(xy 161.532569 -125.98293) (xy 161.524449 -126.038106) (xy 161.508381 -126.091513) (xy 161.484709 -126.14201)
			(xy 161.453936 -126.188523) (xy 161.416719 -126.23006) (xy 161.373851 -126.265735) (xy 161.326245 -126.294789)
			(xy 161.274916 -126.316601) (xy 161.220959 -126.330707) (xy 161.165522 -126.336807) (xy 161.109788 -126.33477)
			(xy 161.054945 -126.32464) (xy 161.002161 -126.306633) (xy 160.952561 -126.281132) (xy 160.907203 -126.248681)
			(xy 160.867054 -126.209972) (xy 160.832968 -126.165829) (xy 160.805672 -126.117194) (xy 160.785749 -126.065103)
			(xy 160.773623 -126.010666) (xy 160.769552 -125.955044) (xy 154.804126 -125.955044) (xy 154.785826 -125.976161)
			(xy 154.74252 -126.01368) (xy 154.694316 -126.044654) (xy 154.642193 -126.068452) (xy 154.587215 -126.084589)
			(xy 154.530499 -126.092737) (xy 154.50185 -126.09322) (xy 154.474468 -126.092783) (xy 154.420217 -126.085309)
			(xy 154.367488 -126.070521) (xy 154.317263 -126.048694) (xy 154.270475 -126.020234) (xy 154.227996 -125.985671)
			(xy 154.190617 -125.945648) (xy 154.174444 -125.923548) (xy 154.16889 -125.916279) (xy 154.153775 -125.905999)
			(xy 154.14498 -125.903482) (xy 154.115008 -125.896116) (xy 154.106057 -125.894377) (xy 154.087969 -125.896588)
			(xy 154.079702 -125.900434) (xy 154.055102 -125.912823) (xy 154.003576 -125.932292) (xy 153.950087 -125.94544)
			(xy 153.895407 -125.952078) (xy 153.867866 -125.952504) (xy 153.840325 -125.952079) (xy 153.785645 -125.945443)
			(xy 153.732155 -125.932295) (xy 153.680629 -125.912826) (xy 153.65603 -125.900434) (xy 153.647765 -125.896572)
			(xy 153.629673 -125.894346) (xy 153.620724 -125.896116) (xy 153.590752 -125.903482) (xy 153.581961 -125.905998)
			(xy 153.566864 -125.916299) (xy 153.561288 -125.923548) (xy 153.545115 -125.945649) (xy 153.507745 -125.985683)
			(xy 153.46527 -126.020253) (xy 153.418482 -126.048715) (xy 153.368253 -126.070539) (xy 153.31552 -126.085317)
			(xy 153.261265 -126.092774) (xy 153.233882 -126.09322) (xy 153.205231 -126.0928) (xy 153.148513 -126.084643)
			(xy 153.093534 -126.068497) (xy 153.041411 -126.044691) (xy 152.993207 -126.013711) (xy 152.949902 -125.976185)
			(xy 152.912379 -125.932879) (xy 152.8814 -125.884673) (xy 152.857597 -125.83255) (xy 152.841453 -125.777569)
			(xy 152.833299 -125.720851) (xy 140.456412 -125.720851) (xy 140.456412 -128.189736) (xy 151.62733 -128.189736)
			(xy 151.631401 -128.134114) (xy 151.643527 -128.079677) (xy 151.66345 -128.027586) (xy 151.690746 -127.978951)
			(xy 151.724832 -127.934808) (xy 151.764981 -127.896099) (xy 151.810339 -127.863648) (xy 151.859939 -127.838147)
			(xy 151.912723 -127.82014) (xy 151.967566 -127.81001) (xy 152.0233 -127.807973) (xy 152.078737 -127.814073)
			(xy 152.132694 -127.828179) (xy 152.184023 -127.849991) (xy 152.231629 -127.879045) (xy 152.274497 -127.91472)
			(xy 152.311079 -127.955548) (xy 162.57524 -127.955548) (xy 162.57524 -127.95504) (xy 162.575753 -127.910143)
			(xy 162.58431 -127.820757) (xy 162.601349 -127.732594) (xy 162.626716 -127.646457) (xy 162.660178 -127.563131)
			(xy 162.701433 -127.483374) (xy 162.750103 -127.407914) (xy 162.805745 -127.337437) (xy 162.867852 -127.272586)
			(xy 162.93586 -127.213951) (xy 163.009147 -127.162067) (xy 163.087047 -127.117405) (xy 163.16885 -127.080374)
			(xy 163.253811 -127.05131) (xy 163.297362 -127.040386) (xy 163.309046 -127.037592) (xy 163.327334 -127.022352)
			(xy 163.369498 -126.925832) (xy 163.368228 -126.90221) (xy 163.362386 -126.891542) (xy 163.35062 -126.869997)
			(xy 163.332107 -126.82453) (xy 163.319582 -126.777063) (xy 163.313252 -126.728381) (xy 163.312856 -126.703836)
			(xy 163.313342 -126.676585) (xy 163.321098 -126.622637) (xy 163.336453 -126.570342) (xy 163.359095 -126.520765)
			(xy 163.388561 -126.474915) (xy 163.424252 -126.433724) (xy 163.465443 -126.398033) (xy 163.511293 -126.368567)
			(xy 163.56087 -126.345925) (xy 163.613165 -126.33057) (xy 163.667113 -126.322814) (xy 163.721615 -126.322814)
			(xy 163.775563 -126.33057) (xy 163.827858 -126.345925) (xy 163.877435 -126.368567) (xy 163.923285 -126.398033)
			(xy 163.964476 -126.433724) (xy 164.000167 -126.474915) (xy 164.029633 -126.520765) (xy 164.052275 -126.570342)
			(xy 164.06763 -126.622637) (xy 164.075386 -126.676585) (xy 164.075872 -126.703836) (xy 164.075872 -126.704344)
			(xy 164.075311 -126.732772) (xy 164.06683 -126.788992) (xy 164.050107 -126.843333) (xy 164.03828 -126.86919)
			(xy 164.03828 -126.869444) (xy 164.034908 -126.877275) (xy 164.033027 -126.89421) (xy 164.036824 -126.910821)
			(xy 164.041074 -126.918212) (xy 164.08654 -126.990856) (xy 164.091406 -126.997964) (xy 164.104868 -127.008693)
			(xy 164.121113 -127.014389) (xy 164.12972 -127.014732) (xy 165.369494 -127.014732) (xy 165.412947 -127.015138)
			(xy 165.499481 -127.023156) (xy 165.584907 -127.039125) (xy 165.668494 -127.062907) (xy 165.749531 -127.0943)
			(xy 165.827326 -127.133037) (xy 165.901214 -127.178786) (xy 165.970566 -127.231158) (xy 166.03479 -127.289706)
			(xy 166.093338 -127.353929) (xy 166.14571 -127.423281) (xy 166.19146 -127.497169) (xy 166.230197 -127.574963)
			(xy 166.261591 -127.656) (xy 166.285374 -127.739587) (xy 166.301343 -127.825013) (xy 166.309362 -127.911547)
			(xy 166.309362 -127.998453) (xy 166.301343 -128.084987) (xy 166.285374 -128.170413) (xy 166.261591 -128.254)
			(xy 166.230197 -128.335037) (xy 166.19146 -128.412831) (xy 166.14571 -128.486719) (xy 166.093338 -128.556071)
			(xy 166.03479 -128.620294) (xy 165.970566 -128.678842) (xy 165.901214 -128.731214) (xy 165.827326 -128.776963)
			(xy 165.749531 -128.8157) (xy 165.668494 -128.847093) (xy 165.584907 -128.870875) (xy 165.499481 -128.886844)
			(xy 165.412947 -128.894862) (xy 165.369494 -128.895348) (xy 163.515294 -128.895348) (xy 163.471863 -128.894858)
			(xy 163.385372 -128.886845) (xy 163.299988 -128.870886) (xy 163.216441 -128.847119) (xy 163.135443 -128.815745)
			(xy 163.057685 -128.777033) (xy 162.983829 -128.731313) (xy 162.914507 -128.678974) (xy 162.850308 -128.620463)
			(xy 162.791781 -128.55628) (xy 162.739424 -128.48697) (xy 162.693685 -128.413127) (xy 162.654953 -128.335378)
			(xy 162.623558 -128.254388) (xy 162.599769 -128.170847) (xy 162.583789 -128.085468) (xy 162.575753 -127.998979)
			(xy 162.57524 -127.955548) (xy 152.311079 -127.955548) (xy 152.311714 -127.956257) (xy 152.342487 -128.00277)
			(xy 152.366159 -128.053267) (xy 152.382227 -128.106674) (xy 152.390347 -128.16185) (xy 152.390856 -128.189736)
			(xy 152.390347 -128.217622) (xy 152.382227 -128.272798) (xy 152.366159 -128.326205) (xy 152.342487 -128.376702)
			(xy 152.311714 -128.423215) (xy 152.274497 -128.464752) (xy 152.231629 -128.500427) (xy 152.184023 -128.529481)
			(xy 152.132694 -128.551293) (xy 152.078737 -128.565399) (xy 152.0233 -128.571499) (xy 151.967566 -128.569462)
			(xy 151.912723 -128.559332) (xy 151.859939 -128.541325) (xy 151.810339 -128.515824) (xy 151.764981 -128.483373)
			(xy 151.724832 -128.444664) (xy 151.690746 -128.400521) (xy 151.66345 -128.351886) (xy 151.643527 -128.299795)
			(xy 151.631401 -128.245358) (xy 151.62733 -128.189736) (xy 140.456412 -128.189736) (xy 140.456412 -131.524144)
			(xy 150.191291 -131.524144) (xy 150.191291 -131.466856) (xy 150.199444 -131.410152) (xy 150.215583 -131.355184)
			(xy 150.23938 -131.303073) (xy 150.270351 -131.254879) (xy 150.307865 -131.211583) (xy 150.351159 -131.174066)
			(xy 150.399351 -131.143092) (xy 150.45146 -131.119292) (xy 150.506426 -131.103149) (xy 150.56313 -131.094993)
			(xy 150.591774 -131.09448) (xy 150.606692 -131.094646) (xy 150.636441 -131.096937) (xy 150.65121 -131.099052)
			(xy 150.662386 -131.10083) (xy 150.683468 -131.094734) (xy 150.75027 -131.037076) (xy 150.758259 -131.029503)
			(xy 150.767329 -131.009468) (xy 150.767796 -130.998468) (xy 150.767796 -130.713988) (xy 150.767266 -130.702968)
			(xy 150.758041 -130.682952) (xy 150.750016 -130.67538) (xy 150.68296 -130.617976) (xy 150.661878 -130.61188)
			(xy 150.650702 -130.613658) (xy 150.636127 -130.615787) (xy 150.606757 -130.618078) (xy 150.592028 -130.61823)
			(xy 150.59152 -130.61823) (xy 150.564268 -130.617724) (xy 150.510318 -130.60997) (xy 150.458021 -130.594616)
			(xy 150.408441 -130.571976) (xy 150.362588 -130.542511) (xy 150.321395 -130.506819) (xy 150.285701 -130.465628)
			(xy 150.256233 -130.419777) (xy 150.233591 -130.370198) (xy 150.218234 -130.317902) (xy 150.210477 -130.263952)
			(xy 150.210477 -130.209448) (xy 150.218234 -130.155498) (xy 150.233591 -130.103202) (xy 150.256233 -130.053623)
			(xy 150.285701 -130.007772) (xy 150.321395 -129.966581) (xy 150.362588 -129.930889) (xy 150.408441 -129.901424)
			(xy 150.458021 -129.878784) (xy 150.510318 -129.86343) (xy 150.564268 -129.855676) (xy 150.59152 -129.855214)
			(xy 150.617458 -129.855617) (xy 150.668855 -129.862649) (xy 150.718825 -129.87658) (xy 150.766447 -129.897154)
			(xy 150.810842 -129.923991) (xy 150.851191 -129.956595) (xy 150.88675 -129.994367) (xy 150.902162 -130.015234)
			(xy 150.90799 -130.022561) (xy 150.923605 -130.032859) (xy 150.932642 -130.0353) (xy 150.962614 -130.042158)
			(xy 150.97191 -130.043854) (xy 150.990574 -130.040973) (xy 150.998936 -130.03657) (xy 151.024943 -130.02227)
			(xy 151.079867 -129.99978) (xy 151.137233 -129.984559) (xy 151.196083 -129.976862) (xy 151.225758 -129.976372)
			(xy 151.255394 -129.976837) (xy 151.314169 -129.984486) (xy 151.371469 -129.999647) (xy 151.426336 -130.022068)
			(xy 151.452326 -130.036316) (xy 151.46071 -130.040648) (xy 151.479348 -130.043508) (xy 151.488648 -130.041904)
			(xy 151.51862 -130.035046) (xy 151.527706 -130.032708) (xy 151.543367 -130.022406) (xy 151.5491 -130.01498)
			(xy 151.564486 -129.994127) (xy 151.600032 -129.956416) (xy 151.640358 -129.923867) (xy 151.684721 -129.897079)
			(xy 151.732304 -129.876548) (xy 151.782229 -129.86265) (xy 151.833576 -129.855643) (xy 151.859488 -129.855214)
			(xy 151.886743 -129.855632) (xy 151.940698 -129.863388) (xy 151.993001 -129.878744) (xy 152.042585 -129.901387)
			(xy 152.088443 -129.930857) (xy 152.127781 -129.964942) (xy 160.769552 -129.964942) (xy 160.773623 -129.90932)
			(xy 160.785749 -129.854883) (xy 160.805672 -129.802792) (xy 160.832968 -129.754157) (xy 160.867054 -129.710014)
			(xy 160.907203 -129.671305) (xy 160.952561 -129.638854) (xy 161.002161 -129.613353) (xy 161.054945 -129.595346)
			(xy 161.109788 -129.585216) (xy 161.165522 -129.583179) (xy 161.220959 -129.589279) (xy 161.274916 -129.603385)
			(xy 161.326245 -129.625197) (xy 161.373851 -129.654251) (xy 161.416719 -129.689926) (xy 161.453936 -129.731463)
			(xy 161.484709 -129.777976) (xy 161.508381 -129.828473) (xy 161.524449 -129.88188) (xy 161.532569 -129.937056)
			(xy 161.533078 -129.964942) (xy 162.750752 -129.964942) (xy 162.754823 -129.90932) (xy 162.766949 -129.854883)
			(xy 162.786872 -129.802792) (xy 162.814168 -129.754157) (xy 162.848254 -129.710014) (xy 162.888403 -129.671305)
			(xy 162.933761 -129.638854) (xy 162.983361 -129.613353) (xy 163.036145 -129.595346) (xy 163.090988 -129.585216)
			(xy 163.146722 -129.583179) (xy 163.202159 -129.589279) (xy 163.256116 -129.603385) (xy 163.307445 -129.625197)
			(xy 163.355051 -129.654251) (xy 163.390209 -129.68351) (xy 165.014146 -129.68351) (xy 165.018217 -129.627888)
			(xy 165.030343 -129.573451) (xy 165.050266 -129.52136) (xy 165.077562 -129.472725) (xy 165.111648 -129.428582)
			(xy 165.151797 -129.389873) (xy 165.197155 -129.357422) (xy 165.246755 -129.331921) (xy 165.299539 -129.313914)
			(xy 165.354382 -129.303784) (xy 165.410116 -129.301747) (xy 165.465553 -129.307847) (xy 165.51951 -129.321953)
			(xy 165.570839 -129.343765) (xy 165.618445 -129.372819) (xy 165.661313 -129.408494) (xy 165.69853 -129.450031)
			(xy 165.729303 -129.496544) (xy 165.752975 -129.547041) (xy 165.769043 -129.600448) (xy 165.777163 -129.655624)
			(xy 165.777672 -129.68351) (xy 165.777163 -129.711396) (xy 165.769043 -129.766572) (xy 165.752975 -129.819979)
			(xy 165.729303 -129.870476) (xy 165.69853 -129.916989) (xy 165.661313 -129.958526) (xy 165.653603 -129.964942)
			(xy 167.350946 -129.964942) (xy 167.355017 -129.90932) (xy 167.367143 -129.854883) (xy 167.387066 -129.802792)
			(xy 167.414362 -129.754157) (xy 167.448448 -129.710014) (xy 167.488597 -129.671305) (xy 167.533955 -129.638854)
			(xy 167.583555 -129.613353) (xy 167.636339 -129.595346) (xy 167.691182 -129.585216) (xy 167.746916 -129.583179)
			(xy 167.802353 -129.589279) (xy 167.85631 -129.603385) (xy 167.907639 -129.625197) (xy 167.955245 -129.654251)
			(xy 167.998113 -129.689926) (xy 168.03533 -129.731463) (xy 168.066103 -129.777976) (xy 168.089775 -129.828473)
			(xy 168.105843 -129.88188) (xy 168.113963 -129.937056) (xy 168.114472 -129.964942) (xy 168.113963 -129.992828)
			(xy 168.105843 -130.048004) (xy 168.089775 -130.101411) (xy 168.066103 -130.151908) (xy 168.03533 -130.198421)
			(xy 167.998113 -130.239958) (xy 167.955245 -130.275633) (xy 167.907639 -130.304687) (xy 167.85631 -130.326499)
			(xy 167.802353 -130.340605) (xy 167.746916 -130.346705) (xy 167.691182 -130.344668) (xy 167.636339 -130.334538)
			(xy 167.583555 -130.316531) (xy 167.533955 -130.29103) (xy 167.488597 -130.258579) (xy 167.448448 -130.21987)
			(xy 167.414362 -130.175727) (xy 167.387066 -130.127092) (xy 167.367143 -130.075001) (xy 167.355017 -130.020564)
			(xy 167.350946 -129.964942) (xy 165.653603 -129.964942) (xy 165.618445 -129.994201) (xy 165.570839 -130.023255)
			(xy 165.51951 -130.045067) (xy 165.465553 -130.059173) (xy 165.410116 -130.065273) (xy 165.354382 -130.063236)
			(xy 165.299539 -130.053106) (xy 165.246755 -130.035099) (xy 165.197155 -130.009598) (xy 165.151797 -129.977147)
			(xy 165.111648 -129.938438) (xy 165.077562 -129.894295) (xy 165.050266 -129.84566) (xy 165.030343 -129.793569)
			(xy 165.018217 -129.739132) (xy 165.014146 -129.68351) (xy 163.390209 -129.68351) (xy 163.397919 -129.689926)
			(xy 163.435136 -129.731463) (xy 163.465909 -129.777976) (xy 163.489581 -129.828473) (xy 163.505649 -129.88188)
			(xy 163.513769 -129.937056) (xy 163.514278 -129.964942) (xy 163.513769 -129.992828) (xy 163.505649 -130.048004)
			(xy 163.489581 -130.101411) (xy 163.465909 -130.151908) (xy 163.435136 -130.198421) (xy 163.397919 -130.239958)
			(xy 163.355051 -130.275633) (xy 163.307445 -130.304687) (xy 163.256116 -130.326499) (xy 163.202159 -130.340605)
			(xy 163.146722 -130.346705) (xy 163.090988 -130.344668) (xy 163.036145 -130.334538) (xy 162.983361 -130.316531)
			(xy 162.933761 -130.29103) (xy 162.888403 -130.258579) (xy 162.848254 -130.21987) (xy 162.814168 -130.175727)
			(xy 162.786872 -130.127092) (xy 162.766949 -130.075001) (xy 162.754823 -130.020564) (xy 162.750752 -129.964942)
			(xy 161.533078 -129.964942) (xy 161.532569 -129.992828) (xy 161.524449 -130.048004) (xy 161.508381 -130.101411)
			(xy 161.484709 -130.151908) (xy 161.453936 -130.198421) (xy 161.416719 -130.239958) (xy 161.373851 -130.275633)
			(xy 161.326245 -130.304687) (xy 161.274916 -130.326499) (xy 161.220959 -130.340605) (xy 161.165522 -130.346705)
			(xy 161.109788 -130.344668) (xy 161.054945 -130.334538) (xy 161.002161 -130.316531) (xy 160.952561 -130.29103)
			(xy 160.907203 -130.258579) (xy 160.867054 -130.21987) (xy 160.832968 -130.175727) (xy 160.805672 -130.127092)
			(xy 160.785749 -130.075001) (xy 160.773623 -130.020564) (xy 160.769552 -129.964942) (xy 152.127781 -129.964942)
			(xy 152.129639 -129.966552) (xy 152.165336 -130.007748) (xy 152.194807 -130.053604) (xy 152.217452 -130.103188)
			(xy 152.232809 -130.15549) (xy 152.240567 -130.209445) (xy 152.240567 -130.263955) (xy 152.232809 -130.31791)
			(xy 152.217452 -130.370212) (xy 152.194807 -130.419796) (xy 152.165336 -130.465652) (xy 152.129639 -130.506848)
			(xy 152.088443 -130.542543) (xy 152.042585 -130.572013) (xy 151.993001 -130.594656) (xy 151.940698 -130.610012)
			(xy 151.886743 -130.617768) (xy 151.859488 -130.61823) (xy 151.844759 -130.61808) (xy 151.815389 -130.615793)
			(xy 151.800814 -130.613658) (xy 151.789839 -130.612558) (xy 151.76865 -130.618602) (xy 151.75992 -130.625342)
			(xy 151.7015 -130.67538) (xy 151.693488 -130.682962) (xy 151.684263 -130.702971) (xy 151.68372 -130.713988)
			(xy 151.68372 -130.998468) (xy 151.684181 -131.009462) (xy 151.693287 -131.029475) (xy 151.701246 -131.037076)
			(xy 151.768048 -131.094734) (xy 151.78913 -131.10083) (xy 151.800306 -131.099052) (xy 151.815075 -131.09694)
			(xy 151.844824 -131.094654) (xy 151.859742 -131.09448) (xy 151.888392 -131.094902) (xy 151.945107 -131.103062)
			(xy 152.000084 -131.119209) (xy 152.052203 -131.143016) (xy 152.100404 -131.173998) (xy 152.143706 -131.211523)
			(xy 152.181227 -131.254829) (xy 152.195869 -131.277614) (xy 164.188392 -131.277614) (xy 164.192463 -131.221992)
			(xy 164.204589 -131.167555) (xy 164.224512 -131.115464) (xy 164.251808 -131.066829) (xy 164.285894 -131.022686)
			(xy 164.326043 -130.983977) (xy 164.371401 -130.951526) (xy 164.421001 -130.926025) (xy 164.473785 -130.908018)
			(xy 164.528628 -130.897888) (xy 164.584362 -130.895851) (xy 164.639799 -130.901951) (xy 164.693756 -130.916057)
			(xy 164.745085 -130.937869) (xy 164.792691 -130.966923) (xy 164.835559 -131.002598) (xy 164.872776 -131.044135)
			(xy 164.903549 -131.090648) (xy 164.927221 -131.141145) (xy 164.943289 -131.194552) (xy 164.951409 -131.249728)
			(xy 164.951918 -131.277614) (xy 164.951409 -131.3055) (xy 164.943289 -131.360676) (xy 164.927221 -131.414083)
			(xy 164.903549 -131.46458) (xy 164.872776 -131.511093) (xy 164.835559 -131.55263) (xy 164.792691 -131.588305)
			(xy 164.745085 -131.617359) (xy 164.693756 -131.639171) (xy 164.639799 -131.653277) (xy 164.584362 -131.659377)
			(xy 164.528628 -131.65734) (xy 164.473785 -131.64721) (xy 164.421001 -131.629203) (xy 164.371401 -131.603702)
			(xy 164.326043 -131.571251) (xy 164.285894 -131.532542) (xy 164.251808 -131.488399) (xy 164.224512 -131.439764)
			(xy 164.204589 -131.387673) (xy 164.192463 -131.333236) (xy 164.188392 -131.277614) (xy 152.195869 -131.277614)
			(xy 152.212204 -131.303034) (xy 152.236005 -131.355156) (xy 152.252147 -131.410134) (xy 152.260301 -131.46685)
			(xy 152.260301 -131.52415) (xy 152.252147 -131.580866) (xy 152.236005 -131.635844) (xy 152.212204 -131.687966)
			(xy 152.181227 -131.736171) (xy 152.143706 -131.779477) (xy 152.100404 -131.817002) (xy 152.052203 -131.847984)
			(xy 152.000084 -131.871791) (xy 151.945107 -131.887938) (xy 151.888392 -131.896098) (xy 151.859742 -131.896612)
			(xy 151.83236 -131.896184) (xy 151.778108 -131.888709) (xy 151.725379 -131.87392) (xy 151.675153 -131.852091)
			(xy 151.628366 -131.82363) (xy 151.585887 -131.789065) (xy 151.548509 -131.749041) (xy 151.532336 -131.72694)
			(xy 151.526752 -131.719698) (xy 151.511659 -131.709403) (xy 151.502872 -131.706874) (xy 151.4729 -131.699508)
			(xy 151.463949 -131.697766) (xy 151.445861 -131.699979) (xy 151.437594 -131.703826) (xy 151.412995 -131.716218)
			(xy 151.361468 -131.735686) (xy 151.307979 -131.748834) (xy 151.253299 -131.755471) (xy 151.225758 -131.755896)
			(xy 151.198217 -131.755475) (xy 151.143536 -131.748838) (xy 151.090047 -131.735689) (xy 151.038521 -131.716219)
			(xy 151.013922 -131.703826) (xy 151.005658 -131.69996) (xy 150.987565 -131.697737) (xy 150.978616 -131.699508)
			(xy 150.948644 -131.706874) (xy 150.939853 -131.70939) (xy 150.924756 -131.719691) (xy 150.91918 -131.72694)
			(xy 150.903009 -131.749043) (xy 150.865639 -131.789077) (xy 150.823164 -131.823647) (xy 150.776375 -131.852109)
			(xy 150.726146 -131.873933) (xy 150.673412 -131.88871) (xy 150.619157 -131.896167) (xy 150.591774 -131.896612)
			(xy 150.56313 -131.896007) (xy 150.506426 -131.887851) (xy 150.45146 -131.871708) (xy 150.399351 -131.847908)
			(xy 150.351159 -131.816934) (xy 150.307865 -131.779417) (xy 150.270351 -131.736121) (xy 150.23938 -131.687927)
			(xy 150.215583 -131.635816) (xy 150.199444 -131.580848) (xy 150.191291 -131.524144) (xy 140.456412 -131.524144)
			(xy 140.456412 -132.07185) (xy 152.833315 -132.07185) (xy 152.833315 -132.01455) (xy 152.841469 -131.957834)
			(xy 152.857612 -131.902856) (xy 152.881414 -131.850735) (xy 152.912391 -131.802531) (xy 152.949914 -131.759226)
			(xy 152.993216 -131.721702) (xy 153.041419 -131.690723) (xy 153.093539 -131.666918) (xy 153.148517 -131.650773)
			(xy 153.205232 -131.642616) (xy 153.233882 -131.642104) (xy 153.261262 -131.642582) (xy 153.315512 -131.650047)
			(xy 153.368241 -131.664827) (xy 153.418467 -131.686648) (xy 153.465255 -131.715101) (xy 153.507734 -131.749659)
			(xy 153.545114 -131.789678) (xy 153.561288 -131.811776) (xy 153.56686 -131.819028) (xy 153.581962 -131.829317)
			(xy 153.590752 -131.831842) (xy 153.620724 -131.839208) (xy 153.629672 -131.840971) (xy 153.647764 -131.838746)
			(xy 153.65603 -131.83489) (xy 153.680625 -131.822491) (xy 153.732153 -131.803024) (xy 153.785644 -131.789878)
			(xy 153.840325 -131.783244) (xy 153.867866 -131.78282) (xy 153.895407 -131.783241) (xy 153.950087 -131.789879)
			(xy 154.003577 -131.803028) (xy 154.055103 -131.822498) (xy 154.079702 -131.83489) (xy 154.087961 -131.838768)
			(xy 154.106058 -131.840983) (xy 154.115008 -131.839208) (xy 154.14498 -131.831842) (xy 154.153759 -131.829291)
			(xy 154.168861 -131.819015) (xy 154.174444 -131.811776) (xy 154.190575 -131.789643) (xy 154.227955 -131.749614)
			(xy 154.270438 -131.715049) (xy 154.317233 -131.686591) (xy 154.367468 -131.664773) (xy 154.420207 -131.65)
			(xy 154.474466 -131.642547) (xy 154.50185 -131.642104) (xy 154.5305 -131.642647) (xy 154.587218 -131.650795)
			(xy 154.642199 -131.666933) (xy 154.694323 -131.690732) (xy 154.74253 -131.721707) (xy 154.785837 -131.759228)
			(xy 154.790874 -131.76504) (xy 160.769552 -131.76504) (xy 160.773623 -131.709418) (xy 160.785749 -131.654981)
			(xy 160.805672 -131.60289) (xy 160.832968 -131.554255) (xy 160.867054 -131.510112) (xy 160.907203 -131.471403)
			(xy 160.952561 -131.438952) (xy 161.002161 -131.413451) (xy 161.054945 -131.395444) (xy 161.109788 -131.385314)
			(xy 161.165522 -131.383277) (xy 161.220959 -131.389377) (xy 161.274916 -131.403483) (xy 161.326245 -131.425295)
			(xy 161.373851 -131.454349) (xy 161.416719 -131.490024) (xy 161.453936 -131.531561) (xy 161.484709 -131.578074)
			(xy 161.508381 -131.628571) (xy 161.524449 -131.681978) (xy 161.532569 -131.737154) (xy 161.533078 -131.76504)
			(xy 162.750752 -131.76504) (xy 162.754823 -131.709418) (xy 162.766949 -131.654981) (xy 162.786872 -131.60289)
			(xy 162.814168 -131.554255) (xy 162.848254 -131.510112) (xy 162.888403 -131.471403) (xy 162.933761 -131.438952)
			(xy 162.983361 -131.413451) (xy 163.036145 -131.395444) (xy 163.090988 -131.385314) (xy 163.146722 -131.383277)
			(xy 163.202159 -131.389377) (xy 163.256116 -131.403483) (xy 163.307445 -131.425295) (xy 163.355051 -131.454349)
			(xy 163.397919 -131.490024) (xy 163.435136 -131.531561) (xy 163.465909 -131.578074) (xy 163.489581 -131.628571)
			(xy 163.505649 -131.681978) (xy 163.513769 -131.737154) (xy 163.514278 -131.76504) (xy 163.513769 -131.792926)
			(xy 163.505649 -131.848102) (xy 163.489581 -131.901509) (xy 163.465909 -131.952006) (xy 163.435136 -131.998519)
			(xy 163.397919 -132.040056) (xy 163.355051 -132.075731) (xy 163.307445 -132.104785) (xy 163.256116 -132.126597)
			(xy 163.202159 -132.140703) (xy 163.146722 -132.146803) (xy 163.090988 -132.144766) (xy 163.036145 -132.134636)
			(xy 162.983361 -132.116629) (xy 162.933761 -132.091128) (xy 162.888403 -132.058677) (xy 162.848254 -132.019968)
			(xy 162.814168 -131.975825) (xy 162.786872 -131.92719) (xy 162.766949 -131.875099) (xy 162.754823 -131.820662)
			(xy 162.750752 -131.76504) (xy 161.533078 -131.76504) (xy 161.532569 -131.792926) (xy 161.524449 -131.848102)
			(xy 161.508381 -131.901509) (xy 161.484709 -131.952006) (xy 161.453936 -131.998519) (xy 161.416719 -132.040056)
			(xy 161.373851 -132.075731) (xy 161.326245 -132.104785) (xy 161.274916 -132.126597) (xy 161.220959 -132.140703)
			(xy 161.165522 -132.146803) (xy 161.109788 -132.144766) (xy 161.054945 -132.134636) (xy 161.002161 -132.116629)
			(xy 160.952561 -132.091128) (xy 160.907203 -132.058677) (xy 160.867054 -132.019968) (xy 160.832968 -131.975825)
			(xy 160.805672 -131.92719) (xy 160.785749 -131.875099) (xy 160.773623 -131.820662) (xy 160.769552 -131.76504)
			(xy 154.790874 -131.76504) (xy 154.823363 -131.80253) (xy 154.854344 -131.850733) (xy 154.878149 -131.902854)
			(xy 154.894294 -131.957833) (xy 154.902449 -132.01455) (xy 154.902449 -132.07185) (xy 154.894294 -132.128567)
			(xy 154.878149 -132.183546) (xy 154.854344 -132.235667) (xy 154.823363 -132.28387) (xy 154.785837 -132.327172)
			(xy 154.74253 -132.364693) (xy 154.694323 -132.395668) (xy 154.642199 -132.419467) (xy 154.587218 -132.435605)
			(xy 154.5305 -132.443753) (xy 154.50185 -132.444236) (xy 154.486932 -132.444067) (xy 154.457183 -132.441778)
			(xy 154.442414 -132.439664) (xy 154.431238 -132.437886) (xy 154.410156 -132.443982) (xy 154.343354 -132.50164)
			(xy 154.335407 -132.50925) (xy 154.326313 -132.529257) (xy 154.325828 -132.540248) (xy 154.325828 -132.804916)
			(xy 154.326316 -132.815907) (xy 154.335403 -132.83592) (xy 154.343354 -132.843524) (xy 154.410156 -132.901182)
			(xy 154.431238 -132.907278) (xy 154.442414 -132.9055) (xy 154.457183 -132.903388) (xy 154.486932 -132.901102)
			(xy 154.50185 -132.900928) (xy 154.530502 -132.901423) (xy 154.587223 -132.909572) (xy 154.642207 -132.925711)
			(xy 154.694335 -132.949511) (xy 154.742544 -132.980488) (xy 154.785854 -133.018011) (xy 154.823382 -133.061316)
			(xy 154.854365 -133.109521) (xy 154.878172 -133.161646) (xy 154.894317 -133.216628) (xy 154.902473 -133.273348)
			(xy 154.902473 -133.330652) (xy 154.894317 -133.387372) (xy 154.878172 -133.442354) (xy 154.854365 -133.494479)
			(xy 154.823382 -133.542684) (xy 154.803923 -133.565138) (xy 160.769552 -133.565138) (xy 160.773623 -133.509516)
			(xy 160.785749 -133.455079) (xy 160.805672 -133.402988) (xy 160.832968 -133.354353) (xy 160.867054 -133.31021)
			(xy 160.907203 -133.271501) (xy 160.952561 -133.23905) (xy 161.002161 -133.213549) (xy 161.054945 -133.195542)
			(xy 161.109788 -133.185412) (xy 161.165522 -133.183375) (xy 161.220959 -133.189475) (xy 161.274916 -133.203581)
			(xy 161.326245 -133.225393) (xy 161.373851 -133.254447) (xy 161.416719 -133.290122) (xy 161.453936 -133.331659)
			(xy 161.484709 -133.378172) (xy 161.508381 -133.428669) (xy 161.524449 -133.482076) (xy 161.532569 -133.537252)
			(xy 161.533078 -133.565138) (xy 162.750752 -133.565138) (xy 162.754823 -133.509516) (xy 162.766949 -133.455079)
			(xy 162.786872 -133.402988) (xy 162.814168 -133.354353) (xy 162.848254 -133.31021) (xy 162.888403 -133.271501)
			(xy 162.933761 -133.23905) (xy 162.983361 -133.213549) (xy 163.036145 -133.195542) (xy 163.090988 -133.185412)
			(xy 163.146722 -133.183375) (xy 163.202159 -133.189475) (xy 163.256116 -133.203581) (xy 163.307445 -133.225393)
			(xy 163.355051 -133.254447) (xy 163.397919 -133.290122) (xy 163.435136 -133.331659) (xy 163.465909 -133.378172)
			(xy 163.489581 -133.428669) (xy 163.505649 -133.482076) (xy 163.513769 -133.537252) (xy 163.514278 -133.565138)
			(xy 163.513769 -133.593024) (xy 163.505649 -133.6482) (xy 163.489581 -133.701607) (xy 163.465909 -133.752104)
			(xy 163.435136 -133.798617) (xy 163.397919 -133.840154) (xy 163.355051 -133.875829) (xy 163.307445 -133.904883)
			(xy 163.256116 -133.926695) (xy 163.202159 -133.940801) (xy 163.146722 -133.946901) (xy 163.090988 -133.944864)
			(xy 163.036145 -133.934734) (xy 162.983361 -133.916727) (xy 162.933761 -133.891226) (xy 162.888403 -133.858775)
			(xy 162.848254 -133.820066) (xy 162.814168 -133.775923) (xy 162.786872 -133.727288) (xy 162.766949 -133.675197)
			(xy 162.754823 -133.62076) (xy 162.750752 -133.565138) (xy 161.533078 -133.565138) (xy 161.532569 -133.593024)
			(xy 161.524449 -133.6482) (xy 161.508381 -133.701607) (xy 161.484709 -133.752104) (xy 161.453936 -133.798617)
			(xy 161.416719 -133.840154) (xy 161.373851 -133.875829) (xy 161.326245 -133.904883) (xy 161.274916 -133.926695)
			(xy 161.220959 -133.940801) (xy 161.165522 -133.946901) (xy 161.109788 -133.944864) (xy 161.054945 -133.934734)
			(xy 161.002161 -133.916727) (xy 160.952561 -133.891226) (xy 160.907203 -133.858775) (xy 160.867054 -133.820066)
			(xy 160.832968 -133.775923) (xy 160.805672 -133.727288) (xy 160.785749 -133.675197) (xy 160.773623 -133.62076)
			(xy 160.769552 -133.565138) (xy 154.803923 -133.565138) (xy 154.785854 -133.585989) (xy 154.742544 -133.623512)
			(xy 154.694335 -133.654489) (xy 154.642207 -133.678289) (xy 154.587223 -133.694428) (xy 154.530502 -133.702577)
			(xy 154.50185 -133.70306) (xy 154.474469 -133.702606) (xy 154.420219 -133.695133) (xy 154.367492 -133.680347)
			(xy 154.317266 -133.658522) (xy 154.270479 -133.630065) (xy 154.227999 -133.595505) (xy 154.190618 -133.555486)
			(xy 154.174444 -133.533388) (xy 154.168903 -133.526109) (xy 154.153778 -133.515835) (xy 154.14498 -133.513322)
			(xy 154.115008 -133.505956) (xy 154.106057 -133.504213) (xy 154.087969 -133.506426) (xy 154.079702 -133.510274)
			(xy 154.055103 -133.522666) (xy 154.003577 -133.542134) (xy 153.950087 -133.555281) (xy 153.895407 -133.561919)
			(xy 153.867866 -133.562344) (xy 153.840326 -133.561914) (xy 153.785645 -133.555279) (xy 153.732156 -133.542133)
			(xy 153.680629 -133.522665) (xy 153.65603 -133.510274) (xy 153.647765 -133.506411) (xy 153.629673 -133.504187)
			(xy 153.620724 -133.505956) (xy 153.590752 -133.513322) (xy 153.581968 -133.515857) (xy 153.566869 -133.526145)
			(xy 153.561288 -133.533388) (xy 153.545127 -133.555498) (xy 153.507753 -133.59553) (xy 153.465276 -133.630098)
			(xy 153.418486 -133.658558) (xy 153.368255 -133.68038) (xy 153.315521 -133.695158) (xy 153.261265 -133.702615)
			(xy 153.233882 -133.70306) (xy 153.205234 -133.70256) (xy 153.148522 -133.694403) (xy 153.093548 -133.678259)
			(xy 153.04143 -133.654456) (xy 152.993231 -133.623478) (xy 152.949931 -133.585956) (xy 152.912411 -133.542654)
			(xy 152.881435 -133.494454) (xy 152.857635 -133.442335) (xy 152.841493 -133.38736) (xy 152.833339 -133.330648)
			(xy 152.833339 -133.273352) (xy 152.841493 -133.21664) (xy 152.857635 -133.161665) (xy 152.881435 -133.109546)
			(xy 152.912411 -133.061346) (xy 152.949931 -133.018044) (xy 152.993231 -132.980522) (xy 153.04143 -132.949544)
			(xy 153.093548 -132.925741) (xy 153.148522 -132.909597) (xy 153.205234 -132.90144) (xy 153.233882 -132.900928)
			(xy 153.2488 -132.901094) (xy 153.278549 -132.903385) (xy 153.293318 -132.9055) (xy 153.304494 -132.907278)
			(xy 153.325576 -132.901182) (xy 153.392378 -132.843524) (xy 153.400346 -132.835933) (xy 153.409427 -132.815911)
			(xy 153.409904 -132.804916) (xy 153.409904 -132.540248) (xy 153.409426 -132.529256) (xy 153.400332 -132.509244)
			(xy 153.392378 -132.50164) (xy 153.325576 -132.443982) (xy 153.304494 -132.437886) (xy 153.293318 -132.439664)
			(xy 153.278549 -132.441773) (xy 153.2488 -132.444061) (xy 153.233882 -132.444236) (xy 153.205232 -132.443784)
			(xy 153.148517 -132.435627) (xy 153.093539 -132.419482) (xy 153.041419 -132.395677) (xy 152.993216 -132.364698)
			(xy 152.949914 -132.327174) (xy 152.912391 -132.283869) (xy 152.881414 -132.235665) (xy 152.857612 -132.183544)
			(xy 152.841469 -132.128566) (xy 152.833315 -132.07185) (xy 140.456412 -132.07185) (xy 140.456412 -133.028436)
			(xy 140.457428 -133.037834) (xy 140.457428 -133.038342) (xy 140.45914 -133.045497) (xy 140.465987 -133.05851)
			(xy 140.47089 -133.063996) (xy 141.272226 -133.865332) (xy 150.191463 -133.865332) (xy 150.191463 -133.808068)
			(xy 150.199612 -133.751388) (xy 150.215744 -133.696445) (xy 150.239531 -133.644356) (xy 150.270488 -133.596182)
			(xy 150.307986 -133.552905) (xy 150.351262 -133.515404) (xy 150.399433 -133.484443) (xy 150.45152 -133.460653)
			(xy 150.506463 -133.444517) (xy 150.563143 -133.436364) (xy 150.591774 -133.435852) (xy 150.619144 -133.436327)
			(xy 150.673376 -133.44377) (xy 150.726091 -133.458519) (xy 150.776311 -133.480302) (xy 150.8231 -133.508714)
			(xy 150.865591 -133.543225) (xy 150.902992 -133.583196) (xy 150.91918 -133.60527) (xy 150.924756 -133.612518)
			(xy 150.939855 -133.62281) (xy 150.948644 -133.625336) (xy 150.978616 -133.632702) (xy 150.987566 -133.634451)
			(xy 151.005655 -133.632233) (xy 151.013922 -133.628384) (xy 151.038522 -133.616012) (xy 151.090059 -133.596613)
			(xy 151.143551 -133.583533) (xy 151.198224 -133.576962) (xy 151.225758 -133.576568) (xy 151.253293 -133.576936)
			(xy 151.307968 -133.583508) (xy 151.361459 -133.596597) (xy 151.41299 -133.616016) (xy 151.437594 -133.628384)
			(xy 151.445855 -133.632258) (xy 151.46395 -133.634475) (xy 151.4729 -133.632702) (xy 151.502872 -133.625336)
			(xy 151.511651 -133.622784) (xy 151.526753 -133.612509) (xy 151.532336 -133.60527) (xy 151.548505 -133.583181)
			(xy 151.585909 -133.543209) (xy 151.628402 -133.508697) (xy 151.675195 -133.480286) (xy 151.725418 -133.458504)
			(xy 151.778136 -133.443755) (xy 151.832371 -133.436315) (xy 151.859742 -133.435852) (xy 151.888368 -133.436437)
			(xy 151.945035 -133.44459) (xy 151.999966 -133.460725) (xy 152.052042 -133.484512) (xy 152.100203 -133.515467)
			(xy 152.143468 -133.552961) (xy 152.180958 -133.596231) (xy 152.211908 -133.644395) (xy 152.23569 -133.696473)
			(xy 152.251819 -133.751406) (xy 152.259966 -133.808074) (xy 152.259966 -133.865326) (xy 152.251819 -133.921994)
			(xy 152.23569 -133.976927) (xy 152.211908 -134.029005) (xy 152.180958 -134.077169) (xy 152.143468 -134.120439)
			(xy 152.100203 -134.157933) (xy 152.052042 -134.188888) (xy 151.999966 -134.212675) (xy 151.945035 -134.22881)
			(xy 151.888368 -134.236963) (xy 151.859742 -134.237476) (xy 151.844828 -134.237368) (xy 151.815079 -134.235206)
			(xy 151.800306 -134.233158) (xy 151.78913 -134.23138) (xy 151.768048 -134.237476) (xy 151.701246 -134.295134)
			(xy 151.693301 -134.302745) (xy 151.684206 -134.322751) (xy 151.68372 -134.333742) (xy 151.68372 -134.59841)
			(xy 151.684214 -134.6094) (xy 151.693297 -134.629413) (xy 151.701246 -134.637018) (xy 151.768048 -134.694676)
			(xy 151.78913 -134.700772) (xy 151.800306 -134.698994) (xy 151.81508 -134.69695) (xy 151.844828 -134.694786)
			(xy 151.859742 -134.694676) (xy 151.888369 -134.695213) (xy 151.94504 -134.703367) (xy 151.999975 -134.719502)
			(xy 152.052054 -134.743291) (xy 152.100217 -134.774248) (xy 152.143485 -134.811744) (xy 152.180977 -134.855016)
			(xy 152.21193 -134.903183) (xy 152.235713 -134.955265) (xy 152.251842 -135.010201) (xy 152.25999 -135.066873)
			(xy 152.25999 -135.124127) (xy 152.251842 -135.180799) (xy 152.235713 -135.235735) (xy 152.21193 -135.287817)
			(xy 152.180977 -135.335984) (xy 152.143485 -135.379256) (xy 152.100217 -135.416752) (xy 152.052054 -135.447709)
			(xy 151.999975 -135.471498) (xy 151.94504 -135.487633) (xy 151.888369 -135.495787) (xy 151.859742 -135.4963)
			(xy 151.832373 -135.495791) (xy 151.778144 -135.488352) (xy 151.72543 -135.473606) (xy 151.675212 -135.451828)
			(xy 151.628422 -135.423423) (xy 151.58593 -135.388917) (xy 151.548526 -135.348953) (xy 151.532336 -135.326882)
			(xy 151.526764 -135.31963) (xy 151.511661 -135.309342) (xy 151.502872 -135.306816) (xy 151.4729 -135.29945)
			(xy 151.46395 -135.297704) (xy 151.445861 -135.299919) (xy 151.437594 -135.303768) (xy 151.412993 -135.316139)
			(xy 151.361456 -135.335537) (xy 151.307965 -135.348617) (xy 151.253292 -135.35519) (xy 151.225758 -135.355584)
			(xy 151.198224 -135.355204) (xy 151.143549 -135.348635) (xy 151.090058 -135.335548) (xy 151.038526 -135.316134)
			(xy 151.013922 -135.303768) (xy 151.005659 -135.2999) (xy 150.987565 -135.29768) (xy 150.978616 -135.29945)
			(xy 150.948644 -135.306816) (xy 150.939859 -135.30935) (xy 150.924761 -135.319639) (xy 150.91918 -135.326882)
			(xy 150.903016 -135.348975) (xy 150.86561 -135.388944) (xy 150.823115 -135.423454) (xy 150.776321 -135.451864)
			(xy 150.726098 -135.473646) (xy 150.67338 -135.488395) (xy 150.619145 -135.495836) (xy 150.591774 -135.4963)
			(xy 150.563144 -135.495812) (xy 150.506468 -135.487659) (xy 150.451529 -135.471525) (xy 150.399445 -135.447736)
			(xy 150.351276 -135.416777) (xy 150.308003 -135.379278) (xy 150.270508 -135.336003) (xy 150.239552 -135.287833)
			(xy 150.215766 -135.235747) (xy 150.199635 -135.180807) (xy 150.191486 -135.12413) (xy 150.191486 -135.06687)
			(xy 150.199635 -135.010193) (xy 150.215766 -134.955253) (xy 150.239552 -134.903167) (xy 150.270508 -134.854997)
			(xy 150.308003 -134.811722) (xy 150.351276 -134.774223) (xy 150.399445 -134.743264) (xy 150.451529 -134.719475)
			(xy 150.506468 -134.703341) (xy 150.563144 -134.695188) (xy 150.591774 -134.694676) (xy 150.606688 -134.694782)
			(xy 150.636437 -134.696946) (xy 150.65121 -134.698994) (xy 150.662386 -134.700772) (xy 150.683468 -134.694676)
			(xy 150.75027 -134.637018) (xy 150.75824 -134.629428) (xy 150.76732 -134.609406) (xy 150.767796 -134.59841)
			(xy 150.767796 -134.333742) (xy 150.767324 -134.322749) (xy 150.758226 -134.302737) (xy 150.75027 -134.295134)
			(xy 150.683468 -134.237476) (xy 150.662386 -134.23138) (xy 150.65121 -134.233158) (xy 150.636438 -134.235211)
			(xy 150.606688 -134.237369) (xy 150.591774 -134.237476) (xy 150.563143 -134.237036) (xy 150.506463 -134.228883)
			(xy 150.45152 -134.212747) (xy 150.399433 -134.188957) (xy 150.351262 -134.157996) (xy 150.307986 -134.120495)
			(xy 150.270488 -134.077218) (xy 150.239531 -134.029044) (xy 150.215744 -133.976955) (xy 150.199612 -133.922012)
			(xy 150.191463 -133.865332) (xy 141.272226 -133.865332) (xy 143.078622 -135.671728) (xy 152.83361 -135.671728)
			(xy 152.83361 -135.614472) (xy 152.841759 -135.557797) (xy 152.857889 -135.50286) (xy 152.881674 -135.450777)
			(xy 152.912629 -135.402609) (xy 152.950123 -135.359336) (xy 152.993394 -135.32184) (xy 153.041561 -135.290883)
			(xy 153.093643 -135.267096) (xy 153.14858 -135.250963) (xy 153.205254 -135.242812) (xy 153.233882 -135.2423)
			(xy 153.261251 -135.242791) (xy 153.315482 -135.250233) (xy 153.368196 -135.264982) (xy 153.418414 -135.286763)
			(xy 153.465204 -135.315171) (xy 153.507695 -135.349679) (xy 153.545098 -135.389646) (xy 153.561288 -135.411718)
			(xy 153.566852 -135.418977) (xy 153.58196 -135.429262) (xy 153.590752 -135.431784) (xy 153.620724 -135.43915)
			(xy 153.629673 -135.440909) (xy 153.647763 -135.438685) (xy 153.65603 -135.434832) (xy 153.680645 -135.422489)
			(xy 153.732177 -135.403084) (xy 153.785663 -135.389996) (xy 153.840333 -135.383415) (xy 153.867866 -135.383016)
			(xy 153.895401 -135.383387) (xy 153.950076 -135.389959) (xy 154.003566 -135.403048) (xy 154.055098 -135.422464)
			(xy 154.079702 -135.434832) (xy 154.08796 -135.438711) (xy 154.106058 -135.440924) (xy 154.115008 -135.43915)
			(xy 154.14498 -135.431784) (xy 154.153754 -135.42922) (xy 154.168859 -135.418952) (xy 154.174444 -135.411718)
			(xy 154.190655 -135.389661) (xy 154.228053 -135.349691) (xy 154.27054 -135.315178) (xy 154.317326 -135.286764)
			(xy 154.367541 -135.264976) (xy 154.420252 -135.250219) (xy 154.474481 -135.242769) (xy 154.50185 -135.2423)
			(xy 154.530485 -135.242759) (xy 154.587173 -135.250903) (xy 154.642125 -135.267032) (xy 154.694221 -135.290818)
			(xy 154.742402 -135.321777) (xy 154.785687 -135.359278) (xy 154.79063 -135.364982) (xy 160.769552 -135.364982)
			(xy 160.773623 -135.30936) (xy 160.785749 -135.254923) (xy 160.805672 -135.202832) (xy 160.832968 -135.154197)
			(xy 160.867054 -135.110054) (xy 160.907203 -135.071345) (xy 160.952561 -135.038894) (xy 161.002161 -135.013393)
			(xy 161.054945 -134.995386) (xy 161.109788 -134.985256) (xy 161.165522 -134.983219) (xy 161.220959 -134.989319)
			(xy 161.274916 -135.003425) (xy 161.326245 -135.025237) (xy 161.373851 -135.054291) (xy 161.416719 -135.089966)
			(xy 161.453936 -135.131503) (xy 161.484709 -135.178016) (xy 161.508381 -135.228513) (xy 161.524449 -135.28192)
			(xy 161.532569 -135.337096) (xy 161.533078 -135.364982) (xy 161.532569 -135.392868) (xy 161.524449 -135.448044)
			(xy 161.508381 -135.501451) (xy 161.484709 -135.551948) (xy 161.453936 -135.598461) (xy 161.416719 -135.639998)
			(xy 161.373851 -135.675673) (xy 161.326245 -135.704727) (xy 161.274916 -135.726539) (xy 161.220959 -135.740645)
			(xy 161.165522 -135.746745) (xy 161.109788 -135.744708) (xy 161.054945 -135.734578) (xy 161.002161 -135.716571)
			(xy 160.952561 -135.69107) (xy 160.907203 -135.658619) (xy 160.867054 -135.61991) (xy 160.832968 -135.575767)
			(xy 160.805672 -135.527132) (xy 160.785749 -135.475041) (xy 160.773623 -135.420604) (xy 160.769552 -135.364982)
			(xy 154.79063 -135.364982) (xy 154.823193 -135.402558) (xy 154.854158 -135.450735) (xy 154.87795 -135.502828)
			(xy 154.894086 -135.557778) (xy 154.902237 -135.614465) (xy 154.902237 -135.671735) (xy 154.894086 -135.728422)
			(xy 154.87795 -135.783372) (xy 154.854158 -135.835465) (xy 154.823193 -135.883642) (xy 154.785687 -135.926922)
			(xy 154.742402 -135.964423) (xy 154.694221 -135.995382) (xy 154.642125 -136.019168) (xy 154.587173 -136.035297)
			(xy 154.530485 -136.043441) (xy 154.50185 -136.043924) (xy 154.486936 -136.043815) (xy 154.457187 -136.041654)
			(xy 154.442414 -136.039606) (xy 154.431238 -136.037828) (xy 154.410156 -136.043924) (xy 154.343354 -136.101582)
			(xy 154.335388 -136.109175) (xy 154.326304 -136.129195) (xy 154.325828 -136.14019) (xy 154.325828 -136.404858)
			(xy 154.326293 -136.415852) (xy 154.335396 -136.435864) (xy 154.343354 -136.443466) (xy 154.410156 -136.501124)
			(xy 154.431238 -136.50722) (xy 154.442414 -136.505442) (xy 154.457187 -136.503397) (xy 154.486936 -136.501234)
			(xy 154.50185 -136.501124) (xy 154.530487 -136.501535) (xy 154.587178 -136.50968) (xy 154.642133 -136.52581)
			(xy 154.694233 -136.549597) (xy 154.742417 -136.580558) (xy 154.785704 -136.618061) (xy 154.823212 -136.661343)
			(xy 154.854179 -136.709523) (xy 154.877973 -136.76162) (xy 154.89411 -136.816573) (xy 154.902261 -136.873263)
			(xy 154.902261 -136.930537) (xy 154.89411 -136.987227) (xy 154.877973 -137.04218) (xy 154.854179 -137.094277)
			(xy 154.823212 -137.142457) (xy 154.785704 -137.185739) (xy 154.742417 -137.223242) (xy 154.694233 -137.254203)
			(xy 154.642133 -137.27799) (xy 154.587178 -137.29412) (xy 154.530487 -137.302265) (xy 154.50185 -137.302748)
			(xy 154.474481 -137.302255) (xy 154.420249 -137.294816) (xy 154.367534 -137.280069) (xy 154.317315 -137.258289)
			(xy 154.270525 -137.22988) (xy 154.228035 -137.195371) (xy 154.190633 -137.155403) (xy 154.174444 -137.13333)
			(xy 154.168894 -137.126058) (xy 154.153776 -137.115779) (xy 154.14498 -137.113264) (xy 154.115008 -137.105898)
			(xy 154.106057 -137.104161) (xy 154.08797 -137.106371) (xy 154.079702 -137.110216) (xy 154.055097 -137.12258)
			(xy 154.003562 -137.141981) (xy 153.950072 -137.155063) (xy 153.895399 -137.161637) (xy 153.867866 -137.162032)
			(xy 153.840332 -137.161654) (xy 153.785657 -137.155085) (xy 153.732166 -137.141999) (xy 153.680634 -137.122583)
			(xy 153.65603 -137.110216) (xy 153.647765 -137.106354) (xy 153.629673 -137.104129) (xy 153.620724 -137.105898)
			(xy 153.590752 -137.113264) (xy 153.581963 -137.115786) (xy 153.566866 -137.126083) (xy 153.561288 -137.13333)
			(xy 153.545104 -137.155408) (xy 153.507702 -137.19538) (xy 153.465212 -137.229893) (xy 153.418422 -137.258305)
			(xy 153.368202 -137.280089) (xy 153.315485 -137.29484) (xy 153.261253 -137.302284) (xy 153.233882 -137.302748)
			(xy 153.205255 -137.302164) (xy 153.148585 -137.294014) (xy 153.093651 -137.277882) (xy 153.041572 -137.254096)
			(xy 152.993409 -137.223141) (xy 152.95014 -137.185647) (xy 152.912648 -137.142377) (xy 152.881695 -137.094212)
			(xy 152.857912 -137.042132) (xy 152.841782 -136.987198) (xy 152.833634 -136.930527) (xy 152.833634 -136.873273)
			(xy 152.841782 -136.816603) (xy 152.857912 -136.761668) (xy 152.881695 -136.709588) (xy 152.912648 -136.661423)
			(xy 152.95014 -136.618153) (xy 152.993409 -136.580659) (xy 153.041572 -136.549704) (xy 153.093651 -136.525918)
			(xy 153.148585 -136.509786) (xy 153.205255 -136.501636) (xy 153.233882 -136.501124) (xy 153.248796 -136.501229)
			(xy 153.278545 -136.503393) (xy 153.293318 -136.505442) (xy 153.304494 -136.50722) (xy 153.325576 -136.501124)
			(xy 153.392378 -136.443466) (xy 153.400327 -136.435858) (xy 153.409419 -136.415849) (xy 153.409904 -136.404858)
			(xy 153.409904 -136.14019) (xy 153.409403 -136.129201) (xy 153.400325 -136.109188) (xy 153.392378 -136.101582)
			(xy 153.325576 -136.043924) (xy 153.304494 -136.037828) (xy 153.293318 -136.039606) (xy 153.278546 -136.041659)
			(xy 153.248796 -136.043817) (xy 153.233882 -136.043924) (xy 153.205254 -136.043388) (xy 153.14858 -136.035237)
			(xy 153.093643 -136.019104) (xy 153.041561 -135.995317) (xy 152.993394 -135.96436) (xy 152.950123 -135.926864)
			(xy 152.912629 -135.883591) (xy 152.881674 -135.835423) (xy 152.857889 -135.78334) (xy 152.841759 -135.728403)
			(xy 152.83361 -135.671728) (xy 143.078622 -135.671728) (xy 143.647922 -136.241028) (xy 151.456388 -136.241028)
			(xy 151.460459 -136.185406) (xy 151.472585 -136.130969) (xy 151.492508 -136.078878) (xy 151.519804 -136.030243)
			(xy 151.55389 -135.9861) (xy 151.594039 -135.947391) (xy 151.639397 -135.91494) (xy 151.688997 -135.889439)
			(xy 151.741781 -135.871432) (xy 151.796624 -135.861302) (xy 151.852358 -135.859265) (xy 151.907795 -135.865365)
			(xy 151.961752 -135.879471) (xy 152.013081 -135.901283) (xy 152.060687 -135.930337) (xy 152.103555 -135.966012)
			(xy 152.140772 -136.007549) (xy 152.171545 -136.054062) (xy 152.195217 -136.104559) (xy 152.211285 -136.157966)
			(xy 152.219405 -136.213142) (xy 152.219914 -136.241028) (xy 152.219405 -136.268914) (xy 152.211285 -136.32409)
			(xy 152.195217 -136.377497) (xy 152.171545 -136.427994) (xy 152.140772 -136.474507) (xy 152.103555 -136.516044)
			(xy 152.060687 -136.551719) (xy 152.013081 -136.580773) (xy 151.961752 -136.602585) (xy 151.907795 -136.616691)
			(xy 151.852358 -136.622791) (xy 151.796624 -136.620754) (xy 151.741781 -136.610624) (xy 151.688997 -136.592617)
			(xy 151.639397 -136.567116) (xy 151.594039 -136.534665) (xy 151.55389 -136.495956) (xy 151.519804 -136.451813)
			(xy 151.492508 -136.403178) (xy 151.472585 -136.351087) (xy 151.460459 -136.29665) (xy 151.456388 -136.241028)
			(xy 143.647922 -136.241028) (xy 145.058892 -137.651998) (xy 145.064324 -137.656974) (xy 145.077366 -137.663809)
			(xy 145.084546 -137.66546) (xy 145.085054 -137.66546) (xy 145.094452 -137.666476) (xy 160.022032 -137.666476)
			(xy 160.031683 -137.666062) (xy 160.04961 -137.658909) (xy 160.063592 -137.645605) (xy 160.068006 -137.637012)
			(xy 160.072578 -137.617962) (xy 160.072832 -137.613136) (xy 160.074552 -137.58403) (xy 160.084454 -137.526569)
			(xy 160.101569 -137.47083) (xy 160.125619 -137.417715) (xy 160.156217 -137.368081) (xy 160.192867 -137.322732)
			(xy 160.234976 -137.282401) (xy 160.281863 -137.247741) (xy 160.33277 -137.219312) (xy 160.386874 -137.197575)
			(xy 160.443299 -137.182879) (xy 160.501133 -137.175465) (xy 160.530286 -137.174986) (xy 160.53054 -137.174986)
			(xy 160.53435 -137.17524) (xy 160.563071 -137.175892) (xy 160.620011 -137.183535) (xy 160.647888 -137.19048)
			(xy 160.658556 -137.193274) (xy 160.668716 -137.19175) (xy 160.673471 -137.19087) (xy 160.682546 -137.187535)
			(xy 160.68675 -137.185146) (xy 160.701228 -137.175748) (xy 160.753298 -137.141712) (xy 160.757159 -137.138867)
			(xy 160.763817 -137.131966) (xy 160.766506 -137.127996) (xy 160.767014 -137.127234) (xy 160.772602 -137.118344)
			(xy 160.77438 -137.107676) (xy 160.77438 -137.107422) (xy 160.778938 -137.080719) (xy 160.794611 -137.028867)
			(xy 160.817462 -136.979753) (xy 160.847033 -136.934367) (xy 160.882728 -136.893621) (xy 160.923829 -136.858336)
			(xy 160.96951 -136.829222) (xy 161.01885 -136.806864) (xy 161.070857 -136.791712) (xy 161.124485 -136.784071)
			(xy 161.15157 -136.783572) (xy 161.178825 -136.784033) (xy 161.23278 -136.791786) (xy 161.285083 -136.807139)
			(xy 161.334668 -136.82978) (xy 161.380526 -136.859247) (xy 161.421724 -136.89494) (xy 161.457423 -136.936134)
			(xy 161.486896 -136.981988) (xy 161.509543 -137.03157) (xy 161.524903 -137.083871) (xy 161.532664 -137.137825)
			(xy 161.533078 -137.16508) (xy 161.532595 -137.192308) (xy 161.524853 -137.246212) (xy 161.509525 -137.298467)
			(xy 161.486922 -137.348011) (xy 161.457503 -137.393837) (xy 161.421866 -137.435014) (xy 161.380736 -137.470704)
			(xy 161.334948 -137.500183) (xy 161.285434 -137.522851) (xy 161.233199 -137.538247) (xy 161.179306 -137.546059)
			(xy 161.152078 -137.546588) (xy 161.15157 -137.546588) (xy 161.151062 -137.546588) (xy 161.130385 -137.546334)
			(xy 161.089271 -137.54188) (xy 161.06902 -137.537698) (xy 161.058707 -137.536994) (xy 161.038921 -137.542905)
			(xy 161.030666 -137.549128) (xy 161.030412 -137.549382) (xy 161.00298 -137.571988) (xy 160.995711 -137.579759)
			(xy 160.987708 -137.599449) (xy 160.987486 -137.610088) (xy 160.987486 -137.611358) (xy 160.98774 -137.612882)
			(xy 160.987994 -137.617708) (xy 160.992566 -137.637266) (xy 160.997022 -137.645806) (xy 161.011032 -137.659002)
			(xy 161.028917 -137.666112) (xy 161.03854 -137.666476) (xy 168.64838 -137.666476) (xy 168.658839 -137.665915)
			(xy 168.677992 -137.657494) (xy 168.69222 -137.642154) (xy 168.696132 -137.63244) (xy 168.710102 -137.591038)
			(xy 168.727882 -137.53846) (xy 168.729671 -137.531321) (xy 168.729546 -137.516609) (xy 168.727628 -137.509504)
			(xy 168.72534 -137.502743) (xy 168.717607 -137.490751) (xy 168.712388 -137.485882) (xy 168.71061 -137.484612)
			(xy 168.709086 -137.483596) (xy 168.685201 -137.464644) (xy 168.6429 -137.420735) (xy 168.607732 -137.370931)
			(xy 168.580506 -137.316377) (xy 168.561851 -137.258331) (xy 168.556432 -137.228326) (xy 168.55567 -137.224008)
			(xy 168.554654 -137.217658) (xy 168.54932 -137.209022) (xy 168.546912 -137.205355) (xy 168.541038 -137.198839)
			(xy 168.537636 -137.196068) (xy 168.505378 -137.173716) (xy 168.50487 -137.173716) (xy 168.472612 -137.15111)
			(xy 168.464763 -137.146807) (xy 168.447223 -137.143305) (xy 168.438322 -137.144252) (xy 168.42867 -137.146284)
			(xy 168.396414 -137.151944) (xy 168.331002 -137.155078) (xy 168.265809 -137.14887) (xy 168.233852 -137.141712)
			(xy 168.222422 -137.138918) (xy 168.21404 -137.140442) (xy 168.20882 -137.141466) (xy 168.19895 -137.14543)
			(xy 168.194482 -137.148316) (xy 168.16324 -137.169144) (xy 168.13149 -137.190226) (xy 168.127325 -137.193193)
			(xy 168.120166 -137.200492) (xy 168.117266 -137.204704) (xy 168.111678 -137.213086) (xy 168.1099 -137.224262)
			(xy 168.105248 -137.250867) (xy 168.089427 -137.302508) (xy 168.06648 -137.351401) (xy 168.036865 -137.396567)
			(xy 168.001174 -137.437105) (xy 167.960122 -137.472201) (xy 167.914529 -137.501156) (xy 167.865307 -137.523389)
			(xy 167.813442 -137.538457) (xy 167.759969 -137.546057) (xy 167.732964 -137.546588) (xy 167.705716 -137.546099)
			(xy 167.651775 -137.538339) (xy 167.599487 -137.522982) (xy 167.549917 -137.50034) (xy 167.504074 -137.470874)
			(xy 167.46289 -137.435184) (xy 167.427204 -137.393997) (xy 167.397743 -137.348151) (xy 167.375106 -137.298579)
			(xy 167.359753 -137.24629) (xy 167.351998 -137.192348) (xy 167.351998 -137.137852) (xy 167.359753 -137.08391)
			(xy 167.375106 -137.031621) (xy 167.397743 -136.982049) (xy 167.427204 -136.936203) (xy 167.46289 -136.895016)
			(xy 167.504074 -136.859326) (xy 167.549917 -136.82986) (xy 167.599487 -136.807218) (xy 167.651775 -136.791861)
			(xy 167.705716 -136.784101) (xy 167.732964 -136.783572) (xy 167.74943 -136.783723) (xy 167.782242 -136.786522)
			(xy 167.798496 -136.78916) (xy 167.799004 -136.789414) (xy 167.799512 -136.789414) (xy 167.801544 -136.789668)
			(xy 167.81018 -136.79043) (xy 167.818437 -136.790147) (xy 167.834111 -136.784958) (xy 167.840914 -136.78027)
			(xy 167.86606 -136.75868) (xy 167.869108 -136.755886) (xy 167.876442 -136.748414) (xy 167.884834 -136.729259)
			(xy 167.885364 -136.718802) (xy 167.885364 -136.71677) (xy 167.884856 -136.69645) (xy 167.884856 -135.83285)
			(xy 167.885364 -135.813546) (xy 167.885366 -135.803008) (xy 167.877875 -135.783335) (xy 167.870886 -135.775446)
			(xy 167.867838 -135.772652) (xy 167.858948 -135.765032) (xy 167.85844 -135.764524) (xy 167.841168 -135.750046)
			(xy 167.834594 -135.745442) (xy 167.81946 -135.740129) (xy 167.81145 -135.739632) (xy 167.802306 -135.740394)
			(xy 167.800274 -135.740648) (xy 167.799004 -135.740902) (xy 167.782812 -135.743523) (xy 167.750128 -135.746319)
			(xy 167.733726 -135.74649) (xy 167.732964 -135.74649) (xy 167.705716 -135.746001) (xy 167.651775 -135.738241)
			(xy 167.599487 -135.722884) (xy 167.549916 -135.700241) (xy 167.504073 -135.670776) (xy 167.462889 -135.635086)
			(xy 167.427203 -135.593898) (xy 167.397741 -135.548052) (xy 167.375104 -135.49848) (xy 167.359751 -135.44619)
			(xy 167.351996 -135.392248) (xy 167.351996 -135.337752) (xy 167.359751 -135.28381) (xy 167.375104 -135.23152)
			(xy 167.397741 -135.181948) (xy 167.427203 -135.136102) (xy 167.462889 -135.094914) (xy 167.504073 -135.059224)
			(xy 167.549916 -135.029759) (xy 167.599487 -135.007116) (xy 167.651775 -134.991759) (xy 167.705716 -134.983999)
			(xy 167.732964 -134.983474) (xy 167.759948 -134.983938) (xy 167.813378 -134.991536) (xy 167.865204 -135.006585)
			(xy 167.914394 -135.028786) (xy 167.959965 -135.057696) (xy 168.001009 -135.092737) (xy 168.036707 -135.133211)
			(xy 168.066347 -135.17831) (xy 168.089338 -135.227136) (xy 168.10522 -135.278713) (xy 168.1099 -135.305292)
			(xy 168.110662 -135.31088) (xy 168.113266 -135.319014) (xy 168.122993 -135.333041) (xy 168.129712 -135.338312)
			(xy 168.15816 -135.357108) (xy 168.194228 -135.381238) (xy 168.198715 -135.384051) (xy 168.208577 -135.387903)
			(xy 168.213786 -135.388858) (xy 168.21531 -135.389112) (xy 168.223946 -135.390636) (xy 168.234106 -135.388096)
			(xy 168.260862 -135.381939) (xy 168.315366 -135.375312) (xy 168.342818 -135.374888) (xy 168.356314 -135.375017)
			(xy 168.383255 -135.376672) (xy 168.396666 -135.37819) (xy 168.397174 -135.37819) (xy 168.40073 -135.378698)
			(xy 168.401492 -135.378698) (xy 168.437306 -135.38327) (xy 168.437814 -135.38327) (xy 168.453054 -135.385048)
			(xy 168.458372 -135.38416) (xy 168.468492 -135.380448) (xy 168.47312 -135.377682) (xy 168.520872 -135.344916)
			(xy 168.528238 -135.339836) (xy 168.534588 -135.334756) (xy 168.537636 -135.331454) (xy 168.53916 -135.329676)
			(xy 168.549066 -135.31596) (xy 168.552029 -135.311372) (xy 168.556118 -135.301249) (xy 168.557194 -135.295894)
			(xy 168.562491 -135.268341) (xy 168.579766 -135.21496) (xy 168.604306 -135.164505) (xy 168.635633 -135.117958)
			(xy 168.673137 -135.076227) (xy 168.716086 -135.040126) (xy 168.763644 -135.010357) (xy 168.814884 -134.9875)
			(xy 168.868808 -134.972002) (xy 168.924365 -134.964164) (xy 168.952418 -134.963662) (xy 168.986708 -134.965186)
			(xy 168.994074 -134.965694) (xy 169.006774 -134.967472) (xy 169.035272 -134.971871) (xy 169.090695 -134.987787)
			(xy 169.143262 -135.011489) (xy 169.191884 -135.042486) (xy 169.214038 -135.060944) (xy 169.220642 -135.066532)
			(xy 169.247058 -135.076946) (xy 169.250884 -135.078146) (xy 169.258797 -135.079429) (xy 169.262806 -135.079486)
			(xy 169.27703 -135.079486) (xy 169.281034 -135.079378) (xy 169.288942 -135.078099) (xy 169.292778 -135.076946)
			(xy 169.319194 -135.066532) (xy 169.325798 -135.060944) (xy 169.347722 -135.042751) (xy 169.395738 -135.012093)
			(xy 169.447608 -134.988534) (xy 169.502288 -134.972549) (xy 169.55868 -134.964458) (xy 169.587164 -134.963916)
			(xy 169.587418 -134.963916) (xy 169.60439 -134.964063) (xy 169.638217 -134.96686) (xy 169.654982 -134.969504)
			(xy 169.65549 -134.969504) (xy 169.665891 -134.970775) (xy 169.68622 -134.965783) (xy 169.69486 -134.959852)
			(xy 169.723308 -134.935468) (xy 169.730431 -134.928045) (xy 169.73856 -134.909168) (xy 169.739056 -134.898892)
			(xy 169.739056 -134.030466) (xy 169.738528 -134.020199) (xy 169.730396 -134.001338) (xy 169.723308 -133.99389)
			(xy 169.695114 -133.96976) (xy 169.686441 -133.963733) (xy 169.665976 -133.958606) (xy 169.65549 -133.959854)
			(xy 169.655236 -133.959854) (xy 169.651426 -133.960616) (xy 169.635785 -133.962981) (xy 169.604252 -133.965527)
			(xy 169.588434 -133.965696) (xy 169.585132 -133.965696) (xy 169.556817 -133.965049) (xy 169.500788 -133.956764)
			(xy 169.446483 -133.940681) (xy 169.39498 -133.917118) (xy 169.347303 -133.886544) (xy 169.325544 -133.868414)
			(xy 169.324528 -133.867398) (xy 169.318686 -133.862572) (xy 169.293286 -133.852666) (xy 169.289156 -133.851352)
			(xy 169.280602 -133.849956) (xy 169.276268 -133.849872) (xy 169.262806 -133.849872) (xy 169.258801 -133.849977)
			(xy 169.250893 -133.851253) (xy 169.247058 -133.852412) (xy 169.220642 -133.862826) (xy 169.214038 -133.868414)
			(xy 169.187114 -133.88975) (xy 169.176954 -133.896862) (xy 169.151952 -133.913099) (xy 169.098167 -133.938808)
			(xy 169.041174 -133.956289) (xy 168.982224 -133.965158) (xy 168.952418 -133.965696) (xy 168.924358 -133.965235)
			(xy 168.868783 -133.957429) (xy 168.814839 -133.941951) (xy 168.763579 -133.919105) (xy 168.716004 -133.889337)
			(xy 168.673044 -133.853227) (xy 168.635537 -133.811481) (xy 168.604215 -133.764915) (xy 168.57969 -133.714437)
			(xy 168.562441 -133.661033) (xy 168.557194 -133.633464) (xy 168.556123 -133.628109) (xy 168.552024 -133.617989)
			(xy 168.549066 -133.613398) (xy 168.53916 -133.599682) (xy 168.537636 -133.597904) (xy 168.534588 -133.594602)
			(xy 168.528238 -133.589522) (xy 168.520872 -133.584442) (xy 168.472358 -133.551168) (xy 168.464348 -133.54674)
			(xy 168.446378 -133.543354) (xy 168.437306 -133.544564) (xy 168.43121 -133.545834) (xy 168.430448 -133.546088)
			(xy 168.42994 -133.546088) (xy 168.428416 -133.546342) (xy 168.405048 -133.550152) (xy 168.40454 -133.550152)
			(xy 168.39565 -133.551422) (xy 168.395142 -133.551422) (xy 168.382104 -133.552778) (xy 168.355926 -133.554178)
			(xy 168.342818 -133.554216) (xy 168.315437 -133.553826) (xy 168.261064 -133.547326) (xy 168.23436 -133.541262)
			(xy 168.223946 -133.538722) (xy 168.21404 -133.5405) (xy 168.208849 -133.54152) (xy 168.198994 -133.545359)
			(xy 168.194482 -133.54812) (xy 168.16324 -133.568948) (xy 168.130474 -133.591046) (xy 168.126617 -133.593895)
			(xy 168.119969 -133.600802) (xy 168.117266 -133.604762) (xy 168.111678 -133.613144) (xy 168.110408 -133.621272)
			(xy 168.1099 -133.624574) (xy 168.105235 -133.651169) (xy 168.089394 -133.702786) (xy 168.066432 -133.751654)
			(xy 168.036808 -133.796796) (xy 168.001115 -133.837309) (xy 167.960065 -133.872384) (xy 167.91448 -133.90132)
			(xy 167.86527 -133.923538) (xy 167.813418 -133.938596) (xy 167.759961 -133.946191) (xy 167.732964 -133.946646)
			(xy 167.705712 -133.946158) (xy 167.651763 -133.938396) (xy 167.599467 -133.923036) (xy 167.549889 -133.900391)
			(xy 167.504039 -133.870921) (xy 167.462849 -133.835226) (xy 167.427158 -133.794032) (xy 167.397692 -133.748179)
			(xy 167.375051 -133.698599) (xy 167.359696 -133.646302) (xy 167.35194 -133.592352) (xy 167.35194 -133.537848)
			(xy 167.359696 -133.483898) (xy 167.375051 -133.431601) (xy 167.397692 -133.382021) (xy 167.427158 -133.336168)
			(xy 167.462849 -133.294974) (xy 167.504039 -133.259279) (xy 167.549889 -133.229809) (xy 167.599467 -133.207164)
			(xy 167.651763 -133.191804) (xy 167.705712 -133.184042) (xy 167.732964 -133.18363) (xy 167.74943 -133.183781)
			(xy 167.782242 -133.18658) (xy 167.798496 -133.189218) (xy 167.799004 -133.189472) (xy 167.799512 -133.189472)
			(xy 167.801544 -133.189726) (xy 167.81018 -133.190488) (xy 167.818436 -133.190204) (xy 167.834108 -133.185012)
			(xy 167.840914 -133.180328) (xy 167.86606 -133.158738) (xy 167.869108 -133.155944) (xy 167.876451 -133.148476)
			(xy 167.884865 -133.12932) (xy 167.885364 -133.11886) (xy 167.885364 -133.116828) (xy 167.884856 -133.096508)
			(xy 167.884856 -132.232908) (xy 167.885364 -132.213604) (xy 167.885377 -132.203061) (xy 167.877902 -132.183373)
			(xy 167.870886 -132.175504) (xy 167.867838 -132.17271) (xy 167.858948 -132.16509) (xy 167.85844 -132.164582)
			(xy 167.841168 -132.150104) (xy 167.834596 -132.145496) (xy 167.819461 -132.140176) (xy 167.81145 -132.13969)
			(xy 167.802306 -132.140452) (xy 167.800274 -132.140706) (xy 167.799004 -132.14096) (xy 167.782812 -132.143581)
			(xy 167.750128 -132.146378) (xy 167.733726 -132.146548) (xy 167.732964 -132.146548) (xy 167.705712 -132.14606)
			(xy 167.651762 -132.138298) (xy 167.599466 -132.122938) (xy 167.549888 -132.100293) (xy 167.504038 -132.070822)
			(xy 167.462847 -132.035127) (xy 167.427156 -131.993934) (xy 167.39769 -131.94808) (xy 167.375049 -131.8985)
			(xy 167.359694 -131.846203) (xy 167.351938 -131.792252) (xy 167.351938 -131.737748) (xy 167.359694 -131.683797)
			(xy 167.375049 -131.6315) (xy 167.39769 -131.58192) (xy 167.427156 -131.536066) (xy 167.462847 -131.494873)
			(xy 167.504038 -131.459178) (xy 167.549888 -131.429707) (xy 167.599466 -131.407062) (xy 167.651762 -131.391702)
			(xy 167.705712 -131.38394) (xy 167.732964 -131.383532) (xy 167.759947 -131.383996) (xy 167.813374 -131.391594)
			(xy 167.865198 -131.406645) (xy 167.914384 -131.428847) (xy 167.959952 -131.457758) (xy 168.000991 -131.4928)
			(xy 168.036684 -131.533276) (xy 168.066318 -131.578376) (xy 168.089301 -131.627202) (xy 168.105176 -131.678779)
			(xy 168.1099 -131.70535) (xy 168.110662 -131.710938) (xy 168.113273 -131.719067) (xy 168.123009 -131.733081)
			(xy 168.129712 -131.73837) (xy 168.15816 -131.757166) (xy 168.195244 -131.781804) (xy 168.199532 -131.784383)
			(xy 168.208873 -131.787965) (xy 168.213786 -131.788916) (xy 168.21531 -131.78917) (xy 168.223946 -131.790694)
			(xy 168.226994 -131.789932) (xy 168.232836 -131.788408) (xy 168.237662 -131.787138) (xy 168.23817 -131.787138)
			(xy 168.246298 -131.785106) (xy 168.248076 -131.784852) (xy 168.259506 -131.782566) (xy 168.290494 -131.777994)
			(xy 168.303468 -131.776642) (xy 168.329519 -131.775241) (xy 168.342564 -131.7752) (xy 168.343072 -131.7752)
			(xy 168.356116 -131.775249) (xy 168.382167 -131.776646) (xy 168.395142 -131.777994) (xy 168.39565 -131.777994)
			(xy 168.40454 -131.779264) (xy 168.405048 -131.779264) (xy 168.430956 -131.783582) (xy 168.433496 -131.78409)
			(xy 168.436036 -131.784598) (xy 168.445688 -131.785614) (xy 168.452729 -131.785394) (xy 168.466269 -131.781535)
			(xy 168.472358 -131.777994) (xy 168.520872 -131.744974) (xy 168.528238 -131.739894) (xy 168.534588 -131.734814)
			(xy 168.537636 -131.731512) (xy 168.53916 -131.729734) (xy 168.549066 -131.716018) (xy 168.552034 -131.711432)
			(xy 168.556134 -131.70131) (xy 168.557194 -131.695952) (xy 168.562483 -131.668327) (xy 168.579777 -131.614806)
			(xy 168.604382 -131.564227) (xy 168.635813 -131.517584) (xy 168.673456 -131.475791) (xy 168.716569 -131.439669)
			(xy 168.764308 -131.409928) (xy 168.815735 -131.38715) (xy 168.869841 -131.371783) (xy 168.925563 -131.364129)
			(xy 168.953688 -131.36372) (xy 168.986031 -131.364436) (xy 169.049849 -131.375026) (xy 169.080688 -131.384802)
			(xy 169.080942 -131.384802) (xy 169.08526 -131.386326) (xy 169.108726 -131.394963) (xy 169.153485 -131.417257)
			(xy 169.195122 -131.444948) (xy 169.214292 -131.461002) (xy 169.220896 -131.466844) (xy 169.245534 -131.476242)
			(xy 169.249882 -131.477783) (xy 169.258956 -131.479441) (xy 169.263568 -131.479544) (xy 169.276268 -131.479544)
			(xy 169.280879 -131.479439) (xy 169.28995 -131.477771) (xy 169.294302 -131.476242) (xy 169.31894 -131.466844)
			(xy 169.325798 -131.461002) (xy 169.349162 -131.4416) (xy 169.400614 -131.409337) (xy 169.456343 -131.385203)
			(xy 169.485564 -131.376928) (xy 169.486834 -131.376674) (xy 169.491406 -131.375404) (xy 169.524426 -131.3688)
			(xy 169.561002 -131.364736) (xy 169.56151 -131.364736) (xy 169.585132 -131.36372) (xy 169.587418 -131.36372)
			(xy 169.58818 -131.36372) (xy 169.605024 -131.363886) (xy 169.638597 -131.36668) (xy 169.655236 -131.369308)
			(xy 169.66057 -131.370324) (xy 169.661332 -131.370324) (xy 169.66946 -131.37007) (xy 169.670984 -131.369816)
			(xy 169.677002 -131.368767) (xy 169.688303 -131.364136) (xy 169.693336 -131.360672) (xy 169.708576 -131.347972)
			(xy 169.709084 -131.347464) (xy 169.72407 -131.334764) (xy 169.730878 -131.327418) (xy 169.738602 -131.308955)
			(xy 169.739056 -131.29895) (xy 169.739056 -130.430524) (xy 169.738485 -130.420081) (xy 169.730079 -130.400953)
			(xy 169.7228 -130.39344) (xy 169.70121 -130.374898) (xy 169.695114 -130.370072) (xy 169.688398 -130.365305)
			(xy 169.672857 -130.359882) (xy 169.664634 -130.359404) (xy 169.658792 -130.359658) (xy 169.657776 -130.359658)
			(xy 169.65549 -130.359912) (xy 169.650918 -130.360674) (xy 169.65041 -130.360674) (xy 169.646092 -130.361436)
			(xy 169.645584 -130.361436) (xy 169.642282 -130.361944) (xy 169.629074 -130.363468) (xy 169.618689 -130.364454)
			(xy 169.59785 -130.365473) (xy 169.587418 -130.3655) (xy 169.558786 -130.365015) (xy 169.502105 -130.356868)
			(xy 169.44716 -130.340737) (xy 169.395071 -130.31695) (xy 169.346897 -130.285992) (xy 169.303619 -130.248494)
			(xy 169.266118 -130.205218) (xy 169.235159 -130.157045) (xy 169.21137 -130.104956) (xy 169.195236 -130.050013)
			(xy 169.187087 -129.993332) (xy 169.187087 -129.936068) (xy 169.195236 -129.879387) (xy 169.21137 -129.824444)
			(xy 169.235159 -129.772355) (xy 169.266118 -129.724182) (xy 169.303619 -129.680906) (xy 169.346897 -129.643408)
			(xy 169.395071 -129.61245) (xy 169.44716 -129.588663) (xy 169.502105 -129.572532) (xy 169.558786 -129.564385)
			(xy 169.587418 -129.563876) (xy 169.600151 -129.563926) (xy 169.62557 -129.565452) (xy 169.638218 -129.566924)
			(xy 169.662602 -129.570734) (xy 169.663618 -129.570988) (xy 169.692338 -129.577075) (xy 169.74773 -129.596519)
			(xy 169.799701 -129.623823) (xy 169.847143 -129.658402) (xy 169.889044 -129.69952) (xy 169.924511 -129.746302)
			(xy 169.952789 -129.797749) (xy 169.973275 -129.852765) (xy 169.979848 -129.881376) (xy 169.980102 -129.882646)
			(xy 169.980864 -129.885694) (xy 169.98188 -129.891282) (xy 169.982896 -129.897378) (xy 169.98403 -129.902326)
			(xy 169.987997 -129.911668) (xy 169.99077 -129.91592) (xy 170.000676 -129.929636) (xy 170.0022 -129.931414)
			(xy 170.005248 -129.934716) (xy 170.011598 -129.939796) (xy 170.018964 -129.944876) (xy 170.06824 -129.978658)
			(xy 170.075208 -129.98234) (xy 170.090597 -129.985695) (xy 170.098466 -129.985262) (xy 170.111057 -129.982599)
			(xy 170.136473 -129.978533) (xy 170.149266 -129.977134) (xy 170.18 -129.974384) (xy 170.241679 -129.976165)
			(xy 170.272202 -129.98069) (xy 170.273218 -129.980944) (xy 170.307254 -129.985008) (xy 170.312572 -129.984121)
			(xy 170.322695 -129.980413) (xy 170.32732 -129.977642) (xy 170.375072 -129.944876) (xy 170.389804 -129.934716)
			(xy 170.390058 -129.934462) (xy 170.391074 -129.933954) (xy 170.3948 -129.931078) (xy 170.401195 -129.924175)
			(xy 170.403774 -129.920238) (xy 170.404536 -129.918968) (xy 170.409616 -129.907538) (xy 170.409616 -129.90703)
			(xy 170.410632 -129.901188) (xy 170.415869 -129.871926) (xy 170.433843 -129.815265) (xy 170.459991 -129.76188)
			(xy 170.476418 -129.737104) (xy 170.478196 -129.734818) (xy 170.481752 -129.729738) (xy 170.48226 -129.728722)
			(xy 170.487848 -129.721356) (xy 170.488356 -129.720848) (xy 170.489626 -129.71907) (xy 170.490134 -129.718562)
			(xy 170.509226 -129.694908) (xy 170.553345 -129.653097) (xy 170.603278 -129.618436) (xy 170.657876 -129.59172)
			(xy 170.715885 -129.573565) (xy 170.775972 -129.564386) (xy 170.806364 -129.563876) (xy 170.806618 -129.563876)
			(xy 170.835248 -129.564388) (xy 170.891925 -129.572539) (xy 170.946866 -129.588673) (xy 170.998951 -129.612462)
			(xy 171.04712 -129.64342) (xy 171.090394 -129.680919) (xy 171.12789 -129.724194) (xy 171.158847 -129.772365)
			(xy 171.182633 -129.824451) (xy 171.198765 -129.879392) (xy 171.206914 -129.93607) (xy 171.206914 -129.99333)
			(xy 171.198765 -130.050008) (xy 171.182633 -130.104949) (xy 171.158847 -130.157035) (xy 171.12789 -130.205206)
			(xy 171.090394 -130.248481) (xy 171.04712 -130.28598) (xy 170.998951 -130.316938) (xy 170.946866 -130.340727)
			(xy 170.891925 -130.356861) (xy 170.835248 -130.365012) (xy 170.806618 -130.3655) (xy 170.796186 -130.365465)
			(xy 170.775348 -130.364449) (xy 170.764962 -130.363468) (xy 170.758104 -130.362706) (xy 170.757596 -130.362706)
			(xy 170.748452 -130.361436) (xy 170.747944 -130.361436) (xy 170.743626 -130.360674) (xy 170.743118 -130.360674)
			(xy 170.738546 -130.359912) (xy 170.73626 -130.359658) (xy 170.726294 -130.358878) (xy 170.707058 -130.36426)
			(xy 170.698922 -130.370072) (xy 170.692826 -130.374898) (xy 170.671236 -130.39344) (xy 170.663901 -130.400911)
			(xy 170.655512 -130.420067) (xy 170.65498 -130.430524) (xy 170.65498 -130.430778) (xy 170.65498 -130.43281)
			(xy 170.65498 -131.29895) (xy 170.655513 -131.309214) (xy 170.663653 -131.328068) (xy 170.670728 -131.335526)
			(xy 170.698922 -131.359656) (xy 170.707596 -131.365675) (xy 170.728059 -131.370786) (xy 170.738546 -131.369562)
			(xy 170.7388 -131.369562) (xy 170.74261 -131.3688) (xy 170.758314 -131.366424) (xy 170.789975 -131.363882)
			(xy 170.805856 -131.36372) (xy 170.806618 -131.36372) (xy 170.835266 -131.364232) (xy 170.89198 -131.372388)
			(xy 170.946955 -131.388533) (xy 170.999074 -131.412337) (xy 171.047274 -131.443315) (xy 171.090575 -131.480838)
			(xy 171.128096 -131.52414) (xy 171.159072 -131.572342) (xy 171.182873 -131.624462) (xy 171.199015 -131.679438)
			(xy 171.207169 -131.736152) (xy 171.207169 -131.793448) (xy 171.199015 -131.850162) (xy 171.182873 -131.905138)
			(xy 171.159072 -131.957258) (xy 171.128096 -132.00546) (xy 171.090575 -132.048762) (xy 171.047274 -132.086285)
			(xy 170.999074 -132.117263) (xy 170.946955 -132.141067) (xy 170.89198 -132.157212) (xy 170.835266 -132.165368)
			(xy 170.806618 -132.165852) (xy 170.778294 -132.165365) (xy 170.722209 -132.157396) (xy 170.667803 -132.141614)
			(xy 170.61616 -132.118334) (xy 170.568306 -132.088018) (xy 170.525195 -132.05127) (xy 170.487684 -132.008821)
			(xy 170.456519 -131.961515) (xy 170.432321 -131.910295) (xy 170.415571 -131.85618) (xy 170.410632 -131.828286)
			(xy 170.410632 -131.82727) (xy 170.409616 -131.821936) (xy 170.408854 -131.817618) (xy 170.40352 -131.808982)
			(xy 170.401246 -131.805498) (xy 170.395754 -131.799247) (xy 170.392598 -131.796536) (xy 170.359578 -131.773676)
			(xy 170.35907 -131.773676) (xy 170.326812 -131.75107) (xy 170.319552 -131.747029) (xy 170.303351 -131.743389)
			(xy 170.295062 -131.743958) (xy 170.27797 -131.747523) (xy 170.243388 -131.752351) (xy 170.225974 -131.75361)
			(xy 170.199876 -131.754965) (xy 170.147676 -131.75242) (xy 170.121834 -131.74853) (xy 170.120818 -131.748276)
			(xy 170.086528 -131.744212) (xy 170.081135 -131.74515) (xy 170.070888 -131.748993) (xy 170.066208 -131.751832)
			(xy 170.034966 -131.773676) (xy 170.034458 -131.773676) (xy 170.001438 -131.796536) (xy 169.998271 -131.799237)
			(xy 169.992782 -131.805492) (xy 169.990516 -131.808982) (xy 169.985182 -131.817618) (xy 169.98442 -131.821936)
			(xy 169.983404 -131.82727) (xy 169.983404 -131.828286) (xy 169.978424 -131.856237) (xy 169.961622 -131.910467)
			(xy 169.937339 -131.961785) (xy 169.906062 -132.009166) (xy 169.868416 -132.051663) (xy 169.825153 -132.088426)
			(xy 169.777138 -132.118721) (xy 169.725331 -132.141941) (xy 169.670767 -132.157624) (xy 169.614536 -132.165455)
			(xy 169.586148 -132.165852) (xy 169.553806 -132.16513) (xy 169.489991 -132.15453) (xy 169.459148 -132.14477)
			(xy 169.458894 -132.14477) (xy 169.454576 -132.143246) (xy 169.431112 -132.134605) (xy 169.386358 -132.112305)
			(xy 169.344728 -132.084607) (xy 169.325544 -132.06857) (xy 169.31894 -132.062728) (xy 169.294302 -132.05333)
			(xy 169.289954 -132.051786) (xy 169.280881 -132.050123) (xy 169.276268 -132.050028) (xy 169.263568 -132.050028)
			(xy 169.258956 -132.050131) (xy 169.249884 -132.051795) (xy 169.245534 -132.05333) (xy 169.220896 -132.062728)
			(xy 169.214038 -132.06857) (xy 169.190673 -132.087971) (xy 169.139221 -132.120232) (xy 169.083493 -132.144367)
			(xy 169.054272 -132.152644) (xy 169.053002 -132.152898) (xy 169.04843 -132.154168) (xy 169.01541 -132.160772)
			(xy 168.978834 -132.164836) (xy 168.978326 -132.164836) (xy 168.954704 -132.165852) (xy 168.952418 -132.165852)
			(xy 168.951656 -132.165852) (xy 168.934812 -132.165683) (xy 168.90124 -132.162884) (xy 168.8846 -132.160264)
			(xy 168.879266 -132.159248) (xy 168.878504 -132.159248) (xy 168.870376 -132.159502) (xy 168.868852 -132.159756)
			(xy 168.862831 -132.160799) (xy 168.851524 -132.165423) (xy 168.8465 -132.1689) (xy 168.83126 -132.1816)
			(xy 168.830752 -132.182108) (xy 168.815766 -132.194808) (xy 168.80895 -132.202151) (xy 168.80121 -132.220614)
			(xy 168.80078 -132.230622) (xy 168.80078 -133.098794) (xy 168.801302 -133.109063) (xy 168.809428 -133.127932)
			(xy 168.816528 -133.13537) (xy 168.844722 -133.1595) (xy 168.853395 -133.165524) (xy 168.873859 -133.170642)
			(xy 168.884346 -133.169406) (xy 168.8846 -133.169406) (xy 168.88841 -133.168644) (xy 168.904051 -133.16628)
			(xy 168.935584 -133.163737) (xy 168.951402 -133.163564) (xy 168.954704 -133.163564) (xy 168.983019 -133.164214)
			(xy 169.039045 -133.172502) (xy 169.093349 -133.188588) (xy 169.14485 -133.212152) (xy 169.192524 -133.242726)
			(xy 169.214292 -133.260846) (xy 169.215308 -133.261862) (xy 169.22115 -133.266688) (xy 169.24655 -133.276594)
			(xy 169.250679 -133.277914) (xy 169.259233 -133.279322) (xy 169.263568 -133.279388) (xy 169.27703 -133.279388)
			(xy 169.281034 -133.27928) (xy 169.288942 -133.278001) (xy 169.292778 -133.276848) (xy 169.319194 -133.266434)
			(xy 169.325798 -133.260846) (xy 169.352722 -133.23951) (xy 169.362882 -133.232398) (xy 169.387885 -133.216164)
			(xy 169.441671 -133.190463) (xy 169.498664 -133.172989) (xy 169.557613 -133.164127) (xy 169.587418 -133.163564)
			(xy 169.615478 -133.164027) (xy 169.671051 -133.171838) (xy 169.724992 -133.187318) (xy 169.77625 -133.210165)
			(xy 169.823823 -133.239934) (xy 169.866782 -133.276043) (xy 169.904289 -133.317787) (xy 169.935612 -133.364351)
			(xy 169.960139 -133.414827) (xy 169.977391 -133.468229) (xy 169.982642 -133.495796) (xy 169.983717 -133.501149)
			(xy 169.987822 -133.511265) (xy 169.99077 -133.515862) (xy 170.000676 -133.529578) (xy 170.0022 -133.531356)
			(xy 170.005248 -133.534658) (xy 170.011598 -133.539738) (xy 170.018964 -133.544818) (xy 170.067478 -133.578092)
			(xy 170.075488 -133.582516) (xy 170.093457 -133.585893) (xy 170.10253 -133.584696) (xy 170.108626 -133.583426)
			(xy 170.109388 -133.583172) (xy 170.109896 -133.583172) (xy 170.11142 -133.582918) (xy 170.134788 -133.579108)
			(xy 170.135296 -133.579108) (xy 170.144186 -133.577838) (xy 170.144694 -133.577838) (xy 170.157668 -133.576486)
			(xy 170.183719 -133.575085) (xy 170.196764 -133.575044) (xy 170.197272 -133.575044) (xy 170.210316 -133.575093)
			(xy 170.236367 -133.57649) (xy 170.249342 -133.577838) (xy 170.24985 -133.577838) (xy 170.25874 -133.579108)
			(xy 170.259248 -133.579108) (xy 170.285156 -133.583426) (xy 170.287696 -133.583934) (xy 170.290236 -133.584442)
			(xy 170.299888 -133.585458) (xy 170.306928 -133.585238) (xy 170.320467 -133.581375) (xy 170.326558 -133.577838)
			(xy 170.375072 -133.544818) (xy 170.382438 -133.539738) (xy 170.388788 -133.534658) (xy 170.391836 -133.531356)
			(xy 170.39336 -133.529578) (xy 170.403266 -133.515862) (xy 170.406229 -133.511274) (xy 170.410318 -133.501151)
			(xy 170.411394 -133.495796) (xy 170.416691 -133.468243) (xy 170.433966 -133.414862) (xy 170.458506 -133.364406)
			(xy 170.489833 -133.317859) (xy 170.527336 -133.276128) (xy 170.570286 -133.240027) (xy 170.617844 -133.210257)
			(xy 170.669084 -133.187401) (xy 170.723008 -133.171902) (xy 170.778565 -133.164064) (xy 170.806618 -133.163564)
			(xy 170.835263 -133.164076) (xy 170.89197 -133.172232) (xy 170.94694 -133.188375) (xy 170.999052 -133.212176)
			(xy 171.047247 -133.243151) (xy 171.090544 -133.280669) (xy 171.12806 -133.323967) (xy 171.159033 -133.372164)
			(xy 171.182832 -133.424277) (xy 171.198972 -133.479247) (xy 171.207125 -133.535955) (xy 171.207125 -133.593245)
			(xy 171.198972 -133.649953) (xy 171.182832 -133.704923) (xy 171.159033 -133.757036) (xy 171.12806 -133.805233)
			(xy 171.090544 -133.848531) (xy 171.047247 -133.886049) (xy 170.999052 -133.917024) (xy 170.94694 -133.940825)
			(xy 170.89197 -133.956968) (xy 170.835263 -133.965124) (xy 170.806618 -133.965696) (xy 170.805856 -133.965696)
			(xy 170.789975 -133.965519) (xy 170.758315 -133.962975) (xy 170.74261 -133.960616) (xy 170.7388 -133.959854)
			(xy 170.738546 -133.959854) (xy 170.728056 -133.958577) (xy 170.707581 -133.963702) (xy 170.698922 -133.96976)
			(xy 170.670728 -133.99389) (xy 170.663605 -134.001314) (xy 170.655471 -134.02019) (xy 170.65498 -134.030466)
			(xy 170.65498 -134.62) (xy 172.994826 -134.62) (xy 172.998897 -134.564378) (xy 173.011023 -134.509941)
			(xy 173.030946 -134.45785) (xy 173.058242 -134.409215) (xy 173.092328 -134.365072) (xy 173.132477 -134.326363)
			(xy 173.177835 -134.293912) (xy 173.227435 -134.268411) (xy 173.280219 -134.250404) (xy 173.335062 -134.240274)
			(xy 173.390796 -134.238237) (xy 173.446233 -134.244337) (xy 173.50019 -134.258443) (xy 173.551519 -134.280255)
			(xy 173.599125 -134.309309) (xy 173.641993 -134.344984) (xy 173.67921 -134.386521) (xy 173.709983 -134.433034)
			(xy 173.733655 -134.483531) (xy 173.749723 -134.536938) (xy 173.757843 -134.592114) (xy 173.758352 -134.62)
			(xy 173.757843 -134.647886) (xy 173.749723 -134.703062) (xy 173.733655 -134.756469) (xy 173.709983 -134.806966)
			(xy 173.67921 -134.853479) (xy 173.641993 -134.895016) (xy 173.599125 -134.930691) (xy 173.551519 -134.959745)
			(xy 173.50019 -134.981557) (xy 173.446233 -134.995663) (xy 173.390796 -135.001763) (xy 173.335062 -134.999726)
			(xy 173.280219 -134.989596) (xy 173.227435 -134.971589) (xy 173.177835 -134.946088) (xy 173.132477 -134.913637)
			(xy 173.092328 -134.874928) (xy 173.058242 -134.830785) (xy 173.030946 -134.78215) (xy 173.011023 -134.730059)
			(xy 172.998897 -134.675622) (xy 172.994826 -134.62) (xy 170.65498 -134.62) (xy 170.65498 -134.898892)
			(xy 170.655502 -134.909161) (xy 170.663627 -134.928031) (xy 170.670728 -134.935468) (xy 170.699176 -134.959852)
			(xy 170.707815 -134.965783) (xy 170.728145 -134.970773) (xy 170.738546 -134.969504) (xy 170.739054 -134.969504)
			(xy 170.755818 -134.966848) (xy 170.789646 -134.964055) (xy 170.806618 -134.963916) (xy 170.835245 -134.964428)
			(xy 170.891917 -134.972578) (xy 170.946852 -134.988711) (xy 170.998931 -135.012497) (xy 171.047096 -135.043452)
			(xy 171.090365 -135.080947) (xy 171.127858 -135.124218) (xy 171.158812 -135.172384) (xy 171.182596 -135.224465)
			(xy 171.198726 -135.279401) (xy 171.206874 -135.336073) (xy 171.206874 -135.393327) (xy 171.198726 -135.449999)
			(xy 171.182596 -135.504935) (xy 171.158812 -135.557016) (xy 171.127858 -135.605182) (xy 171.090365 -135.648453)
			(xy 171.047096 -135.685948) (xy 170.998931 -135.716903) (xy 170.946852 -135.740689) (xy 170.891917 -135.756822)
			(xy 170.835245 -135.764972) (xy 170.806618 -135.76554) (xy 170.793885 -135.765491) (xy 170.768465 -135.763967)
			(xy 170.755818 -135.762492) (xy 170.727492 -135.758358) (xy 170.672318 -135.743102) (xy 170.619873 -135.72016)
			(xy 170.571221 -135.689996) (xy 170.52735 -135.653225) (xy 170.489151 -135.610591) (xy 170.457398 -135.562961)
			(xy 170.432738 -135.511301) (xy 170.41567 -135.456661) (xy 170.410632 -135.428482) (xy 170.409108 -135.417814)
			(xy 170.40352 -135.408924) (xy 170.400913 -135.405009) (xy 170.394527 -135.398103) (xy 170.39082 -135.395208)
			(xy 170.359578 -135.373618) (xy 170.35907 -135.373618) (xy 170.347386 -135.36549) (xy 170.326812 -135.351012)
			(xy 170.318937 -135.346588) (xy 170.301234 -135.343065) (xy 170.292268 -135.344154) (xy 170.284394 -135.345932)
			(xy 170.26128 -135.349742) (xy 170.260772 -135.349742) (xy 170.259248 -135.349996) (xy 170.258994 -135.349996)
			(xy 170.255692 -135.350504) (xy 170.241148 -135.352209) (xy 170.211916 -135.353989) (xy 170.197272 -135.35406)
			(xy 170.196764 -135.35406) (xy 170.18372 -135.35401) (xy 170.157669 -135.352609) (xy 170.144694 -135.351266)
			(xy 170.144186 -135.351266) (xy 170.135296 -135.349996) (xy 170.134788 -135.349996) (xy 170.10888 -135.345678)
			(xy 170.10634 -135.34517) (xy 170.106086 -135.34517) (xy 170.1038 -135.344662) (xy 170.094375 -135.343137)
			(xy 170.075577 -135.34639) (xy 170.067224 -135.351012) (xy 170.034966 -135.373618) (xy 170.034458 -135.373618)
			(xy 170.003216 -135.395208) (xy 169.999494 -135.398087) (xy 169.993107 -135.404996) (xy 169.990516 -135.408924)
			(xy 169.984928 -135.417814) (xy 169.983404 -135.428482) (xy 169.978426 -135.456358) (xy 169.961658 -135.510444)
			(xy 169.937447 -135.561634) (xy 169.906275 -135.608908) (xy 169.868763 -135.651326) (xy 169.825656 -135.688046)
			(xy 169.777813 -135.718336) (xy 169.726183 -135.741593) (xy 169.671796 -135.757356) (xy 169.615731 -135.765311)
			(xy 169.587418 -135.765794) (xy 169.553128 -135.76427) (xy 169.545762 -135.763762) (xy 169.533062 -135.761984)
			(xy 169.504566 -135.757581) (xy 169.449149 -135.741655) (xy 169.39659 -135.717945) (xy 169.347975 -135.686941)
			(xy 169.325798 -135.668512) (xy 169.319194 -135.662924) (xy 169.292778 -135.65251) (xy 169.288952 -135.651316)
			(xy 169.281038 -135.650045) (xy 169.27703 -135.64997) (xy 169.262806 -135.64997) (xy 169.258801 -135.650075)
			(xy 169.250893 -135.651351) (xy 169.247058 -135.65251) (xy 169.220642 -135.662924) (xy 169.214038 -135.668512)
			(xy 169.192116 -135.686708) (xy 169.144101 -135.717374) (xy 169.092232 -135.74094) (xy 169.037551 -135.756932)
			(xy 168.981158 -135.765029) (xy 168.952672 -135.76554) (xy 168.952418 -135.76554) (xy 168.941986 -135.765505)
			(xy 168.921148 -135.764488) (xy 168.910762 -135.763508) (xy 168.903904 -135.762746) (xy 168.903396 -135.762746)
			(xy 168.894252 -135.761476) (xy 168.893744 -135.761476) (xy 168.889426 -135.760714) (xy 168.888918 -135.760714)
			(xy 168.884346 -135.759952) (xy 168.88206 -135.759698) (xy 168.872099 -135.758987) (xy 168.852885 -135.764357)
			(xy 168.844722 -135.770112) (xy 168.838626 -135.774938) (xy 168.817036 -135.79348) (xy 168.809691 -135.800947)
			(xy 168.801279 -135.820103) (xy 168.80078 -135.830564) (xy 168.80078 -136.69899) (xy 168.801301 -136.70926)
			(xy 168.809426 -136.728129) (xy 168.816528 -136.735566) (xy 168.844722 -136.759696) (xy 168.853395 -136.765721)
			(xy 168.873859 -136.770838) (xy 168.884346 -136.769602) (xy 168.8846 -136.769602) (xy 168.88841 -136.76884)
			(xy 168.904114 -136.766465) (xy 168.935775 -136.763922) (xy 168.951656 -136.76376) (xy 168.952418 -136.76376)
			(xy 168.981066 -136.764248) (xy 169.03778 -136.772405) (xy 169.092755 -136.78855) (xy 169.144873 -136.812355)
			(xy 169.193073 -136.843334) (xy 169.236373 -136.880858) (xy 169.273892 -136.924162) (xy 169.304867 -136.972365)
			(xy 169.328665 -137.024486) (xy 169.344805 -137.079463) (xy 169.352955 -137.136177) (xy 169.353484 -137.164826)
			(xy 169.353484 -137.16508) (xy 169.35196 -137.199878) (xy 169.35196 -137.200132) (xy 169.349034 -137.227833)
			(xy 169.336499 -137.282106) (xy 169.316568 -137.33412) (xy 169.289624 -137.382872) (xy 169.256188 -137.427422)
			(xy 169.216904 -137.466912) (xy 169.194988 -137.484104) (xy 169.188638 -137.48893) (xy 169.179748 -137.502138)
			(xy 169.177208 -137.509504) (xy 169.17527 -137.516607) (xy 169.175142 -137.531324) (xy 169.176954 -137.53846)
			(xy 169.194734 -137.591038) (xy 169.208704 -137.63244) (xy 169.212624 -137.642159) (xy 169.226825 -137.657539)
			(xy 169.24599 -137.665961) (xy 169.256456 -137.666476) (xy 172.854874 -137.666476) (xy 172.861986 -137.665968)
			(xy 172.873221 -137.663674) (xy 172.892211 -137.650878) (xy 172.898562 -137.64133) (xy 172.922692 -137.594594)
			(xy 172.942758 -137.555986) (xy 172.945047 -137.550304) (xy 172.947093 -137.53823) (xy 172.946822 -137.53211)
			(xy 172.945806 -137.518394) (xy 172.864018 -137.400538) (xy 172.858834 -137.392271) (xy 172.854521 -137.373257)
			(xy 172.8576 -137.354004) (xy 172.86224 -137.34542) (xy 172.86605 -137.338816) (xy 172.86986 -137.32383)
			(xy 172.869098 -137.311892) (xy 172.868336 -137.287) (xy 172.868336 -137.280142) (xy 172.869352 -137.251927)
			(xy 172.878674 -137.196245) (xy 172.896098 -137.142544) (xy 172.921245 -137.091996) (xy 172.953565 -137.045706)
			(xy 172.992354 -137.004683) (xy 173.036764 -136.969824) (xy 173.085825 -136.941889) (xy 173.138467 -136.921488)
			(xy 173.193541 -136.909066) (xy 173.249844 -136.904895) (xy 173.306147 -136.909066) (xy 173.361221 -136.921488)
			(xy 173.413863 -136.941889) (xy 173.462924 -136.969824) (xy 173.507334 -137.004683) (xy 173.546123 -137.045706)
			(xy 173.578443 -137.091996) (xy 173.60359 -137.142544) (xy 173.621014 -137.196245) (xy 173.630336 -137.251927)
			(xy 173.631352 -137.280142) (xy 173.631352 -137.287) (xy 173.630819 -137.316198) (xy 173.621964 -137.373918)
			(xy 173.604415 -137.429614) (xy 173.578583 -137.481985) (xy 173.562264 -137.506202) (xy 173.56201 -137.506456)
			(xy 173.56074 -137.508488) (xy 173.557478 -137.513882) (xy 173.5535 -137.525838) (xy 173.552866 -137.53211)
			(xy 173.552358 -137.539222) (xy 173.555152 -137.552684) (xy 173.55947 -137.56132) (xy 173.601634 -137.642092)
			(xy 173.607968 -137.651372) (xy 173.626687 -137.663747) (xy 173.637702 -137.665968) (xy 173.644814 -137.666476)
			(xy 174.703486 -137.666476) (xy 174.713536 -137.666983) (xy 174.732095 -137.674706) (xy 174.739554 -137.681462)
			(xy 174.90694 -137.848848) (xy 178.039774 -137.848848) (xy 178.043845 -137.793226) (xy 178.055971 -137.738789)
			(xy 178.075894 -137.686698) (xy 178.10319 -137.638063) (xy 178.137276 -137.59392) (xy 178.177425 -137.555211)
			(xy 178.222783 -137.52276) (xy 178.272383 -137.497259) (xy 178.325167 -137.479252) (xy 178.38001 -137.469122)
			(xy 178.435744 -137.467085) (xy 178.491181 -137.473185) (xy 178.545138 -137.487291) (xy 178.596467 -137.509103)
			(xy 178.644073 -137.538157) (xy 178.686941 -137.573832) (xy 178.724158 -137.615369) (xy 178.754931 -137.661882)
			(xy 178.778603 -137.712379) (xy 178.794671 -137.765786) (xy 178.802791 -137.820962) (xy 178.8033 -137.848848)
			(xy 178.802791 -137.876734) (xy 178.794671 -137.93191) (xy 178.778603 -137.985317) (xy 178.754931 -138.035814)
			(xy 178.724158 -138.082327) (xy 178.686941 -138.123864) (xy 178.644073 -138.159539) (xy 178.596467 -138.188593)
			(xy 178.545138 -138.210405) (xy 178.491181 -138.224511) (xy 178.435744 -138.230611) (xy 178.38001 -138.228574)
			(xy 178.325167 -138.218444) (xy 178.272383 -138.200437) (xy 178.222783 -138.174936) (xy 178.177425 -138.142485)
			(xy 178.137276 -138.103776) (xy 178.10319 -138.059633) (xy 178.075894 -138.010998) (xy 178.055971 -137.958907)
			(xy 178.043845 -137.90447) (xy 178.039774 -137.848848) (xy 174.90694 -137.848848) (xy 175.49241 -138.434318)
			(xy 198.100948 -138.434318) (xy 198.105019 -138.378696) (xy 198.117145 -138.324259) (xy 198.137068 -138.272168)
			(xy 198.164364 -138.223533) (xy 198.19845 -138.17939) (xy 198.238599 -138.140681) (xy 198.283957 -138.10823)
			(xy 198.333557 -138.082729) (xy 198.386341 -138.064722) (xy 198.441184 -138.054592) (xy 198.496918 -138.052555)
			(xy 198.552355 -138.058655) (xy 198.606312 -138.072761) (xy 198.648423 -138.090656) (xy 224.549206 -138.090656)
			(xy 224.553277 -138.035034) (xy 224.565403 -137.980597) (xy 224.585326 -137.928506) (xy 224.612622 -137.879871)
			(xy 224.646708 -137.835728) (xy 224.686857 -137.797019) (xy 224.732215 -137.764568) (xy 224.781815 -137.739067)
			(xy 224.834599 -137.72106) (xy 224.889442 -137.71093) (xy 224.945176 -137.708893) (xy 225.000613 -137.714993)
			(xy 225.05457 -137.729099) (xy 225.105899 -137.750911) (xy 225.153505 -137.779965) (xy 225.196373 -137.81564)
			(xy 225.23359 -137.857177) (xy 225.264363 -137.90369) (xy 225.288035 -137.954187) (xy 225.304103 -138.007594)
			(xy 225.312223 -138.06277) (xy 225.312732 -138.090656) (xy 225.312223 -138.118542) (xy 225.304103 -138.173718)
			(xy 225.288035 -138.227125) (xy 225.264363 -138.277622) (xy 225.23359 -138.324135) (xy 225.196373 -138.365672)
			(xy 225.153505 -138.401347) (xy 225.105899 -138.430401) (xy 225.05457 -138.452213) (xy 225.000613 -138.466319)
			(xy 224.945176 -138.472419) (xy 224.889442 -138.470382) (xy 224.834599 -138.460252) (xy 224.781815 -138.442245)
			(xy 224.732215 -138.416744) (xy 224.686857 -138.384293) (xy 224.646708 -138.345584) (xy 224.612622 -138.301441)
			(xy 224.585326 -138.252806) (xy 224.565403 -138.200715) (xy 224.553277 -138.146278) (xy 224.549206 -138.090656)
			(xy 198.648423 -138.090656) (xy 198.657641 -138.094573) (xy 198.705247 -138.123627) (xy 198.748115 -138.159302)
			(xy 198.785332 -138.200839) (xy 198.816105 -138.247352) (xy 198.839777 -138.297849) (xy 198.855845 -138.351256)
			(xy 198.863965 -138.406432) (xy 198.864474 -138.434318) (xy 198.863965 -138.462204) (xy 198.85764 -138.505184)
			(xy 221.778828 -138.505184) (xy 221.782899 -138.449562) (xy 221.795025 -138.395125) (xy 221.814948 -138.343034)
			(xy 221.842244 -138.294399) (xy 221.87633 -138.250256) (xy 221.916479 -138.211547) (xy 221.961837 -138.179096)
			(xy 222.011437 -138.153595) (xy 222.064221 -138.135588) (xy 222.119064 -138.125458) (xy 222.174798 -138.123421)
			(xy 222.230235 -138.129521) (xy 222.284192 -138.143627) (xy 222.335521 -138.165439) (xy 222.383127 -138.194493)
			(xy 222.425995 -138.230168) (xy 222.463212 -138.271705) (xy 222.493985 -138.318218) (xy 222.517657 -138.368715)
			(xy 222.533725 -138.422122) (xy 222.541845 -138.477298) (xy 222.542354 -138.505184) (xy 222.541845 -138.53307)
			(xy 222.533725 -138.588246) (xy 222.517657 -138.641653) (xy 222.493985 -138.69215) (xy 222.463212 -138.738663)
			(xy 222.425995 -138.7802) (xy 222.383127 -138.815875) (xy 222.369057 -138.824462) (xy 240.561874 -138.824462)
			(xy 240.565945 -138.76884) (xy 240.578071 -138.714403) (xy 240.597994 -138.662312) (xy 240.62529 -138.613677)
			(xy 240.659376 -138.569534) (xy 240.699525 -138.530825) (xy 240.744883 -138.498374) (xy 240.794483 -138.472873)
			(xy 240.847267 -138.454866) (xy 240.90211 -138.444736) (xy 240.957844 -138.442699) (xy 241.013281 -138.448799)
			(xy 241.067238 -138.462905) (xy 241.118567 -138.484717) (xy 241.166173 -138.513771) (xy 241.209041 -138.549446)
			(xy 241.246258 -138.590983) (xy 241.277031 -138.637496) (xy 241.300703 -138.687993) (xy 241.316771 -138.7414)
			(xy 241.324891 -138.796576) (xy 241.3254 -138.824462) (xy 241.324891 -138.852348) (xy 241.318641 -138.89482)
			(xy 244.47703 -138.89482) (xy 244.481101 -138.839198) (xy 244.493227 -138.784761) (xy 244.51315 -138.73267)
			(xy 244.540446 -138.684035) (xy 244.574532 -138.639892) (xy 244.614681 -138.601183) (xy 244.660039 -138.568732)
			(xy 244.709639 -138.543231) (xy 244.762423 -138.525224) (xy 244.817266 -138.515094) (xy 244.873 -138.513057)
			(xy 244.928437 -138.519157) (xy 244.982394 -138.533263) (xy 245.033723 -138.555075) (xy 245.081329 -138.584129)
			(xy 245.124197 -138.619804) (xy 245.161414 -138.661341) (xy 245.192187 -138.707854) (xy 245.215859 -138.758351)
			(xy 245.231927 -138.811758) (xy 245.240047 -138.866934) (xy 245.240556 -138.89482) (xy 245.240047 -138.922706)
			(xy 245.231927 -138.977882) (xy 245.215859 -139.031289) (xy 245.192187 -139.081786) (xy 245.161414 -139.128299)
			(xy 245.124197 -139.169836) (xy 245.081329 -139.205511) (xy 245.033723 -139.234565) (xy 244.982394 -139.256377)
			(xy 244.928437 -139.270483) (xy 244.873 -139.276583) (xy 244.817266 -139.274546) (xy 244.762423 -139.264416)
			(xy 244.709639 -139.246409) (xy 244.660039 -139.220908) (xy 244.614681 -139.188457) (xy 244.574532 -139.149748)
			(xy 244.540446 -139.105605) (xy 244.51315 -139.05697) (xy 244.493227 -139.004879) (xy 244.481101 -138.950442)
			(xy 244.47703 -138.89482) (xy 241.318641 -138.89482) (xy 241.316771 -138.907524) (xy 241.300703 -138.960931)
			(xy 241.277031 -139.011428) (xy 241.246258 -139.057941) (xy 241.209041 -139.099478) (xy 241.166173 -139.135153)
			(xy 241.118567 -139.164207) (xy 241.067238 -139.186019) (xy 241.013281 -139.200125) (xy 240.957844 -139.206225)
			(xy 240.90211 -139.204188) (xy 240.847267 -139.194058) (xy 240.794483 -139.176051) (xy 240.744883 -139.15055)
			(xy 240.699525 -139.118099) (xy 240.659376 -139.07939) (xy 240.62529 -139.035247) (xy 240.597994 -138.986612)
			(xy 240.578071 -138.934521) (xy 240.565945 -138.880084) (xy 240.561874 -138.824462) (xy 222.369057 -138.824462)
			(xy 222.335521 -138.844929) (xy 222.284192 -138.866741) (xy 222.230235 -138.880847) (xy 222.174798 -138.886947)
			(xy 222.119064 -138.88491) (xy 222.064221 -138.87478) (xy 222.011437 -138.856773) (xy 221.961837 -138.831272)
			(xy 221.916479 -138.798821) (xy 221.87633 -138.760112) (xy 221.842244 -138.715969) (xy 221.814948 -138.667334)
			(xy 221.795025 -138.615243) (xy 221.782899 -138.560806) (xy 221.778828 -138.505184) (xy 198.85764 -138.505184)
			(xy 198.855845 -138.51738) (xy 198.839777 -138.570787) (xy 198.816105 -138.621284) (xy 198.785332 -138.667797)
			(xy 198.748115 -138.709334) (xy 198.705247 -138.745009) (xy 198.657641 -138.774063) (xy 198.606312 -138.795875)
			(xy 198.552355 -138.809981) (xy 198.496918 -138.816081) (xy 198.441184 -138.814044) (xy 198.386341 -138.803914)
			(xy 198.333557 -138.785907) (xy 198.283957 -138.760406) (xy 198.238599 -138.727955) (xy 198.19845 -138.689246)
			(xy 198.164364 -138.645103) (xy 198.137068 -138.596468) (xy 198.117145 -138.544377) (xy 198.105019 -138.48994)
			(xy 198.100948 -138.434318) (xy 175.49241 -138.434318) (xy 175.92294 -138.864848) (xy 178.039774 -138.864848)
			(xy 178.043845 -138.809226) (xy 178.055971 -138.754789) (xy 178.075894 -138.702698) (xy 178.10319 -138.654063)
			(xy 178.137276 -138.60992) (xy 178.177425 -138.571211) (xy 178.222783 -138.53876) (xy 178.272383 -138.513259)
			(xy 178.325167 -138.495252) (xy 178.38001 -138.485122) (xy 178.435744 -138.483085) (xy 178.491181 -138.489185)
			(xy 178.545138 -138.503291) (xy 178.596467 -138.525103) (xy 178.644073 -138.554157) (xy 178.686941 -138.589832)
			(xy 178.724158 -138.631369) (xy 178.754931 -138.677882) (xy 178.778603 -138.728379) (xy 178.794671 -138.781786)
			(xy 178.802791 -138.836962) (xy 178.8033 -138.864848) (xy 180.329584 -138.864848) (xy 180.333655 -138.809226)
			(xy 180.345781 -138.754789) (xy 180.365704 -138.702698) (xy 180.393 -138.654063) (xy 180.427086 -138.60992)
			(xy 180.467235 -138.571211) (xy 180.512593 -138.53876) (xy 180.562193 -138.513259) (xy 180.614977 -138.495252)
			(xy 180.66982 -138.485122) (xy 180.725554 -138.483085) (xy 180.780991 -138.489185) (xy 180.834948 -138.503291)
			(xy 180.886277 -138.525103) (xy 180.933883 -138.554157) (xy 180.976751 -138.589832) (xy 181.013968 -138.631369)
			(xy 181.044741 -138.677882) (xy 181.068413 -138.728379) (xy 181.084481 -138.781786) (xy 181.092601 -138.836962)
			(xy 181.09311 -138.864848) (xy 181.092601 -138.892734) (xy 181.084481 -138.94791) (xy 181.068413 -139.001317)
			(xy 181.044741 -139.051814) (xy 181.013968 -139.098327) (xy 180.976751 -139.139864) (xy 180.933883 -139.175539)
			(xy 180.886277 -139.204593) (xy 180.834948 -139.226405) (xy 180.780991 -139.240511) (xy 180.725554 -139.246611)
			(xy 180.66982 -139.244574) (xy 180.614977 -139.234444) (xy 180.562193 -139.216437) (xy 180.512593 -139.190936)
			(xy 180.467235 -139.158485) (xy 180.427086 -139.119776) (xy 180.393 -139.075633) (xy 180.365704 -139.026998)
			(xy 180.345781 -138.974907) (xy 180.333655 -138.92047) (xy 180.329584 -138.864848) (xy 178.8033 -138.864848)
			(xy 178.802791 -138.892734) (xy 178.794671 -138.94791) (xy 178.778603 -139.001317) (xy 178.754931 -139.051814)
			(xy 178.724158 -139.098327) (xy 178.686941 -139.139864) (xy 178.644073 -139.175539) (xy 178.596467 -139.204593)
			(xy 178.545138 -139.226405) (xy 178.491181 -139.240511) (xy 178.435744 -139.246611) (xy 178.38001 -139.244574)
			(xy 178.325167 -139.234444) (xy 178.272383 -139.216437) (xy 178.222783 -139.190936) (xy 178.177425 -139.158485)
			(xy 178.137276 -139.119776) (xy 178.10319 -139.075633) (xy 178.075894 -139.026998) (xy 178.055971 -138.974907)
			(xy 178.043845 -138.92047) (xy 178.039774 -138.864848) (xy 175.92294 -138.864848) (xy 176.806622 -139.74853)
			(xy 182.937652 -139.74853) (xy 182.937652 -139.66163) (xy 182.94567 -139.575101) (xy 182.961638 -139.489681)
			(xy 182.985419 -139.406099) (xy 183.016811 -139.325067) (xy 183.055545 -139.247278) (xy 183.101292 -139.173394)
			(xy 183.153661 -139.104047) (xy 183.212205 -139.039827) (xy 183.276425 -138.981283) (xy 183.345772 -138.928914)
			(xy 183.419656 -138.883167) (xy 183.497445 -138.844433) (xy 183.578477 -138.813041) (xy 183.662059 -138.78926)
			(xy 183.747479 -138.773292) (xy 183.834008 -138.765274) (xy 183.920908 -138.765274) (xy 184.007437 -138.773292)
			(xy 184.092857 -138.78926) (xy 184.176439 -138.813041) (xy 184.257471 -138.844433) (xy 184.33526 -138.883167)
			(xy 184.409144 -138.928914) (xy 184.478491 -138.981283) (xy 184.542711 -139.039827) (xy 184.601255 -139.104047)
			(xy 184.653624 -139.173394) (xy 184.699371 -139.247278) (xy 184.738105 -139.325067) (xy 184.769497 -139.406099)
			(xy 184.793278 -139.489681) (xy 184.809246 -139.575101) (xy 184.817264 -139.66163) (xy 184.817766 -139.70508)
			(xy 184.817264 -139.74853) (xy 184.817262 -139.74855) (xy 185.190374 -139.74855) (xy 185.190374 -139.66165)
			(xy 185.198392 -139.57512) (xy 185.21436 -139.489699) (xy 185.238141 -139.406115) (xy 185.269533 -139.325083)
			(xy 185.308267 -139.247292) (xy 185.354014 -139.173408) (xy 185.406383 -139.104059) (xy 185.464927 -139.039838)
			(xy 185.529147 -138.981293) (xy 185.598495 -138.928923) (xy 185.672378 -138.883175) (xy 185.750168 -138.844439)
			(xy 185.8312 -138.813046) (xy 185.914783 -138.789263) (xy 186.000204 -138.773294) (xy 186.086734 -138.765275)
			(xy 186.130184 -138.764772) (xy 187.984384 -138.764772) (xy 188.027834 -138.765298) (xy 188.114364 -138.773314)
			(xy 188.199785 -138.789281) (xy 188.283368 -138.813061) (xy 188.3644 -138.844452) (xy 188.442191 -138.883186)
			(xy 188.516075 -138.928932) (xy 188.585424 -138.981301) (xy 188.649644 -139.039844) (xy 188.708189 -139.104064)
			(xy 188.760559 -139.173412) (xy 188.806306 -139.247295) (xy 188.845041 -139.325085) (xy 188.876434 -139.406117)
			(xy 188.900215 -139.4897) (xy 188.916183 -139.57512) (xy 188.924202 -139.66165) (xy 188.924202 -139.74853)
			(xy 190.307462 -139.74853) (xy 190.307462 -139.66163) (xy 190.31548 -139.575101) (xy 190.331448 -139.489681)
			(xy 190.355229 -139.406099) (xy 190.386621 -139.325067) (xy 190.425355 -139.247278) (xy 190.471102 -139.173394)
			(xy 190.523471 -139.104047) (xy 190.582015 -139.039827) (xy 190.646235 -138.981283) (xy 190.715582 -138.928914)
			(xy 190.789466 -138.883167) (xy 190.867255 -138.844433) (xy 190.948287 -138.813041) (xy 191.031869 -138.78926)
			(xy 191.117289 -138.773292) (xy 191.203818 -138.765274) (xy 191.290718 -138.765274) (xy 191.377247 -138.773292)
			(xy 191.462667 -138.78926) (xy 191.546249 -138.813041) (xy 191.627281 -138.844433) (xy 191.70507 -138.883167)
			(xy 191.778954 -138.928914) (xy 191.848301 -138.981283) (xy 191.912521 -139.039827) (xy 191.971065 -139.104047)
			(xy 192.023434 -139.173394) (xy 192.069181 -139.247278) (xy 192.107915 -139.325067) (xy 192.139307 -139.406099)
			(xy 192.163088 -139.489681) (xy 192.179056 -139.575101) (xy 192.187074 -139.66163) (xy 192.187576 -139.70508)
			(xy 192.187074 -139.74853) (xy 192.180502 -139.819455) (xy 226.681957 -139.819455) (xy 226.681957 -139.764945)
			(xy 226.689716 -139.710991) (xy 226.705074 -139.658689) (xy 226.72772 -139.609106) (xy 226.757192 -139.563251)
			(xy 226.79289 -139.522058) (xy 226.834088 -139.486364) (xy 226.879947 -139.456898) (xy 226.929532 -139.434258)
			(xy 226.981836 -139.418906) (xy 227.035791 -139.411154) (xy 227.063046 -139.410694) (xy 227.092689 -139.411269)
			(xy 227.151264 -139.420427) (xy 227.207719 -139.438533) (xy 227.260695 -139.465149) (xy 227.308918 -139.499637)
			(xy 227.351229 -139.541167) (xy 227.36937 -139.564618) (xy 227.375282 -139.57186) (xy 227.391038 -139.581894)
			(xy 227.400104 -139.584176) (xy 227.476304 -139.599416) (xy 227.494592 -139.596368) (xy 227.50272 -139.591542)
			(xy 227.52495 -139.578748) (xy 227.572123 -139.55861) (xy 227.621571 -139.544982) (xy 227.6724 -139.538108)
			(xy 227.698046 -139.537694) (xy 227.725295 -139.538179) (xy 227.779238 -139.545941) (xy 227.831528 -139.5613)
			(xy 227.881099 -139.583944) (xy 227.926944 -139.613412) (xy 227.968129 -139.649103) (xy 228.003816 -139.690293)
			(xy 228.033278 -139.736141) (xy 228.050772 -139.77445) (xy 230.905799 -139.77445) (xy 230.905799 -139.71995)
			(xy 230.913556 -139.666004) (xy 230.928911 -139.613711) (xy 230.951551 -139.564136) (xy 230.981017 -139.518288)
			(xy 231.016708 -139.477099) (xy 231.057897 -139.44141) (xy 231.103747 -139.411946) (xy 231.153322 -139.389306)
			(xy 231.205616 -139.373953) (xy 231.259562 -139.366198) (xy 231.286812 -139.365736) (xy 231.316272 -139.36632)
			(xy 231.37449 -139.375393) (xy 231.430621 -139.393305) (xy 231.483333 -139.419632) (xy 231.531372 -139.453747)
			(xy 231.573597 -139.494841) (xy 231.609005 -139.541935) (xy 231.623362 -139.567666) (xy 231.630446 -139.580114)
			(xy 231.65038 -139.600669) (xy 231.675236 -139.614882) (xy 231.703061 -139.621637) (xy 231.731667 -139.620401)
			(xy 231.758806 -139.611272) (xy 231.782344 -139.594968) (xy 231.791764 -139.584176) (xy 231.809964 -139.562701)
			(xy 231.851609 -139.52483) (xy 231.898371 -139.493495) (xy 231.949233 -139.469377) (xy 232.003089 -139.453002)
			(xy 232.058767 -139.444726) (xy 232.086912 -139.444222) (xy 232.114165 -139.444649) (xy 232.168116 -139.452407)
			(xy 232.220413 -139.467765) (xy 232.269993 -139.490408) (xy 232.315845 -139.519877) (xy 232.357037 -139.555571)
			(xy 232.39273 -139.596765) (xy 232.422198 -139.642618) (xy 232.44484 -139.692198) (xy 232.452724 -139.71905)
			(xy 233.542076 -139.71905) (xy 233.546147 -139.663428) (xy 233.558273 -139.608991) (xy 233.578196 -139.5569)
			(xy 233.605492 -139.508265) (xy 233.639578 -139.464122) (xy 233.679727 -139.425413) (xy 233.725085 -139.392962)
			(xy 233.774685 -139.367461) (xy 233.827469 -139.349454) (xy 233.882312 -139.339324) (xy 233.938046 -139.337287)
			(xy 233.993483 -139.343387) (xy 234.04744 -139.357493) (xy 234.091942 -139.376404) (xy 238.37595 -139.376404)
			(xy 238.380021 -139.320782) (xy 238.392147 -139.266345) (xy 238.41207 -139.214254) (xy 238.439366 -139.165619)
			(xy 238.473452 -139.121476) (xy 238.513601 -139.082767) (xy 238.558959 -139.050316) (xy 238.608559 -139.024815)
			(xy 238.661343 -139.006808) (xy 238.716186 -138.996678) (xy 238.77192 -138.994641) (xy 238.827357 -139.000741)
			(xy 238.881314 -139.014847) (xy 238.932643 -139.036659) (xy 238.980249 -139.065713) (xy 239.023117 -139.101388)
			(xy 239.060334 -139.142925) (xy 239.091107 -139.189438) (xy 239.114779 -139.239935) (xy 239.130847 -139.293342)
			(xy 239.138967 -139.348518) (xy 239.139476 -139.376404) (xy 239.138967 -139.40429) (xy 239.130847 -139.459466)
			(xy 239.114779 -139.512873) (xy 239.091107 -139.56337) (xy 239.060334 -139.609883) (xy 239.023117 -139.65142)
			(xy 238.980249 -139.687095) (xy 238.932643 -139.716149) (xy 238.881314 -139.737961) (xy 238.827357 -139.752067)
			(xy 238.77192 -139.758167) (xy 238.716186 -139.75613) (xy 238.661343 -139.746) (xy 238.608559 -139.727993)
			(xy 238.558959 -139.702492) (xy 238.513601 -139.670041) (xy 238.473452 -139.631332) (xy 238.439366 -139.587189)
			(xy 238.41207 -139.538554) (xy 238.392147 -139.486463) (xy 238.380021 -139.432026) (xy 238.37595 -139.376404)
			(xy 234.091942 -139.376404) (xy 234.098769 -139.379305) (xy 234.146375 -139.408359) (xy 234.189243 -139.444034)
			(xy 234.22646 -139.485571) (xy 234.257233 -139.532084) (xy 234.280905 -139.582581) (xy 234.296973 -139.635988)
			(xy 234.305093 -139.691164) (xy 234.305602 -139.71905) (xy 234.305093 -139.746936) (xy 234.296973 -139.802112)
			(xy 234.280905 -139.855519) (xy 234.257233 -139.906016) (xy 234.22646 -139.952529) (xy 234.189243 -139.994066)
			(xy 234.146375 -140.029741) (xy 234.098769 -140.058795) (xy 234.04744 -140.080607) (xy 233.993483 -140.094713)
			(xy 233.938046 -140.100813) (xy 233.882312 -140.098776) (xy 233.827469 -140.088646) (xy 233.774685 -140.070639)
			(xy 233.725085 -140.045138) (xy 233.679727 -140.012687) (xy 233.639578 -139.973978) (xy 233.605492 -139.929835)
			(xy 233.578196 -139.8812) (xy 233.558273 -139.829109) (xy 233.546147 -139.774672) (xy 233.542076 -139.71905)
			(xy 232.452724 -139.71905) (xy 232.460195 -139.744496) (xy 232.467952 -139.798447) (xy 232.467952 -139.852953)
			(xy 232.460195 -139.906904) (xy 232.44484 -139.959202) (xy 232.422198 -140.008782) (xy 232.39273 -140.054635)
			(xy 232.357037 -140.095829) (xy 232.315845 -140.131523) (xy 232.269993 -140.160992) (xy 232.220413 -140.183635)
			(xy 232.168116 -140.198993) (xy 232.114165 -140.206751) (xy 232.086912 -140.207238) (xy 232.057452 -140.206648)
			(xy 231.999234 -140.197578) (xy 231.943102 -140.179668) (xy 231.89039 -140.153342) (xy 231.84235 -140.119228)
			(xy 231.800125 -140.078134) (xy 231.764718 -140.031039) (xy 231.750362 -140.005308) (xy 231.743247 -139.992881)
			(xy 231.723318 -139.972332) (xy 231.698468 -139.958122) (xy 231.670651 -139.951367) (xy 231.642051 -139.952598)
			(xy 231.614917 -139.961719) (xy 231.591381 -139.978012) (xy 231.58196 -139.988798) (xy 231.563741 -140.010256)
			(xy 231.522101 -140.04813) (xy 231.475343 -140.079468) (xy 231.424485 -140.103588) (xy 231.370632 -140.119966)
			(xy 231.314956 -140.128247) (xy 231.286812 -140.128752) (xy 231.259562 -140.128202) (xy 231.205616 -140.120447)
			(xy 231.153322 -140.105094) (xy 231.103747 -140.082454) (xy 231.057897 -140.05299) (xy 231.016708 -140.017301)
			(xy 230.981017 -139.976112) (xy 230.951551 -139.930264) (xy 230.928911 -139.880689) (xy 230.913556 -139.828396)
			(xy 230.905799 -139.77445) (xy 228.050772 -139.77445) (xy 228.055916 -139.785715) (xy 228.071269 -139.838007)
			(xy 228.079024 -139.891951) (xy 228.079024 -139.946449) (xy 228.071269 -140.000393) (xy 228.055916 -140.052685)
			(xy 228.033278 -140.102259) (xy 228.003816 -140.148107) (xy 227.968129 -140.189297) (xy 227.926944 -140.224988)
			(xy 227.881099 -140.254456) (xy 227.831528 -140.2771) (xy 227.779238 -140.292459) (xy 227.725295 -140.300221)
			(xy 227.698046 -140.30071) (xy 227.668402 -140.30014) (xy 227.609827 -140.29098) (xy 227.553373 -140.272873)
			(xy 227.500397 -140.246256) (xy 227.452173 -140.211767) (xy 227.409863 -140.170237) (xy 227.391722 -140.146786)
			(xy 227.385811 -140.139542) (xy 227.370054 -140.12951) (xy 227.360988 -140.127228) (xy 227.284788 -140.111988)
			(xy 227.2665 -140.115036) (xy 227.258372 -140.119862) (xy 227.236144 -140.13266) (xy 227.18897 -140.152796)
			(xy 227.139521 -140.166424) (xy 227.088692 -140.173296) (xy 227.063046 -140.17371) (xy 227.035791 -140.173246)
			(xy 226.981836 -140.165494) (xy 226.929532 -140.150142) (xy 226.879947 -140.127502) (xy 226.834088 -140.098036)
			(xy 226.79289 -140.062342) (xy 226.757192 -140.021149) (xy 226.72772 -139.975294) (xy 226.705074 -139.925711)
			(xy 226.689716 -139.873409) (xy 226.681957 -139.819455) (xy 192.180502 -139.819455) (xy 192.179056 -139.835059)
			(xy 192.163088 -139.920479) (xy 192.139307 -140.004061) (xy 192.107915 -140.085093) (xy 192.069181 -140.162882)
			(xy 192.023434 -140.236766) (xy 191.971065 -140.306113) (xy 191.912521 -140.370333) (xy 191.848301 -140.428877)
			(xy 191.778954 -140.481246) (xy 191.70507 -140.526993) (xy 191.689194 -140.534898) (xy 197.155814 -140.534898)
			(xy 197.159885 -140.479276) (xy 197.172011 -140.424839) (xy 197.191934 -140.372748) (xy 197.21923 -140.324113)
			(xy 197.253316 -140.27997) (xy 197.293465 -140.241261) (xy 197.338823 -140.20881) (xy 197.388423 -140.183309)
			(xy 197.441207 -140.165302) (xy 197.49605 -140.155172) (xy 197.551784 -140.153135) (xy 197.607221 -140.159235)
			(xy 197.661178 -140.173341) (xy 197.712507 -140.195153) (xy 197.760113 -140.224207) (xy 197.802981 -140.259882)
			(xy 197.840198 -140.301419) (xy 197.870971 -140.347932) (xy 197.894643 -140.398429) (xy 197.910711 -140.451836)
			(xy 197.915982 -140.487654) (xy 201.801982 -140.487654) (xy 201.806053 -140.432032) (xy 201.818179 -140.377595)
			(xy 201.838102 -140.325504) (xy 201.865398 -140.276869) (xy 201.899484 -140.232726) (xy 201.939633 -140.194017)
			(xy 201.984991 -140.161566) (xy 202.034591 -140.136065) (xy 202.087375 -140.118058) (xy 202.142218 -140.107928)
			(xy 202.197952 -140.105891) (xy 202.253389 -140.111991) (xy 202.307346 -140.126097) (xy 202.358675 -140.147909)
			(xy 202.406281 -140.176963) (xy 202.449149 -140.212638) (xy 202.486366 -140.254175) (xy 202.517139 -140.300688)
			(xy 202.540811 -140.351185) (xy 202.556879 -140.404592) (xy 202.564999 -140.459768) (xy 202.565508 -140.487654)
			(xy 202.564999 -140.51554) (xy 202.556879 -140.570716) (xy 202.540811 -140.624123) (xy 202.517139 -140.67462)
			(xy 202.486366 -140.721133) (xy 202.449149 -140.76267) (xy 202.406281 -140.798345) (xy 202.358675 -140.827399)
			(xy 202.307346 -140.849211) (xy 202.253389 -140.863317) (xy 202.197952 -140.869417) (xy 202.142218 -140.86738)
			(xy 202.087375 -140.85725) (xy 202.034591 -140.839243) (xy 201.984991 -140.813742) (xy 201.939633 -140.781291)
			(xy 201.899484 -140.742582) (xy 201.865398 -140.698439) (xy 201.838102 -140.649804) (xy 201.818179 -140.597713)
			(xy 201.806053 -140.543276) (xy 201.801982 -140.487654) (xy 197.915982 -140.487654) (xy 197.918831 -140.507012)
			(xy 197.91934 -140.534898) (xy 197.918831 -140.562784) (xy 197.910711 -140.61796) (xy 197.894643 -140.671367)
			(xy 197.870971 -140.721864) (xy 197.840198 -140.768377) (xy 197.802981 -140.809914) (xy 197.760113 -140.845589)
			(xy 197.712507 -140.874643) (xy 197.661178 -140.896455) (xy 197.607221 -140.910561) (xy 197.551784 -140.916661)
			(xy 197.49605 -140.914624) (xy 197.441207 -140.904494) (xy 197.388423 -140.886487) (xy 197.338823 -140.860986)
			(xy 197.293465 -140.828535) (xy 197.253316 -140.789826) (xy 197.21923 -140.745683) (xy 197.191934 -140.697048)
			(xy 197.172011 -140.644957) (xy 197.159885 -140.59052) (xy 197.155814 -140.534898) (xy 191.689194 -140.534898)
			(xy 191.627281 -140.565727) (xy 191.546249 -140.597119) (xy 191.462667 -140.6209) (xy 191.377247 -140.636868)
			(xy 191.290718 -140.644886) (xy 191.203818 -140.644886) (xy 191.117289 -140.636868) (xy 191.031869 -140.6209)
			(xy 190.948287 -140.597119) (xy 190.867255 -140.565727) (xy 190.789466 -140.526993) (xy 190.715582 -140.481246)
			(xy 190.646235 -140.428877) (xy 190.582015 -140.370333) (xy 190.523471 -140.306113) (xy 190.471102 -140.236766)
			(xy 190.425355 -140.162882) (xy 190.386621 -140.085093) (xy 190.355229 -140.004061) (xy 190.331448 -139.920479)
			(xy 190.31548 -139.835059) (xy 190.307462 -139.74853) (xy 188.924202 -139.74853) (xy 188.924202 -139.74855)
			(xy 188.916183 -139.83508) (xy 188.900215 -139.9205) (xy 188.876434 -140.004083) (xy 188.845041 -140.085115)
			(xy 188.806306 -140.162905) (xy 188.760559 -140.236788) (xy 188.708189 -140.306136) (xy 188.649644 -140.370356)
			(xy 188.585424 -140.428899) (xy 188.516075 -140.481268) (xy 188.442191 -140.527014) (xy 188.3644 -140.565748)
			(xy 188.283368 -140.597139) (xy 188.199785 -140.620919) (xy 188.114364 -140.636886) (xy 188.027834 -140.644902)
			(xy 187.984384 -140.645388) (xy 186.130184 -140.645388) (xy 186.086734 -140.644925) (xy 186.000204 -140.636906)
			(xy 185.914783 -140.620937) (xy 185.8312 -140.597154) (xy 185.750168 -140.565761) (xy 185.672378 -140.527025)
			(xy 185.598495 -140.481277) (xy 185.529147 -140.428907) (xy 185.464927 -140.370362) (xy 185.406383 -140.306141)
			(xy 185.354014 -140.236792) (xy 185.308267 -140.162908) (xy 185.269533 -140.085117) (xy 185.238141 -140.004085)
			(xy 185.21436 -139.920501) (xy 185.198392 -139.83508) (xy 185.190374 -139.74855) (xy 184.817262 -139.74855)
			(xy 184.809246 -139.835059) (xy 184.793278 -139.920479) (xy 184.769497 -140.004061) (xy 184.738105 -140.085093)
			(xy 184.699371 -140.162882) (xy 184.653624 -140.236766) (xy 184.601255 -140.306113) (xy 184.542711 -140.370333)
			(xy 184.478491 -140.428877) (xy 184.409144 -140.481246) (xy 184.33526 -140.526993) (xy 184.257471 -140.565727)
			(xy 184.176439 -140.597119) (xy 184.092857 -140.6209) (xy 184.007437 -140.636868) (xy 183.920908 -140.644886)
			(xy 183.834008 -140.644886) (xy 183.747479 -140.636868) (xy 183.662059 -140.6209) (xy 183.578477 -140.597119)
			(xy 183.497445 -140.565727) (xy 183.419656 -140.526993) (xy 183.345772 -140.481246) (xy 183.276425 -140.428877)
			(xy 183.212205 -140.370333) (xy 183.153661 -140.306113) (xy 183.101292 -140.236766) (xy 183.055545 -140.162882)
			(xy 183.016811 -140.085093) (xy 182.985419 -140.004061) (xy 182.961638 -139.920479) (xy 182.94567 -139.835059)
			(xy 182.937652 -139.74853) (xy 176.806622 -139.74853) (xy 178.01336 -140.955268) (xy 222.72701 -140.955268)
			(xy 222.731081 -140.899646) (xy 222.743207 -140.845209) (xy 222.76313 -140.793118) (xy 222.790426 -140.744483)
			(xy 222.824512 -140.70034) (xy 222.864661 -140.661631) (xy 222.910019 -140.62918) (xy 222.959619 -140.603679)
			(xy 223.012403 -140.585672) (xy 223.067246 -140.575542) (xy 223.12298 -140.573505) (xy 223.178417 -140.579605)
			(xy 223.232374 -140.593711) (xy 223.283703 -140.615523) (xy 223.331309 -140.644577) (xy 223.374177 -140.680252)
			(xy 223.397787 -140.706602) (xy 224.801428 -140.706602) (xy 224.805499 -140.65098) (xy 224.817625 -140.596543)
			(xy 224.837548 -140.544452) (xy 224.864844 -140.495817) (xy 224.89893 -140.451674) (xy 224.939079 -140.412965)
			(xy 224.984437 -140.380514) (xy 225.034037 -140.355013) (xy 225.086821 -140.337006) (xy 225.141664 -140.326876)
			(xy 225.197398 -140.324839) (xy 225.252835 -140.330939) (xy 225.306792 -140.345045) (xy 225.358121 -140.366857)
			(xy 225.399981 -140.392404) (xy 238.37595 -140.392404) (xy 238.380021 -140.336782) (xy 238.392147 -140.282345)
			(xy 238.41207 -140.230254) (xy 238.439366 -140.181619) (xy 238.473452 -140.137476) (xy 238.513601 -140.098767)
			(xy 238.558959 -140.066316) (xy 238.608559 -140.040815) (xy 238.661343 -140.022808) (xy 238.716186 -140.012678)
			(xy 238.77192 -140.010641) (xy 238.827357 -140.016741) (xy 238.881314 -140.030847) (xy 238.932643 -140.052659)
			(xy 238.980249 -140.081713) (xy 239.023117 -140.117388) (xy 239.060334 -140.158925) (xy 239.091107 -140.205438)
			(xy 239.114779 -140.255935) (xy 239.130847 -140.309342) (xy 239.138967 -140.364518) (xy 239.139476 -140.392404)
			(xy 240.567716 -140.392404) (xy 240.571787 -140.336782) (xy 240.583913 -140.282345) (xy 240.603836 -140.230254)
			(xy 240.631132 -140.181619) (xy 240.665218 -140.137476) (xy 240.705367 -140.098767) (xy 240.750725 -140.066316)
			(xy 240.800325 -140.040815) (xy 240.853109 -140.022808) (xy 240.907952 -140.012678) (xy 240.963686 -140.010641)
			(xy 241.019123 -140.016741) (xy 241.07308 -140.030847) (xy 241.124409 -140.052659) (xy 241.172015 -140.081713)
			(xy 241.214883 -140.117388) (xy 241.2521 -140.158925) (xy 241.282873 -140.205438) (xy 241.306545 -140.255935)
			(xy 241.322613 -140.309342) (xy 241.330733 -140.364518) (xy 241.331242 -140.392404) (xy 241.330733 -140.42029)
			(xy 241.322613 -140.475466) (xy 241.306545 -140.528873) (xy 241.282873 -140.57937) (xy 241.2521 -140.625883)
			(xy 241.214883 -140.66742) (xy 241.172015 -140.703095) (xy 241.124409 -140.732149) (xy 241.07308 -140.753961)
			(xy 241.019123 -140.768067) (xy 240.963686 -140.774167) (xy 240.907952 -140.77213) (xy 240.853109 -140.762)
			(xy 240.800325 -140.743993) (xy 240.750725 -140.718492) (xy 240.705367 -140.686041) (xy 240.665218 -140.647332)
			(xy 240.631132 -140.603189) (xy 240.603836 -140.554554) (xy 240.583913 -140.502463) (xy 240.571787 -140.448026)
			(xy 240.567716 -140.392404) (xy 239.139476 -140.392404) (xy 239.138967 -140.42029) (xy 239.130847 -140.475466)
			(xy 239.114779 -140.528873) (xy 239.091107 -140.57937) (xy 239.060334 -140.625883) (xy 239.023117 -140.66742)
			(xy 238.980249 -140.703095) (xy 238.932643 -140.732149) (xy 238.881314 -140.753961) (xy 238.827357 -140.768067)
			(xy 238.77192 -140.774167) (xy 238.716186 -140.77213) (xy 238.661343 -140.762) (xy 238.608559 -140.743993)
			(xy 238.558959 -140.718492) (xy 238.513601 -140.686041) (xy 238.473452 -140.647332) (xy 238.439366 -140.603189)
			(xy 238.41207 -140.554554) (xy 238.392147 -140.502463) (xy 238.380021 -140.448026) (xy 238.37595 -140.392404)
			(xy 225.399981 -140.392404) (xy 225.405727 -140.395911) (xy 225.448595 -140.431586) (xy 225.485812 -140.473123)
			(xy 225.516585 -140.519636) (xy 225.540257 -140.570133) (xy 225.556325 -140.62354) (xy 225.564445 -140.678716)
			(xy 225.564954 -140.706602) (xy 225.564445 -140.734488) (xy 225.556325 -140.789664) (xy 225.540257 -140.843071)
			(xy 225.516585 -140.893568) (xy 225.49761 -140.922248) (xy 227.749606 -140.922248) (xy 227.753677 -140.866626)
			(xy 227.765803 -140.812189) (xy 227.785726 -140.760098) (xy 227.813022 -140.711463) (xy 227.847108 -140.66732)
			(xy 227.887257 -140.628611) (xy 227.932615 -140.59616) (xy 227.982215 -140.570659) (xy 228.034999 -140.552652)
			(xy 228.089842 -140.542522) (xy 228.145576 -140.540485) (xy 228.201013 -140.546585) (xy 228.25497 -140.560691)
			(xy 228.306299 -140.582503) (xy 228.353905 -140.611557) (xy 228.396773 -140.647232) (xy 228.43399 -140.688769)
			(xy 228.464763 -140.735282) (xy 228.488435 -140.785779) (xy 228.504503 -140.839186) (xy 228.512623 -140.894362)
			(xy 228.513132 -140.922248) (xy 228.512623 -140.950134) (xy 228.504503 -141.00531) (xy 228.488435 -141.058717)
			(xy 228.464763 -141.109214) (xy 228.453686 -141.125956) (xy 230.59593 -141.125956) (xy 230.600001 -141.070334)
			(xy 230.612127 -141.015897) (xy 230.63205 -140.963806) (xy 230.659346 -140.915171) (xy 230.693432 -140.871028)
			(xy 230.733581 -140.832319) (xy 230.778939 -140.799868) (xy 230.828539 -140.774367) (xy 230.881323 -140.75636)
			(xy 230.936166 -140.74623) (xy 230.9919 -140.744193) (xy 231.047337 -140.750293) (xy 231.101294 -140.764399)
			(xy 231.152623 -140.786211) (xy 231.200229 -140.815265) (xy 231.243097 -140.85094) (xy 231.280314 -140.892477)
			(xy 231.311087 -140.93899) (xy 231.334759 -140.989487) (xy 231.350827 -141.042894) (xy 231.351365 -141.046551)
			(xy 241.177054 -141.046551) (xy 241.177054 -140.992049) (xy 241.18481 -140.938101) (xy 241.200164 -140.885806)
			(xy 241.222804 -140.836228) (xy 241.252269 -140.790376) (xy 241.287959 -140.749184) (xy 241.329147 -140.71349)
			(xy 241.374996 -140.684021) (xy 241.424572 -140.661377) (xy 241.476865 -140.646017) (xy 241.530813 -140.638256)
			(xy 241.558064 -140.637768) (xy 241.584379 -140.638203) (xy 241.636508 -140.645446) (xy 241.687151 -140.659772)
			(xy 241.73535 -140.680911) (xy 241.780193 -140.708462) (xy 241.820832 -140.741905) (xy 241.838988 -140.760958)
			(xy 241.846518 -140.76835) (xy 241.865791 -140.776881) (xy 241.876326 -140.777468) (xy 241.951002 -140.777468)
			(xy 241.961555 -140.776963) (xy 241.98085 -140.768412) (xy 241.98834 -140.760958) (xy 242.006475 -140.741882)
			(xy 242.04711 -140.708428) (xy 242.091955 -140.680873) (xy 242.14016 -140.659738) (xy 242.19081 -140.645425)
			(xy 242.242947 -140.638204) (xy 242.269264 -140.637768) (xy 242.296517 -140.638277) (xy 242.350468 -140.646029)
			(xy 242.402767 -140.661381) (xy 242.452349 -140.68402) (xy 242.498203 -140.713485) (xy 242.539398 -140.749177)
			(xy 242.575093 -140.790368) (xy 242.604563 -140.83622) (xy 242.627206 -140.885799) (xy 242.642563 -140.938097)
			(xy 242.650321 -140.992047) (xy 242.650321 -141.046551) (xy 242.955054 -141.046551) (xy 242.955054 -140.992049)
			(xy 242.96281 -140.938101) (xy 242.978164 -140.885806) (xy 243.000804 -140.836228) (xy 243.030269 -140.790376)
			(xy 243.065959 -140.749184) (xy 243.107147 -140.71349) (xy 243.152996 -140.684021) (xy 243.202572 -140.661377)
			(xy 243.254865 -140.646017) (xy 243.308813 -140.638256) (xy 243.336064 -140.637768) (xy 243.362379 -140.638203)
			(xy 243.414508 -140.645446) (xy 243.465151 -140.659772) (xy 243.51335 -140.680911) (xy 243.558193 -140.708462)
			(xy 243.598832 -140.741905) (xy 243.616988 -140.760958) (xy 243.624518 -140.76835) (xy 243.643791 -140.776881)
			(xy 243.654326 -140.777468) (xy 243.729002 -140.777468) (xy 243.739555 -140.776963) (xy 243.75885 -140.768412)
			(xy 243.76634 -140.760958) (xy 243.784475 -140.741882) (xy 243.82511 -140.708428) (xy 243.869955 -140.680873)
			(xy 243.91816 -140.659738) (xy 243.96881 -140.645425) (xy 244.020947 -140.638204) (xy 244.047264 -140.637768)
			(xy 244.074517 -140.638277) (xy 244.128468 -140.646029) (xy 244.180767 -140.661381) (xy 244.230349 -140.68402)
			(xy 244.276203 -140.713485) (xy 244.317398 -140.749177) (xy 244.353093 -140.790368) (xy 244.382563 -140.83622)
			(xy 244.405206 -140.885799) (xy 244.420563 -140.938097) (xy 244.428321 -140.992047) (xy 244.428321 -141.046553)
			(xy 244.420563 -141.100503) (xy 244.405206 -141.152801) (xy 244.382563 -141.20238) (xy 244.353093 -141.248232)
			(xy 244.317398 -141.289423) (xy 244.276203 -141.325115) (xy 244.230349 -141.35458) (xy 244.180767 -141.377219)
			(xy 244.128468 -141.392571) (xy 244.074517 -141.400323) (xy 244.047264 -141.400784) (xy 244.020949 -141.400346)
			(xy 243.968819 -141.393106) (xy 243.918176 -141.378781) (xy 243.869977 -141.357643) (xy 243.825134 -141.330092)
			(xy 243.784496 -141.296648) (xy 243.76634 -141.277594) (xy 243.758806 -141.270207) (xy 243.739535 -141.261675)
			(xy 243.729002 -141.261084) (xy 243.654326 -141.261084) (xy 243.643777 -141.261619) (xy 243.624482 -141.270151)
			(xy 243.616988 -141.277594) (xy 243.59883 -141.296647) (xy 243.558201 -141.330105) (xy 243.513361 -141.357664)
			(xy 243.465161 -141.378803) (xy 243.414514 -141.393121) (xy 243.36238 -141.400346) (xy 243.336064 -141.400784)
			(xy 243.308813 -141.400344) (xy 243.254865 -141.392583) (xy 243.202572 -141.377223) (xy 243.152996 -141.354579)
			(xy 243.107147 -141.32511) (xy 243.065959 -141.289416) (xy 243.030269 -141.248224) (xy 243.000804 -141.202372)
			(xy 242.978164 -141.152794) (xy 242.96281 -141.100499) (xy 242.955054 -141.046551) (xy 242.650321 -141.046551)
			(xy 242.650321 -141.046553) (xy 242.642563 -141.100503) (xy 242.627206 -141.152801) (xy 242.604563 -141.20238)
			(xy 242.575093 -141.248232) (xy 242.539398 -141.289423) (xy 242.498203 -141.325115) (xy 242.452349 -141.35458)
			(xy 242.402767 -141.377219) (xy 242.350468 -141.392571) (xy 242.296517 -141.400323) (xy 242.269264 -141.400784)
			(xy 242.242949 -141.400346) (xy 242.190819 -141.393106) (xy 242.140176 -141.378781) (xy 242.091977 -141.357643)
			(xy 242.047134 -141.330092) (xy 242.006496 -141.296648) (xy 241.98834 -141.277594) (xy 241.980806 -141.270207)
			(xy 241.961535 -141.261675) (xy 241.951002 -141.261084) (xy 241.876326 -141.261084) (xy 241.865777 -141.261619)
			(xy 241.846482 -141.270151) (xy 241.838988 -141.277594) (xy 241.82083 -141.296647) (xy 241.780201 -141.330105)
			(xy 241.735361 -141.357664) (xy 241.687161 -141.378803) (xy 241.636514 -141.393121) (xy 241.58438 -141.400346)
			(xy 241.558064 -141.400784) (xy 241.530813 -141.400344) (xy 241.476865 -141.392583) (xy 241.424572 -141.377223)
			(xy 241.374996 -141.354579) (xy 241.329147 -141.32511) (xy 241.287959 -141.289416) (xy 241.252269 -141.248224)
			(xy 241.222804 -141.202372) (xy 241.200164 -141.152794) (xy 241.18481 -141.100499) (xy 241.177054 -141.046551)
			(xy 231.351365 -141.046551) (xy 231.358947 -141.09807) (xy 231.359456 -141.125956) (xy 231.358947 -141.153842)
			(xy 231.350827 -141.209018) (xy 231.334759 -141.262425) (xy 231.311087 -141.312922) (xy 231.280314 -141.359435)
			(xy 231.243097 -141.400972) (xy 231.200229 -141.436647) (xy 231.152623 -141.465701) (xy 231.101294 -141.487513)
			(xy 231.047337 -141.501619) (xy 230.9919 -141.507719) (xy 230.936166 -141.505682) (xy 230.881323 -141.495552)
			(xy 230.828539 -141.477545) (xy 230.778939 -141.452044) (xy 230.733581 -141.419593) (xy 230.693432 -141.380884)
			(xy 230.659346 -141.336741) (xy 230.63205 -141.288106) (xy 230.612127 -141.236015) (xy 230.600001 -141.181578)
			(xy 230.59593 -141.125956) (xy 228.453686 -141.125956) (xy 228.43399 -141.155727) (xy 228.396773 -141.197264)
			(xy 228.353905 -141.232939) (xy 228.306299 -141.261993) (xy 228.25497 -141.283805) (xy 228.201013 -141.297911)
			(xy 228.145576 -141.304011) (xy 228.089842 -141.301974) (xy 228.034999 -141.291844) (xy 227.982215 -141.273837)
			(xy 227.932615 -141.248336) (xy 227.887257 -141.215885) (xy 227.847108 -141.177176) (xy 227.813022 -141.133033)
			(xy 227.785726 -141.084398) (xy 227.765803 -141.032307) (xy 227.753677 -140.97787) (xy 227.749606 -140.922248)
			(xy 225.49761 -140.922248) (xy 225.485812 -140.940081) (xy 225.448595 -140.981618) (xy 225.405727 -141.017293)
			(xy 225.358121 -141.046347) (xy 225.306792 -141.068159) (xy 225.252835 -141.082265) (xy 225.197398 -141.088365)
			(xy 225.141664 -141.086328) (xy 225.086821 -141.076198) (xy 225.034037 -141.058191) (xy 224.984437 -141.03269)
			(xy 224.939079 -141.000239) (xy 224.89893 -140.96153) (xy 224.864844 -140.917387) (xy 224.837548 -140.868752)
			(xy 224.817625 -140.816661) (xy 224.805499 -140.762224) (xy 224.801428 -140.706602) (xy 223.397787 -140.706602)
			(xy 223.411394 -140.721789) (xy 223.442167 -140.768302) (xy 223.465839 -140.818799) (xy 223.481907 -140.872206)
			(xy 223.490027 -140.927382) (xy 223.490536 -140.955268) (xy 223.490027 -140.983154) (xy 223.481907 -141.03833)
			(xy 223.465839 -141.091737) (xy 223.442167 -141.142234) (xy 223.411394 -141.188747) (xy 223.374177 -141.230284)
			(xy 223.331309 -141.265959) (xy 223.283703 -141.295013) (xy 223.232374 -141.316825) (xy 223.178417 -141.330931)
			(xy 223.12298 -141.337031) (xy 223.067246 -141.334994) (xy 223.012403 -141.324864) (xy 222.959619 -141.306857)
			(xy 222.910019 -141.281356) (xy 222.864661 -141.248905) (xy 222.824512 -141.210196) (xy 222.790426 -141.166053)
			(xy 222.76313 -141.117418) (xy 222.743207 -141.065327) (xy 222.731081 -141.01089) (xy 222.72701 -140.955268)
			(xy 178.01336 -140.955268) (xy 180.600858 -143.542766) (xy 180.606431 -143.547938) (xy 180.619861 -143.555047)
			(xy 180.627274 -143.556736) (xy 180.646578 -143.556736) (xy 180.64861 -143.556482) (xy 180.648864 -143.556482)
			(xy 180.650388 -143.556228) (xy 180.656484 -143.555466) (xy 180.658008 -143.555466) (xy 180.659278 -143.555212)
			(xy 180.66258 -143.554958) (xy 180.693314 -143.553942) (xy 180.693822 -143.553942) (xy 180.722134 -143.554445)
			(xy 180.778191 -143.562441) (xy 180.832566 -143.578241) (xy 180.884178 -143.601533) (xy 180.932001 -143.631854)
			(xy 180.975083 -143.668599) (xy 181.012569 -143.711038) (xy 181.043713 -143.758329) (xy 181.067895 -143.80953)
			(xy 181.084635 -143.863623) (xy 181.089554 -143.891508) (xy 181.089554 -143.892016) (xy 181.091332 -143.901922)
			(xy 181.091332 -143.90243) (xy 181.096666 -143.911066) (xy 181.099181 -143.914823) (xy 181.105317 -143.921462)
			(xy 181.108858 -143.924274) (xy 181.140608 -143.946372) (xy 181.140862 -143.946626) (xy 181.147466 -143.951198)
			(xy 181.17312 -143.968724) (xy 181.180761 -143.973045) (xy 181.197897 -143.976796) (xy 181.206648 -143.97609)
			(xy 181.210204 -143.975328) (xy 181.212236 -143.97482) (xy 181.212998 -143.974566) (xy 181.216808 -143.973804)
			(xy 181.239376 -143.969701) (xy 181.285056 -143.965501) (xy 181.307994 -143.965422) (xy 181.308756 -143.965422)
			(xy 181.323668 -143.965717) (xy 181.35341 -143.968006) (xy 181.368192 -143.969994) (xy 181.369208 -143.970248)
			(xy 181.371748 -143.970502) (xy 181.372002 -143.970502) (xy 181.386226 -143.97228) (xy 181.386734 -143.97228)
			(xy 181.41188 -143.975582) (xy 181.413658 -143.975836) (xy 181.419052 -143.9749) (xy 181.429302 -143.971062)
			(xy 181.433978 -143.968216) (xy 181.437788 -143.965676) (xy 181.485286 -143.932656) (xy 181.497986 -143.923766)
			(xy 181.50136 -143.921039) (xy 181.507231 -143.914654) (xy 181.50967 -143.911066) (xy 181.515004 -143.90243)
			(xy 181.516782 -143.891762) (xy 181.516782 -143.891508) (xy 181.521744 -143.863631) (xy 181.538482 -143.80954)
			(xy 181.56266 -143.758341) (xy 181.593799 -143.711051) (xy 181.63128 -143.66861) (xy 181.674357 -143.631863)
			(xy 181.722174 -143.601539) (xy 181.77378 -143.578242) (xy 181.828151 -143.562435) (xy 181.884204 -143.554432)
			(xy 181.912514 -143.553942) (xy 181.913022 -143.553942) (xy 181.923944 -143.554196) (xy 181.925722 -143.554196)
			(xy 181.952913 -143.555553) (xy 182.00658 -143.564697) (xy 182.05852 -143.58101) (xy 182.107778 -143.604193)
			(xy 182.153452 -143.633821) (xy 182.174388 -143.651224) (xy 182.180992 -143.656812) (xy 182.207408 -143.667226)
			(xy 182.211234 -143.668422) (xy 182.219148 -143.669697) (xy 182.223156 -143.669766) (xy 182.23738 -143.669766)
			(xy 182.241385 -143.669662) (xy 182.249294 -143.668389) (xy 182.253128 -143.667226) (xy 182.279544 -143.656812)
			(xy 182.286148 -143.651224) (xy 182.308071 -143.633029) (xy 182.356087 -143.602367) (xy 182.407956 -143.578803)
			(xy 182.462636 -143.562811) (xy 182.519029 -143.554714) (xy 182.547514 -143.554196) (xy 182.547768 -143.554196)
			(xy 182.564739 -143.554345) (xy 182.598566 -143.557146) (xy 182.615332 -143.559784) (xy 182.624222 -143.560546)
			(xy 182.632435 -143.560188) (xy 182.647979 -143.554865) (xy 182.654702 -143.550132) (xy 182.682642 -143.526764)
			(xy 182.689028 -143.520523) (xy 182.697464 -143.5048) (xy 182.699152 -143.49603) (xy 182.69966 -143.488918)
			(xy 182.69966 -142.620492) (xy 182.699406 -142.616682) (xy 182.699406 -142.616174) (xy 182.698784 -142.610634)
			(xy 182.695447 -142.599999) (xy 182.692802 -142.595092) (xy 182.687468 -142.587726) (xy 182.68315 -142.583408)
			(xy 182.669434 -142.571978) (xy 182.668926 -142.57147) (xy 182.6641 -142.567406) (xy 182.655972 -142.560548)
			(xy 182.652416 -142.557754) (xy 182.644172 -142.552812) (xy 182.625371 -142.548891) (xy 182.61584 -142.550134)
			(xy 182.615586 -142.550134) (xy 182.611776 -142.550896) (xy 182.596072 -142.553271) (xy 182.564411 -142.555813)
			(xy 182.54853 -142.555976) (xy 182.547768 -142.555976) (xy 182.51912 -142.555463) (xy 182.462409 -142.547305)
			(xy 182.407436 -142.53116) (xy 182.35532 -142.507355) (xy 182.307122 -142.476377) (xy 182.263823 -142.438855)
			(xy 182.226304 -142.395553) (xy 182.195329 -142.347352) (xy 182.171529 -142.295234) (xy 182.155388 -142.24026)
			(xy 182.147235 -142.183548) (xy 182.147235 -142.126252) (xy 182.155388 -142.06954) (xy 182.171529 -142.014566)
			(xy 182.195329 -141.962448) (xy 182.226304 -141.914247) (xy 182.263823 -141.870945) (xy 182.307122 -141.833423)
			(xy 182.35532 -141.802445) (xy 182.407436 -141.77864) (xy 182.462409 -141.762495) (xy 182.51912 -141.754337)
			(xy 182.547768 -141.753844) (xy 182.548022 -141.753844) (xy 182.576334 -141.754347) (xy 182.632391 -141.762343)
			(xy 182.686766 -141.778144) (xy 182.738378 -141.801436) (xy 182.7862 -141.831756) (xy 182.829283 -141.868501)
			(xy 182.866768 -141.910941) (xy 182.897912 -141.958231) (xy 182.922094 -142.009432) (xy 182.938834 -142.063525)
			(xy 182.943754 -142.09141) (xy 182.943754 -142.091664) (xy 182.945532 -142.102332) (xy 182.950866 -142.110968)
			(xy 182.953052 -142.114236) (xy 182.958288 -142.120101) (xy 182.96128 -142.122652) (xy 182.994554 -142.146274)
			(xy 182.995062 -142.146274) (xy 183.028082 -142.169388) (xy 183.035579 -142.173309) (xy 183.052172 -142.176547)
			(xy 183.060594 -142.175738) (xy 183.064912 -142.174976) (xy 183.070246 -142.17396) (xy 183.07558 -142.172944)
			(xy 183.077612 -142.172436) (xy 183.079644 -142.172182) (xy 183.080152 -142.172182) (xy 183.095138 -142.169896)
			(xy 183.096154 -142.169896) (xy 183.104536 -142.168626) (xy 183.105044 -142.168626) (xy 183.1086 -142.168118)
			(xy 183.109616 -142.168118) (xy 183.116982 -142.167356) (xy 183.126888 -142.166594) (xy 183.128412 -142.166594)
			(xy 183.15305 -142.165832) (xy 183.157368 -142.165832) (xy 183.157622 -142.165832) (xy 183.158384 -142.165832)
			(xy 183.16194 -142.165832) (xy 183.168798 -142.165832) (xy 183.17845 -142.166086) (xy 183.178958 -142.166086)
			(xy 183.200548 -142.16761) (xy 183.202834 -142.167864) (xy 183.203342 -142.167864) (xy 183.208168 -142.168372)
			(xy 183.209692 -142.168626) (xy 183.221884 -142.17015) (xy 183.234053 -142.171931) (xy 183.258196 -142.176632)
			(xy 183.270144 -142.179548) (xy 183.27243 -142.180056) (xy 183.273446 -142.18031) (xy 183.27624 -142.181072)
			(xy 183.285638 -142.179294) (xy 183.290769 -142.178276) (xy 183.300499 -142.174435) (xy 183.304942 -142.171674)
			(xy 183.363362 -142.132812) (xy 183.369458 -142.128748) (xy 183.373227 -142.125936) (xy 183.379738 -142.119155)
			(xy 183.382412 -142.115286) (xy 183.388 -142.106904) (xy 183.389778 -142.095474) (xy 183.39444 -142.068879)
			(xy 183.410278 -142.017261) (xy 183.433239 -141.968393) (xy 183.462862 -141.923252) (xy 183.498556 -141.88274)
			(xy 183.539607 -141.847668) (xy 183.585194 -141.818736) (xy 183.634406 -141.796524) (xy 183.68626 -141.781474)
			(xy 183.739717 -141.773889) (xy 183.766714 -141.773402) (xy 183.793964 -141.773889) (xy 183.84791 -141.781647)
			(xy 183.900202 -141.797004) (xy 183.949777 -141.819646) (xy 183.995625 -141.849113) (xy 184.036813 -141.884804)
			(xy 184.072502 -141.925994) (xy 184.101966 -141.971844) (xy 184.124605 -142.02142) (xy 184.139958 -142.073714)
			(xy 184.147712 -142.12766) (xy 184.148222 -142.15491) (xy 185.365896 -142.15491) (xy 185.369967 -142.099288)
			(xy 185.382093 -142.044851) (xy 185.402016 -141.99276) (xy 185.429312 -141.944125) (xy 185.463398 -141.899982)
			(xy 185.503547 -141.861273) (xy 185.548905 -141.828822) (xy 185.598505 -141.803321) (xy 185.651289 -141.785314)
			(xy 185.706132 -141.775184) (xy 185.761866 -141.773147) (xy 185.817303 -141.779247) (xy 185.87126 -141.793353)
			(xy 185.922589 -141.815165) (xy 185.970195 -141.844219) (xy 186.013063 -141.879894) (xy 186.05028 -141.921431)
			(xy 186.081053 -141.967944) (xy 186.104725 -142.018441) (xy 186.120793 -142.071848) (xy 186.128913 -142.127024)
			(xy 186.129422 -142.15491) (xy 187.98489 -142.15491) (xy 187.988961 -142.099288) (xy 188.001087 -142.044851)
			(xy 188.02101 -141.99276) (xy 188.048306 -141.944125) (xy 188.082392 -141.899982) (xy 188.122541 -141.861273)
			(xy 188.167899 -141.828822) (xy 188.217499 -141.803321) (xy 188.270283 -141.785314) (xy 188.325126 -141.775184)
			(xy 188.38086 -141.773147) (xy 188.436297 -141.779247) (xy 188.490254 -141.793353) (xy 188.541583 -141.815165)
			(xy 188.589189 -141.844219) (xy 188.632057 -141.879894) (xy 188.669274 -141.921431) (xy 188.700047 -141.967944)
			(xy 188.723719 -142.018441) (xy 188.739787 -142.071848) (xy 188.747907 -142.127024) (xy 188.748416 -142.15491)
			(xy 189.96609 -142.15491) (xy 189.970161 -142.099288) (xy 189.982287 -142.044851) (xy 190.00221 -141.99276)
			(xy 190.029506 -141.944125) (xy 190.063592 -141.899982) (xy 190.103741 -141.861273) (xy 190.149099 -141.828822)
			(xy 190.198699 -141.803321) (xy 190.251483 -141.785314) (xy 190.306326 -141.775184) (xy 190.36206 -141.773147)
			(xy 190.417497 -141.779247) (xy 190.471454 -141.793353) (xy 190.522783 -141.815165) (xy 190.570389 -141.844219)
			(xy 190.613257 -141.879894) (xy 190.640735 -141.910562) (xy 219.859604 -141.910562) (xy 219.863675 -141.85494)
			(xy 219.875801 -141.800503) (xy 219.895724 -141.748412) (xy 219.92302 -141.699777) (xy 219.957106 -141.655634)
			(xy 219.997255 -141.616925) (xy 220.042613 -141.584474) (xy 220.092213 -141.558973) (xy 220.144997 -141.540966)
			(xy 220.19984 -141.530836) (xy 220.255574 -141.528799) (xy 220.311011 -141.534899) (xy 220.364968 -141.549005)
			(xy 220.41485 -141.570202) (xy 223.887028 -141.570202) (xy 223.891099 -141.51458) (xy 223.903225 -141.460143)
			(xy 223.923148 -141.408052) (xy 223.950444 -141.359417) (xy 223.98453 -141.315274) (xy 224.024679 -141.276565)
			(xy 224.070037 -141.244114) (xy 224.119637 -141.218613) (xy 224.172421 -141.200606) (xy 224.227264 -141.190476)
			(xy 224.282998 -141.188439) (xy 224.338435 -141.194539) (xy 224.392392 -141.208645) (xy 224.443721 -141.230457)
			(xy 224.491327 -141.259511) (xy 224.534195 -141.295186) (xy 224.571412 -141.336723) (xy 224.602185 -141.383236)
			(xy 224.625857 -141.433733) (xy 224.641925 -141.48714) (xy 224.650045 -141.542316) (xy 224.650554 -141.570202)
			(xy 224.650045 -141.598088) (xy 224.641925 -141.653264) (xy 224.625857 -141.706671) (xy 224.602185 -141.757168)
			(xy 224.571412 -141.803681) (xy 224.534195 -141.845218) (xy 224.491327 -141.880893) (xy 224.443721 -141.909947)
			(xy 224.392392 -141.931759) (xy 224.338435 -141.945865) (xy 224.282998 -141.951965) (xy 224.227264 -141.949928)
			(xy 224.172421 -141.939798) (xy 224.119637 -141.921791) (xy 224.070037 -141.89629) (xy 224.024679 -141.863839)
			(xy 223.98453 -141.82513) (xy 223.950444 -141.780987) (xy 223.923148 -141.732352) (xy 223.903225 -141.680261)
			(xy 223.891099 -141.625824) (xy 223.887028 -141.570202) (xy 220.41485 -141.570202) (xy 220.416297 -141.570817)
			(xy 220.463903 -141.599871) (xy 220.506771 -141.635546) (xy 220.543988 -141.677083) (xy 220.574761 -141.723596)
			(xy 220.598433 -141.774093) (xy 220.614501 -141.8275) (xy 220.622621 -141.882676) (xy 220.62313 -141.910562)
			(xy 220.622621 -141.938448) (xy 220.614501 -141.993624) (xy 220.598433 -142.047031) (xy 220.574761 -142.097528)
			(xy 220.543988 -142.144041) (xy 220.506771 -142.185578) (xy 220.463903 -142.221253) (xy 220.425278 -142.244826)
			(xy 228.06736 -142.244826) (xy 228.071431 -142.189204) (xy 228.083557 -142.134767) (xy 228.10348 -142.082676)
			(xy 228.130776 -142.034041) (xy 228.164862 -141.989898) (xy 228.205011 -141.951189) (xy 228.250369 -141.918738)
			(xy 228.299969 -141.893237) (xy 228.352753 -141.87523) (xy 228.407596 -141.8651) (xy 228.46333 -141.863063)
			(xy 228.518767 -141.869163) (xy 228.572724 -141.883269) (xy 228.624053 -141.905081) (xy 228.671659 -141.934135)
			(xy 228.714527 -141.96981) (xy 228.751744 -142.011347) (xy 228.782517 -142.05786) (xy 228.806189 -142.108357)
			(xy 228.822257 -142.161764) (xy 228.830377 -142.21694) (xy 228.830886 -142.244826) (xy 228.830399 -142.271496)
			(xy 230.464866 -142.271496) (xy 230.468937 -142.215874) (xy 230.481063 -142.161437) (xy 230.500986 -142.109346)
			(xy 230.528282 -142.060711) (xy 230.562368 -142.016568) (xy 230.602517 -141.977859) (xy 230.647875 -141.945408)
			(xy 230.697475 -141.919907) (xy 230.750259 -141.9019) (xy 230.805102 -141.89177) (xy 230.860836 -141.889733)
			(xy 230.916273 -141.895833) (xy 230.97023 -141.909939) (xy 231.021559 -141.931751) (xy 231.069165 -141.960805)
			(xy 231.112033 -141.99648) (xy 231.14925 -142.038017) (xy 231.180023 -142.08453) (xy 231.203695 -142.135027)
			(xy 231.219763 -142.188434) (xy 231.227883 -142.24361) (xy 231.228392 -142.271496) (xy 231.227883 -142.299382)
			(xy 231.219763 -142.354558) (xy 231.203695 -142.407965) (xy 231.180023 -142.458462) (xy 231.14925 -142.504975)
			(xy 231.112033 -142.546512) (xy 231.069165 -142.582187) (xy 231.021559 -142.611241) (xy 231.006364 -142.617698)
			(xy 231.737154 -142.617698) (xy 231.737696 -142.588533) (xy 231.746549 -142.53088) (xy 231.764078 -142.475247)
			(xy 231.789875 -142.422932) (xy 231.823338 -142.375156) (xy 231.863686 -142.333034) (xy 231.909979 -142.297547)
			(xy 231.961135 -142.269524) (xy 231.98836 -142.25905) (xy 232.001822 -142.254224) (xy 232.019348 -142.23238)
			(xy 232.033064 -142.128748) (xy 232.033874 -142.119523) (xy 232.029638 -142.10151) (xy 232.019302 -142.086161)
			(xy 232.011982 -142.080488) (xy 231.990832 -142.065134) (xy 231.952553 -142.029549) (xy 231.919491 -141.989071)
			(xy 231.892266 -141.944457) (xy 231.871387 -141.896544) (xy 231.857246 -141.846229) (xy 231.850107 -141.794454)
			(xy 231.849676 -141.768322) (xy 231.850162 -141.741071) (xy 231.857918 -141.687123) (xy 231.873273 -141.634828)
			(xy 231.895915 -141.585251) (xy 231.925381 -141.539401) (xy 231.961072 -141.49821) (xy 232.002263 -141.462519)
			(xy 232.048113 -141.433053) (xy 232.09769 -141.410411) (xy 232.149985 -141.395056) (xy 232.203933 -141.3873)
			(xy 232.258435 -141.3873) (xy 232.312383 -141.395056) (xy 232.364678 -141.410411) (xy 232.414255 -141.433053)
			(xy 232.460105 -141.462519) (xy 232.501296 -141.49821) (xy 232.536987 -141.539401) (xy 232.566453 -141.585251)
			(xy 232.589095 -141.634828) (xy 232.60445 -141.687123) (xy 232.612206 -141.741071) (xy 232.612692 -141.768322)
			(xy 232.612137 -141.797486) (xy 232.603283 -141.855137) (xy 232.585753 -141.910768) (xy 232.559957 -141.963081)
			(xy 232.526496 -142.010856) (xy 232.486151 -142.052979) (xy 232.439862 -142.088468) (xy 232.388709 -142.116494)
			(xy 232.361486 -142.12697) (xy 232.348024 -142.131796) (xy 232.330498 -142.15364) (xy 232.316782 -142.257272)
			(xy 232.315937 -142.266497) (xy 232.320184 -142.284515) (xy 232.330536 -142.299863) (xy 232.337864 -142.305532)
			(xy 232.358827 -142.320744) (xy 232.396815 -142.355952) (xy 232.429685 -142.39598) (xy 232.456833 -142.44009)
			(xy 232.477757 -142.48747) (xy 232.492074 -142.537246) (xy 232.499518 -142.588503) (xy 232.50017 -142.614396)
			(xy 232.50017 -142.61465) (xy 232.500857 -142.625238) (xy 232.507953 -142.640812) (xy 234.22305 -142.640812)
			(xy 234.227121 -142.58519) (xy 234.239247 -142.530753) (xy 234.25917 -142.478662) (xy 234.286466 -142.430027)
			(xy 234.320552 -142.385884) (xy 234.360701 -142.347175) (xy 234.406059 -142.314724) (xy 234.455659 -142.289223)
			(xy 234.508443 -142.271216) (xy 234.563286 -142.261086) (xy 234.61902 -142.259049) (xy 234.674457 -142.265149)
			(xy 234.728414 -142.279255) (xy 234.779743 -142.301067) (xy 234.827349 -142.330121) (xy 234.870217 -142.365796)
			(xy 234.907434 -142.407333) (xy 234.938207 -142.453846) (xy 234.961879 -142.504343) (xy 234.977947 -142.55775)
			(xy 234.986067 -142.612926) (xy 234.986576 -142.640812) (xy 236.25124 -142.640812) (xy 236.255311 -142.58519)
			(xy 236.267437 -142.530753) (xy 236.28736 -142.478662) (xy 236.314656 -142.430027) (xy 236.348742 -142.385884)
			(xy 236.388891 -142.347175) (xy 236.434249 -142.314724) (xy 236.483849 -142.289223) (xy 236.536633 -142.271216)
			(xy 236.591476 -142.261086) (xy 236.64721 -142.259049) (xy 236.702647 -142.265149) (xy 236.756604 -142.279255)
			(xy 236.807933 -142.301067) (xy 236.855539 -142.330121) (xy 236.898407 -142.365796) (xy 236.935624 -142.407333)
			(xy 236.966397 -142.453846) (xy 236.990069 -142.504343) (xy 237.006137 -142.55775) (xy 237.014257 -142.612926)
			(xy 237.014766 -142.640812) (xy 237.014257 -142.668698) (xy 237.006137 -142.723874) (xy 236.990069 -142.777281)
			(xy 236.966397 -142.827778) (xy 236.935624 -142.874291) (xy 236.898407 -142.915828) (xy 236.855539 -142.951503)
			(xy 236.807933 -142.980557) (xy 236.756604 -143.002369) (xy 236.702647 -143.016475) (xy 236.64721 -143.022575)
			(xy 236.591476 -143.020538) (xy 236.536633 -143.010408) (xy 236.483849 -142.992401) (xy 236.434249 -142.9669)
			(xy 236.388891 -142.934449) (xy 236.348742 -142.89574) (xy 236.314656 -142.851597) (xy 236.28736 -142.802962)
			(xy 236.267437 -142.750871) (xy 236.255311 -142.696434) (xy 236.25124 -142.640812) (xy 234.986576 -142.640812)
			(xy 234.986067 -142.668698) (xy 234.977947 -142.723874) (xy 234.961879 -142.777281) (xy 234.938207 -142.827778)
			(xy 234.907434 -142.874291) (xy 234.870217 -142.915828) (xy 234.827349 -142.951503) (xy 234.779743 -142.980557)
			(xy 234.728414 -143.002369) (xy 234.674457 -143.016475) (xy 234.61902 -143.022575) (xy 234.563286 -143.020538)
			(xy 234.508443 -143.010408) (xy 234.455659 -142.992401) (xy 234.406059 -142.9669) (xy 234.360701 -142.934449)
			(xy 234.320552 -142.89574) (xy 234.286466 -142.851597) (xy 234.25917 -142.802962) (xy 234.239247 -142.750871)
			(xy 234.227121 -142.696434) (xy 234.22305 -142.640812) (xy 232.507953 -142.640812) (xy 232.509645 -142.644525)
			(xy 232.517188 -142.651988) (xy 232.581196 -142.709138) (xy 232.601516 -142.715742) (xy 232.612184 -142.714726)
			(xy 232.651046 -142.712694) (xy 232.678295 -142.713179) (xy 232.732238 -142.720941) (xy 232.784528 -142.7363)
			(xy 232.834099 -142.758944) (xy 232.879944 -142.788412) (xy 232.921129 -142.824103) (xy 232.956816 -142.865293)
			(xy 232.986278 -142.911141) (xy 233.008916 -142.960715) (xy 233.024269 -143.013007) (xy 233.032024 -143.066951)
			(xy 233.032024 -143.078551) (xy 241.177054 -143.078551) (xy 241.177054 -143.024049) (xy 241.18481 -142.970101)
			(xy 241.200164 -142.917806) (xy 241.222804 -142.868228) (xy 241.252269 -142.822376) (xy 241.287959 -142.781184)
			(xy 241.329147 -142.74549) (xy 241.374996 -142.716021) (xy 241.424572 -142.693377) (xy 241.476865 -142.678017)
			(xy 241.530813 -142.670256) (xy 241.558064 -142.669768) (xy 241.584379 -142.670203) (xy 241.636508 -142.677446)
			(xy 241.687151 -142.691772) (xy 241.73535 -142.712911) (xy 241.780193 -142.740462) (xy 241.820832 -142.773905)
			(xy 241.838988 -142.792958) (xy 241.846518 -142.80035) (xy 241.865791 -142.808881) (xy 241.876326 -142.809468)
			(xy 241.951002 -142.809468) (xy 241.961555 -142.808963) (xy 241.98085 -142.800412) (xy 241.98834 -142.792958)
			(xy 242.006475 -142.773882) (xy 242.04711 -142.740428) (xy 242.091955 -142.712873) (xy 242.14016 -142.691738)
			(xy 242.19081 -142.677425) (xy 242.242947 -142.670204) (xy 242.269264 -142.669768) (xy 242.296517 -142.670277)
			(xy 242.350468 -142.678029) (xy 242.402767 -142.693381) (xy 242.452349 -142.71602) (xy 242.498203 -142.745485)
			(xy 242.539398 -142.781177) (xy 242.575093 -142.822368) (xy 242.604563 -142.86822) (xy 242.627206 -142.917799)
			(xy 242.642563 -142.970097) (xy 242.650321 -143.024047) (xy 242.650321 -143.078551) (xy 242.955054 -143.078551)
			(xy 242.955054 -143.024049) (xy 242.96281 -142.970101) (xy 242.978164 -142.917806) (xy 243.000804 -142.868228)
			(xy 243.030269 -142.822376) (xy 243.065959 -142.781184) (xy 243.107147 -142.74549) (xy 243.152996 -142.716021)
			(xy 243.202572 -142.693377) (xy 243.254865 -142.678017) (xy 243.308813 -142.670256) (xy 243.336064 -142.669768)
			(xy 243.362379 -142.670203) (xy 243.414508 -142.677446) (xy 243.465151 -142.691772) (xy 243.51335 -142.712911)
			(xy 243.558193 -142.740462) (xy 243.598832 -142.773905) (xy 243.616988 -142.792958) (xy 243.624518 -142.80035)
			(xy 243.643791 -142.808881) (xy 243.654326 -142.809468) (xy 243.729002 -142.809468) (xy 243.739555 -142.808963)
			(xy 243.75885 -142.800412) (xy 243.76634 -142.792958) (xy 243.784475 -142.773882) (xy 243.82511 -142.740428)
			(xy 243.869955 -142.712873) (xy 243.91816 -142.691738) (xy 243.96881 -142.677425) (xy 244.020947 -142.670204)
			(xy 244.047264 -142.669768) (xy 244.074517 -142.670277) (xy 244.128468 -142.678029) (xy 244.180767 -142.693381)
			(xy 244.230349 -142.71602) (xy 244.276203 -142.745485) (xy 244.317398 -142.781177) (xy 244.353093 -142.822368)
			(xy 244.382563 -142.86822) (xy 244.405206 -142.917799) (xy 244.420563 -142.970097) (xy 244.428321 -143.024047)
			(xy 244.428321 -143.078553) (xy 244.420563 -143.132503) (xy 244.405206 -143.184801) (xy 244.382563 -143.23438)
			(xy 244.353093 -143.280232) (xy 244.317398 -143.321423) (xy 244.276203 -143.357115) (xy 244.230349 -143.38658)
			(xy 244.180767 -143.409219) (xy 244.128468 -143.424571) (xy 244.074517 -143.432323) (xy 244.047264 -143.432784)
			(xy 244.020949 -143.432346) (xy 243.968819 -143.425106) (xy 243.918176 -143.410781) (xy 243.869977 -143.389643)
			(xy 243.825134 -143.362092) (xy 243.784496 -143.328648) (xy 243.76634 -143.309594) (xy 243.758806 -143.302207)
			(xy 243.739535 -143.293675) (xy 243.729002 -143.293084) (xy 243.654326 -143.293084) (xy 243.643777 -143.293619)
			(xy 243.624482 -143.302151) (xy 243.616988 -143.309594) (xy 243.59883 -143.328647) (xy 243.558201 -143.362105)
			(xy 243.513361 -143.389664) (xy 243.465161 -143.410803) (xy 243.414514 -143.425121) (xy 243.36238 -143.432346)
			(xy 243.336064 -143.432784) (xy 243.308813 -143.432344) (xy 243.254865 -143.424583) (xy 243.202572 -143.409223)
			(xy 243.152996 -143.386579) (xy 243.107147 -143.35711) (xy 243.065959 -143.321416) (xy 243.030269 -143.280224)
			(xy 243.000804 -143.234372) (xy 242.978164 -143.184794) (xy 242.96281 -143.132499) (xy 242.955054 -143.078551)
			(xy 242.650321 -143.078551) (xy 242.650321 -143.078553) (xy 242.642563 -143.132503) (xy 242.627206 -143.184801)
			(xy 242.604563 -143.23438) (xy 242.575093 -143.280232) (xy 242.539398 -143.321423) (xy 242.498203 -143.357115)
			(xy 242.452349 -143.38658) (xy 242.402767 -143.409219) (xy 242.350468 -143.424571) (xy 242.296517 -143.432323)
			(xy 242.269264 -143.432784) (xy 242.242949 -143.432346) (xy 242.190819 -143.425106) (xy 242.140176 -143.410781)
			(xy 242.091977 -143.389643) (xy 242.047134 -143.362092) (xy 242.006496 -143.328648) (xy 241.98834 -143.309594)
			(xy 241.980806 -143.302207) (xy 241.961535 -143.293675) (xy 241.951002 -143.293084) (xy 241.876326 -143.293084)
			(xy 241.865777 -143.293619) (xy 241.846482 -143.302151) (xy 241.838988 -143.309594) (xy 241.82083 -143.328647)
			(xy 241.780201 -143.362105) (xy 241.735361 -143.389664) (xy 241.687161 -143.410803) (xy 241.636514 -143.425121)
			(xy 241.58438 -143.432346) (xy 241.558064 -143.432784) (xy 241.530813 -143.432344) (xy 241.476865 -143.424583)
			(xy 241.424572 -143.409223) (xy 241.374996 -143.386579) (xy 241.329147 -143.35711) (xy 241.287959 -143.321416)
			(xy 241.252269 -143.280224) (xy 241.222804 -143.234372) (xy 241.200164 -143.184794) (xy 241.18481 -143.132499)
			(xy 241.177054 -143.078551) (xy 233.032024 -143.078551) (xy 233.032024 -143.121449) (xy 233.024269 -143.175393)
			(xy 233.008916 -143.227685) (xy 232.986278 -143.277259) (xy 232.956816 -143.323107) (xy 232.921129 -143.364297)
			(xy 232.879944 -143.399988) (xy 232.834099 -143.429456) (xy 232.784528 -143.4521) (xy 232.732238 -143.467459)
			(xy 232.678295 -143.475221) (xy 232.651046 -143.47571) (xy 232.623945 -143.475204) (xy 232.570288 -143.467538)
			(xy 232.518256 -143.452355) (xy 232.468897 -143.429959) (xy 232.423205 -143.400803) (xy 232.3821 -143.365472)
			(xy 232.34641 -143.324679) (xy 232.316853 -143.279245) (xy 232.294025 -143.230084) (xy 232.278385 -143.178188)
			(xy 232.270248 -143.1246) (xy 232.269538 -143.097504) (xy 232.269538 -143.09725) (xy 232.268848 -143.086662)
			(xy 232.260062 -143.067375) (xy 232.25252 -143.059912) (xy 232.188512 -143.002762) (xy 232.168192 -142.996158)
			(xy 232.157524 -142.997174) (xy 232.118662 -142.999206) (xy 232.09141 -142.998758) (xy 232.037461 -142.990996)
			(xy 231.985165 -142.975636) (xy 231.935588 -142.95299) (xy 231.889737 -142.92352) (xy 231.848547 -142.887824)
			(xy 231.812856 -142.846631) (xy 231.783391 -142.800777) (xy 231.76075 -142.751197) (xy 231.745396 -142.6989)
			(xy 231.73764 -142.64495) (xy 231.737154 -142.617698) (xy 231.006364 -142.617698) (xy 230.97023 -142.633053)
			(xy 230.916273 -142.647159) (xy 230.860836 -142.653259) (xy 230.805102 -142.651222) (xy 230.750259 -142.641092)
			(xy 230.697475 -142.623085) (xy 230.647875 -142.597584) (xy 230.602517 -142.565133) (xy 230.562368 -142.526424)
			(xy 230.528282 -142.482281) (xy 230.500986 -142.433646) (xy 230.481063 -142.381555) (xy 230.468937 -142.327118)
			(xy 230.464866 -142.271496) (xy 228.830399 -142.271496) (xy 228.830377 -142.272712) (xy 228.822257 -142.327888)
			(xy 228.806189 -142.381295) (xy 228.782517 -142.431792) (xy 228.751744 -142.478305) (xy 228.714527 -142.519842)
			(xy 228.671659 -142.555517) (xy 228.624053 -142.584571) (xy 228.572724 -142.606383) (xy 228.518767 -142.620489)
			(xy 228.46333 -142.626589) (xy 228.407596 -142.624552) (xy 228.352753 -142.614422) (xy 228.299969 -142.596415)
			(xy 228.250369 -142.570914) (xy 228.205011 -142.538463) (xy 228.164862 -142.499754) (xy 228.130776 -142.455611)
			(xy 228.10348 -142.406976) (xy 228.083557 -142.354885) (xy 228.071431 -142.300448) (xy 228.06736 -142.244826)
			(xy 220.425278 -142.244826) (xy 220.416297 -142.250307) (xy 220.364968 -142.272119) (xy 220.311011 -142.286225)
			(xy 220.255574 -142.292325) (xy 220.19984 -142.290288) (xy 220.144997 -142.280158) (xy 220.092213 -142.262151)
			(xy 220.042613 -142.23665) (xy 219.997255 -142.204199) (xy 219.957106 -142.16549) (xy 219.92302 -142.121347)
			(xy 219.895724 -142.072712) (xy 219.875801 -142.020621) (xy 219.863675 -141.966184) (xy 219.859604 -141.910562)
			(xy 190.640735 -141.910562) (xy 190.650474 -141.921431) (xy 190.681247 -141.967944) (xy 190.704919 -142.018441)
			(xy 190.720987 -142.071848) (xy 190.729107 -142.127024) (xy 190.729616 -142.15491) (xy 190.729107 -142.182796)
			(xy 190.720987 -142.237972) (xy 190.704919 -142.291379) (xy 190.681247 -142.341876) (xy 190.650474 -142.388389)
			(xy 190.613257 -142.429926) (xy 190.593035 -142.446755) (xy 196.597675 -142.446755) (xy 196.597675 -142.389445)
			(xy 196.605831 -142.332719) (xy 196.621978 -142.277731) (xy 196.645787 -142.2256) (xy 196.676773 -142.177389)
			(xy 196.714304 -142.134079) (xy 196.757618 -142.096551) (xy 196.805832 -142.06557) (xy 196.857964 -142.041766)
			(xy 196.912954 -142.025624) (xy 196.969681 -142.017472) (xy 196.998336 -142.016988) (xy 197.025717 -142.017432)
			(xy 197.079968 -142.024904) (xy 197.132697 -142.039691) (xy 197.182923 -142.061517) (xy 197.229711 -142.089976)
			(xy 197.27219 -142.124538) (xy 197.309569 -142.16456) (xy 197.325742 -142.18666) (xy 197.331299 -142.193926)
			(xy 197.346412 -142.204208) (xy 197.355206 -142.206726) (xy 197.385178 -142.214092) (xy 197.39413 -142.215823)
			(xy 197.412216 -142.213617) (xy 197.420484 -142.209774) (xy 197.445087 -142.197391) (xy 197.496612 -142.17792)
			(xy 197.5501 -142.16477) (xy 197.60478 -142.15813) (xy 197.63232 -142.157704) (xy 197.659861 -142.158134)
			(xy 197.714541 -142.164768) (xy 197.768031 -142.177914) (xy 197.819557 -142.197383) (xy 197.844156 -142.209774)
			(xy 197.852424 -142.213629) (xy 197.870514 -142.215859) (xy 197.879462 -142.214092) (xy 197.909434 -142.206726)
			(xy 197.918222 -142.204202) (xy 197.93332 -142.193907) (xy 197.938898 -142.18666) (xy 197.955082 -142.164567)
			(xy 197.99245 -142.124533) (xy 198.034923 -142.089962) (xy 198.081709 -142.061499) (xy 198.131936 -142.039674)
			(xy 198.184668 -142.024894) (xy 198.238922 -142.017434) (xy 198.266304 -142.016988) (xy 198.294949 -142.017591)
			(xy 198.351655 -142.025745) (xy 198.406624 -142.041886) (xy 198.458736 -142.065685) (xy 198.506931 -142.096658)
			(xy 198.550227 -142.134175) (xy 198.587744 -142.177472) (xy 198.618717 -142.225667) (xy 198.642516 -142.27778)
			(xy 198.658656 -142.332749) (xy 198.666809 -142.389455) (xy 198.666809 -142.446745) (xy 198.658656 -142.503451)
			(xy 198.642516 -142.55842) (xy 198.618717 -142.610533) (xy 198.587744 -142.658728) (xy 198.550227 -142.702025)
			(xy 198.506931 -142.739542) (xy 198.458736 -142.770515) (xy 198.406624 -142.794314) (xy 198.351655 -142.810455)
			(xy 198.294949 -142.818609) (xy 198.266304 -142.81912) (xy 198.251386 -142.818945) (xy 198.221637 -142.81666)
			(xy 198.206868 -142.814548) (xy 198.195692 -142.81277) (xy 198.17461 -142.818866) (xy 198.107554 -142.876524)
			(xy 198.099569 -142.8841) (xy 198.090496 -142.904133) (xy 198.090028 -142.915132) (xy 198.090028 -142.926562)
			(xy 219.859604 -142.926562) (xy 219.863675 -142.87094) (xy 219.875801 -142.816503) (xy 219.895724 -142.764412)
			(xy 219.92302 -142.715777) (xy 219.957106 -142.671634) (xy 219.997255 -142.632925) (xy 220.042613 -142.600474)
			(xy 220.092213 -142.574973) (xy 220.144997 -142.556966) (xy 220.19984 -142.546836) (xy 220.255574 -142.544799)
			(xy 220.311011 -142.550899) (xy 220.364968 -142.565005) (xy 220.416297 -142.586817) (xy 220.463903 -142.615871)
			(xy 220.506771 -142.651546) (xy 220.543988 -142.693083) (xy 220.574761 -142.739596) (xy 220.598433 -142.790093)
			(xy 220.614501 -142.8435) (xy 220.622621 -142.898676) (xy 220.62313 -142.926562) (xy 220.622621 -142.954448)
			(xy 220.614501 -143.009624) (xy 220.598433 -143.063031) (xy 220.574761 -143.113528) (xy 220.543988 -143.160041)
			(xy 220.506771 -143.201578) (xy 220.463903 -143.237253) (xy 220.416297 -143.266307) (xy 220.364968 -143.288119)
			(xy 220.311011 -143.302225) (xy 220.255574 -143.308325) (xy 220.19984 -143.306288) (xy 220.144997 -143.296158)
			(xy 220.092213 -143.278151) (xy 220.042613 -143.25265) (xy 219.997255 -143.220199) (xy 219.957106 -143.18149)
			(xy 219.92302 -143.137347) (xy 219.895724 -143.088712) (xy 219.875801 -143.036621) (xy 219.863675 -142.982184)
			(xy 219.859604 -142.926562) (xy 198.090028 -142.926562) (xy 198.090028 -143.1798) (xy 198.090525 -143.19079)
			(xy 198.099605 -143.210803) (xy 198.107554 -143.218408) (xy 198.17461 -143.276066) (xy 198.195692 -143.282162)
			(xy 198.206868 -143.280384) (xy 198.221637 -143.278277) (xy 198.251386 -143.275988) (xy 198.266304 -143.275812)
			(xy 198.29495 -143.276367) (xy 198.35166 -143.284522) (xy 198.406632 -143.300663) (xy 198.458748 -143.324464)
			(xy 198.506945 -143.355439) (xy 198.550244 -143.392958) (xy 198.587763 -143.436258) (xy 198.609526 -143.470122)
			(xy 198.923402 -143.470122) (xy 198.923888 -143.442871) (xy 198.931644 -143.388923) (xy 198.946999 -143.336628)
			(xy 198.969641 -143.287051) (xy 198.999107 -143.241201) (xy 199.034798 -143.20001) (xy 199.075989 -143.164319)
			(xy 199.121839 -143.134853) (xy 199.171416 -143.112211) (xy 199.223711 -143.096856) (xy 199.277659 -143.0891)
			(xy 199.332161 -143.0891) (xy 199.386109 -143.096856) (xy 199.438404 -143.112211) (xy 199.487981 -143.134853)
			(xy 199.533831 -143.164319) (xy 199.575022 -143.20001) (xy 199.610713 -143.241201) (xy 199.640179 -143.287051)
			(xy 199.662821 -143.336628) (xy 199.678176 -143.388923) (xy 199.685932 -143.442871) (xy 199.686418 -143.470122)
			(xy 199.685955 -143.496923) (xy 199.678445 -143.549996) (xy 199.663577 -143.601494) (xy 199.641643 -143.650402)
			(xy 199.627744 -143.673322) (xy 199.620886 -143.684244) (xy 199.619362 -143.709644) (xy 199.66559 -143.810482)
			(xy 199.686164 -143.825976) (xy 199.699118 -143.827754) (xy 199.725796 -143.832161) (xy 199.777731 -143.847208)
			(xy 199.827173 -143.869098) (xy 199.873225 -143.897434) (xy 199.915052 -143.931701) (xy 199.951894 -143.971279)
			(xy 199.96785 -143.993108) (xy 199.973394 -144.000385) (xy 199.988517 -144.01066) (xy 199.997314 -144.013174)
			(xy 200.027286 -144.02054) (xy 200.036237 -144.02228) (xy 200.054325 -144.02007) (xy 200.062592 -144.016222)
			(xy 200.087192 -144.003832) (xy 200.138718 -143.984364) (xy 200.192207 -143.971216) (xy 200.246887 -143.964578)
			(xy 200.274428 -143.964152) (xy 200.301968 -143.964584) (xy 200.356649 -143.971219) (xy 200.410138 -143.984364)
			(xy 200.461665 -144.003831) (xy 200.486264 -144.016222) (xy 200.49453 -144.020082) (xy 200.512621 -144.022308)
			(xy 200.52157 -144.02054) (xy 200.551542 -144.013174) (xy 200.560326 -144.010638) (xy 200.575425 -144.00035)
			(xy 200.581006 -143.993108) (xy 200.59717 -143.971) (xy 200.634543 -143.930969) (xy 200.67702 -143.8964)
			(xy 200.72381 -143.86794) (xy 200.77404 -143.846117) (xy 200.826774 -143.831339) (xy 200.881029 -143.823882)
			(xy 200.908412 -143.823436) (xy 200.93706 -143.823944) (xy 200.993772 -143.8321) (xy 201.048747 -143.848243)
			(xy 201.100864 -143.872046) (xy 201.149064 -143.903023) (xy 201.192364 -143.940544) (xy 201.194113 -143.942562)
			(xy 219.859604 -143.942562) (xy 219.863675 -143.88694) (xy 219.875801 -143.832503) (xy 219.895724 -143.780412)
			(xy 219.92302 -143.731777) (xy 219.957106 -143.687634) (xy 219.997255 -143.648925) (xy 220.042613 -143.616474)
			(xy 220.092213 -143.590973) (xy 220.144997 -143.572966) (xy 220.19984 -143.562836) (xy 220.255574 -143.560799)
			(xy 220.311011 -143.566899) (xy 220.364968 -143.581005) (xy 220.416297 -143.602817) (xy 220.463903 -143.631871)
			(xy 220.506771 -143.667546) (xy 220.543988 -143.709083) (xy 220.574761 -143.755596) (xy 220.598433 -143.806093)
			(xy 220.614501 -143.8595) (xy 220.622621 -143.914676) (xy 220.62313 -143.942562) (xy 220.623084 -143.945102)
			(xy 225.0219 -143.945102) (xy 225.025971 -143.88948) (xy 225.038097 -143.835043) (xy 225.05802 -143.782952)
			(xy 225.085316 -143.734317) (xy 225.119402 -143.690174) (xy 225.159551 -143.651465) (xy 225.204909 -143.619014)
			(xy 225.254509 -143.593513) (xy 225.307293 -143.575506) (xy 225.362136 -143.565376) (xy 225.41787 -143.563339)
			(xy 225.473307 -143.569439) (xy 225.527264 -143.583545) (xy 225.578593 -143.605357) (xy 225.626199 -143.634411)
			(xy 225.653117 -143.656812) (xy 236.25124 -143.656812) (xy 236.255311 -143.60119) (xy 236.267437 -143.546753)
			(xy 236.28736 -143.494662) (xy 236.314656 -143.446027) (xy 236.348742 -143.401884) (xy 236.388891 -143.363175)
			(xy 236.434249 -143.330724) (xy 236.483849 -143.305223) (xy 236.536633 -143.287216) (xy 236.591476 -143.277086)
			(xy 236.64721 -143.275049) (xy 236.702647 -143.281149) (xy 236.756604 -143.295255) (xy 236.807933 -143.317067)
			(xy 236.855539 -143.346121) (xy 236.898407 -143.381796) (xy 236.935624 -143.423333) (xy 236.966397 -143.469846)
			(xy 236.990069 -143.520343) (xy 237.006137 -143.57375) (xy 237.014257 -143.628926) (xy 237.014766 -143.656812)
			(xy 237.014257 -143.684698) (xy 237.006137 -143.739874) (xy 236.990069 -143.793281) (xy 236.966397 -143.843778)
			(xy 236.935624 -143.890291) (xy 236.898407 -143.931828) (xy 236.856819 -143.966438) (xy 251.664216 -143.966438)
			(xy 251.664626 -143.940462) (xy 251.671676 -143.88899) (xy 251.685652 -143.838952) (xy 251.706293 -143.791276)
			(xy 251.733218 -143.746845) (xy 251.765928 -143.706483) (xy 251.803816 -143.670936) (xy 251.824744 -143.655542)
			(xy 251.834235 -143.64791) (xy 251.84538 -143.626298) (xy 251.84608 -143.61414) (xy 251.84608 -143.531336)
			(xy 251.845388 -143.519174) (xy 251.834248 -143.497553) (xy 251.824744 -143.489934) (xy 251.803825 -143.474531)
			(xy 251.765949 -143.438978) (xy 251.733248 -143.398614) (xy 251.70633 -143.354184) (xy 251.685691 -143.306511)
			(xy 251.671714 -143.256479) (xy 251.664658 -143.205012) (xy 251.664216 -143.179038) (xy 251.664724 -143.150299)
			(xy 251.673354 -143.093472) (xy 251.690409 -143.038582) (xy 251.715503 -142.98687) (xy 251.748069 -142.939507)
			(xy 251.76734 -142.91818) (xy 251.773944 -142.911322) (xy 251.781056 -142.893288) (xy 251.781056 -142.804388)
			(xy 251.773944 -142.786354) (xy 251.76734 -142.779496) (xy 251.748106 -142.758137) (xy 251.715538 -142.71078)
			(xy 251.690444 -142.659074) (xy 251.67339 -142.604188) (xy 251.664763 -142.547365) (xy 251.664759 -142.489891)
			(xy 251.673378 -142.433066) (xy 251.690423 -142.378178) (xy 251.71551 -142.326468) (xy 251.748071 -142.279106)
			(xy 251.76734 -142.25778) (xy 251.773944 -142.250922) (xy 251.781056 -142.232888) (xy 251.781056 -142.143988)
			(xy 251.773944 -142.125954) (xy 251.76734 -142.119096) (xy 251.748106 -142.097737) (xy 251.715538 -142.05038)
			(xy 251.690444 -141.998674) (xy 251.67339 -141.943788) (xy 251.664763 -141.886965) (xy 251.664759 -141.829491)
			(xy 251.673378 -141.772666) (xy 251.690423 -141.717778) (xy 251.71551 -141.666068) (xy 251.748071 -141.618706)
			(xy 251.76734 -141.59738) (xy 251.773944 -141.590522) (xy 251.781056 -141.572488) (xy 251.781056 -141.483588)
			(xy 251.773944 -141.465554) (xy 251.76734 -141.458696) (xy 251.748106 -141.437337) (xy 251.715538 -141.38998)
			(xy 251.690444 -141.338274) (xy 251.67339 -141.283388) (xy 251.664763 -141.226565) (xy 251.664759 -141.169091)
			(xy 251.673378 -141.112266) (xy 251.690423 -141.057378) (xy 251.71551 -141.005668) (xy 251.748071 -140.958306)
			(xy 251.76734 -140.93698) (xy 251.773944 -140.930122) (xy 251.781056 -140.912088) (xy 251.781056 -140.823188)
			(xy 251.773944 -140.805154) (xy 251.76734 -140.798296) (xy 251.748088 -140.776953) (xy 251.715519 -140.729595)
			(xy 251.690423 -140.677888) (xy 251.673368 -140.623001) (xy 251.66474 -140.566176) (xy 251.664216 -140.537438)
			(xy 251.664702 -140.510187) (xy 251.672458 -140.456239) (xy 251.687813 -140.403944) (xy 251.710455 -140.354367)
			(xy 251.739921 -140.308517) (xy 251.775612 -140.267326) (xy 251.816803 -140.231635) (xy 251.862653 -140.202169)
			(xy 251.91223 -140.179527) (xy 251.964525 -140.164172) (xy 252.018473 -140.156416) (xy 252.072975 -140.156416)
			(xy 252.126923 -140.164172) (xy 252.179218 -140.179527) (xy 252.228795 -140.202169) (xy 252.274645 -140.231635)
			(xy 252.315836 -140.267326) (xy 252.351527 -140.308517) (xy 252.380993 -140.354367) (xy 252.403635 -140.403944)
			(xy 252.41899 -140.456239) (xy 252.426746 -140.510187) (xy 252.427232 -140.537438) (xy 252.426723 -140.566177)
			(xy 252.418095 -140.623005) (xy 252.401041 -140.677896) (xy 252.375947 -140.729607) (xy 252.34338 -140.776969)
			(xy 252.324108 -140.798296) (xy 252.317504 -140.805154) (xy 252.310392 -140.823188) (xy 252.310392 -140.912088)
			(xy 252.317504 -140.930122) (xy 252.324108 -140.93698) (xy 252.343415 -140.958275) (xy 252.375976 -141.005644)
			(xy 252.401064 -141.057361) (xy 252.418109 -141.112256) (xy 252.426728 -141.169087) (xy 252.426724 -141.226568)
			(xy 252.418097 -141.283398) (xy 252.401043 -141.338291) (xy 252.375948 -141.390004) (xy 252.34338 -141.437368)
			(xy 252.324108 -141.458696) (xy 252.317504 -141.465554) (xy 252.310392 -141.483588) (xy 252.310392 -141.572488)
			(xy 252.317504 -141.590522) (xy 252.324108 -141.59738) (xy 252.343415 -141.618675) (xy 252.375976 -141.666044)
			(xy 252.401064 -141.717761) (xy 252.418109 -141.772656) (xy 252.426728 -141.829487) (xy 252.426724 -141.886968)
			(xy 252.418097 -141.943798) (xy 252.401043 -141.998691) (xy 252.375948 -142.050404) (xy 252.34338 -142.097768)
			(xy 252.324108 -142.119096) (xy 252.317504 -142.125954) (xy 252.310392 -142.143988) (xy 252.310392 -142.232888)
			(xy 252.317504 -142.250922) (xy 252.324108 -142.25778) (xy 252.343415 -142.279075) (xy 252.375976 -142.326444)
			(xy 252.401064 -142.378161) (xy 252.418109 -142.433056) (xy 252.426728 -142.489887) (xy 252.426724 -142.547368)
			(xy 252.418097 -142.604198) (xy 252.401043 -142.659091) (xy 252.375948 -142.710804) (xy 252.34338 -142.758168)
			(xy 252.324108 -142.779496) (xy 252.317504 -142.786354) (xy 252.310392 -142.804388) (xy 252.310392 -142.893288)
			(xy 252.317504 -142.911322) (xy 252.324108 -142.91818) (xy 252.343387 -142.9395) (xy 252.375954 -142.986863)
			(xy 252.401046 -143.038576) (xy 252.418094 -143.093469) (xy 252.426713 -143.150298) (xy 252.427232 -143.179038)
			(xy 252.426826 -143.205015) (xy 252.419777 -143.256488) (xy 252.405803 -143.306526) (xy 252.385161 -143.354203)
			(xy 252.358235 -143.398634) (xy 252.325524 -143.438996) (xy 252.287633 -143.474541) (xy 252.266704 -143.489934)
			(xy 252.257233 -143.497587) (xy 252.246075 -143.519183) (xy 252.245368 -143.531336) (xy 252.245368 -143.61414)
			(xy 252.246056 -143.626303) (xy 252.257197 -143.647925) (xy 252.266704 -143.655542) (xy 252.287622 -143.670946)
			(xy 252.325497 -143.7065) (xy 252.358195 -143.746865) (xy 252.385113 -143.791295) (xy 252.405752 -143.838966)
			(xy 252.41973 -143.888998) (xy 252.426789 -143.940464) (xy 252.427232 -143.966438) (xy 252.426746 -143.993689)
			(xy 252.41899 -144.047637) (xy 252.403635 -144.099932) (xy 252.380993 -144.149509) (xy 252.351527 -144.195359)
			(xy 252.315836 -144.23655) (xy 252.274645 -144.272241) (xy 252.228795 -144.301707) (xy 252.179218 -144.324349)
			(xy 252.126923 -144.339704) (xy 252.072975 -144.34746) (xy 252.018473 -144.34746) (xy 251.964525 -144.339704)
			(xy 251.91223 -144.324349) (xy 251.862653 -144.301707) (xy 251.816803 -144.272241) (xy 251.775612 -144.23655)
			(xy 251.739921 -144.195359) (xy 251.710455 -144.149509) (xy 251.687813 -144.099932) (xy 251.672458 -144.047637)
			(xy 251.664702 -143.993689) (xy 251.664216 -143.966438) (xy 236.856819 -143.966438) (xy 236.855539 -143.967503)
			(xy 236.807933 -143.996557) (xy 236.756604 -144.018369) (xy 236.702647 -144.032475) (xy 236.64721 -144.038575)
			(xy 236.591476 -144.036538) (xy 236.536633 -144.026408) (xy 236.483849 -144.008401) (xy 236.434249 -143.9829)
			(xy 236.388891 -143.950449) (xy 236.348742 -143.91174) (xy 236.314656 -143.867597) (xy 236.28736 -143.818962)
			(xy 236.267437 -143.766871) (xy 236.255311 -143.712434) (xy 236.25124 -143.656812) (xy 225.653117 -143.656812)
			(xy 225.669067 -143.670086) (xy 225.706284 -143.711623) (xy 225.737057 -143.758136) (xy 225.760729 -143.808633)
			(xy 225.776797 -143.86204) (xy 225.784917 -143.917216) (xy 225.785426 -143.945102) (xy 225.784917 -143.972988)
			(xy 225.776797 -144.028164) (xy 225.760729 -144.081571) (xy 225.737057 -144.132068) (xy 225.706284 -144.178581)
			(xy 225.669067 -144.220118) (xy 225.626199 -144.255793) (xy 225.578593 -144.284847) (xy 225.527264 -144.306659)
			(xy 225.473307 -144.320765) (xy 225.41787 -144.326865) (xy 225.362136 -144.324828) (xy 225.307293 -144.314698)
			(xy 225.254509 -144.296691) (xy 225.204909 -144.27119) (xy 225.159551 -144.238739) (xy 225.119402 -144.20003)
			(xy 225.085316 -144.155887) (xy 225.05802 -144.107252) (xy 225.038097 -144.055161) (xy 225.025971 -144.000724)
			(xy 225.0219 -143.945102) (xy 220.623084 -143.945102) (xy 220.622621 -143.970448) (xy 220.614501 -144.025624)
			(xy 220.598433 -144.079031) (xy 220.574761 -144.129528) (xy 220.543988 -144.176041) (xy 220.506771 -144.217578)
			(xy 220.463903 -144.253253) (xy 220.416297 -144.282307) (xy 220.364968 -144.304119) (xy 220.311011 -144.318225)
			(xy 220.255574 -144.324325) (xy 220.19984 -144.322288) (xy 220.144997 -144.312158) (xy 220.092213 -144.294151)
			(xy 220.042613 -144.26865) (xy 219.997255 -144.236199) (xy 219.957106 -144.19749) (xy 219.92302 -144.153347)
			(xy 219.895724 -144.104712) (xy 219.875801 -144.052621) (xy 219.863675 -143.998184) (xy 219.859604 -143.942562)
			(xy 201.194113 -143.942562) (xy 201.229884 -143.983846) (xy 201.26086 -144.032047) (xy 201.284661 -144.084165)
			(xy 201.300803 -144.13914) (xy 201.308957 -144.195852) (xy 201.308957 -144.253148) (xy 201.300803 -144.30986)
			(xy 201.284661 -144.364835) (xy 201.26086 -144.416953) (xy 201.229884 -144.465154) (xy 201.192364 -144.508456)
			(xy 201.149064 -144.545977) (xy 201.100864 -144.576954) (xy 201.048747 -144.600757) (xy 200.993772 -144.6169)
			(xy 200.93706 -144.625056) (xy 200.908412 -144.625568) (xy 200.893494 -144.625403) (xy 200.863745 -144.623111)
			(xy 200.848976 -144.620996) (xy 200.8378 -144.619218) (xy 200.816718 -144.625314) (xy 200.749662 -144.682972)
			(xy 200.741702 -144.69057) (xy 200.732615 -144.710586) (xy 200.732136 -144.72158) (xy 200.732136 -144.958562)
			(xy 219.859604 -144.958562) (xy 219.863675 -144.90294) (xy 219.875801 -144.848503) (xy 219.895724 -144.796412)
			(xy 219.92302 -144.747777) (xy 219.957106 -144.703634) (xy 219.997255 -144.664925) (xy 220.042613 -144.632474)
			(xy 220.092213 -144.606973) (xy 220.144997 -144.588966) (xy 220.19984 -144.578836) (xy 220.255574 -144.576799)
			(xy 220.311011 -144.582899) (xy 220.364968 -144.597005) (xy 220.416297 -144.618817) (xy 220.463903 -144.647871)
			(xy 220.506771 -144.683546) (xy 220.543988 -144.725083) (xy 220.574761 -144.771596) (xy 220.598433 -144.822093)
			(xy 220.614501 -144.8755) (xy 220.622621 -144.930676) (xy 220.62313 -144.958562) (xy 220.622621 -144.986448)
			(xy 220.614501 -145.041624) (xy 220.598433 -145.095031) (xy 220.577153 -145.140426) (xy 222.363028 -145.140426)
			(xy 222.367099 -145.084804) (xy 222.379225 -145.030367) (xy 222.399148 -144.978276) (xy 222.426444 -144.929641)
			(xy 222.46053 -144.885498) (xy 222.500679 -144.846789) (xy 222.546037 -144.814338) (xy 222.595637 -144.788837)
			(xy 222.648421 -144.77083) (xy 222.703264 -144.7607) (xy 222.758998 -144.758663) (xy 222.814435 -144.764763)
			(xy 222.868392 -144.778869) (xy 222.919721 -144.800681) (xy 222.959084 -144.824704) (xy 226.191824 -144.824704)
			(xy 226.195895 -144.769082) (xy 226.208021 -144.714645) (xy 226.227944 -144.662554) (xy 226.25524 -144.613919)
			(xy 226.289326 -144.569776) (xy 226.329475 -144.531067) (xy 226.374833 -144.498616) (xy 226.424433 -144.473115)
			(xy 226.477217 -144.455108) (xy 226.53206 -144.444978) (xy 226.587794 -144.442941) (xy 226.643231 -144.449041)
			(xy 226.697188 -144.463147) (xy 226.748517 -144.484959) (xy 226.796123 -144.514013) (xy 226.838991 -144.549688)
			(xy 226.876208 -144.591225) (xy 226.906981 -144.637738) (xy 226.930653 -144.688235) (xy 226.946721 -144.741642)
			(xy 226.954841 -144.796818) (xy 226.95535 -144.824704) (xy 227.916992 -144.824704) (xy 227.921063 -144.769082)
			(xy 227.933189 -144.714645) (xy 227.953112 -144.662554) (xy 227.980408 -144.613919) (xy 228.014494 -144.569776)
			(xy 228.054643 -144.531067) (xy 228.100001 -144.498616) (xy 228.149601 -144.473115) (xy 228.202385 -144.455108)
			(xy 228.257228 -144.444978) (xy 228.312962 -144.442941) (xy 228.368399 -144.449041) (xy 228.422356 -144.463147)
			(xy 228.473685 -144.484959) (xy 228.521291 -144.514013) (xy 228.564159 -144.549688) (xy 228.601376 -144.591225)
			(xy 228.632149 -144.637738) (xy 228.655821 -144.688235) (xy 228.671889 -144.741642) (xy 228.680009 -144.796818)
			(xy 228.680518 -144.824704) (xy 229.333804 -144.824704) (xy 229.337875 -144.769082) (xy 229.350001 -144.714645)
			(xy 229.369924 -144.662554) (xy 229.39722 -144.613919) (xy 229.431306 -144.569776) (xy 229.471455 -144.531067)
			(xy 229.516813 -144.498616) (xy 229.566413 -144.473115) (xy 229.619197 -144.455108) (xy 229.67404 -144.444978)
			(xy 229.729774 -144.442941) (xy 229.785211 -144.449041) (xy 229.839168 -144.463147) (xy 229.890497 -144.484959)
			(xy 229.938103 -144.514013) (xy 229.980971 -144.549688) (xy 230.018188 -144.591225) (xy 230.048961 -144.637738)
			(xy 230.072633 -144.688235) (xy 230.088701 -144.741642) (xy 230.096821 -144.796818) (xy 230.09733 -144.824704)
			(xy 230.3813 -144.824704) (xy 230.385371 -144.769082) (xy 230.397497 -144.714645) (xy 230.41742 -144.662554)
			(xy 230.444716 -144.613919) (xy 230.478802 -144.569776) (xy 230.518951 -144.531067) (xy 230.564309 -144.498616)
			(xy 230.613909 -144.473115) (xy 230.666693 -144.455108) (xy 230.721536 -144.444978) (xy 230.77727 -144.442941)
			(xy 230.832707 -144.449041) (xy 230.886664 -144.463147) (xy 230.937993 -144.484959) (xy 230.985599 -144.514013)
			(xy 231.028467 -144.549688) (xy 231.065684 -144.591225) (xy 231.096457 -144.637738) (xy 231.112899 -144.672812)
			(xy 234.175044 -144.672812) (xy 234.179115 -144.61719) (xy 234.191241 -144.562753) (xy 234.211164 -144.510662)
			(xy 234.23846 -144.462027) (xy 234.272546 -144.417884) (xy 234.312695 -144.379175) (xy 234.358053 -144.346724)
			(xy 234.407653 -144.321223) (xy 234.460437 -144.303216) (xy 234.51528 -144.293086) (xy 234.571014 -144.291049)
			(xy 234.626451 -144.297149) (xy 234.680408 -144.311255) (xy 234.731737 -144.333067) (xy 234.779343 -144.362121)
			(xy 234.822211 -144.397796) (xy 234.859428 -144.439333) (xy 234.890201 -144.485846) (xy 234.913873 -144.536343)
			(xy 234.929941 -144.58975) (xy 234.938061 -144.644926) (xy 234.93857 -144.672812) (xy 234.938061 -144.700698)
			(xy 234.929941 -144.755874) (xy 234.913873 -144.809281) (xy 234.890201 -144.859778) (xy 234.859428 -144.906291)
			(xy 234.822211 -144.947828) (xy 234.779343 -144.983503) (xy 234.731737 -145.012557) (xy 234.680408 -145.034369)
			(xy 234.626451 -145.048475) (xy 234.571014 -145.054575) (xy 234.51528 -145.052538) (xy 234.460437 -145.042408)
			(xy 234.407653 -145.024401) (xy 234.358053 -144.9989) (xy 234.312695 -144.966449) (xy 234.272546 -144.92774)
			(xy 234.23846 -144.883597) (xy 234.211164 -144.834962) (xy 234.191241 -144.782871) (xy 234.179115 -144.728434)
			(xy 234.175044 -144.672812) (xy 231.112899 -144.672812) (xy 231.120129 -144.688235) (xy 231.136197 -144.741642)
			(xy 231.144317 -144.796818) (xy 231.144826 -144.824704) (xy 231.144317 -144.85259) (xy 231.136197 -144.907766)
			(xy 231.120129 -144.961173) (xy 231.096457 -145.01167) (xy 231.065684 -145.058183) (xy 231.028467 -145.09972)
			(xy 231.015452 -145.110551) (xy 241.177054 -145.110551) (xy 241.177054 -145.056049) (xy 241.18481 -145.002101)
			(xy 241.200164 -144.949806) (xy 241.222804 -144.900228) (xy 241.252269 -144.854376) (xy 241.287959 -144.813184)
			(xy 241.329147 -144.77749) (xy 241.374996 -144.748021) (xy 241.424572 -144.725377) (xy 241.476865 -144.710017)
			(xy 241.530813 -144.702256) (xy 241.558064 -144.701768) (xy 241.584379 -144.702203) (xy 241.636508 -144.709446)
			(xy 241.687151 -144.723772) (xy 241.73535 -144.744911) (xy 241.780193 -144.772462) (xy 241.820832 -144.805905)
			(xy 241.838988 -144.824958) (xy 241.846518 -144.83235) (xy 241.865791 -144.840881) (xy 241.876326 -144.841468)
			(xy 241.951002 -144.841468) (xy 241.961555 -144.840963) (xy 241.98085 -144.832412) (xy 241.98834 -144.824958)
			(xy 242.006475 -144.805882) (xy 242.04711 -144.772428) (xy 242.091955 -144.744873) (xy 242.14016 -144.723738)
			(xy 242.19081 -144.709425) (xy 242.242947 -144.702204) (xy 242.269264 -144.701768) (xy 242.296517 -144.702277)
			(xy 242.350468 -144.710029) (xy 242.402767 -144.725381) (xy 242.452349 -144.74802) (xy 242.498203 -144.777485)
			(xy 242.539398 -144.813177) (xy 242.575093 -144.854368) (xy 242.604563 -144.90022) (xy 242.627206 -144.949799)
			(xy 242.642563 -145.002097) (xy 242.650321 -145.056047) (xy 242.650321 -145.110551) (xy 242.955054 -145.110551)
			(xy 242.955054 -145.056049) (xy 242.96281 -145.002101) (xy 242.978164 -144.949806) (xy 243.000804 -144.900228)
			(xy 243.030269 -144.854376) (xy 243.065959 -144.813184) (xy 243.107147 -144.77749) (xy 243.152996 -144.748021)
			(xy 243.202572 -144.725377) (xy 243.254865 -144.710017) (xy 243.308813 -144.702256) (xy 243.336064 -144.701768)
			(xy 243.362379 -144.702203) (xy 243.414508 -144.709446) (xy 243.465151 -144.723772) (xy 243.51335 -144.744911)
			(xy 243.558193 -144.772462) (xy 243.598832 -144.805905) (xy 243.616988 -144.824958) (xy 243.624518 -144.83235)
			(xy 243.643791 -144.840881) (xy 243.654326 -144.841468) (xy 243.729002 -144.841468) (xy 243.739555 -144.840963)
			(xy 243.75885 -144.832412) (xy 243.76634 -144.824958) (xy 243.784475 -144.805882) (xy 243.82511 -144.772428)
			(xy 243.869955 -144.744873) (xy 243.91816 -144.723738) (xy 243.96881 -144.709425) (xy 244.020947 -144.702204)
			(xy 244.047264 -144.701768) (xy 244.074517 -144.702277) (xy 244.128468 -144.710029) (xy 244.180767 -144.725381)
			(xy 244.230349 -144.74802) (xy 244.276203 -144.777485) (xy 244.317398 -144.813177) (xy 244.353093 -144.854368)
			(xy 244.382563 -144.90022) (xy 244.405206 -144.949799) (xy 244.406511 -144.954244) (xy 250.138946 -144.954244)
			(xy 250.139519 -144.926996) (xy 250.147268 -144.873054) (xy 250.162616 -144.820764) (xy 250.185248 -144.77119)
			(xy 250.214706 -144.725341) (xy 250.250388 -144.684152) (xy 250.291569 -144.64846) (xy 250.337411 -144.618991)
			(xy 250.386979 -144.596347) (xy 250.439266 -144.580988) (xy 250.493206 -144.573225) (xy 250.520454 -144.572736)
			(xy 250.549228 -144.573258) (xy 250.606123 -144.581908) (xy 250.661074 -144.599005) (xy 250.712834 -144.624159)
			(xy 250.76023 -144.656801) (xy 250.781566 -144.676114) (xy 250.78944 -144.68348) (xy 250.809252 -144.690592)
			(xy 250.905518 -144.683226) (xy 250.924314 -144.67332) (xy 250.930918 -144.664938) (xy 250.949154 -144.642763)
			(xy 250.991086 -144.603551) (xy 251.03842 -144.571064) (xy 251.090085 -144.546034) (xy 251.144918 -144.529026)
			(xy 251.201679 -144.520423) (xy 251.230384 -144.519904) (xy 251.257637 -144.52037) (xy 251.311588 -144.528125)
			(xy 251.363887 -144.54348) (xy 251.413468 -144.566121) (xy 251.459322 -144.595589) (xy 251.500515 -144.631282)
			(xy 251.536209 -144.672475) (xy 251.565677 -144.718329) (xy 251.588319 -144.767909) (xy 251.603674 -144.820208)
			(xy 251.611429 -144.874159) (xy 251.611892 -144.901412) (xy 251.611444 -144.928315) (xy 251.603871 -144.981586)
			(xy 251.588889 -145.033265) (xy 251.566797 -145.082327) (xy 251.538032 -145.127799) (xy 251.503165 -145.16878)
			(xy 251.462887 -145.204457) (xy 251.440696 -145.219674) (xy 251.429774 -145.226786) (xy 251.417836 -145.249646)
			(xy 251.419868 -145.361914) (xy 251.432822 -145.384266) (xy 251.443998 -145.391124) (xy 251.467599 -145.406047)
			(xy 251.510551 -145.441725) (xy 251.547844 -145.483283) (xy 251.578682 -145.529833) (xy 251.602406 -145.58038)
			(xy 251.618508 -145.633846) (xy 251.626646 -145.689087) (xy 251.627132 -145.717006) (xy 251.626677 -145.744)
			(xy 251.61907 -145.797448) (xy 251.604009 -145.849292) (xy 251.581793 -145.898496) (xy 251.552867 -145.94408)
			(xy 251.535692 -145.96491) (xy 251.52858 -145.973038) (xy 251.522484 -145.993612) (xy 251.533406 -146.078956)
			(xy 251.535196 -146.089497) (xy 251.546239 -146.107781) (xy 251.554742 -146.114262) (xy 251.575947 -146.129649)
			(xy 251.614401 -146.16523) (xy 251.647622 -146.205741) (xy 251.674984 -146.250418) (xy 251.695972 -146.298421)
			(xy 251.71019 -146.348845) (xy 251.717371 -146.400741) (xy 251.71781 -146.426936) (xy 251.717324 -146.454187)
			(xy 251.709568 -146.508135) (xy 251.694213 -146.56043) (xy 251.671571 -146.610007) (xy 251.642105 -146.655857)
			(xy 251.606414 -146.697048) (xy 251.565223 -146.732739) (xy 251.519373 -146.762205) (xy 251.469796 -146.784847)
			(xy 251.417501 -146.800202) (xy 251.363553 -146.807958) (xy 251.309051 -146.807958) (xy 251.255103 -146.800202)
			(xy 251.202808 -146.784847) (xy 251.153231 -146.762205) (xy 251.107381 -146.732739) (xy 251.06619 -146.697048)
			(xy 251.030499 -146.655857) (xy 251.001033 -146.610007) (xy 250.978391 -146.56043) (xy 250.963036 -146.508135)
			(xy 250.95528 -146.454187) (xy 250.954794 -146.426936) (xy 250.955291 -146.399944) (xy 250.96289 -146.346498)
			(xy 250.977943 -146.294656) (xy 251.000149 -146.245451) (xy 251.029064 -146.199864) (xy 251.046234 -146.179032)
			(xy 251.053346 -146.170904) (xy 251.059442 -146.15033) (xy 251.04852 -146.064986) (xy 251.046749 -146.054441)
			(xy 251.035691 -146.036159) (xy 251.027184 -146.02968) (xy 251.002883 -146.012068) (xy 250.959624 -145.970472)
			(xy 250.941078 -145.946876) (xy 250.935236 -145.939002) (xy 250.91771 -145.928588) (xy 250.827286 -145.91538)
			(xy 250.807982 -145.920206) (xy 250.800108 -145.926048) (xy 250.799854 -145.926048) (xy 250.775111 -145.943553)
			(xy 250.721258 -145.971356) (xy 250.663686 -145.990292) (xy 250.603843 -145.999883) (xy 250.57354 -146.00047)
			(xy 250.546286 -146.000007) (xy 250.492333 -145.992255) (xy 250.440033 -145.976902) (xy 250.390451 -145.954261)
			(xy 250.344596 -145.924794) (xy 250.303401 -145.8891) (xy 250.267707 -145.847906) (xy 250.23824 -145.802051)
			(xy 250.215599 -145.752469) (xy 250.200246 -145.700168) (xy 250.192493 -145.646216) (xy 250.192032 -145.618962)
			(xy 250.192467 -145.592928) (xy 250.199559 -145.541345) (xy 250.213591 -145.491203) (xy 250.234305 -145.443433)
			(xy 250.261315 -145.398918) (xy 250.277376 -145.378424) (xy 250.283116 -145.370666) (xy 250.288858 -145.352256)
			(xy 250.288552 -145.34261) (xy 250.282202 -145.262854) (xy 250.273566 -145.245074) (xy 250.2662 -145.238724)
			(xy 250.246561 -145.220536) (xy 250.212035 -145.179632) (xy 250.183562 -145.134305) (xy 250.161703 -145.085445)
			(xy 250.146885 -145.034009) (xy 250.1394 -144.981008) (xy 250.138946 -144.954244) (xy 244.406511 -144.954244)
			(xy 244.420563 -145.002097) (xy 244.428321 -145.056047) (xy 244.428321 -145.110553) (xy 244.420563 -145.164503)
			(xy 244.405206 -145.216801) (xy 244.382563 -145.26638) (xy 244.353093 -145.312232) (xy 244.317398 -145.353423)
			(xy 244.276203 -145.389115) (xy 244.230349 -145.41858) (xy 244.180767 -145.441219) (xy 244.128468 -145.456571)
			(xy 244.074517 -145.464323) (xy 244.047264 -145.464784) (xy 244.020949 -145.464346) (xy 243.968819 -145.457106)
			(xy 243.918176 -145.442781) (xy 243.869977 -145.421643) (xy 243.825134 -145.394092) (xy 243.784496 -145.360648)
			(xy 243.76634 -145.341594) (xy 243.758806 -145.334207) (xy 243.739535 -145.325675) (xy 243.729002 -145.325084)
			(xy 243.654326 -145.325084) (xy 243.643777 -145.325619) (xy 243.624482 -145.334151) (xy 243.616988 -145.341594)
			(xy 243.59883 -145.360647) (xy 243.558201 -145.394105) (xy 243.513361 -145.421664) (xy 243.465161 -145.442803)
			(xy 243.414514 -145.457121) (xy 243.36238 -145.464346) (xy 243.336064 -145.464784) (xy 243.308813 -145.464344)
			(xy 243.254865 -145.456583) (xy 243.202572 -145.441223) (xy 243.152996 -145.418579) (xy 243.107147 -145.38911)
			(xy 243.065959 -145.353416) (xy 243.030269 -145.312224) (xy 243.000804 -145.266372) (xy 242.978164 -145.216794)
			(xy 242.96281 -145.164499) (xy 242.955054 -145.110551) (xy 242.650321 -145.110551) (xy 242.650321 -145.110553)
			(xy 242.642563 -145.164503) (xy 242.627206 -145.216801) (xy 242.604563 -145.26638) (xy 242.575093 -145.312232)
			(xy 242.539398 -145.353423) (xy 242.498203 -145.389115) (xy 242.452349 -145.41858) (xy 242.402767 -145.441219)
			(xy 242.350468 -145.456571) (xy 242.296517 -145.464323) (xy 242.269264 -145.464784) (xy 242.242949 -145.464346)
			(xy 242.190819 -145.457106) (xy 242.140176 -145.442781) (xy 242.091977 -145.421643) (xy 242.047134 -145.394092)
			(xy 242.006496 -145.360648) (xy 241.98834 -145.341594) (xy 241.980806 -145.334207) (xy 241.961535 -145.325675)
			(xy 241.951002 -145.325084) (xy 241.876326 -145.325084) (xy 241.865777 -145.325619) (xy 241.846482 -145.334151)
			(xy 241.838988 -145.341594) (xy 241.82083 -145.360647) (xy 241.780201 -145.394105) (xy 241.735361 -145.421664)
			(xy 241.687161 -145.442803) (xy 241.636514 -145.457121) (xy 241.58438 -145.464346) (xy 241.558064 -145.464784)
			(xy 241.530813 -145.464344) (xy 241.476865 -145.456583) (xy 241.424572 -145.441223) (xy 241.374996 -145.418579)
			(xy 241.329147 -145.38911) (xy 241.287959 -145.353416) (xy 241.252269 -145.312224) (xy 241.222804 -145.266372)
			(xy 241.200164 -145.216794) (xy 241.18481 -145.164499) (xy 241.177054 -145.110551) (xy 231.015452 -145.110551)
			(xy 230.985599 -145.135395) (xy 230.937993 -145.164449) (xy 230.886664 -145.186261) (xy 230.832707 -145.200367)
			(xy 230.77727 -145.206467) (xy 230.721536 -145.20443) (xy 230.666693 -145.1943) (xy 230.613909 -145.176293)
			(xy 230.564309 -145.150792) (xy 230.518951 -145.118341) (xy 230.478802 -145.079632) (xy 230.444716 -145.035489)
			(xy 230.41742 -144.986854) (xy 230.397497 -144.934763) (xy 230.385371 -144.880326) (xy 230.3813 -144.824704)
			(xy 230.09733 -144.824704) (xy 230.096821 -144.85259) (xy 230.088701 -144.907766) (xy 230.072633 -144.961173)
			(xy 230.048961 -145.01167) (xy 230.018188 -145.058183) (xy 229.980971 -145.09972) (xy 229.938103 -145.135395)
			(xy 229.890497 -145.164449) (xy 229.839168 -145.186261) (xy 229.785211 -145.200367) (xy 229.729774 -145.206467)
			(xy 229.67404 -145.20443) (xy 229.619197 -145.1943) (xy 229.566413 -145.176293) (xy 229.516813 -145.150792)
			(xy 229.471455 -145.118341) (xy 229.431306 -145.079632) (xy 229.39722 -145.035489) (xy 229.369924 -144.986854)
			(xy 229.350001 -144.934763) (xy 229.337875 -144.880326) (xy 229.333804 -144.824704) (xy 228.680518 -144.824704)
			(xy 228.680009 -144.85259) (xy 228.671889 -144.907766) (xy 228.655821 -144.961173) (xy 228.632149 -145.01167)
			(xy 228.601376 -145.058183) (xy 228.564159 -145.09972) (xy 228.521291 -145.135395) (xy 228.473685 -145.164449)
			(xy 228.422356 -145.186261) (xy 228.368399 -145.200367) (xy 228.312962 -145.206467) (xy 228.257228 -145.20443)
			(xy 228.202385 -145.1943) (xy 228.149601 -145.176293) (xy 228.100001 -145.150792) (xy 228.054643 -145.118341)
			(xy 228.014494 -145.079632) (xy 227.980408 -145.035489) (xy 227.953112 -144.986854) (xy 227.933189 -144.934763)
			(xy 227.921063 -144.880326) (xy 227.916992 -144.824704) (xy 226.95535 -144.824704) (xy 226.954841 -144.85259)
			(xy 226.946721 -144.907766) (xy 226.930653 -144.961173) (xy 226.906981 -145.01167) (xy 226.876208 -145.058183)
			(xy 226.838991 -145.09972) (xy 226.796123 -145.135395) (xy 226.748517 -145.164449) (xy 226.697188 -145.186261)
			(xy 226.643231 -145.200367) (xy 226.587794 -145.206467) (xy 226.53206 -145.20443) (xy 226.477217 -145.1943)
			(xy 226.424433 -145.176293) (xy 226.374833 -145.150792) (xy 226.329475 -145.118341) (xy 226.289326 -145.079632)
			(xy 226.25524 -145.035489) (xy 226.227944 -144.986854) (xy 226.208021 -144.934763) (xy 226.195895 -144.880326)
			(xy 226.191824 -144.824704) (xy 222.959084 -144.824704) (xy 222.967327 -144.829735) (xy 223.010195 -144.86541)
			(xy 223.047412 -144.906947) (xy 223.078185 -144.95346) (xy 223.101857 -145.003957) (xy 223.117925 -145.057364)
			(xy 223.126045 -145.11254) (xy 223.126554 -145.140426) (xy 223.126045 -145.168312) (xy 223.117925 -145.223488)
			(xy 223.101857 -145.276895) (xy 223.078185 -145.327392) (xy 223.047412 -145.373905) (xy 223.010195 -145.415442)
			(xy 222.967327 -145.451117) (xy 222.919721 -145.480171) (xy 222.868392 -145.501983) (xy 222.814435 -145.516089)
			(xy 222.758998 -145.522189) (xy 222.703264 -145.520152) (xy 222.648421 -145.510022) (xy 222.595637 -145.492015)
			(xy 222.546037 -145.466514) (xy 222.500679 -145.434063) (xy 222.46053 -145.395354) (xy 222.426444 -145.351211)
			(xy 222.399148 -145.302576) (xy 222.379225 -145.250485) (xy 222.367099 -145.196048) (xy 222.363028 -145.140426)
			(xy 220.577153 -145.140426) (xy 220.574761 -145.145528) (xy 220.543988 -145.192041) (xy 220.506771 -145.233578)
			(xy 220.463903 -145.269253) (xy 220.416297 -145.298307) (xy 220.364968 -145.320119) (xy 220.311011 -145.334225)
			(xy 220.255574 -145.340325) (xy 220.19984 -145.338288) (xy 220.144997 -145.328158) (xy 220.092213 -145.310151)
			(xy 220.042613 -145.28465) (xy 219.997255 -145.252199) (xy 219.957106 -145.21349) (xy 219.92302 -145.169347)
			(xy 219.895724 -145.120712) (xy 219.875801 -145.068621) (xy 219.863675 -145.014184) (xy 219.859604 -144.958562)
			(xy 200.732136 -144.958562) (xy 200.732136 -144.986248) (xy 200.732604 -144.997242) (xy 200.741704 -145.017254)
			(xy 200.749662 -145.024856) (xy 200.816718 -145.082514) (xy 200.8378 -145.08861) (xy 200.848976 -145.086832)
			(xy 200.863745 -145.084723) (xy 200.893494 -145.082436) (xy 200.908412 -145.08226) (xy 200.937062 -145.08272)
			(xy 200.993777 -145.090876) (xy 201.048755 -145.10702) (xy 201.100876 -145.130824) (xy 201.149078 -145.161803)
			(xy 201.192382 -145.199327) (xy 201.229904 -145.242631) (xy 201.260882 -145.290835) (xy 201.284684 -145.342956)
			(xy 201.300827 -145.397934) (xy 201.308981 -145.45465) (xy 201.308981 -145.51195) (xy 201.300827 -145.568666)
			(xy 201.284684 -145.623644) (xy 201.260882 -145.675765) (xy 201.229904 -145.723969) (xy 201.192382 -145.767273)
			(xy 201.149078 -145.804797) (xy 201.100876 -145.835776) (xy 201.048755 -145.85958) (xy 200.993777 -145.875724)
			(xy 200.937062 -145.88388) (xy 200.908412 -145.884392) (xy 200.881031 -145.88392) (xy 200.826781 -145.876454)
			(xy 200.774053 -145.861673) (xy 200.723827 -145.839852) (xy 200.677038 -145.811397) (xy 200.634559 -145.776838)
			(xy 200.597179 -145.736819) (xy 200.581006 -145.71472) (xy 200.575437 -145.707466) (xy 200.560333 -145.697178)
			(xy 200.551542 -145.694654) (xy 200.52157 -145.687288) (xy 200.512622 -145.685522) (xy 200.49453 -145.687749)
			(xy 200.486264 -145.691606) (xy 200.461669 -145.704007) (xy 200.410141 -145.723473) (xy 200.35665 -145.736618)
			(xy 200.301969 -145.743253) (xy 200.274428 -145.743676) (xy 200.246887 -145.743258) (xy 200.192207 -145.736619)
			(xy 200.138717 -145.723469) (xy 200.087191 -145.703998) (xy 200.062592 -145.691606) (xy 200.054334 -145.687725)
			(xy 200.036236 -145.685512) (xy 200.027286 -145.687288) (xy 199.997314 -145.694654) (xy 199.988535 -145.697204)
			(xy 199.973432 -145.707481) (xy 199.96785 -145.71472) (xy 199.951722 -145.736855) (xy 199.914342 -145.776884)
			(xy 199.871858 -145.81145) (xy 199.825062 -145.839906) (xy 199.774827 -145.861724) (xy 199.722088 -145.876497)
			(xy 199.667828 -145.883949) (xy 199.640444 -145.884392) (xy 199.611794 -145.883856) (xy 199.555076 -145.875707)
			(xy 199.500095 -145.859569) (xy 199.447971 -145.83577) (xy 199.399765 -145.804794) (xy 199.356458 -145.767273)
			(xy 199.318932 -145.72397) (xy 199.287951 -145.675767) (xy 199.264147 -145.623646) (xy 199.248002 -145.568667)
			(xy 199.239847 -145.51195) (xy 199.239847 -145.45465) (xy 199.248002 -145.397933) (xy 199.264147 -145.342954)
			(xy 199.287951 -145.290833) (xy 199.318932 -145.24263) (xy 199.356458 -145.199327) (xy 199.399765 -145.161806)
			(xy 199.447971 -145.13083) (xy 199.500095 -145.107031) (xy 199.555076 -145.090893) (xy 199.611794 -145.082744)
			(xy 199.640444 -145.08226) (xy 199.655362 -145.082429) (xy 199.685111 -145.084718) (xy 199.69988 -145.086832)
			(xy 199.711056 -145.08861) (xy 199.732138 -145.082514) (xy 199.799194 -145.024856) (xy 199.807135 -145.01724)
			(xy 199.816235 -144.997238) (xy 199.81672 -144.986248) (xy 199.81672 -144.72158) (xy 199.816219 -144.710591)
			(xy 199.80714 -144.690579) (xy 199.799194 -144.682972) (xy 199.732138 -144.625314) (xy 199.711056 -144.619218)
			(xy 199.69988 -144.620996) (xy 199.685111 -144.623109) (xy 199.655362 -144.625394) (xy 199.640444 -144.625568)
			(xy 199.6118 -144.625084) (xy 199.555094 -144.616932) (xy 199.500127 -144.60079) (xy 199.448018 -144.576985)
			(xy 199.399831 -144.546003) (xy 199.356545 -144.508475) (xy 199.319045 -144.465166) (xy 199.288093 -144.416958)
			(xy 199.264321 -144.364835) (xy 199.248214 -144.309857) (xy 199.240098 -144.253147) (xy 199.239632 -144.224502)
			(xy 199.240117 -144.195046) (xy 199.24869 -144.136762) (xy 199.265708 -144.080362) (xy 199.290805 -144.027064)
			(xy 199.306688 -144.002252) (xy 199.3138 -143.99133) (xy 199.316086 -143.966184) (xy 199.272398 -143.863822)
			(xy 199.252332 -143.848074) (xy 199.239632 -143.846042) (xy 199.213403 -143.841044) (xy 199.162587 -143.824653)
			(xy 199.114552 -143.801338) (xy 199.070236 -143.771555) (xy 199.030505 -143.735885) (xy 198.996134 -143.695024)
			(xy 198.967795 -143.649771) (xy 198.94604 -143.60101) (xy 198.931296 -143.549692) (xy 198.92385 -143.496819)
			(xy 198.923402 -143.470122) (xy 198.609526 -143.470122) (xy 198.618738 -143.484456) (xy 198.642538 -143.536571)
			(xy 198.658679 -143.591544) (xy 198.666833 -143.648254) (xy 198.666833 -143.705546) (xy 198.658679 -143.762256)
			(xy 198.642538 -143.817229) (xy 198.618738 -143.869344) (xy 198.587763 -143.917542) (xy 198.550244 -143.960842)
			(xy 198.506945 -143.998361) (xy 198.458748 -144.029336) (xy 198.406632 -144.053137) (xy 198.35166 -144.069278)
			(xy 198.29495 -144.077433) (xy 198.266304 -144.077944) (xy 198.238924 -144.077456) (xy 198.184676 -144.06999)
			(xy 198.131948 -144.05521) (xy 198.081723 -144.033391) (xy 198.034935 -144.004939) (xy 197.992455 -143.970384)
			(xy 197.955073 -143.930368) (xy 197.938898 -143.908272) (xy 197.933321 -143.901024) (xy 197.918223 -143.890731)
			(xy 197.909434 -143.888206) (xy 197.879462 -143.88084) (xy 197.870514 -143.879075) (xy 197.852422 -143.881302)
			(xy 197.844156 -143.885158) (xy 197.819565 -143.897566) (xy 197.768035 -143.91703) (xy 197.714543 -143.930173)
			(xy 197.659861 -143.936805) (xy 197.63232 -143.937228) (xy 197.604779 -143.936819) (xy 197.550098 -143.930178)
			(xy 197.496608 -143.917026) (xy 197.445083 -143.897552) (xy 197.420484 -143.885158) (xy 197.412227 -143.881273)
			(xy 197.394128 -143.879061) (xy 197.385178 -143.88084) (xy 197.355206 -143.888206) (xy 197.346431 -143.890767)
			(xy 197.331327 -143.901037) (xy 197.325742 -143.908272) (xy 197.309604 -143.9304) (xy 197.272227 -143.970432)
			(xy 197.229746 -144.004999) (xy 197.182952 -144.033458) (xy 197.132718 -144.055277) (xy 197.079979 -144.07005)
			(xy 197.02572 -144.077502) (xy 196.998336 -144.077944) (xy 196.969683 -144.077504) (xy 196.912959 -144.069353)
			(xy 196.857973 -144.053212) (xy 196.805843 -144.029409) (xy 196.757632 -143.99843) (xy 196.714321 -143.960904)
			(xy 196.676792 -143.917596) (xy 196.645808 -143.869388) (xy 196.622001 -143.817261) (xy 196.605855 -143.762276)
			(xy 196.597699 -143.705553) (xy 196.597699 -143.648247) (xy 196.605855 -143.591524) (xy 196.622001 -143.536539)
			(xy 196.645808 -143.484412) (xy 196.676792 -143.436204) (xy 196.714321 -143.392896) (xy 196.757632 -143.35537)
			(xy 196.805843 -143.324391) (xy 196.857973 -143.300588) (xy 196.912959 -143.284447) (xy 196.969683 -143.276296)
			(xy 196.998336 -143.275812) (xy 197.013254 -143.275983) (xy 197.043003 -143.278271) (xy 197.057772 -143.280384)
			(xy 197.068948 -143.282162) (xy 197.09003 -143.276066) (xy 197.157086 -143.218408) (xy 197.165062 -143.210825)
			(xy 197.174139 -143.190797) (xy 197.174612 -143.1798) (xy 197.174612 -142.915132) (xy 197.17414 -142.904139)
			(xy 197.165041 -142.884128) (xy 197.157086 -142.876524) (xy 197.09003 -142.818866) (xy 197.068948 -142.81277)
			(xy 197.057772 -142.814548) (xy 197.043002 -142.816651) (xy 197.013254 -142.818943) (xy 196.998336 -142.81912)
			(xy 196.969681 -142.818728) (xy 196.912954 -142.810576) (xy 196.857964 -142.794434) (xy 196.805832 -142.77063)
			(xy 196.757618 -142.739649) (xy 196.714304 -142.702121) (xy 196.676773 -142.658811) (xy 196.645787 -142.6106)
			(xy 196.621978 -142.558469) (xy 196.605831 -142.503481) (xy 196.597675 -142.446755) (xy 190.593035 -142.446755)
			(xy 190.570389 -142.465601) (xy 190.522783 -142.494655) (xy 190.471454 -142.516467) (xy 190.417497 -142.530573)
			(xy 190.36206 -142.536673) (xy 190.306326 -142.534636) (xy 190.251483 -142.524506) (xy 190.198699 -142.506499)
			(xy 190.149099 -142.480998) (xy 190.103741 -142.448547) (xy 190.063592 -142.409838) (xy 190.029506 -142.365695)
			(xy 190.00221 -142.31706) (xy 189.982287 -142.264969) (xy 189.970161 -142.210532) (xy 189.96609 -142.15491)
			(xy 188.748416 -142.15491) (xy 188.747907 -142.182796) (xy 188.739787 -142.237972) (xy 188.723719 -142.291379)
			(xy 188.700047 -142.341876) (xy 188.669274 -142.388389) (xy 188.632057 -142.429926) (xy 188.589189 -142.465601)
			(xy 188.541583 -142.494655) (xy 188.490254 -142.516467) (xy 188.436297 -142.530573) (xy 188.38086 -142.536673)
			(xy 188.325126 -142.534636) (xy 188.270283 -142.524506) (xy 188.217499 -142.506499) (xy 188.167899 -142.480998)
			(xy 188.122541 -142.448547) (xy 188.082392 -142.409838) (xy 188.048306 -142.365695) (xy 188.02101 -142.31706)
			(xy 188.001087 -142.264969) (xy 187.988961 -142.210532) (xy 187.98489 -142.15491) (xy 186.129422 -142.15491)
			(xy 186.128913 -142.182796) (xy 186.120793 -142.237972) (xy 186.104725 -142.291379) (xy 186.081053 -142.341876)
			(xy 186.05028 -142.388389) (xy 186.013063 -142.429926) (xy 185.970195 -142.465601) (xy 185.922589 -142.494655)
			(xy 185.87126 -142.516467) (xy 185.817303 -142.530573) (xy 185.761866 -142.536673) (xy 185.706132 -142.534636)
			(xy 185.651289 -142.524506) (xy 185.598505 -142.506499) (xy 185.548905 -142.480998) (xy 185.503547 -142.448547)
			(xy 185.463398 -142.409838) (xy 185.429312 -142.365695) (xy 185.402016 -142.31706) (xy 185.382093 -142.264969)
			(xy 185.369967 -142.210532) (xy 185.365896 -142.15491) (xy 184.148222 -142.15491) (xy 184.147737 -142.182138)
			(xy 184.139993 -142.236041) (xy 184.124662 -142.288295) (xy 184.102058 -142.337838) (xy 184.072639 -142.383663)
			(xy 184.037003 -142.42484) (xy 183.995874 -142.460532) (xy 183.950088 -142.490012) (xy 183.900575 -142.512683)
			(xy 183.848342 -142.528083) (xy 183.794449 -142.5359) (xy 183.767222 -142.536418) (xy 183.766206 -142.536418)
			(xy 183.765698 -142.536418) (xy 183.748909 -142.536246) (xy 183.71546 -142.533319) (xy 183.698896 -142.530576)
			(xy 183.695594 -142.530068) (xy 183.689752 -142.52956) (xy 183.681299 -142.529909) (xy 183.665333 -142.535481)
			(xy 183.65851 -142.540482) (xy 183.651906 -142.546324) (xy 183.632348 -142.563088) (xy 183.624869 -142.570111)
			(xy 183.615713 -142.588451) (xy 183.614568 -142.598648) (xy 183.614822 -142.603728) (xy 183.615076 -142.620746)
			(xy 183.615076 -142.621254) (xy 183.615076 -142.62354) (xy 183.615076 -143.499332) (xy 183.614822 -143.50619)
			(xy 183.614822 -143.514064) (xy 183.616067 -143.522453) (xy 183.623339 -143.537763) (xy 183.629046 -143.544036)
			(xy 183.647842 -143.560292) (xy 183.65851 -143.569436) (xy 183.685019 -143.56247) (xy 183.73931 -143.554953)
			(xy 183.766714 -143.55445) (xy 183.795325 -143.554961) (xy 183.851964 -143.563107) (xy 183.906867 -143.579229)
			(xy 183.958917 -143.603001) (xy 184.007054 -143.633939) (xy 184.032277 -143.655796) (xy 185.46267 -143.655796)
			(xy 185.466741 -143.600174) (xy 185.478867 -143.545737) (xy 185.49879 -143.493646) (xy 185.526086 -143.445011)
			(xy 185.560172 -143.400868) (xy 185.600321 -143.362159) (xy 185.645679 -143.329708) (xy 185.695279 -143.304207)
			(xy 185.748063 -143.2862) (xy 185.802906 -143.27607) (xy 185.85864 -143.274033) (xy 185.914077 -143.280133)
			(xy 185.968034 -143.294239) (xy 186.019363 -143.316051) (xy 186.066969 -143.345105) (xy 186.109837 -143.38078)
			(xy 186.147054 -143.422317) (xy 186.177827 -143.46883) (xy 186.201499 -143.519327) (xy 186.217567 -143.572734)
			(xy 186.225687 -143.62791) (xy 186.226196 -143.655796) (xy 186.225687 -143.683682) (xy 186.217567 -143.738858)
			(xy 186.201499 -143.792265) (xy 186.177827 -143.842762) (xy 186.147054 -143.889275) (xy 186.109837 -143.930812)
			(xy 186.080762 -143.955008) (xy 187.98489 -143.955008) (xy 187.988961 -143.899386) (xy 188.001087 -143.844949)
			(xy 188.02101 -143.792858) (xy 188.048306 -143.744223) (xy 188.082392 -143.70008) (xy 188.122541 -143.661371)
			(xy 188.167899 -143.62892) (xy 188.217499 -143.603419) (xy 188.270283 -143.585412) (xy 188.325126 -143.575282)
			(xy 188.38086 -143.573245) (xy 188.436297 -143.579345) (xy 188.490254 -143.593451) (xy 188.541583 -143.615263)
			(xy 188.589189 -143.644317) (xy 188.632057 -143.679992) (xy 188.669274 -143.721529) (xy 188.700047 -143.768042)
			(xy 188.723719 -143.818539) (xy 188.739787 -143.871946) (xy 188.747907 -143.927122) (xy 188.748416 -143.955008)
			(xy 189.96609 -143.955008) (xy 189.970161 -143.899386) (xy 189.982287 -143.844949) (xy 190.00221 -143.792858)
			(xy 190.029506 -143.744223) (xy 190.063592 -143.70008) (xy 190.103741 -143.661371) (xy 190.149099 -143.62892)
			(xy 190.198699 -143.603419) (xy 190.251483 -143.585412) (xy 190.306326 -143.575282) (xy 190.36206 -143.573245)
			(xy 190.417497 -143.579345) (xy 190.471454 -143.593451) (xy 190.522783 -143.615263) (xy 190.570389 -143.644317)
			(xy 190.613257 -143.679992) (xy 190.650474 -143.721529) (xy 190.681247 -143.768042) (xy 190.704919 -143.818539)
			(xy 190.720987 -143.871946) (xy 190.729107 -143.927122) (xy 190.729616 -143.955008) (xy 190.729107 -143.982894)
			(xy 190.720987 -144.03807) (xy 190.704919 -144.091477) (xy 190.681247 -144.141974) (xy 190.650474 -144.188487)
			(xy 190.613257 -144.230024) (xy 190.570389 -144.265699) (xy 190.522783 -144.294753) (xy 190.471454 -144.316565)
			(xy 190.417497 -144.330671) (xy 190.36206 -144.336771) (xy 190.306326 -144.334734) (xy 190.251483 -144.324604)
			(xy 190.198699 -144.306597) (xy 190.149099 -144.281096) (xy 190.103741 -144.248645) (xy 190.063592 -144.209936)
			(xy 190.029506 -144.165793) (xy 190.00221 -144.117158) (xy 189.982287 -144.065067) (xy 189.970161 -144.01063)
			(xy 189.96609 -143.955008) (xy 188.748416 -143.955008) (xy 188.747907 -143.982894) (xy 188.739787 -144.03807)
			(xy 188.723719 -144.091477) (xy 188.700047 -144.141974) (xy 188.669274 -144.188487) (xy 188.632057 -144.230024)
			(xy 188.589189 -144.265699) (xy 188.541583 -144.294753) (xy 188.490254 -144.316565) (xy 188.436297 -144.330671)
			(xy 188.38086 -144.336771) (xy 188.325126 -144.334734) (xy 188.270283 -144.324604) (xy 188.217499 -144.306597)
			(xy 188.167899 -144.281096) (xy 188.122541 -144.248645) (xy 188.082392 -144.209936) (xy 188.048306 -144.165793)
			(xy 188.02101 -144.117158) (xy 188.001087 -144.065067) (xy 187.988961 -144.01063) (xy 187.98489 -143.955008)
			(xy 186.080762 -143.955008) (xy 186.066969 -143.966487) (xy 186.019363 -143.995541) (xy 185.968034 -144.017353)
			(xy 185.914077 -144.031459) (xy 185.85864 -144.037559) (xy 185.802906 -144.035522) (xy 185.748063 -144.025392)
			(xy 185.695279 -144.007385) (xy 185.645679 -143.981884) (xy 185.600321 -143.949433) (xy 185.560172 -143.910724)
			(xy 185.526086 -143.866581) (xy 185.49879 -143.817946) (xy 185.478867 -143.765855) (xy 185.466741 -143.711418)
			(xy 185.46267 -143.655796) (xy 184.032277 -143.655796) (xy 184.050298 -143.671412) (xy 184.08777 -143.714657)
			(xy 184.118705 -143.762796) (xy 184.142476 -143.814846) (xy 184.158596 -143.86975) (xy 184.16674 -143.926389)
			(xy 184.16674 -143.983611) (xy 184.158596 -144.04025) (xy 184.142476 -144.095154) (xy 184.118705 -144.147204)
			(xy 184.08777 -144.195343) (xy 184.050298 -144.238588) (xy 184.007054 -144.276061) (xy 183.958917 -144.306999)
			(xy 183.906867 -144.330771) (xy 183.851964 -144.346893) (xy 183.795325 -144.355039) (xy 183.766714 -144.355566)
			(xy 183.738144 -144.35506) (xy 183.681583 -144.346944) (xy 183.626748 -144.330875) (xy 183.574753 -144.307178)
			(xy 183.526652 -144.276335) (xy 183.483421 -144.238971) (xy 183.445936 -144.195844) (xy 183.414959 -144.147829)
			(xy 183.391117 -144.0959) (xy 183.374895 -144.04111) (xy 183.37022 -144.01292) (xy 183.368696 -144.002506)
			(xy 183.35244 -143.97609) (xy 183.349404 -143.971471) (xy 183.341715 -143.963532) (xy 183.3372 -143.960342)
			(xy 183.329834 -143.955262) (xy 183.302402 -143.937228) (xy 183.29509 -143.933365) (xy 183.278886 -143.930119)
			(xy 183.270652 -143.930878) (xy 183.265572 -143.932148) (xy 183.251872 -143.935368) (xy 183.224166 -143.940324)
			(xy 183.2102 -143.942054) (xy 183.208676 -143.942054) (xy 183.20385 -143.942562) (xy 183.203342 -143.942562)
			(xy 183.191879 -143.943642) (xy 183.168881 -143.944787) (xy 183.157368 -143.944848) (xy 183.133962 -143.944595)
			(xy 183.087387 -143.93989) (xy 183.064404 -143.93545) (xy 183.054498 -143.933418) (xy 183.043068 -143.935704)
			(xy 183.036718 -143.937736) (xy 183.03621 -143.937736) (xy 183.026558 -143.942562) (xy 182.970932 -143.980916)
			(xy 182.961534 -143.990314) (xy 182.96128 -143.990822) (xy 182.960772 -143.991584) (xy 182.943754 -144.018254)
			(xy 182.941976 -144.027906) (xy 182.936451 -144.055188) (xy 182.918859 -144.108) (xy 182.894129 -144.157868)
			(xy 182.862734 -144.203834) (xy 182.82528 -144.245013) (xy 182.782488 -144.280612) (xy 182.73518 -144.309946)
			(xy 182.684268 -144.33245) (xy 182.630731 -144.347692) (xy 182.5756 -144.355377) (xy 182.547768 -144.35582)
			(xy 182.547514 -144.35582) (xy 182.519025 -144.355326) (xy 182.46262 -144.347263) (xy 182.407928 -144.331284)
			(xy 182.356054 -144.307711) (xy 182.308047 -144.277021) (xy 182.286148 -144.258792) (xy 182.279544 -144.253204)
			(xy 182.253128 -144.24279) (xy 182.249302 -144.241591) (xy 182.241389 -144.24031) (xy 182.23738 -144.24025)
			(xy 182.223156 -144.24025) (xy 182.219152 -144.240359) (xy 182.211246 -144.241641) (xy 182.207408 -144.24279)
			(xy 182.180992 -144.253204) (xy 182.174388 -144.258792) (xy 182.152465 -144.276988) (xy 182.10445 -144.307654)
			(xy 182.052581 -144.331221) (xy 181.997901 -144.347217) (xy 181.941508 -144.355319) (xy 181.913022 -144.35582)
			(xy 181.912768 -144.35582) (xy 181.9024 -144.355779) (xy 181.881688 -144.354763) (xy 181.871366 -144.353788)
			(xy 181.870858 -144.353788) (xy 181.863746 -144.353026) (xy 181.862984 -144.353026) (xy 181.861968 -144.352772)
			(xy 181.86146 -144.352772) (xy 181.860444 -144.352518) (xy 181.858158 -144.352264) (xy 181.857142 -144.352264)
			(xy 181.850538 -144.351248) (xy 181.849776 -144.350994) (xy 181.849268 -144.350994) (xy 181.844696 -144.350232)
			(xy 181.842918 -144.349978) (xy 181.832432 -144.349063) (xy 181.812214 -144.354829) (xy 181.803802 -144.361154)
			(xy 181.79161 -144.371568) (xy 181.791102 -144.372076) (xy 181.778402 -144.38249) (xy 181.776624 -144.384268)
			(xy 181.774846 -144.3863) (xy 181.77256 -144.38884) (xy 181.772052 -144.389348) (xy 181.767192 -144.395903)
			(xy 181.761491 -144.411183) (xy 181.760876 -144.41932) (xy 181.760876 -144.421606) (xy 181.760876 -144.423638)
			(xy 181.760876 -144.681702) (xy 181.761049 -144.68771) (xy 181.763882 -144.699387) (xy 181.766464 -144.704816)
			(xy 181.768302 -144.708291) (xy 181.772893 -144.714673) (xy 181.775608 -144.717516) (xy 182.409084 -145.350992)
			(xy 182.414261 -145.355807) (xy 182.426636 -145.362634) (xy 182.433468 -145.364454) (xy 182.45582 -145.364454)
			(xy 182.46471 -145.362422) (xy 182.465472 -145.362168) (xy 182.466742 -145.361914) (xy 182.467504 -145.361914)
			(xy 182.47233 -145.360898) (xy 182.494682 -145.357342) (xy 182.496714 -145.357088) (xy 182.498492 -145.356834)
			(xy 182.505604 -145.356072) (xy 182.506112 -145.356072) (xy 182.508398 -145.355818) (xy 182.508652 -145.355818)
			(xy 182.544974 -145.35404) (xy 182.547514 -145.35404) (xy 182.552848 -145.353786) (xy 182.580923 -145.354611)
			(xy 182.636436 -145.363149) (xy 182.690214 -145.379351) (xy 182.741204 -145.4029) (xy 182.788409 -145.433335)
			(xy 182.830905 -145.47006) (xy 182.867859 -145.512356) (xy 182.898549 -145.559396) (xy 182.922373 -145.610258)
			(xy 182.938866 -145.663948) (xy 182.943754 -145.691606) (xy 182.945278 -145.702274) (xy 182.950866 -145.711164)
			(xy 182.953731 -145.715457) (xy 182.960903 -145.722877) (xy 182.96509 -145.725896) (xy 182.994808 -145.746724)
			(xy 182.995316 -145.746724) (xy 183.02732 -145.768822) (xy 183.035761 -145.773598) (xy 183.054837 -145.77701)
			(xy 183.064404 -145.775426) (xy 183.065674 -145.775172) (xy 183.066182 -145.774918) (xy 183.066436 -145.774918)
			(xy 183.067452 -145.774664) (xy 183.067706 -145.774664) (xy 183.070754 -145.774156) (xy 183.071516 -145.773902)
			(xy 183.078628 -145.772632) (xy 183.079136 -145.772632) (xy 183.0832 -145.77187) (xy 183.085994 -145.771362)
			(xy 183.086502 -145.771362) (xy 183.093106 -145.770346) (xy 183.095138 -145.770092) (xy 183.098694 -145.769584)
			(xy 183.104536 -145.768822) (xy 183.105044 -145.768822) (xy 183.1086 -145.768314) (xy 183.109616 -145.768314)
			(xy 183.116982 -145.767552) (xy 183.126888 -145.76679) (xy 183.128412 -145.76679) (xy 183.15305 -145.766028)
			(xy 183.157368 -145.766028) (xy 183.157622 -145.766028) (xy 183.158384 -145.766028) (xy 183.16194 -145.766028)
			(xy 183.168798 -145.766028) (xy 183.17845 -145.766282) (xy 183.178958 -145.766282) (xy 183.200548 -145.767806)
			(xy 183.202834 -145.76806) (xy 183.203342 -145.76806) (xy 183.208168 -145.768568) (xy 183.209692 -145.768822)
			(xy 183.221884 -145.770346) (xy 183.234053 -145.772127) (xy 183.258196 -145.776828) (xy 183.270144 -145.779744)
			(xy 183.27243 -145.780252) (xy 183.273446 -145.780506) (xy 183.27624 -145.781268) (xy 183.285638 -145.77949)
			(xy 183.290769 -145.778472) (xy 183.300498 -145.774631) (xy 183.304942 -145.77187) (xy 183.363362 -145.733008)
			(xy 183.369458 -145.728944) (xy 183.373227 -145.726132) (xy 183.379738 -145.71935) (xy 183.382412 -145.715482)
			(xy 183.388 -145.7071) (xy 183.389778 -145.69567) (xy 183.394441 -145.669075) (xy 183.410279 -145.617458)
			(xy 183.433239 -145.56859) (xy 183.462863 -145.523449) (xy 183.498557 -145.482938) (xy 183.539608 -145.447866)
			(xy 183.585195 -145.418935) (xy 183.634407 -145.396723) (xy 183.68626 -145.381673) (xy 183.739717 -145.374088)
			(xy 183.766714 -145.373598) (xy 183.793964 -145.374085) (xy 183.84791 -145.381843) (xy 183.900203 -145.397199)
			(xy 183.949778 -145.419841) (xy 183.995626 -145.449308) (xy 184.036814 -145.485) (xy 184.072504 -145.52619)
			(xy 184.101968 -145.572039) (xy 184.124608 -145.621616) (xy 184.139961 -145.673909) (xy 184.147717 -145.727856)
			(xy 184.148222 -145.755106) (xy 184.147737 -145.782334) (xy 184.139993 -145.836237) (xy 184.126612 -145.881852)
			(xy 185.373008 -145.881852) (xy 185.377079 -145.82623) (xy 185.389205 -145.771793) (xy 185.409128 -145.719702)
			(xy 185.436424 -145.671067) (xy 185.47051 -145.626924) (xy 185.510659 -145.588215) (xy 185.556017 -145.555764)
			(xy 185.605617 -145.530263) (xy 185.658401 -145.512256) (xy 185.713244 -145.502126) (xy 185.768978 -145.500089)
			(xy 185.824415 -145.506189) (xy 185.878372 -145.520295) (xy 185.929701 -145.542107) (xy 185.977307 -145.571161)
			(xy 186.020175 -145.606836) (xy 186.057392 -145.648373) (xy 186.088165 -145.694886) (xy 186.111837 -145.745383)
			(xy 186.114762 -145.755106) (xy 187.98489 -145.755106) (xy 187.988961 -145.699484) (xy 188.001087 -145.645047)
			(xy 188.02101 -145.592956) (xy 188.048306 -145.544321) (xy 188.082392 -145.500178) (xy 188.122541 -145.461469)
			(xy 188.167899 -145.429018) (xy 188.217499 -145.403517) (xy 188.270283 -145.38551) (xy 188.325126 -145.37538)
			(xy 188.38086 -145.373343) (xy 188.436297 -145.379443) (xy 188.490254 -145.393549) (xy 188.541583 -145.415361)
			(xy 188.589189 -145.444415) (xy 188.632057 -145.48009) (xy 188.669274 -145.521627) (xy 188.700047 -145.56814)
			(xy 188.723719 -145.618637) (xy 188.739787 -145.672044) (xy 188.747907 -145.72722) (xy 188.748416 -145.755106)
			(xy 189.96609 -145.755106) (xy 189.970161 -145.699484) (xy 189.982287 -145.645047) (xy 190.00221 -145.592956)
			(xy 190.029506 -145.544321) (xy 190.063592 -145.500178) (xy 190.103741 -145.461469) (xy 190.149099 -145.429018)
			(xy 190.198699 -145.403517) (xy 190.251483 -145.38551) (xy 190.306326 -145.37538) (xy 190.36206 -145.373343)
			(xy 190.417497 -145.379443) (xy 190.471454 -145.393549) (xy 190.522783 -145.415361) (xy 190.570389 -145.444415)
			(xy 190.613257 -145.48009) (xy 190.650474 -145.521627) (xy 190.681247 -145.56814) (xy 190.704919 -145.618637)
			(xy 190.720987 -145.672044) (xy 190.729107 -145.72722) (xy 190.729616 -145.755106) (xy 190.729107 -145.782992)
			(xy 190.720987 -145.838168) (xy 190.704919 -145.891575) (xy 190.681247 -145.942072) (xy 190.650474 -145.988585)
			(xy 190.613257 -146.030122) (xy 190.593416 -146.046634) (xy 196.597971 -146.046634) (xy 196.597971 -145.989366)
			(xy 196.606121 -145.932682) (xy 196.622256 -145.877734) (xy 196.646047 -145.825642) (xy 196.67701 -145.777467)
			(xy 196.714514 -145.734189) (xy 196.757796 -145.696688) (xy 196.805974 -145.66573) (xy 196.858068 -145.641944)
			(xy 196.913017 -145.625814) (xy 196.969702 -145.617668) (xy 196.998336 -145.617184) (xy 197.025708 -145.6176)
			(xy 197.079943 -145.625051) (xy 197.132661 -145.63981) (xy 197.182881 -145.661602) (xy 197.22967 -145.690023)
			(xy 197.272158 -145.724544) (xy 197.309556 -145.764523) (xy 197.325742 -145.786602) (xy 197.33129 -145.793875)
			(xy 197.34641 -145.804152) (xy 197.355206 -145.806668) (xy 197.385178 -145.814034) (xy 197.39413 -145.815771)
			(xy 197.412217 -145.813563) (xy 197.420484 -145.809716) (xy 197.445088 -145.797352) (xy 197.496624 -145.777953)
			(xy 197.550114 -145.764871) (xy 197.604787 -145.758296) (xy 197.63232 -145.7579) (xy 197.659854 -145.758291)
			(xy 197.714528 -145.764857) (xy 197.768019 -145.77794) (xy 197.819551 -145.797351) (xy 197.844156 -145.809716)
			(xy 197.852424 -145.813572) (xy 197.870513 -145.8158) (xy 197.879462 -145.814034) (xy 197.909434 -145.806668)
			(xy 197.918217 -145.80413) (xy 197.933317 -145.793844) (xy 197.938898 -145.786602) (xy 197.955071 -145.764516)
			(xy 197.992476 -145.724547) (xy 198.03497 -145.690037) (xy 198.081762 -145.661627) (xy 198.131983 -145.639844)
			(xy 198.1847 -145.625093) (xy 198.238933 -145.617649) (xy 198.266304 -145.617184) (xy 198.294934 -145.617703)
			(xy 198.35161 -145.625852) (xy 198.40655 -145.641984) (xy 198.458635 -145.665771) (xy 198.506804 -145.696728)
			(xy 198.550078 -145.734225) (xy 198.587574 -145.777499) (xy 198.618531 -145.825669) (xy 198.642317 -145.877754)
			(xy 198.647697 -145.896076) (xy 230.510078 -145.896076) (xy 230.514149 -145.840454) (xy 230.526275 -145.786017)
			(xy 230.546198 -145.733926) (xy 230.573494 -145.685291) (xy 230.60758 -145.641148) (xy 230.647729 -145.602439)
			(xy 230.693087 -145.569988) (xy 230.742687 -145.544487) (xy 230.795471 -145.52648) (xy 230.850314 -145.51635)
			(xy 230.906048 -145.514313) (xy 230.961485 -145.520413) (xy 231.015442 -145.534519) (xy 231.066771 -145.556331)
			(xy 231.077446 -145.562846) (xy 248.178628 -145.562846) (xy 248.178628 -145.508354) (xy 248.186383 -145.454415)
			(xy 248.201735 -145.402129) (xy 248.224371 -145.352561) (xy 248.253831 -145.306717) (xy 248.289515 -145.265533)
			(xy 248.330697 -145.229846) (xy 248.376538 -145.200383) (xy 248.426105 -145.177744) (xy 248.47839 -145.162388)
			(xy 248.532328 -145.15463) (xy 248.559574 -145.154142) (xy 248.585915 -145.154594) (xy 248.638096 -145.161847)
			(xy 248.688784 -145.176203) (xy 248.737017 -145.197392) (xy 248.78188 -145.22501) (xy 248.822521 -145.258533)
			(xy 248.858167 -145.297324) (xy 248.873518 -145.318734) (xy 248.882191 -145.330578) (xy 248.90502 -145.34902)
			(xy 248.932151 -145.360206) (xy 248.961344 -145.363213) (xy 248.990186 -145.357792) (xy 249.016294 -145.344391)
			(xy 249.037512 -145.324116) (xy 249.045222 -145.311622) (xy 249.059904 -145.287078) (xy 249.095508 -145.24232)
			(xy 249.137394 -145.203377) (xy 249.184622 -145.171122) (xy 249.236136 -145.146277) (xy 249.290782 -145.1294)
			(xy 249.347334 -145.120868) (xy 249.37593 -145.12036) (xy 249.403178 -145.120912) (xy 249.457117 -145.128672)
			(xy 249.509404 -145.144028) (xy 249.558973 -145.166669) (xy 249.604816 -145.196134) (xy 249.645999 -145.231822)
			(xy 249.681684 -145.273008) (xy 249.711145 -145.318853) (xy 249.733783 -145.368424) (xy 249.749135 -145.420712)
			(xy 249.75689 -145.474652) (xy 249.75689 -145.529148) (xy 249.749135 -145.583088) (xy 249.733783 -145.635376)
			(xy 249.711145 -145.684947) (xy 249.681684 -145.730792) (xy 249.645999 -145.771978) (xy 249.604816 -145.807666)
			(xy 249.558973 -145.837131) (xy 249.509404 -145.859772) (xy 249.457117 -145.875128) (xy 249.403178 -145.882888)
			(xy 249.37593 -145.883376) (xy 249.349589 -145.882913) (xy 249.29741 -145.875661) (xy 249.246722 -145.861306)
			(xy 249.198489 -145.840119) (xy 249.153626 -145.812503) (xy 249.112985 -145.778982) (xy 249.077338 -145.740193)
			(xy 249.061986 -145.718784) (xy 249.053299 -145.706956) (xy 249.030469 -145.68853) (xy 249.003343 -145.677354)
			(xy 248.974159 -145.67435) (xy 248.945325 -145.679765) (xy 248.91922 -145.693154) (xy 248.897997 -145.71341)
			(xy 248.890282 -145.725896) (xy 248.875603 -145.750442) (xy 248.839998 -145.7952) (xy 248.798112 -145.834142)
			(xy 248.750883 -145.866396) (xy 248.699368 -145.891241) (xy 248.644723 -145.908118) (xy 248.58817 -145.91665)
			(xy 248.559574 -145.917158) (xy 248.532328 -145.91657) (xy 248.47839 -145.908812) (xy 248.426105 -145.893456)
			(xy 248.376538 -145.870817) (xy 248.330697 -145.841354) (xy 248.289515 -145.805667) (xy 248.253831 -145.764483)
			(xy 248.224371 -145.718639) (xy 248.201735 -145.669071) (xy 248.186383 -145.616785) (xy 248.178628 -145.562846)
			(xy 231.077446 -145.562846) (xy 231.114377 -145.585385) (xy 231.157245 -145.62106) (xy 231.194462 -145.662597)
			(xy 231.225235 -145.70911) (xy 231.248907 -145.759607) (xy 231.264975 -145.813014) (xy 231.273095 -145.86819)
			(xy 231.273604 -145.896076) (xy 231.273095 -145.923962) (xy 231.264975 -145.979138) (xy 231.248907 -146.032545)
			(xy 231.225235 -146.083042) (xy 231.194462 -146.129555) (xy 231.157245 -146.171092) (xy 231.114377 -146.206767)
			(xy 231.066771 -146.235821) (xy 231.015442 -146.257633) (xy 230.961485 -146.271739) (xy 230.906048 -146.277839)
			(xy 230.850314 -146.275802) (xy 230.795471 -146.265672) (xy 230.742687 -146.247665) (xy 230.693087 -146.222164)
			(xy 230.647729 -146.189713) (xy 230.60758 -146.151004) (xy 230.573494 -146.106861) (xy 230.546198 -146.058226)
			(xy 230.526275 -146.006135) (xy 230.514149 -145.951698) (xy 230.510078 -145.896076) (xy 198.647697 -145.896076)
			(xy 198.658449 -145.932694) (xy 198.666597 -145.98937) (xy 198.666597 -146.04663) (xy 198.658449 -146.103306)
			(xy 198.642317 -146.158246) (xy 198.618531 -146.210331) (xy 198.587574 -146.258501) (xy 198.550078 -146.301775)
			(xy 198.506804 -146.339272) (xy 198.458635 -146.370229) (xy 198.40655 -146.394016) (xy 198.35161 -146.410148)
			(xy 198.294934 -146.418297) (xy 198.266304 -146.418808) (xy 198.25139 -146.418704) (xy 198.221641 -146.416539)
			(xy 198.206868 -146.41449) (xy 198.195692 -146.412712) (xy 198.17461 -146.418808) (xy 198.107554 -146.476466)
			(xy 198.099596 -146.484066) (xy 198.090508 -146.504081) (xy 198.090028 -146.515074) (xy 198.090028 -146.779742)
			(xy 198.090501 -146.790735) (xy 198.099598 -146.810747) (xy 198.107554 -146.81835) (xy 198.17461 -146.876008)
			(xy 198.195692 -146.882104) (xy 198.206868 -146.880326) (xy 198.221641 -146.878275) (xy 198.25139 -146.876116)
			(xy 198.266304 -146.876008) (xy 198.294935 -146.876479) (xy 198.351615 -146.884629) (xy 198.406558 -146.900762)
			(xy 198.458646 -146.92455) (xy 198.506818 -146.955509) (xy 198.547271 -146.990562) (xy 219.859604 -146.990562)
			(xy 219.863675 -146.93494) (xy 219.875801 -146.880503) (xy 219.895724 -146.828412) (xy 219.92302 -146.779777)
			(xy 219.957106 -146.735634) (xy 219.997255 -146.696925) (xy 220.042613 -146.664474) (xy 220.092213 -146.638973)
			(xy 220.144997 -146.620966) (xy 220.19984 -146.610836) (xy 220.255574 -146.608799) (xy 220.311011 -146.614899)
			(xy 220.364968 -146.629005) (xy 220.416297 -146.650817) (xy 220.463903 -146.679871) (xy 220.506771 -146.715546)
			(xy 220.543988 -146.757083) (xy 220.574761 -146.803596) (xy 220.598433 -146.854093) (xy 220.614501 -146.9075)
			(xy 220.622621 -146.962676) (xy 220.62313 -146.990562) (xy 221.941642 -146.990562) (xy 221.945713 -146.93494)
			(xy 221.957839 -146.880503) (xy 221.977762 -146.828412) (xy 222.005058 -146.779777) (xy 222.039144 -146.735634)
			(xy 222.079293 -146.696925) (xy 222.124651 -146.664474) (xy 222.174251 -146.638973) (xy 222.227035 -146.620966)
			(xy 222.281878 -146.610836) (xy 222.337612 -146.608799) (xy 222.393049 -146.614899) (xy 222.447006 -146.629005)
			(xy 222.48852 -146.646646) (xy 223.425256 -146.646646) (xy 223.429327 -146.591024) (xy 223.441453 -146.536587)
			(xy 223.461376 -146.484496) (xy 223.488672 -146.435861) (xy 223.522758 -146.391718) (xy 223.562907 -146.353009)
			(xy 223.608265 -146.320558) (xy 223.657865 -146.295057) (xy 223.710649 -146.27705) (xy 223.765492 -146.26692)
			(xy 223.821226 -146.264883) (xy 223.876663 -146.270983) (xy 223.93062 -146.285089) (xy 223.981949 -146.306901)
			(xy 224.029555 -146.335955) (xy 224.072423 -146.37163) (xy 224.10964 -146.413167) (xy 224.140413 -146.45968)
			(xy 224.164085 -146.510177) (xy 224.180153 -146.563584) (xy 224.188273 -146.61876) (xy 224.188782 -146.646646)
			(xy 224.188273 -146.674532) (xy 224.180153 -146.729708) (xy 224.164085 -146.783115) (xy 224.140413 -146.833612)
			(xy 224.10964 -146.880125) (xy 224.072423 -146.921662) (xy 224.029555 -146.957337) (xy 223.981949 -146.986391)
			(xy 223.93062 -147.008203) (xy 223.876663 -147.022309) (xy 223.821226 -147.028409) (xy 223.765492 -147.026372)
			(xy 223.710649 -147.016242) (xy 223.657865 -146.998235) (xy 223.608265 -146.972734) (xy 223.562907 -146.940283)
			(xy 223.522758 -146.901574) (xy 223.488672 -146.857431) (xy 223.461376 -146.808796) (xy 223.441453 -146.756705)
			(xy 223.429327 -146.702268) (xy 223.425256 -146.646646) (xy 222.48852 -146.646646) (xy 222.498335 -146.650817)
			(xy 222.545941 -146.679871) (xy 222.588809 -146.715546) (xy 222.626026 -146.757083) (xy 222.656799 -146.803596)
			(xy 222.680471 -146.854093) (xy 222.696539 -146.9075) (xy 222.704659 -146.962676) (xy 222.705168 -146.990562)
			(xy 222.704659 -147.018448) (xy 222.696539 -147.073624) (xy 222.680471 -147.127031) (xy 222.656799 -147.177528)
			(xy 222.626026 -147.224041) (xy 222.588809 -147.265578) (xy 222.588119 -147.266152) (xy 225.921568 -147.266152)
			(xy 225.925639 -147.21053) (xy 225.937765 -147.156093) (xy 225.957688 -147.104002) (xy 225.984984 -147.055367)
			(xy 226.01907 -147.011224) (xy 226.059219 -146.972515) (xy 226.104577 -146.940064) (xy 226.154177 -146.914563)
			(xy 226.206961 -146.896556) (xy 226.261804 -146.886426) (xy 226.317538 -146.884389) (xy 226.372975 -146.890489)
			(xy 226.426932 -146.904595) (xy 226.444537 -146.912076) (xy 230.510078 -146.912076) (xy 230.514149 -146.856454)
			(xy 230.526275 -146.802017) (xy 230.546198 -146.749926) (xy 230.573494 -146.701291) (xy 230.60758 -146.657148)
			(xy 230.647729 -146.618439) (xy 230.693087 -146.585988) (xy 230.742687 -146.560487) (xy 230.795471 -146.54248)
			(xy 230.850314 -146.53235) (xy 230.906048 -146.530313) (xy 230.961485 -146.536413) (xy 231.015442 -146.550519)
			(xy 231.066771 -146.572331) (xy 231.114377 -146.601385) (xy 231.157245 -146.63706) (xy 231.194462 -146.678597)
			(xy 231.225235 -146.72511) (xy 231.248907 -146.775607) (xy 231.264975 -146.829014) (xy 231.273095 -146.88419)
			(xy 231.273604 -146.912076) (xy 231.273095 -146.939962) (xy 231.264975 -146.995138) (xy 231.248907 -147.048545)
			(xy 231.225235 -147.099042) (xy 231.194462 -147.145555) (xy 231.157245 -147.187092) (xy 231.154654 -147.189248)
			(xy 233.05469 -147.189248) (xy 233.05469 -147.134752) (xy 233.062445 -147.08081) (xy 233.077797 -147.028521)
			(xy 233.100434 -146.978948) (xy 233.129895 -146.933102) (xy 233.16558 -146.891914) (xy 233.206763 -146.856224)
			(xy 233.252606 -146.826757) (xy 233.302176 -146.804114) (xy 233.354463 -146.788755) (xy 233.408404 -146.780994)
			(xy 233.435652 -146.780504) (xy 233.467273 -146.781113) (xy 233.529646 -146.791567) (xy 233.589436 -146.812179)
			(xy 233.617516 -146.826732) (xy 233.625869 -146.830746) (xy 233.644237 -146.833091) (xy 233.65333 -146.831304)
			(xy 233.728514 -146.813524) (xy 233.744262 -146.802856) (xy 233.749342 -146.795236) (xy 233.764731 -146.773932)
			(xy 233.80036 -146.735302) (xy 233.840952 -146.701925) (xy 233.885739 -146.674433) (xy 233.933874 -146.653344)
			(xy 233.984447 -146.639058) (xy 234.036502 -146.631846) (xy 234.062778 -146.631406) (xy 234.090033 -146.631839)
			(xy 234.143988 -146.639594) (xy 234.196291 -146.654949) (xy 234.245876 -146.677591) (xy 234.291733 -146.707059)
			(xy 234.33293 -146.742754) (xy 234.368627 -146.783949) (xy 234.398099 -146.829805) (xy 234.420743 -146.879389)
			(xy 234.436101 -146.93169) (xy 234.443859 -146.985645) (xy 234.443859 -147.040155) (xy 234.436101 -147.09411)
			(xy 234.420743 -147.146411) (xy 234.402367 -147.18665) (xy 250.037344 -147.18665) (xy 250.041415 -147.131028)
			(xy 250.053541 -147.076591) (xy 250.073464 -147.0245) (xy 250.10076 -146.975865) (xy 250.134846 -146.931722)
			(xy 250.174995 -146.893013) (xy 250.220353 -146.860562) (xy 250.269953 -146.835061) (xy 250.322737 -146.817054)
			(xy 250.37758 -146.806924) (xy 250.433314 -146.804887) (xy 250.488751 -146.810987) (xy 250.542708 -146.825093)
			(xy 250.594037 -146.846905) (xy 250.641643 -146.875959) (xy 250.684511 -146.911634) (xy 250.68741 -146.91487)
			(xy 251.816106 -146.91487) (xy 251.820177 -146.859248) (xy 251.832303 -146.804811) (xy 251.852226 -146.75272)
			(xy 251.879522 -146.704085) (xy 251.913608 -146.659942) (xy 251.953757 -146.621233) (xy 251.999115 -146.588782)
			(xy 252.048715 -146.563281) (xy 252.101499 -146.545274) (xy 252.156342 -146.535144) (xy 252.212076 -146.533107)
			(xy 252.267513 -146.539207) (xy 252.32147 -146.553313) (xy 252.372799 -146.575125) (xy 252.420405 -146.604179)
			(xy 252.463273 -146.639854) (xy 252.50049 -146.681391) (xy 252.531263 -146.727904) (xy 252.554935 -146.778401)
			(xy 252.571003 -146.831808) (xy 252.579123 -146.886984) (xy 252.579632 -146.91487) (xy 252.579123 -146.942756)
			(xy 252.571003 -146.997932) (xy 252.554935 -147.051339) (xy 252.549729 -147.062444) (xy 253.19431 -147.062444)
			(xy 253.198381 -147.006822) (xy 253.210507 -146.952385) (xy 253.23043 -146.900294) (xy 253.257726 -146.851659)
			(xy 253.291812 -146.807516) (xy 253.331961 -146.768807) (xy 253.377319 -146.736356) (xy 253.426919 -146.710855)
			(xy 253.479703 -146.692848) (xy 253.534546 -146.682718) (xy 253.59028 -146.680681) (xy 253.645717 -146.686781)
			(xy 253.699674 -146.700887) (xy 253.751003 -146.722699) (xy 253.798609 -146.751753) (xy 253.841477 -146.787428)
			(xy 253.878694 -146.828965) (xy 253.909467 -146.875478) (xy 253.933139 -146.925975) (xy 253.949207 -146.979382)
			(xy 253.957327 -147.034558) (xy 253.957836 -147.062444) (xy 253.957327 -147.09033) (xy 253.949207 -147.145506)
			(xy 253.933139 -147.198913) (xy 253.909467 -147.24941) (xy 253.878694 -147.295923) (xy 253.841477 -147.33746)
			(xy 253.798609 -147.373135) (xy 253.751003 -147.402189) (xy 253.699674 -147.424001) (xy 253.645717 -147.438107)
			(xy 253.59028 -147.444207) (xy 253.534546 -147.44217) (xy 253.479703 -147.43204) (xy 253.426919 -147.414033)
			(xy 253.377319 -147.388532) (xy 253.331961 -147.356081) (xy 253.291812 -147.317372) (xy 253.257726 -147.273229)
			(xy 253.23043 -147.224594) (xy 253.210507 -147.172503) (xy 253.198381 -147.118066) (xy 253.19431 -147.062444)
			(xy 252.549729 -147.062444) (xy 252.531263 -147.101836) (xy 252.50049 -147.148349) (xy 252.463273 -147.189886)
			(xy 252.420405 -147.225561) (xy 252.372799 -147.254615) (xy 252.32147 -147.276427) (xy 252.267513 -147.290533)
			(xy 252.212076 -147.296633) (xy 252.156342 -147.294596) (xy 252.101499 -147.284466) (xy 252.048715 -147.266459)
			(xy 251.999115 -147.240958) (xy 251.953757 -147.208507) (xy 251.913608 -147.169798) (xy 251.879522 -147.125655)
			(xy 251.852226 -147.07702) (xy 251.832303 -147.024929) (xy 251.820177 -146.970492) (xy 251.816106 -146.91487)
			(xy 250.68741 -146.91487) (xy 250.721728 -146.953171) (xy 250.752501 -146.999684) (xy 250.776173 -147.050181)
			(xy 250.792241 -147.103588) (xy 250.800361 -147.158764) (xy 250.80087 -147.18665) (xy 250.800361 -147.214536)
			(xy 250.792241 -147.269712) (xy 250.776173 -147.323119) (xy 250.752501 -147.373616) (xy 250.721728 -147.420129)
			(xy 250.684511 -147.461666) (xy 250.641643 -147.497341) (xy 250.594037 -147.526395) (xy 250.542708 -147.548207)
			(xy 250.488751 -147.562313) (xy 250.433314 -147.568413) (xy 250.37758 -147.566376) (xy 250.322737 -147.556246)
			(xy 250.269953 -147.538239) (xy 250.220353 -147.512738) (xy 250.174995 -147.480287) (xy 250.134846 -147.441578)
			(xy 250.10076 -147.397435) (xy 250.073464 -147.3488) (xy 250.053541 -147.296709) (xy 250.041415 -147.242272)
			(xy 250.037344 -147.18665) (xy 234.402367 -147.18665) (xy 234.398099 -147.195995) (xy 234.368627 -147.241851)
			(xy 234.33293 -147.283046) (xy 234.291733 -147.318741) (xy 234.245876 -147.348209) (xy 234.196291 -147.370851)
			(xy 234.143988 -147.386206) (xy 234.090033 -147.393961) (xy 234.062778 -147.394422) (xy 234.031157 -147.393809)
			(xy 233.968784 -147.383359) (xy 233.908994 -147.362748) (xy 233.880914 -147.348194) (xy 233.872555 -147.344195)
			(xy 233.854192 -147.34184) (xy 233.8451 -147.343622) (xy 233.769916 -147.361402) (xy 233.754168 -147.37207)
			(xy 233.749088 -147.37969) (xy 233.733751 -147.401032) (xy 233.698112 -147.43966) (xy 233.657511 -147.473033)
			(xy 233.612715 -147.500521) (xy 233.564572 -147.521603) (xy 233.513991 -147.535881) (xy 233.461931 -147.543085)
			(xy 233.435652 -147.54352) (xy 233.408404 -147.543006) (xy 233.354463 -147.535245) (xy 233.302176 -147.519886)
			(xy 233.252606 -147.497243) (xy 233.206763 -147.467776) (xy 233.16558 -147.432086) (xy 233.129895 -147.390898)
			(xy 233.100434 -147.345052) (xy 233.077797 -147.295479) (xy 233.062445 -147.24319) (xy 233.05469 -147.189248)
			(xy 231.154654 -147.189248) (xy 231.114377 -147.222767) (xy 231.066771 -147.251821) (xy 231.015442 -147.273633)
			(xy 230.961485 -147.287739) (xy 230.906048 -147.293839) (xy 230.850314 -147.291802) (xy 230.795471 -147.281672)
			(xy 230.742687 -147.263665) (xy 230.693087 -147.238164) (xy 230.647729 -147.205713) (xy 230.60758 -147.167004)
			(xy 230.573494 -147.122861) (xy 230.546198 -147.074226) (xy 230.526275 -147.022135) (xy 230.514149 -146.967698)
			(xy 230.510078 -146.912076) (xy 226.444537 -146.912076) (xy 226.478261 -146.926407) (xy 226.525867 -146.955461)
			(xy 226.568735 -146.991136) (xy 226.605952 -147.032673) (xy 226.636725 -147.079186) (xy 226.660397 -147.129683)
			(xy 226.676465 -147.18309) (xy 226.684585 -147.238266) (xy 226.685094 -147.266152) (xy 226.684585 -147.294038)
			(xy 226.676465 -147.349214) (xy 226.660397 -147.402621) (xy 226.636725 -147.453118) (xy 226.605952 -147.499631)
			(xy 226.568735 -147.541168) (xy 226.525867 -147.576843) (xy 226.478261 -147.605897) (xy 226.426932 -147.627709)
			(xy 226.372975 -147.641815) (xy 226.317538 -147.647915) (xy 226.261804 -147.645878) (xy 226.206961 -147.635748)
			(xy 226.154177 -147.617741) (xy 226.104577 -147.59224) (xy 226.059219 -147.559789) (xy 226.01907 -147.52108)
			(xy 225.984984 -147.476937) (xy 225.957688 -147.428302) (xy 225.937765 -147.376211) (xy 225.925639 -147.321774)
			(xy 225.921568 -147.266152) (xy 222.588119 -147.266152) (xy 222.545941 -147.301253) (xy 222.498335 -147.330307)
			(xy 222.447006 -147.352119) (xy 222.393049 -147.366225) (xy 222.337612 -147.372325) (xy 222.281878 -147.370288)
			(xy 222.227035 -147.360158) (xy 222.174251 -147.342151) (xy 222.124651 -147.31665) (xy 222.079293 -147.284199)
			(xy 222.039144 -147.24549) (xy 222.005058 -147.201347) (xy 221.977762 -147.152712) (xy 221.957839 -147.100621)
			(xy 221.945713 -147.046184) (xy 221.941642 -146.990562) (xy 220.62313 -146.990562) (xy 220.622621 -147.018448)
			(xy 220.614501 -147.073624) (xy 220.598433 -147.127031) (xy 220.574761 -147.177528) (xy 220.543988 -147.224041)
			(xy 220.506771 -147.265578) (xy 220.463903 -147.301253) (xy 220.416297 -147.330307) (xy 220.364968 -147.352119)
			(xy 220.311011 -147.366225) (xy 220.255574 -147.372325) (xy 220.19984 -147.370288) (xy 220.144997 -147.360158)
			(xy 220.092213 -147.342151) (xy 220.042613 -147.31665) (xy 219.997255 -147.284199) (xy 219.957106 -147.24549)
			(xy 219.92302 -147.201347) (xy 219.895724 -147.152712) (xy 219.875801 -147.100621) (xy 219.863675 -147.046184)
			(xy 219.859604 -146.990562) (xy 198.547271 -146.990562) (xy 198.550094 -146.993008) (xy 198.587593 -147.036285)
			(xy 198.618552 -147.084457) (xy 198.642339 -147.136546) (xy 198.658472 -147.191489) (xy 198.666621 -147.248169)
			(xy 198.666621 -147.305431) (xy 198.658472 -147.362111) (xy 198.642339 -147.417054) (xy 198.618552 -147.469143)
			(xy 198.587593 -147.517315) (xy 198.550094 -147.560592) (xy 198.506818 -147.598091) (xy 198.458646 -147.62905)
			(xy 198.406558 -147.652838) (xy 198.351615 -147.668971) (xy 198.294935 -147.677121) (xy 198.266304 -147.677632)
			(xy 198.238933 -147.67718) (xy 198.1847 -147.669734) (xy 198.131984 -147.654981) (xy 198.081764 -147.633194)
			(xy 198.034975 -147.604779) (xy 197.992485 -147.570264) (xy 197.955085 -147.53029) (xy 197.938898 -147.508214)
			(xy 197.933333 -147.500956) (xy 197.918226 -147.49067) (xy 197.909434 -147.488148) (xy 197.879462 -147.480782)
			(xy 197.870515 -147.479013) (xy 197.852422 -147.481242) (xy 197.844156 -147.4851) (xy 197.819541 -147.497442)
			(xy 197.76801 -147.516849) (xy 197.714523 -147.529937) (xy 197.659853 -147.536518) (xy 197.63232 -147.536916)
			(xy 197.604787 -147.536507) (xy 197.550113 -147.529946) (xy 197.496622 -147.516868) (xy 197.445089 -147.497462)
			(xy 197.420484 -147.4851) (xy 197.412228 -147.481214) (xy 197.394128 -147.479005) (xy 197.385178 -147.480782)
			(xy 197.355206 -147.488148) (xy 197.346426 -147.490696) (xy 197.331324 -147.500974) (xy 197.325742 -147.508214)
			(xy 197.30952 -147.530263) (xy 197.272125 -147.570236) (xy 197.229642 -147.604752) (xy 197.182858 -147.633168)
			(xy 197.132644 -147.654957) (xy 197.079933 -147.669714) (xy 197.025705 -147.677164) (xy 196.998336 -147.677632)
			(xy 196.969704 -147.677108) (xy 196.913022 -147.668963) (xy 196.858076 -147.652834) (xy 196.805986 -147.629049)
			(xy 196.75781 -147.598092) (xy 196.714531 -147.560594) (xy 196.677029 -147.517319) (xy 196.646068 -147.469146)
			(xy 196.622279 -147.417057) (xy 196.606145 -147.362113) (xy 196.597995 -147.305432) (xy 196.597995 -147.248168)
			(xy 196.606145 -147.191487) (xy 196.622279 -147.136543) (xy 196.646068 -147.084454) (xy 196.677029 -147.036281)
			(xy 196.714531 -146.993006) (xy 196.75781 -146.955508) (xy 196.805986 -146.924551) (xy 196.858076 -146.900766)
			(xy 196.913022 -146.884637) (xy 196.969704 -146.876492) (xy 196.998336 -146.876008) (xy 197.01325 -146.876119)
			(xy 197.042999 -146.878279) (xy 197.057772 -146.880326) (xy 197.068948 -146.882104) (xy 197.09003 -146.876008)
			(xy 197.157086 -146.81835) (xy 197.165043 -146.81075) (xy 197.17413 -146.790735) (xy 197.174612 -146.779742)
			(xy 197.174612 -146.515074) (xy 197.174117 -146.504084) (xy 197.165034 -146.484072) (xy 197.157086 -146.476466)
			(xy 197.09003 -146.418808) (xy 197.068948 -146.412712) (xy 197.057772 -146.41449) (xy 197.042999 -146.416536)
			(xy 197.01325 -146.418699) (xy 196.998336 -146.418808) (xy 196.969702 -146.418332) (xy 196.913017 -146.410186)
			(xy 196.858068 -146.394056) (xy 196.805974 -146.37027) (xy 196.757796 -146.339312) (xy 196.714514 -146.301811)
			(xy 196.67701 -146.258533) (xy 196.646047 -146.210358) (xy 196.622256 -146.158266) (xy 196.606121 -146.103318)
			(xy 196.597971 -146.046634) (xy 190.593416 -146.046634) (xy 190.570389 -146.065797) (xy 190.522783 -146.094851)
			(xy 190.471454 -146.116663) (xy 190.417497 -146.130769) (xy 190.36206 -146.136869) (xy 190.306326 -146.134832)
			(xy 190.251483 -146.124702) (xy 190.198699 -146.106695) (xy 190.149099 -146.081194) (xy 190.103741 -146.048743)
			(xy 190.063592 -146.010034) (xy 190.029506 -145.965891) (xy 190.00221 -145.917256) (xy 189.982287 -145.865165)
			(xy 189.970161 -145.810728) (xy 189.96609 -145.755106) (xy 188.748416 -145.755106) (xy 188.747907 -145.782992)
			(xy 188.739787 -145.838168) (xy 188.723719 -145.891575) (xy 188.700047 -145.942072) (xy 188.669274 -145.988585)
			(xy 188.632057 -146.030122) (xy 188.589189 -146.065797) (xy 188.541583 -146.094851) (xy 188.490254 -146.116663)
			(xy 188.436297 -146.130769) (xy 188.38086 -146.136869) (xy 188.325126 -146.134832) (xy 188.270283 -146.124702)
			(xy 188.217499 -146.106695) (xy 188.167899 -146.081194) (xy 188.122541 -146.048743) (xy 188.082392 -146.010034)
			(xy 188.048306 -145.965891) (xy 188.02101 -145.917256) (xy 188.001087 -145.865165) (xy 187.988961 -145.810728)
			(xy 187.98489 -145.755106) (xy 186.114762 -145.755106) (xy 186.127905 -145.79879) (xy 186.136025 -145.853966)
			(xy 186.136534 -145.881852) (xy 186.136025 -145.909738) (xy 186.127905 -145.964914) (xy 186.111837 -146.018321)
			(xy 186.088165 -146.068818) (xy 186.057392 -146.115331) (xy 186.020175 -146.156868) (xy 185.977307 -146.192543)
			(xy 185.929701 -146.221597) (xy 185.878372 -146.243409) (xy 185.824415 -146.257515) (xy 185.768978 -146.263615)
			(xy 185.713244 -146.261578) (xy 185.658401 -146.251448) (xy 185.605617 -146.233441) (xy 185.556017 -146.20794)
			(xy 185.510659 -146.175489) (xy 185.47051 -146.13678) (xy 185.436424 -146.092637) (xy 185.409128 -146.044002)
			(xy 185.389205 -145.991911) (xy 185.377079 -145.937474) (xy 185.373008 -145.881852) (xy 184.126612 -145.881852)
			(xy 184.124664 -145.888492) (xy 184.102059 -145.938035) (xy 184.07264 -145.983861) (xy 184.037004 -146.025039)
			(xy 183.995875 -146.060731) (xy 183.950089 -146.090212) (xy 183.900576 -146.112883) (xy 183.848342 -146.128283)
			(xy 183.79445 -146.1361) (xy 183.767222 -146.136614) (xy 183.766206 -146.136614) (xy 183.765698 -146.136614)
			(xy 183.748909 -146.136442) (xy 183.71546 -146.133515) (xy 183.698896 -146.130772) (xy 183.695594 -146.130264)
			(xy 183.689752 -146.129756) (xy 183.681299 -146.130105) (xy 183.665333 -146.135677) (xy 183.65851 -146.140678)
			(xy 183.651906 -146.14652) (xy 183.632348 -146.163284) (xy 183.624868 -146.170306) (xy 183.615711 -146.188647)
			(xy 183.614568 -146.198844) (xy 183.614822 -146.203924) (xy 183.615076 -146.220942) (xy 183.615076 -146.22145)
			(xy 183.615076 -146.223736) (xy 183.615076 -146.535902) (xy 183.615249 -146.54191) (xy 183.618082 -146.553587)
			(xy 183.620664 -146.559016) (xy 183.622502 -146.562491) (xy 183.627093 -146.568873) (xy 183.629808 -146.571716)
			(xy 184.372504 -147.314412) (xy 187.94679 -147.314412) (xy 187.950861 -147.25879) (xy 187.962987 -147.204353)
			(xy 187.98291 -147.152262) (xy 188.010206 -147.103627) (xy 188.044292 -147.059484) (xy 188.084441 -147.020775)
			(xy 188.129799 -146.988324) (xy 188.179399 -146.962823) (xy 188.232183 -146.944816) (xy 188.287026 -146.934686)
			(xy 188.34276 -146.932649) (xy 188.398197 -146.938749) (xy 188.452154 -146.952855) (xy 188.503483 -146.974667)
			(xy 188.551089 -147.003721) (xy 188.593957 -147.039396) (xy 188.631174 -147.080933) (xy 188.661947 -147.127446)
			(xy 188.685619 -147.177943) (xy 188.701687 -147.23135) (xy 188.709807 -147.286526) (xy 188.710316 -147.314412)
			(xy 188.709807 -147.342298) (xy 188.701687 -147.397474) (xy 188.685619 -147.450881) (xy 188.661947 -147.501378)
			(xy 188.631174 -147.547891) (xy 188.624849 -147.55495) (xy 189.96609 -147.55495) (xy 189.970161 -147.499328)
			(xy 189.982287 -147.444891) (xy 190.00221 -147.3928) (xy 190.029506 -147.344165) (xy 190.063592 -147.300022)
			(xy 190.103741 -147.261313) (xy 190.149099 -147.228862) (xy 190.198699 -147.203361) (xy 190.251483 -147.185354)
			(xy 190.306326 -147.175224) (xy 190.36206 -147.173187) (xy 190.417497 -147.179287) (xy 190.471454 -147.193393)
			(xy 190.522783 -147.215205) (xy 190.570389 -147.244259) (xy 190.613257 -147.279934) (xy 190.650474 -147.321471)
			(xy 190.681247 -147.367984) (xy 190.704919 -147.418481) (xy 190.720987 -147.471888) (xy 190.729107 -147.527064)
			(xy 190.729616 -147.55495) (xy 190.729107 -147.582836) (xy 190.720987 -147.638012) (xy 190.704919 -147.691419)
			(xy 190.681247 -147.741916) (xy 190.650474 -147.788429) (xy 190.613257 -147.829966) (xy 190.585156 -147.853352)
			(xy 199.239819 -147.853352) (xy 199.239819 -147.796048) (xy 199.247975 -147.739327) (xy 199.26412 -147.684344)
			(xy 199.287927 -147.632219) (xy 199.31891 -147.584013) (xy 199.356438 -147.540707) (xy 199.399748 -147.503183)
			(xy 199.447958 -147.472206) (xy 199.500086 -147.448405) (xy 199.55507 -147.432265) (xy 199.611792 -147.424116)
			(xy 199.640444 -147.423632) (xy 199.667825 -147.424094) (xy 199.722074 -147.431566) (xy 199.774801 -147.446351)
			(xy 199.825026 -147.468175) (xy 199.871814 -147.49663) (xy 199.914294 -147.531189) (xy 199.951675 -147.571207)
			(xy 199.96785 -147.593304) (xy 199.973395 -147.60058) (xy 199.988517 -147.610855) (xy 199.997314 -147.61337)
			(xy 200.027286 -147.620736) (xy 200.036237 -147.622477) (xy 200.054325 -147.620266) (xy 200.062592 -147.616418)
			(xy 200.087191 -147.604027) (xy 200.138718 -147.58456) (xy 200.192207 -147.571412) (xy 200.246887 -147.564774)
			(xy 200.274428 -147.564348) (xy 200.301968 -147.564781) (xy 200.356649 -147.571415) (xy 200.410138 -147.584561)
			(xy 200.461665 -147.604028) (xy 200.486264 -147.616418) (xy 200.49453 -147.620278) (xy 200.512621 -147.622504)
			(xy 200.52157 -147.620736) (xy 200.551542 -147.61337) (xy 200.560326 -147.610835) (xy 200.575425 -147.600547)
			(xy 200.581006 -147.593304) (xy 200.597169 -147.571195) (xy 200.634542 -147.531164) (xy 200.67702 -147.496596)
			(xy 200.723809 -147.468135) (xy 200.774039 -147.446313) (xy 200.826774 -147.431535) (xy 200.881029 -147.424078)
			(xy 200.908412 -147.423632) (xy 200.93706 -147.424148) (xy 200.993771 -147.432303) (xy 201.048745 -147.448447)
			(xy 201.100862 -147.472249) (xy 201.149061 -147.503226) (xy 201.192361 -147.540747) (xy 201.229881 -147.584048)
			(xy 201.260857 -147.632248) (xy 201.284657 -147.684366) (xy 201.300799 -147.73934) (xy 201.308953 -147.796052)
			(xy 201.308953 -147.853348) (xy 201.300799 -147.91006) (xy 201.284657 -147.965034) (xy 201.260857 -148.017152)
			(xy 201.247258 -148.038312) (xy 219.859604 -148.038312) (xy 219.863675 -147.98269) (xy 219.875801 -147.928253)
			(xy 219.895724 -147.876162) (xy 219.92302 -147.827527) (xy 219.957106 -147.783384) (xy 219.997255 -147.744675)
			(xy 220.042613 -147.712224) (xy 220.092213 -147.686723) (xy 220.144997 -147.668716) (xy 220.19984 -147.658586)
			(xy 220.255574 -147.656549) (xy 220.311011 -147.662649) (xy 220.364968 -147.676755) (xy 220.416297 -147.698567)
			(xy 220.452746 -147.720812) (xy 234.212128 -147.720812) (xy 234.216199 -147.66519) (xy 234.228325 -147.610753)
			(xy 234.248248 -147.558662) (xy 234.275544 -147.510027) (xy 234.30963 -147.465884) (xy 234.349779 -147.427175)
			(xy 234.395137 -147.394724) (xy 234.444737 -147.369223) (xy 234.497521 -147.351216) (xy 234.552364 -147.341086)
			(xy 234.608098 -147.339049) (xy 234.663535 -147.345149) (xy 234.717492 -147.359255) (xy 234.768821 -147.381067)
			(xy 234.816427 -147.410121) (xy 234.859295 -147.445796) (xy 234.896512 -147.487333) (xy 234.927285 -147.533846)
			(xy 234.950957 -147.584343) (xy 234.967025 -147.63775) (xy 234.969954 -147.65765) (xy 239.350566 -147.65765)
			(xy 239.350566 -147.60315) (xy 239.358321 -147.549205) (xy 239.373674 -147.496913) (xy 239.396312 -147.447337)
			(xy 239.425775 -147.401488) (xy 239.461462 -147.360298) (xy 239.502648 -147.324605) (xy 239.548493 -147.295136)
			(xy 239.598066 -147.272492) (xy 239.650356 -147.257132) (xy 239.7043 -147.249369) (xy 239.73155 -147.24888)
			(xy 239.757865 -147.249321) (xy 239.809994 -147.256562) (xy 239.860637 -147.270887) (xy 239.908836 -147.292024)
			(xy 239.953679 -147.319575) (xy 239.994318 -147.353017) (xy 240.012474 -147.37207) (xy 240.020007 -147.379458)
			(xy 240.039278 -147.387991) (xy 240.049812 -147.38858) (xy 240.124488 -147.38858) (xy 240.135039 -147.388064)
			(xy 240.154335 -147.37952) (xy 240.161826 -147.37207) (xy 240.181646 -147.351282) (xy 240.226418 -147.315307)
			(xy 240.276076 -147.286447) (xy 240.329498 -147.265354) (xy 240.385477 -147.252505) (xy 240.44275 -147.24819)
			(xy 240.500023 -147.252505) (xy 240.556002 -147.265354) (xy 240.609424 -147.286447) (xy 240.659082 -147.315307)
			(xy 240.703854 -147.351282) (xy 240.723674 -147.37207) (xy 240.731207 -147.379458) (xy 240.750478 -147.387991)
			(xy 240.761012 -147.38858) (xy 240.835688 -147.38858) (xy 240.846239 -147.388064) (xy 240.865535 -147.37952)
			(xy 240.873026 -147.37207) (xy 240.89117 -147.353003) (xy 240.931803 -147.319548) (xy 240.976646 -147.291991)
			(xy 241.024849 -147.270855) (xy 241.075498 -147.25654) (xy 241.127633 -147.249317) (xy 241.15395 -147.24888)
			(xy 241.181204 -147.249364) (xy 241.235159 -147.257115) (xy 241.287461 -147.272466) (xy 241.337046 -147.295105)
			(xy 241.382904 -147.324571) (xy 241.424101 -147.360263) (xy 241.459799 -147.401456) (xy 241.489271 -147.44731)
			(xy 241.511916 -147.496892) (xy 241.527275 -147.549192) (xy 241.535033 -147.603146) (xy 241.535033 -147.657654)
			(xy 241.535033 -147.657656) (xy 243.350443 -147.657656) (xy 243.350443 -147.603144) (xy 243.358201 -147.549188)
			(xy 243.37356 -147.496885) (xy 243.396206 -147.447301) (xy 243.425679 -147.401444) (xy 243.461379 -147.360249)
			(xy 243.502578 -147.324554) (xy 243.548437 -147.295086) (xy 243.598024 -147.272445) (xy 243.650329 -147.257092)
			(xy 243.704286 -147.24934) (xy 243.731542 -147.24888) (xy 243.757857 -147.249326) (xy 243.809986 -147.256566)
			(xy 243.860629 -147.27089) (xy 243.908827 -147.292026) (xy 243.95367 -147.319576) (xy 243.99431 -147.353017)
			(xy 244.012466 -147.37207) (xy 244.020002 -147.379454) (xy 244.039271 -147.38799) (xy 244.049804 -147.38858)
			(xy 244.12448 -147.38858) (xy 244.135031 -147.38806) (xy 244.154327 -147.379519) (xy 244.161818 -147.37207)
			(xy 244.181638 -147.351282) (xy 244.22641 -147.315307) (xy 244.276068 -147.286447) (xy 244.32949 -147.265354)
			(xy 244.385469 -147.252505) (xy 244.442742 -147.24819) (xy 244.500015 -147.252505) (xy 244.555994 -147.265354)
			(xy 244.609416 -147.286447) (xy 244.659074 -147.315307) (xy 244.703846 -147.351282) (xy 244.723666 -147.37207)
			(xy 244.731202 -147.379454) (xy 244.750471 -147.38799) (xy 244.761004 -147.38858) (xy 244.83568 -147.38858)
			(xy 244.846231 -147.38806) (xy 244.865527 -147.379519) (xy 244.873018 -147.37207) (xy 244.891166 -147.353007)
			(xy 244.931798 -147.319552) (xy 244.97664 -147.291994) (xy 245.024842 -147.270857) (xy 245.075491 -147.256542)
			(xy 245.127626 -147.249318) (xy 245.153942 -147.24888) (xy 245.18119 -147.249393) (xy 245.235132 -147.257154)
			(xy 245.28742 -147.272512) (xy 245.33699 -147.295155) (xy 245.382834 -147.324622) (xy 245.424018 -147.360312)
			(xy 245.459703 -147.4015) (xy 245.489165 -147.447347) (xy 245.511802 -147.49692) (xy 245.527155 -147.549209)
			(xy 245.53491 -147.603152) (xy 245.53491 -147.657648) (xy 245.527155 -147.711591) (xy 245.511802 -147.76388)
			(xy 245.489165 -147.813453) (xy 245.459703 -147.8593) (xy 245.424018 -147.900488) (xy 245.382834 -147.936178)
			(xy 245.33699 -147.965645) (xy 245.28742 -147.988288) (xy 245.235132 -148.003646) (xy 245.18119 -148.011407)
			(xy 245.153942 -148.011896) (xy 245.127627 -148.011469) (xy 245.075496 -148.004226) (xy 245.024853 -147.989899)
			(xy 244.976654 -147.968759) (xy 244.931811 -147.941206) (xy 244.891174 -147.907761) (xy 244.873018 -147.888706)
			(xy 244.865491 -147.881311) (xy 244.846215 -147.872783) (xy 244.83568 -147.872196) (xy 244.761004 -147.872196)
			(xy 244.750453 -147.872715) (xy 244.731158 -147.881257) (xy 244.723666 -147.888706) (xy 244.703846 -147.909494)
			(xy 244.659074 -147.945469) (xy 244.609416 -147.974329) (xy 244.555994 -147.995422) (xy 244.500015 -148.008271)
			(xy 244.442742 -148.012586) (xy 244.385469 -148.008271) (xy 244.32949 -147.995422) (xy 244.276068 -147.974329)
			(xy 244.22641 -147.945469) (xy 244.181638 -147.909494) (xy 244.161818 -147.888706) (xy 244.154291 -147.881311)
			(xy 244.135015 -147.872783) (xy 244.12448 -147.872196) (xy 244.049804 -147.872196) (xy 244.039253 -147.872715)
			(xy 244.019958 -147.881257) (xy 244.012466 -147.888706) (xy 243.994321 -147.907772) (xy 243.953689 -147.941228)
			(xy 243.908846 -147.968786) (xy 243.860644 -147.989922) (xy 243.809994 -148.004237) (xy 243.757859 -148.011459)
			(xy 243.731542 -148.011896) (xy 243.704286 -148.01146) (xy 243.650329 -148.003708) (xy 243.598024 -147.988355)
			(xy 243.548437 -147.965714) (xy 243.502578 -147.936246) (xy 243.461379 -147.900551) (xy 243.425679 -147.859356)
			(xy 243.396206 -147.813499) (xy 243.37356 -147.763915) (xy 243.358201 -147.711612) (xy 243.350443 -147.657656)
			(xy 241.535033 -147.657656) (xy 241.527275 -147.711608) (xy 241.511916 -147.763908) (xy 241.489271 -147.81349)
			(xy 241.459799 -147.859344) (xy 241.424101 -147.900537) (xy 241.382904 -147.936229) (xy 241.337046 -147.965695)
			(xy 241.287461 -147.988334) (xy 241.235159 -148.003685) (xy 241.181204 -148.011436) (xy 241.15395 -148.011896)
			(xy 241.127635 -148.011463) (xy 241.075505 -148.004221) (xy 241.024861 -147.989896) (xy 240.976662 -147.968757)
			(xy 240.93182 -147.941205) (xy 240.891182 -147.90776) (xy 240.873026 -147.888706) (xy 240.865496 -147.881315)
			(xy 240.846222 -147.872784) (xy 240.835688 -147.872196) (xy 240.761012 -147.872196) (xy 240.750462 -147.872719)
			(xy 240.731167 -147.881259) (xy 240.723674 -147.888706) (xy 240.703854 -147.909494) (xy 240.659082 -147.945469)
			(xy 240.609424 -147.974329) (xy 240.556002 -147.995422) (xy 240.500023 -148.008271) (xy 240.44275 -148.012586)
			(xy 240.385477 -148.008271) (xy 240.329498 -147.995422) (xy 240.276076 -147.974329) (xy 240.226418 -147.945469)
			(xy 240.181646 -147.909494) (xy 240.161826 -147.888706) (xy 240.154296 -147.881315) (xy 240.135022 -147.872784)
			(xy 240.124488 -147.872196) (xy 240.049812 -147.872196) (xy 240.039262 -147.872719) (xy 240.019967 -147.881259)
			(xy 240.012474 -147.888706) (xy 239.994325 -147.907768) (xy 239.953694 -147.941225) (xy 239.908852 -147.968783)
			(xy 239.86065 -147.98992) (xy 239.810001 -148.004236) (xy 239.757867 -148.011459) (xy 239.73155 -148.011896)
			(xy 239.7043 -148.011431) (xy 239.650356 -148.003668) (xy 239.598066 -147.988308) (xy 239.548493 -147.965664)
			(xy 239.502648 -147.936195) (xy 239.461462 -147.900502) (xy 239.425775 -147.859312) (xy 239.396312 -147.813463)
			(xy 239.373674 -147.763887) (xy 239.358321 -147.711595) (xy 239.350566 -147.65765) (xy 234.969954 -147.65765)
			(xy 234.975145 -147.692926) (xy 234.975654 -147.720812) (xy 234.975145 -147.748698) (xy 234.967025 -147.803874)
			(xy 234.950957 -147.857281) (xy 234.927285 -147.907778) (xy 234.896512 -147.954291) (xy 234.859295 -147.995828)
			(xy 234.832967 -148.017738) (xy 248.177556 -148.017738) (xy 248.181627 -147.962116) (xy 248.193753 -147.907679)
			(xy 248.213676 -147.855588) (xy 248.240972 -147.806953) (xy 248.275058 -147.76281) (xy 248.315207 -147.724101)
			(xy 248.360565 -147.69165) (xy 248.410165 -147.666149) (xy 248.462949 -147.648142) (xy 248.517792 -147.638012)
			(xy 248.573526 -147.635975) (xy 248.628963 -147.642075) (xy 248.68292 -147.656181) (xy 248.734249 -147.677993)
			(xy 248.781855 -147.707047) (xy 248.823118 -147.741386) (xy 254.081532 -147.741386) (xy 254.085603 -147.685764)
			(xy 254.097729 -147.631327) (xy 254.117652 -147.579236) (xy 254.144948 -147.530601) (xy 254.179034 -147.486458)
			(xy 254.219183 -147.447749) (xy 254.264541 -147.415298) (xy 254.314141 -147.389797) (xy 254.366925 -147.37179)
			(xy 254.421768 -147.36166) (xy 254.477502 -147.359623) (xy 254.532939 -147.365723) (xy 254.586896 -147.379829)
			(xy 254.638225 -147.401641) (xy 254.685831 -147.430695) (xy 254.728699 -147.46637) (xy 254.765916 -147.507907)
			(xy 254.796689 -147.55442) (xy 254.820361 -147.604917) (xy 254.836429 -147.658324) (xy 254.844549 -147.7135)
			(xy 254.845058 -147.741386) (xy 254.844549 -147.769272) (xy 254.836429 -147.824448) (xy 254.820361 -147.877855)
			(xy 254.796689 -147.928352) (xy 254.765916 -147.974865) (xy 254.728699 -148.016402) (xy 254.685831 -148.052077)
			(xy 254.638225 -148.081131) (xy 254.586896 -148.102943) (xy 254.532939 -148.117049) (xy 254.477502 -148.123149)
			(xy 254.421768 -148.121112) (xy 254.366925 -148.110982) (xy 254.314141 -148.092975) (xy 254.264541 -148.067474)
			(xy 254.219183 -148.035023) (xy 254.179034 -147.996314) (xy 254.144948 -147.952171) (xy 254.117652 -147.903536)
			(xy 254.097729 -147.851445) (xy 254.085603 -147.797008) (xy 254.081532 -147.741386) (xy 248.823118 -147.741386)
			(xy 248.824723 -147.742722) (xy 248.86194 -147.784259) (xy 248.892713 -147.830772) (xy 248.916385 -147.881269)
			(xy 248.932453 -147.934676) (xy 248.940573 -147.989852) (xy 248.941082 -148.017738) (xy 248.940573 -148.045624)
			(xy 248.932453 -148.1008) (xy 248.916385 -148.154207) (xy 248.892713 -148.204704) (xy 248.86194 -148.251217)
			(xy 248.824723 -148.292754) (xy 248.781855 -148.328429) (xy 248.734249 -148.357483) (xy 248.68292 -148.379295)
			(xy 248.628963 -148.393401) (xy 248.573526 -148.399501) (xy 248.517792 -148.397464) (xy 248.462949 -148.387334)
			(xy 248.410165 -148.369327) (xy 248.360565 -148.343826) (xy 248.315207 -148.311375) (xy 248.275058 -148.272666)
			(xy 248.240972 -148.228523) (xy 248.213676 -148.179888) (xy 248.193753 -148.127797) (xy 248.181627 -148.07336)
			(xy 248.177556 -148.017738) (xy 234.832967 -148.017738) (xy 234.816427 -148.031503) (xy 234.768821 -148.060557)
			(xy 234.717492 -148.082369) (xy 234.663535 -148.096475) (xy 234.608098 -148.102575) (xy 234.552364 -148.100538)
			(xy 234.497521 -148.090408) (xy 234.444737 -148.072401) (xy 234.395137 -148.0469) (xy 234.349779 -148.014449)
			(xy 234.30963 -147.97574) (xy 234.275544 -147.931597) (xy 234.248248 -147.882962) (xy 234.228325 -147.830871)
			(xy 234.216199 -147.776434) (xy 234.212128 -147.720812) (xy 220.452746 -147.720812) (xy 220.463903 -147.727621)
			(xy 220.506771 -147.763296) (xy 220.543988 -147.804833) (xy 220.574761 -147.851346) (xy 220.598433 -147.901843)
			(xy 220.614501 -147.95525) (xy 220.622621 -148.010426) (xy 220.62313 -148.038312) (xy 220.622621 -148.066198)
			(xy 220.614501 -148.121374) (xy 220.598433 -148.174781) (xy 220.574761 -148.225278) (xy 220.543988 -148.271791)
			(xy 220.506771 -148.313328) (xy 220.463903 -148.349003) (xy 220.416297 -148.378057) (xy 220.364968 -148.399869)
			(xy 220.311011 -148.413975) (xy 220.255574 -148.420075) (xy 220.19984 -148.418038) (xy 220.144997 -148.407908)
			(xy 220.092213 -148.389901) (xy 220.042613 -148.3644) (xy 219.997255 -148.331949) (xy 219.957106 -148.29324)
			(xy 219.92302 -148.249097) (xy 219.895724 -148.200462) (xy 219.875801 -148.148371) (xy 219.863675 -148.093934)
			(xy 219.859604 -148.038312) (xy 201.247258 -148.038312) (xy 201.229881 -148.065352) (xy 201.192361 -148.108653)
			(xy 201.149061 -148.146174) (xy 201.100862 -148.177151) (xy 201.048745 -148.200953) (xy 200.993771 -148.217097)
			(xy 200.93706 -148.225252) (xy 200.908412 -148.225764) (xy 200.893494 -148.225599) (xy 200.863745 -148.223307)
			(xy 200.848976 -148.221192) (xy 200.8378 -148.219414) (xy 200.816718 -148.22551) (xy 200.749662 -148.283168)
			(xy 200.741704 -148.290768) (xy 200.732615 -148.310783) (xy 200.732136 -148.321776) (xy 200.732136 -148.586444)
			(xy 200.732606 -148.597437) (xy 200.741705 -148.61745) (xy 200.749662 -148.625052) (xy 200.816718 -148.68271)
			(xy 200.8378 -148.688806) (xy 200.848976 -148.687028) (xy 200.863745 -148.684919) (xy 200.893494 -148.682632)
			(xy 200.908412 -148.682456) (xy 200.937061 -148.682924) (xy 200.993776 -148.69108) (xy 201.048754 -148.707224)
			(xy 201.100874 -148.731028) (xy 201.149076 -148.762006) (xy 201.192379 -148.79953) (xy 201.229901 -148.842834)
			(xy 201.260878 -148.891037) (xy 201.28468 -148.943158) (xy 201.300823 -148.998135) (xy 201.308977 -149.054851)
			(xy 201.308977 -149.112149) (xy 201.300823 -149.168865) (xy 201.28468 -149.223842) (xy 201.260878 -149.275963)
			(xy 201.229901 -149.324166) (xy 201.192379 -149.36747) (xy 201.151022 -149.403308) (xy 223.512886 -149.403308)
			(xy 223.516957 -149.347686) (xy 223.529083 -149.293249) (xy 223.549006 -149.241158) (xy 223.576302 -149.192523)
			(xy 223.610388 -149.14838) (xy 223.650537 -149.109671) (xy 223.695895 -149.07722) (xy 223.745495 -149.051719)
			(xy 223.798279 -149.033712) (xy 223.853122 -149.023582) (xy 223.908856 -149.021545) (xy 223.964293 -149.027645)
			(xy 224.01825 -149.041751) (xy 224.069579 -149.063563) (xy 224.117185 -149.092617) (xy 224.160053 -149.128292)
			(xy 224.19727 -149.169829) (xy 224.228043 -149.216342) (xy 224.251715 -149.266839) (xy 224.267783 -149.320246)
			(xy 224.275903 -149.375422) (xy 224.276412 -149.403308) (xy 224.275903 -149.431194) (xy 224.271406 -149.46175)
			(xy 225.921805 -149.46175) (xy 225.921805 -149.40725) (xy 225.929562 -149.353304) (xy 225.944917 -149.301011)
			(xy 225.967558 -149.251436) (xy 225.997025 -149.205587) (xy 226.032716 -149.164399) (xy 226.073906 -149.12871)
			(xy 226.119757 -149.099247) (xy 226.169333 -149.076609) (xy 226.221627 -149.061257) (xy 226.275574 -149.053504)
			(xy 226.302824 -149.053042) (xy 226.331803 -149.053557) (xy 226.389094 -149.062321) (xy 226.444402 -149.079644)
			(xy 226.496456 -149.105127) (xy 226.544061 -149.138185) (xy 226.586122 -149.178059) (xy 226.604322 -149.200616)
			(xy 226.613011 -149.211062) (xy 226.634723 -149.227378) (xy 226.659971 -149.237386) (xy 226.686965 -149.240376)
			(xy 226.713791 -149.236138) (xy 226.738548 -149.22497) (xy 226.75948 -149.207666) (xy 226.767644 -149.196806)
			(xy 226.783033 -149.175695) (xy 226.818638 -149.137466) (xy 226.859124 -149.104451) (xy 226.903736 -149.077267)
			(xy 226.951638 -149.056422) (xy 227.001936 -149.042305) (xy 227.053689 -149.035181) (xy 227.07981 -149.034754)
			(xy 227.107058 -149.035317) (xy 227.160999 -149.043074) (xy 227.213288 -149.058428) (xy 227.262858 -149.081068)
			(xy 227.308703 -149.110531) (xy 227.349888 -149.146219) (xy 227.385575 -149.187405) (xy 227.415037 -149.23325)
			(xy 227.437675 -149.282822) (xy 227.453028 -149.335111) (xy 227.460784 -149.389052) (xy 227.460784 -149.43328)
			(xy 227.76891 -149.43328) (xy 227.772981 -149.377658) (xy 227.785107 -149.323221) (xy 227.80503 -149.27113)
			(xy 227.832326 -149.222495) (xy 227.866412 -149.178352) (xy 227.906561 -149.139643) (xy 227.951919 -149.107192)
			(xy 228.001519 -149.081691) (xy 228.054303 -149.063684) (xy 228.109146 -149.053554) (xy 228.16488 -149.051517)
			(xy 228.220317 -149.057617) (xy 228.274274 -149.071723) (xy 228.325603 -149.093535) (xy 228.373209 -149.122589)
			(xy 228.416077 -149.158264) (xy 228.453294 -149.199801) (xy 228.484067 -149.246314) (xy 228.507739 -149.296811)
			(xy 228.523807 -149.350218) (xy 228.531927 -149.405394) (xy 228.532366 -149.42947) (xy 228.887272 -149.42947)
			(xy 228.891343 -149.373848) (xy 228.903469 -149.319411) (xy 228.923392 -149.26732) (xy 228.950688 -149.218685)
			(xy 228.984774 -149.174542) (xy 229.024923 -149.135833) (xy 229.070281 -149.103382) (xy 229.119881 -149.077881)
			(xy 229.172665 -149.059874) (xy 229.227508 -149.049744) (xy 229.283242 -149.047707) (xy 229.338679 -149.053807)
			(xy 229.392636 -149.067913) (xy 229.443965 -149.089725) (xy 229.491571 -149.118779) (xy 229.534439 -149.154454)
			(xy 229.571656 -149.195991) (xy 229.602429 -149.242504) (xy 229.626101 -149.293001) (xy 229.642169 -149.346408)
			(xy 229.650289 -149.401584) (xy 229.650798 -149.42947) (xy 229.650444 -149.448855) (xy 229.996651 -149.448855)
			(xy 229.996651 -149.394345) (xy 230.00441 -149.340389) (xy 230.019768 -149.288087) (xy 230.042414 -149.238503)
			(xy 230.071887 -149.192648) (xy 230.107586 -149.151453) (xy 230.148785 -149.115759) (xy 230.194644 -149.086292)
			(xy 230.24423 -149.063652) (xy 230.296534 -149.0483) (xy 230.350491 -149.040548) (xy 230.377746 -149.040088)
			(xy 230.410512 -149.041612) (xy 230.410766 -149.041612) (xy 230.419913 -149.041928) (xy 230.437485 -149.03685)
			(xy 230.445056 -149.031706) (xy 230.499412 -148.99132) (xy 230.506524 -148.985565) (xy 230.516431 -148.970206)
			(xy 230.518716 -148.961348) (xy 230.518716 -148.96084) (xy 230.525207 -148.932643) (xy 230.545478 -148.878454)
			(xy 230.5737 -148.827947) (xy 230.609226 -148.782281) (xy 230.651241 -148.742505) (xy 230.698782 -148.709531)
			(xy 230.750757 -148.684114) (xy 230.805974 -148.666838) (xy 230.863168 -148.6581) (xy 230.892096 -148.657564)
			(xy 230.919347 -148.658083) (xy 230.973294 -148.665839) (xy 231.025589 -148.681193) (xy 231.075166 -148.703834)
			(xy 231.121016 -148.7333) (xy 231.162206 -148.768991) (xy 231.197898 -148.810181) (xy 231.227364 -148.856031)
			(xy 231.250005 -148.905607) (xy 231.26536 -148.957902) (xy 231.273117 -149.011849) (xy 231.273117 -149.066351)
			(xy 231.26536 -149.120298) (xy 231.250005 -149.172593) (xy 231.227364 -149.222169) (xy 231.197898 -149.268019)
			(xy 231.180708 -149.287857) (xy 233.065215 -149.287857) (xy 233.065215 -149.233343) (xy 233.072973 -149.179385)
			(xy 233.088332 -149.12708) (xy 233.110978 -149.077493) (xy 233.140451 -149.031634) (xy 233.176151 -148.990437)
			(xy 233.21735 -148.954739) (xy 233.263211 -148.925269) (xy 233.312799 -148.902625) (xy 233.365105 -148.887269)
			(xy 233.419063 -148.879514) (xy 233.44632 -148.879052) (xy 233.473193 -148.879488) (xy 233.526406 -148.887047)
			(xy 233.578032 -148.901998) (xy 233.627049 -148.924046) (xy 233.672487 -148.952753) (xy 233.713447 -148.987553)
			(xy 233.749118 -149.027757) (xy 233.778795 -149.072568) (xy 233.80189 -149.1211) (xy 233.817946 -149.172393)
			(xy 233.822748 -149.198838) (xy 233.824272 -149.208744) (xy 233.834686 -149.225508) (xy 233.899964 -149.273514)
			(xy 233.908092 -149.278969) (xy 233.927045 -149.283799) (xy 233.936794 -149.282912) (xy 233.937048 -149.282912)
			(xy 233.949938 -149.281253) (xy 233.975868 -149.279475) (xy 233.988864 -149.279356) (xy 233.989118 -149.279356)
			(xy 234.016366 -149.279915) (xy 234.070306 -149.287673) (xy 234.122594 -149.303028) (xy 234.172164 -149.325668)
			(xy 234.218008 -149.355132) (xy 234.259192 -149.390821) (xy 234.294878 -149.432006) (xy 234.32434 -149.477852)
			(xy 234.346978 -149.527423) (xy 234.362331 -149.579711) (xy 234.370086 -149.633652) (xy 234.370086 -149.688148)
			(xy 234.362331 -149.742089) (xy 234.346978 -149.794377) (xy 234.32434 -149.843948) (xy 234.294878 -149.889794)
			(xy 234.259192 -149.930979) (xy 234.218008 -149.966668) (xy 234.172164 -149.996131) (xy 234.122594 -150.018772)
			(xy 234.083747 -150.03018) (xy 236.22 -150.03018) (xy 236.22 -150.029672) (xy 236.220479 -150.001548)
			(xy 236.228355 -149.945852) (xy 236.243936 -149.891804) (xy 236.266915 -149.840463) (xy 236.296842 -149.792835)
			(xy 236.333129 -149.749856) (xy 236.375066 -149.712368) (xy 236.421828 -149.681108) (xy 236.4725 -149.656687)
			(xy 236.526086 -149.639585) (xy 236.581536 -149.630137) (xy 236.609636 -149.62886) (xy 236.619542 -149.628606)
			(xy 236.637576 -149.620732) (xy 236.69371 -149.56282) (xy 236.70023 -149.555474) (xy 236.707684 -149.537322)
			(xy 236.708188 -149.527514) (xy 236.708188 -148.943568) (xy 236.707775 -148.933869) (xy 236.700579 -148.915851)
			(xy 236.694218 -148.908516) (xy 236.645958 -148.85797) (xy 236.638983 -148.851211) (xy 236.62134 -148.843124)
			(xy 236.611668 -148.842222) (xy 236.58399 -148.840377) (xy 236.529497 -148.829996) (xy 236.476956 -148.812205)
			(xy 236.427368 -148.787341) (xy 236.38168 -148.755881) (xy 236.340764 -148.718423) (xy 236.305401 -148.675684)
			(xy 236.276267 -148.628479) (xy 236.253916 -148.577709) (xy 236.238776 -148.524343) (xy 236.231135 -148.4694)
			(xy 236.230668 -148.441664) (xy 236.231165 -148.413034) (xy 236.239318 -148.356357) (xy 236.255454 -148.301417)
			(xy 236.279243 -148.249333) (xy 236.310203 -148.201163) (xy 236.347701 -148.15789) (xy 236.390976 -148.120393)
			(xy 236.439147 -148.089436) (xy 236.491232 -148.065648) (xy 236.546173 -148.049515) (xy 236.60285 -148.041364)
			(xy 236.63148 -148.040852) (xy 236.659812 -148.041297) (xy 236.715913 -148.049276) (xy 236.77033 -148.065077)
			(xy 236.82198 -148.088384) (xy 236.869831 -148.118735) (xy 236.912931 -148.155522) (xy 236.950419 -148.198014)
			(xy 236.981549 -148.245362) (xy 237.005699 -148.296622) (xy 237.014512 -148.323554) (xy 237.01752 -148.33215)
			(xy 237.028593 -148.346594) (xy 237.036102 -148.351748) (xy 237.06201 -148.368004) (xy 237.069906 -148.372576)
			(xy 237.087739 -148.376363) (xy 237.096808 -148.37537) (xy 237.113846 -148.372903) (xy 237.148173 -148.370233)
			(xy 237.165388 -148.370036) (xy 237.16615 -148.370036) (xy 237.196125 -148.370481) (xy 237.255561 -148.378309)
			(xy 237.313468 -148.393825) (xy 237.368856 -148.416763) (xy 237.420777 -148.446732) (xy 237.468344 -148.483219)
			(xy 237.510745 -148.5256) (xy 237.547253 -148.573152) (xy 237.577245 -148.625059) (xy 237.600209 -148.680437)
			(xy 237.610501 -148.718778) (xy 249.89866 -148.718778) (xy 249.902731 -148.663156) (xy 249.914857 -148.608719)
			(xy 249.93478 -148.556628) (xy 249.962076 -148.507993) (xy 249.996162 -148.46385) (xy 250.036311 -148.425141)
			(xy 250.081669 -148.39269) (xy 250.131269 -148.367189) (xy 250.184053 -148.349182) (xy 250.238896 -148.339052)
			(xy 250.29463 -148.337015) (xy 250.350067 -148.343115) (xy 250.404024 -148.357221) (xy 250.455353 -148.379033)
			(xy 250.502959 -148.408087) (xy 250.545827 -148.443762) (xy 250.583044 -148.485299) (xy 250.613817 -148.531812)
			(xy 250.637489 -148.582309) (xy 250.653557 -148.635716) (xy 250.661677 -148.690892) (xy 250.662186 -148.718778)
			(xy 251.065282 -148.718778) (xy 251.069353 -148.663156) (xy 251.081479 -148.608719) (xy 251.101402 -148.556628)
			(xy 251.128698 -148.507993) (xy 251.162784 -148.46385) (xy 251.202933 -148.425141) (xy 251.248291 -148.39269)
			(xy 251.297891 -148.367189) (xy 251.350675 -148.349182) (xy 251.405518 -148.339052) (xy 251.461252 -148.337015)
			(xy 251.516689 -148.343115) (xy 251.570646 -148.357221) (xy 251.621975 -148.379033) (xy 251.669581 -148.408087)
			(xy 251.712449 -148.443762) (xy 251.749666 -148.485299) (xy 251.780439 -148.531812) (xy 251.804111 -148.582309)
			(xy 251.820179 -148.635716) (xy 251.828299 -148.690892) (xy 251.828808 -148.718778) (xy 251.828299 -148.746664)
			(xy 251.820179 -148.80184) (xy 251.804111 -148.855247) (xy 251.780439 -148.905744) (xy 251.749666 -148.952257)
			(xy 251.712449 -148.993794) (xy 251.669581 -149.029469) (xy 251.621975 -149.058523) (xy 251.570646 -149.080335)
			(xy 251.516689 -149.094441) (xy 251.461252 -149.100541) (xy 251.405518 -149.098504) (xy 251.350675 -149.088374)
			(xy 251.297891 -149.070367) (xy 251.248291 -149.044866) (xy 251.202933 -149.012415) (xy 251.162784 -148.973706)
			(xy 251.128698 -148.929563) (xy 251.101402 -148.880928) (xy 251.081479 -148.828837) (xy 251.069353 -148.7744)
			(xy 251.065282 -148.718778) (xy 250.662186 -148.718778) (xy 250.661677 -148.746664) (xy 250.653557 -148.80184)
			(xy 250.637489 -148.855247) (xy 250.613817 -148.905744) (xy 250.583044 -148.952257) (xy 250.545827 -148.993794)
			(xy 250.502959 -149.029469) (xy 250.455353 -149.058523) (xy 250.404024 -149.080335) (xy 250.350067 -149.094441)
			(xy 250.29463 -149.100541) (xy 250.238896 -149.098504) (xy 250.184053 -149.088374) (xy 250.131269 -149.070367)
			(xy 250.081669 -149.044866) (xy 250.036311 -149.012415) (xy 249.996162 -148.973706) (xy 249.962076 -148.929563)
			(xy 249.93478 -148.880928) (xy 249.914857 -148.828837) (xy 249.902731 -148.7744) (xy 249.89866 -148.718778)
			(xy 237.610501 -148.718778) (xy 237.615751 -148.738337) (xy 237.623606 -148.797769) (xy 237.624112 -148.827744)
			(xy 237.624112 -149.691344) (xy 237.62368 -149.721324) (xy 237.615846 -149.780771) (xy 237.600317 -149.838687)
			(xy 237.577359 -149.894079) (xy 237.547366 -149.945999) (xy 237.51085 -149.993559) (xy 237.468438 -150.035944)
			(xy 237.420854 -150.072429) (xy 237.368915 -150.102389) (xy 237.313508 -150.125311) (xy 237.255583 -150.140803)
			(xy 237.196131 -150.148599) (xy 237.16615 -150.149052) (xy 237.143005 -150.148794) (xy 237.096943 -150.144218)
			(xy 237.074202 -150.139908) (xy 237.065561 -150.138613) (xy 237.048294 -150.141203) (xy 237.04042 -150.144988)
			(xy 237.01375 -150.158958) (xy 237.006237 -150.163432) (xy 236.994546 -150.176415) (xy 236.99089 -150.184358)
			(xy 236.985814 -150.195848) (xy 239.350588 -150.195848) (xy 239.350588 -150.141352) (xy 239.358343 -150.08741)
			(xy 239.373695 -150.035121) (xy 239.396332 -149.985548) (xy 239.425793 -149.939701) (xy 239.461478 -149.898514)
			(xy 239.502661 -149.862823) (xy 239.548504 -149.833356) (xy 239.598074 -149.810713) (xy 239.650361 -149.795354)
			(xy 239.704302 -149.787592) (xy 239.73155 -149.787102) (xy 239.757865 -149.787535) (xy 239.809995 -149.794777)
			(xy 239.860639 -149.809103) (xy 239.908837 -149.830242) (xy 239.95368 -149.857794) (xy 239.994318 -149.891238)
			(xy 240.012474 -149.910292) (xy 240.020004 -149.917683) (xy 240.039278 -149.926214) (xy 240.049812 -149.926802)
			(xy 240.124488 -149.926802) (xy 240.135038 -149.926279) (xy 240.154334 -149.917739) (xy 240.161826 -149.910292)
			(xy 240.181646 -149.889504) (xy 240.226418 -149.853529) (xy 240.276076 -149.824669) (xy 240.329498 -149.803576)
			(xy 240.385477 -149.790727) (xy 240.44275 -149.786412) (xy 240.500023 -149.790727) (xy 240.556002 -149.803576)
			(xy 240.609424 -149.824669) (xy 240.659082 -149.853529) (xy 240.703854 -149.889504) (xy 240.723674 -149.910292)
			(xy 240.731204 -149.917683) (xy 240.750478 -149.926214) (xy 240.761012 -149.926802) (xy 240.835688 -149.926802)
			(xy 240.846238 -149.926279) (xy 240.865534 -149.917739) (xy 240.873026 -149.910292) (xy 240.891174 -149.891229)
			(xy 240.931806 -149.857773) (xy 240.976648 -149.830215) (xy 241.02485 -149.809078) (xy 241.075498 -149.794762)
			(xy 241.127633 -149.787539) (xy 241.15395 -149.787102) (xy 241.181206 -149.787541) (xy 241.235164 -149.795293)
			(xy 241.287469 -149.810645) (xy 241.337057 -149.833285) (xy 241.382917 -149.862753) (xy 241.424117 -149.898447)
			(xy 241.459817 -149.939642) (xy 241.489291 -149.985499) (xy 241.511938 -150.035084) (xy 241.527297 -150.087387)
			(xy 241.535055 -150.141344) (xy 241.535055 -150.195854) (xy 243.350465 -150.195854) (xy 243.350465 -150.141346)
			(xy 243.358223 -150.087393) (xy 243.373581 -150.035093) (xy 243.396226 -149.985511) (xy 243.425697 -149.939657)
			(xy 243.461394 -149.898465) (xy 243.502591 -149.862772) (xy 243.548448 -149.833306) (xy 243.598032 -149.810666)
			(xy 243.650334 -149.795314) (xy 243.704288 -149.787562) (xy 243.731542 -149.787102) (xy 243.757857 -149.787541)
			(xy 243.809987 -149.794781) (xy 243.86063 -149.809106) (xy 243.908829 -149.830244) (xy 243.953672 -149.857795)
			(xy 243.99431 -149.891238) (xy 244.012466 -149.910292) (xy 244.019999 -149.917679) (xy 244.03927 -149.926212)
			(xy 244.049804 -149.926802) (xy 244.12448 -149.926802) (xy 244.13503 -149.926275) (xy 244.154325 -149.917738)
			(xy 244.161818 -149.910292) (xy 244.181638 -149.889504) (xy 244.22641 -149.853529) (xy 244.276068 -149.824669)
			(xy 244.32949 -149.803576) (xy 244.385469 -149.790727) (xy 244.442742 -149.786412) (xy 244.500015 -149.790727)
			(xy 244.555994 -149.803576) (xy 244.609416 -149.824669) (xy 244.659074 -149.853529) (xy 244.703846 -149.889504)
			(xy 244.723666 -149.910292) (xy 244.731199 -149.917679) (xy 244.75047 -149.926212) (xy 244.761004 -149.926802)
			(xy 244.83568 -149.926802) (xy 244.84623 -149.926275) (xy 244.865525 -149.917738) (xy 244.873018 -149.910292)
			(xy 244.89117 -149.891233) (xy 244.931801 -149.857777) (xy 244.976642 -149.830218) (xy 245.024843 -149.80908)
			(xy 245.075491 -149.794764) (xy 245.127626 -149.78754) (xy 245.153942 -149.787102) (xy 245.181192 -149.787571)
			(xy 245.235137 -149.795332) (xy 245.287428 -149.810691) (xy 245.337001 -149.833336) (xy 245.382847 -149.862804)
			(xy 245.424034 -149.898496) (xy 245.459721 -149.939686) (xy 245.489185 -149.985536) (xy 245.511823 -150.035112)
			(xy 245.520145 -150.063454) (xy 248.03811 -150.063454) (xy 248.042181 -150.007832) (xy 248.054307 -149.953395)
			(xy 248.07423 -149.901304) (xy 248.101526 -149.852669) (xy 248.135612 -149.808526) (xy 248.175761 -149.769817)
			(xy 248.221119 -149.737366) (xy 248.270719 -149.711865) (xy 248.323503 -149.693858) (xy 248.378346 -149.683728)
			(xy 248.43408 -149.681691) (xy 248.489517 -149.687791) (xy 248.543474 -149.701897) (xy 248.594803 -149.723709)
			(xy 248.642409 -149.752763) (xy 248.685277 -149.788438) (xy 248.722494 -149.829975) (xy 248.753267 -149.876488)
			(xy 248.762803 -149.89683) (xy 249.909836 -149.89683) (xy 249.913907 -149.841208) (xy 249.926033 -149.786771)
			(xy 249.945956 -149.73468) (xy 249.973252 -149.686045) (xy 250.007338 -149.641902) (xy 250.047487 -149.603193)
			(xy 250.092845 -149.570742) (xy 250.142445 -149.545241) (xy 250.195229 -149.527234) (xy 250.250072 -149.517104)
			(xy 250.305806 -149.515067) (xy 250.361243 -149.521167) (xy 250.4152 -149.535273) (xy 250.466529 -149.557085)
			(xy 250.514135 -149.586139) (xy 250.557003 -149.621814) (xy 250.59422 -149.663351) (xy 250.624993 -149.709864)
			(xy 250.648665 -149.760361) (xy 250.664733 -149.813768) (xy 250.672853 -149.868944) (xy 250.673362 -149.89683)
			(xy 250.673153 -149.90826) (xy 251.076712 -149.90826) (xy 251.080783 -149.852638) (xy 251.092909 -149.798201)
			(xy 251.112832 -149.74611) (xy 251.140128 -149.697475) (xy 251.174214 -149.653332) (xy 251.214363 -149.614623)
			(xy 251.259721 -149.582172) (xy 251.309321 -149.556671) (xy 251.362105 -149.538664) (xy 251.416948 -149.528534)
			(xy 251.472682 -149.526497) (xy 251.528119 -149.532597) (xy 251.582076 -149.546703) (xy 251.633405 -149.568515)
			(xy 251.681011 -149.597569) (xy 251.723879 -149.633244) (xy 251.761096 -149.674781) (xy 251.791869 -149.721294)
			(xy 251.815541 -149.771791) (xy 251.831609 -149.825198) (xy 251.839729 -149.880374) (xy 251.840238 -149.90826)
			(xy 251.839729 -149.936146) (xy 251.831609 -149.991322) (xy 251.815541 -150.044729) (xy 251.791869 -150.095226)
			(xy 251.761096 -150.141739) (xy 251.723879 -150.183276) (xy 251.681011 -150.218951) (xy 251.633405 -150.248005)
			(xy 251.582076 -150.269817) (xy 251.528119 -150.283923) (xy 251.472682 -150.290023) (xy 251.416948 -150.287986)
			(xy 251.362105 -150.277856) (xy 251.309321 -150.259849) (xy 251.259721 -150.234348) (xy 251.214363 -150.201897)
			(xy 251.174214 -150.163188) (xy 251.140128 -150.119045) (xy 251.112832 -150.07041) (xy 251.092909 -150.018319)
			(xy 251.080783 -149.963882) (xy 251.076712 -149.90826) (xy 250.673153 -149.90826) (xy 250.672853 -149.924716)
			(xy 250.664733 -149.979892) (xy 250.648665 -150.033299) (xy 250.624993 -150.083796) (xy 250.59422 -150.130309)
			(xy 250.557003 -150.171846) (xy 250.514135 -150.207521) (xy 250.466529 -150.236575) (xy 250.4152 -150.258387)
			(xy 250.361243 -150.272493) (xy 250.305806 -150.278593) (xy 250.250072 -150.276556) (xy 250.195229 -150.266426)
			(xy 250.142445 -150.248419) (xy 250.092845 -150.222918) (xy 250.047487 -150.190467) (xy 250.007338 -150.151758)
			(xy 249.973252 -150.107615) (xy 249.945956 -150.05898) (xy 249.926033 -150.006889) (xy 249.913907 -149.952452)
			(xy 249.909836 -149.89683) (xy 248.762803 -149.89683) (xy 248.776939 -149.926985) (xy 248.793007 -149.980392)
			(xy 248.801127 -150.035568) (xy 248.801636 -150.063454) (xy 248.801127 -150.09134) (xy 248.793007 -150.146516)
			(xy 248.776939 -150.199923) (xy 248.753267 -150.25042) (xy 248.722494 -150.296933) (xy 248.685277 -150.33847)
			(xy 248.642409 -150.374145) (xy 248.594803 -150.403199) (xy 248.543474 -150.425011) (xy 248.489517 -150.439117)
			(xy 248.43408 -150.445217) (xy 248.378346 -150.44318) (xy 248.323503 -150.43305) (xy 248.270719 -150.415043)
			(xy 248.221119 -150.389542) (xy 248.175761 -150.357091) (xy 248.135612 -150.318382) (xy 248.101526 -150.274239)
			(xy 248.07423 -150.225604) (xy 248.054307 -150.173513) (xy 248.042181 -150.119076) (xy 248.03811 -150.063454)
			(xy 245.520145 -150.063454) (xy 245.527177 -150.087404) (xy 245.534932 -150.14135) (xy 245.534932 -150.19585)
			(xy 245.527177 -150.249796) (xy 245.511823 -150.302088) (xy 245.489185 -150.351664) (xy 245.459721 -150.397514)
			(xy 245.424034 -150.438704) (xy 245.382847 -150.474396) (xy 245.337001 -150.503864) (xy 245.287428 -150.526509)
			(xy 245.235137 -150.541868) (xy 245.181192 -150.549629) (xy 245.153942 -150.550118) (xy 245.127627 -150.549683)
			(xy 245.075497 -150.542441) (xy 245.024854 -150.528115) (xy 244.976655 -150.506976) (xy 244.931813 -150.479425)
			(xy 244.891174 -150.445982) (xy 244.873018 -150.426928) (xy 244.865488 -150.419536) (xy 244.846215 -150.411005)
			(xy 244.83568 -150.410418) (xy 244.761004 -150.410418) (xy 244.750452 -150.410931) (xy 244.731157 -150.419477)
			(xy 244.723666 -150.426928) (xy 244.703846 -150.447716) (xy 244.659074 -150.483691) (xy 244.609416 -150.512551)
			(xy 244.555994 -150.533644) (xy 244.500015 -150.546493) (xy 244.442742 -150.550808) (xy 244.385469 -150.546493)
			(xy 244.32949 -150.533644) (xy 244.276068 -150.512551) (xy 244.22641 -150.483691) (xy 244.181638 -150.447716)
			(xy 244.161818 -150.426928) (xy 244.154288 -150.419536) (xy 244.135015 -150.411005) (xy 244.12448 -150.410418)
			(xy 244.049804 -150.410418) (xy 244.039252 -150.410931) (xy 244.019957 -150.419477) (xy 244.012466 -150.426928)
			(xy 243.994325 -150.445998) (xy 243.953692 -150.479453) (xy 243.908848 -150.507009) (xy 243.860645 -150.528145)
			(xy 243.809995 -150.542459) (xy 243.757859 -150.549681) (xy 243.731542 -150.550118) (xy 243.704288 -150.549638)
			(xy 243.650334 -150.541886) (xy 243.598032 -150.526534) (xy 243.548448 -150.503894) (xy 243.502591 -150.474428)
			(xy 243.461394 -150.438735) (xy 243.425697 -150.397543) (xy 243.396226 -150.351689) (xy 243.373581 -150.302107)
			(xy 243.358223 -150.249807) (xy 243.350465 -150.195854) (xy 241.535055 -150.195854) (xy 241.535055 -150.195856)
			(xy 241.527297 -150.249813) (xy 241.511938 -150.302116) (xy 241.489291 -150.351701) (xy 241.459817 -150.397558)
			(xy 241.424117 -150.438753) (xy 241.382917 -150.474447) (xy 241.337057 -150.503915) (xy 241.287469 -150.526555)
			(xy 241.235164 -150.541907) (xy 241.181206 -150.549659) (xy 241.15395 -150.550118) (xy 241.127635 -150.549678)
			(xy 241.075506 -150.542437) (xy 241.024863 -150.528112) (xy 240.976664 -150.506974) (xy 240.931821 -150.479424)
			(xy 240.891182 -150.445981) (xy 240.873026 -150.426928) (xy 240.865493 -150.41954) (xy 240.846222 -150.411007)
			(xy 240.835688 -150.410418) (xy 240.761012 -150.410418) (xy 240.750461 -150.410935) (xy 240.731165 -150.419478)
			(xy 240.723674 -150.426928) (xy 240.703854 -150.447716) (xy 240.659082 -150.483691) (xy 240.609424 -150.512551)
			(xy 240.556002 -150.533644) (xy 240.500023 -150.546493) (xy 240.44275 -150.550808) (xy 240.385477 -150.546493)
			(xy 240.329498 -150.533644) (xy 240.276076 -150.512551) (xy 240.226418 -150.483691) (xy 240.181646 -150.447716)
			(xy 240.161826 -150.426928) (xy 240.154293 -150.41954) (xy 240.135022 -150.411007) (xy 240.124488 -150.410418)
			(xy 240.049812 -150.410418) (xy 240.039261 -150.410935) (xy 240.019965 -150.419478) (xy 240.012474 -150.426928)
			(xy 239.99433 -150.445995) (xy 239.953697 -150.47945) (xy 239.908854 -150.507006) (xy 239.860651 -150.528143)
			(xy 239.810002 -150.542458) (xy 239.757867 -150.549681) (xy 239.73155 -150.550118) (xy 239.704302 -150.549608)
			(xy 239.650361 -150.541846) (xy 239.598074 -150.526487) (xy 239.548504 -150.503844) (xy 239.502661 -150.474377)
			(xy 239.461478 -150.438686) (xy 239.425793 -150.397499) (xy 239.396332 -150.351652) (xy 239.373695 -150.302079)
			(xy 239.358343 -150.24979) (xy 239.350588 -150.195848) (xy 236.985814 -150.195848) (xy 236.978921 -150.21145)
			(xy 236.948194 -150.262081) (xy 236.929676 -150.285196) (xy 236.924149 -150.292508) (xy 236.918156 -150.309814)
			(xy 236.917992 -150.318978) (xy 236.920024 -150.395178) (xy 236.926882 -150.411942) (xy 236.933232 -150.4188)
			(xy 236.95055 -150.438196) (xy 236.980554 -150.480663) (xy 237.004815 -150.526653) (xy 237.014258 -150.55088)
			(xy 237.017652 -150.558963) (xy 237.028953 -150.572347) (xy 237.036356 -150.577042) (xy 237.062264 -150.592282)
			(xy 237.07006 -150.596524) (xy 237.087498 -150.599774) (xy 237.0963 -150.598632) (xy 237.114648 -150.595797)
			(xy 237.15165 -150.592743) (xy 237.170214 -150.592536) (xy 237.200199 -150.593015) (xy 237.259654 -150.600844)
			(xy 237.31758 -150.616367) (xy 237.372983 -150.639317) (xy 237.424918 -150.669303) (xy 237.472494 -150.70581)
			(xy 237.514898 -150.748215) (xy 237.551404 -150.795792) (xy 237.581388 -150.847727) (xy 237.604337 -150.903132)
			(xy 237.619858 -150.961057) (xy 237.627686 -151.020513) (xy 237.628176 -151.050498) (xy 237.628176 -151.67102)
			(xy 247.99366 -151.67102) (xy 247.997731 -151.615398) (xy 248.009857 -151.560961) (xy 248.02978 -151.50887)
			(xy 248.057076 -151.460235) (xy 248.091162 -151.416092) (xy 248.131311 -151.377383) (xy 248.176669 -151.344932)
			(xy 248.226269 -151.319431) (xy 248.279053 -151.301424) (xy 248.333896 -151.291294) (xy 248.38963 -151.289257)
			(xy 248.445067 -151.295357) (xy 248.499024 -151.309463) (xy 248.550353 -151.331275) (xy 248.597959 -151.360329)
			(xy 248.640827 -151.396004) (xy 248.678044 -151.437541) (xy 248.708817 -151.484054) (xy 248.732489 -151.534551)
			(xy 248.748557 -151.587958) (xy 248.756677 -151.643134) (xy 248.757186 -151.67102) (xy 248.756713 -151.696928)
			(xy 249.00966 -151.696928) (xy 249.013731 -151.641306) (xy 249.025857 -151.586869) (xy 249.04578 -151.534778)
			(xy 249.073076 -151.486143) (xy 249.107162 -151.442) (xy 249.147311 -151.403291) (xy 249.192669 -151.37084)
			(xy 249.242269 -151.345339) (xy 249.295053 -151.327332) (xy 249.349896 -151.317202) (xy 249.40563 -151.315165)
			(xy 249.461067 -151.321265) (xy 249.515024 -151.335371) (xy 249.566353 -151.357183) (xy 249.613959 -151.386237)
			(xy 249.638435 -151.406606) (xy 250.236734 -151.406606) (xy 250.240805 -151.350984) (xy 250.252931 -151.296547)
			(xy 250.272854 -151.244456) (xy 250.30015 -151.195821) (xy 250.334236 -151.151678) (xy 250.374385 -151.112969)
			(xy 250.419743 -151.080518) (xy 250.469343 -151.055017) (xy 250.522127 -151.03701) (xy 250.57697 -151.02688)
			(xy 250.632704 -151.024843) (xy 250.688141 -151.030943) (xy 250.742098 -151.045049) (xy 250.793427 -151.066861)
			(xy 250.841033 -151.095915) (xy 250.883901 -151.13159) (xy 250.921118 -151.173127) (xy 250.951891 -151.21964)
			(xy 250.975563 -151.270137) (xy 250.991631 -151.323544) (xy 250.999751 -151.37872) (xy 251.00026 -151.406606)
			(xy 250.999751 -151.434492) (xy 250.991631 -151.489668) (xy 250.975563 -151.543075) (xy 250.957021 -151.582628)
			(xy 251.56236 -151.582628) (xy 251.566431 -151.527006) (xy 251.578557 -151.472569) (xy 251.59848 -151.420478)
			(xy 251.625776 -151.371843) (xy 251.659862 -151.3277) (xy 251.700011 -151.288991) (xy 251.745369 -151.25654)
			(xy 251.794969 -151.231039) (xy 251.847753 -151.213032) (xy 251.902596 -151.202902) (xy 251.95833 -151.200865)
			(xy 252.013767 -151.206965) (xy 252.067724 -151.221071) (xy 252.119053 -151.242883) (xy 252.166659 -151.271937)
			(xy 252.209527 -151.307612) (xy 252.246744 -151.349149) (xy 252.277517 -151.395662) (xy 252.301189 -151.446159)
			(xy 252.317257 -151.499566) (xy 252.325377 -151.554742) (xy 252.32564 -151.569166) (xy 253.07366 -151.569166)
			(xy 253.077731 -151.513544) (xy 253.089857 -151.459107) (xy 253.10978 -151.407016) (xy 253.137076 -151.358381)
			(xy 253.171162 -151.314238) (xy 253.211311 -151.275529) (xy 253.256669 -151.243078) (xy 253.306269 -151.217577)
			(xy 253.359053 -151.19957) (xy 253.413896 -151.18944) (xy 253.46963 -151.187403) (xy 253.525067 -151.193503)
			(xy 253.579024 -151.207609) (xy 253.630353 -151.229421) (xy 253.677959 -151.258475) (xy 253.720827 -151.29415)
			(xy 253.758044 -151.335687) (xy 253.788817 -151.3822) (xy 253.812489 -151.432697) (xy 253.828557 -151.486104)
			(xy 253.836677 -151.54128) (xy 253.837186 -151.569166) (xy 253.836677 -151.597052) (xy 253.828557 -151.652228)
			(xy 253.812489 -151.705635) (xy 253.788817 -151.756132) (xy 253.758044 -151.802645) (xy 253.720827 -151.844182)
			(xy 253.677959 -151.879857) (xy 253.630353 -151.908911) (xy 253.579024 -151.930723) (xy 253.525067 -151.944829)
			(xy 253.46963 -151.950929) (xy 253.413896 -151.948892) (xy 253.359053 -151.938762) (xy 253.306269 -151.920755)
			(xy 253.256669 -151.895254) (xy 253.211311 -151.862803) (xy 253.171162 -151.824094) (xy 253.137076 -151.779951)
			(xy 253.10978 -151.731316) (xy 253.089857 -151.679225) (xy 253.077731 -151.624788) (xy 253.07366 -151.569166)
			(xy 252.32564 -151.569166) (xy 252.325886 -151.582628) (xy 252.325377 -151.610514) (xy 252.317257 -151.66569)
			(xy 252.301189 -151.719097) (xy 252.277517 -151.769594) (xy 252.246744 -151.816107) (xy 252.209527 -151.857644)
			(xy 252.166659 -151.893319) (xy 252.119053 -151.922373) (xy 252.067724 -151.944185) (xy 252.013767 -151.958291)
			(xy 251.95833 -151.964391) (xy 251.902596 -151.962354) (xy 251.847753 -151.952224) (xy 251.794969 -151.934217)
			(xy 251.745369 -151.908716) (xy 251.700011 -151.876265) (xy 251.659862 -151.837556) (xy 251.625776 -151.793413)
			(xy 251.59848 -151.744778) (xy 251.578557 -151.692687) (xy 251.566431 -151.63825) (xy 251.56236 -151.582628)
			(xy 250.957021 -151.582628) (xy 250.951891 -151.593572) (xy 250.921118 -151.640085) (xy 250.883901 -151.681622)
			(xy 250.841033 -151.717297) (xy 250.793427 -151.746351) (xy 250.742098 -151.768163) (xy 250.688141 -151.782269)
			(xy 250.632704 -151.788369) (xy 250.57697 -151.786332) (xy 250.522127 -151.776202) (xy 250.469343 -151.758195)
			(xy 250.419743 -151.732694) (xy 250.374385 -151.700243) (xy 250.334236 -151.661534) (xy 250.30015 -151.617391)
			(xy 250.272854 -151.568756) (xy 250.252931 -151.516665) (xy 250.240805 -151.462228) (xy 250.236734 -151.406606)
			(xy 249.638435 -151.406606) (xy 249.656827 -151.421912) (xy 249.694044 -151.463449) (xy 249.724817 -151.509962)
			(xy 249.748489 -151.560459) (xy 249.764557 -151.613866) (xy 249.772677 -151.669042) (xy 249.773186 -151.696928)
			(xy 249.772677 -151.724814) (xy 249.764557 -151.77999) (xy 249.748489 -151.833397) (xy 249.724817 -151.883894)
			(xy 249.694044 -151.930407) (xy 249.656827 -151.971944) (xy 249.613959 -152.007619) (xy 249.566353 -152.036673)
			(xy 249.515024 -152.058485) (xy 249.461067 -152.072591) (xy 249.40563 -152.078691) (xy 249.349896 -152.076654)
			(xy 249.295053 -152.066524) (xy 249.242269 -152.048517) (xy 249.192669 -152.023016) (xy 249.147311 -151.990565)
			(xy 249.107162 -151.951856) (xy 249.073076 -151.907713) (xy 249.04578 -151.859078) (xy 249.025857 -151.806987)
			(xy 249.013731 -151.75255) (xy 249.00966 -151.696928) (xy 248.756713 -151.696928) (xy 248.756677 -151.698906)
			(xy 248.748557 -151.754082) (xy 248.732489 -151.807489) (xy 248.708817 -151.857986) (xy 248.678044 -151.904499)
			(xy 248.640827 -151.946036) (xy 248.597959 -151.981711) (xy 248.550353 -152.010765) (xy 248.499024 -152.032577)
			(xy 248.445067 -152.046683) (xy 248.38963 -152.052783) (xy 248.333896 -152.050746) (xy 248.279053 -152.040616)
			(xy 248.226269 -152.022609) (xy 248.176669 -151.997108) (xy 248.131311 -151.964657) (xy 248.091162 -151.925948)
			(xy 248.057076 -151.881805) (xy 248.02978 -151.83317) (xy 248.009857 -151.781079) (xy 247.997731 -151.726642)
			(xy 247.99366 -151.67102) (xy 237.628176 -151.67102) (xy 237.628176 -151.914098) (xy 237.62767 -151.944082)
			(xy 237.619843 -152.003536) (xy 237.604323 -152.06146) (xy 237.581375 -152.116863) (xy 237.551392 -152.168797)
			(xy 237.514887 -152.216372) (xy 237.472484 -152.258776) (xy 237.42491 -152.295283) (xy 237.372977 -152.325268)
			(xy 237.317575 -152.348218) (xy 237.259652 -152.36374) (xy 237.200198 -152.371569) (xy 237.170214 -152.37206)
			(xy 237.147127 -152.371733) (xy 237.101193 -152.367025) (xy 237.07852 -152.362662) (xy 237.069817 -152.361286)
			(xy 237.052405 -152.363884) (xy 237.044484 -152.367742) (xy 237.017814 -152.381712) (xy 237.0103 -152.386184)
			(xy 236.998607 -152.399168) (xy 236.994954 -152.407112) (xy 236.983076 -152.434082) (xy 236.952631 -152.484536)
			(xy 236.915132 -152.529994) (xy 236.871387 -152.569477) (xy 236.822337 -152.602137) (xy 236.769037 -152.62727)
			(xy 236.712633 -152.644336) (xy 236.65434 -152.652967) (xy 236.624876 -152.653492) (xy 236.596256 -152.653025)
			(xy 236.539598 -152.644878) (xy 236.484676 -152.628755) (xy 236.432605 -152.604983) (xy 236.384446 -152.574045)
			(xy 236.341178 -152.53657) (xy 236.303681 -152.493322) (xy 236.272718 -152.445179) (xy 236.248918 -152.393121)
			(xy 236.232766 -152.338207) (xy 236.22459 -152.281554) (xy 236.224064 -152.252934) (xy 236.224064 -152.252426)
			(xy 236.224535 -152.224302) (xy 236.232417 -152.168608) (xy 236.248001 -152.114562) (xy 236.270983 -152.063222)
			(xy 236.300912 -152.015597) (xy 236.3372 -151.972619) (xy 236.379136 -151.935132) (xy 236.425897 -151.903871)
			(xy 236.476567 -151.879449) (xy 236.530152 -151.862345) (xy 236.585601 -151.852893) (xy 236.6137 -151.851614)
			(xy 236.623606 -151.85136) (xy 236.64164 -151.843486) (xy 236.697774 -151.785574) (xy 236.704323 -151.778251)
			(xy 236.711757 -151.760081) (xy 236.712252 -151.750268) (xy 236.712252 -151.19223) (xy 236.711865 -151.182614)
			(xy 236.704818 -151.164723) (xy 236.698536 -151.157432) (xy 236.643672 -151.09952) (xy 236.626146 -151.091392)
			(xy 236.61624 -151.090884) (xy 236.588674 -151.088851) (xy 236.534424 -151.078271) (xy 236.482142 -151.06034)
			(xy 236.432818 -151.035398) (xy 236.387388 -151.003916) (xy 236.346714 -150.966492) (xy 236.311565 -150.923836)
			(xy 236.282609 -150.876756) (xy 236.260395 -150.826145) (xy 236.245344 -150.772962) (xy 236.23774 -150.718216)
			(xy 236.237272 -150.69058) (xy 236.237789 -150.662857) (xy 236.245478 -150.607947) (xy 236.260651 -150.554617)
			(xy 236.283019 -150.503883) (xy 236.312157 -150.456711) (xy 236.329474 -150.435056) (xy 236.335016 -150.427754)
			(xy 236.341001 -150.41044) (xy 236.341158 -150.401274) (xy 236.339126 -150.325074) (xy 236.332268 -150.30831)
			(xy 236.325918 -150.301452) (xy 236.306108 -150.27916) (xy 236.272683 -150.229772) (xy 236.246936 -150.17598)
			(xy 236.229435 -150.11897) (xy 236.220566 -150.059998) (xy 236.22 -150.03018) (xy 234.083747 -150.03018)
			(xy 234.070306 -150.034127) (xy 234.016366 -150.041885) (xy 233.989118 -150.042372) (xy 233.962247 -150.041881)
			(xy 233.909037 -150.034328) (xy 233.857413 -150.019383) (xy 233.808398 -149.997342) (xy 233.762961 -149.96864)
			(xy 233.722001 -149.933846) (xy 233.686329 -149.893649) (xy 233.65665 -149.848843) (xy 233.633553 -149.800316)
			(xy 233.617494 -149.749029) (xy 233.61269 -149.722586) (xy 233.611166 -149.71268) (xy 233.600752 -149.695916)
			(xy 233.535474 -149.64791) (xy 233.527334 -149.642476) (xy 233.508391 -149.637632) (xy 233.498644 -149.638512)
			(xy 233.49839 -149.638512) (xy 233.4855 -149.640167) (xy 233.45957 -149.641948) (xy 233.446574 -149.642068)
			(xy 233.44632 -149.642068) (xy 233.419063 -149.641686) (xy 233.365105 -149.633931) (xy 233.312799 -149.618575)
			(xy 233.263211 -149.595931) (xy 233.21735 -149.566461) (xy 233.176151 -149.530763) (xy 233.140451 -149.489566)
			(xy 233.110978 -149.443707) (xy 233.088332 -149.39412) (xy 233.072973 -149.341815) (xy 233.065215 -149.287857)
			(xy 231.180708 -149.287857) (xy 231.162206 -149.309209) (xy 231.121016 -149.3449) (xy 231.075166 -149.374366)
			(xy 231.025589 -149.397007) (xy 230.973294 -149.412361) (xy 230.919347 -149.420117) (xy 230.892096 -149.42058)
			(xy 230.85933 -149.419056) (xy 230.859076 -149.419056) (xy 230.849928 -149.418748) (xy 230.832356 -149.423819)
			(xy 230.824786 -149.428962) (xy 230.77043 -149.469348) (xy 230.763286 -149.475068) (xy 230.753398 -149.490453)
			(xy 230.751126 -149.49932) (xy 230.751126 -149.499828) (xy 230.744737 -149.52805) (xy 230.724452 -149.582243)
			(xy 230.696217 -149.632752) (xy 230.660677 -149.678416) (xy 230.618649 -149.718191) (xy 230.571096 -149.751162)
			(xy 230.519109 -149.776573) (xy 230.463881 -149.793842) (xy 230.406679 -149.802573) (xy 230.377746 -149.803104)
			(xy 230.350491 -149.802652) (xy 230.296534 -149.7949) (xy 230.24423 -149.779548) (xy 230.194644 -149.756908)
			(xy 230.148785 -149.727441) (xy 230.107586 -149.691747) (xy 230.071887 -149.650552) (xy 230.042414 -149.604697)
			(xy 230.019768 -149.555113) (xy 230.00441 -149.502811) (xy 229.996651 -149.448855) (xy 229.650444 -149.448855)
			(xy 229.650289 -149.457356) (xy 229.642169 -149.512532) (xy 229.626101 -149.565939) (xy 229.602429 -149.616436)
			(xy 229.571656 -149.662949) (xy 229.534439 -149.704486) (xy 229.491571 -149.740161) (xy 229.443965 -149.769215)
			(xy 229.392636 -149.791027) (xy 229.338679 -149.805133) (xy 229.283242 -149.811233) (xy 229.227508 -149.809196)
			(xy 229.172665 -149.799066) (xy 229.119881 -149.781059) (xy 229.070281 -149.755558) (xy 229.024923 -149.723107)
			(xy 228.984774 -149.684398) (xy 228.950688 -149.640255) (xy 228.923392 -149.59162) (xy 228.903469 -149.539529)
			(xy 228.891343 -149.485092) (xy 228.887272 -149.42947) (xy 228.532366 -149.42947) (xy 228.532436 -149.43328)
			(xy 228.531927 -149.461166) (xy 228.523807 -149.516342) (xy 228.507739 -149.569749) (xy 228.484067 -149.620246)
			(xy 228.453294 -149.666759) (xy 228.416077 -149.708296) (xy 228.373209 -149.743971) (xy 228.325603 -149.773025)
			(xy 228.274274 -149.794837) (xy 228.220317 -149.808943) (xy 228.16488 -149.815043) (xy 228.109146 -149.813006)
			(xy 228.054303 -149.802876) (xy 228.001519 -149.784869) (xy 227.951919 -149.759368) (xy 227.906561 -149.726917)
			(xy 227.866412 -149.688208) (xy 227.832326 -149.644065) (xy 227.80503 -149.59543) (xy 227.785107 -149.543339)
			(xy 227.772981 -149.488902) (xy 227.76891 -149.43328) (xy 227.460784 -149.43328) (xy 227.460784 -149.443548)
			(xy 227.453028 -149.497489) (xy 227.437675 -149.549778) (xy 227.415037 -149.59935) (xy 227.385575 -149.645195)
			(xy 227.349888 -149.686381) (xy 227.308703 -149.722069) (xy 227.262858 -149.751532) (xy 227.213288 -149.774172)
			(xy 227.160999 -149.789526) (xy 227.107058 -149.797283) (xy 227.07981 -149.79777) (xy 227.050832 -149.797225)
			(xy 226.993543 -149.788467) (xy 226.938236 -149.77115) (xy 226.886181 -149.745672) (xy 226.838576 -149.712619)
			(xy 226.796514 -149.67275) (xy 226.778312 -149.650196) (xy 226.769699 -149.639682) (xy 226.74797 -149.623364)
			(xy 226.722704 -149.61336) (xy 226.695695 -149.610378) (xy 226.668856 -149.614629) (xy 226.64409 -149.625813)
			(xy 226.623154 -149.643137) (xy 226.61499 -149.654006) (xy 226.599646 -149.675151) (xy 226.564033 -149.713378)
			(xy 226.523538 -149.74639) (xy 226.478919 -149.77357) (xy 226.43101 -149.794409) (xy 226.380706 -149.808519)
			(xy 226.328947 -149.815635) (xy 226.302824 -149.816058) (xy 226.275574 -149.815496) (xy 226.221627 -149.807743)
			(xy 226.169333 -149.792391) (xy 226.119757 -149.769753) (xy 226.073906 -149.74029) (xy 226.032716 -149.704601)
			(xy 225.997025 -149.663413) (xy 225.967558 -149.617564) (xy 225.944917 -149.567989) (xy 225.929562 -149.515696)
			(xy 225.921805 -149.46175) (xy 224.271406 -149.46175) (xy 224.267783 -149.48637) (xy 224.251715 -149.539777)
			(xy 224.228043 -149.590274) (xy 224.19727 -149.636787) (xy 224.160053 -149.678324) (xy 224.117185 -149.713999)
			(xy 224.069579 -149.743053) (xy 224.01825 -149.764865) (xy 223.964293 -149.778971) (xy 223.908856 -149.785071)
			(xy 223.853122 -149.783034) (xy 223.798279 -149.772904) (xy 223.745495 -149.754897) (xy 223.695895 -149.729396)
			(xy 223.650537 -149.696945) (xy 223.610388 -149.658236) (xy 223.576302 -149.614093) (xy 223.549006 -149.565458)
			(xy 223.529083 -149.513367) (xy 223.516957 -149.45893) (xy 223.512886 -149.403308) (xy 201.151022 -149.403308)
			(xy 201.149076 -149.404994) (xy 201.100874 -149.435972) (xy 201.048754 -149.459776) (xy 200.993776 -149.47592)
			(xy 200.937061 -149.484076) (xy 200.908412 -149.484588) (xy 200.881033 -149.484076) (xy 200.826787 -149.476612)
			(xy 200.77406 -149.461834) (xy 200.723836 -149.440019) (xy 200.677048 -149.411571) (xy 200.634566 -149.377021)
			(xy 200.597182 -149.33701) (xy 200.581006 -149.314916) (xy 200.575437 -149.307661) (xy 200.560333 -149.297373)
			(xy 200.551542 -149.29485) (xy 200.52157 -149.287484) (xy 200.512622 -149.285719) (xy 200.49453 -149.287945)
			(xy 200.486264 -149.291802) (xy 200.461669 -149.304203) (xy 200.410141 -149.323669) (xy 200.35665 -149.336814)
			(xy 200.301969 -149.343449) (xy 200.274428 -149.343872) (xy 200.246887 -149.343455) (xy 200.192207 -149.336815)
			(xy 200.138717 -149.323665) (xy 200.087191 -149.304194) (xy 200.062592 -149.291802) (xy 200.054334 -149.287921)
			(xy 200.036236 -149.285708) (xy 200.027286 -149.287484) (xy 199.997314 -149.29485) (xy 199.988535 -149.297401)
			(xy 199.973432 -149.307677) (xy 199.96785 -149.314916) (xy 199.95172 -149.33705) (xy 199.914341 -149.37708)
			(xy 199.871857 -149.411645) (xy 199.825062 -149.440102) (xy 199.774827 -149.46192) (xy 199.722088 -149.476693)
			(xy 199.667828 -149.484145) (xy 199.640444 -149.484588) (xy 199.611794 -149.48406) (xy 199.555075 -149.475911)
			(xy 199.500094 -149.459773) (xy 199.447969 -149.435973) (xy 199.399763 -149.404997) (xy 199.356455 -149.367476)
			(xy 199.318929 -149.324173) (xy 199.287948 -149.275969) (xy 199.264143 -149.223847) (xy 199.247998 -149.168868)
			(xy 199.239843 -149.11215) (xy 199.239843 -149.05485) (xy 199.247998 -148.998132) (xy 199.264143 -148.943153)
			(xy 199.287948 -148.891031) (xy 199.318929 -148.842827) (xy 199.356455 -148.799524) (xy 199.399763 -148.762003)
			(xy 199.447969 -148.731027) (xy 199.500094 -148.707227) (xy 199.555075 -148.691089) (xy 199.611794 -148.68294)
			(xy 199.640444 -148.682456) (xy 199.655362 -148.682625) (xy 199.685111 -148.684914) (xy 199.69988 -148.687028)
			(xy 199.711056 -148.688806) (xy 199.732138 -148.68271) (xy 199.799194 -148.625052) (xy 199.807136 -148.617438)
			(xy 199.816235 -148.597434) (xy 199.81672 -148.586444) (xy 199.81672 -148.321776) (xy 199.816221 -148.310786)
			(xy 199.807141 -148.290775) (xy 199.799194 -148.283168) (xy 199.732138 -148.22551) (xy 199.711056 -148.219414)
			(xy 199.69988 -148.221192) (xy 199.685111 -148.223305) (xy 199.655362 -148.22559) (xy 199.640444 -148.225764)
			(xy 199.611792 -148.225284) (xy 199.55507 -148.217135) (xy 199.500086 -148.200995) (xy 199.447958 -148.177194)
			(xy 199.399748 -148.146217) (xy 199.356438 -148.108693) (xy 199.31891 -148.065387) (xy 199.287927 -148.017181)
			(xy 199.26412 -147.965056) (xy 199.247975 -147.910073) (xy 199.239819 -147.853352) (xy 190.585156 -147.853352)
			(xy 190.570389 -147.865641) (xy 190.522783 -147.894695) (xy 190.471454 -147.916507) (xy 190.417497 -147.930613)
			(xy 190.36206 -147.936713) (xy 190.306326 -147.934676) (xy 190.251483 -147.924546) (xy 190.198699 -147.906539)
			(xy 190.149099 -147.881038) (xy 190.103741 -147.848587) (xy 190.063592 -147.809878) (xy 190.029506 -147.765735)
			(xy 190.00221 -147.7171) (xy 189.982287 -147.665009) (xy 189.970161 -147.610572) (xy 189.96609 -147.55495)
			(xy 188.624849 -147.55495) (xy 188.593957 -147.589428) (xy 188.551089 -147.625103) (xy 188.503483 -147.654157)
			(xy 188.452154 -147.675969) (xy 188.398197 -147.690075) (xy 188.34276 -147.696175) (xy 188.287026 -147.694138)
			(xy 188.232183 -147.684008) (xy 188.179399 -147.666001) (xy 188.129799 -147.6405) (xy 188.084441 -147.608049)
			(xy 188.044292 -147.56934) (xy 188.010206 -147.525197) (xy 187.98291 -147.476562) (xy 187.962987 -147.424471)
			(xy 187.950861 -147.370034) (xy 187.94679 -147.314412) (xy 184.372504 -147.314412) (xy 186.41314 -149.355048)
			(xy 189.96609 -149.355048) (xy 189.970161 -149.299426) (xy 189.982287 -149.244989) (xy 190.00221 -149.192898)
			(xy 190.029506 -149.144263) (xy 190.063592 -149.10012) (xy 190.103741 -149.061411) (xy 190.149099 -149.02896)
			(xy 190.198699 -149.003459) (xy 190.251483 -148.985452) (xy 190.306326 -148.975322) (xy 190.36206 -148.973285)
			(xy 190.417497 -148.979385) (xy 190.471454 -148.993491) (xy 190.522783 -149.015303) (xy 190.570389 -149.044357)
			(xy 190.613257 -149.080032) (xy 190.650474 -149.121569) (xy 190.681247 -149.168082) (xy 190.704919 -149.218579)
			(xy 190.720987 -149.271986) (xy 190.729107 -149.327162) (xy 190.729616 -149.355048) (xy 190.729107 -149.382934)
			(xy 190.720987 -149.43811) (xy 190.704919 -149.491517) (xy 190.681247 -149.542014) (xy 190.650474 -149.588527)
			(xy 190.613257 -149.630064) (xy 190.570389 -149.665739) (xy 190.522783 -149.694793) (xy 190.471454 -149.716605)
			(xy 190.417497 -149.730711) (xy 190.36206 -149.736811) (xy 190.306326 -149.734774) (xy 190.251483 -149.724644)
			(xy 190.198699 -149.706637) (xy 190.149099 -149.681136) (xy 190.103741 -149.648685) (xy 190.063592 -149.609976)
			(xy 190.029506 -149.565833) (xy 190.00221 -149.517198) (xy 189.982287 -149.465107) (xy 189.970161 -149.41067)
			(xy 189.96609 -149.355048) (xy 186.41314 -149.355048) (xy 188.213238 -151.155146) (xy 189.96609 -151.155146)
			(xy 189.970161 -151.099524) (xy 189.982287 -151.045087) (xy 190.00221 -150.992996) (xy 190.029506 -150.944361)
			(xy 190.063592 -150.900218) (xy 190.103741 -150.861509) (xy 190.149099 -150.829058) (xy 190.198699 -150.803557)
			(xy 190.251483 -150.78555) (xy 190.306326 -150.77542) (xy 190.36206 -150.773383) (xy 190.417497 -150.779483)
			(xy 190.471454 -150.793589) (xy 190.522783 -150.815401) (xy 190.570389 -150.844455) (xy 190.613257 -150.88013)
			(xy 190.635947 -150.905454) (xy 196.597683 -150.905454) (xy 196.597683 -150.848146) (xy 196.605839 -150.79142)
			(xy 196.621986 -150.736433) (xy 196.645794 -150.684304) (xy 196.676779 -150.636094) (xy 196.71431 -150.592785)
			(xy 196.757623 -150.555257) (xy 196.805836 -150.524277) (xy 196.857967 -150.500473) (xy 196.912956 -150.484332)
			(xy 196.969682 -150.47618) (xy 196.998336 -150.475696) (xy 197.013254 -150.475867) (xy 197.043003 -150.478155)
			(xy 197.057772 -150.480268) (xy 197.068948 -150.482046) (xy 197.09003 -150.47595) (xy 197.157086 -150.418292)
			(xy 197.16507 -150.410715) (xy 197.174142 -150.390683) (xy 197.174612 -150.379684) (xy 197.174612 -150.115016)
			(xy 197.174094 -150.104029) (xy 197.165027 -150.084017) (xy 197.157086 -150.076408) (xy 197.09003 -150.01875)
			(xy 197.068948 -150.012654) (xy 197.057772 -150.014432) (xy 197.043002 -150.016535) (xy 197.013254 -150.018827)
			(xy 196.998336 -150.019004) (xy 196.969687 -150.018444) (xy 196.912972 -150.010294) (xy 196.857994 -149.994155)
			(xy 196.805872 -149.970357) (xy 196.757668 -149.939382) (xy 196.714364 -149.901862) (xy 196.67684 -149.85856)
			(xy 196.645861 -149.810359) (xy 196.622057 -149.75824) (xy 196.605914 -149.703263) (xy 196.597759 -149.646549)
			(xy 196.597759 -149.589251) (xy 196.605914 -149.532537) (xy 196.622057 -149.47756) (xy 196.645861 -149.425441)
			(xy 196.67684 -149.37724) (xy 196.714364 -149.333938) (xy 196.757668 -149.296418) (xy 196.805872 -149.265443)
			(xy 196.857994 -149.241645) (xy 196.912972 -149.225506) (xy 196.969687 -149.217356) (xy 196.998336 -149.216872)
			(xy 197.025717 -149.217323) (xy 197.079967 -149.224795) (xy 197.132696 -149.239581) (xy 197.182922 -149.261406)
			(xy 197.229709 -149.289863) (xy 197.272188 -149.324424) (xy 197.309568 -149.364445) (xy 197.325742 -149.386544)
			(xy 197.331302 -149.393807) (xy 197.346412 -149.404091) (xy 197.355206 -149.40661) (xy 197.385178 -149.413976)
			(xy 197.39413 -149.415708) (xy 197.412216 -149.413502) (xy 197.420484 -149.409658) (xy 197.445086 -149.397273)
			(xy 197.496612 -149.377803) (xy 197.5501 -149.364654) (xy 197.60478 -149.358014) (xy 197.63232 -149.357588)
			(xy 197.65986 -149.35802) (xy 197.714541 -149.364654) (xy 197.76803 -149.377799) (xy 197.819557 -149.397267)
			(xy 197.844156 -149.409658) (xy 197.852424 -149.413513) (xy 197.870514 -149.415743) (xy 197.879462 -149.413976)
			(xy 197.909434 -149.40661) (xy 197.918224 -149.404091) (xy 197.933322 -149.393792) (xy 197.938898 -149.386544)
			(xy 197.955078 -149.364448) (xy 197.992447 -149.324414) (xy 198.034921 -149.289844) (xy 198.081708 -149.261381)
			(xy 198.131935 -149.239557) (xy 198.184668 -149.224777) (xy 198.238922 -149.217318) (xy 198.266304 -149.216872)
			(xy 198.294955 -149.217307) (xy 198.351673 -149.225462) (xy 198.406653 -149.241607) (xy 198.458777 -149.265411)
			(xy 198.506982 -149.296391) (xy 198.550287 -149.333916) (xy 198.587812 -149.377222) (xy 198.618791 -149.425427)
			(xy 198.642595 -149.47755) (xy 198.658738 -149.532531) (xy 198.666893 -149.589249) (xy 198.666893 -149.646551)
			(xy 198.658738 -149.703269) (xy 198.642595 -149.75825) (xy 198.618791 -149.810373) (xy 198.587812 -149.858578)
			(xy 198.550287 -149.901884) (xy 198.506982 -149.939409) (xy 198.458777 -149.970389) (xy 198.406653 -149.994193)
			(xy 198.351673 -150.010338) (xy 198.294955 -150.018493) (xy 198.266304 -150.019004) (xy 198.251386 -150.018829)
			(xy 198.221637 -150.016544) (xy 198.206868 -150.014432) (xy 198.195692 -150.012654) (xy 198.17461 -150.01875)
			(xy 198.107554 -150.076408) (xy 198.099576 -150.083991) (xy 198.090499 -150.104018) (xy 198.090028 -150.115016)
			(xy 198.090028 -150.379684) (xy 198.090534 -150.390673) (xy 198.099608 -150.410686) (xy 198.107554 -150.418292)
			(xy 198.17461 -150.47595) (xy 198.195692 -150.482046) (xy 198.206868 -150.480268) (xy 198.221637 -150.478161)
			(xy 198.251386 -150.475872) (xy 198.266304 -150.475696) (xy 198.294949 -150.476283) (xy 198.351657 -150.484437)
			(xy 198.406627 -150.500578) (xy 198.45874 -150.524378) (xy 198.506936 -150.555352) (xy 198.550233 -150.59287)
			(xy 198.58775 -150.636167) (xy 198.618724 -150.684363) (xy 198.642523 -150.736477) (xy 198.658664 -150.791447)
			(xy 198.666817 -150.848155) (xy 198.666817 -150.905445) (xy 198.658664 -150.962153) (xy 198.642523 -151.017123)
			(xy 198.618724 -151.069237) (xy 198.58775 -151.117433) (xy 198.550233 -151.16073) (xy 198.506936 -151.198248)
			(xy 198.45874 -151.229222) (xy 198.406627 -151.253022) (xy 198.351657 -151.269163) (xy 198.294949 -151.277317)
			(xy 198.266304 -151.277828) (xy 198.238924 -151.277347) (xy 198.184675 -151.269881) (xy 198.131947 -151.2551)
			(xy 198.081721 -151.23328) (xy 198.034933 -151.204827) (xy 197.992453 -151.17027) (xy 197.955072 -151.130253)
			(xy 197.938898 -151.108156) (xy 197.933324 -151.100906) (xy 197.918224 -151.090615) (xy 197.909434 -151.08809)
			(xy 197.879462 -151.080724) (xy 197.870514 -151.078961) (xy 197.852423 -151.081187) (xy 197.844156 -151.085042)
			(xy 197.819564 -151.097449) (xy 197.768035 -151.116913) (xy 197.714543 -151.130056) (xy 197.659861 -151.136689)
			(xy 197.63232 -151.137112) (xy 197.604779 -151.136705) (xy 197.550098 -151.130063) (xy 197.496608 -151.116911)
			(xy 197.445082 -151.097436) (xy 197.420484 -151.085042) (xy 197.412227 -151.081157) (xy 197.394128 -151.078946)
			(xy 197.385178 -151.080724) (xy 197.355206 -151.08809) (xy 197.346421 -151.090625) (xy 197.331321 -151.100912)
			(xy 197.325742 -151.108156) (xy 197.309599 -151.13028) (xy 197.272224 -151.170313) (xy 197.229744 -151.204881)
			(xy 197.18295 -151.23334) (xy 197.132717 -151.25516) (xy 197.079979 -151.269934) (xy 197.02572 -151.277386)
			(xy 196.998336 -151.277828) (xy 196.969682 -151.27742) (xy 196.912956 -151.269268) (xy 196.857967 -151.253127)
			(xy 196.805836 -151.229323) (xy 196.757623 -151.198343) (xy 196.71431 -151.160815) (xy 196.676779 -151.117506)
			(xy 196.645794 -151.069296) (xy 196.621986 -151.017167) (xy 196.605839 -150.96218) (xy 196.597683 -150.905454)
			(xy 190.635947 -150.905454) (xy 190.650474 -150.921667) (xy 190.681247 -150.96818) (xy 190.704919 -151.018677)
			(xy 190.720987 -151.072084) (xy 190.729107 -151.12726) (xy 190.729616 -151.155146) (xy 190.729107 -151.183032)
			(xy 190.720987 -151.238208) (xy 190.704919 -151.291615) (xy 190.681247 -151.342112) (xy 190.650474 -151.388625)
			(xy 190.613257 -151.430162) (xy 190.570389 -151.465837) (xy 190.522783 -151.494891) (xy 190.471454 -151.516703)
			(xy 190.417497 -151.530809) (xy 190.36206 -151.536909) (xy 190.306326 -151.534872) (xy 190.251483 -151.524742)
			(xy 190.198699 -151.506735) (xy 190.149099 -151.481234) (xy 190.103741 -151.448783) (xy 190.063592 -151.410074)
			(xy 190.029506 -151.365931) (xy 190.00221 -151.317296) (xy 189.982287 -151.265205) (xy 189.970161 -151.210768)
			(xy 189.96609 -151.155146) (xy 188.213238 -151.155146) (xy 189.854078 -152.795986) (xy 189.861605 -152.802192)
			(xy 189.879884 -152.80897) (xy 189.889638 -152.809194) (xy 189.981586 -152.796494) (xy 189.985992 -152.795261)
			(xy 189.9943 -152.791429) (xy 189.998096 -152.788874) (xy 189.998604 -152.788366) (xy 190.006732 -152.779476)
			(xy 190.01232 -152.773126) (xy 190.015114 -152.768046) (xy 190.029672 -152.743222) (xy 190.065083 -152.697861)
			(xy 190.106897 -152.658324) (xy 190.154169 -152.625506) (xy 190.205827 -152.600149) (xy 190.260705 -152.582828)
			(xy 190.31756 -152.573933) (xy 190.34633 -152.573228) (xy 190.348108 -152.573228) (xy 190.375377 -152.573715)
			(xy 190.429361 -152.581478) (xy 190.48169 -152.596843) (xy 190.531299 -152.6195) (xy 190.57718 -152.648986)
			(xy 190.618398 -152.684701) (xy 190.642171 -152.712136) (xy 199.240039 -152.712136) (xy 199.240039 -152.654864)
			(xy 199.24819 -152.598174) (xy 199.264327 -152.543221) (xy 199.28812 -152.491125) (xy 199.319086 -152.442945)
			(xy 199.356594 -152.399663) (xy 199.39988 -152.36216) (xy 199.448063 -152.331199) (xy 199.500163 -152.307411)
			(xy 199.555117 -152.291281) (xy 199.611808 -152.283136) (xy 199.640444 -152.282652) (xy 199.655358 -152.282761)
			(xy 199.685107 -152.284922) (xy 199.69988 -152.28697) (xy 199.711056 -152.288748) (xy 199.732138 -152.282652)
			(xy 199.799194 -152.224994) (xy 199.807163 -152.217403) (xy 199.816247 -152.197382) (xy 199.81672 -152.186386)
			(xy 199.81672 -151.921718) (xy 199.816198 -151.910731) (xy 199.807134 -151.890719) (xy 199.799194 -151.88311)
			(xy 199.732138 -151.825452) (xy 199.711056 -151.819356) (xy 199.69988 -151.821134) (xy 199.685107 -151.82318)
			(xy 199.655358 -151.825343) (xy 199.640444 -151.825452) (xy 199.611813 -151.824889) (xy 199.555133 -151.816745)
			(xy 199.500189 -151.800617) (xy 199.4481 -151.776834) (xy 199.399926 -151.745879) (xy 199.356648 -151.708383)
			(xy 199.319147 -151.665109) (xy 199.288187 -151.616939) (xy 199.264398 -151.564852) (xy 199.248264 -151.50991)
			(xy 199.240115 -151.453231) (xy 199.240115 -151.395969) (xy 199.248264 -151.33929) (xy 199.264398 -151.284348)
			(xy 199.288187 -151.232261) (xy 199.319147 -151.184091) (xy 199.356648 -151.140817) (xy 199.399926 -151.103321)
			(xy 199.4481 -151.072366) (xy 199.500189 -151.048583) (xy 199.555133 -151.032455) (xy 199.611813 -151.024311)
			(xy 199.640444 -151.023828) (xy 199.667813 -151.024336) (xy 199.722043 -151.031774) (xy 199.774757 -151.046518)
			(xy 199.824976 -151.068296) (xy 199.871766 -151.096702) (xy 199.914257 -151.131209) (xy 199.95166 -151.171174)
			(xy 199.96785 -151.193246) (xy 199.973407 -151.200512) (xy 199.988519 -151.210794) (xy 199.997314 -151.213312)
			(xy 200.027286 -151.220678) (xy 200.036237 -151.222414) (xy 200.054325 -151.220205) (xy 200.062592 -151.21636)
			(xy 200.087197 -151.203997) (xy 200.138732 -151.184596) (xy 200.192222 -151.171514) (xy 200.246895 -151.164939)
			(xy 200.274428 -151.164544) (xy 200.301962 -151.164927) (xy 200.356637 -151.171495) (xy 200.410128 -151.18458)
			(xy 200.46166 -151.203994) (xy 200.486264 -151.21636) (xy 200.494531 -151.220219) (xy 200.512621 -151.222447)
			(xy 200.52157 -151.220678) (xy 200.551542 -151.213312) (xy 200.560333 -151.210795) (xy 200.57543 -151.200495)
			(xy 200.581006 -151.193246) (xy 200.597187 -151.171166) (xy 200.63459 -151.131195) (xy 200.677081 -151.096683)
			(xy 200.723872 -151.068271) (xy 200.774092 -151.046487) (xy 200.826809 -151.031736) (xy 200.881041 -151.024293)
			(xy 200.908412 -151.023828) (xy 200.937044 -151.024259) (xy 200.993726 -151.032411) (xy 201.048671 -151.048545)
			(xy 201.10076 -151.072335) (xy 201.148934 -151.103296) (xy 201.192211 -151.140797) (xy 201.229711 -151.184075)
			(xy 201.260671 -151.23225) (xy 201.284459 -151.28434) (xy 201.300592 -151.339286) (xy 201.308741 -151.395968)
			(xy 201.308741 -151.453232) (xy 201.300592 -151.509914) (xy 201.284459 -151.56486) (xy 201.260671 -151.61695)
			(xy 201.23033 -151.664162) (xy 231.773474 -151.664162) (xy 231.777545 -151.60854) (xy 231.789671 -151.554103)
			(xy 231.809594 -151.502012) (xy 231.83689 -151.453377) (xy 231.870976 -151.409234) (xy 231.911125 -151.370525)
			(xy 231.956483 -151.338074) (xy 232.006083 -151.312573) (xy 232.058867 -151.294566) (xy 232.11371 -151.284436)
			(xy 232.169444 -151.282399) (xy 232.224881 -151.288499) (xy 232.278838 -151.302605) (xy 232.330167 -151.324417)
			(xy 232.377773 -151.353471) (xy 232.420641 -151.389146) (xy 232.457858 -151.430683) (xy 232.488631 -151.477196)
			(xy 232.512303 -151.527693) (xy 232.528371 -151.5811) (xy 232.536491 -151.636276) (xy 232.537 -151.664162)
			(xy 232.536491 -151.692048) (xy 232.528371 -151.747224) (xy 232.512303 -151.800631) (xy 232.488631 -151.851128)
			(xy 232.457858 -151.897641) (xy 232.420641 -151.939178) (xy 232.377773 -151.974853) (xy 232.330167 -152.003907)
			(xy 232.278838 -152.025719) (xy 232.224881 -152.039825) (xy 232.169444 -152.045925) (xy 232.11371 -152.043888)
			(xy 232.058867 -152.033758) (xy 232.006083 -152.015751) (xy 231.956483 -151.99025) (xy 231.911125 -151.957799)
			(xy 231.870976 -151.91909) (xy 231.83689 -151.874947) (xy 231.809594 -151.826312) (xy 231.789671 -151.774221)
			(xy 231.777545 -151.719784) (xy 231.773474 -151.664162) (xy 201.23033 -151.664162) (xy 201.229711 -151.665125)
			(xy 201.192211 -151.708403) (xy 201.148934 -151.745904) (xy 201.10076 -151.776865) (xy 201.048671 -151.800655)
			(xy 200.993726 -151.816789) (xy 200.937044 -151.824941) (xy 200.908412 -151.825452) (xy 200.893498 -151.825348)
			(xy 200.863749 -151.823183) (xy 200.848976 -151.821134) (xy 200.8378 -151.819356) (xy 200.816718 -151.825452)
			(xy 200.749662 -151.88311) (xy 200.741685 -151.890693) (xy 200.732607 -151.91072) (xy 200.732136 -151.921718)
			(xy 200.732136 -152.186386) (xy 200.732638 -152.197376) (xy 200.741714 -152.217389) (xy 200.749662 -152.224994)
			(xy 200.816718 -152.282652) (xy 200.8378 -152.288748) (xy 200.848976 -152.28697) (xy 200.863749 -152.284918)
			(xy 200.893498 -152.282759) (xy 200.908412 -152.282652) (xy 200.937039 -152.283235) (xy 200.99371 -152.291385)
			(xy 201.048644 -152.307517) (xy 201.100724 -152.331302) (xy 201.148889 -152.362257) (xy 201.192158 -152.399751)
			(xy 201.203158 -152.412446) (xy 226.102924 -152.412446) (xy 226.106995 -152.356824) (xy 226.119121 -152.302387)
			(xy 226.139044 -152.250296) (xy 226.16634 -152.201661) (xy 226.200426 -152.157518) (xy 226.240575 -152.118809)
			(xy 226.285933 -152.086358) (xy 226.335533 -152.060857) (xy 226.388317 -152.04285) (xy 226.44316 -152.03272)
			(xy 226.498894 -152.030683) (xy 226.554331 -152.036783) (xy 226.608288 -152.050889) (xy 226.659617 -152.072701)
			(xy 226.707223 -152.101755) (xy 226.750091 -152.13743) (xy 226.787308 -152.178967) (xy 226.818081 -152.22548)
			(xy 226.841753 -152.275977) (xy 226.857821 -152.329384) (xy 226.864139 -152.372314) (xy 227.76256 -152.372314)
			(xy 227.766631 -152.316692) (xy 227.778757 -152.262255) (xy 227.79868 -152.210164) (xy 227.825976 -152.161529)
			(xy 227.860062 -152.117386) (xy 227.900211 -152.078677) (xy 227.945569 -152.046226) (xy 227.995169 -152.020725)
			(xy 228.047953 -152.002718) (xy 228.102796 -151.992588) (xy 228.15853 -151.990551) (xy 228.213967 -151.996651)
			(xy 228.267924 -152.010757) (xy 228.319253 -152.032569) (xy 228.366859 -152.061623) (xy 228.38462 -152.076404)
			(xy 230.958388 -152.076404) (xy 230.962459 -152.020782) (xy 230.974585 -151.966345) (xy 230.994508 -151.914254)
			(xy 231.021804 -151.865619) (xy 231.05589 -151.821476) (xy 231.096039 -151.782767) (xy 231.141397 -151.750316)
			(xy 231.190997 -151.724815) (xy 231.243781 -151.706808) (xy 231.298624 -151.696678) (xy 231.354358 -151.694641)
			(xy 231.409795 -151.700741) (xy 231.463752 -151.714847) (xy 231.515081 -151.736659) (xy 231.562687 -151.765713)
			(xy 231.605555 -151.801388) (xy 231.642772 -151.842925) (xy 231.673545 -151.889438) (xy 231.697217 -151.939935)
			(xy 231.713285 -151.993342) (xy 231.721405 -152.048518) (xy 231.721914 -152.076404) (xy 231.721405 -152.10429)
			(xy 231.713285 -152.159466) (xy 231.697217 -152.212873) (xy 231.673545 -152.26337) (xy 231.642772 -152.309883)
			(xy 231.605555 -152.35142) (xy 231.562687 -152.387095) (xy 231.515081 -152.416149) (xy 231.463752 -152.437961)
			(xy 231.409795 -152.452067) (xy 231.354358 -152.458167) (xy 231.298624 -152.45613) (xy 231.243781 -152.446)
			(xy 231.190997 -152.427993) (xy 231.141397 -152.402492) (xy 231.096039 -152.370041) (xy 231.05589 -152.331332)
			(xy 231.021804 -152.287189) (xy 230.994508 -152.238554) (xy 230.974585 -152.186463) (xy 230.962459 -152.132026)
			(xy 230.958388 -152.076404) (xy 228.38462 -152.076404) (xy 228.409727 -152.097298) (xy 228.446944 -152.138835)
			(xy 228.477717 -152.185348) (xy 228.501389 -152.235845) (xy 228.517457 -152.289252) (xy 228.525577 -152.344428)
			(xy 228.526086 -152.372314) (xy 228.525577 -152.4002) (xy 228.517457 -152.455376) (xy 228.501389 -152.508783)
			(xy 228.477717 -152.55928) (xy 228.446944 -152.605793) (xy 228.409727 -152.64733) (xy 228.366859 -152.683005)
			(xy 228.319253 -152.712059) (xy 228.267924 -152.733871) (xy 228.213967 -152.747977) (xy 228.15853 -152.754077)
			(xy 228.102796 -152.75204) (xy 228.047953 -152.74191) (xy 227.995169 -152.723903) (xy 227.945569 -152.698402)
			(xy 227.900211 -152.665951) (xy 227.860062 -152.627242) (xy 227.825976 -152.583099) (xy 227.79868 -152.534464)
			(xy 227.778757 -152.482373) (xy 227.766631 -152.427936) (xy 227.76256 -152.372314) (xy 226.864139 -152.372314)
			(xy 226.865941 -152.38456) (xy 226.86645 -152.412446) (xy 226.865941 -152.440332) (xy 226.857821 -152.495508)
			(xy 226.841753 -152.548915) (xy 226.818081 -152.599412) (xy 226.787308 -152.645925) (xy 226.750091 -152.687462)
			(xy 226.707223 -152.723137) (xy 226.659617 -152.752191) (xy 226.608288 -152.774003) (xy 226.554331 -152.788109)
			(xy 226.498894 -152.794209) (xy 226.44316 -152.792172) (xy 226.388317 -152.782042) (xy 226.335533 -152.764035)
			(xy 226.285933 -152.738534) (xy 226.240575 -152.706083) (xy 226.200426 -152.667374) (xy 226.16634 -152.623231)
			(xy 226.139044 -152.574596) (xy 226.119121 -152.522505) (xy 226.106995 -152.468068) (xy 226.102924 -152.412446)
			(xy 201.203158 -152.412446) (xy 201.229651 -152.443021) (xy 201.260604 -152.491186) (xy 201.284388 -152.543267)
			(xy 201.300518 -152.598202) (xy 201.308666 -152.654873) (xy 201.308666 -152.712127) (xy 201.300518 -152.768798)
			(xy 201.284388 -152.823733) (xy 201.260604 -152.875814) (xy 201.229651 -152.923979) (xy 201.192158 -152.967249)
			(xy 201.148889 -153.004743) (xy 201.100724 -153.035698) (xy 201.048644 -153.059483) (xy 200.99371 -153.075615)
			(xy 200.937039 -153.083765) (xy 200.908412 -153.084276) (xy 200.881042 -153.083799) (xy 200.826811 -153.076356)
			(xy 200.774096 -153.061605) (xy 200.723877 -153.039822) (xy 200.677087 -153.011411) (xy 200.634597 -152.976901)
			(xy 200.597195 -152.936932) (xy 200.581006 -152.914858) (xy 200.575429 -152.90761) (xy 200.560331 -152.897318)
			(xy 200.551542 -152.894792) (xy 200.52157 -152.887426) (xy 200.512622 -152.885666) (xy 200.494531 -152.887891)
			(xy 200.486264 -152.891744) (xy 200.46165 -152.904087) (xy 200.410118 -152.923493) (xy 200.356631 -152.93658)
			(xy 200.301961 -152.943161) (xy 200.274428 -152.94356) (xy 200.246894 -152.943154) (xy 200.19222 -152.936593)
			(xy 200.13873 -152.923514) (xy 200.087197 -152.904107) (xy 200.062592 -152.891744) (xy 200.054334 -152.887863)
			(xy 200.036236 -152.885649) (xy 200.027286 -152.887426) (xy 199.997314 -152.894792) (xy 199.98853 -152.89733)
			(xy 199.973429 -152.907615) (xy 199.96785 -152.914858) (xy 199.951636 -152.936913) (xy 199.914239 -152.976884)
			(xy 199.871753 -153.011398) (xy 199.824968 -153.039813) (xy 199.774753 -153.061601) (xy 199.722042 -153.076357)
			(xy 199.667813 -153.083808) (xy 199.640444 -153.084276) (xy 199.611808 -153.083864) (xy 199.555117 -153.075719)
			(xy 199.500163 -153.059589) (xy 199.448063 -153.035801) (xy 199.39988 -153.00484) (xy 199.356594 -152.967337)
			(xy 199.319086 -152.924055) (xy 199.28812 -152.875875) (xy 199.264327 -152.823779) (xy 199.24819 -152.768826)
			(xy 199.240039 -152.712136) (xy 190.642171 -152.712136) (xy 190.654113 -152.725918) (xy 190.683599 -152.771799)
			(xy 190.706256 -152.821408) (xy 190.721622 -152.873738) (xy 190.729385 -152.927721) (xy 190.72987 -152.95499)
			(xy 190.729336 -152.984308) (xy 190.720377 -153.042255) (xy 190.702667 -153.098153) (xy 190.676623 -153.150687)
			(xy 190.642857 -153.198625) (xy 190.602161 -153.240839) (xy 190.555493 -153.276338) (xy 190.529972 -153.290778)
			(xy 190.526416 -153.29281) (xy 190.514224 -153.305002) (xy 190.511149 -153.309691) (xy 190.506923 -153.320074)
			(xy 190.505842 -153.325576) (xy 190.497714 -153.381964) (xy 190.495936 -153.39441) (xy 190.49365 -153.410158)
			(xy 190.49365 -153.411428) (xy 190.493517 -153.415073) (xy 190.494155 -153.422339) (xy 190.49492 -153.425906)
			(xy 190.495854 -153.429567) (xy 190.498659 -153.436581) (xy 190.500508 -153.439876) (xy 190.508382 -153.45029)
			(xy 191.563747 -154.505655) (xy 196.597679 -154.505655) (xy 196.597679 -154.448345) (xy 196.605835 -154.39162)
			(xy 196.621982 -154.336632) (xy 196.645791 -154.284502) (xy 196.676776 -154.236292) (xy 196.714307 -154.192982)
			(xy 196.75762 -154.155454) (xy 196.805834 -154.124473) (xy 196.857966 -154.10067) (xy 196.912955 -154.084528)
			(xy 196.969681 -154.076376) (xy 196.998336 -154.075892) (xy 197.013254 -154.076063) (xy 197.043003 -154.078351)
			(xy 197.057772 -154.080464) (xy 197.068948 -154.082242) (xy 197.09003 -154.076146) (xy 197.157086 -154.018488)
			(xy 197.165071 -154.010913) (xy 197.174143 -153.990879) (xy 197.174612 -153.97988) (xy 197.174612 -153.715212)
			(xy 197.174096 -153.704224) (xy 197.165028 -153.684212) (xy 197.157086 -153.676604) (xy 197.09003 -153.618946)
			(xy 197.068948 -153.61285) (xy 197.057772 -153.614628) (xy 197.043002 -153.616731) (xy 197.013254 -153.619023)
			(xy 196.998336 -153.6192) (xy 196.969687 -153.618648) (xy 196.912971 -153.610498) (xy 196.857992 -153.594359)
			(xy 196.80587 -153.57056) (xy 196.757666 -153.539585) (xy 196.714361 -153.502065) (xy 196.676837 -153.458763)
			(xy 196.645857 -153.410561) (xy 196.622053 -153.358441) (xy 196.60591 -153.303464) (xy 196.597755 -153.246749)
			(xy 196.597755 -153.189451) (xy 196.60591 -153.132736) (xy 196.622053 -153.077759) (xy 196.645857 -153.025639)
			(xy 196.676837 -152.977437) (xy 196.714361 -152.934135) (xy 196.757666 -152.896615) (xy 196.80587 -152.86564)
			(xy 196.857992 -152.841841) (xy 196.912971 -152.825702) (xy 196.969687 -152.817552) (xy 196.998336 -152.817068)
			(xy 197.025717 -152.817521) (xy 197.079967 -152.824992) (xy 197.132696 -152.839778) (xy 197.182921 -152.861603)
			(xy 197.229709 -152.89006) (xy 197.272188 -152.924621) (xy 197.309568 -152.964641) (xy 197.325742 -152.98674)
			(xy 197.331303 -152.994002) (xy 197.346412 -153.004287) (xy 197.355206 -153.006806) (xy 197.385178 -153.014172)
			(xy 197.39413 -153.015905) (xy 197.412216 -153.013698) (xy 197.420484 -153.009854) (xy 197.445086 -152.997469)
			(xy 197.496612 -152.977999) (xy 197.5501 -152.96485) (xy 197.60478 -152.95821) (xy 197.63232 -152.957784)
			(xy 197.65986 -152.958216) (xy 197.714541 -152.96485) (xy 197.76803 -152.977996) (xy 197.819557 -152.997463)
			(xy 197.844156 -153.009854) (xy 197.852425 -153.013709) (xy 197.870514 -153.015939) (xy 197.879462 -153.014172)
			(xy 197.909434 -153.006806) (xy 197.918225 -153.004288) (xy 197.933322 -152.993989) (xy 197.938898 -152.98674)
			(xy 197.955076 -152.964643) (xy 197.992446 -152.92461) (xy 198.03492 -152.89004) (xy 198.081707 -152.861577)
			(xy 198.131935 -152.839753) (xy 198.184668 -152.824973) (xy 198.238922 -152.817514) (xy 198.266304 -152.817068)
			(xy 198.294955 -152.817511) (xy 198.351672 -152.825666) (xy 198.406652 -152.84181) (xy 198.458775 -152.865614)
			(xy 198.506979 -152.896594) (xy 198.550284 -152.934118) (xy 198.587808 -152.977424) (xy 198.618787 -153.025629)
			(xy 198.642591 -153.077752) (xy 198.658735 -153.132732) (xy 198.666889 -153.189449) (xy 198.666889 -153.246751)
			(xy 198.658735 -153.303468) (xy 198.642591 -153.358448) (xy 198.618787 -153.410571) (xy 198.587808 -153.458776)
			(xy 198.550284 -153.502082) (xy 198.506979 -153.539606) (xy 198.458775 -153.570586) (xy 198.406652 -153.59439)
			(xy 198.351672 -153.610534) (xy 198.294955 -153.618689) (xy 198.266304 -153.6192) (xy 198.251386 -153.619025)
			(xy 198.221637 -153.61674) (xy 198.206868 -153.614628) (xy 198.195692 -153.61285) (xy 198.17461 -153.618946)
			(xy 198.107554 -153.676604) (xy 198.099578 -153.684188) (xy 198.0905 -153.704215) (xy 198.090028 -153.715212)
			(xy 198.090028 -153.97988) (xy 198.090536 -153.990869) (xy 198.099608 -154.010882) (xy 198.105166 -154.016202)
			(xy 226.808028 -154.016202) (xy 226.812099 -153.96058) (xy 226.824225 -153.906143) (xy 226.844148 -153.854052)
			(xy 226.871444 -153.805417) (xy 226.90553 -153.761274) (xy 226.945679 -153.722565) (xy 226.991037 -153.690114)
			(xy 227.040637 -153.664613) (xy 227.093421 -153.646606) (xy 227.148264 -153.636476) (xy 227.203998 -153.634439)
			(xy 227.259435 -153.640539) (xy 227.313392 -153.654645) (xy 227.364721 -153.676457) (xy 227.412327 -153.705511)
			(xy 227.455195 -153.741186) (xy 227.492232 -153.782522) (xy 246.97766 -153.782522) (xy 246.981731 -153.7269)
			(xy 246.993857 -153.672463) (xy 247.01378 -153.620372) (xy 247.041076 -153.571737) (xy 247.075162 -153.527594)
			(xy 247.115311 -153.488885) (xy 247.160669 -153.456434) (xy 247.210269 -153.430933) (xy 247.263053 -153.412926)
			(xy 247.317896 -153.402796) (xy 247.37363 -153.400759) (xy 247.429067 -153.406859) (xy 247.483024 -153.420965)
			(xy 247.534353 -153.442777) (xy 247.581959 -153.471831) (xy 247.624827 -153.507506) (xy 247.662044 -153.549043)
			(xy 247.692817 -153.595556) (xy 247.716489 -153.646053) (xy 247.732557 -153.69946) (xy 247.740677 -153.754636)
			(xy 247.741186 -153.782522) (xy 247.740677 -153.810408) (xy 247.732557 -153.865584) (xy 247.716489 -153.918991)
			(xy 247.692817 -153.969488) (xy 247.662044 -154.016001) (xy 247.624827 -154.057538) (xy 247.581959 -154.093213)
			(xy 247.534353 -154.122267) (xy 247.483024 -154.144079) (xy 247.429067 -154.158185) (xy 247.37363 -154.164285)
			(xy 247.317896 -154.162248) (xy 247.263053 -154.152118) (xy 247.210269 -154.134111) (xy 247.160669 -154.10861)
			(xy 247.115311 -154.076159) (xy 247.075162 -154.03745) (xy 247.041076 -153.993307) (xy 247.01378 -153.944672)
			(xy 246.993857 -153.892581) (xy 246.981731 -153.838144) (xy 246.97766 -153.782522) (xy 227.492232 -153.782522)
			(xy 227.492412 -153.782723) (xy 227.523185 -153.829236) (xy 227.546857 -153.879733) (xy 227.562925 -153.93314)
			(xy 227.571045 -153.988316) (xy 227.571554 -154.016202) (xy 227.571045 -154.044088) (xy 227.562925 -154.099264)
			(xy 227.546857 -154.152671) (xy 227.523185 -154.203168) (xy 227.492412 -154.249681) (xy 227.455195 -154.291218)
			(xy 227.412327 -154.326893) (xy 227.364721 -154.355947) (xy 227.313392 -154.377759) (xy 227.259435 -154.391865)
			(xy 227.203998 -154.397965) (xy 227.148264 -154.395928) (xy 227.093421 -154.385798) (xy 227.040637 -154.367791)
			(xy 226.991037 -154.34229) (xy 226.945679 -154.309839) (xy 226.90553 -154.27113) (xy 226.871444 -154.226987)
			(xy 226.844148 -154.178352) (xy 226.824225 -154.126261) (xy 226.812099 -154.071824) (xy 226.808028 -154.016202)
			(xy 198.105166 -154.016202) (xy 198.107554 -154.018488) (xy 198.17461 -154.076146) (xy 198.195692 -154.082242)
			(xy 198.206868 -154.080464) (xy 198.221637 -154.078357) (xy 198.251386 -154.076068) (xy 198.266304 -154.075892)
			(xy 198.294949 -154.076487) (xy 198.351656 -154.084641) (xy 198.406625 -154.100782) (xy 198.458738 -154.124582)
			(xy 198.506933 -154.155555) (xy 198.55023 -154.193073) (xy 198.587747 -154.23637) (xy 198.61872 -154.284565)
			(xy 198.642519 -154.336678) (xy 198.65866 -154.391648) (xy 198.666813 -154.448355) (xy 198.666813 -154.505645)
			(xy 198.65866 -154.562352) (xy 198.642519 -154.617322) (xy 198.61872 -154.669435) (xy 198.587747 -154.71763)
			(xy 198.55023 -154.760927) (xy 198.506933 -154.798445) (xy 198.458738 -154.829418) (xy 198.406625 -154.853218)
			(xy 198.351656 -154.869359) (xy 198.294949 -154.877513) (xy 198.266304 -154.878024) (xy 198.238924 -154.877545)
			(xy 198.184675 -154.870078) (xy 198.131947 -154.855297) (xy 198.081721 -154.833477) (xy 198.034933 -154.805024)
			(xy 197.992453 -154.770467) (xy 197.955072 -154.730449) (xy 197.938898 -154.708352) (xy 197.933325 -154.701101)
			(xy 197.918224 -154.69081) (xy 197.909434 -154.688286) (xy 197.879462 -154.68092) (xy 197.870514 -154.679157)
			(xy 197.852423 -154.681384) (xy 197.844156 -154.685238) (xy 197.819564 -154.697644) (xy 197.768035 -154.717109)
			(xy 197.714543 -154.730252) (xy 197.659861 -154.736885) (xy 197.63232 -154.737308) (xy 197.604779 -154.736901)
			(xy 197.550098 -154.73026) (xy 197.496608 -154.717107) (xy 197.445082 -154.697632) (xy 197.420484 -154.685238)
			(xy 197.412227 -154.681353) (xy 197.394128 -154.679142) (xy 197.385178 -154.68092) (xy 197.355206 -154.688286)
			(xy 197.346422 -154.690823) (xy 197.331322 -154.701109) (xy 197.325742 -154.708352) (xy 197.309598 -154.730476)
			(xy 197.272223 -154.770508) (xy 197.229743 -154.805077) (xy 197.18295 -154.833536) (xy 197.132716 -154.855356)
			(xy 197.079979 -154.87013) (xy 197.02572 -154.877582) (xy 196.998336 -154.878024) (xy 196.969681 -154.877624)
			(xy 196.912955 -154.869472) (xy 196.857966 -154.85333) (xy 196.805834 -154.829527) (xy 196.75762 -154.798546)
			(xy 196.714307 -154.761018) (xy 196.676776 -154.717708) (xy 196.645791 -154.669498) (xy 196.621982 -154.617368)
			(xy 196.605835 -154.56238) (xy 196.597679 -154.505655) (xy 191.563747 -154.505655) (xy 192.111345 -155.053253)
			(xy 199.239803 -155.053253) (xy 199.239803 -154.995947) (xy 199.247959 -154.939224) (xy 199.264105 -154.884239)
			(xy 199.287913 -154.832111) (xy 199.318897 -154.783903) (xy 199.356427 -154.740596) (xy 199.399739 -154.703071)
			(xy 199.44795 -154.672092) (xy 199.50008 -154.64829) (xy 199.555067 -154.63215) (xy 199.611791 -154.624)
			(xy 199.640444 -154.623516) (xy 199.667824 -154.623985) (xy 199.722073 -154.631456) (xy 199.7748 -154.646241)
			(xy 199.825025 -154.668064) (xy 199.871812 -154.696518) (xy 199.914293 -154.731075) (xy 199.951675 -154.771091)
			(xy 199.96785 -154.793188) (xy 199.973398 -154.800461) (xy 199.988517 -154.810739) (xy 199.997314 -154.813254)
			(xy 200.027286 -154.82062) (xy 200.036237 -154.822363) (xy 200.054325 -154.820151) (xy 200.062592 -154.816302)
			(xy 200.087195 -154.803918) (xy 200.13872 -154.784447) (xy 200.192208 -154.771297) (xy 200.246888 -154.764658)
			(xy 200.274428 -154.764232) (xy 200.301968 -154.764667) (xy 200.356648 -154.771301) (xy 200.410138 -154.784446)
			(xy 200.461665 -154.803912) (xy 200.486264 -154.816302) (xy 200.49453 -154.820162) (xy 200.512621 -154.822388)
			(xy 200.52157 -154.82062) (xy 200.551542 -154.813254) (xy 200.560328 -154.810724) (xy 200.575427 -154.800432)
			(xy 200.581006 -154.793188) (xy 200.597164 -154.771076) (xy 200.634539 -154.731045) (xy 200.677017 -154.696478)
			(xy 200.723808 -154.668018) (xy 200.774038 -154.646196) (xy 200.826773 -154.631419) (xy 200.881029 -154.623962)
			(xy 200.908412 -154.623516) (xy 200.937058 -154.624064) (xy 200.993768 -154.632219) (xy 201.04874 -154.648362)
			(xy 201.054958 -154.651202) (xy 225.157028 -154.651202) (xy 225.161099 -154.59558) (xy 225.173225 -154.541143)
			(xy 225.193148 -154.489052) (xy 225.220444 -154.440417) (xy 225.25453 -154.396274) (xy 225.294679 -154.357565)
			(xy 225.340037 -154.325114) (xy 225.389637 -154.299613) (xy 225.442421 -154.281606) (xy 225.497264 -154.271476)
			(xy 225.552998 -154.269439) (xy 225.608435 -154.275539) (xy 225.662392 -154.289645) (xy 225.713721 -154.311457)
			(xy 225.761327 -154.340511) (xy 225.804195 -154.376186) (xy 225.841412 -154.417723) (xy 225.872185 -154.464236)
			(xy 225.895857 -154.514733) (xy 225.911925 -154.56814) (xy 225.920045 -154.623316) (xy 225.920554 -154.651202)
			(xy 225.920045 -154.679088) (xy 225.911925 -154.734264) (xy 225.895857 -154.787671) (xy 225.872185 -154.838168)
			(xy 225.855899 -154.862784) (xy 227.184964 -154.862784) (xy 227.189035 -154.807162) (xy 227.201161 -154.752725)
			(xy 227.221084 -154.700634) (xy 227.24838 -154.651999) (xy 227.282466 -154.607856) (xy 227.322615 -154.569147)
			(xy 227.367973 -154.536696) (xy 227.417573 -154.511195) (xy 227.470357 -154.493188) (xy 227.5252 -154.483058)
			(xy 227.580934 -154.481021) (xy 227.636371 -154.487121) (xy 227.690328 -154.501227) (xy 227.741657 -154.523039)
			(xy 227.789263 -154.552093) (xy 227.832131 -154.587768) (xy 227.869348 -154.629305) (xy 227.900121 -154.675818)
			(xy 227.923793 -154.726315) (xy 227.939861 -154.779722) (xy 227.947981 -154.834898) (xy 227.94849 -154.862784)
			(xy 227.947981 -154.89067) (xy 227.939861 -154.945846) (xy 227.923793 -154.999253) (xy 227.900121 -155.04975)
			(xy 227.869348 -155.096263) (xy 227.832131 -155.1378) (xy 227.789263 -155.173475) (xy 227.741657 -155.202529)
			(xy 227.719289 -155.212034) (xy 239.469166 -155.212034) (xy 239.473237 -155.156412) (xy 239.485363 -155.101975)
			(xy 239.505286 -155.049884) (xy 239.532582 -155.001249) (xy 239.566668 -154.957106) (xy 239.606817 -154.918397)
			(xy 239.652175 -154.885946) (xy 239.701775 -154.860445) (xy 239.754559 -154.842438) (xy 239.809402 -154.832308)
			(xy 239.865136 -154.830271) (xy 239.920573 -154.836371) (xy 239.97453 -154.850477) (xy 240.025859 -154.872289)
			(xy 240.073465 -154.901343) (xy 240.116333 -154.937018) (xy 240.15355 -154.978555) (xy 240.184323 -155.025068)
			(xy 240.207995 -155.075565) (xy 240.224063 -155.128972) (xy 240.232183 -155.184148) (xy 240.232692 -155.212034)
			(xy 240.232599 -155.217114) (xy 240.51844 -155.217114) (xy 240.522511 -155.161492) (xy 240.534637 -155.107055)
			(xy 240.55456 -155.054964) (xy 240.581856 -155.006329) (xy 240.615942 -154.962186) (xy 240.656091 -154.923477)
			(xy 240.701449 -154.891026) (xy 240.751049 -154.865525) (xy 240.803833 -154.847518) (xy 240.858676 -154.837388)
			(xy 240.91441 -154.835351) (xy 240.969847 -154.841451) (xy 241.023804 -154.855557) (xy 241.075133 -154.877369)
			(xy 241.122739 -154.906423) (xy 241.165607 -154.942098) (xy 241.202824 -154.983635) (xy 241.233597 -155.030148)
			(xy 241.256588 -155.079192) (xy 242.069872 -155.079192) (xy 242.073943 -155.02357) (xy 242.086069 -154.969133)
			(xy 242.105992 -154.917042) (xy 242.133288 -154.868407) (xy 242.167374 -154.824264) (xy 242.207523 -154.785555)
			(xy 242.252881 -154.753104) (xy 242.302481 -154.727603) (xy 242.355265 -154.709596) (xy 242.410108 -154.699466)
			(xy 242.465842 -154.697429) (xy 242.521279 -154.703529) (xy 242.575236 -154.717635) (xy 242.626565 -154.739447)
			(xy 242.674171 -154.768501) (xy 242.717039 -154.804176) (xy 242.754256 -154.845713) (xy 242.785029 -154.892226)
			(xy 242.808701 -154.942723) (xy 242.824769 -154.99613) (xy 242.832889 -155.051306) (xy 242.833398 -155.079192)
			(xy 242.833333 -155.082748) (xy 243.393722 -155.082748) (xy 243.394148 -155.056433) (xy 243.40139 -155.004302)
			(xy 243.415717 -154.953658) (xy 243.436857 -154.905459) (xy 243.464411 -154.860617) (xy 243.497857 -154.819979)
			(xy 243.516912 -154.801824) (xy 243.524307 -154.794297) (xy 243.532835 -154.775021) (xy 243.533422 -154.764486)
			(xy 243.533422 -154.68981) (xy 243.532895 -154.67926) (xy 243.524358 -154.659965) (xy 243.516912 -154.652472)
			(xy 243.497852 -154.634321) (xy 243.464395 -154.59369) (xy 243.436836 -154.548849) (xy 243.415698 -154.500648)
			(xy 243.401382 -154.449999) (xy 243.394159 -154.397864) (xy 243.393722 -154.371548) (xy 243.3942 -154.344295)
			(xy 243.401951 -154.290343) (xy 243.417303 -154.238044) (xy 243.439942 -154.188462) (xy 243.469408 -154.142607)
			(xy 243.5051 -154.101413) (xy 243.546292 -154.065718) (xy 243.592146 -154.03625) (xy 243.641727 -154.013609)
			(xy 243.694025 -153.998255) (xy 243.747977 -153.990501) (xy 243.77523 -153.99004) (xy 243.801545 -153.990475)
			(xy 243.853676 -153.997714) (xy 243.90432 -154.012039) (xy 243.952519 -154.033178) (xy 243.997361 -154.06073)
			(xy 244.037999 -154.094175) (xy 244.056154 -154.11323) (xy 244.063663 -154.120647) (xy 244.082952 -154.129165)
			(xy 244.093492 -154.12974) (xy 244.168168 -154.12974) (xy 244.178716 -154.129195) (xy 244.19801 -154.12067)
			(xy 244.205506 -154.11323) (xy 244.225326 -154.092442) (xy 244.270098 -154.056467) (xy 244.319756 -154.027607)
			(xy 244.373178 -154.006514) (xy 244.429157 -153.993665) (xy 244.48643 -153.98935) (xy 244.543703 -153.993665)
			(xy 244.599682 -154.006514) (xy 244.653104 -154.027607) (xy 244.702762 -154.056467) (xy 244.747534 -154.092442)
			(xy 244.767354 -154.11323) (xy 244.774863 -154.120647) (xy 244.794152 -154.129165) (xy 244.804692 -154.12974)
			(xy 244.879368 -154.12974) (xy 244.889916 -154.129195) (xy 244.90921 -154.12067) (xy 244.916706 -154.11323)
			(xy 244.936526 -154.092442) (xy 244.981298 -154.056467) (xy 245.030956 -154.027607) (xy 245.084378 -154.006514)
			(xy 245.140357 -153.993665) (xy 245.19763 -153.98935) (xy 245.254903 -153.993665) (xy 245.310882 -154.006514)
			(xy 245.364304 -154.027607) (xy 245.413962 -154.056467) (xy 245.458734 -154.092442) (xy 245.478554 -154.11323)
			(xy 245.486063 -154.120647) (xy 245.505352 -154.129165) (xy 245.515892 -154.12974) (xy 245.590568 -154.12974)
			(xy 245.601116 -154.129195) (xy 245.62041 -154.12067) (xy 245.627906 -154.11323) (xy 245.646072 -154.094184)
			(xy 245.686698 -154.060725) (xy 245.731536 -154.033164) (xy 245.779735 -154.012024) (xy 245.830381 -153.997705)
			(xy 245.882514 -153.990479) (xy 245.90883 -153.99004) (xy 245.936086 -153.990427) (xy 245.990042 -153.998189)
			(xy 246.042344 -154.013552) (xy 246.091928 -154.036201) (xy 246.137783 -154.065677) (xy 246.178977 -154.101379)
			(xy 246.21467 -154.142579) (xy 246.244136 -154.188441) (xy 246.266776 -154.238029) (xy 246.282127 -154.290334)
			(xy 246.289878 -154.344292) (xy 246.290338 -154.371548) (xy 246.289922 -154.397864) (xy 246.28268 -154.449996)
			(xy 246.268352 -154.50064) (xy 246.26381 -154.510994) (xy 247.76684 -154.510994) (xy 247.767399 -154.482054)
			(xy 247.77613 -154.424838) (xy 247.793405 -154.369597) (xy 247.818827 -154.3176) (xy 247.851814 -154.270041)
			(xy 247.891607 -154.228011) (xy 247.937294 -154.192476) (xy 247.987824 -154.164252) (xy 248.014744 -154.153616)
			(xy 248.028994 -154.147652) (xy 248.05333 -154.128653) (xy 248.070894 -154.103261) (xy 248.080086 -154.073787)
			(xy 248.080071 -154.042912) (xy 248.070849 -154.013447) (xy 248.062496 -154.000454) (xy 248.046399 -153.976317)
			(xy 248.020858 -153.924228) (xy 248.003496 -153.868873) (xy 247.994713 -153.811529) (xy 247.99417 -153.782522)
			(xy 247.994656 -153.755271) (xy 248.002412 -153.701323) (xy 248.017767 -153.649028) (xy 248.040409 -153.599451)
			(xy 248.069875 -153.553601) (xy 248.105566 -153.51241) (xy 248.146757 -153.476719) (xy 248.192607 -153.447253)
			(xy 248.242184 -153.424611) (xy 248.294479 -153.409256) (xy 248.348427 -153.4015) (xy 248.402929 -153.4015)
			(xy 248.456877 -153.409256) (xy 248.509172 -153.424611) (xy 248.558749 -153.447253) (xy 248.604599 -153.476719)
			(xy 248.64579 -153.51241) (xy 248.681481 -153.553601) (xy 248.710947 -153.599451) (xy 248.733589 -153.649028)
			(xy 248.748944 -153.701323) (xy 248.7567 -153.755271) (xy 248.757186 -153.782522) (xy 248.756624 -153.811461)
			(xy 248.75352 -153.831798) (xy 249.00966 -153.831798) (xy 249.013731 -153.776176) (xy 249.025857 -153.721739)
			(xy 249.04578 -153.669648) (xy 249.073076 -153.621013) (xy 249.107162 -153.57687) (xy 249.147311 -153.538161)
			(xy 249.192669 -153.50571) (xy 249.242269 -153.480209) (xy 249.295053 -153.462202) (xy 249.349896 -153.452072)
			(xy 249.40563 -153.450035) (xy 249.461067 -153.456135) (xy 249.515024 -153.470241) (xy 249.566353 -153.492053)
			(xy 249.613959 -153.521107) (xy 249.656827 -153.556782) (xy 249.694044 -153.598319) (xy 249.724817 -153.644832)
			(xy 249.748489 -153.695329) (xy 249.764557 -153.748736) (xy 249.769529 -153.782522) (xy 251.04166 -153.782522)
			(xy 251.045731 -153.7269) (xy 251.057857 -153.672463) (xy 251.07778 -153.620372) (xy 251.105076 -153.571737)
			(xy 251.139162 -153.527594) (xy 251.179311 -153.488885) (xy 251.224669 -153.456434) (xy 251.274269 -153.430933)
			(xy 251.327053 -153.412926) (xy 251.381896 -153.402796) (xy 251.43763 -153.400759) (xy 251.493067 -153.406859)
			(xy 251.547024 -153.420965) (xy 251.598353 -153.442777) (xy 251.645959 -153.471831) (xy 251.688827 -153.507506)
			(xy 251.726044 -153.549043) (xy 251.756817 -153.595556) (xy 251.780489 -153.646053) (xy 251.796557 -153.69946)
			(xy 251.804677 -153.754636) (xy 251.805186 -153.782522) (xy 252.05766 -153.782522) (xy 252.061731 -153.7269)
			(xy 252.073857 -153.672463) (xy 252.09378 -153.620372) (xy 252.121076 -153.571737) (xy 252.155162 -153.527594)
			(xy 252.195311 -153.488885) (xy 252.240669 -153.456434) (xy 252.290269 -153.430933) (xy 252.343053 -153.412926)
			(xy 252.397896 -153.402796) (xy 252.45363 -153.400759) (xy 252.509067 -153.406859) (xy 252.563024 -153.420965)
			(xy 252.614353 -153.442777) (xy 252.661959 -153.471831) (xy 252.704827 -153.507506) (xy 252.742044 -153.549043)
			(xy 252.772817 -153.595556) (xy 252.796489 -153.646053) (xy 252.812557 -153.69946) (xy 252.820677 -153.754636)
			(xy 252.821186 -153.782522) (xy 253.07366 -153.782522) (xy 253.077731 -153.7269) (xy 253.089857 -153.672463)
			(xy 253.10978 -153.620372) (xy 253.137076 -153.571737) (xy 253.171162 -153.527594) (xy 253.211311 -153.488885)
			(xy 253.256669 -153.456434) (xy 253.306269 -153.430933) (xy 253.359053 -153.412926) (xy 253.413896 -153.402796)
			(xy 253.46963 -153.400759) (xy 253.525067 -153.406859) (xy 253.579024 -153.420965) (xy 253.630353 -153.442777)
			(xy 253.677959 -153.471831) (xy 253.720827 -153.507506) (xy 253.758044 -153.549043) (xy 253.788817 -153.595556)
			(xy 253.812489 -153.646053) (xy 253.828557 -153.69946) (xy 253.836677 -153.754636) (xy 253.837186 -153.782522)
			(xy 254.08966 -153.782522) (xy 254.093731 -153.7269) (xy 254.105857 -153.672463) (xy 254.12578 -153.620372)
			(xy 254.153076 -153.571737) (xy 254.187162 -153.527594) (xy 254.227311 -153.488885) (xy 254.272669 -153.456434)
			(xy 254.322269 -153.430933) (xy 254.375053 -153.412926) (xy 254.429896 -153.402796) (xy 254.48563 -153.400759)
			(xy 254.541067 -153.406859) (xy 254.595024 -153.420965) (xy 254.646353 -153.442777) (xy 254.693959 -153.471831)
			(xy 254.736827 -153.507506) (xy 254.774044 -153.549043) (xy 254.804817 -153.595556) (xy 254.828489 -153.646053)
			(xy 254.844557 -153.69946) (xy 254.852677 -153.754636) (xy 254.853186 -153.782522) (xy 254.852677 -153.810408)
			(xy 254.844557 -153.865584) (xy 254.828489 -153.918991) (xy 254.804817 -153.969488) (xy 254.774044 -154.016001)
			(xy 254.736827 -154.057538) (xy 254.693959 -154.093213) (xy 254.646353 -154.122267) (xy 254.595024 -154.144079)
			(xy 254.541067 -154.158185) (xy 254.48563 -154.164285) (xy 254.429896 -154.162248) (xy 254.375053 -154.152118)
			(xy 254.322269 -154.134111) (xy 254.272669 -154.10861) (xy 254.227311 -154.076159) (xy 254.187162 -154.03745)
			(xy 254.153076 -153.993307) (xy 254.12578 -153.944672) (xy 254.105857 -153.892581) (xy 254.093731 -153.838144)
			(xy 254.08966 -153.782522) (xy 253.837186 -153.782522) (xy 253.836677 -153.810408) (xy 253.828557 -153.865584)
			(xy 253.812489 -153.918991) (xy 253.788817 -153.969488) (xy 253.758044 -154.016001) (xy 253.720827 -154.057538)
			(xy 253.677959 -154.093213) (xy 253.630353 -154.122267) (xy 253.579024 -154.144079) (xy 253.525067 -154.158185)
			(xy 253.46963 -154.164285) (xy 253.413896 -154.162248) (xy 253.359053 -154.152118) (xy 253.306269 -154.134111)
			(xy 253.256669 -154.10861) (xy 253.211311 -154.076159) (xy 253.171162 -154.03745) (xy 253.137076 -153.993307)
			(xy 253.10978 -153.944672) (xy 253.089857 -153.892581) (xy 253.077731 -153.838144) (xy 253.07366 -153.782522)
			(xy 252.821186 -153.782522) (xy 252.820677 -153.810408) (xy 252.812557 -153.865584) (xy 252.796489 -153.918991)
			(xy 252.772817 -153.969488) (xy 252.742044 -154.016001) (xy 252.704827 -154.057538) (xy 252.661959 -154.093213)
			(xy 252.614353 -154.122267) (xy 252.563024 -154.144079) (xy 252.509067 -154.158185) (xy 252.45363 -154.164285)
			(xy 252.397896 -154.162248) (xy 252.343053 -154.152118) (xy 252.290269 -154.134111) (xy 252.240669 -154.10861)
			(xy 252.195311 -154.076159) (xy 252.155162 -154.03745) (xy 252.121076 -153.993307) (xy 252.09378 -153.944672)
			(xy 252.073857 -153.892581) (xy 252.061731 -153.838144) (xy 252.05766 -153.782522) (xy 251.805186 -153.782522)
			(xy 251.804677 -153.810408) (xy 251.796557 -153.865584) (xy 251.780489 -153.918991) (xy 251.756817 -153.969488)
			(xy 251.726044 -154.016001) (xy 251.688827 -154.057538) (xy 251.645959 -154.093213) (xy 251.598353 -154.122267)
			(xy 251.547024 -154.144079) (xy 251.493067 -154.158185) (xy 251.43763 -154.164285) (xy 251.381896 -154.162248)
			(xy 251.327053 -154.152118) (xy 251.274269 -154.134111) (xy 251.224669 -154.10861) (xy 251.179311 -154.076159)
			(xy 251.139162 -154.03745) (xy 251.105076 -153.993307) (xy 251.07778 -153.944672) (xy 251.057857 -153.892581)
			(xy 251.045731 -153.838144) (xy 251.04166 -153.782522) (xy 249.769529 -153.782522) (xy 249.772677 -153.803912)
			(xy 249.773186 -153.831798) (xy 249.772677 -153.859684) (xy 249.764557 -153.91486) (xy 249.748489 -153.968267)
			(xy 249.724817 -154.018764) (xy 249.694044 -154.065277) (xy 249.656827 -154.106814) (xy 249.613959 -154.142489)
			(xy 249.566353 -154.171543) (xy 249.515024 -154.193355) (xy 249.461067 -154.207461) (xy 249.40563 -154.213561)
			(xy 249.349896 -154.211524) (xy 249.295053 -154.201394) (xy 249.242269 -154.183387) (xy 249.192669 -154.157886)
			(xy 249.147311 -154.125435) (xy 249.107162 -154.086726) (xy 249.073076 -154.042583) (xy 249.04578 -153.993948)
			(xy 249.025857 -153.941857) (xy 249.013731 -153.88742) (xy 249.00966 -153.831798) (xy 248.75352 -153.831798)
			(xy 248.747892 -153.868677) (xy 248.730616 -153.923917) (xy 248.705194 -153.975913) (xy 248.672208 -154.023472)
			(xy 248.632415 -154.065502) (xy 248.58673 -154.101037) (xy 248.536201 -154.129263) (xy 248.509282 -154.1399)
			(xy 248.495025 -154.145851) (xy 248.470683 -154.16485) (xy 248.453117 -154.190245) (xy 248.443925 -154.219723)
			(xy 248.443944 -154.250602) (xy 248.453172 -154.280069) (xy 248.46153 -154.293062) (xy 248.477637 -154.317193)
			(xy 248.503174 -154.369284) (xy 248.520534 -154.424641) (xy 248.529315 -154.481987) (xy 248.529856 -154.510994)
			(xy 248.52937 -154.538245) (xy 248.521614 -154.592193) (xy 248.506259 -154.644488) (xy 248.483617 -154.694065)
			(xy 248.454151 -154.739915) (xy 248.41846 -154.781106) (xy 248.377269 -154.816797) (xy 248.331419 -154.846263)
			(xy 248.281842 -154.868905) (xy 248.229547 -154.88426) (xy 248.175599 -154.892016) (xy 248.121097 -154.892016)
			(xy 248.067149 -154.88426) (xy 248.014854 -154.868905) (xy 247.965277 -154.846263) (xy 247.919427 -154.816797)
			(xy 247.878236 -154.781106) (xy 247.842545 -154.739915) (xy 247.813079 -154.694065) (xy 247.790437 -154.644488)
			(xy 247.775082 -154.592193) (xy 247.767326 -154.538245) (xy 247.76684 -154.510994) (xy 246.26381 -154.510994)
			(xy 246.24721 -154.548839) (xy 246.219654 -154.593681) (xy 246.186205 -154.634318) (xy 246.167148 -154.652472)
			(xy 246.159764 -154.660009) (xy 246.151228 -154.679277) (xy 246.150638 -154.68981) (xy 246.150638 -154.764486)
			(xy 246.15115 -154.775038) (xy 246.159696 -154.794334) (xy 246.167148 -154.801824) (xy 246.186217 -154.819965)
			(xy 246.219671 -154.860599) (xy 246.247227 -154.905443) (xy 246.268363 -154.953646) (xy 246.282678 -155.004296)
			(xy 246.2899 -155.056431) (xy 246.290338 -155.082748) (xy 246.289867 -155.109999) (xy 246.282105 -155.163946)
			(xy 246.266745 -155.216239) (xy 246.2441 -155.265814) (xy 246.214632 -155.311663) (xy 246.178939 -155.352852)
			(xy 246.137749 -155.388543) (xy 246.091899 -155.418009) (xy 246.042322 -155.440651) (xy 245.990028 -155.456008)
			(xy 245.936081 -155.463768) (xy 245.90883 -155.464256) (xy 245.882514 -155.463849) (xy 245.830382 -155.456604)
			(xy 245.779738 -155.442274) (xy 245.731539 -155.42113) (xy 245.686697 -155.393573) (xy 245.64606 -155.360123)
			(xy 245.627906 -155.341066) (xy 245.620375 -155.333675) (xy 245.601103 -155.325142) (xy 245.590568 -155.324556)
			(xy 245.515892 -155.324556) (xy 245.505342 -155.32508) (xy 245.486048 -155.33362) (xy 245.478554 -155.341066)
			(xy 245.458734 -155.361854) (xy 245.413962 -155.397829) (xy 245.364304 -155.426689) (xy 245.310882 -155.447782)
			(xy 245.254903 -155.460631) (xy 245.19763 -155.464946) (xy 245.140357 -155.460631) (xy 245.084378 -155.447782)
			(xy 245.030956 -155.426689) (xy 244.981298 -155.397829) (xy 244.936526 -155.361854) (xy 244.916706 -155.341066)
			(xy 244.909175 -155.333675) (xy 244.889903 -155.325142) (xy 244.879368 -155.324556) (xy 244.804692 -155.324556)
			(xy 244.794142 -155.32508) (xy 244.774848 -155.33362) (xy 244.767354 -155.341066) (xy 244.747534 -155.361854)
			(xy 244.702762 -155.397829) (xy 244.653104 -155.426689) (xy 244.599682 -155.447782) (xy 244.543703 -155.460631)
			(xy 244.48643 -155.464946) (xy 244.429157 -155.460631) (xy 244.373178 -155.447782) (xy 244.319756 -155.426689)
			(xy 244.270098 -155.397829) (xy 244.225326 -155.361854) (xy 244.205506 -155.341066) (xy 244.197975 -155.333675)
			(xy 244.178703 -155.325142) (xy 244.168168 -155.324556) (xy 244.093492 -155.324556) (xy 244.082942 -155.32508)
			(xy 244.063648 -155.33362) (xy 244.056154 -155.341066) (xy 244.038027 -155.360149) (xy 243.997389 -155.393602)
			(xy 243.952543 -155.421155) (xy 243.904337 -155.442288) (xy 243.853685 -155.4566) (xy 243.801548 -155.46382)
			(xy 243.77523 -155.464256) (xy 243.747982 -155.463694) (xy 243.694039 -155.455943) (xy 243.641749 -155.440594)
			(xy 243.592175 -155.41796) (xy 243.546327 -155.388501) (xy 243.505138 -155.352818) (xy 243.469446 -155.311636)
			(xy 243.439978 -155.265793) (xy 243.417333 -155.216224) (xy 243.401974 -155.163937) (xy 243.394212 -155.109996)
			(xy 243.393722 -155.082748) (xy 242.833333 -155.082748) (xy 242.832889 -155.107078) (xy 242.824769 -155.162254)
			(xy 242.808701 -155.215661) (xy 242.785029 -155.266158) (xy 242.754256 -155.312671) (xy 242.717039 -155.354208)
			(xy 242.674171 -155.389883) (xy 242.626565 -155.418937) (xy 242.575236 -155.440749) (xy 242.521279 -155.454855)
			(xy 242.465842 -155.460955) (xy 242.410108 -155.458918) (xy 242.355265 -155.448788) (xy 242.302481 -155.430781)
			(xy 242.252881 -155.40528) (xy 242.207523 -155.372829) (xy 242.167374 -155.33412) (xy 242.133288 -155.289977)
			(xy 242.105992 -155.241342) (xy 242.086069 -155.189251) (xy 242.073943 -155.134814) (xy 242.069872 -155.079192)
			(xy 241.256588 -155.079192) (xy 241.257269 -155.080645) (xy 241.273337 -155.134052) (xy 241.281457 -155.189228)
			(xy 241.281966 -155.217114) (xy 241.281457 -155.245) (xy 241.273337 -155.300176) (xy 241.257269 -155.353583)
			(xy 241.233597 -155.40408) (xy 241.202824 -155.450593) (xy 241.165607 -155.49213) (xy 241.122739 -155.527805)
			(xy 241.075133 -155.556859) (xy 241.023804 -155.578671) (xy 240.969847 -155.592777) (xy 240.91441 -155.598877)
			(xy 240.858676 -155.59684) (xy 240.803833 -155.58671) (xy 240.751049 -155.568703) (xy 240.701449 -155.543202)
			(xy 240.656091 -155.510751) (xy 240.615942 -155.472042) (xy 240.581856 -155.427899) (xy 240.55456 -155.379264)
			(xy 240.534637 -155.327173) (xy 240.522511 -155.272736) (xy 240.51844 -155.217114) (xy 240.232599 -155.217114)
			(xy 240.232183 -155.23992) (xy 240.224063 -155.295096) (xy 240.207995 -155.348503) (xy 240.184323 -155.399)
			(xy 240.15355 -155.445513) (xy 240.116333 -155.48705) (xy 240.073465 -155.522725) (xy 240.025859 -155.551779)
			(xy 239.97453 -155.573591) (xy 239.920573 -155.587697) (xy 239.865136 -155.593797) (xy 239.809402 -155.59176)
			(xy 239.754559 -155.58163) (xy 239.701775 -155.563623) (xy 239.652175 -155.538122) (xy 239.606817 -155.505671)
			(xy 239.566668 -155.466962) (xy 239.532582 -155.422819) (xy 239.505286 -155.374184) (xy 239.485363 -155.322093)
			(xy 239.473237 -155.267656) (xy 239.469166 -155.212034) (xy 227.719289 -155.212034) (xy 227.690328 -155.224341)
			(xy 227.636371 -155.238447) (xy 227.580934 -155.244547) (xy 227.5252 -155.24251) (xy 227.470357 -155.23238)
			(xy 227.417573 -155.214373) (xy 227.367973 -155.188872) (xy 227.322615 -155.156421) (xy 227.282466 -155.117712)
			(xy 227.24838 -155.073569) (xy 227.221084 -155.024934) (xy 227.201161 -154.972843) (xy 227.189035 -154.918406)
			(xy 227.184964 -154.862784) (xy 225.855899 -154.862784) (xy 225.841412 -154.884681) (xy 225.804195 -154.926218)
			(xy 225.761327 -154.961893) (xy 225.713721 -154.990947) (xy 225.662392 -155.012759) (xy 225.608435 -155.026865)
			(xy 225.552998 -155.032965) (xy 225.497264 -155.030928) (xy 225.442421 -155.020798) (xy 225.389637 -155.002791)
			(xy 225.340037 -154.97729) (xy 225.294679 -154.944839) (xy 225.25453 -154.90613) (xy 225.220444 -154.861987)
			(xy 225.193148 -154.813352) (xy 225.173225 -154.761261) (xy 225.161099 -154.706824) (xy 225.157028 -154.651202)
			(xy 201.054958 -154.651202) (xy 201.100854 -154.672163) (xy 201.149052 -154.703139) (xy 201.19235 -154.740658)
			(xy 201.229868 -154.783958) (xy 201.260843 -154.832156) (xy 201.284642 -154.884272) (xy 201.300783 -154.939244)
			(xy 201.308937 -154.995954) (xy 201.308937 -155.053246) (xy 201.300783 -155.109956) (xy 201.284642 -155.164928)
			(xy 201.260843 -155.217044) (xy 201.229868 -155.265242) (xy 201.19235 -155.308542) (xy 201.149052 -155.346061)
			(xy 201.100854 -155.377037) (xy 201.04874 -155.400838) (xy 200.993768 -155.416981) (xy 200.937058 -155.425136)
			(xy 200.908412 -155.425648) (xy 200.893494 -155.425483) (xy 200.863745 -155.423191) (xy 200.848976 -155.421076)
			(xy 200.8378 -155.419298) (xy 200.816718 -155.425394) (xy 200.749662 -155.483052) (xy 200.741711 -155.490658)
			(xy 200.732619 -155.510668) (xy 200.732136 -155.52166) (xy 200.732136 -155.786328) (xy 200.732615 -155.79732)
			(xy 200.741708 -155.817333) (xy 200.749662 -155.824936) (xy 200.816718 -155.882594) (xy 200.8378 -155.88869)
			(xy 200.848976 -155.886912) (xy 200.863745 -155.884804) (xy 200.893494 -155.882516) (xy 200.908412 -155.88234)
			(xy 200.93706 -155.88284) (xy 200.993773 -155.890996) (xy 201.035225 -155.903168) (xy 232.20883 -155.903168)
			(xy 232.212901 -155.847546) (xy 232.225027 -155.793109) (xy 232.24495 -155.741018) (xy 232.272246 -155.692383)
			(xy 232.306332 -155.64824) (xy 232.346481 -155.609531) (xy 232.391839 -155.57708) (xy 232.441439 -155.551579)
			(xy 232.494223 -155.533572) (xy 232.549066 -155.523442) (xy 232.6048 -155.521405) (xy 232.660237 -155.527505)
			(xy 232.714194 -155.541611) (xy 232.765523 -155.563423) (xy 232.813129 -155.592477) (xy 232.855997 -155.628152)
			(xy 232.893214 -155.669689) (xy 232.923987 -155.716202) (xy 232.947659 -155.766699) (xy 232.963727 -155.820106)
			(xy 232.971847 -155.875282) (xy 232.972356 -155.903168) (xy 232.971847 -155.931054) (xy 232.963727 -155.98623)
			(xy 232.947659 -156.039637) (xy 232.923987 -156.090134) (xy 232.893214 -156.136647) (xy 232.855997 -156.178184)
			(xy 232.813129 -156.213859) (xy 232.765523 -156.242913) (xy 232.714194 -156.264725) (xy 232.660237 -156.278831)
			(xy 232.6048 -156.284931) (xy 232.549066 -156.282894) (xy 232.494223 -156.272764) (xy 232.441439 -156.254757)
			(xy 232.391839 -156.229256) (xy 232.346481 -156.196805) (xy 232.306332 -156.158096) (xy 232.272246 -156.113953)
			(xy 232.24495 -156.065318) (xy 232.225027 -156.013227) (xy 232.212901 -155.95879) (xy 232.20883 -155.903168)
			(xy 201.035225 -155.903168) (xy 201.048748 -155.907139) (xy 201.100866 -155.930942) (xy 201.149066 -155.96192)
			(xy 201.192367 -155.999441) (xy 201.229887 -156.042744) (xy 201.260864 -156.090945) (xy 201.284665 -156.143063)
			(xy 201.300807 -156.198039) (xy 201.308961 -156.254752) (xy 201.308961 -156.312048) (xy 201.300807 -156.368761)
			(xy 201.284665 -156.423737) (xy 201.260864 -156.475855) (xy 201.229887 -156.524056) (xy 201.192367 -156.567359)
			(xy 201.149066 -156.60488) (xy 201.100866 -156.635858) (xy 201.048748 -156.659661) (xy 200.993773 -156.675804)
			(xy 200.93706 -156.68396) (xy 200.908412 -156.684472) (xy 200.881033 -156.683967) (xy 200.826786 -156.676502)
			(xy 200.774059 -156.661724) (xy 200.723834 -156.639908) (xy 200.677046 -156.611459) (xy 200.634565 -156.576907)
			(xy 200.597182 -156.536895) (xy 200.581006 -156.5148) (xy 200.57544 -156.507542) (xy 200.560333 -156.497257)
			(xy 200.551542 -156.494734) (xy 200.52157 -156.487368) (xy 200.512622 -156.485604) (xy 200.49453 -156.48783)
			(xy 200.486264 -156.491686) (xy 200.461669 -156.504085) (xy 200.410141 -156.523553) (xy 200.35665 -156.536698)
			(xy 200.301969 -156.543333) (xy 200.274428 -156.543756) (xy 200.246887 -156.54334) (xy 200.192206 -156.536701)
			(xy 200.138717 -156.52355) (xy 200.087191 -156.504079) (xy 200.062592 -156.491686) (xy 200.054335 -156.487804)
			(xy 200.036236 -156.485592) (xy 200.027286 -156.487368) (xy 199.997314 -156.494734) (xy 199.988537 -156.49729)
			(xy 199.973434 -156.507563) (xy 199.96785 -156.5148) (xy 199.951716 -156.53693) (xy 199.914337 -156.576961)
			(xy 199.871855 -156.611527) (xy 199.82506 -156.639985) (xy 199.774826 -156.661804) (xy 199.722087 -156.676577)
			(xy 199.667828 -156.684029) (xy 199.640444 -156.684472) (xy 199.611792 -156.683976) (xy 199.555072 -156.675827)
			(xy 199.500088 -156.659688) (xy 199.447962 -156.635887) (xy 199.399753 -156.60491) (xy 199.356444 -156.567387)
			(xy 199.318916 -156.524082) (xy 199.287934 -156.475877) (xy 199.264128 -156.423753) (xy 199.247983 -156.368771)
			(xy 199.239827 -156.312052) (xy 199.239827 -156.254748) (xy 199.247983 -156.198029) (xy 199.264128 -156.143047)
			(xy 199.287934 -156.090923) (xy 199.318916 -156.042718) (xy 199.356444 -155.999413) (xy 199.399753 -155.96189)
			(xy 199.447962 -155.930913) (xy 199.500088 -155.907112) (xy 199.555072 -155.890973) (xy 199.611792 -155.882824)
			(xy 199.640444 -155.88234) (xy 199.655362 -155.88251) (xy 199.685111 -155.884798) (xy 199.69988 -155.886912)
			(xy 199.711056 -155.88869) (xy 199.732138 -155.882594) (xy 199.799194 -155.824936) (xy 199.807144 -155.817328)
			(xy 199.816239 -155.79732) (xy 199.81672 -155.786328) (xy 199.81672 -155.52166) (xy 199.816231 -155.510669)
			(xy 199.807144 -155.490658) (xy 199.799194 -155.483052) (xy 199.732138 -155.425394) (xy 199.711056 -155.419298)
			(xy 199.69988 -155.421076) (xy 199.685111 -155.423189) (xy 199.655362 -155.425474) (xy 199.640444 -155.425648)
			(xy 199.611791 -155.4252) (xy 199.555067 -155.41705) (xy 199.50008 -155.40091) (xy 199.44795 -155.377108)
			(xy 199.399739 -155.346129) (xy 199.356427 -155.308604) (xy 199.318897 -155.265297) (xy 199.287913 -155.217089)
			(xy 199.264105 -155.164961) (xy 199.247959 -155.109976) (xy 199.239803 -155.053253) (xy 192.111345 -155.053253)
			(xy 194.066414 -157.008322) (xy 227.184964 -157.008322) (xy 227.189035 -156.9527) (xy 227.201161 -156.898263)
			(xy 227.221084 -156.846172) (xy 227.24838 -156.797537) (xy 227.282466 -156.753394) (xy 227.322615 -156.714685)
			(xy 227.367973 -156.682234) (xy 227.417573 -156.656733) (xy 227.470357 -156.638726) (xy 227.5252 -156.628596)
			(xy 227.580934 -156.626559) (xy 227.636371 -156.632659) (xy 227.690328 -156.646765) (xy 227.741657 -156.668577)
			(xy 227.7831 -156.69387) (xy 241.0874 -156.69387) (xy 241.091471 -156.638248) (xy 241.103597 -156.583811)
			(xy 241.12352 -156.53172) (xy 241.150816 -156.483085) (xy 241.184902 -156.438942) (xy 241.225051 -156.400233)
			(xy 241.270409 -156.367782) (xy 241.320009 -156.342281) (xy 241.372793 -156.324274) (xy 241.427636 -156.314144)
			(xy 241.48337 -156.312107) (xy 241.538807 -156.318207) (xy 241.592764 -156.332313) (xy 241.644093 -156.354125)
			(xy 241.691699 -156.383179) (xy 241.734567 -156.418854) (xy 241.771784 -156.460391) (xy 241.802557 -156.506904)
			(xy 241.826229 -156.557401) (xy 241.842297 -156.610808) (xy 241.850417 -156.665984) (xy 241.850926 -156.69387)
			(xy 241.850417 -156.721756) (xy 241.842297 -156.776932) (xy 241.826229 -156.830339) (xy 241.802557 -156.880836)
			(xy 241.771784 -156.927349) (xy 241.734567 -156.968886) (xy 241.691699 -157.004561) (xy 241.644093 -157.033615)
			(xy 241.592764 -157.055427) (xy 241.538807 -157.069533) (xy 241.48337 -157.075633) (xy 241.427636 -157.073596)
			(xy 241.372793 -157.063466) (xy 241.320009 -157.045459) (xy 241.270409 -157.019958) (xy 241.225051 -156.987507)
			(xy 241.184902 -156.948798) (xy 241.150816 -156.904655) (xy 241.12352 -156.85602) (xy 241.103597 -156.803929)
			(xy 241.091471 -156.749492) (xy 241.0874 -156.69387) (xy 227.7831 -156.69387) (xy 227.789263 -156.697631)
			(xy 227.832131 -156.733306) (xy 227.869348 -156.774843) (xy 227.900121 -156.821356) (xy 227.923793 -156.871853)
			(xy 227.939861 -156.92526) (xy 227.947981 -156.980436) (xy 227.94849 -157.008322) (xy 227.947981 -157.036208)
			(xy 227.939861 -157.091384) (xy 227.923793 -157.144791) (xy 227.900121 -157.195288) (xy 227.869348 -157.241801)
			(xy 227.832131 -157.283338) (xy 227.789263 -157.319013) (xy 227.741657 -157.348067) (xy 227.690328 -157.369879)
			(xy 227.636371 -157.383985) (xy 227.580934 -157.390085) (xy 227.5252 -157.388048) (xy 227.470357 -157.377918)
			(xy 227.417573 -157.359911) (xy 227.367973 -157.33441) (xy 227.322615 -157.301959) (xy 227.282466 -157.26325)
			(xy 227.24838 -157.219107) (xy 227.221084 -157.170472) (xy 227.201161 -157.118381) (xy 227.189035 -157.063944)
			(xy 227.184964 -157.008322) (xy 194.066414 -157.008322) (xy 194.875404 -157.817312) (xy 194.880832 -157.822297)
			(xy 194.89387 -157.829152) (xy 194.901058 -157.830774) (xy 194.901566 -157.830774) (xy 194.910964 -157.83179)
			(xy 228.270816 -157.83179) (xy 228.279739 -157.831402) (xy 228.29651 -157.825305) (xy 228.303582 -157.819852)
			(xy 228.303582 -157.819598) (xy 228.310069 -157.813654) (xy 228.318916 -157.798461) (xy 228.320854 -157.78988)
			(xy 228.320854 -157.789626) (xy 228.327667 -157.755441) (xy 228.350244 -157.689496) (xy 228.365812 -157.658308)
			(xy 228.368352 -157.65272) (xy 228.369875 -157.648432) (xy 228.371541 -157.639488) (xy 228.371654 -157.63494)
			(xy 228.37013 -157.622748) (xy 228.36505 -157.60192) (xy 228.363854 -157.597534) (xy 228.360142 -157.589235)
			(xy 228.357684 -157.58541) (xy 228.342952 -157.56382) (xy 228.33584 -157.55874) (xy 228.314586 -157.542454)
			(xy 228.276168 -157.505156) (xy 228.243051 -157.46308) (xy 228.215824 -157.416973) (xy 228.194971 -157.367656)
			(xy 228.180861 -157.316003) (xy 228.173746 -157.262933) (xy 228.17328 -157.23616) (xy 228.173791 -157.207512)
			(xy 228.181945 -157.150798) (xy 228.198088 -157.095823) (xy 228.221889 -157.043704) (xy 228.252866 -156.995503)
			(xy 228.290387 -156.952201) (xy 228.333689 -156.91468) (xy 228.38189 -156.883703) (xy 228.434009 -156.859902)
			(xy 228.488984 -156.843759) (xy 228.545698 -156.835605) (xy 228.602994 -156.835605) (xy 228.659708 -156.843759)
			(xy 228.714683 -156.859902) (xy 228.766802 -156.883703) (xy 228.815003 -156.91468) (xy 228.858305 -156.952201)
			(xy 228.895826 -156.995503) (xy 228.926803 -157.043704) (xy 228.950604 -157.095823) (xy 228.966747 -157.150798)
			(xy 228.974901 -157.207512) (xy 228.975412 -157.23616) (xy 228.975412 -157.236414) (xy 228.975287 -157.251201)
			(xy 228.973127 -157.280695) (xy 228.971094 -157.295342) (xy 228.971094 -157.295596) (xy 228.969899 -157.306312)
			(xy 228.975551 -157.3271) (xy 228.982016 -157.335728) (xy 228.982778 -157.33649) (xy 229.032816 -157.394656)
			(xy 229.040392 -157.40267) (xy 229.060408 -157.411874) (xy 229.071424 -157.412436) (xy 229.336092 -157.412436)
			(xy 229.347112 -157.411898) (xy 229.367134 -157.402686) (xy 229.3747 -157.394656) (xy 229.424992 -157.336236)
			(xy 229.428391 -157.332054) (xy 229.433512 -157.322574) (xy 229.435152 -157.31744) (xy 229.4382 -157.307026)
			(xy 229.436422 -157.295596) (xy 229.434384 -157.280886) (xy 229.43222 -157.251264) (xy 229.432104 -157.236414)
			(xy 229.432104 -157.23616) (xy 229.432617 -157.207513) (xy 229.440776 -157.150802) (xy 229.456921 -157.09583)
			(xy 229.480725 -157.043714) (xy 229.511703 -156.995516) (xy 229.549223 -156.952216) (xy 229.592524 -156.914697)
			(xy 229.640723 -156.88372) (xy 229.692839 -156.859918) (xy 229.747812 -156.843774) (xy 229.804523 -156.835617)
			(xy 229.83317 -156.835094) (xy 229.861438 -156.835582) (xy 229.917413 -156.843529) (xy 229.971718 -156.859255)
			(xy 230.023278 -156.88245) (xy 230.071071 -156.912653) (xy 230.11415 -156.949266) (xy 230.151663 -156.991564)
			(xy 230.182866 -157.03871) (xy 230.207141 -157.08977) (xy 230.224008 -157.143732) (xy 230.233132 -157.199527)
			(xy 230.234236 -157.227778) (xy 230.234236 -157.237176) (xy 230.233728 -157.25394) (xy 230.233728 -157.255464)
			(xy 230.231717 -157.28574) (xy 230.219705 -157.345215) (xy 230.198858 -157.402197) (xy 230.169654 -157.455383)
			(xy 230.132761 -157.503554) (xy 230.089024 -157.545609) (xy 230.064564 -157.563566) (xy 230.061516 -157.565598)
			(xy 230.05572 -157.570773) (xy 230.047319 -157.583834) (xy 230.045006 -157.591252) (xy 230.036624 -157.625288)
			(xy 230.035393 -157.632496) (xy 230.03656 -157.647065) (xy 230.03891 -157.65399) (xy 230.04145 -157.658562)
			(xy 230.05195 -157.679403) (xy 230.069131 -157.722795) (xy 230.07574 -157.745176) (xy 230.07574 -157.745684)
			(xy 230.078825 -157.756614) (xy 230.084033 -157.778723) (xy 230.086154 -157.78988) (xy 230.086154 -157.790134)
			(xy 230.088131 -157.798647) (xy 230.096965 -157.813712) (xy 230.103426 -157.819598) (xy 230.103426 -157.819852)
			(xy 230.110474 -157.825353) (xy 230.127258 -157.831479) (xy 230.136192 -157.83179) (xy 230.518462 -157.83179)
			(xy 230.518716 -157.83179) (xy 230.529753 -157.83118) (xy 230.549751 -157.821815) (xy 230.563995 -157.804942)
			(xy 230.567484 -157.794452) (xy 230.567992 -157.791912) (xy 230.574957 -157.76249) (xy 230.595594 -157.705659)
			(xy 230.60914 -157.678628) (xy 230.612442 -157.6705) (xy 230.614264 -157.664317) (xy 230.615038 -157.651456)
			(xy 230.613966 -157.6451) (xy 230.608378 -157.62224) (xy 230.607184 -157.617853) (xy 230.603476 -157.609552)
			(xy 230.601012 -157.60573) (xy 230.58628 -157.58414) (xy 230.579168 -157.57906) (xy 230.557912 -157.562775)
			(xy 230.519489 -157.525479) (xy 230.486368 -157.483404) (xy 230.459137 -157.437298) (xy 230.43828 -157.387979)
			(xy 230.424166 -157.336326) (xy 230.417047 -157.283254) (xy 230.416608 -157.25648) (xy 230.417119 -157.227832)
			(xy 230.425273 -157.171118) (xy 230.441416 -157.116143) (xy 230.465217 -157.064024) (xy 230.496194 -157.015823)
			(xy 230.533715 -156.972521) (xy 230.577017 -156.935) (xy 230.625218 -156.904023) (xy 230.677337 -156.880222)
			(xy 230.732312 -156.864079) (xy 230.789026 -156.855925) (xy 230.846322 -156.855925) (xy 230.903036 -156.864079)
			(xy 230.958011 -156.880222) (xy 231.01013 -156.904023) (xy 231.058331 -156.935) (xy 231.101633 -156.972521)
			(xy 231.139154 -157.015823) (xy 231.170131 -157.064024) (xy 231.193932 -157.116143) (xy 231.210075 -157.171118)
			(xy 231.218229 -157.227832) (xy 231.21874 -157.25648) (xy 231.21874 -157.256734) (xy 231.218614 -157.271521)
			(xy 231.216452 -157.301015) (xy 231.214422 -157.315662) (xy 231.214422 -157.315916) (xy 231.213231 -157.326631)
			(xy 231.218882 -157.347418) (xy 231.225344 -157.356048) (xy 231.226106 -157.35681) (xy 231.276144 -157.414976)
			(xy 231.283717 -157.422996) (xy 231.303735 -157.432203) (xy 231.314752 -157.432756) (xy 231.57942 -157.432756)
			(xy 231.590438 -157.432213) (xy 231.610454 -157.422996) (xy 231.618028 -157.414976) (xy 231.66832 -157.356556)
			(xy 231.671718 -157.352373) (xy 231.676841 -157.342894) (xy 231.67848 -157.33776) (xy 231.681528 -157.327346)
			(xy 231.67975 -157.315916) (xy 231.677715 -157.301205) (xy 231.675556 -157.271584) (xy 231.675432 -157.256734)
			(xy 231.675432 -157.25648) (xy 231.675945 -157.227833) (xy 231.684101 -157.171121) (xy 231.700245 -157.116148)
			(xy 231.724048 -157.064032) (xy 231.755025 -157.015833) (xy 231.792546 -156.972534) (xy 231.835848 -156.935014)
			(xy 231.884048 -156.904039) (xy 231.936165 -156.880239) (xy 231.991139 -156.864097) (xy 232.047851 -156.855943)
			(xy 232.076498 -156.855414) (xy 232.104764 -156.855904) (xy 232.160735 -156.863854) (xy 232.215036 -156.879583)
			(xy 232.266591 -156.902779) (xy 232.314379 -156.932983) (xy 232.357453 -156.969597) (xy 232.394961 -157.011895)
			(xy 232.42616 -157.05904) (xy 232.45043 -157.110098) (xy 232.467293 -157.164057) (xy 232.476414 -157.21985)
			(xy 232.477564 -157.248098) (xy 232.477564 -157.257496) (xy 232.477056 -157.27426) (xy 232.477056 -157.275784)
			(xy 232.475044 -157.30606) (xy 232.46303 -157.365534) (xy 232.442182 -157.422515) (xy 232.412977 -157.4757)
			(xy 232.376085 -157.523871) (xy 232.332349 -157.565926) (xy 232.307892 -157.583886) (xy 232.304844 -157.585918)
			(xy 232.299093 -157.591053) (xy 232.290702 -157.60398) (xy 232.288334 -157.611318) (xy 232.280206 -157.6451)
			(xy 232.278936 -157.656022) (xy 232.28427 -157.67812) (xy 232.287064 -157.683454) (xy 232.299689 -157.709418)
			(xy 232.319049 -157.763811) (xy 232.325672 -157.791912) (xy 232.32618 -157.794452) (xy 232.329636 -157.804954)
			(xy 232.343889 -157.821825) (xy 232.363907 -157.831155) (xy 232.374948 -157.83179) (xy 238.781336 -157.83179)
			(xy 238.790289 -157.8314) (xy 238.807074 -157.825158) (xy 238.814102 -157.819598) (xy 238.838486 -157.797246)
			(xy 238.845344 -157.788864) (xy 238.847372 -157.785656) (xy 238.850559 -157.778769) (xy 238.851694 -157.775148)
			(xy 238.85271 -157.767528) (xy 238.85271 -157.767274) (xy 238.85652 -157.739789) (xy 238.871049 -157.686237)
			(xy 238.893168 -157.635349) (xy 238.922409 -157.588192) (xy 238.958161 -157.545757) (xy 238.999671 -157.508937)
			(xy 239.046068 -157.478503) (xy 239.096376 -157.455096) (xy 239.14954 -157.439206) (xy 239.204442 -157.431169)
			(xy 239.232186 -157.430724) (xy 239.260805 -157.431231) (xy 239.317403 -157.43976) (xy 239.372097 -157.45663)
			(xy 239.423666 -157.481464) (xy 239.470958 -157.513706) (xy 239.512915 -157.552637) (xy 239.548602 -157.597388)
			(xy 239.577219 -157.646957) (xy 239.598129 -157.700238) (xy 239.610864 -157.75604) (xy 239.61344 -157.784546)
			(xy 239.61344 -157.7848) (xy 239.614202 -157.793944) (xy 239.616237 -157.800854) (xy 239.623587 -157.813234)
			(xy 239.62868 -157.818328) (xy 239.635792 -157.824932) (xy 239.644428 -157.828234) (xy 239.648891 -157.829866)
			(xy 239.65822 -157.831664) (xy 239.66297 -157.83179) (xy 241.080798 -157.83179) (xy 241.086032 -157.831636)
			(xy 241.096275 -157.829464) (xy 241.101118 -157.827472) (xy 241.107468 -157.824424) (xy 241.123978 -157.81655)
			(xy 241.134646 -157.808676) (xy 241.136932 -157.806136) (xy 241.155109 -157.786441) (xy 241.196032 -157.751833)
			(xy 241.241395 -157.723292) (xy 241.290306 -157.70138) (xy 241.341801 -157.686527) (xy 241.394869 -157.679028)
			(xy 241.448463 -157.679028) (xy 241.501531 -157.686527) (xy 241.553026 -157.70138) (xy 241.601937 -157.723292)
			(xy 241.6473 -157.751833) (xy 241.688223 -157.786441) (xy 241.7064 -157.806136) (xy 241.708686 -157.808676)
			(xy 241.719354 -157.81655) (xy 241.735864 -157.824424) (xy 241.742214 -157.827472) (xy 241.747053 -157.829479)
			(xy 241.757297 -157.831664) (xy 241.762534 -157.83179) (xy 243.120164 -157.83179) (xy 243.131406 -157.831211)
			(xy 243.151723 -157.821589) (xy 243.15928 -157.813248) (xy 243.209572 -157.752542) (xy 243.212971 -157.748176)
			(xy 243.217972 -157.738308) (xy 243.219478 -157.732984) (xy 243.222272 -157.72257) (xy 243.219986 -157.710886)
			(xy 243.218716 -157.704536) (xy 243.218716 -157.704282) (xy 243.217954 -157.699964) (xy 243.2177 -157.698694)
			(xy 243.2177 -157.697678) (xy 243.21643 -157.68955) (xy 243.21643 -157.689042) (xy 243.215922 -157.686248)
			(xy 243.215922 -157.685994) (xy 243.215668 -157.683962) (xy 243.214906 -157.67685) (xy 243.214906 -157.676342)
			(xy 243.214652 -157.67304) (xy 243.21389 -157.648148) (xy 243.21389 -157.64764) (xy 243.214445 -157.620652)
			(xy 243.223247 -157.567398) (xy 243.240575 -157.516278) (xy 243.26597 -157.468649) (xy 243.298759 -157.425772)
			(xy 243.338071 -157.388786) (xy 243.360194 -157.37332) (xy 243.363763 -157.370224) (xy 243.369776 -157.362937)
			(xy 243.372132 -157.358842) (xy 243.372132 -157.358334) (xy 243.37503 -157.352723) (xy 243.378247 -157.340515)
			(xy 243.378482 -157.334204) (xy 243.378482 -157.250384) (xy 243.378231 -157.244075) (xy 243.375025 -157.231866)
			(xy 243.372132 -157.226254) (xy 243.372132 -157.225746) (xy 243.369742 -157.221674) (xy 243.363731 -157.214396)
			(xy 243.360194 -157.211268) (xy 243.33807 -157.195765) (xy 243.298716 -157.158761) (xy 243.265901 -157.115851)
			(xy 243.240499 -157.068177) (xy 243.223185 -157.017007) (xy 243.214421 -156.963704) (xy 243.21389 -156.936694)
			(xy 243.2144 -156.910707) (xy 243.22253 -156.859372) (xy 243.238591 -156.809942) (xy 243.262187 -156.763632)
			(xy 243.292737 -156.721584) (xy 243.329488 -156.684833) (xy 243.371536 -156.654283) (xy 243.417846 -156.630687)
			(xy 243.467276 -156.614626) (xy 243.518611 -156.606496) (xy 243.570585 -156.606496) (xy 243.62192 -156.614626)
			(xy 243.67135 -156.630687) (xy 243.71766 -156.654283) (xy 243.759708 -156.684833) (xy 243.796459 -156.721584)
			(xy 243.827009 -156.763632) (xy 243.850605 -156.809942) (xy 243.866666 -156.859372) (xy 243.874796 -156.910707)
			(xy 243.875306 -156.936694) (xy 243.875199 -156.95028) (xy 243.873039 -156.977365) (xy 243.870988 -156.990796)
			(xy 243.870988 -156.99105) (xy 243.87048 -156.99359) (xy 243.870226 -156.995114) (xy 243.865027 -157.021147)
			(xy 243.847435 -157.07123) (xy 243.822059 -157.117855) (xy 243.789553 -157.159821) (xy 243.750753 -157.196049)
			(xy 243.729002 -157.211268) (xy 243.725433 -157.214364) (xy 243.719419 -157.22165) (xy 243.717064 -157.225746)
			(xy 243.717064 -157.226254) (xy 243.714165 -157.231865) (xy 243.710945 -157.244073) (xy 243.710714 -157.250384)
			(xy 243.710714 -157.334204) (xy 243.710963 -157.340514) (xy 243.714167 -157.352724) (xy 243.717064 -157.358334)
			(xy 243.717064 -157.358842) (xy 243.719453 -157.362914) (xy 243.725463 -157.370195) (xy 243.729002 -157.37332)
			(xy 243.751127 -157.388822) (xy 243.790483 -157.425826) (xy 243.823299 -157.468736) (xy 243.848703 -157.51641)
			(xy 243.866019 -157.56758) (xy 243.874786 -157.620884) (xy 243.875306 -157.647894) (xy 243.875107 -157.663743)
			(xy 243.872054 -157.695293) (xy 243.86921 -157.710886) (xy 243.866924 -157.72257) (xy 243.869718 -157.732984)
			(xy 243.871245 -157.7383) (xy 243.876243 -157.748164) (xy 243.879624 -157.752542) (xy 243.929916 -157.813248)
			(xy 243.937514 -157.82154) (xy 243.957804 -157.83118) (xy 243.969032 -157.83179) (xy 244.020086 -157.83179)
			(xy 244.031325 -157.831207) (xy 244.051635 -157.821579) (xy 244.059202 -157.813248) (xy 244.109494 -157.752542)
			(xy 244.112892 -157.748176) (xy 244.117891 -157.738307) (xy 244.1194 -157.732984) (xy 244.122194 -157.72257)
			(xy 244.119908 -157.710886) (xy 244.118638 -157.704536) (xy 244.118638 -157.704282) (xy 244.117876 -157.699964)
			(xy 244.117622 -157.698694) (xy 244.117622 -157.697678) (xy 244.116352 -157.68955) (xy 244.116352 -157.689042)
			(xy 244.115844 -157.686248) (xy 244.115844 -157.685994) (xy 244.11559 -157.683962) (xy 244.114828 -157.67685)
			(xy 244.114828 -157.676342) (xy 244.114574 -157.67304) (xy 244.113812 -157.648148) (xy 244.113812 -157.64764)
			(xy 244.114367 -157.620652) (xy 244.123169 -157.567399) (xy 244.140498 -157.51628) (xy 244.165894 -157.468652)
			(xy 244.198684 -157.425777) (xy 244.237998 -157.388792) (xy 244.260116 -157.37332) (xy 244.263684 -157.370223)
			(xy 244.269694 -157.362935) (xy 244.272054 -157.358842) (xy 244.272054 -157.358334) (xy 244.27495 -157.352722)
			(xy 244.278166 -157.340514) (xy 244.278404 -157.334204) (xy 244.278404 -157.250384) (xy 244.278154 -157.244075)
			(xy 244.274948 -157.231865) (xy 244.272054 -157.226254) (xy 244.272054 -157.225746) (xy 244.269665 -157.221674)
			(xy 244.263655 -157.214393) (xy 244.260116 -157.211268) (xy 244.237991 -157.195766) (xy 244.198634 -157.158763)
			(xy 244.165817 -157.115853) (xy 244.140413 -157.068179) (xy 244.123098 -157.017009) (xy 244.114333 -156.963704)
			(xy 244.113812 -156.936694) (xy 244.114322 -156.910707) (xy 244.122452 -156.859372) (xy 244.138513 -156.809942)
			(xy 244.162109 -156.763632) (xy 244.192659 -156.721584) (xy 244.22941 -156.684833) (xy 244.271458 -156.654283)
			(xy 244.317768 -156.630687) (xy 244.367198 -156.614626) (xy 244.418533 -156.606496) (xy 244.470507 -156.606496)
			(xy 244.521842 -156.614626) (xy 244.571272 -156.630687) (xy 244.617582 -156.654283) (xy 244.65963 -156.684833)
			(xy 244.696381 -156.721584) (xy 244.726931 -156.763632) (xy 244.750527 -156.809942) (xy 244.766588 -156.859372)
			(xy 244.774718 -156.910707) (xy 244.775228 -156.936694) (xy 244.775121 -156.95028) (xy 244.772961 -156.977365)
			(xy 244.77091 -156.990796) (xy 244.77091 -156.99105) (xy 244.770402 -156.99359) (xy 244.770148 -156.995114)
			(xy 244.76495 -157.021147) (xy 244.747358 -157.071231) (xy 244.721983 -157.117858) (xy 244.689478 -157.159826)
			(xy 244.65068 -157.196055) (xy 244.628924 -157.211268) (xy 244.625353 -157.214363) (xy 244.619337 -157.221648)
			(xy 244.616986 -157.225746) (xy 244.616986 -157.226254) (xy 244.614086 -157.231865) (xy 244.610865 -157.244073)
			(xy 244.610636 -157.250384) (xy 244.610636 -157.334204) (xy 244.610884 -157.340514) (xy 244.614083 -157.352726)
			(xy 244.616986 -157.358334) (xy 244.616986 -157.358842) (xy 244.619372 -157.362917) (xy 244.625376 -157.370204)
			(xy 244.628924 -157.37332) (xy 244.651053 -157.388819) (xy 244.690418 -157.425819) (xy 244.723242 -157.468728)
			(xy 244.748653 -157.516403) (xy 244.765973 -157.567575) (xy 244.774742 -157.620882) (xy 244.775228 -157.647894)
			(xy 244.775029 -157.663743) (xy 244.771977 -157.695293) (xy 244.769132 -157.710886) (xy 244.766846 -157.72257)
			(xy 244.76964 -157.732984) (xy 244.771168 -157.7383) (xy 244.776167 -157.748163) (xy 244.779546 -157.752542)
			(xy 244.829838 -157.813248) (xy 244.837437 -157.821536) (xy 244.857728 -157.831168) (xy 244.868954 -157.83179)
			(xy 244.920008 -157.83179) (xy 244.931245 -157.831202) (xy 244.951548 -157.821569) (xy 244.959124 -157.813248)
			(xy 245.009416 -157.752542) (xy 245.012818 -157.748178) (xy 245.017825 -157.738311) (xy 245.019322 -157.732984)
			(xy 245.022116 -157.72257) (xy 245.01983 -157.710886) (xy 245.01856 -157.704536) (xy 245.01856 -157.704282)
			(xy 245.017798 -157.699964) (xy 245.017544 -157.698694) (xy 245.017544 -157.697678) (xy 245.016274 -157.68955)
			(xy 245.016274 -157.689042) (xy 245.015766 -157.686248) (xy 245.015766 -157.685994) (xy 245.015512 -157.683962)
			(xy 245.01475 -157.67685) (xy 245.01475 -157.676342) (xy 245.014496 -157.67304) (xy 245.013734 -157.648148)
			(xy 245.013734 -157.64764) (xy 245.014289 -157.620653) (xy 245.023092 -157.5674) (xy 245.040422 -157.516282)
			(xy 245.065819 -157.468655) (xy 245.09861 -157.425781) (xy 245.137925 -157.388799) (xy 245.160038 -157.37332)
			(xy 245.16361 -157.370226) (xy 245.169629 -157.362943) (xy 245.171976 -157.358842) (xy 245.171976 -157.358334)
			(xy 245.174872 -157.352722) (xy 245.178086 -157.340514) (xy 245.178326 -157.334204) (xy 245.178326 -157.250384)
			(xy 245.178076 -157.244075) (xy 245.174872 -157.231865) (xy 245.171976 -157.226254) (xy 245.171976 -157.225746)
			(xy 245.169588 -157.221673) (xy 245.16358 -157.21439) (xy 245.160038 -157.211268) (xy 245.137912 -157.195767)
			(xy 245.098553 -157.158765) (xy 245.065734 -157.115855) (xy 245.040328 -157.068181) (xy 245.023011 -157.01701)
			(xy 245.014245 -156.963705) (xy 245.013734 -156.936694) (xy 245.014244 -156.910707) (xy 245.022374 -156.859372)
			(xy 245.038435 -156.809942) (xy 245.062031 -156.763632) (xy 245.092581 -156.721584) (xy 245.129332 -156.684833)
			(xy 245.17138 -156.654283) (xy 245.21769 -156.630687) (xy 245.26712 -156.614626) (xy 245.318455 -156.606496)
			(xy 245.370429 -156.606496) (xy 245.421764 -156.614626) (xy 245.471194 -156.630687) (xy 245.517504 -156.654283)
			(xy 245.559552 -156.684833) (xy 245.596303 -156.721584) (xy 245.626853 -156.763632) (xy 245.650449 -156.809942)
			(xy 245.66651 -156.859372) (xy 245.67464 -156.910707) (xy 245.67515 -156.936694) (xy 245.675043 -156.95028)
			(xy 245.672883 -156.977365) (xy 245.670832 -156.990796) (xy 245.670832 -156.99105) (xy 245.670324 -156.99359)
			(xy 245.67007 -156.995114) (xy 245.664872 -157.021148) (xy 245.647281 -157.071233) (xy 245.621908 -157.11786)
			(xy 245.589404 -157.15983) (xy 245.550606 -157.196062) (xy 245.528846 -157.211268) (xy 245.525274 -157.214362)
			(xy 245.519256 -157.221645) (xy 245.516908 -157.225746) (xy 245.516908 -157.226254) (xy 245.514012 -157.231866)
			(xy 245.510795 -157.244074) (xy 245.510558 -157.250384) (xy 245.510558 -157.334204) (xy 245.510807 -157.340514)
			(xy 245.514007 -157.352726) (xy 245.516908 -157.358334) (xy 245.516908 -157.358842) (xy 245.519295 -157.362916)
			(xy 245.525301 -157.370201) (xy 245.528846 -157.37332) (xy 245.550974 -157.38882) (xy 245.590336 -157.425821)
			(xy 245.623158 -157.46873) (xy 245.648567 -157.516405) (xy 245.665886 -157.567576) (xy 245.674655 -157.620882)
			(xy 245.67515 -157.647894) (xy 245.674951 -157.663743) (xy 245.671899 -157.695293) (xy 245.669054 -157.710886)
			(xy 245.666768 -157.72257) (xy 245.669562 -157.732984) (xy 245.671087 -157.738301) (xy 245.676081 -157.748169)
			(xy 245.679468 -157.752542) (xy 245.72976 -157.813248) (xy 245.73736 -157.821533) (xy 245.757651 -157.831156)
			(xy 245.768876 -157.83179) (xy 245.820184 -157.83179) (xy 245.831424 -157.831207) (xy 245.851734 -157.82158)
			(xy 245.8593 -157.813248) (xy 245.909592 -157.752542) (xy 245.91299 -157.748176) (xy 245.917989 -157.738307)
			(xy 245.919498 -157.732984) (xy 245.922292 -157.72257) (xy 245.920006 -157.710886) (xy 245.918736 -157.704536)
			(xy 245.918736 -157.704282) (xy 245.917974 -157.699964) (xy 245.91772 -157.698694) (xy 245.91772 -157.697678)
			(xy 245.91645 -157.68955) (xy 245.91645 -157.689042) (xy 245.915942 -157.686248) (xy 245.915942 -157.685994)
			(xy 245.915688 -157.683962) (xy 245.914926 -157.67685) (xy 245.914926 -157.676342) (xy 245.914672 -157.67304)
			(xy 245.91391 -157.648148) (xy 245.91391 -157.64764) (xy 245.914465 -157.620652) (xy 245.923267 -157.567399)
			(xy 245.940596 -157.51628) (xy 245.965992 -157.468652) (xy 245.998782 -157.425776) (xy 246.038095 -157.388792)
			(xy 246.060214 -157.37332) (xy 246.063782 -157.370223) (xy 246.069793 -157.362935) (xy 246.072152 -157.358842)
			(xy 246.072152 -157.358334) (xy 246.075048 -157.352722) (xy 246.078265 -157.340514) (xy 246.078502 -157.334204)
			(xy 246.078502 -157.250384) (xy 246.078252 -157.244075) (xy 246.075046 -157.231865) (xy 246.072152 -157.226254)
			(xy 246.072152 -157.225746) (xy 246.069763 -157.221674) (xy 246.063753 -157.214393) (xy 246.060214 -157.211268)
			(xy 246.038089 -157.195766) (xy 245.998733 -157.158762) (xy 245.965916 -157.115853) (xy 245.940512 -157.068179)
			(xy 245.923197 -157.017009) (xy 245.914432 -156.963704) (xy 245.91391 -156.936694) (xy 245.91442 -156.910707)
			(xy 245.92255 -156.859372) (xy 245.938611 -156.809942) (xy 245.962207 -156.763632) (xy 245.992757 -156.721584)
			(xy 246.029508 -156.684833) (xy 246.071556 -156.654283) (xy 246.117866 -156.630687) (xy 246.167296 -156.614626)
			(xy 246.218631 -156.606496) (xy 246.270605 -156.606496) (xy 246.32194 -156.614626) (xy 246.37137 -156.630687)
			(xy 246.41768 -156.654283) (xy 246.459728 -156.684833) (xy 246.496479 -156.721584) (xy 246.527029 -156.763632)
			(xy 246.550625 -156.809942) (xy 246.566686 -156.859372) (xy 246.574816 -156.910707) (xy 246.575326 -156.936694)
			(xy 246.575219 -156.95028) (xy 246.573059 -156.977365) (xy 246.571008 -156.990796) (xy 246.571008 -156.99105)
			(xy 246.5705 -156.99359) (xy 246.570246 -156.995114) (xy 246.565048 -157.021147) (xy 246.547456 -157.071231)
			(xy 246.522081 -157.117857) (xy 246.489576 -157.159825) (xy 246.450777 -157.196054) (xy 246.429022 -157.211268)
			(xy 246.425452 -157.214363) (xy 246.419435 -157.221648) (xy 246.417084 -157.225746) (xy 246.417084 -157.226254)
			(xy 246.414184 -157.231865) (xy 246.410963 -157.244073) (xy 246.410734 -157.250384) (xy 246.410734 -157.334204)
			(xy 246.410982 -157.340514) (xy 246.414181 -157.352727) (xy 246.417084 -157.358334) (xy 246.417084 -157.358842)
			(xy 246.41947 -157.362917) (xy 246.425474 -157.370204) (xy 246.429022 -157.37332) (xy 246.451151 -157.388819)
			(xy 246.490516 -157.425819) (xy 246.523341 -157.468728) (xy 246.548752 -157.516402) (xy 246.566072 -157.567574)
			(xy 246.574841 -157.620882) (xy 246.575326 -157.647894) (xy 246.575127 -157.663743) (xy 246.572075 -157.695293)
			(xy 246.56923 -157.710886) (xy 246.566944 -157.72257) (xy 246.569738 -157.732984) (xy 246.571265 -157.7383)
			(xy 246.576265 -157.748163) (xy 246.579644 -157.752542) (xy 246.629936 -157.813248) (xy 246.637535 -157.821537)
			(xy 246.657826 -157.831169) (xy 246.669052 -157.83179) (xy 247.43537 -157.83179) (xy 247.446497 -157.831155)
			(xy 247.466631 -157.821656) (xy 247.474232 -157.813502) (xy 247.49252 -157.791658) (xy 247.526048 -157.751272)
			(xy 247.528906 -157.747227) (xy 247.533134 -157.738272) (xy 247.53443 -157.733492) (xy 247.535192 -157.729936)
			(xy 247.535192 -157.71495) (xy 247.53443 -157.710886) (xy 247.531954 -157.694874) (xy 247.529413 -157.662572)
			(xy 247.52935 -157.64637) (xy 247.52935 -157.640528) (xy 247.530335 -157.610455) (xy 247.540597 -157.55117)
			(xy 247.560021 -157.494225) (xy 247.588128 -157.441026) (xy 247.624223 -157.392889) (xy 247.645428 -157.371542)
			(xy 247.652794 -157.36443) (xy 247.664224 -157.33776) (xy 247.664224 -157.337506) (xy 247.666764 -157.331918)
			(xy 247.668288 -157.325314) (xy 247.668288 -157.324806) (xy 247.66905 -157.316932) (xy 247.66905 -157.263592)
			(xy 247.668288 -157.255718) (xy 247.668288 -157.25521) (xy 247.666764 -157.24886) (xy 247.666002 -157.247082)
			(xy 247.664986 -157.244542) (xy 247.664224 -157.243018) (xy 247.652794 -157.216094) (xy 247.645428 -157.208982)
			(xy 247.627422 -157.190913) (xy 247.595871 -157.150831) (xy 247.569928 -157.10691) (xy 247.550055 -157.059929)
			(xy 247.536604 -157.010724) (xy 247.529814 -156.960167) (xy 247.52935 -156.934662) (xy 247.529836 -156.907411)
			(xy 247.537592 -156.853463) (xy 247.552947 -156.801168) (xy 247.575589 -156.751591) (xy 247.605055 -156.705741)
			(xy 247.640746 -156.66455) (xy 247.681937 -156.628859) (xy 247.727787 -156.599393) (xy 247.777364 -156.576751)
			(xy 247.829659 -156.561396) (xy 247.883607 -156.55364) (xy 247.938109 -156.55364) (xy 247.992057 -156.561396)
			(xy 248.044352 -156.576751) (xy 248.093929 -156.599393) (xy 248.139779 -156.628859) (xy 248.18097 -156.66455)
			(xy 248.216661 -156.705741) (xy 248.246127 -156.751591) (xy 248.268769 -156.801168) (xy 248.284124 -156.853463)
			(xy 248.29188 -156.907411) (xy 248.292366 -156.934662) (xy 248.291945 -156.96017) (xy 248.285161 -157.010732)
			(xy 248.271708 -157.059942) (xy 248.251827 -157.106923) (xy 248.22587 -157.150841) (xy 248.194299 -157.190915)
			(xy 248.176288 -157.208982) (xy 248.168922 -157.216094) (xy 248.157492 -157.242764) (xy 248.157492 -157.243018)
			(xy 248.154952 -157.248606) (xy 248.153428 -157.25521) (xy 248.153428 -157.255718) (xy 248.152666 -157.263592)
			(xy 248.152666 -157.316932) (xy 248.153428 -157.324806) (xy 248.153428 -157.325314) (xy 248.154952 -157.331664)
			(xy 248.155714 -157.333442) (xy 248.15673 -157.335982) (xy 248.157492 -157.337506) (xy 248.168922 -157.36443)
			(xy 248.176288 -157.371542) (xy 248.197495 -157.392886) (xy 248.233595 -157.441021) (xy 248.261701 -157.49422)
			(xy 248.281121 -157.551168) (xy 248.291372 -157.610455) (xy 248.292366 -157.640528) (xy 248.292366 -157.645862)
			(xy 248.292226 -157.661555) (xy 248.28968 -157.692836) (xy 248.287286 -157.708346) (xy 248.286524 -157.71241)
			(xy 248.286524 -157.712664) (xy 248.285757 -157.717863) (xy 248.286136 -157.728364) (xy 248.287286 -157.733492)
			(xy 248.289826 -157.741112) (xy 248.29135 -157.744414) (xy 248.292874 -157.747208) (xy 248.294906 -157.750256)
			(xy 248.303796 -157.761178) (xy 248.304304 -157.761686) (xy 248.344436 -157.809946) (xy 248.348754 -157.815026)
			(xy 248.356294 -157.822547) (xy 248.375713 -157.831229) (xy 248.386346 -157.83179) (xy 249.590306 -157.83179)
			(xy 249.600164 -157.831277) (xy 249.618395 -157.823753) (xy 249.63246 -157.809928) (xy 249.636788 -157.801056)
			(xy 249.671078 -157.705552) (xy 249.673396 -157.696498) (xy 249.67205 -157.677873) (xy 249.664093 -157.660981)
			(xy 249.657616 -157.654244) (xy 249.654568 -157.651704) (xy 249.633096 -157.633475) (xy 249.595228 -157.591779)
			(xy 249.563898 -157.544972) (xy 249.539785 -157.49407) (xy 249.523413 -157.440178) (xy 249.515137 -157.384464)
			(xy 249.514614 -157.356302) (xy 249.515038 -157.330795) (xy 249.521826 -157.280235) (xy 249.535281 -157.231028)
			(xy 249.555165 -157.184049) (xy 249.581124 -157.140133) (xy 249.612695 -157.100063) (xy 249.630692 -157.081982)
			(xy 249.638058 -157.07487) (xy 249.649488 -157.0482) (xy 249.649488 -157.047946) (xy 249.652028 -157.042358)
			(xy 249.653552 -157.035754) (xy 249.653552 -157.035246) (xy 249.654314 -157.027372) (xy 249.654314 -156.974032)
			(xy 249.654153 -156.968799) (xy 249.651969 -156.958562) (xy 249.649996 -156.953712) (xy 249.638312 -156.926788)
			(xy 249.630946 -156.919676) (xy 249.611249 -156.89995) (xy 249.577209 -156.855807) (xy 249.549952 -156.807182)
			(xy 249.530058 -156.755109) (xy 249.51795 -156.700696) (xy 249.513885 -156.645101) (xy 249.517949 -156.589506)
			(xy 249.530057 -156.535094) (xy 249.549951 -156.483021) (xy 249.577208 -156.434396) (xy 249.611247 -156.390252)
			(xy 249.630946 -156.370528) (xy 249.638312 -156.363416) (xy 249.649996 -156.336492) (xy 249.652002 -156.331653)
			(xy 249.654188 -156.321409) (xy 249.654314 -156.316172) (xy 249.654314 -156.262832) (xy 249.653552 -156.254958)
			(xy 249.653552 -156.25445) (xy 249.652028 -156.2481) (xy 249.651266 -156.246322) (xy 249.65025 -156.243782)
			(xy 249.649488 -156.242258) (xy 249.638058 -156.215334) (xy 249.630692 -156.208222) (xy 249.612682 -156.190155)
			(xy 249.581121 -156.150076) (xy 249.555169 -156.106156) (xy 249.535287 -156.059175) (xy 249.521829 -156.009968)
			(xy 249.515033 -155.959409) (xy 249.514614 -155.933902) (xy 249.5151 -155.906651) (xy 249.522856 -155.852703)
			(xy 249.538211 -155.800408) (xy 249.560853 -155.750831) (xy 249.590319 -155.704981) (xy 249.62601 -155.66379)
			(xy 249.667201 -155.628099) (xy 249.713051 -155.598633) (xy 249.762628 -155.575991) (xy 249.814923 -155.560636)
			(xy 249.868871 -155.55288) (xy 249.923373 -155.55288) (xy 249.977321 -155.560636) (xy 250.029616 -155.575991)
			(xy 250.079193 -155.598633) (xy 250.125043 -155.628099) (xy 250.166234 -155.66379) (xy 250.201925 -155.704981)
			(xy 250.231391 -155.750831) (xy 250.254033 -155.800408) (xy 250.269388 -155.852703) (xy 250.277144 -155.906651)
			(xy 250.27763 -155.933902) (xy 250.277206 -155.959409) (xy 250.270418 -156.00997) (xy 250.256963 -156.059177)
			(xy 250.237081 -156.106158) (xy 250.211124 -156.150075) (xy 250.179555 -156.190148) (xy 250.161552 -156.208222)
			(xy 250.154186 -156.215334) (xy 250.142756 -156.242004) (xy 250.142756 -156.242258) (xy 250.140216 -156.247846)
			(xy 250.138692 -156.25445) (xy 250.138692 -156.254958) (xy 250.13793 -156.262832) (xy 250.13793 -156.316172)
			(xy 250.138091 -156.321405) (xy 250.140273 -156.331643) (xy 250.142248 -156.336492) (xy 250.153932 -156.363416)
			(xy 250.161298 -156.370528) (xy 250.180993 -156.390255) (xy 250.215028 -156.4344) (xy 250.242281 -156.483025)
			(xy 250.262172 -156.535097) (xy 250.274279 -156.589508) (xy 250.278343 -156.645101) (xy 250.274279 -156.700695)
			(xy 250.262172 -156.755106) (xy 250.24228 -156.807178) (xy 250.215027 -156.855803) (xy 250.180991 -156.899947)
			(xy 250.161298 -156.919676) (xy 250.153932 -156.926788) (xy 250.142248 -156.953712) (xy 250.14024 -156.958551)
			(xy 250.138054 -156.968795) (xy 250.13793 -156.974032) (xy 250.13793 -157.027372) (xy 250.138692 -157.035246)
			(xy 250.138692 -157.035754) (xy 250.140216 -157.042104) (xy 250.140978 -157.043882) (xy 250.141994 -157.046422)
			(xy 250.142756 -157.047946) (xy 250.154186 -157.07487) (xy 250.161552 -157.081982) (xy 250.181604 -157.102173)
			(xy 250.216114 -157.147418) (xy 250.243538 -157.197278) (xy 250.263271 -157.25065) (xy 250.274877 -157.306358)
			(xy 250.278101 -157.36317) (xy 250.272871 -157.419833) (xy 250.259302 -157.475095) (xy 250.237695 -157.527737)
			(xy 250.208525 -157.576596) (xy 250.172438 -157.620593) (xy 250.151646 -157.64002) (xy 250.151138 -157.640528)
			(xy 250.137676 -157.651704) (xy 250.134628 -157.654244) (xy 250.128184 -157.661005) (xy 250.120238 -157.67789)
			(xy 250.118866 -157.6965) (xy 250.121166 -157.705552) (xy 250.155456 -157.801056) (xy 250.159769 -157.809938)
			(xy 250.173826 -157.823777) (xy 250.192076 -157.831265) (xy 250.201938 -157.83179) (xy 252.59284 -157.83179)
			(xy 252.602487 -157.831372) (xy 252.620401 -157.824212) (xy 252.634361 -157.810897) (xy 252.638814 -157.802326)
			(xy 252.650498 -157.777434) (xy 252.678438 -157.71749) (xy 252.681502 -157.709431) (xy 252.682581 -157.692234)
			(xy 252.677846 -157.675667) (xy 252.673104 -157.668468) (xy 252.672596 -157.66796) (xy 252.67031 -157.665166)
			(xy 252.670056 -157.664912) (xy 252.653145 -157.644167) (xy 252.624688 -157.598837) (xy 252.602842 -157.549977)
			(xy 252.588037 -157.498544) (xy 252.580562 -157.445547) (xy 252.58014 -157.418786) (xy 252.58014 -157.418532)
			(xy 252.581156 -157.388814) (xy 252.582934 -157.373574) (xy 252.586115 -157.349787) (xy 252.597693 -157.303212)
			(xy 252.615023 -157.258458) (xy 252.626114 -157.237176) (xy 252.640368 -157.211909) (xy 252.675322 -157.165612)
			(xy 252.69571 -157.144974) (xy 252.696218 -157.144466) (xy 252.697234 -157.14345) (xy 252.700554 -157.139924)
			(xy 252.705934 -157.131873) (xy 252.707902 -157.127448) (xy 252.715268 -157.11043) (xy 252.718062 -157.10408)
			(xy 252.719078 -157.099254) (xy 252.720094 -157.089856) (xy 252.720094 -157.036262) (xy 252.719936 -157.031028)
			(xy 252.717757 -157.020789) (xy 252.715776 -157.015942) (xy 252.704092 -156.989018) (xy 252.696726 -156.981906)
			(xy 252.677028 -156.962179) (xy 252.642985 -156.918035) (xy 252.615726 -156.869408) (xy 252.595829 -156.817334)
			(xy 252.583717 -156.76292) (xy 252.579649 -156.707322) (xy 252.583711 -156.651724) (xy 252.595816 -156.597309)
			(xy 252.615707 -156.545232) (xy 252.642961 -156.496602) (xy 252.676998 -156.452454) (xy 252.696726 -156.432758)
			(xy 252.704092 -156.425646) (xy 252.715776 -156.398722) (xy 252.717776 -156.393882) (xy 252.719948 -156.383638)
			(xy 252.720094 -156.378402) (xy 252.720094 -156.321252) (xy 252.717808 -156.309822) (xy 252.715522 -156.304488)
			(xy 252.715268 -156.304234) (xy 252.707902 -156.287216) (xy 252.705933 -156.282791) (xy 252.70056 -156.274734)
			(xy 252.697234 -156.271214) (xy 252.696472 -156.270452) (xy 252.678461 -156.252385) (xy 252.646898 -156.212306)
			(xy 252.620945 -156.168386) (xy 252.601061 -156.121406) (xy 252.587599 -156.072199) (xy 252.580799 -156.021639)
			(xy 252.580394 -155.996132) (xy 252.58088 -155.968881) (xy 252.588636 -155.914933) (xy 252.603991 -155.862638)
			(xy 252.626633 -155.813061) (xy 252.656099 -155.767211) (xy 252.69179 -155.72602) (xy 252.732981 -155.690329)
			(xy 252.778831 -155.660863) (xy 252.828408 -155.638221) (xy 252.880703 -155.622866) (xy 252.934651 -155.61511)
			(xy 252.989153 -155.61511) (xy 253.043101 -155.622866) (xy 253.095396 -155.638221) (xy 253.144973 -155.660863)
			(xy 253.190823 -155.690329) (xy 253.232014 -155.72602) (xy 253.267705 -155.767211) (xy 253.297171 -155.813061)
			(xy 253.319813 -155.862638) (xy 253.335168 -155.914933) (xy 253.342924 -155.968881) (xy 253.34341 -155.996132)
			(xy 253.342994 -156.02158) (xy 253.336245 -156.072027) (xy 253.322856 -156.121131) (xy 253.303066 -156.168022)
			(xy 253.277224 -156.21187) (xy 253.245788 -156.251899) (xy 253.22784 -156.269944) (xy 253.22657 -156.271214)
			(xy 253.22337 -156.274581) (xy 253.218128 -156.282248) (xy 253.216156 -156.286454) (xy 253.215902 -156.286962)
			(xy 253.215902 -156.287216) (xy 253.208536 -156.304234) (xy 253.205742 -156.310584) (xy 253.204726 -156.31541)
			(xy 253.20371 -156.324808) (xy 253.20371 -156.378402) (xy 253.203865 -156.383636) (xy 253.206037 -156.393879)
			(xy 253.208028 -156.398722) (xy 253.219712 -156.425646) (xy 253.227078 -156.432758) (xy 253.246771 -156.452485)
			(xy 253.280804 -156.496628) (xy 253.308055 -156.545252) (xy 253.327943 -156.597322) (xy 253.340046 -156.651731)
			(xy 253.344108 -156.707322) (xy 253.34004 -156.762913) (xy 253.32793 -156.817321) (xy 253.308036 -156.869389)
			(xy 253.28078 -156.918009) (xy 253.246742 -156.962149) (xy 253.227078 -156.981906) (xy 253.219712 -156.989018)
			(xy 253.208028 -157.015942) (xy 253.206024 -157.020782) (xy 253.203845 -157.031026) (xy 253.20371 -157.036262)
			(xy 253.20371 -157.093412) (xy 253.205996 -157.104842) (xy 253.208282 -157.110176) (xy 253.208536 -157.11043)
			(xy 253.215902 -157.127448) (xy 253.216156 -157.127956) (xy 253.216918 -157.129734) (xy 253.218727 -157.133343)
			(xy 253.22332 -157.13998) (xy 253.226062 -157.142942) (xy 253.228602 -157.145228) (xy 253.235667 -157.151085)
			(xy 253.252717 -157.157842) (xy 253.261876 -157.158436) (xy 253.295658 -157.159198) (xy 253.303495 -157.158562)
			(xy 253.318247 -157.153142) (xy 253.324614 -157.14853) (xy 253.327154 -157.146244) (xy 253.329186 -157.144466)
			(xy 253.738126 -156.735526) (xy 253.76169 -156.712628) (xy 253.813074 -156.671674) (xy 253.868717 -156.636726)
			(xy 253.92792 -156.608222) (xy 253.98994 -156.586521) (xy 254.053999 -156.571894) (xy 254.119292 -156.564526)
			(xy 254.152146 -156.564076) (xy 258.428236 -156.564076) (xy 258.436427 -156.563761) (xy 258.451965 -156.558568)
			(xy 258.458716 -156.553916) (xy 258.464304 -156.54909) (xy 266.50569 -148.507704) (xy 266.510516 -148.502116)
			(xy 266.515191 -148.495378) (xy 266.520387 -148.479831) (xy 266.520676 -148.471636) (xy 266.520676 -140.563346)
			(xy 266.521134 -140.530491) (xy 266.528485 -140.465194) (xy 266.543101 -140.401131) (xy 266.564798 -140.339107)
			(xy 266.593302 -140.279902) (xy 266.628255 -140.22426) (xy 266.669219 -140.172882) (xy 266.692126 -140.149326)
			(xy 268.774926 -138.066526) (xy 268.79849 -138.043628) (xy 268.849874 -138.002674) (xy 268.905517 -137.967726)
			(xy 268.96472 -137.939222) (xy 269.02674 -137.917521) (xy 269.090799 -137.902894) (xy 269.156092 -137.895526)
			(xy 269.188946 -137.895076) (xy 273.472148 -137.895076) (xy 273.479857 -137.894846) (xy 273.494594 -137.890321)
			(xy 273.501104 -137.886186) (xy 273.505168 -137.882884) (xy 275.709126 -135.678926) (xy 275.735219 -135.653606)
			(xy 275.792599 -135.608951) (xy 275.855068 -135.571748) (xy 275.921666 -135.54257) (xy 275.991364 -135.521867)
			(xy 276.027134 -135.51535) (xy 276.027388 -135.51535) (xy 276.035516 -135.513826) (xy 276.042374 -135.51027)
			(xy 276.045771 -135.5084) (xy 276.052025 -135.503814) (xy 276.05482 -135.501126) (xy 276.427438 -135.128508)
			(xy 276.432426 -135.123009) (xy 276.439274 -135.109844) (xy 276.4409 -135.1026) (xy 276.441916 -135.092948)
			(xy 276.441916 -119.470678) (xy 276.442344 -119.46061) (xy 276.450065 -119.442013) (xy 276.456902 -119.43461)
			(xy 276.740112 -119.1514) (xy 276.745102 -119.145902) (xy 276.751951 -119.132736) (xy 276.753574 -119.125492)
			(xy 276.75459 -119.11584) (xy 276.75459 -116.692426) (xy 276.753912 -116.68055) (xy 276.743201 -116.659341)
			(xy 276.734016 -116.651786) (xy 276.668484 -116.603272) (xy 276.663731 -116.599939) (xy 276.653081 -116.59533)
			(xy 276.647402 -116.594128) (xy 276.635464 -116.591842) (xy 276.62378 -116.595398) (xy 276.57982 -116.608063)
			(xy 276.490067 -116.625797) (xy 276.399014 -116.634719) (xy 276.35327 -116.635276) (xy 276.352508 -116.635276)
			(xy 276.309059 -116.63479) (xy 276.222531 -116.626773) (xy 276.137111 -116.610806) (xy 276.05353 -116.587025)
			(xy 275.972499 -116.555635) (xy 275.89471 -116.516901) (xy 275.820827 -116.471155) (xy 275.751481 -116.418787)
			(xy 275.687261 -116.360244) (xy 275.628718 -116.296026) (xy 275.576349 -116.226679) (xy 275.530603 -116.152797)
			(xy 275.491869 -116.075008) (xy 275.460477 -115.993978) (xy 275.436696 -115.910396) (xy 275.420728 -115.824977)
			(xy 275.41271 -115.738449) (xy 275.41271 -115.651551) (xy 275.420728 -115.565023) (xy 275.436696 -115.479604)
			(xy 275.460477 -115.396022) (xy 275.491869 -115.314992) (xy 275.530603 -115.237203) (xy 275.576349 -115.163321)
			(xy 275.628718 -115.093974) (xy 275.687261 -115.029756) (xy 275.751481 -114.971213) (xy 275.820827 -114.918845)
			(xy 275.89471 -114.873099) (xy 275.972499 -114.834365) (xy 276.05353 -114.802975) (xy 276.137111 -114.779194)
			(xy 276.222531 -114.763227) (xy 276.309059 -114.75521) (xy 276.352508 -114.75466) (xy 276.35327 -114.75466)
			(xy 276.399013 -114.755232) (xy 276.490064 -114.764161) (xy 276.579819 -114.781881) (xy 276.62378 -114.794538)
			(xy 276.629622 -114.796316) (xy 276.64156 -114.797078) (xy 276.647402 -114.795808) (xy 276.65308 -114.794604)
			(xy 276.66373 -114.789993) (xy 276.668484 -114.786664) (xy 276.734016 -114.73815) (xy 276.743207 -114.730591)
			(xy 276.75395 -114.709392) (xy 276.75459 -114.69751) (xy 276.75459 -95.684086) (xy 276.754427 -95.678075)
			(xy 276.75161 -95.666389) (xy 276.749002 -95.660972) (xy 276.747162 -95.657498) (xy 276.742568 -95.65112)
			(xy 276.739858 -95.648272) (xy 276.7076 -95.616014) (xy 276.684656 -95.592459) (xy 276.643639 -95.541058)
			(xy 276.60864 -95.485387) (xy 276.580097 -95.426144) (xy 276.558372 -95.364077) (xy 276.543737 -95.299966)
			(xy 276.536376 -95.23462) (xy 276.535896 -95.20174) (xy 276.535896 -95.201486) (xy 276.536442 -95.166195)
			(xy 276.544957 -95.096127) (xy 276.561825 -95.027589) (xy 276.586802 -94.961573) (xy 276.619527 -94.899034)
			(xy 276.659526 -94.840879) (xy 276.70622 -94.787948) (xy 276.732238 -94.764098) (xy 276.737064 -94.759526)
			(xy 276.749764 -94.73184) (xy 276.751972 -94.726782) (xy 276.754403 -94.71602) (xy 276.75459 -94.710504)
			(xy 276.75459 -79.682086) (xy 276.754427 -79.676075) (xy 276.75161 -79.664389) (xy 276.749002 -79.658972)
			(xy 276.747162 -79.655498) (xy 276.742568 -79.64912) (xy 276.739858 -79.646272) (xy 276.441916 -79.34833)
			(xy 276.441747 -79.342321) (xy 276.438919 -79.33064) (xy 276.436328 -79.325216) (xy 276.434491 -79.32174)
			(xy 276.429903 -79.315356) (xy 276.427184 -79.312516) (xy 273.767804 -76.653136) (xy 273.764953 -76.65043)
			(xy 273.758575 -76.645836) (xy 273.755104 -76.643992) (xy 273.749676 -76.641415) (xy 273.737996 -76.638604)
			(xy 273.73199 -76.638404) (xy 273.304 -76.638404) (xy 273.270845 -76.63794) (xy 273.204951 -76.63052)
			(xy 273.140302 -76.615774) (xy 273.077708 -76.593886) (xy 273.017957 -76.565131) (xy 272.961799 -76.529872)
			(xy 272.909939 -76.488549) (xy 272.88617 -76.46543) (xy 271.349216 -74.928476) (xy 271.346367 -74.925768)
			(xy 271.339991 -74.92117) (xy 271.336516 -74.919332) (xy 271.331089 -74.916752) (xy 271.319409 -74.913936)
			(xy 271.313402 -74.913744) (xy 264.090404 -74.913744) (xy 264.08399 -74.916525) (xy 264.0729 -74.925028)
			(xy 264.06856 -74.930508) (xy 264.06729 -74.932286) (xy 264.019792 -75.001628) (xy 264.017206 -75.005613)
			(xy 264.013377 -75.014305) (xy 264.012172 -75.0189) (xy 264.014204 -75.023726) (xy 264.025834 -75.05157)
			(xy 264.044014 -75.109114) (xy 264.056226 -75.168212) (xy 264.062343 -75.228248) (xy 264.062718 -75.258422)
			(xy 264.062718 -75.258676) (xy 264.062198 -75.294528) (xy 264.053531 -75.365705) (xy 264.036309 -75.43531)
			(xy 264.010785 -75.502317) (xy 263.977336 -75.56574) (xy 263.957308 -75.59548) (xy 263.957997 -75.60426)
			(xy 263.964496 -75.620615) (xy 263.970008 -75.627484) (xy 263.988775 -75.649545) (xy 264.02042 -75.698054)
			(xy 264.04475 -75.750615) (xy 264.061256 -75.806132) (xy 264.069596 -75.863447) (xy 264.070084 -75.892406)
			(xy 264.069573 -75.921036) (xy 264.061424 -75.977714) (xy 264.045292 -76.032654) (xy 264.021506 -76.08474)
			(xy 263.990548 -76.132911) (xy 263.953051 -76.176185) (xy 263.909777 -76.213682) (xy 263.861606 -76.24464)
			(xy 263.80952 -76.268426) (xy 263.803805 -76.270104) (xy 264.157966 -76.270104) (xy 264.162037 -76.214482)
			(xy 264.174163 -76.160045) (xy 264.194086 -76.107954) (xy 264.221382 -76.059319) (xy 264.255468 -76.015176)
			(xy 264.295617 -75.976467) (xy 264.340975 -75.944016) (xy 264.390575 -75.918515) (xy 264.443359 -75.900508)
			(xy 264.498202 -75.890378) (xy 264.553936 -75.888341) (xy 264.609373 -75.894441) (xy 264.66333 -75.908547)
			(xy 264.714659 -75.930359) (xy 264.762265 -75.959413) (xy 264.805133 -75.995088) (xy 264.84235 -76.036625)
			(xy 264.873123 -76.083138) (xy 264.896795 -76.133635) (xy 264.912863 -76.187042) (xy 264.920983 -76.242218)
			(xy 264.921492 -76.270104) (xy 264.920983 -76.29799) (xy 264.912863 -76.353166) (xy 264.896795 -76.406573)
			(xy 264.873123 -76.45707) (xy 264.84235 -76.503583) (xy 264.805133 -76.54512) (xy 264.762265 -76.580795)
			(xy 264.714659 -76.609849) (xy 264.66333 -76.631661) (xy 264.609373 -76.645767) (xy 264.553936 -76.651867)
			(xy 264.498202 -76.64983) (xy 264.443359 -76.6397) (xy 264.390575 -76.621693) (xy 264.340975 -76.596192)
			(xy 264.295617 -76.563741) (xy 264.255468 -76.525032) (xy 264.221382 -76.480889) (xy 264.194086 -76.432254)
			(xy 264.174163 -76.380163) (xy 264.162037 -76.325726) (xy 264.157966 -76.270104) (xy 263.803805 -76.270104)
			(xy 263.75458 -76.284558) (xy 263.697902 -76.292707) (xy 263.640642 -76.292707) (xy 263.583964 -76.284558)
			(xy 263.529024 -76.268426) (xy 263.476938 -76.24464) (xy 263.428767 -76.213682) (xy 263.385493 -76.176185)
			(xy 263.347996 -76.132911) (xy 263.317038 -76.08474) (xy 263.293252 -76.032654) (xy 263.27712 -75.977714)
			(xy 263.268971 -75.921036) (xy 263.26846 -75.892406) (xy 263.26846 -75.891898) (xy 263.268559 -75.880186)
			(xy 263.269957 -75.856803) (xy 263.271254 -75.845162) (xy 263.271891 -75.836457) (xy 263.267987 -75.819455)
			(xy 263.263634 -75.811888) (xy 263.236344 -75.801219) (xy 263.183822 -75.775231) (xy 263.134128 -75.744177)
			(xy 263.110726 -75.726544) (xy 263.107343 -75.724058) (xy 263.099941 -75.7201) (xy 263.095994 -75.71867)
			(xy 263.089136 -75.716384) (xy 262.998966 -75.716384) (xy 262.998712 -75.716384) (xy 262.990585 -75.716728)
			(xy 262.975176 -75.721916) (xy 262.968486 -75.726544) (xy 262.968232 -75.726798) (xy 262.944972 -75.744303)
			(xy 262.895606 -75.775161) (xy 262.843446 -75.801017) (xy 262.81634 -75.811634) (xy 262.813732 -75.815859)
			(xy 262.81003 -75.82507) (xy 262.808974 -75.829922) (xy 262.808212 -75.841352) (xy 262.809662 -75.853874)
			(xy 262.811188 -75.879038) (xy 262.81126 -75.891644) (xy 262.81126 -75.892406) (xy 262.810749 -75.921036)
			(xy 262.8026 -75.977714) (xy 262.786468 -76.032654) (xy 262.762682 -76.08474) (xy 262.731724 -76.132911)
			(xy 262.694227 -76.176185) (xy 262.650953 -76.213682) (xy 262.602782 -76.24464) (xy 262.550696 -76.268426)
			(xy 262.495756 -76.284558) (xy 262.439078 -76.292707) (xy 262.381818 -76.292707) (xy 262.32514 -76.284558)
			(xy 262.2702 -76.268426) (xy 262.218114 -76.24464) (xy 262.169943 -76.213682) (xy 262.126669 -76.176185)
			(xy 262.089172 -76.132911) (xy 262.058214 -76.08474) (xy 262.034428 -76.032654) (xy 262.018296 -75.977714)
			(xy 262.010147 -75.921036) (xy 262.009636 -75.892406) (xy 262.010171 -75.863452) (xy 262.018543 -75.806152)
			(xy 262.035057 -75.750648) (xy 262.059371 -75.69809) (xy 262.09098 -75.649569) (xy 262.109712 -75.627484)
			(xy 262.11527 -75.620571) (xy 262.12175 -75.604073) (xy 262.122412 -75.595226) (xy 262.102467 -75.565532)
			(xy 262.069121 -75.502247) (xy 262.043669 -75.435395) (xy 262.026483 -75.365957) (xy 262.017815 -75.29495)
			(xy 262.017256 -75.259184) (xy 262.017256 -75.258422) (xy 262.017724 -75.225268) (xy 262.025151 -75.159379)
			(xy 262.039904 -75.094733) (xy 262.061797 -75.032145) (xy 262.090555 -74.972398) (xy 262.125818 -74.916245)
			(xy 262.167141 -74.864389) (xy 262.19023 -74.840592) (xy 262.29564 -74.734928) (xy 262.299871 -74.729647)
			(xy 262.305654 -74.717416) (xy 262.30707 -74.710798) (xy 262.307832 -74.701908) (xy 262.307832 -74.617072)
			(xy 262.307992 -74.599438) (xy 262.310151 -74.564235) (xy 262.31215 -74.546714) (xy 262.313768 -74.534003)
			(xy 262.317961 -74.508721) (xy 262.320532 -74.496168) (xy 262.32104 -74.490326) (xy 262.32104 -74.490072)
			(xy 262.322935 -74.453773) (xy 262.334629 -74.382032) (xy 262.35516 -74.312304) (xy 262.38421 -74.245673)
			(xy 262.421326 -74.183176) (xy 262.465931 -74.125783) (xy 262.49122 -74.099674) (xy 262.948674 -73.64222)
			(xy 262.972655 -73.618883) (xy 263.025072 -73.577285) (xy 263.081916 -73.541976) (xy 263.142436 -73.513423)
			(xy 263.205832 -73.492003) (xy 263.271268 -73.477998) (xy 263.304528 -73.474326) (xy 263.313164 -73.472548)
			(xy 263.313672 -73.472548) (xy 263.35292 -73.46213) (xy 263.433345 -73.450917) (xy 263.473946 -73.450196)
			(xy 268.742414 -73.450196) (xy 268.750607 -73.449884) (xy 268.76615 -73.444699) (xy 268.772894 -73.440036)
			(xy 268.778482 -73.43521) (xy 268.976602 -73.23709) (xy 268.981591 -73.231592) (xy 268.988439 -73.218426)
			(xy 268.990064 -73.211182) (xy 268.99108 -73.20153) (xy 268.99108 -72.535796) (xy 268.990906 -72.529788)
			(xy 268.98807 -72.518112) (xy 268.985492 -72.512682) (xy 268.983652 -72.509208) (xy 268.979058 -72.50283)
			(xy 268.976348 -72.499982) (xy 268.129258 -71.652892) (xy 268.126404 -71.65019) (xy 268.120022 -71.645605)
			(xy 268.116558 -71.643748) (xy 268.111132 -71.641163) (xy 268.099452 -71.638336) (xy 268.093444 -71.63816)
			(xy 255.271778 -71.63816) (xy 255.260094 -71.639684) (xy 255.237996 -71.646288) (xy 255.232154 -71.649844)
			(xy 255.209446 -71.663363) (xy 255.161094 -71.684696) (xy 255.11026 -71.699149) (xy 255.057918 -71.706445)
			(xy 255.00507 -71.706445) (xy 254.952728 -71.699149) (xy 254.901894 -71.684696) (xy 254.853542 -71.663363)
			(xy 254.830834 -71.649844) (xy 254.824992 -71.646288) (xy 254.802894 -71.639684) (xy 254.79121 -71.63816)
			(xy 253.712726 -71.63816) (xy 253.703704 -71.638566) (xy 253.686802 -71.644899) (xy 253.673134 -71.656685)
			(xy 253.664384 -71.672471) (xy 253.662688 -71.68134) (xy 253.658111 -71.708031) (xy 253.642409 -71.759858)
			(xy 253.619537 -71.808944) (xy 253.589956 -71.854304) (xy 253.554259 -71.895026) (xy 253.513164 -71.930294)
			(xy 253.467496 -71.959397) (xy 253.418173 -71.981752) (xy 253.366184 -71.996909) (xy 253.312575 -72.004565)
			(xy 253.258421 -72.004565) (xy 253.204812 -71.996909) (xy 253.152823 -71.981752) (xy 253.1035 -71.959397)
			(xy 253.057832 -71.930294) (xy 253.016737 -71.895026) (xy 252.98104 -71.854304) (xy 252.951459 -71.808944)
			(xy 252.928587 -71.759858) (xy 252.912885 -71.708031) (xy 252.908308 -71.68134) (xy 252.906605 -71.672465)
			(xy 252.897884 -71.65665) (xy 252.884215 -71.644845) (xy 252.867299 -71.638519) (xy 252.85827 -71.63816)
			(xy 252.18771 -71.63816) (xy 252.177043 -71.638712) (xy 252.157551 -71.647386) (xy 252.143272 -71.663238)
			(xy 252.13945 -71.673212) (xy 252.130275 -71.69993) (xy 252.105162 -71.750529) (xy 252.07286 -71.796871)
			(xy 252.034078 -71.837943) (xy 251.989663 -71.872847) (xy 251.940586 -71.900819) (xy 251.88792 -71.921248)
			(xy 251.832818 -71.933686) (xy 251.776484 -71.937863) (xy 251.72015 -71.933686) (xy 251.665048 -71.921248)
			(xy 251.612382 -71.900819) (xy 251.563305 -71.872847) (xy 251.51889 -71.837943) (xy 251.480108 -71.796871)
			(xy 251.447806 -71.750529) (xy 251.422693 -71.69993) (xy 251.413518 -71.673212) (xy 251.410978 -71.665338)
			(xy 251.40158 -71.652638) (xy 251.394976 -71.647812) (xy 251.388343 -71.643414) (xy 251.37321 -71.638516)
			(xy 251.365258 -71.63816) (xy 239.973866 -71.63816) (xy 239.9665 -71.638668) (xy 239.96072 -71.639714)
			(xy 239.949818 -71.644077) (xy 239.94491 -71.647304) (xy 239.938814 -71.651622) (xy 239.934242 -71.657464)
			(xy 239.93197 -71.660576) (xy 239.928271 -71.667334) (xy 239.926876 -71.670926) (xy 239.915332 -71.700638)
			(xy 239.883801 -71.75603) (xy 239.843501 -71.80541) (xy 239.819942 -71.826882) (xy 239.798192 -71.845227)
			(xy 239.750296 -71.875937) (xy 239.698371 -71.899198) (xy 239.643569 -71.914493) (xy 239.587103 -71.921484)
			(xy 239.530226 -71.920016) (xy 239.474196 -71.910121) (xy 239.420256 -71.892019) (xy 239.369601 -71.866111)
			(xy 239.323352 -71.832971) (xy 239.282535 -71.793332) (xy 239.248054 -71.748074) (xy 239.220673 -71.698199)
			(xy 239.210342 -71.671688) (xy 239.210342 -71.671434) (xy 239.210088 -71.670672) (xy 239.207075 -71.663653)
			(xy 239.197645 -71.651649) (xy 239.191546 -71.64705) (xy 239.18545 -71.642732) (xy 239.178084 -71.640446)
			(xy 239.174427 -71.63939) (xy 239.166903 -71.638236) (xy 239.163098 -71.63816) (xy 217.29573 -71.63816)
			(xy 217.287988 -71.638518) (xy 217.273257 -71.64331) (xy 217.266774 -71.647558) (xy 217.266266 -71.647558)
			(xy 217.263361 -71.649698) (xy 217.258129 -71.654666) (xy 217.255852 -71.657464) (xy 217.240747 -71.680216)
			(xy 217.205063 -71.721556) (xy 217.163847 -71.757384) (xy 217.117943 -71.786967) (xy 217.068289 -71.8097)
			(xy 217.0159 -71.825119) (xy 216.961847 -71.832908) (xy 216.907237 -71.832908) (xy 216.853184 -71.825119)
			(xy 216.800795 -71.8097) (xy 216.751141 -71.786967) (xy 216.705237 -71.757384) (xy 216.664021 -71.721556)
			(xy 216.628337 -71.680216) (xy 216.613232 -71.657464) (xy 216.610944 -71.654676) (xy 216.605712 -71.649711)
			(xy 216.602818 -71.647558) (xy 216.60231 -71.647558) (xy 216.59584 -71.643284) (xy 216.5811 -71.638494)
			(xy 216.573354 -71.63816) (xy 215.612726 -71.63816) (xy 215.603704 -71.638566) (xy 215.586802 -71.644899)
			(xy 215.573134 -71.656685) (xy 215.564384 -71.672471) (xy 215.562688 -71.68134) (xy 215.558111 -71.708031)
			(xy 215.542409 -71.759858) (xy 215.519537 -71.808944) (xy 215.489956 -71.854304) (xy 215.454259 -71.895026)
			(xy 215.413164 -71.930294) (xy 215.367496 -71.959397) (xy 215.318173 -71.981752) (xy 215.266184 -71.996909)
			(xy 215.212575 -72.004565) (xy 215.158421 -72.004565) (xy 215.104812 -71.996909) (xy 215.052823 -71.981752)
			(xy 215.0035 -71.959397) (xy 214.957832 -71.930294) (xy 214.916737 -71.895026) (xy 214.88104 -71.854304)
			(xy 214.851459 -71.808944) (xy 214.828587 -71.759858) (xy 214.812885 -71.708031) (xy 214.808308 -71.68134)
			(xy 214.806605 -71.672465) (xy 214.797884 -71.65665) (xy 214.784215 -71.644845) (xy 214.767299 -71.638519)
			(xy 214.75827 -71.63816) (xy 214.08771 -71.63816) (xy 214.077043 -71.638712) (xy 214.057551 -71.647386)
			(xy 214.043272 -71.663238) (xy 214.03945 -71.673212) (xy 214.030275 -71.69993) (xy 214.005162 -71.750529)
			(xy 213.97286 -71.796871) (xy 213.934078 -71.837943) (xy 213.889663 -71.872847) (xy 213.840586 -71.900819)
			(xy 213.78792 -71.921248) (xy 213.732818 -71.933686) (xy 213.676484 -71.937863) (xy 213.62015 -71.933686)
			(xy 213.565048 -71.921248) (xy 213.512382 -71.900819) (xy 213.463305 -71.872847) (xy 213.41889 -71.837943)
			(xy 213.380108 -71.796871) (xy 213.347806 -71.750529) (xy 213.322693 -71.69993) (xy 213.313518 -71.673212)
			(xy 213.310978 -71.665338) (xy 213.30158 -71.652638) (xy 213.294976 -71.647812) (xy 213.288343 -71.643414)
			(xy 213.27321 -71.638516) (xy 213.265258 -71.63816) (xy 204.889608 -71.63816) (xy 204.886758 -71.635453)
			(xy 204.880381 -71.630857) (xy 204.876908 -71.629016) (xy 204.87148 -71.626437) (xy 204.859801 -71.623624)
			(xy 204.853794 -71.623428) (xy 198.304404 -71.623428) (xy 198.298396 -71.623601) (xy 198.286719 -71.626435)
			(xy 198.28129 -71.629016) (xy 198.277816 -71.630856) (xy 198.271437 -71.635449) (xy 198.26859 -71.63816)
			(xy 196.142298 -73.764452) (xy 199.903594 -73.764452) (xy 199.903594 -73.709953) (xy 199.91135 -73.656008)
			(xy 199.926703 -73.603717) (xy 199.949342 -73.554142) (xy 199.978806 -73.508294) (xy 200.014495 -73.467105)
			(xy 200.055682 -73.431415) (xy 200.101529 -73.401949) (xy 200.151103 -73.379308) (xy 200.203394 -73.363953)
			(xy 200.257338 -73.356195) (xy 200.284588 -73.355708) (xy 200.31075 -73.356724) (xy 200.311258 -73.356724)
			(xy 200.325147 -73.357193) (xy 200.352334 -73.351494) (xy 200.376977 -73.338674) (xy 200.39725 -73.319683)
			(xy 200.41165 -73.295928) (xy 200.41911 -73.269171) (xy 200.419077 -73.241392) (xy 200.411555 -73.214652)
			(xy 200.40473 -73.202546) (xy 200.391666 -73.180093) (xy 200.371055 -73.13241) (xy 200.357098 -73.082374)
			(xy 200.350052 -73.030907) (xy 200.349612 -73.004934) (xy 200.350019 -72.977678) (xy 200.357771 -72.923722)
			(xy 200.373124 -72.871417) (xy 200.395765 -72.82183) (xy 200.425232 -72.77597) (xy 200.460926 -72.734771)
			(xy 200.502119 -72.69907) (xy 200.547975 -72.669595) (xy 200.597558 -72.646947) (xy 200.64986 -72.631585)
			(xy 200.703815 -72.623823) (xy 200.758326 -72.623819) (xy 200.812283 -72.631572) (xy 200.864587 -72.646926)
			(xy 200.914174 -72.669567) (xy 200.960034 -72.699035) (xy 201.001233 -72.734729) (xy 201.036933 -72.775923)
			(xy 201.066407 -72.821779) (xy 201.089055 -72.871362) (xy 201.104416 -72.923664) (xy 201.112177 -72.97762)
			(xy 201.112181 -73.032131) (xy 201.104427 -73.086088) (xy 201.089072 -73.138392) (xy 201.066431 -73.187978)
			(xy 201.058539 -73.20026) (xy 210.556856 -73.20026) (xy 210.557344 -73.17289) (xy 210.565154 -73.118712)
			(xy 210.580637 -73.066208) (xy 210.603475 -73.016461) (xy 210.633196 -72.970494) (xy 210.650836 -72.949562)
			(xy 210.65109 -72.949308) (xy 210.656678 -72.942223) (xy 210.662924 -72.925305) (xy 210.663282 -72.916288)
			(xy 210.663282 -72.849232) (xy 210.662913 -72.840216) (xy 210.656674 -72.823299) (xy 210.65109 -72.816212)
			(xy 210.650836 -72.816212) (xy 210.650836 -72.815958) (xy 210.633216 -72.79501) (xy 210.6035 -72.749042)
			(xy 210.58066 -72.699299) (xy 210.565165 -72.646801) (xy 210.557332 -72.592628) (xy 210.556856 -72.56526)
			(xy 210.55734 -72.538009) (xy 210.565102 -72.484064) (xy 210.58046 -72.431771) (xy 210.603103 -72.382196)
			(xy 210.63257 -72.336348) (xy 210.668262 -72.295159) (xy 210.709451 -72.259468) (xy 210.755299 -72.230001)
			(xy 210.804875 -72.207358) (xy 210.857167 -72.192001) (xy 210.911113 -72.18424) (xy 210.938364 -72.183752)
			(xy 210.965734 -72.184226) (xy 211.019913 -72.19204) (xy 211.072417 -72.207527) (xy 211.122164 -72.230367)
			(xy 211.168131 -72.260091) (xy 211.189062 -72.277732) (xy 211.189316 -72.277986) (xy 211.196395 -72.283584)
			(xy 211.213318 -72.289824) (xy 211.222336 -72.290178) (xy 211.289392 -72.290178) (xy 211.298409 -72.289822)
			(xy 211.315326 -72.283574) (xy 211.322412 -72.277986) (xy 211.322412 -72.277732) (xy 211.322666 -72.277732)
			(xy 211.343604 -72.2601) (xy 211.389575 -72.230386) (xy 211.439321 -72.207548) (xy 211.49182 -72.192056)
			(xy 211.545995 -72.184226) (xy 211.573364 -72.183752) (xy 211.59968 -72.18416) (xy 211.651812 -72.191405)
			(xy 211.702456 -72.205734) (xy 211.750656 -72.226878) (xy 211.795497 -72.254435) (xy 211.836134 -72.287885)
			(xy 211.854288 -72.306942) (xy 211.86182 -72.314332) (xy 211.881092 -72.322865) (xy 211.891626 -72.323452)
			(xy 211.966302 -72.323452) (xy 211.976855 -72.322952) (xy 211.996151 -72.314398) (xy 212.00364 -72.306942)
			(xy 212.021772 -72.287863) (xy 212.062408 -72.25441) (xy 212.107254 -72.226856) (xy 212.155459 -72.205722)
			(xy 212.20611 -72.191409) (xy 212.258247 -72.184188) (xy 212.284564 -72.183752) (xy 212.311813 -72.184312)
			(xy 212.365755 -72.192062) (xy 212.418046 -72.207411) (xy 212.467621 -72.230045) (xy 212.513469 -72.259503)
			(xy 212.554659 -72.295187) (xy 212.558463 -72.299576) (xy 224.676968 -72.299576) (xy 224.681039 -72.243954)
			(xy 224.693165 -72.189517) (xy 224.713088 -72.137426) (xy 224.740384 -72.088791) (xy 224.77447 -72.044648)
			(xy 224.814619 -72.005939) (xy 224.859977 -71.973488) (xy 224.909577 -71.947987) (xy 224.962361 -71.92998)
			(xy 225.017204 -71.91985) (xy 225.072938 -71.917813) (xy 225.128375 -71.923913) (xy 225.182332 -71.938019)
			(xy 225.233661 -71.959831) (xy 225.281267 -71.988885) (xy 225.324135 -72.02456) (xy 225.361352 -72.066097)
			(xy 225.392125 -72.11261) (xy 225.415797 -72.163107) (xy 225.431865 -72.216514) (xy 225.439985 -72.27169)
			(xy 225.440494 -72.299576) (xy 225.439985 -72.327462) (xy 225.431865 -72.382638) (xy 225.415797 -72.436045)
			(xy 225.392125 -72.486542) (xy 225.361352 -72.533055) (xy 225.324135 -72.574592) (xy 225.281267 -72.610267)
			(xy 225.233661 -72.639321) (xy 225.182332 -72.661133) (xy 225.128375 -72.675239) (xy 225.072938 -72.681339)
			(xy 225.017204 -72.679302) (xy 224.962361 -72.669172) (xy 224.909577 -72.651165) (xy 224.859977 -72.625664)
			(xy 224.814619 -72.593213) (xy 224.77447 -72.554504) (xy 224.740384 -72.510361) (xy 224.713088 -72.461726)
			(xy 224.693165 -72.409635) (xy 224.681039 -72.355198) (xy 224.676968 -72.299576) (xy 212.558463 -72.299576)
			(xy 212.590351 -72.33637) (xy 212.619819 -72.382213) (xy 212.642463 -72.431782) (xy 212.657822 -72.48407)
			(xy 212.665583 -72.538012) (xy 212.666072 -72.56526) (xy 212.665589 -72.59263) (xy 212.657777 -72.646808)
			(xy 212.642292 -72.699312) (xy 212.619454 -72.749059) (xy 212.589732 -72.795026) (xy 212.572092 -72.815958)
			(xy 212.571838 -72.816212) (xy 212.566233 -72.823286) (xy 212.559999 -72.840213) (xy 212.559646 -72.849232)
			(xy 212.559646 -72.916288) (xy 212.559999 -72.925305) (xy 212.566248 -72.942223) (xy 212.571838 -72.949308)
			(xy 212.572092 -72.949308) (xy 212.572092 -72.949562) (xy 212.589725 -72.970499) (xy 212.619438 -73.01647)
			(xy 212.642276 -73.066216) (xy 212.657768 -73.118716) (xy 212.665597 -73.172891) (xy 212.666072 -73.20026)
			(xy 212.665607 -73.227513) (xy 212.657855 -73.281466) (xy 212.642502 -73.333766) (xy 212.619862 -73.383349)
			(xy 212.590394 -73.429204) (xy 212.554701 -73.470398) (xy 212.513507 -73.506092) (xy 212.467652 -73.53556)
			(xy 212.41807 -73.558201) (xy 212.36577 -73.573554) (xy 212.311817 -73.581307) (xy 212.284564 -73.581768)
			(xy 212.258249 -73.581335) (xy 212.206118 -73.574094) (xy 212.155475 -73.559769) (xy 212.107275 -73.53863)
			(xy 212.062433 -73.511078) (xy 212.021795 -73.477633) (xy 212.00364 -73.458578) (xy 211.996108 -73.451189)
			(xy 211.976836 -73.442658) (xy 211.966302 -73.442068) (xy 211.891626 -73.442068) (xy 211.881078 -73.442607)
			(xy 211.861783 -73.451136) (xy 211.854288 -73.458578) (xy 211.836127 -73.477628) (xy 211.795499 -73.511087)
			(xy 211.75066 -73.538647) (xy 211.70246 -73.559786) (xy 211.651813 -73.574104) (xy 211.59968 -73.58133)
			(xy 211.573364 -73.581768) (xy 211.545993 -73.581331) (xy 211.491812 -73.573507) (xy 211.439308 -73.558012)
			(xy 211.389562 -73.535163) (xy 211.343597 -73.505432) (xy 211.322666 -73.487788) (xy 211.322412 -73.487534)
			(xy 211.315332 -73.481939) (xy 211.29841 -73.475699) (xy 211.289392 -73.475342) (xy 211.222336 -73.475342)
			(xy 211.21332 -73.475707) (xy 211.196402 -73.481948) (xy 211.189316 -73.487534) (xy 211.189316 -73.487788)
			(xy 211.189062 -73.487788) (xy 211.168116 -73.50541) (xy 211.122147 -73.535124) (xy 211.072403 -73.557964)
			(xy 211.019906 -73.573459) (xy 210.965732 -73.581292) (xy 210.938364 -73.581768) (xy 210.911108 -73.581378)
			(xy 210.857153 -73.573616) (xy 210.804851 -73.558253) (xy 210.755268 -73.535603) (xy 210.709413 -73.506128)
			(xy 210.66822 -73.470426) (xy 210.632527 -73.429226) (xy 210.60306 -73.383365) (xy 210.58042 -73.333778)
			(xy 210.565068 -73.281473) (xy 210.557316 -73.227516) (xy 210.556856 -73.20026) (xy 201.058539 -73.20026)
			(xy 201.036962 -73.233837) (xy 201.001268 -73.275036) (xy 200.960073 -73.310736) (xy 200.914217 -73.340209)
			(xy 200.864633 -73.362857) (xy 200.812331 -73.378217) (xy 200.758376 -73.385978) (xy 200.73112 -73.386442)
			(xy 200.704958 -73.385426) (xy 200.70445 -73.385426) (xy 200.690562 -73.385039) (xy 200.663387 -73.390733)
			(xy 200.638754 -73.403544) (xy 200.618488 -73.422522) (xy 200.60409 -73.446263) (xy 200.596626 -73.473006)
			(xy 200.596651 -73.500771) (xy 200.604161 -73.527501) (xy 200.610978 -73.539604) (xy 200.624053 -73.562051)
			(xy 200.644663 -73.609735) (xy 200.658618 -73.659774) (xy 200.66566 -73.711242) (xy 200.666096 -73.737216)
			(xy 200.665605 -73.764466) (xy 200.657846 -73.81841) (xy 200.648049 -73.85177) (xy 212.97595 -73.85177)
			(xy 212.980021 -73.796148) (xy 212.992147 -73.741711) (xy 213.01207 -73.68962) (xy 213.039366 -73.640985)
			(xy 213.073452 -73.596842) (xy 213.113601 -73.558133) (xy 213.158959 -73.525682) (xy 213.208559 -73.500181)
			(xy 213.261343 -73.482174) (xy 213.316186 -73.472044) (xy 213.37192 -73.470007) (xy 213.427357 -73.476107)
			(xy 213.481314 -73.490213) (xy 213.532643 -73.512025) (xy 213.580249 -73.541079) (xy 213.623117 -73.576754)
			(xy 213.660334 -73.618291) (xy 213.691107 -73.664804) (xy 213.714779 -73.715301) (xy 213.730847 -73.768708)
			(xy 213.738967 -73.823884) (xy 213.739476 -73.85177) (xy 213.99195 -73.85177) (xy 213.996021 -73.796148)
			(xy 214.008147 -73.741711) (xy 214.02807 -73.68962) (xy 214.055366 -73.640985) (xy 214.089452 -73.596842)
			(xy 214.129601 -73.558133) (xy 214.174959 -73.525682) (xy 214.224559 -73.500181) (xy 214.277343 -73.482174)
			(xy 214.332186 -73.472044) (xy 214.38792 -73.470007) (xy 214.443357 -73.476107) (xy 214.497314 -73.490213)
			(xy 214.548643 -73.512025) (xy 214.596249 -73.541079) (xy 214.639117 -73.576754) (xy 214.676334 -73.618291)
			(xy 214.707107 -73.664804) (xy 214.730779 -73.715301) (xy 214.746847 -73.768708) (xy 214.754967 -73.823884)
			(xy 214.755476 -73.85177) (xy 215.00795 -73.85177) (xy 215.012021 -73.796148) (xy 215.024147 -73.741711)
			(xy 215.04407 -73.68962) (xy 215.071366 -73.640985) (xy 215.105452 -73.596842) (xy 215.145601 -73.558133)
			(xy 215.190959 -73.525682) (xy 215.240559 -73.500181) (xy 215.293343 -73.482174) (xy 215.348186 -73.472044)
			(xy 215.40392 -73.470007) (xy 215.459357 -73.476107) (xy 215.513314 -73.490213) (xy 215.564643 -73.512025)
			(xy 215.612249 -73.541079) (xy 215.655117 -73.576754) (xy 215.692334 -73.618291) (xy 215.723107 -73.664804)
			(xy 215.746779 -73.715301) (xy 215.762847 -73.768708) (xy 215.770967 -73.823884) (xy 215.771476 -73.85177)
			(xy 215.770967 -73.879656) (xy 215.762847 -73.934832) (xy 215.746779 -73.988239) (xy 215.723107 -74.038736)
			(xy 215.692334 -74.085249) (xy 215.655117 -74.126786) (xy 215.612249 -74.162461) (xy 215.564643 -74.191515)
			(xy 215.513314 -74.213327) (xy 215.459357 -74.227433) (xy 215.40392 -74.233533) (xy 215.348186 -74.231496)
			(xy 215.293343 -74.221366) (xy 215.240559 -74.203359) (xy 215.190959 -74.177858) (xy 215.145601 -74.145407)
			(xy 215.105452 -74.106698) (xy 215.071366 -74.062555) (xy 215.04407 -74.01392) (xy 215.024147 -73.961829)
			(xy 215.012021 -73.907392) (xy 215.00795 -73.85177) (xy 214.755476 -73.85177) (xy 214.754967 -73.879656)
			(xy 214.746847 -73.934832) (xy 214.730779 -73.988239) (xy 214.707107 -74.038736) (xy 214.676334 -74.085249)
			(xy 214.639117 -74.126786) (xy 214.596249 -74.162461) (xy 214.548643 -74.191515) (xy 214.497314 -74.213327)
			(xy 214.443357 -74.227433) (xy 214.38792 -74.233533) (xy 214.332186 -74.231496) (xy 214.277343 -74.221366)
			(xy 214.224559 -74.203359) (xy 214.174959 -74.177858) (xy 214.129601 -74.145407) (xy 214.089452 -74.106698)
			(xy 214.055366 -74.062555) (xy 214.02807 -74.01392) (xy 214.008147 -73.961829) (xy 213.996021 -73.907392)
			(xy 213.99195 -73.85177) (xy 213.739476 -73.85177) (xy 213.738967 -73.879656) (xy 213.730847 -73.934832)
			(xy 213.714779 -73.988239) (xy 213.691107 -74.038736) (xy 213.660334 -74.085249) (xy 213.623117 -74.126786)
			(xy 213.580249 -74.162461) (xy 213.532643 -74.191515) (xy 213.481314 -74.213327) (xy 213.427357 -74.227433)
			(xy 213.37192 -74.233533) (xy 213.316186 -74.231496) (xy 213.261343 -74.221366) (xy 213.208559 -74.203359)
			(xy 213.158959 -74.177858) (xy 213.113601 -74.145407) (xy 213.073452 -74.106698) (xy 213.039366 -74.062555)
			(xy 213.01207 -74.01392) (xy 212.992147 -73.961829) (xy 212.980021 -73.907392) (xy 212.97595 -73.85177)
			(xy 200.648049 -73.85177) (xy 200.64249 -73.870701) (xy 200.619849 -73.920274) (xy 200.590383 -73.966121)
			(xy 200.554692 -74.007308) (xy 200.513503 -74.042996) (xy 200.467655 -74.07246) (xy 200.41808 -74.095098)
			(xy 200.365788 -74.110451) (xy 200.311843 -74.118206) (xy 200.257344 -74.118205) (xy 200.203399 -74.110448)
			(xy 200.151108 -74.095094) (xy 200.101534 -74.072453) (xy 200.055686 -74.042988) (xy 200.014499 -74.007299)
			(xy 199.978809 -73.966111) (xy 199.949345 -73.920263) (xy 199.926705 -73.870688) (xy 199.911351 -73.818397)
			(xy 199.903594 -73.764452) (xy 196.142298 -73.764452) (xy 195.477638 -74.429112) (xy 199.379076 -74.429112)
			(xy 199.383147 -74.37349) (xy 199.395273 -74.319053) (xy 199.415196 -74.266962) (xy 199.442492 -74.218327)
			(xy 199.476578 -74.174184) (xy 199.516727 -74.135475) (xy 199.562085 -74.103024) (xy 199.611685 -74.077523)
			(xy 199.664469 -74.059516) (xy 199.719312 -74.049386) (xy 199.775046 -74.047349) (xy 199.830483 -74.053449)
			(xy 199.88444 -74.067555) (xy 199.935769 -74.089367) (xy 199.983375 -74.118421) (xy 200.026243 -74.154096)
			(xy 200.06346 -74.195633) (xy 200.094233 -74.242146) (xy 200.117905 -74.292643) (xy 200.133973 -74.34605)
			(xy 200.142093 -74.401226) (xy 200.142602 -74.429112) (xy 200.142093 -74.456998) (xy 200.133973 -74.512174)
			(xy 200.117905 -74.565581) (xy 200.094233 -74.616078) (xy 200.070828 -74.651454) (xy 208.521739 -74.651454)
			(xy 208.521739 -74.596946) (xy 208.529496 -74.542992) (xy 208.544854 -74.490691) (xy 208.567498 -74.441108)
			(xy 208.596968 -74.395253) (xy 208.632664 -74.354058) (xy 208.673859 -74.318363) (xy 208.719715 -74.288894)
			(xy 208.769298 -74.266251) (xy 208.821599 -74.250895) (xy 208.875554 -74.243138) (xy 208.902808 -74.242676)
			(xy 208.930179 -74.243119) (xy 208.98436 -74.250939) (xy 209.036864 -74.266433) (xy 209.086611 -74.28928)
			(xy 209.132576 -74.319011) (xy 209.153506 -74.336656) (xy 209.15376 -74.33691) (xy 209.160853 -74.342487)
			(xy 209.177765 -74.348739) (xy 209.18678 -74.349102) (xy 209.253836 -74.349102) (xy 209.262855 -74.348762)
			(xy 209.279771 -74.342502) (xy 209.286856 -74.33691) (xy 209.286856 -74.336656) (xy 209.28711 -74.336656)
			(xy 209.308022 -74.318992) (xy 209.354001 -74.289285) (xy 209.403753 -74.266454) (xy 209.456258 -74.250969)
			(xy 209.510438 -74.243147) (xy 209.537808 -74.242676) (xy 209.565058 -74.243195) (xy 209.619002 -74.250952)
			(xy 209.671294 -74.266307) (xy 209.720868 -74.288948) (xy 209.766715 -74.318413) (xy 209.807903 -74.354103)
			(xy 209.843592 -74.395291) (xy 209.873056 -74.441139) (xy 209.895696 -74.490714) (xy 209.91105 -74.543006)
			(xy 209.917207 -74.58583) (xy 217.058494 -74.58583) (xy 217.058917 -74.559515) (xy 217.066161 -74.507384)
			(xy 217.080489 -74.456741) (xy 217.10163 -74.408542) (xy 217.129184 -74.3637) (xy 217.162629 -74.323062)
			(xy 217.181684 -74.304906) (xy 217.189083 -74.297382) (xy 217.197609 -74.278104) (xy 217.198194 -74.267568)
			(xy 217.198194 -74.192892) (xy 217.197685 -74.18234) (xy 217.189136 -74.163045) (xy 217.181684 -74.155554)
			(xy 217.16261 -74.137417) (xy 217.129155 -74.096783) (xy 217.101599 -74.051939) (xy 217.080464 -74.003734)
			(xy 217.06615 -73.953084) (xy 217.05893 -73.900947) (xy 217.058494 -73.87463) (xy 217.058979 -73.84726)
			(xy 217.066793 -73.793082) (xy 217.082277 -73.740579) (xy 217.105115 -73.690832) (xy 217.134835 -73.644864)
			(xy 217.152474 -73.623932) (xy 217.152728 -73.623678) (xy 217.158333 -73.616604) (xy 217.164568 -73.599678)
			(xy 217.16492 -73.590658) (xy 217.16492 -73.523602) (xy 217.164558 -73.514586) (xy 217.158313 -73.497669)
			(xy 217.152728 -73.490582) (xy 217.152474 -73.490582) (xy 217.152474 -73.490328) (xy 217.134831 -73.4694)
			(xy 217.10512 -73.423425) (xy 217.082286 -73.373677) (xy 217.066795 -73.321176) (xy 217.058968 -73.266999)
			(xy 217.058494 -73.23963) (xy 217.058983 -73.212378) (xy 217.066736 -73.158428) (xy 217.082088 -73.10613)
			(xy 217.104728 -73.05655) (xy 217.134193 -73.010697) (xy 217.169884 -72.969504) (xy 217.211074 -72.93381)
			(xy 217.256925 -72.904341) (xy 217.306504 -72.881698) (xy 217.3588 -72.866342) (xy 217.41275 -72.858585)
			(xy 217.440002 -72.858122) (xy 217.467373 -72.858582) (xy 217.521552 -72.8664) (xy 217.574056 -72.88189)
			(xy 217.623802 -72.904734) (xy 217.669769 -72.93446) (xy 217.6907 -72.952102) (xy 217.690954 -72.952356)
			(xy 217.698045 -72.957936) (xy 217.714959 -72.964185) (xy 217.723974 -72.964548) (xy 217.79103 -72.964548)
			(xy 217.80005 -72.964217) (xy 217.816967 -72.957953) (xy 217.82405 -72.952356) (xy 217.82405 -72.952102)
			(xy 217.824304 -72.952102) (xy 217.845224 -72.934448) (xy 217.8912 -72.904738) (xy 217.940951 -72.881905)
			(xy 217.993454 -72.866418) (xy 218.047632 -72.858594) (xy 218.075002 -72.858122) (xy 218.102256 -72.858554)
			(xy 218.15621 -72.866312) (xy 218.20851 -72.881669) (xy 218.258092 -72.904314) (xy 218.303947 -72.933785)
			(xy 218.34514 -72.969482) (xy 218.380834 -73.010679) (xy 218.410301 -73.056536) (xy 218.432942 -73.10612)
			(xy 218.448295 -73.158421) (xy 218.456049 -73.212376) (xy 218.45651 -73.23963) (xy 218.456059 -73.267001)
			(xy 218.448237 -73.32118) (xy 218.432744 -73.373684) (xy 218.409899 -73.42343) (xy 218.380172 -73.469397)
			(xy 218.36253 -73.490328) (xy 218.362276 -73.490582) (xy 218.356688 -73.497668) (xy 218.350443 -73.514585)
			(xy 218.350084 -73.523602) (xy 218.350084 -73.533) (xy 224.641154 -73.533) (xy 224.645225 -73.477378)
			(xy 224.657351 -73.422941) (xy 224.677274 -73.37085) (xy 224.70457 -73.322215) (xy 224.738656 -73.278072)
			(xy 224.778805 -73.239363) (xy 224.824163 -73.206912) (xy 224.873763 -73.181411) (xy 224.926547 -73.163404)
			(xy 224.98139 -73.153274) (xy 225.037124 -73.151237) (xy 225.092561 -73.157337) (xy 225.146518 -73.171443)
			(xy 225.197847 -73.193255) (xy 225.209325 -73.20026) (xy 248.656856 -73.20026) (xy 248.657344 -73.17289)
			(xy 248.665154 -73.118712) (xy 248.680637 -73.066208) (xy 248.703475 -73.016461) (xy 248.733196 -72.970494)
			(xy 248.750836 -72.949562) (xy 248.75109 -72.949308) (xy 248.756678 -72.942223) (xy 248.762924 -72.925305)
			(xy 248.763282 -72.916288) (xy 248.763282 -72.849232) (xy 248.762913 -72.840216) (xy 248.756674 -72.823299)
			(xy 248.75109 -72.816212) (xy 248.750836 -72.816212) (xy 248.750836 -72.815958) (xy 248.733216 -72.79501)
			(xy 248.7035 -72.749042) (xy 248.68066 -72.699299) (xy 248.665165 -72.646801) (xy 248.657332 -72.592628)
			(xy 248.656856 -72.56526) (xy 248.65734 -72.538009) (xy 248.665102 -72.484064) (xy 248.68046 -72.431771)
			(xy 248.703103 -72.382196) (xy 248.73257 -72.336348) (xy 248.768262 -72.295159) (xy 248.809451 -72.259468)
			(xy 248.855299 -72.230001) (xy 248.904875 -72.207358) (xy 248.957167 -72.192001) (xy 249.011113 -72.18424)
			(xy 249.038364 -72.183752) (xy 249.065734 -72.184226) (xy 249.119913 -72.19204) (xy 249.172417 -72.207527)
			(xy 249.222164 -72.230367) (xy 249.268131 -72.260091) (xy 249.289062 -72.277732) (xy 249.289316 -72.277986)
			(xy 249.296395 -72.283584) (xy 249.313318 -72.289824) (xy 249.322336 -72.290178) (xy 249.389392 -72.290178)
			(xy 249.398409 -72.289822) (xy 249.415326 -72.283574) (xy 249.422412 -72.277986) (xy 249.422412 -72.277732)
			(xy 249.422666 -72.277732) (xy 249.443604 -72.2601) (xy 249.489575 -72.230386) (xy 249.539321 -72.207548)
			(xy 249.59182 -72.192056) (xy 249.645995 -72.184226) (xy 249.673364 -72.183752) (xy 249.69968 -72.18416)
			(xy 249.751812 -72.191405) (xy 249.802456 -72.205734) (xy 249.850656 -72.226878) (xy 249.895497 -72.254435)
			(xy 249.936134 -72.287885) (xy 249.954288 -72.306942) (xy 249.96182 -72.314332) (xy 249.981092 -72.322865)
			(xy 249.991626 -72.323452) (xy 250.066302 -72.323452) (xy 250.076855 -72.322952) (xy 250.096151 -72.314398)
			(xy 250.10364 -72.306942) (xy 250.121772 -72.287863) (xy 250.162408 -72.25441) (xy 250.207254 -72.226856)
			(xy 250.255459 -72.205722) (xy 250.30611 -72.191409) (xy 250.358247 -72.184188) (xy 250.384564 -72.183752)
			(xy 250.411813 -72.184312) (xy 250.465755 -72.192062) (xy 250.518046 -72.207411) (xy 250.567621 -72.230045)
			(xy 250.613469 -72.259503) (xy 250.654659 -72.295187) (xy 250.690351 -72.33637) (xy 250.719819 -72.382213)
			(xy 250.742463 -72.431782) (xy 250.757822 -72.48407) (xy 250.765583 -72.538012) (xy 250.766072 -72.56526)
			(xy 250.765589 -72.59263) (xy 250.757777 -72.646808) (xy 250.742292 -72.699312) (xy 250.719454 -72.749059)
			(xy 250.689732 -72.795026) (xy 250.672092 -72.815958) (xy 250.671838 -72.816212) (xy 250.666233 -72.823286)
			(xy 250.659999 -72.840213) (xy 250.659646 -72.849232) (xy 250.659646 -72.916288) (xy 250.659999 -72.925305)
			(xy 250.666248 -72.942223) (xy 250.671838 -72.949308) (xy 250.672092 -72.949308) (xy 250.672092 -72.949562)
			(xy 250.689725 -72.970499) (xy 250.719438 -73.01647) (xy 250.742276 -73.066216) (xy 250.757768 -73.118716)
			(xy 250.765597 -73.172891) (xy 250.766072 -73.20026) (xy 250.765607 -73.227513) (xy 250.757855 -73.281466)
			(xy 250.742502 -73.333766) (xy 250.719862 -73.383349) (xy 250.690394 -73.429204) (xy 250.654701 -73.470398)
			(xy 250.613507 -73.506092) (xy 250.567652 -73.53556) (xy 250.51807 -73.558201) (xy 250.46577 -73.573554)
			(xy 250.411817 -73.581307) (xy 250.384564 -73.581768) (xy 250.358249 -73.581335) (xy 250.306118 -73.574094)
			(xy 250.255475 -73.559769) (xy 250.207275 -73.53863) (xy 250.162433 -73.511078) (xy 250.121795 -73.477633)
			(xy 250.10364 -73.458578) (xy 250.096108 -73.451189) (xy 250.076836 -73.442658) (xy 250.066302 -73.442068)
			(xy 249.991626 -73.442068) (xy 249.981078 -73.442607) (xy 249.961783 -73.451136) (xy 249.954288 -73.458578)
			(xy 249.936127 -73.477628) (xy 249.895499 -73.511087) (xy 249.85066 -73.538647) (xy 249.80246 -73.559786)
			(xy 249.751813 -73.574104) (xy 249.69968 -73.58133) (xy 249.673364 -73.581768) (xy 249.645993 -73.581331)
			(xy 249.591812 -73.573507) (xy 249.539308 -73.558012) (xy 249.489562 -73.535163) (xy 249.443597 -73.505432)
			(xy 249.422666 -73.487788) (xy 249.422412 -73.487534) (xy 249.415332 -73.481939) (xy 249.39841 -73.475699)
			(xy 249.389392 -73.475342) (xy 249.322336 -73.475342) (xy 249.31332 -73.475707) (xy 249.296402 -73.481948)
			(xy 249.289316 -73.487534) (xy 249.289316 -73.487788) (xy 249.289062 -73.487788) (xy 249.268116 -73.50541)
			(xy 249.222147 -73.535124) (xy 249.172403 -73.557964) (xy 249.119906 -73.573459) (xy 249.065732 -73.581292)
			(xy 249.038364 -73.581768) (xy 249.011108 -73.581378) (xy 248.957153 -73.573616) (xy 248.904851 -73.558253)
			(xy 248.855268 -73.535603) (xy 248.809413 -73.506128) (xy 248.76822 -73.470426) (xy 248.732527 -73.429226)
			(xy 248.70306 -73.383365) (xy 248.68042 -73.333778) (xy 248.665068 -73.281473) (xy 248.657316 -73.227516)
			(xy 248.656856 -73.20026) (xy 225.209325 -73.20026) (xy 225.245453 -73.222309) (xy 225.288321 -73.257984)
			(xy 225.325538 -73.299521) (xy 225.356311 -73.346034) (xy 225.379983 -73.396531) (xy 225.396051 -73.449938)
			(xy 225.404171 -73.505114) (xy 225.40468 -73.533) (xy 225.404171 -73.560886) (xy 225.396051 -73.616062)
			(xy 225.379983 -73.669469) (xy 225.356311 -73.719966) (xy 225.325538 -73.766479) (xy 225.288321 -73.808016)
			(xy 225.245453 -73.843691) (xy 225.197847 -73.872745) (xy 225.146518 -73.894557) (xy 225.092561 -73.908663)
			(xy 225.037124 -73.914763) (xy 224.98139 -73.912726) (xy 224.926547 -73.902596) (xy 224.873763 -73.884589)
			(xy 224.824163 -73.859088) (xy 224.778805 -73.826637) (xy 224.738656 -73.787928) (xy 224.70457 -73.743785)
			(xy 224.677274 -73.69515) (xy 224.657351 -73.643059) (xy 224.645225 -73.588622) (xy 224.641154 -73.533)
			(xy 218.350084 -73.533) (xy 218.350084 -73.590658) (xy 218.350464 -73.599672) (xy 218.356696 -73.616589)
			(xy 218.362276 -73.623678) (xy 218.36253 -73.623678) (xy 218.36253 -73.623932) (xy 218.380155 -73.644875)
			(xy 218.409868 -73.690845) (xy 218.432706 -73.74059) (xy 218.448201 -73.793088) (xy 218.456033 -73.847262)
			(xy 218.45651 -73.87463) (xy 218.456059 -73.900944) (xy 218.448821 -73.953074) (xy 218.434498 -74.003717)
			(xy 218.413362 -74.051915) (xy 218.411641 -74.054716) (xy 240.911378 -74.054716) (xy 240.915449 -73.999094)
			(xy 240.927575 -73.944657) (xy 240.947498 -73.892566) (xy 240.974794 -73.843931) (xy 241.00888 -73.799788)
			(xy 241.049029 -73.761079) (xy 241.094387 -73.728628) (xy 241.143987 -73.703127) (xy 241.196771 -73.68512)
			(xy 241.251614 -73.67499) (xy 241.307348 -73.672953) (xy 241.362785 -73.679053) (xy 241.416742 -73.693159)
			(xy 241.468071 -73.714971) (xy 241.515677 -73.744025) (xy 241.558545 -73.7797) (xy 241.595762 -73.821237)
			(xy 241.615963 -73.85177) (xy 251.07595 -73.85177) (xy 251.080021 -73.796148) (xy 251.092147 -73.741711)
			(xy 251.11207 -73.68962) (xy 251.139366 -73.640985) (xy 251.173452 -73.596842) (xy 251.213601 -73.558133)
			(xy 251.258959 -73.525682) (xy 251.308559 -73.500181) (xy 251.361343 -73.482174) (xy 251.416186 -73.472044)
			(xy 251.47192 -73.470007) (xy 251.527357 -73.476107) (xy 251.581314 -73.490213) (xy 251.632643 -73.512025)
			(xy 251.680249 -73.541079) (xy 251.723117 -73.576754) (xy 251.760334 -73.618291) (xy 251.791107 -73.664804)
			(xy 251.814779 -73.715301) (xy 251.830847 -73.768708) (xy 251.838967 -73.823884) (xy 251.839476 -73.85177)
			(xy 252.09195 -73.85177) (xy 252.096021 -73.796148) (xy 252.108147 -73.741711) (xy 252.12807 -73.68962)
			(xy 252.155366 -73.640985) (xy 252.189452 -73.596842) (xy 252.229601 -73.558133) (xy 252.274959 -73.525682)
			(xy 252.324559 -73.500181) (xy 252.377343 -73.482174) (xy 252.432186 -73.472044) (xy 252.48792 -73.470007)
			(xy 252.543357 -73.476107) (xy 252.597314 -73.490213) (xy 252.648643 -73.512025) (xy 252.696249 -73.541079)
			(xy 252.739117 -73.576754) (xy 252.776334 -73.618291) (xy 252.807107 -73.664804) (xy 252.830779 -73.715301)
			(xy 252.846847 -73.768708) (xy 252.854967 -73.823884) (xy 252.855476 -73.85177) (xy 253.10795 -73.85177)
			(xy 253.112021 -73.796148) (xy 253.124147 -73.741711) (xy 253.14407 -73.68962) (xy 253.171366 -73.640985)
			(xy 253.205452 -73.596842) (xy 253.245601 -73.558133) (xy 253.290959 -73.525682) (xy 253.340559 -73.500181)
			(xy 253.393343 -73.482174) (xy 253.448186 -73.472044) (xy 253.50392 -73.470007) (xy 253.559357 -73.476107)
			(xy 253.613314 -73.490213) (xy 253.664643 -73.512025) (xy 253.712249 -73.541079) (xy 253.755117 -73.576754)
			(xy 253.792334 -73.618291) (xy 253.823107 -73.664804) (xy 253.846779 -73.715301) (xy 253.862847 -73.768708)
			(xy 253.870967 -73.823884) (xy 253.871476 -73.85177) (xy 253.870967 -73.879656) (xy 253.862847 -73.934832)
			(xy 253.846779 -73.988239) (xy 253.823107 -74.038736) (xy 253.792334 -74.085249) (xy 253.755117 -74.126786)
			(xy 253.712249 -74.162461) (xy 253.664643 -74.191515) (xy 253.613314 -74.213327) (xy 253.559357 -74.227433)
			(xy 253.50392 -74.233533) (xy 253.448186 -74.231496) (xy 253.393343 -74.221366) (xy 253.340559 -74.203359)
			(xy 253.290959 -74.177858) (xy 253.245601 -74.145407) (xy 253.205452 -74.106698) (xy 253.171366 -74.062555)
			(xy 253.14407 -74.01392) (xy 253.124147 -73.961829) (xy 253.112021 -73.907392) (xy 253.10795 -73.85177)
			(xy 252.855476 -73.85177) (xy 252.854967 -73.879656) (xy 252.846847 -73.934832) (xy 252.830779 -73.988239)
			(xy 252.807107 -74.038736) (xy 252.776334 -74.085249) (xy 252.739117 -74.126786) (xy 252.696249 -74.162461)
			(xy 252.648643 -74.191515) (xy 252.597314 -74.213327) (xy 252.543357 -74.227433) (xy 252.48792 -74.233533)
			(xy 252.432186 -74.231496) (xy 252.377343 -74.221366) (xy 252.324559 -74.203359) (xy 252.274959 -74.177858)
			(xy 252.229601 -74.145407) (xy 252.189452 -74.106698) (xy 252.155366 -74.062555) (xy 252.12807 -74.01392)
			(xy 252.108147 -73.961829) (xy 252.096021 -73.907392) (xy 252.09195 -73.85177) (xy 251.839476 -73.85177)
			(xy 251.838967 -73.879656) (xy 251.830847 -73.934832) (xy 251.814779 -73.988239) (xy 251.791107 -74.038736)
			(xy 251.760334 -74.085249) (xy 251.723117 -74.126786) (xy 251.680249 -74.162461) (xy 251.632643 -74.191515)
			(xy 251.581314 -74.213327) (xy 251.527357 -74.227433) (xy 251.47192 -74.233533) (xy 251.416186 -74.231496)
			(xy 251.361343 -74.221366) (xy 251.308559 -74.203359) (xy 251.258959 -74.177858) (xy 251.213601 -74.145407)
			(xy 251.173452 -74.106698) (xy 251.139366 -74.062555) (xy 251.11207 -74.01392) (xy 251.092147 -73.961829)
			(xy 251.080021 -73.907392) (xy 251.07595 -73.85177) (xy 241.615963 -73.85177) (xy 241.626535 -73.86775)
			(xy 241.650207 -73.918247) (xy 241.666275 -73.971654) (xy 241.674395 -74.02683) (xy 241.674904 -74.054716)
			(xy 241.674395 -74.082602) (xy 241.666275 -74.137778) (xy 241.650207 -74.191185) (xy 241.626535 -74.241682)
			(xy 241.595762 -74.288195) (xy 241.558545 -74.329732) (xy 241.515677 -74.365407) (xy 241.468071 -74.394461)
			(xy 241.416742 -74.416273) (xy 241.362785 -74.430379) (xy 241.307348 -74.436479) (xy 241.251614 -74.434442)
			(xy 241.196771 -74.424312) (xy 241.143987 -74.406305) (xy 241.094387 -74.380804) (xy 241.049029 -74.348353)
			(xy 241.00888 -74.309644) (xy 240.974794 -74.265501) (xy 240.947498 -74.216866) (xy 240.927575 -74.164775)
			(xy 240.915449 -74.110338) (xy 240.911378 -74.054716) (xy 218.411641 -74.054716) (xy 218.385814 -74.096758)
			(xy 218.352373 -74.137398) (xy 218.33332 -74.155554) (xy 218.325895 -74.163056) (xy 218.317384 -74.182351)
			(xy 218.31681 -74.192892) (xy 218.31681 -74.267568) (xy 218.31734 -74.278118) (xy 218.325874 -74.297413)
			(xy 218.33332 -74.304906) (xy 218.352375 -74.323062) (xy 218.385832 -74.363692) (xy 218.41339 -74.408532)
			(xy 218.434529 -74.456733) (xy 218.448846 -74.50738) (xy 218.456071 -74.559514) (xy 218.45651 -74.58583)
			(xy 218.456184 -74.605134) (xy 222.27997 -74.605134) (xy 222.284041 -74.549512) (xy 222.296167 -74.495075)
			(xy 222.31609 -74.442984) (xy 222.343386 -74.394349) (xy 222.377472 -74.350206) (xy 222.417621 -74.311497)
			(xy 222.462979 -74.279046) (xy 222.512579 -74.253545) (xy 222.565363 -74.235538) (xy 222.620206 -74.225408)
			(xy 222.67594 -74.223371) (xy 222.731377 -74.229471) (xy 222.785334 -74.243577) (xy 222.836663 -74.265389)
			(xy 222.884269 -74.294443) (xy 222.927137 -74.330118) (xy 222.964354 -74.371655) (xy 222.995127 -74.418168)
			(xy 223.018799 -74.468665) (xy 223.034867 -74.522072) (xy 223.042987 -74.577248) (xy 223.043496 -74.605134)
			(xy 223.042987 -74.63302) (xy 223.040274 -74.651454) (xy 246.621739 -74.651454) (xy 246.621739 -74.596946)
			(xy 246.629496 -74.542992) (xy 246.644854 -74.490691) (xy 246.667498 -74.441108) (xy 246.696968 -74.395253)
			(xy 246.732664 -74.354058) (xy 246.773859 -74.318363) (xy 246.819715 -74.288894) (xy 246.869298 -74.266251)
			(xy 246.921599 -74.250895) (xy 246.975554 -74.243138) (xy 247.002808 -74.242676) (xy 247.030179 -74.243119)
			(xy 247.08436 -74.250939) (xy 247.136864 -74.266433) (xy 247.186611 -74.28928) (xy 247.232576 -74.319011)
			(xy 247.253506 -74.336656) (xy 247.25376 -74.33691) (xy 247.260853 -74.342487) (xy 247.277765 -74.348739)
			(xy 247.28678 -74.349102) (xy 247.353836 -74.349102) (xy 247.362855 -74.348762) (xy 247.379771 -74.342502)
			(xy 247.386856 -74.33691) (xy 247.386856 -74.336656) (xy 247.38711 -74.336656) (xy 247.408022 -74.318992)
			(xy 247.454001 -74.289285) (xy 247.503753 -74.266454) (xy 247.556258 -74.250969) (xy 247.610438 -74.243147)
			(xy 247.637808 -74.242676) (xy 247.665058 -74.243195) (xy 247.719002 -74.250952) (xy 247.771294 -74.266307)
			(xy 247.820868 -74.288948) (xy 247.866715 -74.318413) (xy 247.907903 -74.354103) (xy 247.943592 -74.395291)
			(xy 247.973056 -74.441139) (xy 247.995696 -74.490714) (xy 248.01105 -74.543006) (xy 248.017207 -74.58583)
			(xy 255.158494 -74.58583) (xy 255.158917 -74.559515) (xy 255.166161 -74.507384) (xy 255.180489 -74.456741)
			(xy 255.20163 -74.408542) (xy 255.229184 -74.3637) (xy 255.262629 -74.323062) (xy 255.281684 -74.304906)
			(xy 255.289083 -74.297382) (xy 255.297609 -74.278104) (xy 255.298194 -74.267568) (xy 255.298194 -74.192892)
			(xy 255.297685 -74.18234) (xy 255.289136 -74.163045) (xy 255.281684 -74.155554) (xy 255.26261 -74.137417)
			(xy 255.229155 -74.096783) (xy 255.201599 -74.051939) (xy 255.180464 -74.003734) (xy 255.16615 -73.953084)
			(xy 255.15893 -73.900947) (xy 255.158494 -73.87463) (xy 255.158979 -73.84726) (xy 255.166793 -73.793082)
			(xy 255.182277 -73.740579) (xy 255.205115 -73.690832) (xy 255.234835 -73.644864) (xy 255.252474 -73.623932)
			(xy 255.252728 -73.623678) (xy 255.258333 -73.616604) (xy 255.264568 -73.599678) (xy 255.26492 -73.590658)
			(xy 255.26492 -73.523602) (xy 255.264558 -73.514586) (xy 255.258313 -73.497669) (xy 255.252728 -73.490582)
			(xy 255.252474 -73.490582) (xy 255.252474 -73.490328) (xy 255.234831 -73.4694) (xy 255.20512 -73.423425)
			(xy 255.182286 -73.373677) (xy 255.166795 -73.321176) (xy 255.158968 -73.266999) (xy 255.158494 -73.23963)
			(xy 255.158983 -73.212378) (xy 255.166736 -73.158428) (xy 255.182088 -73.10613) (xy 255.204728 -73.05655)
			(xy 255.234193 -73.010697) (xy 255.269884 -72.969504) (xy 255.311074 -72.93381) (xy 255.356925 -72.904341)
			(xy 255.406504 -72.881698) (xy 255.4588 -72.866342) (xy 255.51275 -72.858585) (xy 255.540002 -72.858122)
			(xy 255.567373 -72.858582) (xy 255.621552 -72.8664) (xy 255.674056 -72.88189) (xy 255.723802 -72.904734)
			(xy 255.769769 -72.93446) (xy 255.7907 -72.952102) (xy 255.790954 -72.952356) (xy 255.798045 -72.957936)
			(xy 255.814959 -72.964185) (xy 255.823974 -72.964548) (xy 255.89103 -72.964548) (xy 255.90005 -72.964217)
			(xy 255.916967 -72.957953) (xy 255.92405 -72.952356) (xy 255.92405 -72.952102) (xy 255.924304 -72.952102)
			(xy 255.945224 -72.934448) (xy 255.9912 -72.904738) (xy 256.040951 -72.881905) (xy 256.093454 -72.866418)
			(xy 256.147632 -72.858594) (xy 256.175002 -72.858122) (xy 256.202256 -72.858554) (xy 256.25621 -72.866312)
			(xy 256.30851 -72.881669) (xy 256.358092 -72.904314) (xy 256.403947 -72.933785) (xy 256.44514 -72.969482)
			(xy 256.480834 -73.010679) (xy 256.510301 -73.056536) (xy 256.532942 -73.10612) (xy 256.548295 -73.158421)
			(xy 256.556049 -73.212376) (xy 256.55651 -73.23963) (xy 256.556059 -73.267001) (xy 256.548237 -73.32118)
			(xy 256.532744 -73.373684) (xy 256.509899 -73.42343) (xy 256.480172 -73.469397) (xy 256.46253 -73.490328)
			(xy 256.462276 -73.490582) (xy 256.456688 -73.497668) (xy 256.450443 -73.514585) (xy 256.450084 -73.523602)
			(xy 256.450084 -73.590658) (xy 256.450464 -73.599672) (xy 256.456696 -73.616589) (xy 256.462276 -73.623678)
			(xy 256.46253 -73.623678) (xy 256.46253 -73.623932) (xy 256.480155 -73.644875) (xy 256.509868 -73.690845)
			(xy 256.526259 -73.726548) (xy 259.359398 -73.726548) (xy 259.363469 -73.670926) (xy 259.375595 -73.616489)
			(xy 259.395518 -73.564398) (xy 259.422814 -73.515763) (xy 259.4569 -73.47162) (xy 259.497049 -73.432911)
			(xy 259.542407 -73.40046) (xy 259.592007 -73.374959) (xy 259.644791 -73.356952) (xy 259.699634 -73.346822)
			(xy 259.755368 -73.344785) (xy 259.810805 -73.350885) (xy 259.864762 -73.364991) (xy 259.916091 -73.386803)
			(xy 259.963697 -73.415857) (xy 260.006565 -73.451532) (xy 260.043782 -73.493069) (xy 260.074555 -73.539582)
			(xy 260.077119 -73.545052) (xy 260.531838 -73.545052) (xy 260.531838 -73.490548) (xy 260.539594 -73.436597)
			(xy 260.554949 -73.3843) (xy 260.57759 -73.33472) (xy 260.607056 -73.288866) (xy 260.642747 -73.247673)
			(xy 260.683938 -73.211978) (xy 260.729788 -73.182507) (xy 260.779366 -73.159862) (xy 260.831662 -73.144502)
			(xy 260.885612 -73.13674) (xy 260.912864 -73.136252) (xy 260.939259 -73.136728) (xy 260.991544 -73.144007)
			(xy 261.042329 -73.158417) (xy 261.090645 -73.179685) (xy 261.135572 -73.207404) (xy 261.156196 -73.223882)
			(xy 261.166959 -73.232137) (xy 261.191639 -73.243346) (xy 261.218401 -73.247657) (xy 261.245354 -73.244767)
			(xy 261.270593 -73.23488) (xy 261.292337 -73.218693) (xy 261.309048 -73.19735) (xy 261.314692 -73.18502)
			(xy 261.326017 -73.159373) (xy 261.354963 -73.111362) (xy 261.390623 -73.068104) (xy 261.43223 -73.03053)
			(xy 261.478887 -72.999449) (xy 261.529591 -72.975531) (xy 261.583249 -72.959291) (xy 261.638705 -72.951077)
			(xy 261.666736 -72.950578) (xy 261.693985 -72.951095) (xy 261.747926 -72.958855) (xy 261.800215 -72.974213)
			(xy 261.849786 -72.996855) (xy 261.89563 -73.026321) (xy 261.936814 -73.062011) (xy 261.9725 -73.103199)
			(xy 262.001962 -73.149046) (xy 262.0246 -73.198619) (xy 262.039953 -73.250909) (xy 262.047708 -73.304851)
			(xy 262.047708 -73.359349) (xy 262.039953 -73.413291) (xy 262.0246 -73.465581) (xy 262.001962 -73.515154)
			(xy 261.9725 -73.561001) (xy 261.936814 -73.602189) (xy 261.89563 -73.637879) (xy 261.849786 -73.667345)
			(xy 261.800215 -73.689987) (xy 261.747926 -73.705345) (xy 261.693985 -73.713105) (xy 261.666736 -73.713594)
			(xy 261.640341 -73.713131) (xy 261.588054 -73.70585) (xy 261.537269 -73.691438) (xy 261.488953 -73.670167)
			(xy 261.444027 -73.642444) (xy 261.423404 -73.625964) (xy 261.412653 -73.617691) (xy 261.387969 -73.606475)
			(xy 261.361202 -73.60216) (xy 261.334244 -73.605051) (xy 261.309001 -73.614944) (xy 261.287256 -73.631139)
			(xy 261.270548 -73.652491) (xy 261.264908 -73.664826) (xy 261.253606 -73.690484) (xy 261.224654 -73.738493)
			(xy 261.18899 -73.781749) (xy 261.147379 -73.819321) (xy 261.100719 -73.8504) (xy 261.050013 -73.874316)
			(xy 260.996354 -73.890556) (xy 260.940895 -73.898769) (xy 260.912864 -73.899268) (xy 260.885612 -73.89886)
			(xy 260.831662 -73.891098) (xy 260.779366 -73.875738) (xy 260.729788 -73.853093) (xy 260.683938 -73.823622)
			(xy 260.642747 -73.787927) (xy 260.607056 -73.746734) (xy 260.57759 -73.70088) (xy 260.554949 -73.6513)
			(xy 260.539594 -73.599003) (xy 260.531838 -73.545052) (xy 260.077119 -73.545052) (xy 260.098227 -73.590079)
			(xy 260.114295 -73.643486) (xy 260.122415 -73.698662) (xy 260.122924 -73.726548) (xy 260.122415 -73.754434)
			(xy 260.114295 -73.80961) (xy 260.098227 -73.863017) (xy 260.074555 -73.913514) (xy 260.043782 -73.960027)
			(xy 260.006565 -74.001564) (xy 259.963697 -74.037239) (xy 259.916091 -74.066293) (xy 259.864762 -74.088105)
			(xy 259.810805 -74.102211) (xy 259.755368 -74.108311) (xy 259.699634 -74.106274) (xy 259.644791 -74.096144)
			(xy 259.592007 -74.078137) (xy 259.542407 -74.052636) (xy 259.497049 -74.020185) (xy 259.4569 -73.981476)
			(xy 259.422814 -73.937333) (xy 259.395518 -73.888698) (xy 259.375595 -73.836607) (xy 259.363469 -73.78217)
			(xy 259.359398 -73.726548) (xy 256.526259 -73.726548) (xy 256.532706 -73.74059) (xy 256.548201 -73.793088)
			(xy 256.556033 -73.847262) (xy 256.55651 -73.87463) (xy 256.556059 -73.900944) (xy 256.548821 -73.953074)
			(xy 256.534498 -74.003717) (xy 256.513362 -74.051915) (xy 256.485814 -74.096758) (xy 256.452373 -74.137398)
			(xy 256.43332 -74.155554) (xy 256.425895 -74.163056) (xy 256.417384 -74.182351) (xy 256.41681 -74.192892)
			(xy 256.41681 -74.267568) (xy 256.41734 -74.278118) (xy 256.425874 -74.297413) (xy 256.43332 -74.304906)
			(xy 256.452375 -74.323062) (xy 256.485832 -74.363692) (xy 256.51339 -74.408532) (xy 256.534529 -74.456733)
			(xy 256.548846 -74.50738) (xy 256.556071 -74.559514) (xy 256.55651 -74.58583) (xy 256.55605 -74.613082)
			(xy 256.54829 -74.66703) (xy 256.532931 -74.719326) (xy 256.510286 -74.768903) (xy 256.480817 -74.814753)
			(xy 256.445123 -74.855943) (xy 256.40393 -74.891634) (xy 256.358078 -74.9211) (xy 256.308499 -74.943741)
			(xy 256.256203 -74.959096) (xy 256.202254 -74.966852) (xy 256.175002 -74.967338) (xy 256.147631 -74.966886)
			(xy 256.093451 -74.959067) (xy 256.040947 -74.943576) (xy 255.9912 -74.92073) (xy 255.945235 -74.891002)
			(xy 255.924304 -74.873358) (xy 255.92405 -74.873104) (xy 255.916953 -74.867533) (xy 255.900044 -74.861277)
			(xy 255.89103 -74.860912) (xy 255.823974 -74.860912) (xy 255.814956 -74.861254) (xy 255.798039 -74.867512)
			(xy 255.790954 -74.873104) (xy 255.790954 -74.873358) (xy 255.7907 -74.873358) (xy 255.769773 -74.891004)
			(xy 255.7238 -74.920716) (xy 255.674051 -74.943552) (xy 255.621549 -74.959041) (xy 255.567372 -74.966866)
			(xy 255.540002 -74.967338) (xy 255.512752 -74.96682) (xy 255.458807 -74.959065) (xy 255.406515 -74.943712)
			(xy 255.35694 -74.921073) (xy 255.311091 -74.89161) (xy 255.269901 -74.855922) (xy 255.23421 -74.814735)
			(xy 255.204742 -74.768889) (xy 255.1821 -74.719315) (xy 255.166742 -74.667024) (xy 255.158982 -74.61308)
			(xy 255.158494 -74.58583) (xy 248.017207 -74.58583) (xy 248.018806 -74.59695) (xy 248.018806 -74.65145)
			(xy 248.01105 -74.705394) (xy 247.995696 -74.757686) (xy 247.973056 -74.807261) (xy 247.943592 -74.853109)
			(xy 247.907903 -74.894297) (xy 247.866715 -74.929987) (xy 247.820868 -74.959452) (xy 247.771294 -74.982093)
			(xy 247.719002 -74.997448) (xy 247.665058 -75.005205) (xy 247.637808 -75.005692) (xy 247.610438 -75.005223)
			(xy 247.556259 -74.997406) (xy 247.503756 -74.981918) (xy 247.454009 -74.959077) (xy 247.408042 -74.929353)
			(xy 247.38711 -74.911712) (xy 247.386856 -74.911458) (xy 247.379761 -74.905884) (xy 247.362851 -74.899631)
			(xy 247.353836 -74.899266) (xy 247.28678 -74.899266) (xy 247.277763 -74.899621) (xy 247.260846 -74.905871)
			(xy 247.25376 -74.911458) (xy 247.25376 -74.911712) (xy 247.253506 -74.911712) (xy 247.232584 -74.929364)
			(xy 247.186608 -74.959073) (xy 247.136858 -74.981906) (xy 247.084355 -74.997395) (xy 247.030178 -75.00522)
			(xy 247.002808 -75.005692) (xy 246.975554 -75.005262) (xy 246.921599 -74.997505) (xy 246.869298 -74.982149)
			(xy 246.819715 -74.959506) (xy 246.773859 -74.930037) (xy 246.732664 -74.894342) (xy 246.696968 -74.853147)
			(xy 246.667498 -74.807292) (xy 246.644854 -74.757709) (xy 246.629496 -74.705408) (xy 246.621739 -74.651454)
			(xy 223.040274 -74.651454) (xy 223.034867 -74.688196) (xy 223.018799 -74.741603) (xy 222.995127 -74.7921)
			(xy 222.964354 -74.838613) (xy 222.927137 -74.88015) (xy 222.884269 -74.915825) (xy 222.836663 -74.944879)
			(xy 222.785334 -74.966691) (xy 222.731377 -74.980797) (xy 222.67594 -74.986897) (xy 222.620206 -74.98486)
			(xy 222.565363 -74.97473) (xy 222.512579 -74.956723) (xy 222.462979 -74.931222) (xy 222.417621 -74.898771)
			(xy 222.377472 -74.860062) (xy 222.343386 -74.815919) (xy 222.31609 -74.767284) (xy 222.296167 -74.715193)
			(xy 222.284041 -74.660756) (xy 222.27997 -74.605134) (xy 218.456184 -74.605134) (xy 218.45605 -74.613082)
			(xy 218.44829 -74.66703) (xy 218.432931 -74.719326) (xy 218.410286 -74.768903) (xy 218.380817 -74.814753)
			(xy 218.345123 -74.855943) (xy 218.30393 -74.891634) (xy 218.258078 -74.9211) (xy 218.208499 -74.943741)
			(xy 218.156203 -74.959096) (xy 218.102254 -74.966852) (xy 218.075002 -74.967338) (xy 218.047631 -74.966886)
			(xy 217.993451 -74.959067) (xy 217.940947 -74.943576) (xy 217.8912 -74.92073) (xy 217.845235 -74.891002)
			(xy 217.824304 -74.873358) (xy 217.82405 -74.873104) (xy 217.816953 -74.867533) (xy 217.800044 -74.861277)
			(xy 217.79103 -74.860912) (xy 217.723974 -74.860912) (xy 217.714956 -74.861254) (xy 217.698039 -74.867512)
			(xy 217.690954 -74.873104) (xy 217.690954 -74.873358) (xy 217.6907 -74.873358) (xy 217.669773 -74.891004)
			(xy 217.6238 -74.920716) (xy 217.574051 -74.943552) (xy 217.521549 -74.959041) (xy 217.467372 -74.966866)
			(xy 217.440002 -74.967338) (xy 217.412752 -74.96682) (xy 217.358807 -74.959065) (xy 217.306515 -74.943712)
			(xy 217.25694 -74.921073) (xy 217.211091 -74.89161) (xy 217.169901 -74.855922) (xy 217.13421 -74.814735)
			(xy 217.104742 -74.768889) (xy 217.0821 -74.719315) (xy 217.066742 -74.667024) (xy 217.058982 -74.61308)
			(xy 217.058494 -74.58583) (xy 209.917207 -74.58583) (xy 209.918806 -74.59695) (xy 209.918806 -74.65145)
			(xy 209.91105 -74.705394) (xy 209.895696 -74.757686) (xy 209.873056 -74.807261) (xy 209.843592 -74.853109)
			(xy 209.807903 -74.894297) (xy 209.766715 -74.929987) (xy 209.720868 -74.959452) (xy 209.671294 -74.982093)
			(xy 209.619002 -74.997448) (xy 209.565058 -75.005205) (xy 209.537808 -75.005692) (xy 209.510438 -75.005223)
			(xy 209.456259 -74.997406) (xy 209.403756 -74.981918) (xy 209.354009 -74.959077) (xy 209.308042 -74.929353)
			(xy 209.28711 -74.911712) (xy 209.286856 -74.911458) (xy 209.279761 -74.905884) (xy 209.262851 -74.899631)
			(xy 209.253836 -74.899266) (xy 209.18678 -74.899266) (xy 209.177763 -74.899621) (xy 209.160846 -74.905871)
			(xy 209.15376 -74.911458) (xy 209.15376 -74.911712) (xy 209.153506 -74.911712) (xy 209.132584 -74.929364)
			(xy 209.086608 -74.959073) (xy 209.036858 -74.981906) (xy 208.984355 -74.997395) (xy 208.930178 -75.00522)
			(xy 208.902808 -75.005692) (xy 208.875554 -75.005262) (xy 208.821599 -74.997505) (xy 208.769298 -74.982149)
			(xy 208.719715 -74.959506) (xy 208.673859 -74.930037) (xy 208.632664 -74.894342) (xy 208.596968 -74.853147)
			(xy 208.567498 -74.807292) (xy 208.544854 -74.757709) (xy 208.529496 -74.705408) (xy 208.521739 -74.651454)
			(xy 200.070828 -74.651454) (xy 200.06346 -74.662591) (xy 200.026243 -74.704128) (xy 199.983375 -74.739803)
			(xy 199.935769 -74.768857) (xy 199.88444 -74.790669) (xy 199.830483 -74.804775) (xy 199.775046 -74.810875)
			(xy 199.719312 -74.808838) (xy 199.664469 -74.798708) (xy 199.611685 -74.780701) (xy 199.562085 -74.7552)
			(xy 199.516727 -74.722749) (xy 199.476578 -74.68404) (xy 199.442492 -74.639897) (xy 199.415196 -74.591262)
			(xy 199.395273 -74.539171) (xy 199.383147 -74.484734) (xy 199.379076 -74.429112) (xy 195.477638 -74.429112)
			(xy 188.278262 -81.628488) (xy 188.270862 -81.63533) (xy 188.252264 -81.643052) (xy 188.242194 -81.643474)
			(xy 135.756904 -81.643474) (xy 135.750896 -81.643646) (xy 135.739218 -81.646478) (xy 135.73379 -81.649062)
			(xy 135.730315 -81.6509) (xy 135.723933 -81.65549) (xy 135.72109 -81.658206) (xy 134.95782 -82.421476)
			(xy 192.76136 -82.421476) (xy 192.765431 -82.365854) (xy 192.777557 -82.311417) (xy 192.79748 -82.259326)
			(xy 192.824776 -82.210691) (xy 192.858862 -82.166548) (xy 192.899011 -82.127839) (xy 192.944369 -82.095388)
			(xy 192.993969 -82.069887) (xy 193.046753 -82.05188) (xy 193.101596 -82.04175) (xy 193.15733 -82.039713)
			(xy 193.212767 -82.045813) (xy 193.266724 -82.059919) (xy 193.318053 -82.081731) (xy 193.365659 -82.110785)
			(xy 193.408527 -82.14646) (xy 193.445744 -82.187997) (xy 193.476517 -82.23451) (xy 193.500189 -82.285007)
			(xy 193.516257 -82.338414) (xy 193.524377 -82.39359) (xy 193.524886 -82.421476) (xy 193.524377 -82.449362)
			(xy 193.516257 -82.504538) (xy 193.500189 -82.557945) (xy 193.476517 -82.608442) (xy 193.445744 -82.654955)
			(xy 193.408527 -82.696492) (xy 193.365659 -82.732167) (xy 193.318053 -82.761221) (xy 193.266724 -82.783033)
			(xy 193.212767 -82.797139) (xy 193.15733 -82.803239) (xy 193.101596 -82.801202) (xy 193.046753 -82.791072)
			(xy 192.993969 -82.773065) (xy 192.944369 -82.747564) (xy 192.899011 -82.715113) (xy 192.858862 -82.676404)
			(xy 192.824776 -82.632261) (xy 192.79748 -82.583626) (xy 192.777557 -82.531535) (xy 192.765431 -82.477098)
			(xy 192.76136 -82.421476) (xy 134.95782 -82.421476) (xy 133.656578 -83.722718) (xy 133.649182 -83.72957)
			(xy 133.630583 -83.737309) (xy 133.62051 -83.737704) (xy 129.45237 -83.737704) (xy 129.44636 -83.737869)
			(xy 129.434675 -83.740689) (xy 129.429256 -83.743292) (xy 129.425783 -83.745133) (xy 129.419406 -83.749728)
			(xy 129.416556 -83.752436) (xy 128.836674 -84.332318) (xy 192.411858 -84.332318) (xy 192.412295 -84.305713)
			(xy 192.419676 -84.253019) (xy 192.43431 -84.201862) (xy 192.455914 -84.153236) (xy 192.484068 -84.108085)
			(xy 192.518225 -84.067287) (xy 192.557722 -84.031633) (xy 192.579498 -84.016342) (xy 192.591009 -84.008047)
			(xy 192.609214 -83.986295) (xy 192.62073 -83.960373) (xy 192.624666 -83.932282) (xy 192.62072 -83.904193)
			(xy 192.609195 -83.878274) (xy 192.590983 -83.856529) (xy 192.579498 -83.848194) (xy 192.557729 -83.832897)
			(xy 192.518247 -83.797233) (xy 192.484102 -83.756431) (xy 192.455955 -83.711281) (xy 192.434353 -83.66266)
			(xy 192.419713 -83.611509) (xy 192.41232 -83.55882) (xy 192.411858 -83.532218) (xy 192.412344 -83.504967)
			(xy 192.4201 -83.451019) (xy 192.435455 -83.398724) (xy 192.458097 -83.349147) (xy 192.487563 -83.303297)
			(xy 192.523254 -83.262106) (xy 192.564445 -83.226415) (xy 192.610295 -83.196949) (xy 192.659872 -83.174307)
			(xy 192.712167 -83.158952) (xy 192.766115 -83.151196) (xy 192.820617 -83.151196) (xy 192.874565 -83.158952)
			(xy 192.92686 -83.174307) (xy 192.976437 -83.196949) (xy 193.022287 -83.226415) (xy 193.063478 -83.262106)
			(xy 193.099169 -83.303297) (xy 193.128635 -83.349147) (xy 193.151277 -83.398724) (xy 193.166632 -83.451019)
			(xy 193.174388 -83.504967) (xy 193.174874 -83.532218) (xy 193.17445 -83.558823) (xy 193.167065 -83.611518)
			(xy 193.152428 -83.662674) (xy 193.130821 -83.7113) (xy 193.102666 -83.75645) (xy 193.068507 -83.797248)
			(xy 193.02901 -83.832902) (xy 193.007234 -83.848194) (xy 192.995782 -83.856566) (xy 192.977573 -83.878299)
			(xy 192.966051 -83.904205) (xy 192.962105 -83.932282) (xy 192.966041 -83.96036) (xy 192.977554 -83.98627)
			(xy 192.995755 -84.008009) (xy 193.007234 -84.016342) (xy 193.02898 -84.03167) (xy 193.068461 -84.06733)
			(xy 193.102607 -84.108127) (xy 193.130756 -84.153271) (xy 193.152362 -84.201888) (xy 193.167007 -84.253033)
			(xy 193.174407 -84.305717) (xy 193.174874 -84.332318) (xy 193.174388 -84.359569) (xy 193.166632 -84.413517)
			(xy 193.151277 -84.465812) (xy 193.128635 -84.515389) (xy 193.099169 -84.561239) (xy 193.063478 -84.60243)
			(xy 193.022287 -84.638121) (xy 192.976437 -84.667587) (xy 192.92686 -84.690229) (xy 192.874565 -84.705584)
			(xy 192.820617 -84.71334) (xy 192.766115 -84.71334) (xy 192.712167 -84.705584) (xy 192.659872 -84.690229)
			(xy 192.610295 -84.667587) (xy 192.564445 -84.638121) (xy 192.523254 -84.60243) (xy 192.487563 -84.561239)
			(xy 192.458097 -84.515389) (xy 192.435455 -84.465812) (xy 192.4201 -84.413517) (xy 192.412344 -84.359569)
			(xy 192.411858 -84.332318) (xy 128.836674 -84.332318) (xy 127.698439 -85.470553) (xy 146.479969 -85.470553)
			(xy 146.479969 -85.416047) (xy 146.487727 -85.362096) (xy 146.503083 -85.309799) (xy 146.525726 -85.260219)
			(xy 146.555195 -85.214366) (xy 146.59089 -85.173175) (xy 146.632084 -85.137482) (xy 146.677938 -85.108016)
			(xy 146.727519 -85.085376) (xy 146.779818 -85.070022) (xy 146.833769 -85.062268) (xy 146.861022 -85.061806)
			(xy 146.888221 -85.062316) (xy 146.94207 -85.070033) (xy 146.994275 -85.085322) (xy 147.04378 -85.107872)
			(xy 147.089579 -85.137225) (xy 147.130743 -85.172788) (xy 147.166438 -85.213838) (xy 147.195939 -85.259542)
			(xy 147.207732 -85.284056) (xy 147.21332 -85.296502) (xy 147.235672 -85.311996) (xy 147.337272 -85.320886)
			(xy 147.346233 -85.321277) (xy 147.363532 -85.316605) (xy 147.378145 -85.306234) (xy 147.3835 -85.299042)
			(xy 147.398837 -85.277588) (xy 147.434499 -85.238733) (xy 147.475167 -85.205156) (xy 147.520069 -85.177493)
			(xy 147.56835 -85.156273) (xy 147.619092 -85.141897) (xy 147.671329 -85.13464) (xy 147.697698 -85.134196)
			(xy 147.72586 -85.134727) (xy 147.781573 -85.143002) (xy 147.835465 -85.159373) (xy 147.886367 -85.183485)
			(xy 147.933174 -85.214813) (xy 147.97487 -85.252678) (xy 147.9931 -85.27415) (xy 147.998764 -85.280643)
			(xy 148.013414 -85.289695) (xy 148.030232 -85.293394) (xy 148.03882 -85.292692) (xy 148.123656 -85.282024)
			(xy 148.132142 -85.280709) (xy 148.147568 -85.273192) (xy 148.159597 -85.260953) (xy 148.163534 -85.253322)
			(xy 148.175467 -85.229168) (xy 148.205123 -85.184192) (xy 148.240811 -85.143833) (xy 148.281819 -85.108896)
			(xy 148.327334 -85.080072) (xy 148.37645 -85.057937) (xy 148.428192 -85.042929) (xy 148.481529 -85.035348)
			(xy 148.508466 -85.034882) (xy 148.53572 -85.035363) (xy 148.589673 -85.043116) (xy 148.641973 -85.058469)
			(xy 148.691557 -85.081108) (xy 148.737413 -85.110575) (xy 148.778608 -85.146268) (xy 148.814305 -85.18746)
			(xy 148.843775 -85.233314) (xy 148.86642 -85.282895) (xy 148.881777 -85.335194) (xy 148.889535 -85.389146)
			(xy 148.889535 -85.443654) (xy 148.881777 -85.497606) (xy 148.86642 -85.549905) (xy 148.843775 -85.599486)
			(xy 148.814305 -85.64534) (xy 148.778608 -85.686532) (xy 148.737413 -85.722225) (xy 148.691557 -85.751692)
			(xy 148.641973 -85.774331) (xy 148.589673 -85.789684) (xy 148.53572 -85.797437) (xy 148.508466 -85.797898)
			(xy 148.480303 -85.797394) (xy 148.424589 -85.789114) (xy 148.370696 -85.772737) (xy 148.319794 -85.748621)
			(xy 148.272988 -85.717288) (xy 148.231293 -85.679418) (xy 148.213064 -85.657944) (xy 148.207365 -85.651485)
			(xy 148.192732 -85.642426) (xy 148.175928 -85.63871) (xy 148.167344 -85.639402) (xy 148.082508 -85.65007)
			(xy 148.074018 -85.651366) (xy 148.058593 -85.658893) (xy 148.046566 -85.671138) (xy 148.04263 -85.678772)
			(xy 148.030723 -85.702939) (xy 148.001063 -85.747916) (xy 147.965372 -85.788275) (xy 147.92436 -85.823212)
			(xy 147.878841 -85.852034) (xy 147.829721 -85.874167) (xy 147.777977 -85.889172) (xy 147.724636 -85.896749)
			(xy 147.697698 -85.897212) (xy 147.670497 -85.896733) (xy 147.616645 -85.889016) (xy 147.564436 -85.873727)
			(xy 147.51493 -85.851174) (xy 147.46913 -85.821816) (xy 147.427966 -85.786247) (xy 147.392274 -85.745191)
			(xy 147.362778 -85.69948) (xy 147.350988 -85.674962) (xy 147.3454 -85.662516) (xy 147.323048 -85.647022)
			(xy 147.221448 -85.638132) (xy 147.212487 -85.637674) (xy 147.195181 -85.642374) (xy 147.18057 -85.652771)
			(xy 147.17522 -85.659976) (xy 147.159876 -85.681425) (xy 147.124215 -85.720279) (xy 147.083547 -85.753856)
			(xy 147.038647 -85.781519) (xy 146.990367 -85.80274) (xy 146.939627 -85.817118) (xy 146.887391 -85.824377)
			(xy 146.861022 -85.824822) (xy 146.833769 -85.824332) (xy 146.779818 -85.816578) (xy 146.727519 -85.801224)
			(xy 146.677938 -85.778584) (xy 146.632084 -85.749118) (xy 146.59089 -85.713425) (xy 146.555195 -85.672234)
			(xy 146.525726 -85.626381) (xy 146.503083 -85.576801) (xy 146.487727 -85.524504) (xy 146.479969 -85.470553)
			(xy 127.698439 -85.470553) (xy 126.914539 -86.254453) (xy 173.064636 -86.254453) (xy 173.064636 -86.199947)
			(xy 173.072393 -86.145995) (xy 173.087748 -86.093696) (xy 173.11039 -86.044115) (xy 173.139858 -85.998261)
			(xy 173.175551 -85.957066) (xy 173.216743 -85.921371) (xy 173.262596 -85.891901) (xy 173.312176 -85.869256)
			(xy 173.364473 -85.853897) (xy 173.418425 -85.846137) (xy 173.445678 -85.84565) (xy 173.475291 -85.846176)
			(xy 173.533806 -85.855326) (xy 173.590203 -85.873409) (xy 173.643129 -85.89999) (xy 173.69131 -85.934432)
			(xy 173.73359 -85.975906) (xy 173.768952 -86.023416) (xy 173.783244 -86.049358) (xy 173.790363 -86.061789)
			(xy 173.810223 -86.082415) (xy 173.83503 -86.096714) (xy 173.862832 -86.103561) (xy 173.891441 -86.102417)
			(xy 173.918608 -86.093373) (xy 173.942194 -86.07714) (xy 173.951646 -86.066376) (xy 173.96986 -86.044889)
			(xy 174.011555 -86.007015) (xy 174.058363 -85.97568) (xy 174.109269 -85.951565) (xy 174.163166 -85.935194)
			(xy 174.218884 -85.926923) (xy 174.247048 -85.926422) (xy 174.274299 -85.926851) (xy 174.328246 -85.934614)
			(xy 174.380539 -85.949974) (xy 174.430114 -85.97262) (xy 174.475962 -86.00209) (xy 174.51715 -86.037784)
			(xy 174.552839 -86.078976) (xy 174.582303 -86.124828) (xy 174.604943 -86.174406) (xy 174.620296 -86.226701)
			(xy 174.624233 -86.254082) (xy 174.747426 -86.254082) (xy 174.751497 -86.19846) (xy 174.763623 -86.144023)
			(xy 174.783546 -86.091932) (xy 174.810842 -86.043297) (xy 174.844928 -85.999154) (xy 174.885077 -85.960445)
			(xy 174.930435 -85.927994) (xy 174.980035 -85.902493) (xy 175.032819 -85.884486) (xy 175.087662 -85.874356)
			(xy 175.143396 -85.872319) (xy 175.198833 -85.878419) (xy 175.25279 -85.892525) (xy 175.304119 -85.914337)
			(xy 175.351725 -85.943391) (xy 175.394593 -85.979066) (xy 175.43181 -86.020603) (xy 175.462583 -86.067116)
			(xy 175.486255 -86.117613) (xy 175.502323 -86.17102) (xy 175.510443 -86.226196) (xy 175.510841 -86.247986)
			(xy 191.338452 -86.247986) (xy 191.342523 -86.192364) (xy 191.354649 -86.137927) (xy 191.374572 -86.085836)
			(xy 191.401868 -86.037201) (xy 191.435954 -85.993058) (xy 191.476103 -85.954349) (xy 191.521461 -85.921898)
			(xy 191.571061 -85.896397) (xy 191.623845 -85.87839) (xy 191.678688 -85.86826) (xy 191.734422 -85.866223)
			(xy 191.789859 -85.872323) (xy 191.843816 -85.886429) (xy 191.895145 -85.908241) (xy 191.942751 -85.937295)
			(xy 191.985619 -85.97297) (xy 192.022836 -86.014507) (xy 192.053609 -86.06102) (xy 192.077281 -86.111517)
			(xy 192.093349 -86.164924) (xy 192.101469 -86.2201) (xy 192.101978 -86.247986) (xy 192.101469 -86.275872)
			(xy 192.093349 -86.331048) (xy 192.077281 -86.384455) (xy 192.053609 -86.434952) (xy 192.022836 -86.481465)
			(xy 191.985619 -86.523002) (xy 191.942751 -86.558677) (xy 191.895145 -86.587731) (xy 191.843816 -86.609543)
			(xy 191.789859 -86.623649) (xy 191.734422 -86.629749) (xy 191.678688 -86.627712) (xy 191.623845 -86.617582)
			(xy 191.571061 -86.599575) (xy 191.521461 -86.574074) (xy 191.476103 -86.541623) (xy 191.435954 -86.502914)
			(xy 191.401868 -86.458771) (xy 191.374572 -86.410136) (xy 191.354649 -86.358045) (xy 191.342523 -86.303608)
			(xy 191.338452 -86.247986) (xy 175.510841 -86.247986) (xy 175.510952 -86.254082) (xy 175.510443 -86.281968)
			(xy 175.502323 -86.337144) (xy 175.486255 -86.390551) (xy 175.462583 -86.441048) (xy 175.43181 -86.487561)
			(xy 175.394593 -86.529098) (xy 175.351725 -86.564773) (xy 175.304119 -86.593827) (xy 175.25279 -86.615639)
			(xy 175.198833 -86.629745) (xy 175.143396 -86.635845) (xy 175.087662 -86.633808) (xy 175.032819 -86.623678)
			(xy 174.980035 -86.605671) (xy 174.930435 -86.58017) (xy 174.885077 -86.547719) (xy 174.844928 -86.50901)
			(xy 174.810842 -86.464867) (xy 174.783546 -86.416232) (xy 174.763623 -86.364141) (xy 174.751497 -86.309704)
			(xy 174.747426 -86.254082) (xy 174.624233 -86.254082) (xy 174.628052 -86.280649) (xy 174.628052 -86.335151)
			(xy 174.620296 -86.389099) (xy 174.604943 -86.441394) (xy 174.582303 -86.490972) (xy 174.552839 -86.536824)
			(xy 174.51715 -86.578016) (xy 174.475962 -86.61371) (xy 174.430114 -86.64318) (xy 174.380539 -86.665826)
			(xy 174.328246 -86.681186) (xy 174.274299 -86.688949) (xy 174.247048 -86.689438) (xy 174.217436 -86.688897)
			(xy 174.158921 -86.679751) (xy 174.102524 -86.661671) (xy 174.049598 -86.635092) (xy 174.001416 -86.600652)
			(xy 173.959136 -86.55918) (xy 173.923774 -86.511671) (xy 173.909482 -86.48573) (xy 173.902328 -86.473321)
			(xy 173.882475 -86.452699) (xy 173.857675 -86.438402) (xy 173.829881 -86.431553) (xy 173.801278 -86.432692)
			(xy 173.774116 -86.441729) (xy 173.750532 -86.457953) (xy 173.74108 -86.468712) (xy 173.722849 -86.490184)
			(xy 173.681158 -86.52806) (xy 173.634353 -86.559397) (xy 173.583451 -86.583514) (xy 173.529557 -86.599888)
			(xy 173.473841 -86.608164) (xy 173.445678 -86.608666) (xy 173.418425 -86.608263) (xy 173.364473 -86.600503)
			(xy 173.312176 -86.585144) (xy 173.262596 -86.562499) (xy 173.216743 -86.533029) (xy 173.175551 -86.497334)
			(xy 173.139858 -86.456139) (xy 173.11039 -86.410285) (xy 173.087748 -86.360704) (xy 173.072393 -86.308405)
			(xy 173.064636 -86.254453) (xy 126.914539 -86.254453) (xy 126.219966 -86.949026) (xy 193.648074 -86.949026)
			(xy 193.652145 -86.893404) (xy 193.664271 -86.838967) (xy 193.684194 -86.786876) (xy 193.71149 -86.738241)
			(xy 193.745576 -86.694098) (xy 193.785725 -86.655389) (xy 193.831083 -86.622938) (xy 193.880683 -86.597437)
			(xy 193.933467 -86.57943) (xy 193.98831 -86.5693) (xy 194.044044 -86.567263) (xy 194.099481 -86.573363)
			(xy 194.153438 -86.587469) (xy 194.204767 -86.609281) (xy 194.252373 -86.638335) (xy 194.295241 -86.67401)
			(xy 194.332458 -86.715547) (xy 194.363231 -86.76206) (xy 194.386903 -86.812557) (xy 194.402971 -86.865964)
			(xy 194.411091 -86.92114) (xy 194.4116 -86.949026) (xy 194.411091 -86.976912) (xy 194.402971 -87.032088)
			(xy 194.386903 -87.085495) (xy 194.363231 -87.135992) (xy 194.332458 -87.182505) (xy 194.295241 -87.224042)
			(xy 194.252373 -87.259717) (xy 194.204767 -87.288771) (xy 194.153438 -87.310583) (xy 194.099481 -87.324689)
			(xy 194.044044 -87.330789) (xy 193.98831 -87.328752) (xy 193.933467 -87.318622) (xy 193.880683 -87.300615)
			(xy 193.831083 -87.275114) (xy 193.785725 -87.242663) (xy 193.745576 -87.203954) (xy 193.71149 -87.159811)
			(xy 193.684194 -87.111176) (xy 193.664271 -87.059085) (xy 193.652145 -87.004648) (xy 193.648074 -86.949026)
			(xy 126.219966 -86.949026) (xy 125.35535 -87.813642) (xy 139.708126 -87.813642) (xy 139.712197 -87.75802)
			(xy 139.724323 -87.703583) (xy 139.744246 -87.651492) (xy 139.771542 -87.602857) (xy 139.805628 -87.558714)
			(xy 139.845777 -87.520005) (xy 139.891135 -87.487554) (xy 139.940735 -87.462053) (xy 139.993519 -87.444046)
			(xy 140.048362 -87.433916) (xy 140.104096 -87.431879) (xy 140.159533 -87.437979) (xy 140.21349 -87.452085)
			(xy 140.264819 -87.473897) (xy 140.312425 -87.502951) (xy 140.355293 -87.538626) (xy 140.39251 -87.580163)
			(xy 140.423283 -87.626676) (xy 140.446955 -87.677173) (xy 140.463023 -87.73058) (xy 140.471143 -87.785756)
			(xy 140.471652 -87.813642) (xy 140.471143 -87.841528) (xy 140.463023 -87.896704) (xy 140.446955 -87.950111)
			(xy 140.423283 -88.000608) (xy 140.39251 -88.047121) (xy 140.355293 -88.088658) (xy 140.312425 -88.124333)
			(xy 140.264819 -88.153387) (xy 140.21349 -88.175199) (xy 140.159533 -88.189305) (xy 140.104096 -88.195405)
			(xy 140.048362 -88.193368) (xy 139.993519 -88.183238) (xy 139.940735 -88.165231) (xy 139.891135 -88.13973)
			(xy 139.845777 -88.107279) (xy 139.805628 -88.06857) (xy 139.771542 -88.024427) (xy 139.744246 -87.975792)
			(xy 139.724323 -87.923701) (xy 139.712197 -87.869264) (xy 139.708126 -87.813642) (xy 125.35535 -87.813642)
			(xy 123.992386 -89.176606) (xy 124.546104 -89.176606) (xy 124.550175 -89.120984) (xy 124.562301 -89.066547)
			(xy 124.582224 -89.014456) (xy 124.60952 -88.965821) (xy 124.643606 -88.921678) (xy 124.683755 -88.882969)
			(xy 124.729113 -88.850518) (xy 124.778713 -88.825017) (xy 124.831497 -88.80701) (xy 124.88634 -88.79688)
			(xy 124.942074 -88.794843) (xy 124.997511 -88.800943) (xy 125.051468 -88.815049) (xy 125.102797 -88.836861)
			(xy 125.150403 -88.865915) (xy 125.193271 -88.90159) (xy 125.230488 -88.943127) (xy 125.261261 -88.98964)
			(xy 125.284933 -89.040137) (xy 125.301001 -89.093544) (xy 125.309121 -89.14872) (xy 125.30963 -89.176606)
			(xy 125.309121 -89.204492) (xy 125.3053 -89.230454) (xy 133.320534 -89.230454) (xy 133.324605 -89.174832)
			(xy 133.336731 -89.120395) (xy 133.356654 -89.068304) (xy 133.38395 -89.019669) (xy 133.418036 -88.975526)
			(xy 133.458185 -88.936817) (xy 133.503543 -88.904366) (xy 133.553143 -88.878865) (xy 133.605927 -88.860858)
			(xy 133.66077 -88.850728) (xy 133.716504 -88.848691) (xy 133.771941 -88.854791) (xy 133.825898 -88.868897)
			(xy 133.877227 -88.890709) (xy 133.924833 -88.919763) (xy 133.967701 -88.955438) (xy 134.004918 -88.996975)
			(xy 134.035691 -89.043488) (xy 134.059363 -89.093985) (xy 134.075431 -89.147392) (xy 134.083551 -89.202568)
			(xy 134.08406 -89.230454) (xy 134.083551 -89.25834) (xy 134.075431 -89.313516) (xy 134.059363 -89.366923)
			(xy 134.035691 -89.41742) (xy 134.004918 -89.463933) (xy 133.967701 -89.50547) (xy 133.924833 -89.541145)
			(xy 133.877227 -89.570199) (xy 133.825898 -89.592011) (xy 133.771941 -89.606117) (xy 133.716504 -89.612217)
			(xy 133.66077 -89.61018) (xy 133.605927 -89.60005) (xy 133.553143 -89.582043) (xy 133.503543 -89.556542)
			(xy 133.458185 -89.524091) (xy 133.418036 -89.485382) (xy 133.38395 -89.441239) (xy 133.356654 -89.392604)
			(xy 133.336731 -89.340513) (xy 133.324605 -89.286076) (xy 133.320534 -89.230454) (xy 125.3053 -89.230454)
			(xy 125.301001 -89.259668) (xy 125.284933 -89.313075) (xy 125.261261 -89.363572) (xy 125.230488 -89.410085)
			(xy 125.193271 -89.451622) (xy 125.150403 -89.487297) (xy 125.102797 -89.516351) (xy 125.051468 -89.538163)
			(xy 124.997511 -89.552269) (xy 124.942074 -89.558369) (xy 124.88634 -89.556332) (xy 124.831497 -89.546202)
			(xy 124.778713 -89.528195) (xy 124.729113 -89.502694) (xy 124.683755 -89.470243) (xy 124.643606 -89.431534)
			(xy 124.60952 -89.387391) (xy 124.582224 -89.338756) (xy 124.562301 -89.286665) (xy 124.550175 -89.232228)
			(xy 124.546104 -89.176606) (xy 123.992386 -89.176606) (xy 123.111006 -90.057986) (xy 125.963678 -90.057986)
			(xy 125.967749 -90.002364) (xy 125.979875 -89.947927) (xy 125.999798 -89.895836) (xy 126.027094 -89.847201)
			(xy 126.06118 -89.803058) (xy 126.101329 -89.764349) (xy 126.146687 -89.731898) (xy 126.196287 -89.706397)
			(xy 126.249071 -89.68839) (xy 126.303914 -89.67826) (xy 126.359648 -89.676223) (xy 126.415085 -89.682323)
			(xy 126.469042 -89.696429) (xy 126.520371 -89.718241) (xy 126.567977 -89.747295) (xy 126.610845 -89.78297)
			(xy 126.648062 -89.824507) (xy 126.678835 -89.87102) (xy 126.702507 -89.921517) (xy 126.709941 -89.946226)
			(xy 132.766306 -89.946226) (xy 132.770377 -89.890604) (xy 132.782503 -89.836167) (xy 132.802426 -89.784076)
			(xy 132.829722 -89.735441) (xy 132.863808 -89.691298) (xy 132.903957 -89.652589) (xy 132.949315 -89.620138)
			(xy 132.998915 -89.594637) (xy 133.051699 -89.57663) (xy 133.106542 -89.5665) (xy 133.162276 -89.564463)
			(xy 133.217713 -89.570563) (xy 133.27167 -89.584669) (xy 133.322999 -89.606481) (xy 133.370605 -89.635535)
			(xy 133.413473 -89.67121) (xy 133.45069 -89.712747) (xy 133.481463 -89.75926) (xy 133.505135 -89.809757)
			(xy 133.521203 -89.863164) (xy 133.529323 -89.91834) (xy 133.529832 -89.946226) (xy 133.529323 -89.974112)
			(xy 133.527708 -89.985088) (xy 134.64794 -89.985088) (xy 134.648464 -89.956241) (xy 134.657139 -89.899202)
			(xy 134.674305 -89.84412) (xy 134.69957 -89.792252) (xy 134.732359 -89.74478) (xy 134.771922 -89.702787)
			(xy 134.817358 -89.66723) (xy 134.86763 -89.638922) (xy 134.921592 -89.618507) (xy 134.949692 -89.611962)
			(xy 134.96036 -89.609676) (xy 134.977632 -89.59723) (xy 135.026146 -89.513156) (xy 135.028686 -89.492328)
			(xy 135.025384 -89.482168) (xy 135.025384 -89.48166) (xy 135.016988 -89.453572) (xy 135.007926 -89.395654)
			(xy 135.00735 -89.366344) (xy 135.00735 -89.36609) (xy 135.007976 -89.334812) (xy 135.018203 -89.273097)
			(xy 135.03835 -89.213874) (xy 135.052562 -89.186004) (xy 135.058404 -89.175082) (xy 135.058658 -89.150444)
			(xy 135.010398 -89.053924) (xy 134.99084 -89.0397) (xy 134.978648 -89.037668) (xy 134.978394 -89.037668)
			(xy 134.951664 -89.033137) (xy 134.89975 -89.017513) (xy 134.850571 -88.994697) (xy 134.805118 -88.965148)
			(xy 134.764306 -88.929462) (xy 134.728958 -88.888356) (xy 134.699786 -88.84266) (xy 134.677377 -88.793294)
			(xy 134.662183 -88.741253) (xy 134.654511 -88.687585) (xy 134.654036 -88.660478) (xy 134.654522 -88.633227)
			(xy 134.662278 -88.579279) (xy 134.677633 -88.526984) (xy 134.700275 -88.477407) (xy 134.729741 -88.431557)
			(xy 134.765432 -88.390366) (xy 134.806623 -88.354675) (xy 134.852473 -88.325209) (xy 134.90205 -88.302567)
			(xy 134.954345 -88.287212) (xy 135.008293 -88.279456) (xy 135.062795 -88.279456) (xy 135.116743 -88.287212)
			(xy 135.169038 -88.302567) (xy 135.218615 -88.325209) (xy 135.264465 -88.354675) (xy 135.305656 -88.390366)
			(xy 135.341347 -88.431557) (xy 135.370813 -88.477407) (xy 135.393455 -88.526984) (xy 135.40881 -88.579279)
			(xy 135.416566 -88.633227) (xy 135.417052 -88.660478) (xy 135.417052 -88.660732) (xy 135.416395 -88.692008)
			(xy 135.406181 -88.753722) (xy 135.386046 -88.812947) (xy 135.37184 -88.840818) (xy 135.365998 -88.85174)
			(xy 135.365744 -88.876378) (xy 135.405876 -88.956642) (xy 139.708126 -88.956642) (xy 139.712197 -88.90102)
			(xy 139.724323 -88.846583) (xy 139.744246 -88.794492) (xy 139.771542 -88.745857) (xy 139.805628 -88.701714)
			(xy 139.845777 -88.663005) (xy 139.891135 -88.630554) (xy 139.940735 -88.605053) (xy 139.993519 -88.587046)
			(xy 140.048362 -88.576916) (xy 140.104096 -88.574879) (xy 140.159533 -88.580979) (xy 140.21349 -88.595085)
			(xy 140.264819 -88.616897) (xy 140.312425 -88.645951) (xy 140.355293 -88.681626) (xy 140.39251 -88.723163)
			(xy 140.423283 -88.769676) (xy 140.446955 -88.820173) (xy 140.463023 -88.87358) (xy 140.471143 -88.928756)
			(xy 140.471652 -88.956642) (xy 140.471143 -88.984528) (xy 140.463023 -89.039704) (xy 140.446955 -89.093111)
			(xy 140.423283 -89.143608) (xy 140.39251 -89.190121) (xy 140.355293 -89.231658) (xy 140.312425 -89.267333)
			(xy 140.264819 -89.296387) (xy 140.21349 -89.318199) (xy 140.159533 -89.332305) (xy 140.104096 -89.338405)
			(xy 140.048362 -89.336368) (xy 139.993519 -89.326238) (xy 139.940735 -89.308231) (xy 139.891135 -89.28273)
			(xy 139.845777 -89.250279) (xy 139.805628 -89.21157) (xy 139.771542 -89.167427) (xy 139.744246 -89.118792)
			(xy 139.724323 -89.066701) (xy 139.712197 -89.012264) (xy 139.708126 -88.956642) (xy 135.405876 -88.956642)
			(xy 135.414004 -88.972898) (xy 135.433562 -88.987122) (xy 135.445754 -88.989154) (xy 135.446008 -88.989154)
			(xy 135.472742 -88.993663) (xy 135.524658 -89.009287) (xy 135.573838 -89.032105) (xy 135.619292 -89.061657)
			(xy 135.660104 -89.097346) (xy 135.695452 -89.138454) (xy 135.724624 -89.184153) (xy 135.747031 -89.233522)
			(xy 135.762223 -89.285565) (xy 135.769893 -89.339236) (xy 135.770366 -89.366344) (xy 135.769866 -89.395192)
			(xy 135.761186 -89.452232) (xy 135.744016 -89.507313) (xy 135.718748 -89.559182) (xy 135.685956 -89.606654)
			(xy 135.646391 -89.648646) (xy 135.600952 -89.684202) (xy 135.550678 -89.71251) (xy 135.496715 -89.732925)
			(xy 135.468614 -89.73947) (xy 135.457946 -89.741756) (xy 135.440674 -89.754202) (xy 135.39216 -89.838276)
			(xy 135.38962 -89.859104) (xy 135.392922 -89.869264) (xy 135.392922 -89.869772) (xy 135.401326 -89.897858)
			(xy 135.410383 -89.955777) (xy 135.410956 -89.985088) (xy 135.41047 -90.012339) (xy 135.402714 -90.066287)
			(xy 135.39292 -90.099642) (xy 139.708126 -90.099642) (xy 139.712197 -90.04402) (xy 139.724323 -89.989583)
			(xy 139.744246 -89.937492) (xy 139.771542 -89.888857) (xy 139.805628 -89.844714) (xy 139.845777 -89.806005)
			(xy 139.891135 -89.773554) (xy 139.940735 -89.748053) (xy 139.993519 -89.730046) (xy 140.048362 -89.719916)
			(xy 140.104096 -89.717879) (xy 140.159533 -89.723979) (xy 140.21349 -89.738085) (xy 140.264819 -89.759897)
			(xy 140.312425 -89.788951) (xy 140.355293 -89.824626) (xy 140.39251 -89.866163) (xy 140.418928 -89.906094)
			(xy 192.562478 -89.906094) (xy 192.566549 -89.850472) (xy 192.578675 -89.796035) (xy 192.598598 -89.743944)
			(xy 192.625894 -89.695309) (xy 192.65998 -89.651166) (xy 192.700129 -89.612457) (xy 192.745487 -89.580006)
			(xy 192.795087 -89.554505) (xy 192.847871 -89.536498) (xy 192.902714 -89.526368) (xy 192.958448 -89.524331)
			(xy 193.013885 -89.530431) (xy 193.067842 -89.544537) (xy 193.119171 -89.566349) (xy 193.166777 -89.595403)
			(xy 193.209645 -89.631078) (xy 193.246862 -89.672615) (xy 193.277635 -89.719128) (xy 193.301307 -89.769625)
			(xy 193.317375 -89.823032) (xy 193.325495 -89.878208) (xy 193.326004 -89.906094) (xy 193.325495 -89.93398)
			(xy 193.317375 -89.989156) (xy 193.301307 -90.042563) (xy 193.277635 -90.09306) (xy 193.246862 -90.139573)
			(xy 193.209645 -90.18111) (xy 193.166777 -90.216785) (xy 193.119171 -90.245839) (xy 193.067842 -90.267651)
			(xy 193.013885 -90.281757) (xy 192.958448 -90.287857) (xy 192.902714 -90.28582) (xy 192.847871 -90.27569)
			(xy 192.795087 -90.257683) (xy 192.745487 -90.232182) (xy 192.700129 -90.199731) (xy 192.65998 -90.161022)
			(xy 192.625894 -90.116879) (xy 192.598598 -90.068244) (xy 192.578675 -90.016153) (xy 192.566549 -89.961716)
			(xy 192.562478 -89.906094) (xy 140.418928 -89.906094) (xy 140.423283 -89.912676) (xy 140.446955 -89.963173)
			(xy 140.463023 -90.01658) (xy 140.471143 -90.071756) (xy 140.471652 -90.099642) (xy 140.471143 -90.127528)
			(xy 140.463023 -90.182704) (xy 140.446955 -90.236111) (xy 140.423283 -90.286608) (xy 140.39251 -90.333121)
			(xy 140.355293 -90.374658) (xy 140.312425 -90.410333) (xy 140.264819 -90.439387) (xy 140.21349 -90.461199)
			(xy 140.159533 -90.475305) (xy 140.104096 -90.481405) (xy 140.048362 -90.479368) (xy 139.993519 -90.469238)
			(xy 139.940735 -90.451231) (xy 139.891135 -90.42573) (xy 139.845777 -90.393279) (xy 139.805628 -90.35457)
			(xy 139.771542 -90.310427) (xy 139.744246 -90.261792) (xy 139.724323 -90.209701) (xy 139.712197 -90.155264)
			(xy 139.708126 -90.099642) (xy 135.39292 -90.099642) (xy 135.387359 -90.118582) (xy 135.364717 -90.168159)
			(xy 135.335251 -90.214009) (xy 135.29956 -90.2552) (xy 135.258369 -90.290891) (xy 135.212519 -90.320357)
			(xy 135.162942 -90.342999) (xy 135.110647 -90.358354) (xy 135.056699 -90.36611) (xy 135.002197 -90.36611)
			(xy 134.948249 -90.358354) (xy 134.895954 -90.342999) (xy 134.846377 -90.320357) (xy 134.800527 -90.290891)
			(xy 134.759336 -90.2552) (xy 134.723645 -90.214009) (xy 134.694179 -90.168159) (xy 134.671537 -90.118582)
			(xy 134.656182 -90.066287) (xy 134.648426 -90.012339) (xy 134.64794 -89.985088) (xy 133.527708 -89.985088)
			(xy 133.521203 -90.029288) (xy 133.505135 -90.082695) (xy 133.481463 -90.133192) (xy 133.45069 -90.179705)
			(xy 133.413473 -90.221242) (xy 133.370605 -90.256917) (xy 133.322999 -90.285971) (xy 133.27167 -90.307783)
			(xy 133.217713 -90.321889) (xy 133.162276 -90.327989) (xy 133.106542 -90.325952) (xy 133.051699 -90.315822)
			(xy 132.998915 -90.297815) (xy 132.949315 -90.272314) (xy 132.903957 -90.239863) (xy 132.863808 -90.201154)
			(xy 132.829722 -90.157011) (xy 132.802426 -90.108376) (xy 132.782503 -90.056285) (xy 132.770377 -90.001848)
			(xy 132.766306 -89.946226) (xy 126.709941 -89.946226) (xy 126.718575 -89.974924) (xy 126.726695 -90.0301)
			(xy 126.727204 -90.057986) (xy 126.726695 -90.085872) (xy 126.718575 -90.141048) (xy 126.702507 -90.194455)
			(xy 126.678835 -90.244952) (xy 126.648062 -90.291465) (xy 126.610845 -90.333002) (xy 126.567977 -90.368677)
			(xy 126.520371 -90.397731) (xy 126.469042 -90.419543) (xy 126.415085 -90.433649) (xy 126.359648 -90.439749)
			(xy 126.303914 -90.437712) (xy 126.249071 -90.427582) (xy 126.196287 -90.409575) (xy 126.146687 -90.384074)
			(xy 126.101329 -90.351623) (xy 126.06118 -90.312914) (xy 126.027094 -90.268771) (xy 125.999798 -90.220136)
			(xy 125.979875 -90.168045) (xy 125.967749 -90.113608) (xy 125.963678 -90.057986) (xy 123.111006 -90.057986)
			(xy 122.462798 -90.706194) (xy 124.7935 -90.706194) (xy 124.797571 -90.650572) (xy 124.809697 -90.596135)
			(xy 124.82962 -90.544044) (xy 124.856916 -90.495409) (xy 124.891002 -90.451266) (xy 124.931151 -90.412557)
			(xy 124.976509 -90.380106) (xy 125.026109 -90.354605) (xy 125.078893 -90.336598) (xy 125.133736 -90.326468)
			(xy 125.18947 -90.324431) (xy 125.244907 -90.330531) (xy 125.298864 -90.344637) (xy 125.350193 -90.366449)
			(xy 125.397799 -90.395503) (xy 125.440667 -90.431178) (xy 125.477884 -90.472715) (xy 125.508657 -90.519228)
			(xy 125.532329 -90.569725) (xy 125.548016 -90.621866) (xy 180.64175 -90.621866) (xy 180.645821 -90.566244)
			(xy 180.657947 -90.511807) (xy 180.67787 -90.459716) (xy 180.705166 -90.411081) (xy 180.739252 -90.366938)
			(xy 180.779401 -90.328229) (xy 180.824759 -90.295778) (xy 180.874359 -90.270277) (xy 180.927143 -90.25227)
			(xy 180.981986 -90.24214) (xy 181.03772 -90.240103) (xy 181.093157 -90.246203) (xy 181.147114 -90.260309)
			(xy 181.198443 -90.282121) (xy 181.246049 -90.311175) (xy 181.288917 -90.34685) (xy 181.326134 -90.388387)
			(xy 181.356907 -90.4349) (xy 181.380579 -90.485397) (xy 181.396647 -90.538804) (xy 181.404767 -90.59398)
			(xy 181.405276 -90.621866) (xy 181.404767 -90.649752) (xy 181.396647 -90.704928) (xy 181.380579 -90.758335)
			(xy 181.356907 -90.808832) (xy 181.326134 -90.855345) (xy 181.288917 -90.896882) (xy 181.246049 -90.932557)
			(xy 181.198443 -90.961611) (xy 181.147114 -90.983423) (xy 181.093157 -90.997529) (xy 181.03772 -91.003629)
			(xy 180.981986 -91.001592) (xy 180.927143 -90.991462) (xy 180.874359 -90.973455) (xy 180.824759 -90.947954)
			(xy 180.779401 -90.915503) (xy 180.739252 -90.876794) (xy 180.705166 -90.832651) (xy 180.67787 -90.784016)
			(xy 180.657947 -90.731925) (xy 180.645821 -90.677488) (xy 180.64175 -90.621866) (xy 125.548016 -90.621866)
			(xy 125.548397 -90.623132) (xy 125.556517 -90.678308) (xy 125.557026 -90.706194) (xy 125.556517 -90.73408)
			(xy 125.548397 -90.789256) (xy 125.532329 -90.842663) (xy 125.508657 -90.89316) (xy 125.477884 -90.939673)
			(xy 125.440667 -90.98121) (xy 125.397799 -91.016885) (xy 125.350193 -91.045939) (xy 125.298864 -91.067751)
			(xy 125.244907 -91.081857) (xy 125.18947 -91.087957) (xy 125.133736 -91.08592) (xy 125.078893 -91.07579)
			(xy 125.026109 -91.057783) (xy 124.976509 -91.032282) (xy 124.931151 -90.999831) (xy 124.891002 -90.961122)
			(xy 124.856916 -90.916979) (xy 124.82962 -90.868344) (xy 124.809697 -90.816253) (xy 124.797571 -90.761816)
			(xy 124.7935 -90.706194) (xy 122.462798 -90.706194) (xy 121.841514 -91.327478) (xy 134.913368 -91.327478)
			(xy 134.917439 -91.271856) (xy 134.929565 -91.217419) (xy 134.949488 -91.165328) (xy 134.976784 -91.116693)
			(xy 135.01087 -91.07255) (xy 135.051019 -91.033841) (xy 135.096377 -91.00139) (xy 135.145977 -90.975889)
			(xy 135.198761 -90.957882) (xy 135.253604 -90.947752) (xy 135.309338 -90.945715) (xy 135.364775 -90.951815)
			(xy 135.418732 -90.965921) (xy 135.470061 -90.987733) (xy 135.517667 -91.016787) (xy 135.560535 -91.052462)
			(xy 135.597752 -91.093999) (xy 135.628525 -91.140512) (xy 135.652197 -91.191009) (xy 135.667731 -91.242642)
			(xy 139.708126 -91.242642) (xy 139.712197 -91.18702) (xy 139.724323 -91.132583) (xy 139.744246 -91.080492)
			(xy 139.771542 -91.031857) (xy 139.805628 -90.987714) (xy 139.845777 -90.949005) (xy 139.891135 -90.916554)
			(xy 139.940735 -90.891053) (xy 139.993519 -90.873046) (xy 140.048362 -90.862916) (xy 140.104096 -90.860879)
			(xy 140.159533 -90.866979) (xy 140.21349 -90.881085) (xy 140.264819 -90.902897) (xy 140.312425 -90.931951)
			(xy 140.355293 -90.967626) (xy 140.39251 -91.009163) (xy 140.423283 -91.055676) (xy 140.446955 -91.106173)
			(xy 140.463023 -91.15958) (xy 140.471143 -91.214756) (xy 140.471652 -91.242642) (xy 140.471143 -91.270528)
			(xy 140.463023 -91.325704) (xy 140.446955 -91.379111) (xy 140.423283 -91.429608) (xy 140.39251 -91.476121)
			(xy 140.355293 -91.517658) (xy 140.312425 -91.553333) (xy 140.264819 -91.582387) (xy 140.21349 -91.604199)
			(xy 140.159533 -91.618305) (xy 140.104096 -91.624405) (xy 140.048362 -91.622368) (xy 139.993519 -91.612238)
			(xy 139.940735 -91.594231) (xy 139.891135 -91.56873) (xy 139.845777 -91.536279) (xy 139.805628 -91.49757)
			(xy 139.771542 -91.453427) (xy 139.744246 -91.404792) (xy 139.724323 -91.352701) (xy 139.712197 -91.298264)
			(xy 139.708126 -91.242642) (xy 135.667731 -91.242642) (xy 135.668265 -91.244416) (xy 135.676385 -91.299592)
			(xy 135.676894 -91.327478) (xy 135.676385 -91.355364) (xy 135.668265 -91.41054) (xy 135.652197 -91.463947)
			(xy 135.628525 -91.514444) (xy 135.597752 -91.560957) (xy 135.560535 -91.602494) (xy 135.517667 -91.638169)
			(xy 135.470061 -91.667223) (xy 135.418732 -91.689035) (xy 135.364775 -91.703141) (xy 135.309338 -91.709241)
			(xy 135.253604 -91.707204) (xy 135.198761 -91.697074) (xy 135.145977 -91.679067) (xy 135.096377 -91.653566)
			(xy 135.051019 -91.621115) (xy 135.01087 -91.582406) (xy 134.976784 -91.538263) (xy 134.949488 -91.489628)
			(xy 134.929565 -91.437537) (xy 134.917439 -91.3831) (xy 134.913368 -91.327478) (xy 121.841514 -91.327478)
			(xy 121.439432 -91.72956) (xy 121.432032 -91.7364) (xy 121.413433 -91.744116) (xy 121.403364 -91.744546)
			(xy 120.404128 -91.744546) (xy 120.399048 -91.7448) (xy 120.387618 -91.74734) (xy 120.364758 -91.755468)
			(xy 120.360186 -91.759024) (xy 120.337404 -91.776806) (xy 120.287536 -91.806012) (xy 120.233835 -91.827364)
			(xy 120.177527 -91.840374) (xy 120.119902 -91.844743) (xy 120.062277 -91.840374) (xy 120.005969 -91.827364)
			(xy 119.952268 -91.806012) (xy 119.9024 -91.776806) (xy 119.879618 -91.759024) (xy 119.875046 -91.755468)
			(xy 119.852186 -91.74734) (xy 119.840756 -91.7448) (xy 119.835676 -91.744546) (xy 118.933722 -91.744546)
			(xy 118.920514 -91.746324) (xy 118.902226 -91.751404) (xy 118.898924 -91.753182) (xy 118.89613 -91.75496)
			(xy 118.870908 -91.76914) (xy 118.817155 -91.790552) (xy 118.760784 -91.803599) (xy 118.70309 -91.807982)
			(xy 118.645396 -91.803599) (xy 118.589025 -91.790552) (xy 118.535272 -91.76914) (xy 118.51005 -91.75496)
			(xy 118.507256 -91.753182) (xy 118.503954 -91.751404) (xy 118.485666 -91.746324) (xy 118.472458 -91.744546)
			(xy 118.063264 -91.744546) (xy 118.057254 -91.744711) (xy 118.045569 -91.747529) (xy 118.04015 -91.750134)
			(xy 118.036678 -91.751976) (xy 118.030304 -91.756575) (xy 118.02745 -91.759278) (xy 117.606826 -92.179902)
			(xy 125.607824 -92.179902) (xy 125.611895 -92.12428) (xy 125.624021 -92.069843) (xy 125.643944 -92.017752)
			(xy 125.67124 -91.969117) (xy 125.705326 -91.924974) (xy 125.745475 -91.886265) (xy 125.790833 -91.853814)
			(xy 125.840433 -91.828313) (xy 125.893217 -91.810306) (xy 125.94806 -91.800176) (xy 126.003794 -91.798139)
			(xy 126.059231 -91.804239) (xy 126.113188 -91.818345) (xy 126.164517 -91.840157) (xy 126.212123 -91.869211)
			(xy 126.254991 -91.904886) (xy 126.292208 -91.946423) (xy 126.322981 -91.992936) (xy 126.346653 -92.043433)
			(xy 126.362721 -92.09684) (xy 126.370841 -92.152016) (xy 126.37135 -92.179902) (xy 126.370841 -92.207788)
			(xy 126.362721 -92.262964) (xy 126.346653 -92.316371) (xy 126.322981 -92.366868) (xy 126.292208 -92.413381)
			(xy 126.254991 -92.454918) (xy 126.212123 -92.490593) (xy 126.164517 -92.519647) (xy 126.113188 -92.541459)
			(xy 126.059231 -92.555565) (xy 126.003794 -92.561665) (xy 125.94806 -92.559628) (xy 125.893217 -92.549498)
			(xy 125.840433 -92.531491) (xy 125.790833 -92.50599) (xy 125.745475 -92.473539) (xy 125.705326 -92.43483)
			(xy 125.67124 -92.390687) (xy 125.643944 -92.342052) (xy 125.624021 -92.289961) (xy 125.611895 -92.235524)
			(xy 125.607824 -92.179902) (xy 117.606826 -92.179902) (xy 116.730028 -93.0567) (xy 118.042009 -93.0567)
			(xy 118.045895 -92.999883) (xy 118.057481 -92.944125) (xy 118.076551 -92.890463) (xy 118.102749 -92.839897)
			(xy 118.135589 -92.79337) (xy 118.174458 -92.751747) (xy 118.218632 -92.715803) (xy 118.267288 -92.68621)
			(xy 118.319521 -92.663516) (xy 118.374357 -92.648146) (xy 118.430775 -92.640385) (xy 118.45925 -92.639896)
			(xy 118.487537 -92.640362) (xy 118.543588 -92.648037) (xy 118.598086 -92.663223) (xy 118.650028 -92.685643)
			(xy 118.69846 -92.714885) (xy 118.74249 -92.750409) (xy 118.781309 -92.791564) (xy 118.814203 -92.837593)
			(xy 118.827804 -92.8624) (xy 118.834585 -92.874244) (xy 118.853187 -92.894194) (xy 118.876412 -92.9085)
			(xy 118.902598 -92.916137) (xy 118.929872 -92.916559) (xy 118.956282 -92.909736) (xy 118.979939 -92.896157)
			(xy 118.989856 -92.886784) (xy 119.011474 -92.865797) (xy 119.060105 -92.83023) (xy 119.113723 -92.802752)
			(xy 119.170995 -92.784045) (xy 119.230495 -92.774576) (xy 119.26062 -92.774008) (xy 119.287871 -92.774463)
			(xy 119.341819 -92.782222) (xy 119.394114 -92.79758) (xy 119.443691 -92.820223) (xy 119.48954 -92.849691)
			(xy 119.53073 -92.885384) (xy 119.566421 -92.926576) (xy 119.595887 -92.972427) (xy 119.618527 -93.022005)
			(xy 119.633882 -93.0743) (xy 119.641638 -93.128249) (xy 119.641638 -93.182751) (xy 119.633882 -93.2367)
			(xy 119.618527 -93.288995) (xy 119.595887 -93.338573) (xy 119.566421 -93.384424) (xy 119.53073 -93.425616)
			(xy 119.48954 -93.461309) (xy 119.443691 -93.490777) (xy 119.394114 -93.51342) (xy 119.341819 -93.528778)
			(xy 119.287871 -93.536537) (xy 119.26062 -93.537024) (xy 119.232423 -93.536505) (xy 119.176642 -93.528219)
			(xy 119.122689 -93.51181) (xy 119.071741 -93.487635) (xy 119.024907 -93.456222) (xy 118.98321 -93.418255)
			(xy 118.947557 -93.374562) (xy 118.932706 -93.350588) (xy 118.925367 -93.339083) (xy 118.905753 -93.320126)
			(xy 118.881817 -93.307044) (xy 118.85527 -93.300773) (xy 118.828011 -93.30176) (xy 118.801987 -93.309936)
			(xy 118.77906 -93.324715) (xy 118.769638 -93.334586) (xy 118.749782 -93.356007) (xy 118.705157 -93.393688)
			(xy 118.655706 -93.424767) (xy 118.602399 -93.448634) (xy 118.546282 -93.464823) (xy 118.488453 -93.473015)
			(xy 118.45925 -93.473524) (xy 118.430775 -93.473015) (xy 118.374357 -93.465254) (xy 118.319521 -93.449884)
			(xy 118.267288 -93.42719) (xy 118.218632 -93.397597) (xy 118.174458 -93.361653) (xy 118.135589 -93.32003)
			(xy 118.102749 -93.273503) (xy 118.076551 -93.222937) (xy 118.057481 -93.169275) (xy 118.045895 -93.113517)
			(xy 118.042009 -93.0567) (xy 116.730028 -93.0567) (xy 116.038122 -93.748606) (xy 119.737884 -93.748606)
			(xy 119.741955 -93.692984) (xy 119.754081 -93.638547) (xy 119.774004 -93.586456) (xy 119.8013 -93.537821)
			(xy 119.835386 -93.493678) (xy 119.875535 -93.454969) (xy 119.920893 -93.422518) (xy 119.970493 -93.397017)
			(xy 120.023277 -93.37901) (xy 120.07812 -93.36888) (xy 120.133854 -93.366843) (xy 120.189291 -93.372943)
			(xy 120.243248 -93.387049) (xy 120.294577 -93.408861) (xy 120.342183 -93.437915) (xy 120.385051 -93.47359)
			(xy 120.422268 -93.515127) (xy 120.453041 -93.56164) (xy 120.476713 -93.612137) (xy 120.492781 -93.665544)
			(xy 120.500901 -93.72072) (xy 120.50141 -93.748606) (xy 120.500901 -93.776492) (xy 120.492781 -93.831668)
			(xy 120.476713 -93.885075) (xy 120.453041 -93.935572) (xy 120.422268 -93.982085) (xy 120.385051 -94.023622)
			(xy 120.342183 -94.059297) (xy 120.294577 -94.088351) (xy 120.243248 -94.110163) (xy 120.189291 -94.124269)
			(xy 120.133854 -94.130369) (xy 120.07812 -94.128332) (xy 120.023277 -94.118202) (xy 119.970493 -94.100195)
			(xy 119.920893 -94.074694) (xy 119.875535 -94.042243) (xy 119.835386 -94.003534) (xy 119.8013 -93.959391)
			(xy 119.774004 -93.910756) (xy 119.754081 -93.858665) (xy 119.741955 -93.804228) (xy 119.737884 -93.748606)
			(xy 116.038122 -93.748606) (xy 115.563396 -94.223332) (xy 115.556792 -94.23146) (xy 115.551966 -94.239842)
			(xy 115.550188 -94.247208) (xy 115.543566 -94.272365) (xy 115.524426 -94.320735) (xy 115.498889 -94.366055)
			(xy 115.467429 -94.407483) (xy 115.43063 -94.44425) (xy 115.389174 -94.475674) (xy 115.343831 -94.501171)
			(xy 115.295444 -94.520268) (xy 115.27028 -94.526862) (xy 115.263168 -94.52864) (xy 115.25758 -94.531942)
			(xy 115.246658 -94.54007) (xy 114.895122 -94.891606) (xy 119.737884 -94.891606) (xy 119.741955 -94.835984)
			(xy 119.754081 -94.781547) (xy 119.774004 -94.729456) (xy 119.8013 -94.680821) (xy 119.835386 -94.636678)
			(xy 119.875535 -94.597969) (xy 119.920893 -94.565518) (xy 119.970493 -94.540017) (xy 120.023277 -94.52201)
			(xy 120.07812 -94.51188) (xy 120.133854 -94.509843) (xy 120.189291 -94.515943) (xy 120.243248 -94.530049)
			(xy 120.294577 -94.551861) (xy 120.342183 -94.580915) (xy 120.385051 -94.61659) (xy 120.422268 -94.658127)
			(xy 120.453041 -94.70464) (xy 120.476713 -94.755137) (xy 120.492781 -94.808544) (xy 120.500901 -94.86372)
			(xy 120.50141 -94.891606) (xy 120.500901 -94.919492) (xy 120.492781 -94.974668) (xy 120.476713 -95.028075)
			(xy 120.453041 -95.078572) (xy 120.422268 -95.125085) (xy 120.385051 -95.166622) (xy 120.342183 -95.202297)
			(xy 120.294577 -95.231351) (xy 120.243248 -95.253163) (xy 120.189291 -95.267269) (xy 120.133854 -95.273369)
			(xy 120.07812 -95.271332) (xy 120.023277 -95.261202) (xy 119.970493 -95.243195) (xy 119.920893 -95.217694)
			(xy 119.875535 -95.185243) (xy 119.835386 -95.146534) (xy 119.8013 -95.102391) (xy 119.774004 -95.053756)
			(xy 119.754081 -95.001665) (xy 119.741955 -94.947228) (xy 119.737884 -94.891606) (xy 114.895122 -94.891606)
			(xy 114.211608 -95.57512) (xy 114.207798 -95.586042) (xy 114.19694 -95.61476) (xy 114.167994 -95.668905)
			(xy 114.131419 -95.718216) (xy 114.088005 -95.761629) (xy 114.038692 -95.798203) (xy 113.984546 -95.827146)
			(xy 113.95583 -95.83801) (xy 113.944908 -95.84182) (xy 113.901982 -95.884746) (xy 113.895845 -95.891471)
			(xy 113.888351 -95.908048) (xy 113.887101 -95.926198) (xy 113.889282 -95.935038) (xy 113.900712 -95.973646)
			(xy 113.900712 -95.974154) (xy 113.91519 -96.022414) (xy 113.917041 -96.027458) (xy 113.921311 -96.034606)
			(xy 119.737884 -96.034606) (xy 119.741955 -95.978984) (xy 119.754081 -95.924547) (xy 119.774004 -95.872456)
			(xy 119.8013 -95.823821) (xy 119.835386 -95.779678) (xy 119.875535 -95.740969) (xy 119.920893 -95.708518)
			(xy 119.970493 -95.683017) (xy 120.023277 -95.66501) (xy 120.07812 -95.65488) (xy 120.133854 -95.652843)
			(xy 120.189291 -95.658943) (xy 120.243248 -95.673049) (xy 120.294577 -95.694861) (xy 120.342183 -95.723915)
			(xy 120.385051 -95.75959) (xy 120.422268 -95.801127) (xy 120.453041 -95.84764) (xy 120.476713 -95.898137)
			(xy 120.492781 -95.951544) (xy 120.500901 -96.00672) (xy 120.50141 -96.034606) (xy 120.500901 -96.062492)
			(xy 120.492781 -96.117668) (xy 120.476713 -96.171075) (xy 120.453041 -96.221572) (xy 120.422268 -96.268085)
			(xy 120.385051 -96.309622) (xy 120.342183 -96.345297) (xy 120.294577 -96.374351) (xy 120.243248 -96.396163)
			(xy 120.189291 -96.410269) (xy 120.133854 -96.416369) (xy 120.07812 -96.414332) (xy 120.023277 -96.404202)
			(xy 119.970493 -96.386195) (xy 119.920893 -96.360694) (xy 119.875535 -96.328243) (xy 119.835386 -96.289534)
			(xy 119.8013 -96.245391) (xy 119.774004 -96.196756) (xy 119.754081 -96.144665) (xy 119.741955 -96.090228)
			(xy 119.737884 -96.034606) (xy 113.921311 -96.034606) (xy 113.92255 -96.03668) (xy 113.926112 -96.040702)
			(xy 113.92916 -96.04375) (xy 113.940844 -96.051878) (xy 113.945416 -96.054164) (xy 113.952274 -96.055688)
			(xy 113.952528 -96.055942) (xy 113.953544 -96.055942) (xy 113.979259 -96.061863) (xy 114.028869 -96.079843)
			(xy 114.075526 -96.104492) (xy 114.118339 -96.13534) (xy 114.156488 -96.171796) (xy 114.189246 -96.213165)
			(xy 114.215986 -96.258656) (xy 114.236198 -96.3074) (xy 114.249495 -96.358465) (xy 114.25301 -96.384618)
			(xy 114.254534 -96.397318) (xy 114.255804 -96.429322) (xy 114.255286 -96.457833) (xy 114.246819 -96.514221)
			(xy 114.230047 -96.568719) (xy 114.205344 -96.620111) (xy 114.173262 -96.667251) (xy 114.134516 -96.709085)
			(xy 114.112548 -96.727264) (xy 114.106166 -96.733816) (xy 114.098092 -96.750214) (xy 114.0968 -96.759268)
			(xy 114.098324 -96.808544) (xy 114.099594 -96.851216) (xy 114.100194 -96.855437) (xy 114.102619 -96.863608)
			(xy 114.10442 -96.867472) (xy 114.10696 -96.872044) (xy 114.114326 -96.880934) (xy 114.119152 -96.884744)
			(xy 114.142562 -96.902887) (xy 114.184017 -96.945184) (xy 114.218446 -96.993373) (xy 114.245025 -97.046298)
			(xy 114.263116 -97.102692) (xy 114.272286 -97.161202) (xy 114.272583 -97.177606) (xy 119.737884 -97.177606)
			(xy 119.741955 -97.121984) (xy 119.754081 -97.067547) (xy 119.774004 -97.015456) (xy 119.8013 -96.966821)
			(xy 119.835386 -96.922678) (xy 119.875535 -96.883969) (xy 119.920893 -96.851518) (xy 119.970493 -96.826017)
			(xy 120.023277 -96.80801) (xy 120.07812 -96.79788) (xy 120.133854 -96.795843) (xy 120.189291 -96.801943)
			(xy 120.243248 -96.816049) (xy 120.294577 -96.837861) (xy 120.342183 -96.866915) (xy 120.385051 -96.90259)
			(xy 120.422268 -96.944127) (xy 120.453041 -96.99064) (xy 120.476713 -97.041137) (xy 120.492781 -97.094544)
			(xy 120.500901 -97.14972) (xy 120.50141 -97.177606) (xy 121.976388 -97.177606) (xy 121.976827 -97.150774)
			(xy 121.98432 -97.097637) (xy 121.999187 -97.046074) (xy 122.021136 -96.997104) (xy 122.049731 -96.951695)
			(xy 122.084409 -96.910741) (xy 122.124485 -96.875053) (xy 122.169168 -96.845335) (xy 122.217575 -96.822173)
			(xy 122.268751 -96.806024) (xy 122.321685 -96.797209) (xy 122.348498 -96.796098) (xy 122.359643 -96.795246)
			(xy 122.379669 -96.785389) (xy 122.387106 -96.777048) (xy 122.435874 -96.715834) (xy 122.442242 -96.70681)
			(xy 122.447389 -96.685358) (xy 122.44578 -96.674432) (xy 122.44578 -96.673924) (xy 122.442139 -96.655083)
			(xy 122.438196 -96.616911) (xy 122.437906 -96.597724) (xy 122.438088 -96.581836) (xy 122.440758 -96.550172)
			(xy 122.44324 -96.534478) (xy 122.44324 -96.534224) (xy 122.444511 -96.52347) (xy 122.439001 -96.502551)
			(xy 122.432572 -96.493838) (xy 122.383804 -96.434402) (xy 122.376488 -96.426372) (xy 122.357036 -96.416755)
			(xy 122.346212 -96.41586) (xy 122.319513 -96.414675) (xy 122.266843 -96.405609) (xy 122.215954 -96.38928)
			(xy 122.167843 -96.366005) (xy 122.123453 -96.336243) (xy 122.083652 -96.300575) (xy 122.049219 -96.2597)
			(xy 122.020831 -96.214418) (xy 121.999042 -96.165617) (xy 121.984278 -96.114252) (xy 121.97683 -96.061328)
			(xy 121.976388 -96.034606) (xy 121.976871 -96.007447) (xy 121.984575 -95.953678) (xy 121.999827 -95.901545)
			(xy 122.022319 -95.852102) (xy 122.051596 -95.80635) (xy 122.087067 -95.765213) (xy 122.128014 -95.729522)
			(xy 122.173609 -95.7) (xy 122.22293 -95.677244) (xy 122.274981 -95.661713) (xy 122.328708 -95.653722)
			(xy 122.355864 -95.653098) (xy 122.367294 -95.653098) (xy 122.387614 -95.643446) (xy 122.44451 -95.574612)
			(xy 122.451173 -95.565647) (xy 122.456691 -95.544025) (xy 122.455178 -95.532956) (xy 122.452217 -95.515837)
			(xy 122.449037 -95.48124) (xy 122.448828 -95.463868) (xy 122.448828 -95.46336) (xy 122.449057 -95.445729)
			(xy 122.452368 -95.410621) (xy 122.455432 -95.393256) (xy 122.456924 -95.382191) (xy 122.451391 -95.360586)
			(xy 122.444764 -95.3516) (xy 122.387614 -95.282766) (xy 122.367294 -95.273114) (xy 122.355864 -95.273114)
			(xy 122.328708 -95.272482) (xy 122.274981 -95.264492) (xy 122.222931 -95.248961) (xy 122.17361 -95.226206)
			(xy 122.128015 -95.196684) (xy 122.087068 -95.160995) (xy 122.051597 -95.119858) (xy 122.022319 -95.074107)
			(xy 121.999826 -95.024665) (xy 121.984572 -94.972533) (xy 121.976868 -94.918765) (xy 121.976388 -94.891606)
			(xy 121.976861 -94.864353) (xy 121.984617 -94.810403) (xy 121.999972 -94.758106) (xy 122.022614 -94.708526)
			(xy 122.052081 -94.662673) (xy 122.087773 -94.62148) (xy 122.128965 -94.585787) (xy 122.174817 -94.556318)
			(xy 122.224396 -94.533676) (xy 122.276693 -94.518319) (xy 122.330643 -94.510562) (xy 122.357896 -94.510098)
			(xy 122.389646 -94.511368) (xy 122.401735 -94.51178) (xy 122.424145 -94.502773) (xy 122.432572 -94.494096)
			(xy 122.49404 -94.422722) (xy 122.499882 -94.399354) (xy 122.497088 -94.387416) (xy 122.492549 -94.366245)
			(xy 122.487711 -94.323215) (xy 122.487436 -94.301564) (xy 122.487537 -94.287479) (xy 122.489571 -94.259383)
			(xy 122.4915 -94.24543) (xy 122.492583 -94.23407) (xy 122.485837 -94.2123) (xy 122.478546 -94.20352)
			(xy 122.424952 -94.145354) (xy 122.41678 -94.137434) (xy 122.395689 -94.12898) (xy 122.384312 -94.129098)
			(xy 122.383804 -94.129098) (xy 122.35815 -94.130114) (xy 122.357642 -94.130114) (xy 122.330403 -94.129609)
			(xy 122.276483 -94.121822) (xy 122.224219 -94.106445) (xy 122.174674 -94.083789) (xy 122.128856 -94.054316)
			(xy 122.087696 -94.018625) (xy 122.052032 -93.977442) (xy 122.02259 -93.931604) (xy 121.999967 -93.882044)
			(xy 121.984624 -93.82977) (xy 121.976873 -93.775846) (xy 121.976388 -93.748606) (xy 121.976838 -93.721057)
			(xy 121.98475 -93.66653) (xy 122.000425 -93.613709) (xy 122.023537 -93.563693) (xy 122.053605 -93.517523)
			(xy 122.090002 -93.476159) (xy 122.131973 -93.440462) (xy 122.178642 -93.411175) (xy 122.22904 -93.388908)
			(xy 122.282117 -93.374124) (xy 122.309382 -93.370146) (xy 122.321066 -93.368622) (xy 122.340878 -93.355668)
			(xy 122.393456 -93.265498) (xy 122.39498 -93.241876) (xy 122.390408 -93.230954) (xy 122.381406 -93.207979)
			(xy 122.368753 -93.160284) (xy 122.362361 -93.111354) (xy 122.36196 -93.086682) (xy 122.36196 -93.086174)
			(xy 122.362446 -93.058923) (xy 122.370202 -93.004975) (xy 122.385557 -92.95268) (xy 122.408199 -92.903103)
			(xy 122.437665 -92.857253) (xy 122.473356 -92.816062) (xy 122.514547 -92.780371) (xy 122.560397 -92.750905)
			(xy 122.609974 -92.728263) (xy 122.662269 -92.712908) (xy 122.716217 -92.705152) (xy 122.770719 -92.705152)
			(xy 122.824667 -92.712908) (xy 122.876962 -92.728263) (xy 122.926539 -92.750905) (xy 122.972389 -92.780371)
			(xy 123.01358 -92.816062) (xy 123.014776 -92.817442) (xy 124.345444 -92.817442) (xy 124.349515 -92.76182)
			(xy 124.361641 -92.707383) (xy 124.381564 -92.655292) (xy 124.40886 -92.606657) (xy 124.442946 -92.562514)
			(xy 124.483095 -92.523805) (xy 124.528453 -92.491354) (xy 124.578053 -92.465853) (xy 124.630837 -92.447846)
			(xy 124.68568 -92.437716) (xy 124.741414 -92.435679) (xy 124.796851 -92.441779) (xy 124.850808 -92.455885)
			(xy 124.902137 -92.477697) (xy 124.949743 -92.506751) (xy 124.992611 -92.542426) (xy 125.029828 -92.583963)
			(xy 125.034122 -92.590454) (xy 134.293543 -92.590454) (xy 134.293543 -92.535946) (xy 134.3013 -92.481992)
			(xy 134.316657 -92.429692) (xy 134.339301 -92.380109) (xy 134.368771 -92.334254) (xy 134.404467 -92.29306)
			(xy 134.445662 -92.257365) (xy 134.491518 -92.227897) (xy 134.541101 -92.205254) (xy 134.593402 -92.189898)
			(xy 134.647356 -92.182142) (xy 134.67461 -92.18168) (xy 134.702491 -92.182172) (xy 134.757662 -92.190265)
			(xy 134.811065 -92.206308) (xy 134.861563 -92.229958) (xy 134.908077 -92.260711) (xy 134.949617 -92.29791)
			(xy 134.985296 -92.340763) (xy 135.000238 -92.364306) (xy 135.007537 -92.375419) (xy 135.026791 -92.393741)
			(xy 135.050124 -92.406469) (xy 135.075952 -92.412739) (xy 135.102523 -92.412125) (xy 135.128034 -92.404668)
			(xy 135.150754 -92.390876) (xy 135.160258 -92.381578) (xy 135.17829 -92.363333) (xy 135.218432 -92.331393)
			(xy 135.262488 -92.305114) (xy 135.309665 -92.284968) (xy 135.359114 -92.271319) (xy 135.409945 -92.264412)
			(xy 135.435594 -92.263976) (xy 135.462846 -92.264471) (xy 135.516795 -92.272227) (xy 135.569092 -92.287582)
			(xy 135.61867 -92.310223) (xy 135.664522 -92.33969) (xy 135.705714 -92.375382) (xy 135.714605 -92.385642)
			(xy 139.708126 -92.385642) (xy 139.712197 -92.33002) (xy 139.724323 -92.275583) (xy 139.744246 -92.223492)
			(xy 139.771542 -92.174857) (xy 139.805628 -92.130714) (xy 139.845777 -92.092005) (xy 139.891135 -92.059554)
			(xy 139.940735 -92.034053) (xy 139.993519 -92.016046) (xy 140.048362 -92.005916) (xy 140.104096 -92.003879)
			(xy 140.159533 -92.009979) (xy 140.21349 -92.024085) (xy 140.264819 -92.045897) (xy 140.312425 -92.074951)
			(xy 140.355293 -92.110626) (xy 140.39251 -92.152163) (xy 140.423283 -92.198676) (xy 140.446955 -92.249173)
			(xy 140.463023 -92.30258) (xy 140.471143 -92.357756) (xy 140.471652 -92.385642) (xy 140.471143 -92.413528)
			(xy 140.463023 -92.468704) (xy 140.446955 -92.522111) (xy 140.423283 -92.572608) (xy 140.39251 -92.619121)
			(xy 140.355293 -92.660658) (xy 140.312425 -92.696333) (xy 140.264819 -92.725387) (xy 140.21349 -92.747199)
			(xy 140.159533 -92.761305) (xy 140.104096 -92.767405) (xy 140.048362 -92.765368) (xy 139.993519 -92.755238)
			(xy 139.940735 -92.737231) (xy 139.891135 -92.71173) (xy 139.845777 -92.679279) (xy 139.805628 -92.64057)
			(xy 139.771542 -92.596427) (xy 139.744246 -92.547792) (xy 139.724323 -92.495701) (xy 139.712197 -92.441264)
			(xy 139.708126 -92.385642) (xy 135.714605 -92.385642) (xy 135.741407 -92.416573) (xy 135.770874 -92.462424)
			(xy 135.793516 -92.512003) (xy 135.808872 -92.564299) (xy 135.816629 -92.618248) (xy 135.816629 -92.672752)
			(xy 135.808872 -92.726701) (xy 135.793516 -92.778997) (xy 135.770874 -92.828576) (xy 135.741407 -92.874427)
			(xy 135.705714 -92.915618) (xy 135.664522 -92.95131) (xy 135.61867 -92.980777) (xy 135.569092 -93.003418)
			(xy 135.516795 -93.018773) (xy 135.462846 -93.026529) (xy 135.435594 -93.026992) (xy 135.407715 -93.026463)
			(xy 135.352547 -93.018371) (xy 135.299146 -93.002332) (xy 135.24865 -92.978688) (xy 135.202135 -92.947942)
			(xy 135.160594 -92.91075) (xy 135.124911 -92.867906) (xy 135.109966 -92.844366) (xy 135.102656 -92.833258)
			(xy 135.08341 -92.814925) (xy 135.060079 -92.802189) (xy 135.034249 -92.795915) (xy 135.007676 -92.796529)
			(xy 134.982164 -92.80399) (xy 134.959447 -92.817791) (xy 134.949946 -92.827094) (xy 134.931907 -92.845332)
			(xy 134.891767 -92.877273) (xy 134.847713 -92.903554) (xy 134.800537 -92.923701) (xy 134.751089 -92.937352)
			(xy 134.700259 -92.94426) (xy 134.67461 -92.944696) (xy 134.647356 -92.944258) (xy 134.593402 -92.936502)
			(xy 134.541101 -92.921146) (xy 134.491518 -92.898503) (xy 134.445662 -92.869035) (xy 134.404467 -92.83334)
			(xy 134.368771 -92.792146) (xy 134.339301 -92.746291) (xy 134.316657 -92.696708) (xy 134.3013 -92.644408)
			(xy 134.293543 -92.590454) (xy 125.034122 -92.590454) (xy 125.060601 -92.630476) (xy 125.084273 -92.680973)
			(xy 125.100341 -92.73438) (xy 125.108461 -92.789556) (xy 125.10897 -92.817442) (xy 125.108461 -92.845328)
			(xy 125.100341 -92.900504) (xy 125.084273 -92.953911) (xy 125.060601 -93.004408) (xy 125.029828 -93.050921)
			(xy 124.992611 -93.092458) (xy 124.949743 -93.128133) (xy 124.902137 -93.157187) (xy 124.850808 -93.178999)
			(xy 124.796851 -93.193105) (xy 124.741414 -93.199205) (xy 124.68568 -93.197168) (xy 124.630837 -93.187038)
			(xy 124.578053 -93.169031) (xy 124.528453 -93.14353) (xy 124.483095 -93.111079) (xy 124.442946 -93.07237)
			(xy 124.40886 -93.028227) (xy 124.381564 -92.979592) (xy 124.361641 -92.927501) (xy 124.349515 -92.873064)
			(xy 124.345444 -92.817442) (xy 123.014776 -92.817442) (xy 123.049271 -92.857253) (xy 123.078737 -92.903103)
			(xy 123.101379 -92.95268) (xy 123.116734 -93.004975) (xy 123.12449 -93.058923) (xy 123.124976 -93.086174)
			(xy 123.124452 -93.11372) (xy 123.116544 -93.168241) (xy 123.100875 -93.221057) (xy 123.07777 -93.27107)
			(xy 123.047711 -93.317238) (xy 123.011322 -93.358601) (xy 122.969361 -93.394299) (xy 122.9227 -93.423589)
			(xy 122.872312 -93.445861) (xy 122.819243 -93.460652) (xy 122.791982 -93.464634) (xy 122.780298 -93.466158)
			(xy 122.760486 -93.479112) (xy 122.707908 -93.569282) (xy 122.706384 -93.592904) (xy 122.710956 -93.603826)
			(xy 122.719982 -93.626882) (xy 122.732658 -93.674746) (xy 122.739029 -93.723849) (xy 122.739404 -93.748606)
			(xy 122.739299 -93.762691) (xy 122.737268 -93.790787) (xy 122.73534 -93.80474) (xy 122.73429 -93.8161)
			(xy 122.741015 -93.837866) (xy 122.743032 -93.8403) (xy 125.868174 -93.8403) (xy 125.872245 -93.784678)
			(xy 125.884371 -93.730241) (xy 125.904294 -93.67815) (xy 125.93159 -93.629515) (xy 125.965676 -93.585372)
			(xy 126.005825 -93.546663) (xy 126.051183 -93.514212) (xy 126.100783 -93.488711) (xy 126.153567 -93.470704)
			(xy 126.20841 -93.460574) (xy 126.264144 -93.458537) (xy 126.319581 -93.464637) (xy 126.373538 -93.478743)
			(xy 126.424867 -93.500555) (xy 126.472473 -93.529609) (xy 126.515341 -93.565284) (xy 126.552558 -93.606821)
			(xy 126.583331 -93.653334) (xy 126.607003 -93.703831) (xy 126.623071 -93.757238) (xy 126.624604 -93.767656)
			(xy 133.93623 -93.767656) (xy 133.940301 -93.712034) (xy 133.952427 -93.657597) (xy 133.97235 -93.605506)
			(xy 133.999646 -93.556871) (xy 134.033732 -93.512728) (xy 134.073881 -93.474019) (xy 134.119239 -93.441568)
			(xy 134.168839 -93.416067) (xy 134.221623 -93.39806) (xy 134.276466 -93.38793) (xy 134.3322 -93.385893)
			(xy 134.387637 -93.391993) (xy 134.441594 -93.406099) (xy 134.492923 -93.427911) (xy 134.540529 -93.456965)
			(xy 134.583397 -93.49264) (xy 134.615655 -93.528642) (xy 139.708126 -93.528642) (xy 139.712197 -93.47302)
			(xy 139.724323 -93.418583) (xy 139.744246 -93.366492) (xy 139.771542 -93.317857) (xy 139.805628 -93.273714)
			(xy 139.845777 -93.235005) (xy 139.891135 -93.202554) (xy 139.940735 -93.177053) (xy 139.993519 -93.159046)
			(xy 140.048362 -93.148916) (xy 140.104096 -93.146879) (xy 140.159533 -93.152979) (xy 140.21349 -93.167085)
			(xy 140.264819 -93.188897) (xy 140.312425 -93.217951) (xy 140.355293 -93.253626) (xy 140.39251 -93.295163)
			(xy 140.423283 -93.341676) (xy 140.446955 -93.392173) (xy 140.463023 -93.44558) (xy 140.471143 -93.500756)
			(xy 140.471652 -93.528642) (xy 140.471143 -93.556528) (xy 140.463023 -93.611704) (xy 140.446976 -93.66504)
			(xy 162.57524 -93.66504) (xy 162.575718 -93.622771) (xy 162.583514 -93.538592) (xy 162.599042 -93.455491)
			(xy 162.622171 -93.374178) (xy 162.652704 -93.295345) (xy 162.690378 -93.219665) (xy 162.734875 -93.147784)
			(xy 162.785813 -93.080315) (xy 162.842758 -93.017832) (xy 162.905225 -92.96087) (xy 162.972681 -92.909914)
			(xy 163.04455 -92.865398) (xy 163.12022 -92.827703) (xy 163.199045 -92.79715) (xy 163.280352 -92.773999)
			(xy 163.363448 -92.758448) (xy 163.447625 -92.75063) (xy 163.489894 -92.750132) (xy 165.394894 -92.750132)
			(xy 165.43715 -92.750639) (xy 165.521303 -92.758435) (xy 165.604378 -92.773961) (xy 165.685666 -92.797084)
			(xy 165.764474 -92.827608) (xy 165.84013 -92.865272) (xy 165.911989 -92.909755) (xy 165.979438 -92.960677)
			(xy 166.041902 -93.017604) (xy 166.098848 -93.080051) (xy 166.14979 -93.147484) (xy 166.194295 -93.21933)
			(xy 166.231981 -93.294975) (xy 166.262528 -93.373774) (xy 166.285676 -93.455055) (xy 166.301227 -93.538125)
			(xy 166.309048 -93.622276) (xy 166.309548 -93.664532) (xy 166.309548 -93.66504) (xy 166.309072 -93.707527)
			(xy 166.308986 -93.708448) (xy 185.190434 -93.708448) (xy 185.190434 -93.621552) (xy 185.198451 -93.535028)
			(xy 185.214418 -93.449612) (xy 185.238198 -93.366034) (xy 185.269588 -93.285007) (xy 185.30832 -93.207222)
			(xy 185.354064 -93.133342) (xy 185.406429 -93.063998) (xy 185.464969 -92.999781) (xy 185.529185 -92.941239)
			(xy 185.598528 -92.888873) (xy 185.672408 -92.843128) (xy 185.750192 -92.804394) (xy 185.831219 -92.773003)
			(xy 185.914797 -92.749222) (xy 186.000212 -92.733254) (xy 186.086736 -92.725235) (xy 186.130184 -92.724732)
			(xy 187.984384 -92.724732) (xy 188.027835 -92.725194) (xy 188.114368 -92.733211) (xy 188.199791 -92.749178)
			(xy 188.283377 -92.77296) (xy 188.364412 -92.804353) (xy 188.442204 -92.843089) (xy 188.51609 -92.888838)
			(xy 188.58544 -92.941209) (xy 188.649661 -92.999756) (xy 188.708206 -93.063979) (xy 188.760576 -93.13333)
			(xy 188.806323 -93.207217) (xy 188.845057 -93.28501) (xy 188.876448 -93.366046) (xy 188.900227 -93.449632)
			(xy 188.916192 -93.535056) (xy 188.924207 -93.621588) (xy 188.924692 -93.66504) (xy 188.924132 -93.710119)
			(xy 188.915488 -93.799862) (xy 188.898303 -93.888367) (xy 188.872734 -93.974824) (xy 188.856366 -94.01683)
			(xy 188.852048 -94.027752) (xy 188.853572 -94.051374) (xy 188.900562 -94.130876) (xy 188.907025 -94.140659)
			(xy 188.926603 -94.153507) (xy 188.938154 -94.155514) (xy 188.983803 -94.1616) (xy 189.073904 -94.180689)
			(xy 189.162025 -94.20747) (xy 189.247512 -94.241743) (xy 189.329728 -94.283254) (xy 189.408061 -94.331694)
			(xy 189.481931 -94.386703) (xy 189.550786 -94.447871) (xy 189.614115 -94.514744) (xy 189.671447 -94.586825)
			(xy 189.722356 -94.663577) (xy 189.766463 -94.744429) (xy 189.80344 -94.828782) (xy 189.833013 -94.916006)
			(xy 189.85496 -95.005454) (xy 189.86912 -95.09646) (xy 189.875386 -95.188347) (xy 189.873712 -95.280433)
			(xy 189.864111 -95.372032) (xy 189.846654 -95.462464) (xy 189.821471 -95.551055) (xy 189.788748 -95.637147)
			(xy 189.74873 -95.7201) (xy 189.701714 -95.799296) (xy 189.64805 -95.874148) (xy 189.588136 -95.944097)
			(xy 189.522419 -96.008625) (xy 189.451386 -96.067251) (xy 189.375567 -96.119539) (xy 189.295525 -96.1651)
			(xy 189.211855 -96.203596) (xy 189.12518 -96.23474) (xy 189.036143 -96.258301) (xy 188.945408 -96.274103)
			(xy 188.853649 -96.28203) (xy 188.807598 -96.28251) (xy 188.807344 -96.28251) (xy 188.760445 -96.28198)
			(xy 188.667008 -96.273761) (xy 188.574652 -96.257374) (xy 188.484091 -96.232946) (xy 188.396023 -96.200664)
			(xy 188.311128 -96.160779) (xy 188.230061 -96.113597) (xy 188.153447 -96.059482) (xy 188.081877 -95.998854)
			(xy 188.015904 -95.932178) (xy 187.956037 -95.85997) (xy 187.902738 -95.782787) (xy 187.856418 -95.701224)
			(xy 187.817434 -95.615911) (xy 187.786087 -95.527506) (xy 187.76262 -95.436691) (xy 187.747212 -95.344167)
			(xy 187.739984 -95.250648) (xy 187.740991 -95.156856) (xy 187.750225 -95.063513) (xy 187.767614 -94.971341)
			(xy 187.793025 -94.881051) (xy 187.826262 -94.793339) (xy 187.846208 -94.75089) (xy 187.851796 -94.739206)
			(xy 187.850526 -94.713044) (xy 187.797694 -94.629224) (xy 187.792814 -94.622128) (xy 187.779357 -94.611398)
			(xy 187.763119 -94.605696) (xy 187.754514 -94.605348) (xy 186.130184 -94.605348) (xy 186.086736 -94.604765)
			(xy 186.000212 -94.596746) (xy 185.914797 -94.580778) (xy 185.831219 -94.556997) (xy 185.750192 -94.525606)
			(xy 185.672408 -94.486872) (xy 185.598528 -94.441127) (xy 185.529185 -94.388761) (xy 185.464969 -94.330219)
			(xy 185.406429 -94.266002) (xy 185.354064 -94.196658) (xy 185.30832 -94.122778) (xy 185.269588 -94.044993)
			(xy 185.238198 -93.963966) (xy 185.214418 -93.880388) (xy 185.198451 -93.794972) (xy 185.190434 -93.708448)
			(xy 166.308986 -93.708448) (xy 166.301189 -93.792133) (xy 166.285496 -93.875645) (xy 166.262127 -93.957342)
			(xy 166.231284 -94.03652) (xy 166.193232 -94.112497) (xy 166.1483 -94.184619) (xy 166.096874 -94.252263)
			(xy 166.039398 -94.314849) (xy 165.976366 -94.371835) (xy 165.908322 -94.422732) (xy 165.835852 -94.4671)
			(xy 165.75958 -94.504558) (xy 165.680164 -94.534782) (xy 165.598287 -94.557513) (xy 165.514656 -94.572554)
			(xy 165.472364 -94.576646) (xy 165.459827 -94.578303) (xy 165.438636 -94.592054) (xy 165.431978 -94.602808)
			(xy 165.384988 -94.687898) (xy 165.384734 -94.713044) (xy 165.390576 -94.724474) (xy 165.411052 -94.76517)
			(xy 165.445866 -94.849364) (xy 165.473378 -94.936219) (xy 165.493387 -95.025103) (xy 165.505747 -95.115369)
			(xy 165.51037 -95.206359) (xy 165.50722 -95.297413) (xy 165.496322 -95.387867) (xy 165.477754 -95.477063)
			(xy 165.451651 -95.564351) (xy 165.429758 -95.619824) (xy 174.129952 -95.619824) (xy 174.134023 -95.564202)
			(xy 174.146149 -95.509765) (xy 174.166072 -95.457674) (xy 174.193368 -95.409039) (xy 174.227454 -95.364896)
			(xy 174.267603 -95.326187) (xy 174.312961 -95.293736) (xy 174.362561 -95.268235) (xy 174.415345 -95.250228)
			(xy 174.470188 -95.240098) (xy 174.525922 -95.238061) (xy 174.581359 -95.244161) (xy 174.635316 -95.258267)
			(xy 174.686645 -95.280079) (xy 174.734251 -95.309133) (xy 174.777119 -95.344808) (xy 174.814336 -95.386345)
			(xy 174.845109 -95.432858) (xy 174.868781 -95.483355) (xy 174.884849 -95.536762) (xy 174.892969 -95.591938)
			(xy 174.893478 -95.619824) (xy 174.892969 -95.64771) (xy 174.884849 -95.702886) (xy 174.868781 -95.756293)
			(xy 174.845109 -95.80679) (xy 174.814336 -95.853303) (xy 174.777119 -95.89484) (xy 174.734251 -95.930515)
			(xy 174.686645 -95.959569) (xy 174.635316 -95.981381) (xy 174.581359 -95.995487) (xy 174.525922 -96.001587)
			(xy 174.470188 -95.99955) (xy 174.415345 -95.98942) (xy 174.362561 -95.971413) (xy 174.312961 -95.945912)
			(xy 174.267603 -95.913461) (xy 174.227454 -95.874752) (xy 174.193368 -95.830609) (xy 174.166072 -95.781974)
			(xy 174.146149 -95.729883) (xy 174.134023 -95.675446) (xy 174.129952 -95.619824) (xy 165.429758 -95.619824)
			(xy 165.418204 -95.649098) (xy 165.377655 -95.730685) (xy 165.330301 -95.80852) (xy 165.276485 -95.882035)
			(xy 165.216599 -95.950697) (xy 165.151079 -96.014004) (xy 165.080402 -96.071497) (xy 165.005082 -96.122757)
			(xy 164.925668 -96.167411) (xy 164.842736 -96.205134) (xy 164.756891 -96.235651) (xy 164.668757 -96.258741)
			(xy 164.578977 -96.274236) (xy 164.488202 -96.282022) (xy 164.442648 -96.28251) (xy 164.442394 -96.28251)
			(xy 164.396837 -96.281932) (xy 164.306054 -96.274166) (xy 164.216264 -96.25869) (xy 164.12812 -96.235616)
			(xy 164.042263 -96.205114) (xy 163.959318 -96.167405) (xy 163.879889 -96.122763) (xy 163.804555 -96.071514)
			(xy 163.733863 -96.01403) (xy 163.668327 -95.95073) (xy 163.608426 -95.882074) (xy 163.554594 -95.808562)
			(xy 163.507224 -95.73073) (xy 163.466661 -95.649143) (xy 163.433199 -95.564396) (xy 163.407082 -95.477105)
			(xy 163.388501 -95.387905) (xy 163.37759 -95.297447) (xy 163.374429 -95.206387) (xy 163.379041 -95.11539)
			(xy 163.391393 -95.025117) (xy 163.411393 -94.936225) (xy 163.438898 -94.849361) (xy 163.473707 -94.765158)
			(xy 163.494212 -94.724474) (xy 163.499356 -94.713035) (xy 163.498961 -94.687988) (xy 163.49345 -94.676722)
			(xy 163.45281 -94.602808) (xy 163.44615 -94.592059) (xy 163.424957 -94.578327) (xy 163.412424 -94.576646)
			(xy 163.370132 -94.572556) (xy 163.286501 -94.557513) (xy 163.204626 -94.534782) (xy 163.12521 -94.504557)
			(xy 163.048939 -94.467099) (xy 162.97647 -94.42273) (xy 162.908426 -94.371833) (xy 162.845395 -94.314846)
			(xy 162.78792 -94.252261) (xy 162.736494 -94.184616) (xy 162.691563 -94.112495) (xy 162.653511 -94.036518)
			(xy 162.622669 -93.95734) (xy 162.5993 -93.875644) (xy 162.583607 -93.792133) (xy 162.575725 -93.707526)
			(xy 162.57524 -93.66504) (xy 140.446976 -93.66504) (xy 140.446955 -93.665111) (xy 140.423283 -93.715608)
			(xy 140.39251 -93.762121) (xy 140.355293 -93.803658) (xy 140.312425 -93.839333) (xy 140.264819 -93.868387)
			(xy 140.21349 -93.890199) (xy 140.159533 -93.904305) (xy 140.104096 -93.910405) (xy 140.048362 -93.908368)
			(xy 139.993519 -93.898238) (xy 139.940735 -93.880231) (xy 139.891135 -93.85473) (xy 139.845777 -93.822279)
			(xy 139.805628 -93.78357) (xy 139.771542 -93.739427) (xy 139.744246 -93.690792) (xy 139.724323 -93.638701)
			(xy 139.712197 -93.584264) (xy 139.708126 -93.528642) (xy 134.615655 -93.528642) (xy 134.620614 -93.534177)
			(xy 134.651387 -93.58069) (xy 134.675059 -93.631187) (xy 134.691127 -93.684594) (xy 134.699247 -93.73977)
			(xy 134.699756 -93.767656) (xy 134.699247 -93.795542) (xy 134.691127 -93.850718) (xy 134.675059 -93.904125)
			(xy 134.651387 -93.954622) (xy 134.620614 -94.001135) (xy 134.583397 -94.042672) (xy 134.540529 -94.078347)
			(xy 134.492923 -94.107401) (xy 134.441594 -94.129213) (xy 134.387637 -94.143319) (xy 134.3322 -94.149419)
			(xy 134.276466 -94.147382) (xy 134.221623 -94.137252) (xy 134.168839 -94.119245) (xy 134.119239 -94.093744)
			(xy 134.073881 -94.061293) (xy 134.033732 -94.022584) (xy 133.999646 -93.978441) (xy 133.97235 -93.929806)
			(xy 133.952427 -93.877715) (xy 133.940301 -93.823278) (xy 133.93623 -93.767656) (xy 126.624604 -93.767656)
			(xy 126.631191 -93.812414) (xy 126.6317 -93.8403) (xy 126.631191 -93.868186) (xy 126.623071 -93.923362)
			(xy 126.607003 -93.976769) (xy 126.583331 -94.027266) (xy 126.552558 -94.073779) (xy 126.515341 -94.115316)
			(xy 126.472473 -94.150991) (xy 126.424867 -94.180045) (xy 126.373538 -94.201857) (xy 126.319581 -94.215963)
			(xy 126.264144 -94.222063) (xy 126.20841 -94.220026) (xy 126.153567 -94.209896) (xy 126.100783 -94.191889)
			(xy 126.051183 -94.166388) (xy 126.005825 -94.133937) (xy 125.965676 -94.095228) (xy 125.93159 -94.051085)
			(xy 125.904294 -94.00245) (xy 125.884371 -93.950359) (xy 125.872245 -93.895922) (xy 125.868174 -93.8403)
			(xy 122.743032 -93.8403) (xy 122.748294 -93.84665) (xy 122.801888 -93.904816) (xy 122.810047 -93.912751)
			(xy 122.831148 -93.921197) (xy 122.842528 -93.921072) (xy 122.843036 -93.921072) (xy 122.86869 -93.920056)
			(xy 122.869198 -93.920056) (xy 122.896437 -93.920554) (xy 122.950355 -93.928345) (xy 123.002617 -93.943726)
			(xy 123.052161 -93.966384) (xy 123.097977 -93.995858) (xy 123.139135 -94.03155) (xy 123.174799 -94.072733)
			(xy 123.204242 -94.11857) (xy 123.226866 -94.168128) (xy 123.242211 -94.220401) (xy 123.249965 -94.274325)
			(xy 123.250452 -94.301564) (xy 123.249888 -94.328812) (xy 123.242138 -94.382755) (xy 123.22679 -94.435046)
			(xy 123.219312 -94.451424) (xy 135.029192 -94.451424) (xy 135.033263 -94.395802) (xy 135.045389 -94.341365)
			(xy 135.065312 -94.289274) (xy 135.092608 -94.240639) (xy 135.126694 -94.196496) (xy 135.166843 -94.157787)
			(xy 135.212201 -94.125336) (xy 135.261801 -94.099835) (xy 135.314585 -94.081828) (xy 135.369428 -94.071698)
			(xy 135.425162 -94.069661) (xy 135.480599 -94.075761) (xy 135.534556 -94.089867) (xy 135.585885 -94.111679)
			(xy 135.633491 -94.140733) (xy 135.676359 -94.176408) (xy 135.713576 -94.217945) (xy 135.744349 -94.264458)
			(xy 135.768021 -94.314955) (xy 135.784089 -94.368362) (xy 135.792209 -94.423538) (xy 135.792718 -94.451424)
			(xy 135.792209 -94.47931) (xy 135.784089 -94.534486) (xy 135.768021 -94.587893) (xy 135.744349 -94.63839)
			(xy 135.722349 -94.671642) (xy 139.708126 -94.671642) (xy 139.712197 -94.61602) (xy 139.724323 -94.561583)
			(xy 139.744246 -94.509492) (xy 139.771542 -94.460857) (xy 139.805628 -94.416714) (xy 139.845777 -94.378005)
			(xy 139.891135 -94.345554) (xy 139.940735 -94.320053) (xy 139.993519 -94.302046) (xy 140.048362 -94.291916)
			(xy 140.104096 -94.289879) (xy 140.159533 -94.295979) (xy 140.21349 -94.310085) (xy 140.264819 -94.331897)
			(xy 140.312425 -94.360951) (xy 140.355293 -94.396626) (xy 140.39251 -94.438163) (xy 140.423283 -94.484676)
			(xy 140.446955 -94.535173) (xy 140.463023 -94.58858) (xy 140.471143 -94.643756) (xy 140.471652 -94.671642)
			(xy 140.471143 -94.699528) (xy 140.463023 -94.754704) (xy 140.446955 -94.808111) (xy 140.423283 -94.858608)
			(xy 140.39251 -94.905121) (xy 140.355293 -94.946658) (xy 140.312425 -94.982333) (xy 140.264819 -95.011387)
			(xy 140.21349 -95.033199) (xy 140.159533 -95.047305) (xy 140.104096 -95.053405) (xy 140.048362 -95.051368)
			(xy 139.993519 -95.041238) (xy 139.940735 -95.023231) (xy 139.891135 -94.99773) (xy 139.845777 -94.965279)
			(xy 139.805628 -94.92657) (xy 139.771542 -94.882427) (xy 139.744246 -94.833792) (xy 139.724323 -94.781701)
			(xy 139.712197 -94.727264) (xy 139.708126 -94.671642) (xy 135.722349 -94.671642) (xy 135.713576 -94.684903)
			(xy 135.676359 -94.72644) (xy 135.633491 -94.762115) (xy 135.585885 -94.791169) (xy 135.534556 -94.812981)
			(xy 135.480599 -94.827087) (xy 135.425162 -94.833187) (xy 135.369428 -94.83115) (xy 135.314585 -94.82102)
			(xy 135.261801 -94.803013) (xy 135.212201 -94.777512) (xy 135.166843 -94.745061) (xy 135.126694 -94.706352)
			(xy 135.092608 -94.662209) (xy 135.065312 -94.613574) (xy 135.045389 -94.561483) (xy 135.033263 -94.507046)
			(xy 135.029192 -94.451424) (xy 123.219312 -94.451424) (xy 123.204156 -94.48462) (xy 123.174697 -94.530468)
			(xy 123.139014 -94.571657) (xy 123.097832 -94.607349) (xy 123.05199 -94.636817) (xy 123.002421 -94.659462)
			(xy 122.950133 -94.674821) (xy 122.896192 -94.682583) (xy 122.868944 -94.683072) (xy 122.837194 -94.681802)
			(xy 122.825104 -94.681362) (xy 122.802693 -94.69039) (xy 122.794268 -94.699074) (xy 122.7328 -94.770448)
			(xy 122.726958 -94.793816) (xy 122.729752 -94.805754) (xy 122.734287 -94.826926) (xy 122.739127 -94.869955)
			(xy 122.739404 -94.891606) (xy 124.303282 -94.891606) (xy 124.303768 -94.864355) (xy 124.311524 -94.810407)
			(xy 124.326879 -94.758112) (xy 124.349521 -94.708535) (xy 124.378987 -94.662685) (xy 124.414678 -94.621494)
			(xy 124.455869 -94.585803) (xy 124.501719 -94.556337) (xy 124.551296 -94.533695) (xy 124.603591 -94.51834)
			(xy 124.657539 -94.510584) (xy 124.712041 -94.510584) (xy 124.765989 -94.51834) (xy 124.818284 -94.533695)
			(xy 124.867861 -94.556337) (xy 124.913711 -94.585803) (xy 124.954902 -94.621494) (xy 124.990593 -94.662685)
			(xy 125.020059 -94.708535) (xy 125.042701 -94.758112) (xy 125.058056 -94.810407) (xy 125.065812 -94.864355)
			(xy 125.066298 -94.891606) (xy 125.065812 -94.918674) (xy 125.058164 -94.972267) (xy 125.043009 -95.024238)
			(xy 125.032262 -95.049086) (xy 125.027066 -95.061406) (xy 125.0227 -95.087778) (xy 125.025339 -95.114379)
			(xy 125.034802 -95.139379) (xy 125.050438 -95.161061) (xy 125.071171 -95.177933) (xy 125.095578 -95.188836)
			(xy 125.108716 -95.191326) (xy 125.135255 -95.196048) (xy 125.186757 -95.211952) (xy 125.235508 -95.234949)
			(xy 125.280535 -95.26458) (xy 125.320943 -95.300256) (xy 125.355925 -95.341264) (xy 125.384785 -95.38679)
			(xy 125.406949 -95.435925) (xy 125.421974 -95.487691) (xy 125.429561 -95.541057) (xy 125.430026 -95.568008)
			(xy 125.42954 -95.595259) (xy 125.421784 -95.649207) (xy 125.406429 -95.701502) (xy 125.383787 -95.751079)
			(xy 125.354321 -95.796929) (xy 125.31863 -95.83812) (xy 125.277439 -95.873811) (xy 125.247776 -95.892874)
			(xy 125.538482 -95.892874) (xy 125.542553 -95.837252) (xy 125.554679 -95.782815) (xy 125.574602 -95.730724)
			(xy 125.601898 -95.682089) (xy 125.635984 -95.637946) (xy 125.676133 -95.599237) (xy 125.721491 -95.566786)
			(xy 125.771091 -95.541285) (xy 125.823875 -95.523278) (xy 125.878718 -95.513148) (xy 125.934452 -95.511111)
			(xy 125.989889 -95.517211) (xy 125.999593 -95.519748) (xy 134.274558 -95.519748) (xy 134.278629 -95.464126)
			(xy 134.290755 -95.409689) (xy 134.310678 -95.357598) (xy 134.337974 -95.308963) (xy 134.37206 -95.26482)
			(xy 134.412209 -95.226111) (xy 134.457567 -95.19366) (xy 134.507167 -95.168159) (xy 134.559951 -95.150152)
			(xy 134.614794 -95.140022) (xy 134.670528 -95.137985) (xy 134.725965 -95.144085) (xy 134.779922 -95.158191)
			(xy 134.831251 -95.180003) (xy 134.878857 -95.209057) (xy 134.921725 -95.244732) (xy 134.958942 -95.286269)
			(xy 134.989715 -95.332782) (xy 135.013387 -95.383279) (xy 135.029455 -95.436686) (xy 135.037575 -95.491862)
			(xy 135.038084 -95.519748) (xy 135.037575 -95.547634) (xy 135.029455 -95.60281) (xy 135.013387 -95.656217)
			(xy 134.989715 -95.706714) (xy 134.958942 -95.753227) (xy 134.921725 -95.794764) (xy 134.897839 -95.814642)
			(xy 139.708126 -95.814642) (xy 139.712197 -95.75902) (xy 139.724323 -95.704583) (xy 139.744246 -95.652492)
			(xy 139.771542 -95.603857) (xy 139.805628 -95.559714) (xy 139.845777 -95.521005) (xy 139.891135 -95.488554)
			(xy 139.940735 -95.463053) (xy 139.993519 -95.445046) (xy 140.048362 -95.434916) (xy 140.104096 -95.432879)
			(xy 140.159533 -95.438979) (xy 140.21349 -95.453085) (xy 140.264819 -95.474897) (xy 140.312425 -95.503951)
			(xy 140.355293 -95.539626) (xy 140.39251 -95.581163) (xy 140.423283 -95.627676) (xy 140.446955 -95.678173)
			(xy 140.463023 -95.73158) (xy 140.471143 -95.786756) (xy 140.471652 -95.814642) (xy 140.471143 -95.842528)
			(xy 140.463023 -95.897704) (xy 140.446955 -95.951111) (xy 140.423283 -96.001608) (xy 140.39251 -96.048121)
			(xy 140.355293 -96.089658) (xy 140.351856 -96.092518) (xy 144.382744 -96.092518) (xy 144.383248 -96.06569)
			(xy 144.390764 -96.012563) (xy 144.405649 -95.961013) (xy 144.427611 -95.912057) (xy 144.456215 -95.866662)
			(xy 144.490898 -95.825722) (xy 144.530975 -95.790046) (xy 144.575655 -95.760337) (xy 144.59966 -95.748348)
			(xy 144.609594 -95.742933) (xy 144.623842 -95.725402) (xy 144.627092 -95.714566) (xy 144.648428 -95.626936)
			(xy 144.643602 -95.60433) (xy 144.636744 -95.59544) (xy 144.618602 -95.570462) (xy 144.589781 -95.515872)
			(xy 144.570124 -95.457354) (xy 144.560144 -95.396435) (xy 144.559528 -95.36557) (xy 144.559528 -95.365062)
			(xy 144.559943 -95.337808) (xy 144.567705 -95.283856) (xy 144.583067 -95.231558) (xy 144.605715 -95.181978)
			(xy 144.635189 -95.136126) (xy 144.670888 -95.094935) (xy 144.712085 -95.059244) (xy 144.757943 -95.02978)
			(xy 144.807527 -95.007141) (xy 144.859828 -94.991789) (xy 144.913782 -94.984037) (xy 144.941036 -94.983554)
			(xy 144.970949 -94.984133) (xy 145.030039 -94.993488) (xy 145.086941 -95.011963) (xy 145.140257 -95.039102)
			(xy 145.16481 -95.056198) (xy 145.165064 -95.056198) (xy 145.174519 -95.0622) (xy 145.196508 -95.066296)
			(xy 145.207482 -95.064072) (xy 145.294858 -95.040958) (xy 145.311876 -95.02648) (xy 145.316702 -95.016066)
			(xy 145.328541 -94.991547) (xy 145.358049 -94.945793) (xy 145.393757 -94.904695) (xy 145.434943 -94.869087)
			(xy 145.48077 -94.839692) (xy 145.530308 -94.817106) (xy 145.582553 -94.801788) (xy 145.636444 -94.794048)
			(xy 145.663666 -94.793562) (xy 145.690918 -94.794083) (xy 145.744869 -94.801835) (xy 145.797166 -94.817187)
			(xy 145.846747 -94.839826) (xy 145.892601 -94.869291) (xy 145.933794 -94.904982) (xy 145.969489 -94.946172)
			(xy 145.998958 -94.992023) (xy 146.021601 -95.041602) (xy 146.036957 -95.093898) (xy 146.044715 -95.147848)
			(xy 146.044715 -95.202352) (xy 146.036957 -95.256302) (xy 146.021601 -95.308598) (xy 145.998958 -95.358177)
			(xy 145.969489 -95.404028) (xy 145.933794 -95.445218) (xy 145.892601 -95.480909) (xy 145.846747 -95.510374)
			(xy 145.797166 -95.533013) (xy 145.744869 -95.548365) (xy 145.690918 -95.556117) (xy 145.663666 -95.556578)
			(xy 145.633753 -95.555992) (xy 145.574664 -95.546638) (xy 145.517762 -95.528166) (xy 145.464446 -95.501028)
			(xy 145.439892 -95.483934) (xy 145.439638 -95.483934) (xy 145.430181 -95.477935) (xy 145.408194 -95.473835)
			(xy 145.39722 -95.47606) (xy 145.309844 -95.499174) (xy 145.292826 -95.513652) (xy 145.288 -95.524066)
			(xy 145.276524 -95.547993) (xy 145.247938 -95.592701) (xy 145.213423 -95.633008) (xy 145.173647 -95.668134)
			(xy 145.12938 -95.697399) (xy 145.105628 -95.709232) (xy 145.095698 -95.714652) (xy 145.081449 -95.73218)
			(xy 145.078196 -95.743014) (xy 145.05686 -95.830644) (xy 145.061686 -95.85325) (xy 145.068544 -95.86214)
			(xy 145.086676 -95.887125) (xy 145.115499 -95.941713) (xy 145.135159 -96.000228) (xy 145.145142 -96.061145)
			(xy 145.14576 -96.09201) (xy 145.14576 -96.092518) (xy 145.145274 -96.119769) (xy 145.138857 -96.1644)
			(xy 153.32532 -96.1644) (xy 153.329391 -96.108778) (xy 153.341517 -96.054341) (xy 153.36144 -96.00225)
			(xy 153.388736 -95.953615) (xy 153.422822 -95.909472) (xy 153.462971 -95.870763) (xy 153.508329 -95.838312)
			(xy 153.557929 -95.812811) (xy 153.610713 -95.794804) (xy 153.665556 -95.784674) (xy 153.72129 -95.782637)
			(xy 153.776727 -95.788737) (xy 153.830684 -95.802843) (xy 153.882013 -95.824655) (xy 153.929619 -95.853709)
			(xy 153.972487 -95.889384) (xy 154.009704 -95.930921) (xy 154.040477 -95.977434) (xy 154.064149 -96.027931)
			(xy 154.080217 -96.081338) (xy 154.088337 -96.136514) (xy 154.088846 -96.1644) (xy 154.088337 -96.192286)
			(xy 154.080217 -96.247462) (xy 154.064149 -96.300869) (xy 154.040477 -96.351366) (xy 154.009704 -96.397879)
			(xy 153.978345 -96.432878) (xy 183.362598 -96.432878) (xy 183.366669 -96.377256) (xy 183.378795 -96.322819)
			(xy 183.398718 -96.270728) (xy 183.426014 -96.222093) (xy 183.4601 -96.17795) (xy 183.500249 -96.139241)
			(xy 183.545607 -96.10679) (xy 183.595207 -96.081289) (xy 183.647991 -96.063282) (xy 183.702834 -96.053152)
			(xy 183.758568 -96.051115) (xy 183.814005 -96.057215) (xy 183.867962 -96.071321) (xy 183.919291 -96.093133)
			(xy 183.966897 -96.122187) (xy 184.009765 -96.157862) (xy 184.046982 -96.199399) (xy 184.077755 -96.245912)
			(xy 184.101427 -96.296409) (xy 184.117495 -96.349816) (xy 184.125615 -96.404992) (xy 184.126124 -96.432878)
			(xy 184.125615 -96.460764) (xy 184.117495 -96.51594) (xy 184.101427 -96.569347) (xy 184.077755 -96.619844)
			(xy 184.046982 -96.666357) (xy 184.009765 -96.707894) (xy 183.966897 -96.743569) (xy 183.919291 -96.772623)
			(xy 183.867962 -96.794435) (xy 183.814005 -96.808541) (xy 183.758568 -96.814641) (xy 183.702834 -96.812604)
			(xy 183.647991 -96.802474) (xy 183.595207 -96.784467) (xy 183.545607 -96.758966) (xy 183.500249 -96.726515)
			(xy 183.4601 -96.687806) (xy 183.426014 -96.643663) (xy 183.398718 -96.595028) (xy 183.378795 -96.542937)
			(xy 183.366669 -96.4885) (xy 183.362598 -96.432878) (xy 153.978345 -96.432878) (xy 153.972487 -96.439416)
			(xy 153.929619 -96.475091) (xy 153.882013 -96.504145) (xy 153.830684 -96.525957) (xy 153.776727 -96.540063)
			(xy 153.72129 -96.546163) (xy 153.665556 -96.544126) (xy 153.610713 -96.533996) (xy 153.557929 -96.515989)
			(xy 153.508329 -96.490488) (xy 153.462971 -96.458037) (xy 153.422822 -96.419328) (xy 153.388736 -96.375185)
			(xy 153.36144 -96.32655) (xy 153.341517 -96.274459) (xy 153.329391 -96.220022) (xy 153.32532 -96.1644)
			(xy 145.138857 -96.1644) (xy 145.137518 -96.173717) (xy 145.122163 -96.226012) (xy 145.099521 -96.275589)
			(xy 145.070055 -96.321439) (xy 145.034364 -96.36263) (xy 144.993173 -96.398321) (xy 144.947323 -96.427787)
			(xy 144.897746 -96.450429) (xy 144.845451 -96.465784) (xy 144.791503 -96.47354) (xy 144.737001 -96.47354)
			(xy 144.683053 -96.465784) (xy 144.630758 -96.450429) (xy 144.581181 -96.427787) (xy 144.535331 -96.398321)
			(xy 144.49414 -96.36263) (xy 144.458449 -96.321439) (xy 144.428983 -96.275589) (xy 144.406341 -96.226012)
			(xy 144.390986 -96.173717) (xy 144.38323 -96.119769) (xy 144.382744 -96.092518) (xy 140.351856 -96.092518)
			(xy 140.312425 -96.125333) (xy 140.264819 -96.154387) (xy 140.21349 -96.176199) (xy 140.159533 -96.190305)
			(xy 140.104096 -96.196405) (xy 140.048362 -96.194368) (xy 139.993519 -96.184238) (xy 139.940735 -96.166231)
			(xy 139.891135 -96.14073) (xy 139.845777 -96.108279) (xy 139.805628 -96.06957) (xy 139.771542 -96.025427)
			(xy 139.744246 -95.976792) (xy 139.724323 -95.924701) (xy 139.712197 -95.870264) (xy 139.708126 -95.814642)
			(xy 134.897839 -95.814642) (xy 134.878857 -95.830439) (xy 134.831251 -95.859493) (xy 134.779922 -95.881305)
			(xy 134.725965 -95.895411) (xy 134.670528 -95.901511) (xy 134.614794 -95.899474) (xy 134.559951 -95.889344)
			(xy 134.507167 -95.871337) (xy 134.457567 -95.845836) (xy 134.412209 -95.813385) (xy 134.37206 -95.774676)
			(xy 134.337974 -95.730533) (xy 134.310678 -95.681898) (xy 134.290755 -95.629807) (xy 134.278629 -95.57537)
			(xy 134.274558 -95.519748) (xy 125.999593 -95.519748) (xy 126.043846 -95.531317) (xy 126.095175 -95.553129)
			(xy 126.142781 -95.582183) (xy 126.185649 -95.617858) (xy 126.222866 -95.659395) (xy 126.253639 -95.705908)
			(xy 126.277311 -95.756405) (xy 126.293379 -95.809812) (xy 126.301499 -95.864988) (xy 126.302008 -95.892874)
			(xy 126.301499 -95.92076) (xy 126.293379 -95.975936) (xy 126.277311 -96.029343) (xy 126.253639 -96.07984)
			(xy 126.222866 -96.126353) (xy 126.185649 -96.16789) (xy 126.142781 -96.203565) (xy 126.095175 -96.232619)
			(xy 126.043846 -96.254431) (xy 125.989889 -96.268537) (xy 125.934452 -96.274637) (xy 125.878718 -96.2726)
			(xy 125.823875 -96.26247) (xy 125.771091 -96.244463) (xy 125.721491 -96.218962) (xy 125.676133 -96.186511)
			(xy 125.635984 -96.147802) (xy 125.601898 -96.103659) (xy 125.574602 -96.055024) (xy 125.554679 -96.002933)
			(xy 125.542553 -95.948496) (xy 125.538482 -95.892874) (xy 125.247776 -95.892874) (xy 125.231589 -95.903277)
			(xy 125.182012 -95.925919) (xy 125.129717 -95.941274) (xy 125.075769 -95.94903) (xy 125.021267 -95.94903)
			(xy 124.967319 -95.941274) (xy 124.915024 -95.925919) (xy 124.865447 -95.903277) (xy 124.819597 -95.873811)
			(xy 124.778406 -95.83812) (xy 124.742715 -95.796929) (xy 124.713249 -95.751079) (xy 124.690607 -95.701502)
			(xy 124.675252 -95.649207) (xy 124.667496 -95.595259) (xy 124.66701 -95.568008) (xy 124.667465 -95.540939)
			(xy 124.675126 -95.487345) (xy 124.690294 -95.435375) (xy 124.701046 -95.410528) (xy 124.706219 -95.398199)
			(xy 124.710587 -95.371831) (xy 124.707951 -95.345233) (xy 124.698492 -95.320235) (xy 124.68286 -95.298555)
			(xy 124.66213 -95.281683) (xy 124.637728 -95.270779) (xy 124.624592 -95.268288) (xy 124.598057 -95.263547)
			(xy 124.546555 -95.247644) (xy 124.497806 -95.224649) (xy 124.452779 -95.19502) (xy 124.412371 -95.159347)
			(xy 124.377389 -95.118341) (xy 124.348528 -95.072817) (xy 124.326363 -95.023685) (xy 124.311337 -94.97192)
			(xy 124.303748 -94.918556) (xy 124.303282 -94.891606) (xy 122.739404 -94.891606) (xy 122.73917 -94.909237)
			(xy 122.735863 -94.944345) (xy 122.7328 -94.96171) (xy 122.731321 -94.972776) (xy 122.736844 -94.99438)
			(xy 122.743468 -95.003366) (xy 122.800618 -95.0722) (xy 122.820938 -95.081852) (xy 122.832368 -95.081852)
			(xy 122.859519 -95.082559) (xy 122.913238 -95.090553) (xy 122.965279 -95.106084) (xy 123.014592 -95.12884)
			(xy 123.060179 -95.158359) (xy 123.101118 -95.194046) (xy 123.136582 -95.235178) (xy 123.165854 -95.280924)
			(xy 123.188342 -95.330359) (xy 123.203591 -95.382484) (xy 123.211294 -95.436245) (xy 123.211294 -95.490555)
			(xy 123.203592 -95.544315) (xy 123.188342 -95.59644) (xy 123.165854 -95.645876) (xy 123.136582 -95.691622)
			(xy 123.101118 -95.732754) (xy 123.060179 -95.76844) (xy 123.014592 -95.79796) (xy 122.96528 -95.820716)
			(xy 122.913238 -95.836247) (xy 122.85952 -95.844241) (xy 122.832368 -95.844868) (xy 122.820938 -95.844868)
			(xy 122.800618 -95.85452) (xy 122.743722 -95.923354) (xy 122.73708 -95.932332) (xy 122.731548 -95.953944)
			(xy 122.733054 -95.96501) (xy 122.73601 -95.982129) (xy 122.739193 -96.016727) (xy 122.739404 -96.034098)
			(xy 122.739404 -96.034606) (xy 122.739225 -96.050494) (xy 122.736553 -96.082158) (xy 122.73407 -96.097852)
			(xy 122.73407 -96.098106) (xy 122.732779 -96.10886) (xy 122.738302 -96.129781) (xy 122.744738 -96.138492)
			(xy 122.793506 -96.197928) (xy 122.800813 -96.205967) (xy 122.820272 -96.215578) (xy 122.831098 -96.21647)
			(xy 122.857792 -96.217716) (xy 122.910457 -96.22678) (xy 122.96134 -96.243108) (xy 123.009447 -96.266377)
			(xy 123.053835 -96.296134) (xy 123.093634 -96.331796) (xy 123.128066 -96.372663) (xy 123.156457 -96.417937)
			(xy 123.166534 -96.440498) (xy 128.268982 -96.440498) (xy 128.273053 -96.384876) (xy 128.285179 -96.330439)
			(xy 128.305102 -96.278348) (xy 128.332398 -96.229713) (xy 128.366484 -96.18557) (xy 128.406633 -96.146861)
			(xy 128.451991 -96.11441) (xy 128.501591 -96.088909) (xy 128.554375 -96.070902) (xy 128.609218 -96.060772)
			(xy 128.664952 -96.058735) (xy 128.720389 -96.064835) (xy 128.774346 -96.078941) (xy 128.825675 -96.100753)
			(xy 128.873281 -96.129807) (xy 128.916149 -96.165482) (xy 128.953366 -96.207019) (xy 128.984139 -96.253532)
			(xy 129.007811 -96.304029) (xy 129.023879 -96.357436) (xy 129.031999 -96.412612) (xy 129.032508 -96.440498)
			(xy 129.031999 -96.468384) (xy 129.023879 -96.52356) (xy 129.007811 -96.576967) (xy 128.984139 -96.627464)
			(xy 128.953366 -96.673977) (xy 128.920869 -96.710246) (xy 134.734044 -96.710246) (xy 134.738115 -96.654624)
			(xy 134.750241 -96.600187) (xy 134.770164 -96.548096) (xy 134.79746 -96.499461) (xy 134.831546 -96.455318)
			(xy 134.871695 -96.416609) (xy 134.917053 -96.384158) (xy 134.966653 -96.358657) (xy 135.019437 -96.34065)
			(xy 135.07428 -96.33052) (xy 135.130014 -96.328483) (xy 135.185451 -96.334583) (xy 135.239408 -96.348689)
			(xy 135.290737 -96.370501) (xy 135.338343 -96.399555) (xy 135.381211 -96.43523) (xy 135.418428 -96.476767)
			(xy 135.449201 -96.52328) (xy 135.472873 -96.573777) (xy 135.488941 -96.627184) (xy 135.497061 -96.68236)
			(xy 135.49757 -96.710246) (xy 135.497061 -96.738132) (xy 135.488941 -96.793308) (xy 135.472873 -96.846715)
			(xy 135.449201 -96.897212) (xy 135.418428 -96.943725) (xy 135.405958 -96.957642) (xy 137.211306 -96.957642)
			(xy 137.215377 -96.90202) (xy 137.227503 -96.847583) (xy 137.247426 -96.795492) (xy 137.274722 -96.746857)
			(xy 137.308808 -96.702714) (xy 137.348957 -96.664005) (xy 137.394315 -96.631554) (xy 137.443915 -96.606053)
			(xy 137.496699 -96.588046) (xy 137.551542 -96.577916) (xy 137.607276 -96.575879) (xy 137.662713 -96.581979)
			(xy 137.71667 -96.596085) (xy 137.767999 -96.617897) (xy 137.815605 -96.646951) (xy 137.858473 -96.682626)
			(xy 137.89569 -96.724163) (xy 137.926463 -96.770676) (xy 137.950135 -96.821173) (xy 137.966203 -96.87458)
			(xy 137.974323 -96.929756) (xy 137.974832 -96.957642) (xy 139.708126 -96.957642) (xy 139.712197 -96.90202)
			(xy 139.724323 -96.847583) (xy 139.744246 -96.795492) (xy 139.771542 -96.746857) (xy 139.805628 -96.702714)
			(xy 139.845777 -96.664005) (xy 139.891135 -96.631554) (xy 139.940735 -96.606053) (xy 139.993519 -96.588046)
			(xy 140.048362 -96.577916) (xy 140.104096 -96.575879) (xy 140.159533 -96.581979) (xy 140.21349 -96.596085)
			(xy 140.264819 -96.617897) (xy 140.312425 -96.646951) (xy 140.355293 -96.682626) (xy 140.39251 -96.724163)
			(xy 140.423283 -96.770676) (xy 140.446955 -96.821173) (xy 140.463023 -96.87458) (xy 140.471143 -96.929756)
			(xy 140.471652 -96.957642) (xy 140.471143 -96.985528) (xy 140.463023 -97.040704) (xy 140.446955 -97.094111)
			(xy 140.423283 -97.144608) (xy 140.399603 -97.1804) (xy 153.32532 -97.1804) (xy 153.329391 -97.124778)
			(xy 153.341517 -97.070341) (xy 153.36144 -97.01825) (xy 153.388736 -96.969615) (xy 153.422822 -96.925472)
			(xy 153.462971 -96.886763) (xy 153.508329 -96.854312) (xy 153.557929 -96.828811) (xy 153.610713 -96.810804)
			(xy 153.665556 -96.800674) (xy 153.72129 -96.798637) (xy 153.776727 -96.804737) (xy 153.830684 -96.818843)
			(xy 153.882013 -96.840655) (xy 153.929619 -96.869709) (xy 153.972487 -96.905384) (xy 154.009704 -96.946921)
			(xy 154.040477 -96.993434) (xy 154.064149 -97.043931) (xy 154.067686 -97.055686) (xy 167.705276 -97.055686)
			(xy 167.709347 -97.000064) (xy 167.721473 -96.945627) (xy 167.741396 -96.893536) (xy 167.768692 -96.844901)
			(xy 167.802778 -96.800758) (xy 167.842927 -96.762049) (xy 167.888285 -96.729598) (xy 167.937885 -96.704097)
			(xy 167.990669 -96.68609) (xy 168.045512 -96.67596) (xy 168.101246 -96.673923) (xy 168.156683 -96.680023)
			(xy 168.21064 -96.694129) (xy 168.261969 -96.715941) (xy 168.309575 -96.744995) (xy 168.352443 -96.78067)
			(xy 168.38966 -96.822207) (xy 168.394783 -96.829951) (xy 185.42278 -96.829951) (xy 185.42278 -96.775449)
			(xy 185.430536 -96.721502) (xy 185.445891 -96.669208) (xy 185.468531 -96.619632) (xy 185.497997 -96.573782)
			(xy 185.533688 -96.532592) (xy 185.574877 -96.496901) (xy 185.620726 -96.467434) (xy 185.670303 -96.444793)
			(xy 185.722596 -96.429437) (xy 185.776543 -96.42168) (xy 185.803794 -96.421194) (xy 185.831841 -96.421677)
			(xy 185.88733 -96.429896) (xy 185.94102 -96.446143) (xy 185.991757 -96.470069) (xy 186.015376 -96.485202)
			(xy 186.026935 -96.492428) (xy 186.052805 -96.500995) (xy 186.08002 -96.502419) (xy 186.106643 -96.496596)
			(xy 186.130779 -96.483942) (xy 186.150711 -96.465358) (xy 186.16502 -96.442165) (xy 186.172688 -96.416014)
			(xy 186.173364 -96.402398) (xy 186.1744 -96.372946) (xy 186.183599 -96.314739) (xy 186.200909 -96.258409)
			(xy 186.225984 -96.205081) (xy 186.258324 -96.155818) (xy 186.297282 -96.111604) (xy 186.342083 -96.073321)
			(xy 186.391831 -96.041733) (xy 186.445534 -96.017471) (xy 186.50212 -96.001018) (xy 186.560459 -95.992703)
			(xy 186.589924 -95.992188) (xy 186.618386 -95.992579) (xy 186.674781 -96.000334) (xy 186.729594 -96.015694)
			(xy 186.781805 -96.038376) (xy 186.830442 -96.067955) (xy 186.874598 -96.103881) (xy 186.913452 -96.145485)
			(xy 186.946278 -96.191992) (xy 186.972466 -96.242535) (xy 186.991529 -96.296173) (xy 187.00311 -96.351908)
			(xy 187.006995 -96.4087) (xy 187.00311 -96.465492) (xy 186.991529 -96.521227) (xy 186.972466 -96.574865)
			(xy 186.946278 -96.625408) (xy 186.913452 -96.671915) (xy 186.874598 -96.713519) (xy 186.830442 -96.749445)
			(xy 186.781805 -96.779024) (xy 186.729594 -96.801706) (xy 186.674781 -96.817066) (xy 186.618386 -96.824821)
			(xy 186.589924 -96.825308) (xy 186.563834 -96.824931) (xy 186.512064 -96.818415) (xy 186.461513 -96.805483)
			(xy 186.412974 -96.786337) (xy 186.367207 -96.761276) (xy 186.34583 -96.746314) (xy 186.334524 -96.738674)
			(xy 186.308974 -96.72912) (xy 186.281807 -96.72667) (xy 186.25496 -96.731499) (xy 186.230349 -96.743261)
			(xy 186.209729 -96.761119) (xy 186.194572 -96.783798) (xy 186.185958 -96.80968) (xy 186.184794 -96.823276)
			(xy 186.182744 -96.85216) (xy 186.172544 -96.901) (xy 187.872876 -96.901) (xy 187.876947 -96.845378)
			(xy 187.889073 -96.790941) (xy 187.908996 -96.73885) (xy 187.936292 -96.690215) (xy 187.970378 -96.646072)
			(xy 188.010527 -96.607363) (xy 188.055885 -96.574912) (xy 188.105485 -96.549411) (xy 188.158269 -96.531404)
			(xy 188.213112 -96.521274) (xy 188.268846 -96.519237) (xy 188.324283 -96.525337) (xy 188.37824 -96.539443)
			(xy 188.429569 -96.561255) (xy 188.477175 -96.590309) (xy 188.520043 -96.625984) (xy 188.55726 -96.667521)
			(xy 188.588033 -96.714034) (xy 188.611705 -96.764531) (xy 188.627773 -96.817938) (xy 188.635893 -96.873114)
			(xy 188.636402 -96.901) (xy 188.635893 -96.928886) (xy 188.627773 -96.984062) (xy 188.611705 -97.037469)
			(xy 188.588033 -97.087966) (xy 188.55726 -97.134479) (xy 188.520043 -97.176016) (xy 188.477175 -97.211691)
			(xy 188.429569 -97.240745) (xy 188.37824 -97.262557) (xy 188.324283 -97.276663) (xy 188.268846 -97.282763)
			(xy 188.213112 -97.280726) (xy 188.158269 -97.270596) (xy 188.105485 -97.252589) (xy 188.055885 -97.227088)
			(xy 188.010527 -97.194637) (xy 187.970378 -97.155928) (xy 187.936292 -97.111785) (xy 187.908996 -97.06315)
			(xy 187.889073 -97.011059) (xy 187.876947 -96.956622) (xy 187.872876 -96.901) (xy 186.172544 -96.901)
			(xy 186.170907 -96.908841) (xy 186.150643 -96.963084) (xy 186.122416 -97.013643) (xy 186.086875 -97.059356)
			(xy 186.044835 -97.099176) (xy 185.997262 -97.132187) (xy 185.945248 -97.157632) (xy 185.889986 -97.174926)
			(xy 185.832746 -97.183674) (xy 185.803794 -97.18421) (xy 185.776543 -97.18372) (xy 185.722596 -97.175963)
			(xy 185.670303 -97.160607) (xy 185.620726 -97.137966) (xy 185.574877 -97.108499) (xy 185.533688 -97.072808)
			(xy 185.497997 -97.031618) (xy 185.468531 -96.985768) (xy 185.445891 -96.936192) (xy 185.430536 -96.883898)
			(xy 185.42278 -96.829951) (xy 168.394783 -96.829951) (xy 168.420433 -96.86872) (xy 168.444105 -96.919217)
			(xy 168.460173 -96.972624) (xy 168.468293 -97.0278) (xy 168.468802 -97.055686) (xy 168.468293 -97.083572)
			(xy 168.460173 -97.138748) (xy 168.444105 -97.192155) (xy 168.420433 -97.242652) (xy 168.38966 -97.289165)
			(xy 168.352443 -97.330702) (xy 168.309575 -97.366377) (xy 168.261969 -97.395431) (xy 168.21064 -97.417243)
			(xy 168.156683 -97.431349) (xy 168.101246 -97.437449) (xy 168.045512 -97.435412) (xy 167.990669 -97.425282)
			(xy 167.937885 -97.407275) (xy 167.888285 -97.381774) (xy 167.842927 -97.349323) (xy 167.802778 -97.310614)
			(xy 167.768692 -97.266471) (xy 167.741396 -97.217836) (xy 167.721473 -97.165745) (xy 167.709347 -97.111308)
			(xy 167.705276 -97.055686) (xy 154.067686 -97.055686) (xy 154.080217 -97.097338) (xy 154.088337 -97.152514)
			(xy 154.088846 -97.1804) (xy 154.088337 -97.208286) (xy 154.080217 -97.263462) (xy 154.064149 -97.316869)
			(xy 154.040477 -97.367366) (xy 154.009704 -97.413879) (xy 153.972487 -97.455416) (xy 153.929619 -97.491091)
			(xy 153.882013 -97.520145) (xy 153.830684 -97.541957) (xy 153.776727 -97.556063) (xy 153.72129 -97.562163)
			(xy 153.665556 -97.560126) (xy 153.610713 -97.549996) (xy 153.557929 -97.531989) (xy 153.508329 -97.506488)
			(xy 153.462971 -97.474037) (xy 153.422822 -97.435328) (xy 153.388736 -97.391185) (xy 153.36144 -97.34255)
			(xy 153.341517 -97.290459) (xy 153.329391 -97.236022) (xy 153.32532 -97.1804) (xy 140.399603 -97.1804)
			(xy 140.39251 -97.191121) (xy 140.355293 -97.232658) (xy 140.312425 -97.268333) (xy 140.264819 -97.297387)
			(xy 140.21349 -97.319199) (xy 140.159533 -97.333305) (xy 140.104096 -97.339405) (xy 140.048362 -97.337368)
			(xy 139.993519 -97.327238) (xy 139.940735 -97.309231) (xy 139.891135 -97.28373) (xy 139.845777 -97.251279)
			(xy 139.805628 -97.21257) (xy 139.771542 -97.168427) (xy 139.744246 -97.119792) (xy 139.724323 -97.067701)
			(xy 139.712197 -97.013264) (xy 139.708126 -96.957642) (xy 137.974832 -96.957642) (xy 137.974323 -96.985528)
			(xy 137.966203 -97.040704) (xy 137.950135 -97.094111) (xy 137.926463 -97.144608) (xy 137.89569 -97.191121)
			(xy 137.858473 -97.232658) (xy 137.815605 -97.268333) (xy 137.767999 -97.297387) (xy 137.71667 -97.319199)
			(xy 137.662713 -97.333305) (xy 137.607276 -97.339405) (xy 137.551542 -97.337368) (xy 137.496699 -97.327238)
			(xy 137.443915 -97.309231) (xy 137.394315 -97.28373) (xy 137.348957 -97.251279) (xy 137.308808 -97.21257)
			(xy 137.274722 -97.168427) (xy 137.247426 -97.119792) (xy 137.227503 -97.067701) (xy 137.215377 -97.013264)
			(xy 137.211306 -96.957642) (xy 135.405958 -96.957642) (xy 135.381211 -96.985262) (xy 135.338343 -97.020937)
			(xy 135.290737 -97.049991) (xy 135.239408 -97.071803) (xy 135.185451 -97.085909) (xy 135.130014 -97.092009)
			(xy 135.07428 -97.089972) (xy 135.019437 -97.079842) (xy 134.966653 -97.061835) (xy 134.917053 -97.036334)
			(xy 134.871695 -97.003883) (xy 134.831546 -96.965174) (xy 134.79746 -96.921031) (xy 134.770164 -96.872396)
			(xy 134.750241 -96.820305) (xy 134.738115 -96.765868) (xy 134.734044 -96.710246) (xy 128.920869 -96.710246)
			(xy 128.916149 -96.715514) (xy 128.873281 -96.751189) (xy 128.825675 -96.780243) (xy 128.774346 -96.802055)
			(xy 128.720389 -96.816161) (xy 128.664952 -96.822261) (xy 128.609218 -96.820224) (xy 128.554375 -96.810094)
			(xy 128.501591 -96.792087) (xy 128.451991 -96.766586) (xy 128.406633 -96.734135) (xy 128.366484 -96.695426)
			(xy 128.332398 -96.651283) (xy 128.305102 -96.602648) (xy 128.285179 -96.550557) (xy 128.273053 -96.49612)
			(xy 128.268982 -96.440498) (xy 123.166534 -96.440498) (xy 123.17825 -96.46673) (xy 123.193019 -96.518088)
			(xy 123.200475 -96.571004) (xy 123.200922 -96.597724) (xy 123.200501 -96.624556) (xy 123.193004 -96.677694)
			(xy 123.178134 -96.729256) (xy 123.156183 -96.778225) (xy 123.127585 -96.823635) (xy 123.092905 -96.864587)
			(xy 123.052828 -96.900275) (xy 123.008144 -96.929993) (xy 122.959736 -96.953155) (xy 122.90856 -96.969304)
			(xy 122.855625 -96.97812) (xy 122.828812 -96.979232) (xy 122.817666 -96.98008) (xy 122.797639 -96.989939)
			(xy 122.790204 -96.998282) (xy 122.741436 -97.059496) (xy 122.735053 -97.068511) (xy 122.729915 -97.089971)
			(xy 122.73153 -97.100898) (xy 122.73153 -97.101406) (xy 122.735175 -97.120246) (xy 122.739116 -97.158419)
			(xy 122.739332 -97.17278) (xy 124.302772 -97.17278) (xy 124.306843 -97.117158) (xy 124.318969 -97.062721)
			(xy 124.338892 -97.01063) (xy 124.366188 -96.961995) (xy 124.400274 -96.917852) (xy 124.440423 -96.879143)
			(xy 124.485781 -96.846692) (xy 124.535381 -96.821191) (xy 124.588165 -96.803184) (xy 124.643008 -96.793054)
			(xy 124.698742 -96.791017) (xy 124.754179 -96.797117) (xy 124.808136 -96.811223) (xy 124.859465 -96.833035)
			(xy 124.907071 -96.862089) (xy 124.949939 -96.897764) (xy 124.987156 -96.939301) (xy 125.017929 -96.985814)
			(xy 125.041601 -97.036311) (xy 125.057669 -97.089718) (xy 125.065789 -97.144894) (xy 125.066298 -97.17278)
			(xy 125.065789 -97.200666) (xy 125.057669 -97.255842) (xy 125.041601 -97.309249) (xy 125.017929 -97.359746)
			(xy 124.987156 -97.406259) (xy 124.949939 -97.447796) (xy 124.907071 -97.483471) (xy 124.859465 -97.512525)
			(xy 124.808136 -97.534337) (xy 124.754179 -97.548443) (xy 124.698742 -97.554543) (xy 124.643008 -97.552506)
			(xy 124.588165 -97.542376) (xy 124.535381 -97.524369) (xy 124.485781 -97.498868) (xy 124.440423 -97.466417)
			(xy 124.400274 -97.427708) (xy 124.366188 -97.383565) (xy 124.338892 -97.33493) (xy 124.318969 -97.282839)
			(xy 124.306843 -97.228402) (xy 124.302772 -97.17278) (xy 122.739332 -97.17278) (xy 122.739404 -97.177606)
			(xy 122.738918 -97.204857) (xy 122.731162 -97.258805) (xy 122.715807 -97.3111) (xy 122.693165 -97.360677)
			(xy 122.663699 -97.406527) (xy 122.628008 -97.447718) (xy 122.586817 -97.483409) (xy 122.540967 -97.512875)
			(xy 122.49139 -97.535517) (xy 122.439095 -97.550872) (xy 122.385147 -97.558628) (xy 122.330645 -97.558628)
			(xy 122.276697 -97.550872) (xy 122.224402 -97.535517) (xy 122.174825 -97.512875) (xy 122.128975 -97.483409)
			(xy 122.087784 -97.447718) (xy 122.052093 -97.406527) (xy 122.022627 -97.360677) (xy 121.999985 -97.3111)
			(xy 121.98463 -97.258805) (xy 121.976874 -97.204857) (xy 121.976388 -97.177606) (xy 120.50141 -97.177606)
			(xy 120.500901 -97.205492) (xy 120.492781 -97.260668) (xy 120.476713 -97.314075) (xy 120.453041 -97.364572)
			(xy 120.422268 -97.411085) (xy 120.385051 -97.452622) (xy 120.342183 -97.488297) (xy 120.294577 -97.517351)
			(xy 120.243248 -97.539163) (xy 120.189291 -97.553269) (xy 120.133854 -97.559369) (xy 120.07812 -97.557332)
			(xy 120.023277 -97.547202) (xy 119.970493 -97.529195) (xy 119.920893 -97.503694) (xy 119.875535 -97.471243)
			(xy 119.835386 -97.432534) (xy 119.8013 -97.388391) (xy 119.774004 -97.339756) (xy 119.754081 -97.287665)
			(xy 119.741955 -97.233228) (xy 119.737884 -97.177606) (xy 114.272583 -97.177606) (xy 114.272822 -97.190814)
			(xy 114.272335 -97.218065) (xy 114.264577 -97.272012) (xy 114.249221 -97.324306) (xy 114.226579 -97.373882)
			(xy 114.197113 -97.419732) (xy 114.161422 -97.460922) (xy 114.120232 -97.496613) (xy 114.074382 -97.526079)
			(xy 114.024806 -97.548721) (xy 113.972512 -97.564077) (xy 113.918565 -97.571835) (xy 113.891314 -97.572322)
			(xy 113.863577 -97.571819) (xy 113.808688 -97.563776) (xy 113.755541 -97.547873) (xy 113.705256 -97.524444)
			(xy 113.658892 -97.493984) (xy 113.617425 -97.457132) (xy 113.58173 -97.414667) (xy 113.552557 -97.367482)
			(xy 113.530522 -97.316571) (xy 113.516088 -97.263006) (xy 113.512346 -97.235518) (xy 113.510822 -97.221548)
			(xy 113.509552 -97.190814) (xy 113.509733 -97.175439) (xy 113.512276 -97.144794) (xy 113.514632 -97.1296)
			(xy 113.519624 -97.101994) (xy 113.536635 -97.048536) (xy 113.561286 -96.998143) (xy 113.593046 -96.951899)
			(xy 113.63123 -96.9108) (xy 113.652808 -96.892872) (xy 113.659186 -96.886319) (xy 113.667247 -96.869919)
			(xy 113.668556 -96.860868) (xy 113.667032 -96.811592) (xy 113.665762 -96.76892) (xy 113.665166 -96.764698)
			(xy 113.662748 -96.756523) (xy 113.660936 -96.752664) (xy 113.658396 -96.748092) (xy 113.65103 -96.739202)
			(xy 113.646204 -96.735392) (xy 113.622799 -96.717247) (xy 113.581356 -96.674946) (xy 113.546939 -96.626755)
			(xy 113.520372 -96.573829) (xy 113.502293 -96.517438) (xy 113.493134 -96.458931) (xy 113.492534 -96.429322)
			(xy 113.49299 -96.402485) (xy 113.500517 -96.349341) (xy 113.515425 -96.297779) (xy 113.537419 -96.248818)
			(xy 113.566063 -96.203427) (xy 113.600793 -96.162503) (xy 113.62055 -96.144334) (xy 113.620804 -96.14408)
			(xy 113.627835 -96.137049) (xy 113.636381 -96.119116) (xy 113.637519 -96.099283) (xy 113.634774 -96.089724)
			(xy 113.617502 -96.044004) (xy 113.600484 -95.999554) (xy 113.596396 -95.99012) (xy 113.582158 -95.975313)
			(xy 113.563257 -95.967269) (xy 113.552986 -95.966788) (xy 111.94542 -95.966788) (xy 111.940848 -95.967042)
			(xy 111.938054 -95.967042) (xy 111.9251 -95.967296) (xy 110.287308 -95.967296) (xy 110.274354 -95.967042)
			(xy 110.27156 -95.967042) (xy 110.266988 -95.966788) (xy 110.067344 -95.966788) (xy 110.057279 -95.966354)
			(xy 110.03869 -95.958624) (xy 110.031276 -95.951802) (xy 109.889036 -95.809562) (xy 109.88802 -95.808546)
			(xy 109.875828 -95.796608) (xy 109.490256 -95.411036) (xy 109.478318 -95.398844) (xy 109.477302 -95.397828)
			(xy 108.964476 -94.885002) (xy 108.957621 -94.877607) (xy 108.949874 -94.859008) (xy 108.94949 -94.848934)
			(xy 108.94949 -91.128088) (xy 108.94568 -91.11869) (xy 108.935879 -91.093605) (xy 108.922088 -91.041543)
			(xy 108.915121 -90.988138) (xy 108.914692 -90.96121) (xy 108.915132 -90.934282) (xy 108.922101 -90.880879)
			(xy 108.935886 -90.828817) (xy 108.94568 -90.80373) (xy 108.94949 -90.794332) (xy 108.94949 -90.290904)
			(xy 108.948951 -90.280544) (xy 108.940695 -90.261535) (xy 108.933488 -90.254074) (xy 108.906564 -90.228674)
			(xy 108.877862 -90.20175) (xy 108.870189 -90.195764) (xy 108.85178 -90.189502) (xy 108.842048 -90.189558)
			(xy 108.841794 -90.189558) (xy 108.81868 -90.19032) (xy 108.805942 -90.190241) (xy 108.780521 -90.188586)
			(xy 108.76788 -90.187018) (xy 108.76788 -90.187272) (xy 108.735622 -90.18143) (xy 108.7247 -90.179144)
			(xy 108.71581 -90.180922) (xy 108.710965 -90.181901) (xy 108.701755 -90.185482) (xy 108.697522 -90.188034)
			(xy 108.633768 -90.230198) (xy 108.630257 -90.232894) (xy 108.624128 -90.239281) (xy 108.621576 -90.242898)
			(xy 108.615988 -90.251026) (xy 108.613956 -90.261694) (xy 108.608552 -90.287516) (xy 108.591578 -90.337466)
			(xy 108.567889 -90.384604) (xy 108.537936 -90.428031) (xy 108.502288 -90.466921) (xy 108.461626 -90.500532)
			(xy 108.416723 -90.528225) (xy 108.368435 -90.549471) (xy 108.317682 -90.563867) (xy 108.26543 -90.571137)
			(xy 108.239052 -90.571574) (xy 108.211804 -90.571084) (xy 108.157863 -90.563322) (xy 108.105576 -90.547963)
			(xy 108.056007 -90.525318) (xy 108.010165 -90.49585) (xy 107.968984 -90.460158) (xy 107.933301 -90.418969)
			(xy 107.903842 -90.373121) (xy 107.881209 -90.323547) (xy 107.86586 -90.271257) (xy 107.85811 -90.217314)
			(xy 107.857544 -90.190066) (xy 107.858044 -90.162328) (xy 107.866081 -90.107436) (xy 107.88198 -90.054287)
			(xy 107.905407 -90.003999) (xy 107.935868 -89.957633) (xy 107.97272 -89.916166) (xy 108.015188 -89.880471)
			(xy 108.062377 -89.851301) (xy 108.113291 -89.82927) (xy 108.166859 -89.814843) (xy 108.194348 -89.811098)
			(xy 108.208826 -89.809574) (xy 108.239052 -89.808304) (xy 108.25999 -89.808585) (xy 108.301614 -89.813162)
			(xy 108.32211 -89.817448) (xy 108.333032 -89.819734) (xy 108.341922 -89.817956) (xy 108.346916 -89.816979)
			(xy 108.356388 -89.813264) (xy 108.360718 -89.81059) (xy 108.422186 -89.76995) (xy 108.425882 -89.767352)
			(xy 108.432398 -89.761095) (xy 108.43514 -89.757504) (xy 108.441744 -89.747598) (xy 108.443776 -89.737184)
			(xy 108.450056 -89.707291) (xy 108.470853 -89.649862) (xy 108.485178 -89.622884) (xy 108.486956 -89.62009)
			(xy 108.500401 -89.59735) (xy 108.532593 -89.555464) (xy 108.57025 -89.518413) (xy 108.612653 -89.486906)
			(xy 108.658994 -89.461543) (xy 108.708388 -89.442807) (xy 108.759892 -89.431057) (xy 108.786168 -89.42832)
			(xy 108.787184 -89.42832) (xy 108.8009 -89.427558) (xy 108.801408 -89.427558) (xy 108.818426 -89.42705)
			(xy 108.818934 -89.42705) (xy 108.841794 -89.427812) (xy 108.852716 -89.42832) (xy 108.861606 -89.425272)
			(xy 108.865953 -89.423652) (xy 108.874012 -89.419058) (xy 108.877608 -89.416128) (xy 108.933488 -89.36355)
			(xy 108.940714 -89.356102) (xy 108.948967 -89.337085) (xy 108.94949 -89.32672) (xy 108.94949 -88.30945)
			(xy 108.948982 -88.302592) (xy 108.947589 -88.295212) (xy 108.941128 -88.281661) (xy 108.936282 -88.275922)
			(xy 108.911136 -88.251284) (xy 108.880148 -88.221058) (xy 108.876876 -88.218313) (xy 108.869598 -88.213844)
			(xy 108.86567 -88.212168) (xy 108.85678 -88.208612) (xy 108.839 -88.208612) (xy 108.811748 -88.208126)
			(xy 108.7578 -88.20037) (xy 108.705505 -88.185014) (xy 108.655927 -88.162373) (xy 108.610076 -88.132906)
			(xy 108.568886 -88.097214) (xy 108.533194 -88.056024) (xy 108.503727 -88.010173) (xy 108.481086 -87.960595)
			(xy 108.46573 -87.9083) (xy 108.457974 -87.854352) (xy 108.457974 -87.799848) (xy 108.46573 -87.7459)
			(xy 108.481086 -87.693605) (xy 108.503727 -87.644027) (xy 108.533194 -87.598176) (xy 108.568886 -87.556986)
			(xy 108.610076 -87.521294) (xy 108.655927 -87.491827) (xy 108.705505 -87.469186) (xy 108.7578 -87.45383)
			(xy 108.811748 -87.446074) (xy 108.839 -87.445596) (xy 108.85678 -87.445596) (xy 108.86567 -87.44204)
			(xy 108.870232 -87.44003) (xy 108.878543 -87.434528) (xy 108.88218 -87.431118) (xy 108.93425 -87.380318)
			(xy 108.941205 -87.372896) (xy 108.949077 -87.354159) (xy 108.94949 -87.343996) (xy 108.94949 -84.619592)
			(xy 108.948947 -84.611471) (xy 108.943374 -84.596189) (xy 108.938568 -84.58962) (xy 108.936028 -84.586826)
			(xy 108.886752 -84.539582) (xy 108.878116 -84.5312) (xy 108.874808 -84.528657) (xy 108.867532 -84.524571)
			(xy 108.863638 -84.523072) (xy 108.854494 -84.51977) (xy 108.844334 -84.520024) (xy 108.828586 -84.520278)
			(xy 108.801338 -84.519791) (xy 108.747396 -84.512033) (xy 108.695107 -84.496678) (xy 108.645535 -84.474038)
			(xy 108.59969 -84.444574) (xy 108.558505 -84.408885) (xy 108.522818 -84.367699) (xy 108.493355 -84.321852)
			(xy 108.470717 -84.27228) (xy 108.455364 -84.219991) (xy 108.447608 -84.166048) (xy 108.447608 -84.111552)
			(xy 108.455364 -84.057609) (xy 108.470717 -84.00532) (xy 108.493355 -83.955748) (xy 108.522818 -83.909901)
			(xy 108.558505 -83.868715) (xy 108.59969 -83.833026) (xy 108.645535 -83.803562) (xy 108.695107 -83.780922)
			(xy 108.747396 -83.765567) (xy 108.801338 -83.757809) (xy 108.828586 -83.757262) (xy 108.84408 -83.757516)
			(xy 108.854494 -83.75777) (xy 108.863638 -83.754468) (xy 108.867766 -83.752842) (xy 108.875431 -83.748373)
			(xy 108.878878 -83.745578) (xy 108.899198 -83.72602) (xy 108.93552 -83.691222) (xy 108.938568 -83.68792)
			(xy 108.94337 -83.68135) (xy 108.948933 -83.666067) (xy 108.94949 -83.657948) (xy 108.94949 -82.20964)
			(xy 108.947204 -82.202274) (xy 108.943394 -82.18932) (xy 108.94314 -82.188304) (xy 108.942632 -82.18678)
			(xy 108.940346 -82.178398) (xy 108.931964 -82.167984) (xy 108.929032 -82.164995) (xy 108.922396 -82.159892)
			(xy 108.918756 -82.157824) (xy 108.907072 -82.152236) (xy 108.906056 -82.151728) (xy 108.854494 -82.128106)
			(xy 108.84154 -82.12455) (xy 108.841032 -82.12455) (xy 108.834682 -82.124042) (xy 108.81741 -82.124042)
			(xy 108.808774 -82.124804) (xy 108.805218 -82.125566) (xy 108.793026 -82.12836) (xy 108.792772 -82.12836)
			(xy 108.78947 -82.129884) (xy 108.7882 -82.130392) (xy 108.764527 -82.13998) (xy 108.715262 -82.153455)
			(xy 108.66464 -82.160233) (xy 108.639102 -82.160618) (xy 108.634022 -82.160618) (xy 108.60701 -82.159788)
			(xy 108.553616 -82.151449) (xy 108.501933 -82.135658) (xy 108.452996 -82.11273) (xy 108.407785 -82.083125)
			(xy 108.367205 -82.047436) (xy 108.332069 -82.006376) (xy 108.303079 -81.960768) (xy 108.280816 -81.911525)
			(xy 108.265727 -81.859633) (xy 108.258112 -81.806131) (xy 108.257594 -81.77911) (xy 108.258065 -81.752054)
			(xy 108.26571 -81.698486) (xy 108.280847 -81.646535) (xy 108.303172 -81.597244) (xy 108.332239 -81.551602)
			(xy 108.367463 -81.510526) (xy 108.408137 -81.474838) (xy 108.453447 -81.445256) (xy 108.502481 -81.422373)
			(xy 108.554257 -81.406648) (xy 108.607736 -81.398396) (xy 108.634784 -81.397602) (xy 108.641134 -81.397602)
			(xy 108.669119 -81.398221) (xy 108.724457 -81.406652) (xy 108.777968 -81.423079) (xy 108.80344 -81.434686)
			(xy 108.809536 -81.43748) (xy 108.818172 -81.439512) (xy 108.824522 -81.44002) (xy 108.837476 -81.43875)
			(xy 108.84916 -81.434432) (xy 108.888784 -81.409794) (xy 108.9279 -81.385156) (xy 108.928408 -81.384648)
			(xy 108.931456 -81.382108) (xy 108.931964 -81.3816) (xy 108.934758 -81.37906) (xy 108.937852 -81.375862)
			(xy 108.942962 -81.368579) (xy 108.944918 -81.364582) (xy 108.94693 -81.359869) (xy 108.949241 -81.349888)
			(xy 108.94949 -81.34477) (xy 108.94949 -80.50657) (xy 108.949325 -80.50056) (xy 108.946505 -80.488876)
			(xy 108.943902 -80.483456) (xy 108.942061 -80.479983) (xy 108.937465 -80.473606) (xy 108.934758 -80.470756)
			(xy 107.572556 -79.108554) (xy 107.568159 -79.10449) (xy 107.557889 -79.098339) (xy 107.552236 -79.096362)
			(xy 107.542076 -79.093568) (xy 107.52836 -79.094076) (xy 107.514136 -79.098394) (xy 107.512612 -79.098902)
			(xy 107.512358 -79.098902) (xy 107.511342 -79.099156) (xy 107.507786 -79.100172) (xy 107.496178 -79.103171)
			(xy 107.472665 -79.107872) (xy 107.460796 -79.10957) (xy 107.460288 -79.10957) (xy 107.45089 -79.11084)
			(xy 107.449366 -79.11084) (xy 107.447588 -79.111094) (xy 107.446572 -79.111094) (xy 107.431332 -79.112364)
			(xy 107.429046 -79.112364) (xy 107.42676 -79.112618) (xy 107.425236 -79.112618) (xy 107.411012 -79.113126)
			(xy 107.409488 -79.113126) (xy 107.382102 -79.112638) (xy 107.327898 -79.104773) (xy 107.275376 -79.089236)
			(xy 107.225616 -79.066346) (xy 107.179642 -79.036574) (xy 107.138399 -79.000533) (xy 107.102736 -78.958962)
			(xy 107.08767 -78.936088) (xy 107.0864 -78.93431) (xy 107.082844 -78.929484) (xy 107.076494 -78.923896)
			(xy 107.06989 -78.919324) (xy 107.048554 -78.906878) (xy 107.045011 -78.905029) (xy 107.037482 -78.902349)
			(xy 107.033568 -78.901544) (xy 107.025186 -78.900782) (xy 96.56064 -78.900782) (xy 96.554631 -78.90095)
			(xy 96.542949 -78.903775) (xy 96.537526 -78.90637) (xy 96.534049 -78.908206) (xy 96.527664 -78.912794)
			(xy 96.524826 -78.915514) (xy 95.423188 -80.017152) (xy 103.627889 -80.017152) (xy 103.627889 -79.962648)
			(xy 103.635647 -79.908699) (xy 103.651003 -79.856403) (xy 103.673646 -79.806824) (xy 103.703115 -79.760974)
			(xy 103.738809 -79.719784) (xy 103.780003 -79.684093) (xy 103.825856 -79.654629) (xy 103.875436 -79.63199)
			(xy 103.927734 -79.616639) (xy 103.981684 -79.608887) (xy 104.008936 -79.608426) (xy 104.036307 -79.608865)
			(xy 104.090488 -79.616688) (xy 104.142991 -79.632183) (xy 104.192738 -79.655031) (xy 104.238703 -79.684762)
			(xy 104.259634 -79.702406) (xy 104.259888 -79.70266) (xy 104.266969 -79.708255) (xy 104.28389 -79.714495)
			(xy 104.292908 -79.714852) (xy 104.359964 -79.714852) (xy 104.36898 -79.714488) (xy 104.385898 -79.708246)
			(xy 104.392984 -79.70266) (xy 104.392984 -79.702406) (xy 104.393238 -79.702406) (xy 104.414183 -79.684783)
			(xy 104.460152 -79.655069) (xy 104.509897 -79.63223) (xy 104.562394 -79.616735) (xy 104.616568 -79.608902)
			(xy 104.643936 -79.608426) (xy 104.671188 -79.608846) (xy 104.725137 -79.616608) (xy 104.777432 -79.631967)
			(xy 104.827009 -79.654613) (xy 104.872859 -79.684082) (xy 104.914048 -79.719777) (xy 104.949739 -79.76097)
			(xy 104.979205 -79.806823) (xy 105.001845 -79.856402) (xy 105.0172 -79.908699) (xy 105.024956 -79.962648)
			(xy 105.024956 -80.017152) (xy 105.0172 -80.071101) (xy 105.001845 -80.123398) (xy 104.979205 -80.172977)
			(xy 104.949739 -80.21883) (xy 104.914048 -80.260023) (xy 104.872859 -80.295718) (xy 104.827009 -80.325187)
			(xy 104.777432 -80.347833) (xy 104.725137 -80.363192) (xy 104.671188 -80.370954) (xy 104.643936 -80.371442)
			(xy 104.616566 -80.370969) (xy 104.562386 -80.363155) (xy 104.509883 -80.347668) (xy 104.460136 -80.324828)
			(xy 104.414169 -80.295103) (xy 104.393238 -80.277462) (xy 104.392984 -80.277208) (xy 104.385906 -80.271609)
			(xy 104.368983 -80.26537) (xy 104.359964 -80.265016) (xy 104.292908 -80.265016) (xy 104.283891 -80.265373)
			(xy 104.266974 -80.27162) (xy 104.259888 -80.277208) (xy 104.259888 -80.277462) (xy 104.259634 -80.277462)
			(xy 104.238695 -80.295093) (xy 104.192725 -80.324807) (xy 104.142979 -80.347645) (xy 104.09048 -80.363138)
			(xy 104.036305 -80.370968) (xy 104.008936 -80.371442) (xy 103.981684 -80.370913) (xy 103.927734 -80.363161)
			(xy 103.875436 -80.34781) (xy 103.825856 -80.325171) (xy 103.780003 -80.295707) (xy 103.738809 -80.260016)
			(xy 103.703115 -80.218826) (xy 103.673646 -80.172976) (xy 103.651003 -80.123397) (xy 103.635647 -80.071101)
			(xy 103.627889 -80.017152) (xy 95.423188 -80.017152) (xy 93.239082 -82.201258) (xy 107.056934 -82.201258)
			(xy 107.061005 -82.145636) (xy 107.073131 -82.091199) (xy 107.093054 -82.039108) (xy 107.12035 -81.990473)
			(xy 107.154436 -81.94633) (xy 107.194585 -81.907621) (xy 107.239943 -81.87517) (xy 107.289543 -81.849669)
			(xy 107.342327 -81.831662) (xy 107.39717 -81.821532) (xy 107.452904 -81.819495) (xy 107.508341 -81.825595)
			(xy 107.562298 -81.839701) (xy 107.613627 -81.861513) (xy 107.661233 -81.890567) (xy 107.704101 -81.926242)
			(xy 107.741318 -81.967779) (xy 107.772091 -82.014292) (xy 107.795763 -82.064789) (xy 107.811831 -82.118196)
			(xy 107.819951 -82.173372) (xy 107.82046 -82.201258) (xy 107.819951 -82.229144) (xy 107.811831 -82.28432)
			(xy 107.795763 -82.337727) (xy 107.772091 -82.388224) (xy 107.741318 -82.434737) (xy 107.704101 -82.476274)
			(xy 107.661233 -82.511949) (xy 107.613627 -82.541003) (xy 107.562298 -82.562815) (xy 107.508341 -82.576921)
			(xy 107.452904 -82.583021) (xy 107.39717 -82.580984) (xy 107.342327 -82.570854) (xy 107.289543 -82.552847)
			(xy 107.239943 -82.527346) (xy 107.194585 -82.494895) (xy 107.154436 -82.456186) (xy 107.12035 -82.412043)
			(xy 107.093054 -82.363408) (xy 107.073131 -82.311317) (xy 107.061005 -82.25688) (xy 107.056934 -82.201258)
			(xy 93.239082 -82.201258) (xy 92.844366 -82.595974) (xy 105.060748 -82.595974) (xy 105.064819 -82.540352)
			(xy 105.076945 -82.485915) (xy 105.096868 -82.433824) (xy 105.124164 -82.385189) (xy 105.15825 -82.341046)
			(xy 105.198399 -82.302337) (xy 105.243757 -82.269886) (xy 105.293357 -82.244385) (xy 105.346141 -82.226378)
			(xy 105.400984 -82.216248) (xy 105.456718 -82.214211) (xy 105.512155 -82.220311) (xy 105.566112 -82.234417)
			(xy 105.617441 -82.256229) (xy 105.665047 -82.285283) (xy 105.707915 -82.320958) (xy 105.745132 -82.362495)
			(xy 105.775905 -82.409008) (xy 105.799577 -82.459505) (xy 105.815645 -82.512912) (xy 105.823765 -82.568088)
			(xy 105.824274 -82.595974) (xy 105.823765 -82.62386) (xy 105.815645 -82.679036) (xy 105.799577 -82.732443)
			(xy 105.775905 -82.78294) (xy 105.745132 -82.829453) (xy 105.707915 -82.87099) (xy 105.665047 -82.906665)
			(xy 105.617441 -82.935719) (xy 105.566112 -82.957531) (xy 105.512155 -82.971637) (xy 105.456718 -82.977737)
			(xy 105.400984 -82.9757) (xy 105.346141 -82.96557) (xy 105.293357 -82.947563) (xy 105.243757 -82.922062)
			(xy 105.198399 -82.889611) (xy 105.15825 -82.850902) (xy 105.124164 -82.806759) (xy 105.096868 -82.758124)
			(xy 105.076945 -82.706033) (xy 105.064819 -82.651596) (xy 105.060748 -82.595974) (xy 92.844366 -82.595974)
			(xy 91.518232 -83.922108) (xy 91.515527 -83.924959) (xy 91.510935 -83.931338) (xy 91.509088 -83.934808)
			(xy 91.506502 -83.940234) (xy 91.503671 -83.951914) (xy 91.5035 -83.957922) (xy 91.5035 -84.78985)
			(xy 100.952572 -84.78985) (xy 100.952572 -84.73535) (xy 100.960327 -84.681406) (xy 100.97568 -84.629114)
			(xy 100.998318 -84.579539) (xy 101.027781 -84.53369) (xy 101.063468 -84.4925) (xy 101.104653 -84.456808)
			(xy 101.150499 -84.42734) (xy 101.200071 -84.404696) (xy 101.252361 -84.389337) (xy 101.306304 -84.381575)
			(xy 101.333554 -84.381086) (xy 101.364288 -84.382356) (xy 101.37565 -84.382668) (xy 101.396879 -84.374625)
			(xy 101.405182 -84.366862) (xy 101.467666 -84.301838) (xy 101.474778 -84.280502) (xy 101.473508 -84.269072)
			(xy 101.472211 -84.25775) (xy 101.470812 -84.235002) (xy 101.470714 -84.223606) (xy 101.471171 -84.196355)
			(xy 101.478927 -84.142406) (xy 101.494281 -84.090111) (xy 101.516922 -84.040533) (xy 101.546387 -83.994682)
			(xy 101.582078 -83.95349) (xy 101.623268 -83.917798) (xy 101.669118 -83.88833) (xy 101.718695 -83.865687)
			(xy 101.770989 -83.850331) (xy 101.824937 -83.842573) (xy 101.87944 -83.842571) (xy 101.933388 -83.850326)
			(xy 101.985684 -83.865679) (xy 102.035262 -83.888319) (xy 102.081114 -83.917784) (xy 102.122306 -83.953474)
			(xy 102.157999 -83.994663) (xy 102.187468 -84.040513) (xy 102.210111 -84.09009) (xy 102.225468 -84.142384)
			(xy 102.233227 -84.196332) (xy 102.233227 -84.196368) (xy 103.671382 -84.196368) (xy 103.679136 -84.142422)
			(xy 103.694488 -84.090128) (xy 103.717125 -84.040551) (xy 103.746588 -83.994701) (xy 103.782276 -83.95351)
			(xy 103.823462 -83.917817) (xy 103.869309 -83.888348) (xy 103.918883 -83.865705) (xy 103.971175 -83.850346)
			(xy 104.02512 -83.842586) (xy 104.05237 -83.842098) (xy 104.081108 -83.842641) (xy 104.137935 -83.851259)
			(xy 104.192825 -83.868304) (xy 104.244537 -83.893392) (xy 104.291901 -83.925953) (xy 104.313228 -83.945222)
			(xy 104.320034 -83.951039) (xy 104.336475 -83.958086) (xy 104.354334 -83.959104) (xy 104.363012 -83.956906)
			(xy 104.460548 -83.92668) (xy 104.478836 -83.906614) (xy 104.481884 -83.893406) (xy 104.488623 -83.865561)
			(xy 104.509369 -83.812161) (xy 104.537863 -83.762461) (xy 104.573465 -83.717578) (xy 104.615375 -83.678519)
			(xy 104.662651 -83.646163) (xy 104.714232 -83.621235) (xy 104.76896 -83.604297) (xy 104.825604 -83.595727)
			(xy 104.854248 -83.59521) (xy 104.881501 -83.595633) (xy 104.935452 -83.603397) (xy 104.987749 -83.618759)
			(xy 105.037328 -83.641407) (xy 105.083179 -83.67088) (xy 105.124369 -83.706578) (xy 105.16006 -83.747774)
			(xy 105.189525 -83.79363) (xy 105.212164 -83.843213) (xy 105.227517 -83.895512) (xy 105.235271 -83.949465)
			(xy 105.235756 -83.976718) (xy 105.235297 -84.004687) (xy 105.227138 -84.060028) (xy 105.210982 -84.113583)
			(xy 105.199137 -84.13877) (xy 106.610656 -84.13877) (xy 106.614727 -84.083148) (xy 106.626853 -84.028711)
			(xy 106.646776 -83.97662) (xy 106.674072 -83.927985) (xy 106.708158 -83.883842) (xy 106.748307 -83.845133)
			(xy 106.793665 -83.812682) (xy 106.843265 -83.787181) (xy 106.896049 -83.769174) (xy 106.950892 -83.759044)
			(xy 107.006626 -83.757007) (xy 107.062063 -83.763107) (xy 107.11602 -83.777213) (xy 107.167349 -83.799025)
			(xy 107.214955 -83.828079) (xy 107.257823 -83.863754) (xy 107.29504 -83.905291) (xy 107.325813 -83.951804)
			(xy 107.349485 -84.002301) (xy 107.365553 -84.055708) (xy 107.373673 -84.110884) (xy 107.374182 -84.13877)
			(xy 107.373673 -84.166656) (xy 107.365553 -84.221832) (xy 107.349485 -84.275239) (xy 107.325813 -84.325736)
			(xy 107.29504 -84.372249) (xy 107.257823 -84.413786) (xy 107.214955 -84.449461) (xy 107.167349 -84.478515)
			(xy 107.11602 -84.500327) (xy 107.062063 -84.514433) (xy 107.006626 -84.520533) (xy 106.950892 -84.518496)
			(xy 106.896049 -84.508366) (xy 106.843265 -84.490359) (xy 106.793665 -84.464858) (xy 106.748307 -84.432407)
			(xy 106.708158 -84.393698) (xy 106.674072 -84.349555) (xy 106.646776 -84.30092) (xy 106.626853 -84.248829)
			(xy 106.614727 -84.194392) (xy 106.610656 -84.13877) (xy 105.199137 -84.13877) (xy 105.187177 -84.164203)
			(xy 105.156233 -84.210804) (xy 105.118813 -84.252384) (xy 105.09758 -84.270596) (xy 105.089452 -84.277454)
			(xy 105.0798 -84.296504) (xy 105.075228 -84.381848) (xy 105.075269 -84.392474) (xy 105.082871 -84.412288)
			(xy 105.08996 -84.420202) (xy 105.110456 -84.441743) (xy 105.145155 -84.490025) (xy 105.17194 -84.543108)
			(xy 105.190161 -84.599704) (xy 105.199378 -84.658443) (xy 105.199942 -84.688172) (xy 105.199456 -84.715423)
			(xy 105.1917 -84.769371) (xy 105.176345 -84.821666) (xy 105.153703 -84.871243) (xy 105.124237 -84.917093)
			(xy 105.088546 -84.958284) (xy 105.047355 -84.993975) (xy 105.001505 -85.023441) (xy 104.951928 -85.046083)
			(xy 104.899633 -85.061438) (xy 104.845685 -85.069194) (xy 104.791183 -85.069194) (xy 104.737235 -85.061438)
			(xy 104.68494 -85.046083) (xy 104.635363 -85.023441) (xy 104.589513 -84.993975) (xy 104.548322 -84.958284)
			(xy 104.512631 -84.917093) (xy 104.483165 -84.871243) (xy 104.460523 -84.821666) (xy 104.445168 -84.769371)
			(xy 104.437412 -84.715423) (xy 104.436926 -84.688172) (xy 104.437384 -84.660203) (xy 104.445544 -84.604862)
			(xy 104.461701 -84.551308) (xy 104.485506 -84.500687) (xy 104.51645 -84.454087) (xy 104.553869 -84.412507)
			(xy 104.575102 -84.394294) (xy 104.58323 -84.387436) (xy 104.592882 -84.368386) (xy 104.597454 -84.283042)
			(xy 104.597423 -84.272416) (xy 104.589815 -84.2526) (xy 104.582722 -84.244688) (xy 104.567139 -84.22845)
			(xy 104.539509 -84.192921) (xy 104.527604 -84.173822) (xy 104.522338 -84.165688) (xy 104.506932 -84.153951)
			(xy 104.488273 -84.148761) (xy 104.469019 -84.150857) (xy 104.451913 -84.159942) (xy 104.439395 -84.17472)
			(xy 104.433245 -84.193086) (xy 104.43337 -84.202778) (xy 104.433878 -84.223606) (xy 104.433416 -84.250856)
			(xy 104.425659 -84.304802) (xy 104.410304 -84.357095) (xy 104.387663 -84.40667) (xy 104.358198 -84.452519)
			(xy 104.322507 -84.493707) (xy 104.281319 -84.529398) (xy 104.23547 -84.558863) (xy 104.185895 -84.581504)
			(xy 104.133602 -84.596859) (xy 104.079656 -84.604616) (xy 104.025156 -84.604617) (xy 103.97121 -84.596861)
			(xy 103.918917 -84.581508) (xy 103.869341 -84.558869) (xy 103.823491 -84.529405) (xy 103.782301 -84.493716)
			(xy 103.74661 -84.452528) (xy 103.717143 -84.406681) (xy 103.6945 -84.357106) (xy 103.679144 -84.304814)
			(xy 103.671385 -84.250868) (xy 103.671382 -84.196368) (xy 102.233227 -84.196368) (xy 102.233229 -84.250835)
			(xy 102.225475 -84.304783) (xy 102.210122 -84.357079) (xy 102.187484 -84.406658) (xy 102.158019 -84.45251)
			(xy 102.12233 -84.493702) (xy 102.081141 -84.529396) (xy 102.035292 -84.558865) (xy 101.985715 -84.581509)
			(xy 101.933421 -84.596867) (xy 101.879473 -84.604627) (xy 101.852222 -84.605114) (xy 101.821488 -84.603844)
			(xy 101.810125 -84.603517) (xy 101.788896 -84.611571) (xy 101.780594 -84.619338) (xy 101.71811 -84.684362)
			(xy 101.710998 -84.705698) (xy 101.712268 -84.716874) (xy 101.712268 -84.717128) (xy 101.713473 -84.727502)
			(xy 101.714869 -84.748342) (xy 101.715062 -84.758784) (xy 101.715667 -84.769264) (xy 101.724176 -84.788422)
			(xy 101.731572 -84.795868) (xy 101.794056 -84.853018) (xy 101.81336 -84.859876) (xy 101.824028 -84.859114)
			(xy 101.852222 -84.858098) (xy 101.879473 -84.858573) (xy 101.933419 -84.866332) (xy 101.985712 -84.88169)
			(xy 102.035287 -84.904333) (xy 102.081135 -84.9338) (xy 102.122324 -84.969492) (xy 102.158013 -85.010682)
			(xy 102.187478 -85.056532) (xy 102.210118 -85.106109) (xy 102.225472 -85.158403) (xy 102.233228 -85.212349)
			(xy 102.233228 -85.266851) (xy 102.225472 -85.320797) (xy 102.210118 -85.373091) (xy 102.187478 -85.422668)
			(xy 102.158013 -85.468518) (xy 102.122324 -85.509708) (xy 102.081135 -85.5454) (xy 102.08031 -85.54593)
			(xy 103.779826 -85.54593) (xy 103.783897 -85.490308) (xy 103.796023 -85.435871) (xy 103.815946 -85.38378)
			(xy 103.843242 -85.335145) (xy 103.877328 -85.291002) (xy 103.917477 -85.252293) (xy 103.962835 -85.219842)
			(xy 104.012435 -85.194341) (xy 104.065219 -85.176334) (xy 104.120062 -85.166204) (xy 104.175796 -85.164167)
			(xy 104.231233 -85.170267) (xy 104.28519 -85.184373) (xy 104.336519 -85.206185) (xy 104.384125 -85.235239)
			(xy 104.426993 -85.270914) (xy 104.46421 -85.312451) (xy 104.494983 -85.358964) (xy 104.518655 -85.409461)
			(xy 104.534723 -85.462868) (xy 104.542843 -85.518044) (xy 104.543352 -85.54593) (xy 104.542843 -85.573816)
			(xy 104.534723 -85.628992) (xy 104.518655 -85.682399) (xy 104.494983 -85.732896) (xy 104.46421 -85.779409)
			(xy 104.426993 -85.820946) (xy 104.384125 -85.856621) (xy 104.336519 -85.885675) (xy 104.28519 -85.907487)
			(xy 104.231233 -85.921593) (xy 104.175796 -85.927693) (xy 104.120062 -85.925656) (xy 104.065219 -85.915526)
			(xy 104.012435 -85.897519) (xy 103.962835 -85.872018) (xy 103.917477 -85.839567) (xy 103.877328 -85.800858)
			(xy 103.843242 -85.756715) (xy 103.815946 -85.70808) (xy 103.796023 -85.655989) (xy 103.783897 -85.601552)
			(xy 103.779826 -85.54593) (xy 102.08031 -85.54593) (xy 102.035287 -85.574867) (xy 101.985712 -85.59751)
			(xy 101.933419 -85.612868) (xy 101.879473 -85.620627) (xy 101.852222 -85.621114) (xy 101.825143 -85.620633)
			(xy 101.771529 -85.612977) (xy 101.719537 -85.597816) (xy 101.670212 -85.575455) (xy 101.624544 -85.546343)
			(xy 101.583453 -85.511065) (xy 101.547763 -85.47033) (xy 101.518193 -85.424958) (xy 101.495336 -85.37586)
			(xy 101.479653 -85.324023) (xy 101.471458 -85.270489) (xy 101.470714 -85.243416) (xy 101.470117 -85.232935)
			(xy 101.461603 -85.213776) (xy 101.454204 -85.206332) (xy 101.39172 -85.149182) (xy 101.372416 -85.142324)
			(xy 101.361748 -85.143086) (xy 101.333554 -85.144102) (xy 101.306304 -85.143625) (xy 101.252361 -85.135863)
			(xy 101.200071 -85.120504) (xy 101.150499 -85.09786) (xy 101.104653 -85.068392) (xy 101.063468 -85.0327)
			(xy 101.027781 -84.99151) (xy 100.998318 -84.945661) (xy 100.97568 -84.896086) (xy 100.960327 -84.843794)
			(xy 100.952572 -84.78985) (xy 91.5035 -84.78985) (xy 91.5035 -87.036253) (xy 99.285248 -87.036253)
			(xy 99.285248 -86.981747) (xy 99.293005 -86.927795) (xy 99.308361 -86.875496) (xy 99.331004 -86.825915)
			(xy 99.360472 -86.780061) (xy 99.396166 -86.738868) (xy 99.43736 -86.703174) (xy 99.483213 -86.673705)
			(xy 99.532794 -86.651062) (xy 99.585093 -86.635705) (xy 99.639045 -86.627948) (xy 99.666298 -86.627462)
			(xy 99.681091 -86.627595) (xy 99.710589 -86.629886) (xy 99.725226 -86.632034) (xy 99.7362 -86.633159)
			(xy 99.757391 -86.627098) (xy 99.76612 -86.62035) (xy 99.82454 -86.570312) (xy 99.832562 -86.562739)
			(xy 99.841779 -86.542723) (xy 99.84232 -86.531704) (xy 99.84232 -86.227412) (xy 99.841769 -86.216395)
			(xy 99.832558 -86.196378) (xy 99.82454 -86.188804) (xy 99.757484 -86.1314) (xy 99.736402 -86.125304)
			(xy 99.725226 -86.127082) (xy 99.710589 -86.129226) (xy 99.681091 -86.131512) (xy 99.666298 -86.131654)
			(xy 99.63905 -86.131076) (xy 99.585109 -86.12332) (xy 99.532821 -86.107966) (xy 99.48325 -86.085328)
			(xy 99.437406 -86.055865) (xy 99.396221 -86.020178) (xy 99.360534 -85.978993) (xy 99.331071 -85.933148)
			(xy 99.308433 -85.883577) (xy 99.29308 -85.831289) (xy 99.285324 -85.777348) (xy 99.285324 -85.722852)
			(xy 99.29308 -85.668911) (xy 99.308433 -85.616623) (xy 99.331071 -85.567052) (xy 99.360534 -85.521207)
			(xy 99.396221 -85.480022) (xy 99.437406 -85.444335) (xy 99.48325 -85.414872) (xy 99.532821 -85.392234)
			(xy 99.585109 -85.37688) (xy 99.63905 -85.369124) (xy 99.666298 -85.368638) (xy 99.692208 -85.369038)
			(xy 99.743548 -85.376075) (xy 99.793463 -85.389994) (xy 99.841037 -85.410537) (xy 99.885395 -85.437327)
			(xy 99.92572 -85.469872) (xy 99.961271 -85.507574) (xy 99.976686 -85.528404) (xy 99.982438 -85.535725)
			(xy 99.997931 -85.546018) (xy 100.006912 -85.54847) (xy 100.037392 -85.555328) (xy 100.046666 -85.5571)
			(xy 100.065332 -85.554343) (xy 100.073714 -85.549994) (xy 100.099688 -85.535696) (xy 100.154541 -85.513186)
			(xy 100.211845 -85.49796) (xy 100.270636 -85.490275) (xy 100.300282 -85.489796) (xy 100.330264 -85.490345)
			(xy 100.389716 -85.498169) (xy 100.447637 -85.513686) (xy 100.503038 -85.536631) (xy 100.554971 -85.56661)
			(xy 100.602546 -85.603111) (xy 100.64495 -85.645509) (xy 100.681457 -85.693079) (xy 100.711443 -85.745008)
			(xy 100.734394 -85.800406) (xy 100.749919 -85.858325) (xy 100.757751 -85.917776) (xy 100.758244 -85.947758)
			(xy 100.758244 -85.984842) (xy 106.610656 -85.984842) (xy 106.614727 -85.92922) (xy 106.626853 -85.874783)
			(xy 106.646776 -85.822692) (xy 106.674072 -85.774057) (xy 106.708158 -85.729914) (xy 106.748307 -85.691205)
			(xy 106.793665 -85.658754) (xy 106.843265 -85.633253) (xy 106.896049 -85.615246) (xy 106.950892 -85.605116)
			(xy 107.006626 -85.603079) (xy 107.062063 -85.609179) (xy 107.11602 -85.623285) (xy 107.167349 -85.645097)
			(xy 107.214955 -85.674151) (xy 107.257823 -85.709826) (xy 107.29504 -85.751363) (xy 107.325813 -85.797876)
			(xy 107.349485 -85.848373) (xy 107.365553 -85.90178) (xy 107.373673 -85.956956) (xy 107.374182 -85.984842)
			(xy 107.373673 -86.012728) (xy 107.365553 -86.067904) (xy 107.349485 -86.121311) (xy 107.325813 -86.171808)
			(xy 107.29504 -86.218321) (xy 107.257823 -86.259858) (xy 107.214955 -86.295533) (xy 107.167349 -86.324587)
			(xy 107.11602 -86.346399) (xy 107.062063 -86.360505) (xy 107.006626 -86.366605) (xy 106.950892 -86.364568)
			(xy 106.896049 -86.354438) (xy 106.843265 -86.336431) (xy 106.793665 -86.31093) (xy 106.748307 -86.278479)
			(xy 106.708158 -86.23977) (xy 106.674072 -86.195627) (xy 106.646776 -86.146992) (xy 106.626853 -86.094901)
			(xy 106.614727 -86.040464) (xy 106.610656 -85.984842) (xy 100.758244 -85.984842) (xy 100.758244 -86.811358)
			(xy 100.757804 -86.840211) (xy 100.750509 -86.897453) (xy 100.736031 -86.953312) (xy 100.725732 -86.980268)
			(xy 100.725732 -86.980522) (xy 100.722745 -86.98923) (xy 100.722534 -87.007622) (xy 100.728885 -87.024884)
			(xy 100.734622 -87.032084) (xy 100.802948 -87.111078) (xy 100.830126 -87.119714) (xy 100.843842 -87.116412)
			(xy 100.865804 -87.111518) (xy 100.910497 -87.106297) (xy 100.932996 -87.105998) (xy 100.960248 -87.106474)
			(xy 101.014196 -87.11423) (xy 101.066491 -87.129584) (xy 101.116069 -87.152225) (xy 101.16192 -87.181691)
			(xy 101.203111 -87.217382) (xy 101.238804 -87.258573) (xy 101.268271 -87.304423) (xy 101.290913 -87.354001)
			(xy 101.306269 -87.406296) (xy 101.314026 -87.460244) (xy 101.314027 -87.514747) (xy 101.307098 -87.562944)
			(xy 103.932734 -87.562944) (xy 103.936805 -87.507322) (xy 103.948931 -87.452885) (xy 103.968854 -87.400794)
			(xy 103.99615 -87.352159) (xy 104.030236 -87.308016) (xy 104.070385 -87.269307) (xy 104.115743 -87.236856)
			(xy 104.165343 -87.211355) (xy 104.218127 -87.193348) (xy 104.27297 -87.183218) (xy 104.328704 -87.181181)
			(xy 104.384141 -87.187281) (xy 104.438098 -87.201387) (xy 104.489427 -87.223199) (xy 104.537033 -87.252253)
			(xy 104.579901 -87.287928) (xy 104.617118 -87.329465) (xy 104.647891 -87.375978) (xy 104.671563 -87.426475)
			(xy 104.687631 -87.479882) (xy 104.695751 -87.535058) (xy 104.69626 -87.562944) (xy 104.695751 -87.59083)
			(xy 104.687631 -87.646006) (xy 104.671563 -87.699413) (xy 104.647891 -87.74991) (xy 104.617118 -87.796423)
			(xy 104.579901 -87.83796) (xy 104.537033 -87.873635) (xy 104.489427 -87.902689) (xy 104.438098 -87.924501)
			(xy 104.384141 -87.938607) (xy 104.328704 -87.944707) (xy 104.27297 -87.94267) (xy 104.218127 -87.93254)
			(xy 104.165343 -87.914533) (xy 104.115743 -87.889032) (xy 104.070385 -87.856581) (xy 104.030236 -87.817872)
			(xy 103.99615 -87.773729) (xy 103.968854 -87.725094) (xy 103.948931 -87.673003) (xy 103.936805 -87.618566)
			(xy 103.932734 -87.562944) (xy 101.307098 -87.562944) (xy 101.306271 -87.568695) (xy 101.290916 -87.620991)
			(xy 101.268275 -87.670569) (xy 101.238809 -87.71642) (xy 101.203118 -87.757611) (xy 101.161928 -87.793303)
			(xy 101.116077 -87.82277) (xy 101.0665 -87.845413) (xy 101.014205 -87.860768) (xy 100.960257 -87.868526)
			(xy 100.905754 -87.868527) (xy 100.851805 -87.860771) (xy 100.79951 -87.845416) (xy 100.749932 -87.822776)
			(xy 100.704081 -87.79331) (xy 100.66289 -87.757618) (xy 100.627197 -87.716428) (xy 100.59773 -87.670578)
			(xy 100.575088 -87.621001) (xy 100.559732 -87.568706) (xy 100.551974 -87.514757) (xy 100.551488 -87.487506)
			(xy 100.552013 -87.45867) (xy 100.560687 -87.401656) (xy 100.56876 -87.373968) (xy 100.571133 -87.36502)
			(xy 100.569988 -87.346557) (xy 100.562345 -87.329712) (xy 100.55606 -87.322914) (xy 100.481638 -87.249254)
			(xy 100.454206 -87.24265) (xy 100.44049 -87.247222) (xy 100.406355 -87.25752) (xy 100.335929 -87.268622)
			(xy 100.300282 -87.26932) (xy 100.27064 -87.268799) (xy 100.211859 -87.261085) (xy 100.154561 -87.245865)
			(xy 100.099699 -87.223393) (xy 100.073714 -87.209122) (xy 100.065303 -87.204872) (xy 100.046671 -87.202141)
			(xy 100.037392 -87.203788) (xy 100.006912 -87.210646) (xy 99.99791 -87.213046) (xy 99.982409 -87.223358)
			(xy 99.976686 -87.230712) (xy 99.961306 -87.25157) (xy 99.925759 -87.289281) (xy 99.885432 -87.32183)
			(xy 99.841068 -87.348617) (xy 99.793484 -87.369148) (xy 99.743558 -87.383044) (xy 99.69221 -87.39005)
			(xy 99.666298 -87.390478) (xy 99.639045 -87.390052) (xy 99.585093 -87.382295) (xy 99.532794 -87.366938)
			(xy 99.483213 -87.344295) (xy 99.43736 -87.314826) (xy 99.396166 -87.279132) (xy 99.360472 -87.237939)
			(xy 99.331004 -87.192085) (xy 99.308361 -87.142504) (xy 99.293005 -87.090205) (xy 99.285248 -87.036253)
			(xy 91.5035 -87.036253) (xy 91.5035 -88.086438) (xy 104.62971 -88.086438) (xy 104.633781 -88.030816)
			(xy 104.645907 -87.976379) (xy 104.66583 -87.924288) (xy 104.693126 -87.875653) (xy 104.727212 -87.83151)
			(xy 104.767361 -87.792801) (xy 104.812719 -87.76035) (xy 104.862319 -87.734849) (xy 104.915103 -87.716842)
			(xy 104.969946 -87.706712) (xy 105.02568 -87.704675) (xy 105.081117 -87.710775) (xy 105.135074 -87.724881)
			(xy 105.186403 -87.746693) (xy 105.234009 -87.775747) (xy 105.276877 -87.811422) (xy 105.290928 -87.827104)
			(xy 106.610656 -87.827104) (xy 106.614727 -87.771482) (xy 106.626853 -87.717045) (xy 106.646776 -87.664954)
			(xy 106.674072 -87.616319) (xy 106.708158 -87.572176) (xy 106.748307 -87.533467) (xy 106.793665 -87.501016)
			(xy 106.843265 -87.475515) (xy 106.896049 -87.457508) (xy 106.950892 -87.447378) (xy 107.006626 -87.445341)
			(xy 107.062063 -87.451441) (xy 107.11602 -87.465547) (xy 107.167349 -87.487359) (xy 107.214955 -87.516413)
			(xy 107.257823 -87.552088) (xy 107.29504 -87.593625) (xy 107.325813 -87.640138) (xy 107.349485 -87.690635)
			(xy 107.365553 -87.744042) (xy 107.373673 -87.799218) (xy 107.374182 -87.827104) (xy 107.373673 -87.85499)
			(xy 107.365553 -87.910166) (xy 107.349485 -87.963573) (xy 107.325813 -88.01407) (xy 107.29504 -88.060583)
			(xy 107.257823 -88.10212) (xy 107.214955 -88.137795) (xy 107.167349 -88.166849) (xy 107.11602 -88.188661)
			(xy 107.062063 -88.202767) (xy 107.006626 -88.208867) (xy 106.950892 -88.20683) (xy 106.896049 -88.1967)
			(xy 106.843265 -88.178693) (xy 106.793665 -88.153192) (xy 106.748307 -88.120741) (xy 106.708158 -88.082032)
			(xy 106.674072 -88.037889) (xy 106.646776 -87.989254) (xy 106.626853 -87.937163) (xy 106.614727 -87.882726)
			(xy 106.610656 -87.827104) (xy 105.290928 -87.827104) (xy 105.314094 -87.852959) (xy 105.344867 -87.899472)
			(xy 105.368539 -87.949969) (xy 105.384607 -88.003376) (xy 105.392727 -88.058552) (xy 105.393236 -88.086438)
			(xy 105.392727 -88.114324) (xy 105.384607 -88.1695) (xy 105.368539 -88.222907) (xy 105.344867 -88.273404)
			(xy 105.314094 -88.319917) (xy 105.276877 -88.361454) (xy 105.234009 -88.397129) (xy 105.186403 -88.426183)
			(xy 105.135074 -88.447995) (xy 105.081117 -88.462101) (xy 105.02568 -88.468201) (xy 104.969946 -88.466164)
			(xy 104.915103 -88.456034) (xy 104.862319 -88.438027) (xy 104.812719 -88.412526) (xy 104.767361 -88.380075)
			(xy 104.727212 -88.341366) (xy 104.693126 -88.297223) (xy 104.66583 -88.248588) (xy 104.645907 -88.196497)
			(xy 104.633781 -88.14206) (xy 104.62971 -88.086438) (xy 91.5035 -88.086438) (xy 91.5035 -90.019451)
			(xy 92.470978 -90.019451) (xy 92.470978 -89.964949) (xy 92.478734 -89.911003) (xy 92.494088 -89.858709)
			(xy 92.516728 -89.809133) (xy 92.546193 -89.763283) (xy 92.581883 -89.722093) (xy 92.623072 -89.686402)
			(xy 92.668921 -89.656935) (xy 92.718496 -89.634293) (xy 92.770789 -89.618937) (xy 92.824735 -89.611179)
			(xy 92.851986 -89.610692) (xy 92.877602 -89.611128) (xy 92.928371 -89.617986) (xy 92.977766 -89.631581)
			(xy 93.024895 -89.651667) (xy 93.06891 -89.677884) (xy 93.089222 -89.693496) (xy 93.089476 -89.69375)
			(xy 93.096798 -89.699018) (xy 93.113983 -89.704471) (xy 93.123004 -89.704418) (xy 93.199204 -89.700862)
			(xy 93.215714 -89.69375) (xy 93.222572 -89.687146) (xy 93.244037 -89.667411) (xy 93.291799 -89.633971)
			(xy 93.344093 -89.608185) (xy 93.399699 -89.590653) (xy 93.457325 -89.581782) (xy 93.486478 -89.581228)
			(xy 93.513354 -89.581706) (xy 93.566574 -89.589253) (xy 93.618206 -89.6042) (xy 93.667227 -89.626251)
			(xy 93.712664 -89.654969) (xy 93.753618 -89.689785) (xy 93.789275 -89.730008) (xy 93.804486 -89.75217)
			(xy 93.80474 -89.752424) (xy 93.810195 -89.759844) (xy 93.825233 -89.770458) (xy 93.843045 -89.775099)
			(xy 93.852238 -89.774522) (xy 93.942154 -89.76487) (xy 93.951352 -89.763442) (xy 93.967907 -89.75497)
			(xy 93.980342 -89.741143) (xy 93.984064 -89.732612) (xy 93.994937 -89.706082) (xy 94.0234 -89.656312)
			(xy 94.058988 -89.611361) (xy 94.1009 -89.572239) (xy 94.148192 -89.539827) (xy 94.199801 -89.514854)
			(xy 94.254565 -89.497882) (xy 94.311251 -89.489293) (xy 94.339918 -89.488772) (xy 94.367167 -89.489299)
			(xy 94.42111 -89.497058) (xy 94.4734 -89.512413) (xy 94.522972 -89.535054) (xy 94.568818 -89.56452)
			(xy 94.610003 -89.600209) (xy 94.645691 -89.641397) (xy 94.675154 -89.687244) (xy 94.681257 -89.700608)
			(xy 101.402894 -89.700608) (xy 101.406965 -89.644986) (xy 101.419091 -89.590549) (xy 101.439014 -89.538458)
			(xy 101.46631 -89.489823) (xy 101.500396 -89.44568) (xy 101.540545 -89.406971) (xy 101.585903 -89.37452)
			(xy 101.635503 -89.349019) (xy 101.688287 -89.331012) (xy 101.74313 -89.320882) (xy 101.798864 -89.318845)
			(xy 101.854301 -89.324945) (xy 101.908258 -89.339051) (xy 101.959587 -89.360863) (xy 102.007193 -89.389917)
			(xy 102.050061 -89.425592) (xy 102.087278 -89.467129) (xy 102.118051 -89.513642) (xy 102.141723 -89.564139)
			(xy 102.157791 -89.617546) (xy 102.165911 -89.672722) (xy 102.16642 -89.700608) (xy 102.165911 -89.728494)
			(xy 102.157791 -89.78367) (xy 102.141723 -89.837077) (xy 102.118051 -89.887574) (xy 102.087278 -89.934087)
			(xy 102.071167 -89.952068) (xy 103.085899 -89.952068) (xy 103.08996 -89.893988) (xy 103.102065 -89.837038)
			(xy 103.121978 -89.782327) (xy 103.149312 -89.730921) (xy 103.183534 -89.683818) (xy 103.223978 -89.641937)
			(xy 103.269858 -89.606092) (xy 103.32028 -89.576981) (xy 103.374262 -89.55517) (xy 103.430755 -89.541085)
			(xy 103.488658 -89.534999) (xy 103.546844 -89.537031) (xy 103.604182 -89.547141) (xy 103.659554 -89.565133)
			(xy 103.711884 -89.590656) (xy 103.760152 -89.623213) (xy 103.803419 -89.662171) (xy 103.840843 -89.706772)
			(xy 103.871696 -89.756147) (xy 103.895377 -89.809335) (xy 103.911425 -89.865302) (xy 103.919528 -89.922957)
			(xy 103.920036 -89.952068) (xy 103.919528 -89.981179) (xy 103.911425 -90.038834) (xy 103.895377 -90.094801)
			(xy 103.871696 -90.147989) (xy 103.840843 -90.197364) (xy 103.803419 -90.241965) (xy 103.760152 -90.280923)
			(xy 103.711884 -90.31348) (xy 103.659554 -90.339003) (xy 103.604182 -90.356995) (xy 103.546844 -90.367105)
			(xy 103.488658 -90.369137) (xy 103.430755 -90.363051) (xy 103.374262 -90.348966) (xy 103.32028 -90.327155)
			(xy 103.269858 -90.298044) (xy 103.223978 -90.262199) (xy 103.183534 -90.220318) (xy 103.149312 -90.173215)
			(xy 103.121978 -90.121809) (xy 103.102065 -90.067098) (xy 103.08996 -90.010148) (xy 103.085899 -89.952068)
			(xy 102.071167 -89.952068) (xy 102.050061 -89.975624) (xy 102.007193 -90.011299) (xy 101.959587 -90.040353)
			(xy 101.908258 -90.062165) (xy 101.854301 -90.076271) (xy 101.798864 -90.082371) (xy 101.74313 -90.080334)
			(xy 101.688287 -90.070204) (xy 101.635503 -90.052197) (xy 101.585903 -90.026696) (xy 101.540545 -89.994245)
			(xy 101.500396 -89.955536) (xy 101.46631 -89.911393) (xy 101.439014 -89.862758) (xy 101.419091 -89.810667)
			(xy 101.406965 -89.75623) (xy 101.402894 -89.700608) (xy 94.681257 -89.700608) (xy 94.697793 -89.736817)
			(xy 94.713146 -89.789108) (xy 94.720902 -89.843051) (xy 94.720902 -89.897549) (xy 94.713146 -89.951492)
			(xy 94.697793 -90.003783) (xy 94.675154 -90.053356) (xy 94.645691 -90.099203) (xy 94.610003 -90.140391)
			(xy 94.568818 -90.17608) (xy 94.522972 -90.205546) (xy 94.4734 -90.228187) (xy 94.42111 -90.243542)
			(xy 94.367167 -90.251301) (xy 94.339918 -90.251788) (xy 94.31304 -90.251351) (xy 94.259817 -90.243801)
			(xy 94.208182 -90.22885) (xy 94.15916 -90.206793) (xy 94.113722 -90.178067) (xy 94.072771 -90.143244)
			(xy 94.037118 -90.103013) (xy 94.02191 -90.080846) (xy 94.021656 -90.080592) (xy 94.0162 -90.073172)
			(xy 94.001163 -90.062557) (xy 93.983351 -90.057916) (xy 93.974158 -90.058494) (xy 93.884242 -90.068146)
			(xy 93.875041 -90.069562) (xy 93.858485 -90.078038) (xy 93.846052 -90.091871) (xy 93.842332 -90.100404)
			(xy 93.83147 -90.126939) (xy 93.803005 -90.176708) (xy 93.767415 -90.221659) (xy 93.725501 -90.26078)
			(xy 93.678208 -90.293192) (xy 93.626597 -90.318164) (xy 93.571832 -90.335135) (xy 93.515145 -90.343723)
			(xy 93.486478 -90.344244) (xy 93.460861 -90.343842) (xy 93.410089 -90.336977) (xy 93.360694 -90.323376)
			(xy 93.313566 -90.303281) (xy 93.269553 -90.277057) (xy 93.249242 -90.26144) (xy 93.248988 -90.261186)
			(xy 93.241646 -90.25595) (xy 93.224477 -90.250477) (xy 93.21546 -90.250518) (xy 93.13926 -90.254074)
			(xy 93.12275 -90.261186) (xy 93.115892 -90.26779) (xy 93.094448 -90.287549) (xy 93.046679 -90.320983)
			(xy 92.99438 -90.346764) (xy 92.93877 -90.364292) (xy 92.88114 -90.373157) (xy 92.851986 -90.373708)
			(xy 92.824735 -90.373221) (xy 92.770789 -90.365463) (xy 92.718496 -90.350107) (xy 92.668921 -90.327465)
			(xy 92.623072 -90.297998) (xy 92.581883 -90.262307) (xy 92.546193 -90.221117) (xy 92.516728 -90.175267)
			(xy 92.494088 -90.125691) (xy 92.478734 -90.073397) (xy 92.470978 -90.019451) (xy 91.5035 -90.019451)
			(xy 91.5035 -90.612722) (xy 104.01376 -90.612722) (xy 104.017831 -90.5571) (xy 104.029957 -90.502663)
			(xy 104.04988 -90.450572) (xy 104.077176 -90.401937) (xy 104.111262 -90.357794) (xy 104.151411 -90.319085)
			(xy 104.196769 -90.286634) (xy 104.246369 -90.261133) (xy 104.299153 -90.243126) (xy 104.353996 -90.232996)
			(xy 104.40973 -90.230959) (xy 104.465167 -90.237059) (xy 104.519124 -90.251165) (xy 104.570453 -90.272977)
			(xy 104.618059 -90.302031) (xy 104.660927 -90.337706) (xy 104.698144 -90.379243) (xy 104.728917 -90.425756)
			(xy 104.752589 -90.476253) (xy 104.768657 -90.52966) (xy 104.776777 -90.584836) (xy 104.777286 -90.612722)
			(xy 104.776777 -90.640608) (xy 104.768657 -90.695784) (xy 104.752589 -90.749191) (xy 104.728917 -90.799688)
			(xy 104.720697 -90.812112) (xy 105.427778 -90.812112) (xy 105.431849 -90.75649) (xy 105.443975 -90.702053)
			(xy 105.463898 -90.649962) (xy 105.491194 -90.601327) (xy 105.52528 -90.557184) (xy 105.565429 -90.518475)
			(xy 105.610787 -90.486024) (xy 105.660387 -90.460523) (xy 105.713171 -90.442516) (xy 105.768014 -90.432386)
			(xy 105.823748 -90.430349) (xy 105.879185 -90.436449) (xy 105.933142 -90.450555) (xy 105.984471 -90.472367)
			(xy 106.032077 -90.501421) (xy 106.074945 -90.537096) (xy 106.112162 -90.578633) (xy 106.142935 -90.625146)
			(xy 106.166607 -90.675643) (xy 106.182675 -90.72905) (xy 106.190795 -90.784226) (xy 106.191304 -90.812112)
			(xy 106.190795 -90.839998) (xy 106.182675 -90.895174) (xy 106.166607 -90.948581) (xy 106.142935 -90.999078)
			(xy 106.112162 -91.045591) (xy 106.074945 -91.087128) (xy 106.032077 -91.122803) (xy 105.984471 -91.151857)
			(xy 105.933142 -91.173669) (xy 105.879185 -91.187775) (xy 105.823748 -91.193875) (xy 105.768014 -91.191838)
			(xy 105.713171 -91.181708) (xy 105.660387 -91.163701) (xy 105.610787 -91.1382) (xy 105.565429 -91.105749)
			(xy 105.52528 -91.06704) (xy 105.491194 -91.022897) (xy 105.463898 -90.974262) (xy 105.443975 -90.922171)
			(xy 105.431849 -90.867734) (xy 105.427778 -90.812112) (xy 104.720697 -90.812112) (xy 104.698144 -90.846201)
			(xy 104.660927 -90.887738) (xy 104.618059 -90.923413) (xy 104.570453 -90.952467) (xy 104.519124 -90.974279)
			(xy 104.465167 -90.988385) (xy 104.40973 -90.994485) (xy 104.353996 -90.992448) (xy 104.299153 -90.982318)
			(xy 104.246369 -90.964311) (xy 104.196769 -90.93881) (xy 104.151411 -90.906359) (xy 104.111262 -90.86765)
			(xy 104.077176 -90.823507) (xy 104.04988 -90.774872) (xy 104.029957 -90.722781) (xy 104.017831 -90.668344)
			(xy 104.01376 -90.612722) (xy 91.5035 -90.612722) (xy 91.5035 -91.199462) (xy 106.656884 -91.199462)
			(xy 106.660955 -91.14384) (xy 106.673081 -91.089403) (xy 106.693004 -91.037312) (xy 106.7203 -90.988677)
			(xy 106.754386 -90.944534) (xy 106.794535 -90.905825) (xy 106.839893 -90.873374) (xy 106.889493 -90.847873)
			(xy 106.942277 -90.829866) (xy 106.99712 -90.819736) (xy 107.052854 -90.817699) (xy 107.108291 -90.823799)
			(xy 107.162248 -90.837905) (xy 107.213577 -90.859717) (xy 107.261183 -90.888771) (xy 107.304051 -90.924446)
			(xy 107.341268 -90.965983) (xy 107.372041 -91.012496) (xy 107.395713 -91.062993) (xy 107.411781 -91.1164)
			(xy 107.419901 -91.171576) (xy 107.420285 -91.192604) (xy 108.032802 -91.192604) (xy 108.036873 -91.136982)
			(xy 108.048999 -91.082545) (xy 108.068922 -91.030454) (xy 108.096218 -90.981819) (xy 108.130304 -90.937676)
			(xy 108.170453 -90.898967) (xy 108.215811 -90.866516) (xy 108.265411 -90.841015) (xy 108.318195 -90.823008)
			(xy 108.373038 -90.812878) (xy 108.428772 -90.810841) (xy 108.484209 -90.816941) (xy 108.538166 -90.831047)
			(xy 108.589495 -90.852859) (xy 108.637101 -90.881913) (xy 108.679969 -90.917588) (xy 108.717186 -90.959125)
			(xy 108.747959 -91.005638) (xy 108.771631 -91.056135) (xy 108.787699 -91.109542) (xy 108.795819 -91.164718)
			(xy 108.796328 -91.192604) (xy 108.795819 -91.22049) (xy 108.787699 -91.275666) (xy 108.771631 -91.329073)
			(xy 108.747959 -91.37957) (xy 108.717186 -91.426083) (xy 108.679969 -91.46762) (xy 108.637101 -91.503295)
			(xy 108.589495 -91.532349) (xy 108.538166 -91.554161) (xy 108.484209 -91.568267) (xy 108.428772 -91.574367)
			(xy 108.373038 -91.57233) (xy 108.318195 -91.5622) (xy 108.265411 -91.544193) (xy 108.215811 -91.518692)
			(xy 108.170453 -91.486241) (xy 108.130304 -91.447532) (xy 108.096218 -91.403389) (xy 108.068922 -91.354754)
			(xy 108.048999 -91.302663) (xy 108.036873 -91.248226) (xy 108.032802 -91.192604) (xy 107.420285 -91.192604)
			(xy 107.42041 -91.199462) (xy 107.419901 -91.227348) (xy 107.411781 -91.282524) (xy 107.395713 -91.335931)
			(xy 107.372041 -91.386428) (xy 107.341268 -91.432941) (xy 107.304051 -91.474478) (xy 107.261183 -91.510153)
			(xy 107.213577 -91.539207) (xy 107.162248 -91.561019) (xy 107.108291 -91.575125) (xy 107.052854 -91.581225)
			(xy 106.99712 -91.579188) (xy 106.942277 -91.569058) (xy 106.889493 -91.551051) (xy 106.839893 -91.52555)
			(xy 106.794535 -91.493099) (xy 106.754386 -91.45439) (xy 106.7203 -91.410247) (xy 106.693004 -91.361612)
			(xy 106.673081 -91.309521) (xy 106.660955 -91.255084) (xy 106.656884 -91.199462) (xy 91.5035 -91.199462)
			(xy 91.5035 -93.447362) (xy 105.362754 -93.447362) (xy 105.366825 -93.39174) (xy 105.378951 -93.337303)
			(xy 105.398874 -93.285212) (xy 105.42617 -93.236577) (xy 105.460256 -93.192434) (xy 105.500405 -93.153725)
			(xy 105.545763 -93.121274) (xy 105.595363 -93.095773) (xy 105.648147 -93.077766) (xy 105.70299 -93.067636)
			(xy 105.758724 -93.065599) (xy 105.814161 -93.071699) (xy 105.868118 -93.085805) (xy 105.919447 -93.107617)
			(xy 105.967053 -93.136671) (xy 106.009921 -93.172346) (xy 106.047138 -93.213883) (xy 106.077911 -93.260396)
			(xy 106.101583 -93.310893) (xy 106.117651 -93.3643) (xy 106.125771 -93.419476) (xy 106.126076 -93.436186)
			(xy 107.435648 -93.436186) (xy 107.439719 -93.380564) (xy 107.451845 -93.326127) (xy 107.471768 -93.274036)
			(xy 107.499064 -93.225401) (xy 107.53315 -93.181258) (xy 107.573299 -93.142549) (xy 107.618657 -93.110098)
			(xy 107.668257 -93.084597) (xy 107.721041 -93.06659) (xy 107.775884 -93.05646) (xy 107.831618 -93.054423)
			(xy 107.887055 -93.060523) (xy 107.941012 -93.074629) (xy 107.992341 -93.096441) (xy 108.039947 -93.125495)
			(xy 108.082815 -93.16117) (xy 108.120032 -93.202707) (xy 108.150805 -93.24922) (xy 108.174477 -93.299717)
			(xy 108.190545 -93.353124) (xy 108.198665 -93.4083) (xy 108.199174 -93.436186) (xy 108.198665 -93.464072)
			(xy 108.190545 -93.519248) (xy 108.174477 -93.572655) (xy 108.150805 -93.623152) (xy 108.120032 -93.669665)
			(xy 108.082815 -93.711202) (xy 108.039947 -93.746877) (xy 107.992341 -93.775931) (xy 107.941012 -93.797743)
			(xy 107.887055 -93.811849) (xy 107.831618 -93.817949) (xy 107.775884 -93.815912) (xy 107.721041 -93.805782)
			(xy 107.668257 -93.787775) (xy 107.618657 -93.762274) (xy 107.573299 -93.729823) (xy 107.53315 -93.691114)
			(xy 107.499064 -93.646971) (xy 107.471768 -93.598336) (xy 107.451845 -93.546245) (xy 107.439719 -93.491808)
			(xy 107.435648 -93.436186) (xy 106.126076 -93.436186) (xy 106.12628 -93.447362) (xy 106.125771 -93.475248)
			(xy 106.117651 -93.530424) (xy 106.101583 -93.583831) (xy 106.077911 -93.634328) (xy 106.047138 -93.680841)
			(xy 106.009921 -93.722378) (xy 105.967053 -93.758053) (xy 105.919447 -93.787107) (xy 105.868118 -93.808919)
			(xy 105.814161 -93.823025) (xy 105.758724 -93.829125) (xy 105.70299 -93.827088) (xy 105.648147 -93.816958)
			(xy 105.595363 -93.798951) (xy 105.545763 -93.77345) (xy 105.500405 -93.740999) (xy 105.460256 -93.70229)
			(xy 105.42617 -93.658147) (xy 105.398874 -93.609512) (xy 105.378951 -93.557421) (xy 105.366825 -93.502984)
			(xy 105.362754 -93.447362) (xy 91.5035 -93.447362) (xy 91.5035 -93.98254) (xy 94.427038 -93.98254)
			(xy 94.431109 -93.926918) (xy 94.443235 -93.872481) (xy 94.463158 -93.82039) (xy 94.490454 -93.771755)
			(xy 94.52454 -93.727612) (xy 94.564689 -93.688903) (xy 94.610047 -93.656452) (xy 94.659647 -93.630951)
			(xy 94.712431 -93.612944) (xy 94.767274 -93.602814) (xy 94.823008 -93.600777) (xy 94.878445 -93.606877)
			(xy 94.932402 -93.620983) (xy 94.983731 -93.642795) (xy 95.031337 -93.671849) (xy 95.074205 -93.707524)
			(xy 95.111422 -93.749061) (xy 95.142195 -93.795574) (xy 95.165867 -93.846071) (xy 95.181935 -93.899478)
			(xy 95.190055 -93.954654) (xy 95.190564 -93.98254) (xy 95.190055 -94.010426) (xy 95.181935 -94.065602)
			(xy 95.165867 -94.119009) (xy 95.142195 -94.169506) (xy 95.111422 -94.216019) (xy 95.081656 -94.24924)
			(xy 95.43618 -94.24924) (xy 95.440251 -94.193618) (xy 95.452377 -94.139181) (xy 95.4723 -94.08709)
			(xy 95.499596 -94.038455) (xy 95.533682 -93.994312) (xy 95.573831 -93.955603) (xy 95.619189 -93.923152)
			(xy 95.668789 -93.897651) (xy 95.721573 -93.879644) (xy 95.776416 -93.869514) (xy 95.83215 -93.867477)
			(xy 95.887587 -93.873577) (xy 95.941544 -93.887683) (xy 95.992873 -93.909495) (xy 96.040479 -93.938549)
			(xy 96.083347 -93.974224) (xy 96.120564 -94.015761) (xy 96.151337 -94.062274) (xy 96.175009 -94.112771)
			(xy 96.191077 -94.166178) (xy 96.199197 -94.221354) (xy 96.199706 -94.24924) (xy 96.199632 -94.253304)
			(xy 96.45218 -94.253304) (xy 96.456251 -94.197682) (xy 96.468377 -94.143245) (xy 96.4883 -94.091154)
			(xy 96.515596 -94.042519) (xy 96.549682 -93.998376) (xy 96.589831 -93.959667) (xy 96.635189 -93.927216)
			(xy 96.684789 -93.901715) (xy 96.737573 -93.883708) (xy 96.792416 -93.873578) (xy 96.84815 -93.871541)
			(xy 96.903587 -93.877641) (xy 96.957544 -93.891747) (xy 97.008873 -93.913559) (xy 97.056479 -93.942613)
			(xy 97.099347 -93.978288) (xy 97.136564 -94.019825) (xy 97.167337 -94.066338) (xy 97.191009 -94.116835)
			(xy 97.207077 -94.170242) (xy 97.215197 -94.225418) (xy 97.215242 -94.227904) (xy 97.46818 -94.227904)
			(xy 97.472251 -94.172282) (xy 97.484377 -94.117845) (xy 97.5043 -94.065754) (xy 97.531596 -94.017119)
			(xy 97.565682 -93.972976) (xy 97.605831 -93.934267) (xy 97.651189 -93.901816) (xy 97.700789 -93.876315)
			(xy 97.753573 -93.858308) (xy 97.808416 -93.848178) (xy 97.86415 -93.846141) (xy 97.919587 -93.852241)
			(xy 97.973544 -93.866347) (xy 98.024873 -93.888159) (xy 98.072479 -93.917213) (xy 98.115347 -93.952888)
			(xy 98.152564 -93.994425) (xy 98.183337 -94.040938) (xy 98.207009 -94.091435) (xy 98.223077 -94.144842)
			(xy 98.231197 -94.200018) (xy 98.231706 -94.227904) (xy 98.23127 -94.25178) (xy 98.48418 -94.25178)
			(xy 98.488251 -94.196158) (xy 98.500377 -94.141721) (xy 98.5203 -94.08963) (xy 98.547596 -94.040995)
			(xy 98.581682 -93.996852) (xy 98.621831 -93.958143) (xy 98.667189 -93.925692) (xy 98.716789 -93.900191)
			(xy 98.769573 -93.882184) (xy 98.824416 -93.872054) (xy 98.88015 -93.870017) (xy 98.935587 -93.876117)
			(xy 98.989544 -93.890223) (xy 99.040873 -93.912035) (xy 99.088479 -93.941089) (xy 99.131347 -93.976764)
			(xy 99.168564 -94.018301) (xy 99.199337 -94.064814) (xy 99.223009 -94.115311) (xy 99.239077 -94.168718)
			(xy 99.244909 -94.208346) (xy 99.75418 -94.208346) (xy 99.758251 -94.152724) (xy 99.770377 -94.098287)
			(xy 99.7903 -94.046196) (xy 99.817596 -93.997561) (xy 99.851682 -93.953418) (xy 99.891831 -93.914709)
			(xy 99.937189 -93.882258) (xy 99.986789 -93.856757) (xy 100.039573 -93.83875) (xy 100.094416 -93.82862)
			(xy 100.15015 -93.826583) (xy 100.205587 -93.832683) (xy 100.259544 -93.846789) (xy 100.310873 -93.868601)
			(xy 100.358479 -93.897655) (xy 100.401347 -93.93333) (xy 100.438564 -93.974867) (xy 100.469337 -94.02138)
			(xy 100.493009 -94.071877) (xy 100.509077 -94.125284) (xy 100.517197 -94.18046) (xy 100.517706 -94.208346)
			(xy 100.517197 -94.236232) (xy 100.509077 -94.291408) (xy 100.493009 -94.344815) (xy 100.469337 -94.395312)
			(xy 100.438564 -94.441825) (xy 100.401347 -94.483362) (xy 100.358479 -94.519037) (xy 100.310873 -94.548091)
			(xy 100.259544 -94.569903) (xy 100.205587 -94.584009) (xy 100.15015 -94.590109) (xy 100.094416 -94.588072)
			(xy 100.039573 -94.577942) (xy 99.986789 -94.559935) (xy 99.937189 -94.534434) (xy 99.891831 -94.501983)
			(xy 99.851682 -94.463274) (xy 99.817596 -94.419131) (xy 99.7903 -94.370496) (xy 99.770377 -94.318405)
			(xy 99.758251 -94.263968) (xy 99.75418 -94.208346) (xy 99.244909 -94.208346) (xy 99.247197 -94.223894)
			(xy 99.247706 -94.25178) (xy 99.247197 -94.279666) (xy 99.239077 -94.334842) (xy 99.223009 -94.388249)
			(xy 99.199337 -94.438746) (xy 99.168564 -94.485259) (xy 99.131347 -94.526796) (xy 99.088479 -94.562471)
			(xy 99.040873 -94.591525) (xy 98.989544 -94.613337) (xy 98.935587 -94.627443) (xy 98.88015 -94.633543)
			(xy 98.824416 -94.631506) (xy 98.769573 -94.621376) (xy 98.716789 -94.603369) (xy 98.667189 -94.577868)
			(xy 98.621831 -94.545417) (xy 98.581682 -94.506708) (xy 98.547596 -94.462565) (xy 98.5203 -94.41393)
			(xy 98.500377 -94.361839) (xy 98.488251 -94.307402) (xy 98.48418 -94.25178) (xy 98.23127 -94.25178)
			(xy 98.231197 -94.25579) (xy 98.223077 -94.310966) (xy 98.207009 -94.364373) (xy 98.183337 -94.41487)
			(xy 98.152564 -94.461383) (xy 98.115347 -94.50292) (xy 98.072479 -94.538595) (xy 98.024873 -94.567649)
			(xy 97.973544 -94.589461) (xy 97.919587 -94.603567) (xy 97.86415 -94.609667) (xy 97.808416 -94.60763)
			(xy 97.753573 -94.5975) (xy 97.700789 -94.579493) (xy 97.651189 -94.553992) (xy 97.605831 -94.521541)
			(xy 97.565682 -94.482832) (xy 97.531596 -94.438689) (xy 97.5043 -94.390054) (xy 97.484377 -94.337963)
			(xy 97.472251 -94.283526) (xy 97.46818 -94.227904) (xy 97.215242 -94.227904) (xy 97.215706 -94.253304)
			(xy 97.215197 -94.28119) (xy 97.207077 -94.336366) (xy 97.191009 -94.389773) (xy 97.167337 -94.44027)
			(xy 97.136564 -94.486783) (xy 97.099347 -94.52832) (xy 97.056479 -94.563995) (xy 97.008873 -94.593049)
			(xy 96.957544 -94.614861) (xy 96.903587 -94.628967) (xy 96.84815 -94.635067) (xy 96.792416 -94.63303)
			(xy 96.737573 -94.6229) (xy 96.684789 -94.604893) (xy 96.635189 -94.579392) (xy 96.589831 -94.546941)
			(xy 96.549682 -94.508232) (xy 96.515596 -94.464089) (xy 96.4883 -94.415454) (xy 96.468377 -94.363363)
			(xy 96.456251 -94.308926) (xy 96.45218 -94.253304) (xy 96.199632 -94.253304) (xy 96.199197 -94.277126)
			(xy 96.191077 -94.332302) (xy 96.175009 -94.385709) (xy 96.151337 -94.436206) (xy 96.120564 -94.482719)
			(xy 96.083347 -94.524256) (xy 96.040479 -94.559931) (xy 95.992873 -94.588985) (xy 95.941544 -94.610797)
			(xy 95.887587 -94.624903) (xy 95.83215 -94.631003) (xy 95.776416 -94.628966) (xy 95.721573 -94.618836)
			(xy 95.668789 -94.600829) (xy 95.619189 -94.575328) (xy 95.573831 -94.542877) (xy 95.533682 -94.504168)
			(xy 95.499596 -94.460025) (xy 95.4723 -94.41139) (xy 95.452377 -94.359299) (xy 95.440251 -94.304862)
			(xy 95.43618 -94.24924) (xy 95.081656 -94.24924) (xy 95.074205 -94.257556) (xy 95.031337 -94.293231)
			(xy 94.983731 -94.322285) (xy 94.932402 -94.344097) (xy 94.878445 -94.358203) (xy 94.823008 -94.364303)
			(xy 94.767274 -94.362266) (xy 94.712431 -94.352136) (xy 94.659647 -94.334129) (xy 94.610047 -94.308628)
			(xy 94.564689 -94.276177) (xy 94.52454 -94.237468) (xy 94.490454 -94.193325) (xy 94.463158 -94.14469)
			(xy 94.443235 -94.092599) (xy 94.431109 -94.038162) (xy 94.427038 -93.98254) (xy 91.5035 -93.98254)
			(xy 91.5035 -95.054928) (xy 92.2782 -95.054928) (xy 92.278684 -95.026589) (xy 92.286401 -94.97044)
			(xy 92.301693 -94.915864) (xy 92.324273 -94.863878) (xy 92.353722 -94.815452) (xy 92.38949 -94.771487)
			(xy 92.430912 -94.732801) (xy 92.477216 -94.700116) (xy 92.527539 -94.674041) (xy 92.580944 -94.655061)
			(xy 92.636437 -94.643529) (xy 92.692982 -94.639662) (xy 92.749527 -94.643529) (xy 92.80502 -94.655061)
			(xy 92.858425 -94.674041) (xy 92.908748 -94.700116) (xy 92.955052 -94.732801) (xy 92.996474 -94.771487)
			(xy 93.032242 -94.815452) (xy 93.061691 -94.863878) (xy 93.084271 -94.915864) (xy 93.099563 -94.97044)
			(xy 93.10728 -95.026589) (xy 93.107764 -95.054928) (xy 93.107764 -95.055436) (xy 93.107286 -95.083391)
			(xy 93.099744 -95.138792) (xy 93.084827 -95.192676) (xy 93.062806 -95.244069) (xy 93.048836 -95.268288)
			(xy 93.041678 -95.281227) (xy 93.034376 -95.309867) (xy 93.035586 -95.339398) (xy 93.045204 -95.367344)
			(xy 93.062426 -95.391364) (xy 93.085808 -95.409443) (xy 93.113389 -95.420066) (xy 93.128084 -95.421704)
			(xy 93.156403 -95.424492) (xy 93.211821 -95.437401) (xy 93.264706 -95.4584) (xy 93.313884 -95.487023)
			(xy 93.358264 -95.522634) (xy 93.396862 -95.564444) (xy 93.428819 -95.611523) (xy 93.453428 -95.662829)
			(xy 93.470141 -95.71722) (xy 93.478589 -95.773491) (xy 93.479112 -95.801942) (xy 93.721426 -95.801942)
			(xy 93.725497 -95.74632) (xy 93.737623 -95.691883) (xy 93.757546 -95.639792) (xy 93.784842 -95.591157)
			(xy 93.818928 -95.547014) (xy 93.859077 -95.508305) (xy 93.904435 -95.475854) (xy 93.954035 -95.450353)
			(xy 94.006819 -95.432346) (xy 94.061662 -95.422216) (xy 94.117396 -95.420179) (xy 94.172833 -95.426279)
			(xy 94.22679 -95.440385) (xy 94.278119 -95.462197) (xy 94.325725 -95.491251) (xy 94.368593 -95.526926)
			(xy 94.40581 -95.568463) (xy 94.436583 -95.614976) (xy 94.460255 -95.665473) (xy 94.476323 -95.71888)
			(xy 94.484443 -95.774056) (xy 94.484952 -95.801942) (xy 94.484443 -95.829828) (xy 94.477301 -95.878357)
			(xy 99.120179 -95.878357) (xy 99.127934 -95.82441) (xy 99.143288 -95.772116) (xy 99.165927 -95.722539)
			(xy 99.195392 -95.676689) (xy 99.231081 -95.635498) (xy 99.27227 -95.599806) (xy 99.318118 -95.570339)
			(xy 99.367693 -95.547696) (xy 99.419986 -95.53234) (xy 99.473933 -95.524581) (xy 99.528434 -95.524579)
			(xy 99.582381 -95.532332) (xy 99.634675 -95.547685) (xy 99.684253 -95.570323) (xy 99.730104 -95.599786)
			(xy 99.771295 -95.635475) (xy 99.806988 -95.676662) (xy 99.836457 -95.72251) (xy 99.8591 -95.772085)
			(xy 99.874458 -95.824377) (xy 99.882218 -95.878323) (xy 99.882706 -95.905574) (xy 99.882706 -95.906082)
			(xy 99.882623 -95.916454) (xy 99.881481 -95.937166) (xy 99.88042 -95.947484) (xy 99.879281 -95.962029)
			(xy 99.884489 -95.990727) (xy 99.897586 -96.016789) (xy 99.917505 -96.038095) (xy 99.942628 -96.052912)
			(xy 99.970911 -96.060037) (xy 100.000056 -96.05889) (xy 100.014024 -96.054672) (xy 100.043635 -96.045328)
			(xy 100.1049 -96.03524) (xy 100.135944 -96.034606) (xy 100.136198 -96.034606) (xy 100.163449 -96.035076)
			(xy 100.217397 -96.042832) (xy 100.269692 -96.058187) (xy 100.319269 -96.080827) (xy 100.36512 -96.110293)
			(xy 100.40631 -96.145984) (xy 100.442002 -96.187174) (xy 100.471469 -96.233024) (xy 100.494111 -96.282601)
			(xy 100.509466 -96.334895) (xy 100.517224 -96.388843) (xy 100.517225 -96.443345) (xy 100.509469 -96.497293)
			(xy 100.494115 -96.549588) (xy 100.471475 -96.599166) (xy 100.442009 -96.645016) (xy 100.406319 -96.686207)
			(xy 100.365129 -96.7219) (xy 100.31928 -96.751367) (xy 100.269703 -96.774009) (xy 100.217409 -96.789366)
			(xy 100.163461 -96.797124) (xy 100.108959 -96.797125) (xy 100.055011 -96.78937) (xy 100.002716 -96.774016)
			(xy 99.953138 -96.751377) (xy 99.907287 -96.721912) (xy 99.866095 -96.686222) (xy 99.830403 -96.645032)
			(xy 99.800935 -96.599183) (xy 99.778292 -96.549607) (xy 99.762935 -96.497313) (xy 99.755177 -96.443365)
			(xy 99.75469 -96.416114) (xy 99.75469 -96.415606) (xy 99.754772 -96.405234) (xy 99.755915 -96.384522)
			(xy 99.756976 -96.374204) (xy 99.758131 -96.35966) (xy 99.75292 -96.33096) (xy 99.73982 -96.304898)
			(xy 99.719898 -96.283592) (xy 99.694773 -96.268774) (xy 99.666488 -96.26165) (xy 99.637341 -96.262798)
			(xy 99.623372 -96.267016) (xy 99.593761 -96.276361) (xy 99.532496 -96.286449) (xy 99.501452 -96.287082)
			(xy 99.501198 -96.287082) (xy 99.473947 -96.28662) (xy 99.420001 -96.278864) (xy 99.367707 -96.263509)
			(xy 99.318131 -96.240868) (xy 99.272281 -96.211403) (xy 99.231092 -96.175712) (xy 99.195401 -96.134523)
			(xy 99.165934 -96.088674) (xy 99.143293 -96.039098) (xy 99.127938 -95.986804) (xy 99.12018 -95.932858)
			(xy 99.120179 -95.878357) (xy 94.477301 -95.878357) (xy 94.476323 -95.885004) (xy 94.460255 -95.938411)
			(xy 94.436583 -95.988908) (xy 94.40581 -96.035421) (xy 94.368593 -96.076958) (xy 94.325725 -96.112633)
			(xy 94.278119 -96.141687) (xy 94.22679 -96.163499) (xy 94.172833 -96.177605) (xy 94.117396 -96.183705)
			(xy 94.061662 -96.181668) (xy 94.006819 -96.171538) (xy 93.954035 -96.153531) (xy 93.904435 -96.12803)
			(xy 93.859077 -96.095579) (xy 93.818928 -96.05687) (xy 93.784842 -96.012727) (xy 93.757546 -95.964092)
			(xy 93.737623 -95.912001) (xy 93.725497 -95.857564) (xy 93.721426 -95.801942) (xy 93.479112 -95.801942)
			(xy 93.478626 -95.829193) (xy 93.47087 -95.883141) (xy 93.455515 -95.935436) (xy 93.432873 -95.985013)
			(xy 93.403407 -96.030863) (xy 93.367716 -96.072054) (xy 93.326525 -96.107745) (xy 93.280675 -96.137211)
			(xy 93.231098 -96.159853) (xy 93.178803 -96.175208) (xy 93.124855 -96.182964) (xy 93.070353 -96.182964)
			(xy 93.016405 -96.175208) (xy 92.96411 -96.159853) (xy 92.914533 -96.137211) (xy 92.868683 -96.107745)
			(xy 92.827492 -96.072054) (xy 92.791801 -96.030863) (xy 92.762335 -95.985013) (xy 92.739693 -95.935436)
			(xy 92.724338 -95.883141) (xy 92.716582 -95.829193) (xy 92.716096 -95.801942) (xy 92.716748 -95.770229)
			(xy 92.727272 -95.707681) (xy 92.747971 -95.647727) (xy 92.762578 -95.61957) (xy 92.769141 -95.606342)
			(xy 92.775205 -95.577457) (xy 92.77277 -95.548043) (xy 92.76204 -95.520548) (xy 92.743906 -95.497261)
			(xy 92.71988 -95.480119) (xy 92.691959 -95.470551) (xy 92.677234 -95.469456) (xy 92.64836 -95.46789)
			(xy 92.591443 -95.457676) (xy 92.536496 -95.439657) (xy 92.484584 -95.414182) (xy 92.436712 -95.381745)
			(xy 92.393809 -95.342975) (xy 92.356705 -95.298623) (xy 92.326119 -95.249548) (xy 92.302645 -95.196701)
			(xy 92.286737 -95.141106) (xy 92.278703 -95.083841) (xy 92.2782 -95.054928) (xy 91.5035 -95.054928)
			(xy 91.5035 -96.374966) (xy 94.427038 -96.374966) (xy 94.431109 -96.319344) (xy 94.443235 -96.264907)
			(xy 94.463158 -96.212816) (xy 94.490454 -96.164181) (xy 94.52454 -96.120038) (xy 94.564689 -96.081329)
			(xy 94.610047 -96.048878) (xy 94.659647 -96.023377) (xy 94.712431 -96.00537) (xy 94.767274 -95.99524)
			(xy 94.823008 -95.993203) (xy 94.878445 -95.999303) (xy 94.932402 -96.013409) (xy 94.983731 -96.035221)
			(xy 95.031337 -96.064275) (xy 95.074205 -96.09995) (xy 95.111422 -96.141487) (xy 95.142195 -96.188)
			(xy 95.165867 -96.238497) (xy 95.180866 -96.288352) (xy 95.852232 -96.288352) (xy 95.856303 -96.23273)
			(xy 95.868429 -96.178293) (xy 95.888352 -96.126202) (xy 95.915648 -96.077567) (xy 95.949734 -96.033424)
			(xy 95.989883 -95.994715) (xy 96.035241 -95.962264) (xy 96.084841 -95.936763) (xy 96.137625 -95.918756)
			(xy 96.192468 -95.908626) (xy 96.248202 -95.906589) (xy 96.303639 -95.912689) (xy 96.357596 -95.926795)
			(xy 96.408925 -95.948607) (xy 96.456531 -95.977661) (xy 96.499399 -96.013336) (xy 96.536616 -96.054873)
			(xy 96.567389 -96.101386) (xy 96.591061 -96.151883) (xy 96.607129 -96.20529) (xy 96.615249 -96.260466)
			(xy 96.61548 -96.273112) (xy 97.197924 -96.273112) (xy 97.201995 -96.21749) (xy 97.214121 -96.163053)
			(xy 97.234044 -96.110962) (xy 97.26134 -96.062327) (xy 97.295426 -96.018184) (xy 97.335575 -95.979475)
			(xy 97.380933 -95.947024) (xy 97.430533 -95.921523) (xy 97.483317 -95.903516) (xy 97.53816 -95.893386)
			(xy 97.593894 -95.891349) (xy 97.649331 -95.897449) (xy 97.703288 -95.911555) (xy 97.754617 -95.933367)
			(xy 97.802223 -95.962421) (xy 97.845091 -95.998096) (xy 97.882308 -96.039633) (xy 97.913081 -96.086146)
			(xy 97.936753 -96.136643) (xy 97.952821 -96.19005) (xy 97.960941 -96.245226) (xy 97.96145 -96.273112)
			(xy 97.960941 -96.300998) (xy 97.952821 -96.356174) (xy 97.936753 -96.409581) (xy 97.913081 -96.460078)
			(xy 97.882308 -96.506591) (xy 97.845091 -96.548128) (xy 97.802223 -96.583803) (xy 97.754617 -96.612857)
			(xy 97.703288 -96.634669) (xy 97.649331 -96.648775) (xy 97.593894 -96.654875) (xy 97.53816 -96.652838)
			(xy 97.483317 -96.642708) (xy 97.430533 -96.624701) (xy 97.380933 -96.5992) (xy 97.335575 -96.566749)
			(xy 97.295426 -96.52804) (xy 97.26134 -96.483897) (xy 97.234044 -96.435262) (xy 97.214121 -96.383171)
			(xy 97.201995 -96.328734) (xy 97.197924 -96.273112) (xy 96.61548 -96.273112) (xy 96.615758 -96.288352)
			(xy 96.615249 -96.316238) (xy 96.607129 -96.371414) (xy 96.591061 -96.424821) (xy 96.567389 -96.475318)
			(xy 96.536616 -96.521831) (xy 96.499399 -96.563368) (xy 96.456531 -96.599043) (xy 96.408925 -96.628097)
			(xy 96.357596 -96.649909) (xy 96.303639 -96.664015) (xy 96.248202 -96.670115) (xy 96.192468 -96.668078)
			(xy 96.137625 -96.657948) (xy 96.084841 -96.639941) (xy 96.035241 -96.61444) (xy 95.989883 -96.581989)
			(xy 95.949734 -96.54328) (xy 95.915648 -96.499137) (xy 95.888352 -96.450502) (xy 95.868429 -96.398411)
			(xy 95.856303 -96.343974) (xy 95.852232 -96.288352) (xy 95.180866 -96.288352) (xy 95.181935 -96.291904)
			(xy 95.190055 -96.34708) (xy 95.190564 -96.374966) (xy 95.190055 -96.402852) (xy 95.181935 -96.458028)
			(xy 95.165867 -96.511435) (xy 95.142195 -96.561932) (xy 95.111422 -96.608445) (xy 95.074205 -96.649982)
			(xy 95.031337 -96.685657) (xy 94.983731 -96.714711) (xy 94.932402 -96.736523) (xy 94.878445 -96.750629)
			(xy 94.823008 -96.756729) (xy 94.767274 -96.754692) (xy 94.712431 -96.744562) (xy 94.659647 -96.726555)
			(xy 94.610047 -96.701054) (xy 94.564689 -96.668603) (xy 94.52454 -96.629894) (xy 94.490454 -96.585751)
			(xy 94.463158 -96.537116) (xy 94.443235 -96.485025) (xy 94.431109 -96.430588) (xy 94.427038 -96.374966)
			(xy 91.5035 -96.374966) (xy 91.5035 -97.446846) (xy 91.504516 -97.456244) (xy 91.506802 -97.467166)
			(xy 91.511628 -97.48012) (xy 91.515946 -97.488248) (xy 91.525598 -97.506536) (xy 91.532202 -97.511362)
			(xy 91.53525 -97.513648) (xy 91.53906 -97.516442) (xy 91.539568 -97.51695) (xy 91.541346 -97.51822)
			(xy 91.5416 -97.518474) (xy 91.543632 -97.519998) (xy 91.552797 -97.52721) (xy 91.570335 -97.542589)
			(xy 91.578684 -97.550732) (xy 91.5797 -97.551748) (xy 91.583002 -97.555304) (xy 91.583256 -97.555558)
			(xy 91.583764 -97.556066) (xy 91.585288 -97.557844) (xy 91.610688 -97.583752) (xy 91.61372 -97.586737)
			(xy 91.620618 -97.591717) (xy 91.624404 -97.593658) (xy 91.63685 -97.599754) (xy 91.639898 -97.601278)
			(xy 91.645121 -97.603619) (xy 91.656275 -97.606178) (xy 91.661996 -97.606358) (xy 91.718892 -97.606358)
			(xy 91.724616 -97.606206) (xy 91.735772 -97.603636) (xy 91.74099 -97.601278) (xy 91.744038 -97.599754)
			(xy 91.765882 -97.589086) (xy 91.77274 -97.583752) (xy 91.773248 -97.583244) (xy 91.776804 -97.578672)
			(xy 91.79503 -97.557331) (xy 91.836676 -97.51971) (xy 91.883383 -97.488596) (xy 91.934144 -97.464659)
			(xy 91.987863 -97.448415) (xy 92.043383 -97.440215) (xy 92.071444 -97.439734) (xy 92.098692 -97.440223)
			(xy 92.152633 -97.447985) (xy 92.20492 -97.463344) (xy 92.254489 -97.485989) (xy 92.300331 -97.515457)
			(xy 92.341512 -97.551149) (xy 92.377195 -97.592338) (xy 92.406653 -97.638187) (xy 92.429286 -97.687761)
			(xy 92.444633 -97.740051) (xy 92.452383 -97.793994) (xy 92.452952 -97.821242) (xy 92.705426 -97.821242)
			(xy 92.709497 -97.76562) (xy 92.721623 -97.711183) (xy 92.741546 -97.659092) (xy 92.768842 -97.610457)
			(xy 92.802928 -97.566314) (xy 92.843077 -97.527605) (xy 92.888435 -97.495154) (xy 92.938035 -97.469653)
			(xy 92.990819 -97.451646) (xy 93.045662 -97.441516) (xy 93.101396 -97.439479) (xy 93.156833 -97.445579)
			(xy 93.21079 -97.459685) (xy 93.262119 -97.481497) (xy 93.309725 -97.510551) (xy 93.352593 -97.546226)
			(xy 93.38981 -97.587763) (xy 93.420583 -97.634276) (xy 93.444255 -97.684773) (xy 93.460323 -97.73818)
			(xy 93.468443 -97.793356) (xy 93.468952 -97.821242) (xy 93.468443 -97.849128) (xy 93.460323 -97.904304)
			(xy 93.444255 -97.957711) (xy 93.420583 -98.008208) (xy 93.38981 -98.054721) (xy 93.352593 -98.096258)
			(xy 93.309725 -98.131933) (xy 93.262119 -98.160987) (xy 93.21079 -98.182799) (xy 93.156833 -98.196905)
			(xy 93.101396 -98.203005) (xy 93.045662 -98.200968) (xy 92.990819 -98.190838) (xy 92.938035 -98.172831)
			(xy 92.888435 -98.14733) (xy 92.843077 -98.114879) (xy 92.802928 -98.07617) (xy 92.768842 -98.032027)
			(xy 92.741546 -97.983392) (xy 92.721623 -97.931301) (xy 92.709497 -97.876864) (xy 92.705426 -97.821242)
			(xy 92.452952 -97.821242) (xy 92.452451 -97.84898) (xy 92.444414 -97.90387) (xy 92.428514 -97.957018)
			(xy 92.405086 -98.007305) (xy 92.374625 -98.053669) (xy 92.337772 -98.095136) (xy 92.295304 -98.130829)
			(xy 92.248116 -98.159998) (xy 92.197202 -98.182028) (xy 92.143635 -98.196454) (xy 92.116148 -98.20021)
			(xy 92.10167 -98.201734) (xy 92.071444 -98.203004) (xy 92.043325 -98.202501) (xy 91.987696 -98.19425)
			(xy 91.933877 -98.177933) (xy 91.883031 -98.153905) (xy 91.836256 -98.122683) (xy 91.794562 -98.084943)
			(xy 91.776296 -98.063558) (xy 91.771978 -98.058478) (xy 91.765374 -98.053144) (xy 91.7448 -98.042984)
			(xy 91.74099 -98.041206) (xy 91.735766 -98.038867) (xy 91.724613 -98.036311) (xy 91.718892 -98.036126)
			(xy 91.661996 -98.036126) (xy 91.656272 -98.036279) (xy 91.645117 -98.038851) (xy 91.639898 -98.041206)
			(xy 91.63685 -98.04273) (xy 91.615514 -98.053144) (xy 91.608148 -98.058986) (xy 91.604338 -98.063558)
			(xy 91.59621 -98.072956) (xy 91.595702 -98.073464) (xy 91.594686 -98.074734) (xy 91.589098 -98.08083)
			(xy 91.583764 -98.086418) (xy 91.583256 -98.086926) (xy 91.582748 -98.087434) (xy 91.58224 -98.087942)
			(xy 91.581732 -98.08845) (xy 91.573581 -98.096651) (xy 91.556424 -98.112156) (xy 91.547442 -98.119438)
			(xy 91.5416 -98.12401) (xy 91.540838 -98.124772) (xy 91.539314 -98.125788) (xy 91.53906 -98.126042)
			(xy 91.53525 -98.128836) (xy 91.532202 -98.131122) (xy 91.525344 -98.136202) (xy 91.509342 -98.166428)
			(xy 91.509342 -98.166682) (xy 91.506667 -98.172153) (xy 91.503711 -98.183964) (xy 91.5035 -98.19005)
			(xy 91.5035 -98.759518) (xy 99.171252 -98.759518) (xy 99.171716 -98.732148) (xy 99.179532 -98.677968)
			(xy 99.195021 -98.625464) (xy 99.217864 -98.575717) (xy 99.24759 -98.529751) (xy 99.265232 -98.50882)
			(xy 99.265486 -98.508566) (xy 99.27105 -98.501464) (xy 99.277311 -98.484559) (xy 99.277678 -98.475546)
			(xy 99.277678 -98.40849) (xy 99.277331 -98.399472) (xy 99.271077 -98.382555) (xy 99.265486 -98.37547)
			(xy 99.265232 -98.37547) (xy 99.265232 -98.375216) (xy 99.247609 -98.354269) (xy 99.217883 -98.308304)
			(xy 99.195036 -98.25856) (xy 99.179538 -98.20606) (xy 99.171708 -98.151883) (xy 99.171706 -98.097144)
			(xy 99.179532 -98.042966) (xy 99.195027 -97.990465) (xy 99.21787 -97.94072) (xy 99.247592 -97.894753)
			(xy 99.265232 -97.87382) (xy 99.265486 -97.873566) (xy 99.27105 -97.866464) (xy 99.277311 -97.849559)
			(xy 99.277678 -97.840546) (xy 99.277678 -97.77349) (xy 99.277331 -97.764472) (xy 99.271077 -97.747555)
			(xy 99.265486 -97.74047) (xy 99.265232 -97.74047) (xy 99.265232 -97.740216) (xy 99.247592 -97.719285)
			(xy 99.217879 -97.673312) (xy 99.195043 -97.623565) (xy 99.179552 -97.571063) (xy 99.171725 -97.516887)
			(xy 99.171252 -97.489518) (xy 99.171738 -97.462267) (xy 99.179494 -97.408319) (xy 99.194849 -97.356024)
			(xy 99.217491 -97.306447) (xy 99.246957 -97.260597) (xy 99.282648 -97.219406) (xy 99.323839 -97.183715)
			(xy 99.369689 -97.154249) (xy 99.419266 -97.131607) (xy 99.471561 -97.116252) (xy 99.525509 -97.108496)
			(xy 99.580011 -97.108496) (xy 99.633959 -97.116252) (xy 99.686254 -97.131607) (xy 99.735831 -97.154249)
			(xy 99.781681 -97.183715) (xy 99.822872 -97.219406) (xy 99.858563 -97.260597) (xy 99.888029 -97.306447)
			(xy 99.910671 -97.356024) (xy 99.926026 -97.408319) (xy 99.933782 -97.462267) (xy 99.934268 -97.489518)
			(xy 99.93382 -97.516889) (xy 99.925999 -97.571069) (xy 99.910506 -97.623573) (xy 99.88766 -97.673319)
			(xy 99.857931 -97.719285) (xy 99.840288 -97.740216) (xy 99.840034 -97.74047) (xy 99.834446 -97.747555)
			(xy 99.828202 -97.764473) (xy 99.827842 -97.77349) (xy 99.827842 -97.840546) (xy 99.828216 -97.849561)
			(xy 99.834451 -97.866479) (xy 99.840034 -97.873566) (xy 99.840288 -97.873566) (xy 99.840288 -97.87382)
			(xy 99.857946 -97.894739) (xy 99.887669 -97.940709) (xy 99.910512 -97.990458) (xy 99.926006 -98.042962)
			(xy 99.933833 -98.097142) (xy 99.933831 -98.151885) (xy 99.926 -98.206064) (xy 99.910502 -98.258567)
			(xy 99.887656 -98.308314) (xy 99.857929 -98.354283) (xy 99.840288 -98.375216) (xy 99.840034 -98.37547)
			(xy 99.834446 -98.382555) (xy 99.828202 -98.399473) (xy 99.827842 -98.40849) (xy 99.827842 -98.475546)
			(xy 99.828216 -98.484561) (xy 99.834451 -98.501479) (xy 99.836082 -98.503549) (xy 100.826086 -98.503549)
			(xy 100.826086 -98.449051) (xy 100.833841 -98.395108) (xy 100.849194 -98.342817) (xy 100.871832 -98.293244)
			(xy 100.901294 -98.247396) (xy 100.936981 -98.206207) (xy 100.978165 -98.170517) (xy 101.02401 -98.14105)
			(xy 101.073582 -98.118407) (xy 101.125871 -98.103049) (xy 101.179813 -98.095288) (xy 101.207062 -98.0948)
			(xy 101.233377 -98.095226) (xy 101.285508 -98.102469) (xy 101.336151 -98.116797) (xy 101.38435 -98.137937)
			(xy 101.429192 -98.16549) (xy 101.46983 -98.198935) (xy 101.487986 -98.21799) (xy 101.495512 -98.225386)
			(xy 101.514789 -98.233914) (xy 101.525324 -98.2345) (xy 101.6 -98.2345) (xy 101.610551 -98.233985)
			(xy 101.629847 -98.22544) (xy 101.637338 -98.21799) (xy 101.65548 -98.198921) (xy 101.696113 -98.165466)
			(xy 101.740956 -98.137909) (xy 101.789159 -98.116772) (xy 101.839809 -98.102458) (xy 101.891945 -98.095237)
			(xy 101.918262 -98.0948) (xy 101.945517 -98.095245) (xy 101.999473 -98.102998) (xy 102.051777 -98.118351)
			(xy 102.101363 -98.140991) (xy 102.147222 -98.170459) (xy 102.18842 -98.206153) (xy 102.224118 -98.247348)
			(xy 102.25359 -98.293204) (xy 102.273298 -98.336354) (xy 102.849426 -98.336354) (xy 102.849917 -98.308985)
			(xy 102.857728 -98.254806) (xy 102.873211 -98.202303) (xy 102.896047 -98.152556) (xy 102.925767 -98.106588)
			(xy 102.943406 -98.085656) (xy 102.94366 -98.085402) (xy 102.949259 -98.078324) (xy 102.955497 -98.0614)
			(xy 102.955852 -98.052382) (xy 102.955852 -97.985326) (xy 102.955493 -97.976309) (xy 102.949248 -97.959392)
			(xy 102.94366 -97.952306) (xy 102.943406 -97.952306) (xy 102.943406 -97.952052) (xy 102.925721 -97.931155)
			(xy 102.896 -97.885181) (xy 102.873158 -97.835428) (xy 102.857667 -97.782921) (xy 102.849843 -97.728738)
			(xy 102.849848 -97.673993) (xy 102.857681 -97.619811) (xy 102.873183 -97.567307) (xy 102.896033 -97.517558)
			(xy 102.925763 -97.471589) (xy 102.943406 -97.450656) (xy 102.94366 -97.450402) (xy 102.949259 -97.443324)
			(xy 102.955497 -97.4264) (xy 102.955852 -97.417382) (xy 102.955852 -97.350326) (xy 102.955493 -97.341309)
			(xy 102.949248 -97.324392) (xy 102.94366 -97.317306) (xy 102.943406 -97.317306) (xy 102.943406 -97.317052)
			(xy 102.925779 -97.29611) (xy 102.896065 -97.25014) (xy 102.873227 -97.200395) (xy 102.857733 -97.147897)
			(xy 102.849902 -97.093723) (xy 102.849426 -97.066354) (xy 102.849912 -97.039103) (xy 102.857668 -96.985155)
			(xy 102.873023 -96.93286) (xy 102.895665 -96.883283) (xy 102.925131 -96.837433) (xy 102.960822 -96.796242)
			(xy 103.002013 -96.760551) (xy 103.047863 -96.731085) (xy 103.09744 -96.708443) (xy 103.149735 -96.693088)
			(xy 103.203683 -96.685332) (xy 103.258185 -96.685332) (xy 103.312133 -96.693088) (xy 103.364428 -96.708443)
			(xy 103.414005 -96.731085) (xy 103.459855 -96.760551) (xy 103.501046 -96.796242) (xy 103.536737 -96.837433)
			(xy 103.566203 -96.883283) (xy 103.588845 -96.93286) (xy 103.6042 -96.985155) (xy 103.611956 -97.039103)
			(xy 103.612442 -97.066354) (xy 103.611963 -97.093724) (xy 103.604151 -97.147903) (xy 103.588665 -97.200407)
			(xy 103.565826 -97.250154) (xy 103.536103 -97.296121) (xy 103.518462 -97.317052) (xy 103.518208 -97.317306)
			(xy 103.512614 -97.324387) (xy 103.506371 -97.341308) (xy 103.506016 -97.350326) (xy 103.506016 -97.417382)
			(xy 103.506378 -97.426398) (xy 103.512622 -97.443316) (xy 103.518208 -97.450402) (xy 103.518462 -97.450402)
			(xy 103.518462 -97.450656) (xy 103.536058 -97.471625) (xy 103.565786 -97.517586) (xy 103.588634 -97.567326)
			(xy 103.604135 -97.619823) (xy 103.611968 -97.673997) (xy 103.611973 -97.728734) (xy 103.604149 -97.782909)
			(xy 103.588659 -97.835409) (xy 103.565819 -97.885153) (xy 103.5361 -97.93112) (xy 103.518462 -97.952052)
			(xy 103.518208 -97.952306) (xy 103.512614 -97.959387) (xy 103.506371 -97.976308) (xy 103.506016 -97.985326)
			(xy 103.506016 -98.052382) (xy 103.506378 -98.061398) (xy 103.512622 -98.078316) (xy 103.518208 -98.085402)
			(xy 103.518462 -98.085402) (xy 103.518462 -98.085656) (xy 103.536088 -98.106599) (xy 103.565803 -98.152568)
			(xy 103.588642 -98.202313) (xy 103.604136 -98.254811) (xy 103.611967 -98.308985) (xy 103.612442 -98.336354)
			(xy 103.612175 -98.35134) (xy 106.04373 -98.35134) (xy 106.044212 -98.32397) (xy 106.052025 -98.269792)
			(xy 106.06751 -98.217288) (xy 106.090348 -98.167541) (xy 106.12007 -98.121574) (xy 106.13771 -98.100642)
			(xy 106.137964 -98.100388) (xy 106.143569 -98.093315) (xy 106.149803 -98.076387) (xy 106.150156 -98.067368)
			(xy 106.150156 -98.000312) (xy 106.149803 -97.991295) (xy 106.143553 -97.974377) (xy 106.137964 -97.967292)
			(xy 106.13771 -97.967292) (xy 106.13771 -97.967038) (xy 106.120109 -97.946073) (xy 106.090384 -97.900111)
			(xy 106.067537 -97.850369) (xy 106.052039 -97.797872) (xy 106.044207 -97.743699) (xy 106.044202 -97.688962)
			(xy 106.052026 -97.634786) (xy 106.067516 -97.582287) (xy 106.090355 -97.532542) (xy 106.120073 -97.486575)
			(xy 106.13771 -97.465642) (xy 106.137964 -97.465388) (xy 106.143569 -97.458315) (xy 106.149803 -97.441387)
			(xy 106.150156 -97.432368) (xy 106.150156 -97.365312) (xy 106.149803 -97.356295) (xy 106.143553 -97.339377)
			(xy 106.137964 -97.332292) (xy 106.13771 -97.332292) (xy 106.13771 -97.332038) (xy 106.120077 -97.311101)
			(xy 106.090364 -97.26513) (xy 106.067527 -97.215384) (xy 106.052034 -97.162884) (xy 106.044205 -97.108709)
			(xy 106.04373 -97.08134) (xy 106.044216 -97.054089) (xy 106.051972 -97.000141) (xy 106.067327 -96.947846)
			(xy 106.089969 -96.898269) (xy 106.119435 -96.852419) (xy 106.155126 -96.811228) (xy 106.196317 -96.775537)
			(xy 106.242167 -96.746071) (xy 106.291744 -96.723429) (xy 106.344039 -96.708074) (xy 106.397987 -96.700318)
			(xy 106.452489 -96.700318) (xy 106.506437 -96.708074) (xy 106.558732 -96.723429) (xy 106.608309 -96.746071)
			(xy 106.654159 -96.775537) (xy 106.69535 -96.811228) (xy 106.731041 -96.852419) (xy 106.760507 -96.898269)
			(xy 106.783149 -96.947846) (xy 106.798504 -97.000141) (xy 106.80626 -97.054089) (xy 106.806746 -97.08134)
			(xy 106.806258 -97.10871) (xy 106.798447 -97.162888) (xy 106.782964 -97.215392) (xy 106.760127 -97.265139)
			(xy 106.730406 -97.311106) (xy 106.712766 -97.332038) (xy 106.712512 -97.332292) (xy 106.706924 -97.339378)
			(xy 106.700678 -97.356295) (xy 106.70032 -97.365312) (xy 106.70032 -97.432368) (xy 106.700688 -97.441384)
			(xy 106.706928 -97.458301) (xy 106.712512 -97.465388) (xy 106.712766 -97.465388) (xy 106.712766 -97.465642)
			(xy 106.730446 -97.486543) (xy 106.76017 -97.532516) (xy 106.783013 -97.582268) (xy 106.798507 -97.634774)
			(xy 106.806332 -97.688958) (xy 106.806327 -97.743703) (xy 106.798494 -97.797884) (xy 106.782992 -97.850389)
			(xy 106.760141 -97.900137) (xy 106.73041 -97.946105) (xy 106.712766 -97.967038) (xy 106.712512 -97.967292)
			(xy 106.706924 -97.974378) (xy 106.700678 -97.991295) (xy 106.70032 -98.000312) (xy 106.70032 -98.067368)
			(xy 106.700688 -98.076384) (xy 106.706928 -98.093301) (xy 106.712512 -98.100388) (xy 106.712766 -98.100388)
			(xy 106.712766 -98.100642) (xy 106.730386 -98.121589) (xy 106.760102 -98.167558) (xy 106.782942 -98.217301)
			(xy 106.798437 -98.269799) (xy 106.80627 -98.323972) (xy 106.806746 -98.35134) (xy 106.80626 -98.378591)
			(xy 106.798504 -98.432539) (xy 106.783149 -98.484834) (xy 106.760507 -98.534411) (xy 106.731041 -98.580261)
			(xy 106.69535 -98.621452) (xy 106.654159 -98.657143) (xy 106.608309 -98.686609) (xy 106.558732 -98.709251)
			(xy 106.506437 -98.724606) (xy 106.452489 -98.732362) (xy 106.397987 -98.732362) (xy 106.344039 -98.724606)
			(xy 106.291744 -98.709251) (xy 106.242167 -98.686609) (xy 106.196317 -98.657143) (xy 106.155126 -98.621452)
			(xy 106.119435 -98.580261) (xy 106.089969 -98.534411) (xy 106.067327 -98.484834) (xy 106.051972 -98.432539)
			(xy 106.044216 -98.378591) (xy 106.04373 -98.35134) (xy 103.612175 -98.35134) (xy 103.611956 -98.363605)
			(xy 103.6042 -98.417553) (xy 103.588845 -98.469848) (xy 103.566203 -98.519425) (xy 103.536737 -98.565275)
			(xy 103.501046 -98.606466) (xy 103.459855 -98.642157) (xy 103.414005 -98.671623) (xy 103.364428 -98.694265)
			(xy 103.312133 -98.70962) (xy 103.258185 -98.717376) (xy 103.203683 -98.717376) (xy 103.149735 -98.70962)
			(xy 103.09744 -98.694265) (xy 103.047863 -98.671623) (xy 103.002013 -98.642157) (xy 102.960822 -98.606466)
			(xy 102.925131 -98.565275) (xy 102.895665 -98.519425) (xy 102.873023 -98.469848) (xy 102.857668 -98.417553)
			(xy 102.849912 -98.363605) (xy 102.849426 -98.336354) (xy 102.273298 -98.336354) (xy 102.276236 -98.342787)
			(xy 102.291594 -98.395089) (xy 102.299353 -98.449045) (xy 102.299353 -98.503555) (xy 102.291594 -98.557511)
			(xy 102.276236 -98.609813) (xy 102.25359 -98.659396) (xy 102.224118 -98.705252) (xy 102.18842 -98.746447)
			(xy 102.147222 -98.782141) (xy 102.101363 -98.811609) (xy 102.051777 -98.834249) (xy 101.999473 -98.849602)
			(xy 101.945517 -98.857355) (xy 101.918262 -98.857816) (xy 101.891947 -98.857369) (xy 101.839818 -98.850129)
			(xy 101.789175 -98.835806) (xy 101.740977 -98.814669) (xy 101.696134 -98.78712) (xy 101.655494 -98.753679)
			(xy 101.637338 -98.734626) (xy 101.629801 -98.727243) (xy 101.610533 -98.718707) (xy 101.6 -98.718116)
			(xy 101.525324 -98.718116) (xy 101.514774 -98.71864) (xy 101.495478 -98.727178) (xy 101.487986 -98.734626)
			(xy 101.469835 -98.753686) (xy 101.429204 -98.787142) (xy 101.384363 -98.8147) (xy 101.336161 -98.835837)
			(xy 101.285513 -98.850154) (xy 101.233378 -98.857378) (xy 101.207062 -98.857816) (xy 101.179813 -98.857312)
			(xy 101.125871 -98.849551) (xy 101.073582 -98.834193) (xy 101.02401 -98.81155) (xy 100.978165 -98.782083)
			(xy 100.936981 -98.746393) (xy 100.901294 -98.705204) (xy 100.871832 -98.659356) (xy 100.849194 -98.609783)
			(xy 100.833841 -98.557492) (xy 100.826086 -98.503549) (xy 99.836082 -98.503549) (xy 99.840034 -98.508566)
			(xy 99.840288 -98.509074) (xy 99.851231 -98.521809) (xy 99.871073 -98.5489) (xy 99.879912 -98.563176)
			(xy 99.885246 -98.572066) (xy 99.902264 -98.584258) (xy 99.995482 -98.604578) (xy 100.016056 -98.60026)
			(xy 100.024692 -98.594418) (xy 100.048758 -98.578421) (xy 100.100688 -98.553077) (xy 100.155846 -98.535851)
			(xy 100.21297 -98.527135) (xy 100.241862 -98.5266) (xy 100.269117 -98.527045) (xy 100.323073 -98.534798)
			(xy 100.375377 -98.550151) (xy 100.424963 -98.572791) (xy 100.470822 -98.602259) (xy 100.51202 -98.637953)
			(xy 100.547718 -98.679148) (xy 100.57719 -98.725004) (xy 100.599836 -98.774587) (xy 100.615194 -98.826889)
			(xy 100.622953 -98.880845) (xy 100.622953 -98.935355) (xy 100.62135 -98.9465) (xy 119.061439 -98.9465)
			(xy 119.065326 -98.889669) (xy 119.076916 -98.833896) (xy 119.095992 -98.780221) (xy 119.1222 -98.729644)
			(xy 119.15505 -98.683106) (xy 119.193931 -98.641475) (xy 119.238119 -98.605527) (xy 119.286791 -98.575929)
			(xy 119.339039 -98.553235) (xy 119.393891 -98.537867) (xy 119.450324 -98.530112) (xy 119.478806 -98.529648)
			(xy 119.503237 -98.530013) (xy 119.551757 -98.53578) (xy 119.59927 -98.547186) (xy 119.622316 -98.555302)
			(xy 119.631282 -98.558149) (xy 119.650076 -98.557822) (xy 119.667494 -98.550754) (xy 119.67464 -98.544634)
			(xy 119.751348 -98.47199) (xy 119.758714 -98.444558) (xy 119.75465 -98.430588) (xy 119.747085 -98.403722)
			(xy 119.738924 -98.348511) (xy 119.738394 -98.320606) (xy 119.738849 -98.293353) (xy 119.746605 -98.239401)
			(xy 119.761961 -98.187102) (xy 119.784603 -98.13752) (xy 119.814071 -98.091666) (xy 119.849764 -98.050472)
			(xy 119.890957 -98.014777) (xy 119.936811 -97.985308) (xy 119.986392 -97.962664) (xy 120.03869 -97.947307)
			(xy 120.092642 -97.93955) (xy 120.147149 -97.939549) (xy 120.201101 -97.947305) (xy 120.2534 -97.962661)
			(xy 120.302981 -97.985304) (xy 120.348835 -98.014772) (xy 120.390029 -98.050465) (xy 120.425724 -98.091658)
			(xy 120.455193 -98.137512) (xy 120.477836 -98.187093) (xy 120.493193 -98.239392) (xy 120.50095 -98.293343)
			(xy 120.500951 -98.320606) (xy 121.975878 -98.320606) (xy 121.979949 -98.264984) (xy 121.992075 -98.210547)
			(xy 122.011998 -98.158456) (xy 122.039294 -98.109821) (xy 122.07338 -98.065678) (xy 122.113529 -98.026969)
			(xy 122.158887 -97.994518) (xy 122.208487 -97.969017) (xy 122.261271 -97.95101) (xy 122.316114 -97.94088)
			(xy 122.371848 -97.938843) (xy 122.427285 -97.944943) (xy 122.481242 -97.959049) (xy 122.532571 -97.980861)
			(xy 122.580177 -98.009915) (xy 122.623045 -98.04559) (xy 122.660262 -98.087127) (xy 122.691035 -98.13364)
			(xy 122.714707 -98.184137) (xy 122.730775 -98.237544) (xy 122.73556 -98.27006) (xy 125.399544 -98.27006)
			(xy 125.403615 -98.214438) (xy 125.415741 -98.160001) (xy 125.435664 -98.10791) (xy 125.46296 -98.059275)
			(xy 125.497046 -98.015132) (xy 125.537195 -97.976423) (xy 125.582553 -97.943972) (xy 125.632153 -97.918471)
			(xy 125.684937 -97.900464) (xy 125.73978 -97.890334) (xy 125.795514 -97.888297) (xy 125.850951 -97.894397)
			(xy 125.904908 -97.908503) (xy 125.956237 -97.930315) (xy 126.003843 -97.959369) (xy 126.028929 -97.980246)
			(xy 134.734044 -97.980246) (xy 134.738115 -97.924624) (xy 134.750241 -97.870187) (xy 134.770164 -97.818096)
			(xy 134.79746 -97.769461) (xy 134.831546 -97.725318) (xy 134.871695 -97.686609) (xy 134.917053 -97.654158)
			(xy 134.966653 -97.628657) (xy 135.019437 -97.61065) (xy 135.07428 -97.60052) (xy 135.130014 -97.598483)
			(xy 135.185451 -97.604583) (xy 135.239408 -97.618689) (xy 135.290737 -97.640501) (xy 135.338343 -97.669555)
			(xy 135.381211 -97.70523) (xy 135.418428 -97.746767) (xy 135.449201 -97.79328) (xy 135.472873 -97.843777)
			(xy 135.488941 -97.897184) (xy 135.497061 -97.95236) (xy 135.49757 -97.980246) (xy 135.497061 -98.008132)
			(xy 135.488941 -98.063308) (xy 135.472873 -98.116715) (xy 135.449201 -98.167212) (xy 135.418428 -98.213725)
			(xy 135.381211 -98.255262) (xy 135.338343 -98.290937) (xy 135.290737 -98.319991) (xy 135.239408 -98.341803)
			(xy 135.185451 -98.355909) (xy 135.130014 -98.362009) (xy 135.07428 -98.359972) (xy 135.019437 -98.349842)
			(xy 134.966653 -98.331835) (xy 134.917053 -98.306334) (xy 134.871695 -98.273883) (xy 134.831546 -98.235174)
			(xy 134.79746 -98.191031) (xy 134.770164 -98.142396) (xy 134.750241 -98.090305) (xy 134.738115 -98.035868)
			(xy 134.734044 -97.980246) (xy 126.028929 -97.980246) (xy 126.046711 -97.995044) (xy 126.083928 -98.036581)
			(xy 126.114701 -98.083094) (xy 126.138373 -98.133591) (xy 126.154441 -98.186998) (xy 126.162561 -98.242174)
			(xy 126.16307 -98.27006) (xy 126.162561 -98.297946) (xy 126.154441 -98.353122) (xy 126.138373 -98.406529)
			(xy 126.114701 -98.457026) (xy 126.083928 -98.503539) (xy 126.046711 -98.545076) (xy 126.003843 -98.580751)
			(xy 125.956237 -98.609805) (xy 125.904908 -98.631617) (xy 125.850951 -98.645723) (xy 125.795514 -98.651823)
			(xy 125.73978 -98.649786) (xy 125.684937 -98.639656) (xy 125.632153 -98.621649) (xy 125.582553 -98.596148)
			(xy 125.537195 -98.563697) (xy 125.497046 -98.524988) (xy 125.46296 -98.480845) (xy 125.435664 -98.43221)
			(xy 125.415741 -98.380119) (xy 125.403615 -98.325682) (xy 125.399544 -98.27006) (xy 122.73556 -98.27006)
			(xy 122.738895 -98.29272) (xy 122.739404 -98.320606) (xy 122.738895 -98.348492) (xy 122.730775 -98.403668)
			(xy 122.714707 -98.457075) (xy 122.691035 -98.507572) (xy 122.660262 -98.554085) (xy 122.623045 -98.595622)
			(xy 122.580177 -98.631297) (xy 122.532571 -98.660351) (xy 122.481242 -98.682163) (xy 122.427285 -98.696269)
			(xy 122.371848 -98.702369) (xy 122.316114 -98.700332) (xy 122.261271 -98.690202) (xy 122.208487 -98.672195)
			(xy 122.158887 -98.646694) (xy 122.113529 -98.614243) (xy 122.07338 -98.575534) (xy 122.039294 -98.531391)
			(xy 122.011998 -98.482756) (xy 121.992075 -98.430665) (xy 121.979949 -98.376228) (xy 121.975878 -98.320606)
			(xy 120.500951 -98.320606) (xy 120.500951 -98.34785) (xy 120.493194 -98.401802) (xy 120.477838 -98.454101)
			(xy 120.455196 -98.503682) (xy 120.425728 -98.549536) (xy 120.390034 -98.59073) (xy 120.34884 -98.626424)
			(xy 120.302987 -98.655893) (xy 120.253406 -98.678536) (xy 120.201107 -98.693893) (xy 120.147155 -98.70165)
			(xy 120.119902 -98.702114) (xy 120.089661 -98.701521) (xy 120.02994 -98.691956) (xy 120.00103 -98.683064)
			(xy 119.987314 -98.678492) (xy 119.959628 -98.68535) (xy 119.875046 -98.77044) (xy 119.868696 -98.798634)
			(xy 119.873268 -98.81235) (xy 119.875053 -98.817938) (xy 137.196068 -98.817938) (xy 137.196541 -98.790619)
			(xy 137.204336 -98.736541) (xy 137.219771 -98.68413) (xy 137.24253 -98.634459) (xy 137.272147 -98.588546)
			(xy 137.308016 -98.547331) (xy 137.328402 -98.52914) (xy 137.33653 -98.522028) (xy 137.345674 -98.502724)
			(xy 137.347706 -98.405442) (xy 137.339578 -98.38563) (xy 137.331704 -98.378264) (xy 137.313124 -98.360182)
			(xy 137.280545 -98.31985) (xy 137.253732 -98.275476) (xy 137.233179 -98.227878) (xy 137.219265 -98.177934)
			(xy 137.212248 -98.126565) (xy 137.211816 -98.100642) (xy 137.212302 -98.073391) (xy 137.220058 -98.019443)
			(xy 137.235413 -97.967148) (xy 137.258055 -97.917571) (xy 137.287521 -97.871721) (xy 137.323212 -97.83053)
			(xy 137.364403 -97.794839) (xy 137.410253 -97.765373) (xy 137.45983 -97.742731) (xy 137.512125 -97.727376)
			(xy 137.566073 -97.71962) (xy 137.620575 -97.71962) (xy 137.674523 -97.727376) (xy 137.726818 -97.742731)
			(xy 137.776395 -97.765373) (xy 137.809577 -97.786698) (xy 140.222984 -97.786698) (xy 140.227055 -97.731076)
			(xy 140.239181 -97.676639) (xy 140.259104 -97.624548) (xy 140.2864 -97.575913) (xy 140.320486 -97.53177)
			(xy 140.360635 -97.493061) (xy 140.405993 -97.46061) (xy 140.455593 -97.435109) (xy 140.508377 -97.417102)
			(xy 140.56322 -97.406972) (xy 140.618954 -97.404935) (xy 140.674391 -97.411035) (xy 140.728348 -97.425141)
			(xy 140.779677 -97.446953) (xy 140.827283 -97.476007) (xy 140.870151 -97.511682) (xy 140.907368 -97.553219)
			(xy 140.938141 -97.599732) (xy 140.961813 -97.650229) (xy 140.965655 -97.663) (xy 182.980582 -97.663)
			(xy 182.984653 -97.607378) (xy 182.996779 -97.552941) (xy 183.016702 -97.50085) (xy 183.043998 -97.452215)
			(xy 183.078084 -97.408072) (xy 183.118233 -97.369363) (xy 183.163591 -97.336912) (xy 183.213191 -97.311411)
			(xy 183.265975 -97.293404) (xy 183.320818 -97.283274) (xy 183.376552 -97.281237) (xy 183.431989 -97.287337)
			(xy 183.485946 -97.301443) (xy 183.537275 -97.323255) (xy 183.584881 -97.352309) (xy 183.627749 -97.387984)
			(xy 183.664966 -97.429521) (xy 183.695739 -97.476034) (xy 183.719411 -97.526531) (xy 183.735479 -97.579938)
			(xy 183.743599 -97.635114) (xy 183.744108 -97.663) (xy 183.743599 -97.690886) (xy 183.735479 -97.746062)
			(xy 183.719411 -97.799469) (xy 183.695739 -97.849966) (xy 183.664966 -97.896479) (xy 183.627749 -97.938016)
			(xy 183.584881 -97.973691) (xy 183.537275 -98.002745) (xy 183.485946 -98.024557) (xy 183.431989 -98.038663)
			(xy 183.376552 -98.044763) (xy 183.320818 -98.042726) (xy 183.265975 -98.032596) (xy 183.213191 -98.014589)
			(xy 183.163591 -97.989088) (xy 183.118233 -97.956637) (xy 183.078084 -97.917928) (xy 183.043998 -97.873785)
			(xy 183.016702 -97.82515) (xy 182.996779 -97.773059) (xy 182.984653 -97.718622) (xy 182.980582 -97.663)
			(xy 140.965655 -97.663) (xy 140.977881 -97.703636) (xy 140.986001 -97.758812) (xy 140.98651 -97.786698)
			(xy 140.986001 -97.814584) (xy 140.977881 -97.86976) (xy 140.961813 -97.923167) (xy 140.938141 -97.973664)
			(xy 140.907368 -98.020177) (xy 140.870151 -98.061714) (xy 140.827283 -98.097389) (xy 140.779677 -98.126443)
			(xy 140.728348 -98.148255) (xy 140.674391 -98.162361) (xy 140.618954 -98.168461) (xy 140.56322 -98.166424)
			(xy 140.508377 -98.156294) (xy 140.455593 -98.138287) (xy 140.405993 -98.112786) (xy 140.360635 -98.080335)
			(xy 140.320486 -98.041626) (xy 140.2864 -97.997483) (xy 140.259104 -97.948848) (xy 140.239181 -97.896757)
			(xy 140.227055 -97.84232) (xy 140.222984 -97.786698) (xy 137.809577 -97.786698) (xy 137.822245 -97.794839)
			(xy 137.863436 -97.83053) (xy 137.899127 -97.871721) (xy 137.928593 -97.917571) (xy 137.951235 -97.967148)
			(xy 137.96659 -98.019443) (xy 137.974346 -98.073391) (xy 137.974832 -98.100642) (xy 137.974345 -98.12796)
			(xy 137.966553 -98.182038) (xy 137.951121 -98.234449) (xy 137.928364 -98.28412) (xy 137.89875 -98.330033)
			(xy 137.862883 -98.371249) (xy 137.842498 -98.38944) (xy 137.83437 -98.396552) (xy 137.825226 -98.415856)
			(xy 137.823194 -98.513138) (xy 137.831322 -98.53295) (xy 137.839196 -98.540316) (xy 137.857766 -98.558408)
			(xy 137.890346 -98.598737) (xy 137.917161 -98.643109) (xy 137.937715 -98.690705) (xy 137.951631 -98.740648)
			(xy 137.958651 -98.792015) (xy 137.959084 -98.817938) (xy 137.958604 -98.845616) (xy 137.950594 -98.900391)
			(xy 137.934747 -98.953431) (xy 137.911398 -99.003623) (xy 137.881035 -99.04991) (xy 137.844299 -99.09132)
			(xy 137.823448 -99.10953) (xy 137.817228 -99.1152) (xy 137.808602 -99.12964) (xy 137.805166 -99.146106)
			(xy 137.805922 -99.154488) (xy 137.81786 -99.25177) (xy 137.831353 -99.270847) (xy 139.73052 -99.270847)
			(xy 139.73052 -99.216352) (xy 139.738275 -99.162412) (xy 139.753628 -99.110125) (xy 139.776265 -99.060555)
			(xy 139.805726 -99.01471) (xy 139.841412 -98.973525) (xy 139.882595 -98.937838) (xy 139.928438 -98.908374)
			(xy 139.978007 -98.885735) (xy 140.030293 -98.870379) (xy 140.084233 -98.862622) (xy 140.11148 -98.862134)
			(xy 140.112242 -98.862134) (xy 140.124213 -98.862244) (xy 140.148106 -98.863771) (xy 140.159994 -98.865182)
			(xy 140.173619 -98.866442) (xy 140.200694 -98.862562) (xy 140.225769 -98.851638) (xy 140.247046 -98.834451)
			(xy 140.262999 -98.812234) (xy 140.272485 -98.786581) (xy 140.274824 -98.75933) (xy 140.27277 -98.745802)
			(xy 140.269688 -98.72844) (xy 140.266385 -98.69333) (xy 140.266166 -98.675698) (xy 140.266658 -98.648445)
			(xy 140.274415 -98.594494) (xy 140.289772 -98.542196) (xy 140.312415 -98.492615) (xy 140.341884 -98.446762)
			(xy 140.377578 -98.40557) (xy 140.418772 -98.369876) (xy 140.464626 -98.340409) (xy 140.514207 -98.317767)
			(xy 140.566505 -98.302412) (xy 140.620457 -98.294657) (xy 140.674963 -98.294658) (xy 140.728914 -98.302417)
			(xy 140.781212 -98.317774) (xy 140.830792 -98.340419) (xy 140.876644 -98.369888) (xy 140.917836 -98.405584)
			(xy 140.953528 -98.446778) (xy 140.982995 -98.492633) (xy 141.005635 -98.542214) (xy 141.020989 -98.594513)
			(xy 141.028744 -98.648465) (xy 141.028741 -98.702971) (xy 141.020982 -98.756922) (xy 141.005623 -98.80922)
			(xy 140.982978 -98.858799) (xy 140.953507 -98.904651) (xy 140.917811 -98.945842) (xy 140.876615 -98.981533)
			(xy 140.83076 -99.010999) (xy 140.781178 -99.033638) (xy 140.728879 -99.048991) (xy 140.674927 -99.056744)
			(xy 140.647674 -99.057206) (xy 140.646912 -99.057206) (xy 140.634941 -99.057091) (xy 140.611048 -99.055568)
			(xy 140.59916 -99.054158) (xy 140.58554 -99.052806) (xy 140.558454 -99.056698) (xy 140.533372 -99.067637)
			(xy 140.512091 -99.084839) (xy 140.496138 -99.107072) (xy 140.486656 -99.13274) (xy 140.484325 -99.160005)
			(xy 140.486384 -99.173538) (xy 140.489458 -99.190901) (xy 140.492767 -99.22601) (xy 140.492988 -99.243642)
			(xy 140.492477 -99.270889) (xy 140.484716 -99.324828) (xy 140.469358 -99.377114) (xy 140.446715 -99.426682)
			(xy 140.417249 -99.472523) (xy 140.381559 -99.513704) (xy 140.340372 -99.549387) (xy 140.294526 -99.578846)
			(xy 140.244954 -99.60148) (xy 140.192666 -99.616829) (xy 140.138726 -99.624581) (xy 140.084231 -99.624578)
			(xy 140.030292 -99.61682) (xy 139.978006 -99.601465) (xy 139.928436 -99.578825) (xy 139.882594 -99.549361)
			(xy 139.841411 -99.513674) (xy 139.805725 -99.472489) (xy 139.776264 -99.426644) (xy 139.753627 -99.377074)
			(xy 139.738275 -99.324787) (xy 139.73052 -99.270847) (xy 137.831353 -99.270847) (xy 137.832592 -99.272598)
			(xy 137.844276 -99.27844) (xy 137.868 -99.290514) (xy 137.912108 -99.320319) (xy 137.951641 -99.35597)
			(xy 137.985831 -99.396772) (xy 138.014014 -99.441933) (xy 138.035642 -99.490574) (xy 138.050295 -99.541752)
			(xy 138.057687 -99.594469) (xy 138.058144 -99.621086) (xy 138.057658 -99.648337) (xy 138.049902 -99.702285)
			(xy 138.034547 -99.75458) (xy 138.011905 -99.804157) (xy 137.982439 -99.850007) (xy 137.946748 -99.891198)
			(xy 137.905557 -99.926889) (xy 137.859707 -99.956355) (xy 137.81013 -99.978997) (xy 137.757835 -99.994352)
			(xy 137.703887 -100.002108) (xy 137.649385 -100.002108) (xy 137.595437 -99.994352) (xy 137.543142 -99.978997)
			(xy 137.493565 -99.956355) (xy 137.447715 -99.926889) (xy 137.406524 -99.891198) (xy 137.370833 -99.850007)
			(xy 137.341367 -99.804157) (xy 137.318725 -99.75458) (xy 137.30337 -99.702285) (xy 137.295614 -99.648337)
			(xy 137.295128 -99.621086) (xy 137.29562 -99.593408) (xy 137.303627 -99.538634) (xy 137.319471 -99.485594)
			(xy 137.342819 -99.435402) (xy 137.373179 -99.389114) (xy 137.409914 -99.347704) (xy 137.430764 -99.329494)
			(xy 137.437029 -99.323867) (xy 137.445643 -99.309406) (xy 137.449059 -99.292923) (xy 137.44829 -99.284536)
			(xy 137.436352 -99.187254) (xy 137.42162 -99.166426) (xy 137.409936 -99.160584) (xy 137.386224 -99.148486)
			(xy 137.342117 -99.118685) (xy 137.302583 -99.083038) (xy 137.268392 -99.04224) (xy 137.240207 -98.997082)
			(xy 137.218577 -98.948443) (xy 137.203922 -98.897269) (xy 137.196527 -98.844554) (xy 137.196068 -98.817938)
			(xy 119.875053 -98.817938) (xy 119.883668 -98.8449) (xy 119.894896 -98.912299) (xy 119.89562 -98.946462)
			(xy 119.893588 -98.987102) (xy 119.892318 -98.999294) (xy 119.901716 -99.022662) (xy 119.984266 -99.09302)
			(xy 120.008904 -99.098354) (xy 120.020842 -99.095052) (xy 120.045152 -99.088964) (xy 120.094844 -99.082462)
			(xy 120.119902 -99.082098) (xy 120.147153 -99.08258) (xy 120.2011 -99.090337) (xy 120.253394 -99.105692)
			(xy 120.302971 -99.128333) (xy 120.348821 -99.157799) (xy 120.390011 -99.19349) (xy 120.425702 -99.23468)
			(xy 120.455168 -99.28053) (xy 120.477809 -99.330107) (xy 120.493164 -99.382401) (xy 120.50092 -99.436348)
			(xy 120.50092 -99.463606) (xy 121.975878 -99.463606) (xy 121.979949 -99.407984) (xy 121.992075 -99.353547)
			(xy 122.011998 -99.301456) (xy 122.039294 -99.252821) (xy 122.07338 -99.208678) (xy 122.113529 -99.169969)
			(xy 122.158887 -99.137518) (xy 122.208487 -99.112017) (xy 122.261271 -99.09401) (xy 122.316114 -99.08388)
			(xy 122.371848 -99.081843) (xy 122.427285 -99.087943) (xy 122.481242 -99.102049) (xy 122.532571 -99.123861)
			(xy 122.580177 -99.152915) (xy 122.623045 -99.18859) (xy 122.660262 -99.230127) (xy 122.691035 -99.27664)
			(xy 122.714707 -99.327137) (xy 122.730775 -99.380544) (xy 122.738895 -99.43572) (xy 122.739404 -99.463606)
			(xy 124.405388 -99.463606) (xy 124.409459 -99.407984) (xy 124.421585 -99.353547) (xy 124.441508 -99.301456)
			(xy 124.468804 -99.252821) (xy 124.50289 -99.208678) (xy 124.543039 -99.169969) (xy 124.588397 -99.137518)
			(xy 124.637997 -99.112017) (xy 124.690781 -99.09401) (xy 124.745624 -99.08388) (xy 124.801358 -99.081843)
			(xy 124.856795 -99.087943) (xy 124.910752 -99.102049) (xy 124.962081 -99.123861) (xy 125.009687 -99.152915)
			(xy 125.052555 -99.18859) (xy 125.089772 -99.230127) (xy 125.098714 -99.243642) (xy 135.047988 -99.243642)
			(xy 135.052059 -99.18802) (xy 135.064185 -99.133583) (xy 135.084108 -99.081492) (xy 135.111404 -99.032857)
			(xy 135.14549 -98.988714) (xy 135.185639 -98.950005) (xy 135.230997 -98.917554) (xy 135.280597 -98.892053)
			(xy 135.333381 -98.874046) (xy 135.388224 -98.863916) (xy 135.443958 -98.861879) (xy 135.499395 -98.867979)
			(xy 135.553352 -98.882085) (xy 135.604681 -98.903897) (xy 135.652287 -98.932951) (xy 135.695155 -98.968626)
			(xy 135.732372 -99.010163) (xy 135.763145 -99.056676) (xy 135.786817 -99.107173) (xy 135.802885 -99.16058)
			(xy 135.811005 -99.215756) (xy 135.811514 -99.243642) (xy 135.811005 -99.271528) (xy 135.802885 -99.326704)
			(xy 135.786817 -99.380111) (xy 135.763145 -99.430608) (xy 135.732372 -99.477121) (xy 135.695155 -99.518658)
			(xy 135.652287 -99.554333) (xy 135.604681 -99.583387) (xy 135.553352 -99.605199) (xy 135.499395 -99.619305)
			(xy 135.443958 -99.625405) (xy 135.388224 -99.623368) (xy 135.333381 -99.613238) (xy 135.280597 -99.595231)
			(xy 135.230997 -99.56973) (xy 135.185639 -99.537279) (xy 135.14549 -99.49857) (xy 135.111404 -99.454427)
			(xy 135.084108 -99.405792) (xy 135.064185 -99.353701) (xy 135.052059 -99.299264) (xy 135.047988 -99.243642)
			(xy 125.098714 -99.243642) (xy 125.120545 -99.27664) (xy 125.144217 -99.327137) (xy 125.160285 -99.380544)
			(xy 125.168405 -99.43572) (xy 125.168914 -99.463606) (xy 125.168405 -99.491492) (xy 125.160285 -99.546668)
			(xy 125.144217 -99.600075) (xy 125.120545 -99.650572) (xy 125.089772 -99.697085) (xy 125.052555 -99.738622)
			(xy 125.009687 -99.774297) (xy 124.962081 -99.803351) (xy 124.910752 -99.825163) (xy 124.856795 -99.839269)
			(xy 124.801358 -99.845369) (xy 124.745624 -99.843332) (xy 124.690781 -99.833202) (xy 124.637997 -99.815195)
			(xy 124.588397 -99.789694) (xy 124.543039 -99.757243) (xy 124.50289 -99.718534) (xy 124.468804 -99.674391)
			(xy 124.441508 -99.625756) (xy 124.421585 -99.573665) (xy 124.409459 -99.519228) (xy 124.405388 -99.463606)
			(xy 122.739404 -99.463606) (xy 122.738895 -99.491492) (xy 122.730775 -99.546668) (xy 122.714707 -99.600075)
			(xy 122.691035 -99.650572) (xy 122.660262 -99.697085) (xy 122.623045 -99.738622) (xy 122.580177 -99.774297)
			(xy 122.532571 -99.803351) (xy 122.481242 -99.825163) (xy 122.427285 -99.839269) (xy 122.371848 -99.845369)
			(xy 122.316114 -99.843332) (xy 122.261271 -99.833202) (xy 122.208487 -99.815195) (xy 122.158887 -99.789694)
			(xy 122.113529 -99.757243) (xy 122.07338 -99.718534) (xy 122.039294 -99.674391) (xy 122.011998 -99.625756)
			(xy 121.992075 -99.573665) (xy 121.979949 -99.519228) (xy 121.975878 -99.463606) (xy 120.50092 -99.463606)
			(xy 120.50092 -99.49085) (xy 120.493164 -99.544798) (xy 120.477809 -99.597092) (xy 120.455168 -99.646669)
			(xy 120.425703 -99.692519) (xy 120.390012 -99.733709) (xy 120.348822 -99.7694) (xy 120.302972 -99.798866)
			(xy 120.253396 -99.821508) (xy 120.201101 -99.836863) (xy 120.147154 -99.84462) (xy 120.092652 -99.84462)
			(xy 120.038705 -99.836865) (xy 119.986411 -99.82151) (xy 119.936834 -99.79887) (xy 119.890983 -99.769404)
			(xy 119.849793 -99.733713) (xy 119.814101 -99.692524) (xy 119.784635 -99.646675) (xy 119.761993 -99.597098)
			(xy 119.746637 -99.544804) (xy 119.73888 -99.490857) (xy 119.738394 -99.463606) (xy 119.738902 -99.44481)
			(xy 119.73941 -99.432364) (xy 119.728996 -99.409758) (xy 119.652796 -99.351338) (xy 119.642626 -99.344282)
			(xy 119.618272 -99.340014) (xy 119.606314 -99.34321) (xy 119.575271 -99.352569) (xy 119.511223 -99.362643)
			(xy 119.478806 -99.363276) (xy 119.450324 -99.362888) (xy 119.393891 -99.355133) (xy 119.339039 -99.339765)
			(xy 119.286791 -99.317071) (xy 119.238119 -99.287473) (xy 119.193931 -99.251525) (xy 119.15505 -99.209894)
			(xy 119.1222 -99.163356) (xy 119.095992 -99.112779) (xy 119.076916 -99.059104) (xy 119.065326 -99.003331)
			(xy 119.061439 -98.9465) (xy 100.62135 -98.9465) (xy 100.615194 -98.989311) (xy 100.599836 -99.041613)
			(xy 100.57719 -99.091196) (xy 100.547718 -99.137052) (xy 100.51202 -99.178247) (xy 100.470822 -99.213941)
			(xy 100.424963 -99.243409) (xy 100.375377 -99.266049) (xy 100.323073 -99.281402) (xy 100.269117 -99.289155)
			(xy 100.241862 -99.289616) (xy 100.213769 -99.289152) (xy 100.158191 -99.28092) (xy 100.104421 -99.264623)
			(xy 100.053623 -99.240615) (xy 100.006897 -99.209416) (xy 99.965253 -99.171699) (xy 99.929592 -99.128282)
			(xy 99.91471 -99.10445) (xy 99.909376 -99.09556) (xy 99.892358 -99.083368) (xy 99.79914 -99.063048)
			(xy 99.778566 -99.067366) (xy 99.76993 -99.073208) (xy 99.74586 -99.089198) (xy 99.693931 -99.114543)
			(xy 99.638775 -99.131771) (xy 99.581652 -99.14049) (xy 99.55276 -99.141026) (xy 99.525509 -99.140559)
			(xy 99.471561 -99.132798) (xy 99.419267 -99.117439) (xy 99.369691 -99.094794) (xy 99.323842 -99.065325)
			(xy 99.282652 -99.029632) (xy 99.246961 -98.988441) (xy 99.217495 -98.94259) (xy 99.194854 -98.893012)
			(xy 99.179497 -98.840717) (xy 99.171739 -98.786769) (xy 99.171252 -98.759518) (xy 91.5035 -98.759518)
			(xy 91.5035 -99.234752) (xy 91.504 -99.245835) (xy 91.513223 -99.265986) (xy 91.52128 -99.273614)
			(xy 91.521788 -99.273614) (xy 91.523058 -99.274884) (xy 91.528138 -99.27844) (xy 91.56192 -99.295712)
			(xy 91.611958 -99.321112) (xy 91.616459 -99.32325) (xy 91.626051 -99.325939) (xy 91.631008 -99.326446)
			(xy 91.639136 -99.326446) (xy 91.644954 -99.325876) (xy 91.656114 -99.322409) (xy 91.661234 -99.319588)
			(xy 91.665044 -99.316794) (xy 91.689616 -99.299746) (xy 91.742948 -99.272691) (xy 91.799845 -99.25428)
			(xy 91.858917 -99.244961) (xy 91.888818 -99.244404) (xy 91.916068 -99.244892) (xy 91.970013 -99.25265)
			(xy 92.022305 -99.268007) (xy 92.071879 -99.290649) (xy 92.117726 -99.320116) (xy 92.158913 -99.355808)
			(xy 92.194602 -99.396998) (xy 92.224065 -99.442847) (xy 92.231225 -99.458526) (xy 93.638622 -99.458526)
			(xy 93.642693 -99.402904) (xy 93.654819 -99.348467) (xy 93.674742 -99.296376) (xy 93.702038 -99.247741)
			(xy 93.736124 -99.203598) (xy 93.776273 -99.164889) (xy 93.821631 -99.132438) (xy 93.871231 -99.106937)
			(xy 93.924015 -99.08893) (xy 93.978858 -99.0788) (xy 94.034592 -99.076763) (xy 94.090029 -99.082863)
			(xy 94.143986 -99.096969) (xy 94.195315 -99.118781) (xy 94.242921 -99.147835) (xy 94.285789 -99.18351)
			(xy 94.323006 -99.225047) (xy 94.353779 -99.27156) (xy 94.377451 -99.322057) (xy 94.393519 -99.375464)
			(xy 94.401639 -99.43064) (xy 94.402148 -99.458526) (xy 94.401639 -99.486412) (xy 94.393519 -99.541588)
			(xy 94.377451 -99.594995) (xy 94.353779 -99.645492) (xy 94.323006 -99.692005) (xy 94.285789 -99.733542)
			(xy 94.242921 -99.769217) (xy 94.195315 -99.798271) (xy 94.143986 -99.820083) (xy 94.090029 -99.834189)
			(xy 94.034592 -99.840289) (xy 93.978858 -99.838252) (xy 93.924015 -99.828122) (xy 93.871231 -99.810115)
			(xy 93.821631 -99.784614) (xy 93.776273 -99.752163) (xy 93.736124 -99.713454) (xy 93.702038 -99.669311)
			(xy 93.674742 -99.620676) (xy 93.654819 -99.568585) (xy 93.642693 -99.514148) (xy 93.638622 -99.458526)
			(xy 92.231225 -99.458526) (xy 92.246704 -99.492423) (xy 92.262056 -99.544716) (xy 92.269811 -99.598662)
			(xy 92.270326 -99.625912) (xy 92.269821 -99.653648) (xy 92.261775 -99.708535) (xy 92.24587 -99.761679)
			(xy 92.22244 -99.811961) (xy 92.191978 -99.858322) (xy 92.155127 -99.899786) (xy 92.112662 -99.935479)
			(xy 92.065478 -99.964649) (xy 92.014569 -99.986683) (xy 91.961007 -100.001116) (xy 91.933522 -100.00488)
			(xy 91.919806 -100.006404) (xy 91.888818 -100.007674) (xy 91.858918 -100.007096) (xy 91.799847 -99.997782)
			(xy 91.742948 -99.979379) (xy 91.689612 -99.952336) (xy 91.665044 -99.935284) (xy 91.664536 -99.93503)
			(xy 91.66098 -99.932998) (xy 91.655646 -99.929696) (xy 91.651596 -99.927893) (xy 91.643036 -99.925596)
			(xy 91.638628 -99.925124) (xy 91.624658 -99.924108) (xy 91.606624 -99.933252) (xy 91.530424 -99.972114)
			(xy 91.521534 -99.97821) (xy 91.513397 -99.9858) (xy 91.504037 -100.005958) (xy 91.5035 -100.017072)
			(xy 91.5035 -100.392992) (xy 95.37395 -100.392992) (xy 95.378021 -100.33737) (xy 95.390147 -100.282933)
			(xy 95.41007 -100.230842) (xy 95.437366 -100.182207) (xy 95.471452 -100.138064) (xy 95.511601 -100.099355)
			(xy 95.556959 -100.066904) (xy 95.606559 -100.041403) (xy 95.659343 -100.023396) (xy 95.714186 -100.013266)
			(xy 95.76992 -100.011229) (xy 95.825357 -100.017329) (xy 95.879314 -100.031435) (xy 95.930643 -100.053247)
			(xy 95.978249 -100.082301) (xy 96.021117 -100.117976) (xy 96.058334 -100.159513) (xy 96.089107 -100.206026)
			(xy 96.098643 -100.226368) (xy 119.200166 -100.226368) (xy 119.204237 -100.170746) (xy 119.216363 -100.116309)
			(xy 119.236286 -100.064218) (xy 119.263582 -100.015583) (xy 119.297668 -99.97144) (xy 119.337817 -99.932731)
			(xy 119.383175 -99.90028) (xy 119.432775 -99.874779) (xy 119.485559 -99.856772) (xy 119.540402 -99.846642)
			(xy 119.596136 -99.844605) (xy 119.651573 -99.850705) (xy 119.70553 -99.864811) (xy 119.756859 -99.886623)
			(xy 119.804465 -99.915677) (xy 119.847333 -99.951352) (xy 119.88455 -99.992889) (xy 119.915323 -100.039402)
			(xy 119.938995 -100.089899) (xy 119.955063 -100.143306) (xy 119.963183 -100.198482) (xy 119.963692 -100.226368)
			(xy 119.963183 -100.254254) (xy 119.955063 -100.30943) (xy 119.938995 -100.362837) (xy 119.919628 -100.40415)
			(xy 152.833311 -100.40415) (xy 152.833311 -100.34685) (xy 152.841465 -100.290134) (xy 152.857608 -100.235155)
			(xy 152.88141 -100.183033) (xy 152.912388 -100.134828) (xy 152.949911 -100.091523) (xy 152.993214 -100.053999)
			(xy 153.041417 -100.023019) (xy 153.093538 -99.999214) (xy 153.148516 -99.983069) (xy 153.205232 -99.974912)
			(xy 153.233882 -99.9744) (xy 153.2488 -99.974566) (xy 153.278549 -99.976857) (xy 153.293318 -99.978972)
			(xy 153.304494 -99.98075) (xy 153.325576 -99.974654) (xy 153.392378 -99.916996) (xy 153.400359 -99.909416)
			(xy 153.409433 -99.889386) (xy 153.409904 -99.878388) (xy 153.409904 -99.61372) (xy 153.409386 -99.602733)
			(xy 153.40032 -99.58272) (xy 153.392378 -99.575112) (xy 153.325576 -99.517454) (xy 153.304494 -99.511358)
			(xy 153.293318 -99.513136) (xy 153.278549 -99.515245) (xy 153.2488 -99.517533) (xy 153.233882 -99.517708)
			(xy 153.205238 -99.517112) (xy 153.148532 -99.508956) (xy 153.093565 -99.492814) (xy 153.041453 -99.469014)
			(xy 152.99326 -99.43804) (xy 152.949965 -99.400522) (xy 152.912449 -99.357226) (xy 152.881478 -99.309031)
			(xy 152.85768 -99.256919) (xy 152.84154 -99.20195) (xy 152.833387 -99.145244) (xy 152.833387 -99.087956)
			(xy 152.84154 -99.03125) (xy 152.85768 -98.976281) (xy 152.881478 -98.924169) (xy 152.912449 -98.875974)
			(xy 152.949965 -98.832678) (xy 152.99326 -98.79516) (xy 153.041453 -98.764186) (xy 153.093565 -98.740386)
			(xy 153.148532 -98.724244) (xy 153.205238 -98.716088) (xy 153.233882 -98.715576) (xy 153.261262 -98.716066)
			(xy 153.315511 -98.72353) (xy 153.368238 -98.738309) (xy 153.418464 -98.760128) (xy 153.465252 -98.78858)
			(xy 153.507732 -98.823135) (xy 153.545114 -98.863151) (xy 153.561288 -98.885248) (xy 153.566866 -98.892495)
			(xy 153.581964 -98.902788) (xy 153.590752 -98.905314) (xy 153.620724 -98.91268) (xy 153.629673 -98.914436)
			(xy 153.647763 -98.912214) (xy 153.65603 -98.908362) (xy 153.680624 -98.895961) (xy 153.732153 -98.876495)
			(xy 153.785644 -98.86335) (xy 153.840325 -98.856716) (xy 153.867866 -98.856292) (xy 153.895407 -98.856705)
			(xy 153.950088 -98.863344) (xy 154.003578 -98.876495) (xy 154.055103 -98.895968) (xy 154.079702 -98.908362)
			(xy 154.087961 -98.91224) (xy 154.106058 -98.914455) (xy 154.115008 -98.91268) (xy 154.14498 -98.905314)
			(xy 154.153762 -98.902772) (xy 154.168864 -98.89249) (xy 154.174444 -98.885248) (xy 154.190596 -98.863131)
			(xy 154.22797 -98.823098) (xy 154.270449 -98.788529) (xy 154.31724 -98.760069) (xy 154.367472 -98.738248)
			(xy 154.420209 -98.723473) (xy 154.474466 -98.716019) (xy 154.50185 -98.715576) (xy 154.530505 -98.715975)
			(xy 154.587233 -98.724125) (xy 154.642224 -98.740266) (xy 154.694358 -98.764069) (xy 154.742573 -98.795049)
			(xy 154.785888 -98.832577) (xy 154.796754 -98.845116) (xy 160.769552 -98.845116) (xy 160.773623 -98.789494)
			(xy 160.785749 -98.735057) (xy 160.805672 -98.682966) (xy 160.832968 -98.634331) (xy 160.867054 -98.590188)
			(xy 160.907203 -98.551479) (xy 160.952561 -98.519028) (xy 161.002161 -98.493527) (xy 161.054945 -98.47552)
			(xy 161.109788 -98.46539) (xy 161.165522 -98.463353) (xy 161.220959 -98.469453) (xy 161.274916 -98.483559)
			(xy 161.326245 -98.505371) (xy 161.373851 -98.534425) (xy 161.416719 -98.5701) (xy 161.453936 -98.611637)
			(xy 161.484709 -98.65815) (xy 161.508381 -98.708647) (xy 161.524449 -98.762054) (xy 161.532569 -98.81723)
			(xy 161.533078 -98.845116) (xy 162.750752 -98.845116) (xy 162.754823 -98.789494) (xy 162.766949 -98.735057)
			(xy 162.786872 -98.682966) (xy 162.814168 -98.634331) (xy 162.848254 -98.590188) (xy 162.888403 -98.551479)
			(xy 162.933761 -98.519028) (xy 162.983361 -98.493527) (xy 163.036145 -98.47552) (xy 163.090988 -98.46539)
			(xy 163.146722 -98.463353) (xy 163.202159 -98.469453) (xy 163.256116 -98.483559) (xy 163.307445 -98.505371)
			(xy 163.355051 -98.534425) (xy 163.397919 -98.5701) (xy 163.435136 -98.611637) (xy 163.465909 -98.65815)
			(xy 163.489581 -98.708647) (xy 163.505649 -98.762054) (xy 163.513769 -98.81723) (xy 163.514278 -98.845116)
			(xy 164.482778 -98.845116) (xy 164.486849 -98.789494) (xy 164.498975 -98.735057) (xy 164.518898 -98.682966)
			(xy 164.546194 -98.634331) (xy 164.58028 -98.590188) (xy 164.620429 -98.551479) (xy 164.665787 -98.519028)
			(xy 164.715387 -98.493527) (xy 164.768171 -98.47552) (xy 164.823014 -98.46539) (xy 164.878748 -98.463353)
			(xy 164.934185 -98.469453) (xy 164.988142 -98.483559) (xy 165.039471 -98.505371) (xy 165.087077 -98.534425)
			(xy 165.129945 -98.5701) (xy 165.167162 -98.611637) (xy 165.197935 -98.65815) (xy 165.221607 -98.708647)
			(xy 165.237675 -98.762054) (xy 165.245795 -98.81723) (xy 165.246304 -98.845116) (xy 167.350946 -98.845116)
			(xy 167.355017 -98.789494) (xy 167.367143 -98.735057) (xy 167.387066 -98.682966) (xy 167.414362 -98.634331)
			(xy 167.448448 -98.590188) (xy 167.488597 -98.551479) (xy 167.533955 -98.519028) (xy 167.583555 -98.493527)
			(xy 167.636339 -98.47552) (xy 167.691182 -98.46539) (xy 167.746916 -98.463353) (xy 167.802353 -98.469453)
			(xy 167.85631 -98.483559) (xy 167.907639 -98.505371) (xy 167.955245 -98.534425) (xy 167.998113 -98.5701)
			(xy 168.03533 -98.611637) (xy 168.066103 -98.65815) (xy 168.089775 -98.708647) (xy 168.105843 -98.762054)
			(xy 168.113963 -98.81723) (xy 168.114472 -98.845116) (xy 168.113963 -98.873002) (xy 168.105843 -98.928178)
			(xy 168.089775 -98.981585) (xy 168.066103 -99.032082) (xy 168.03533 -99.078595) (xy 167.998113 -99.120132)
			(xy 167.955245 -99.155807) (xy 167.907639 -99.184861) (xy 167.85631 -99.206673) (xy 167.802353 -99.220779)
			(xy 167.746916 -99.226879) (xy 167.691182 -99.224842) (xy 167.636339 -99.214712) (xy 167.583555 -99.196705)
			(xy 167.533955 -99.171204) (xy 167.488597 -99.138753) (xy 167.448448 -99.100044) (xy 167.414362 -99.055901)
			(xy 167.387066 -99.007266) (xy 167.367143 -98.955175) (xy 167.355017 -98.900738) (xy 167.350946 -98.845116)
			(xy 165.246304 -98.845116) (xy 165.245795 -98.873002) (xy 165.237675 -98.928178) (xy 165.221607 -98.981585)
			(xy 165.197935 -99.032082) (xy 165.167162 -99.078595) (xy 165.129945 -99.120132) (xy 165.087077 -99.155807)
			(xy 165.039471 -99.184861) (xy 164.988142 -99.206673) (xy 164.934185 -99.220779) (xy 164.878748 -99.226879)
			(xy 164.823014 -99.224842) (xy 164.768171 -99.214712) (xy 164.715387 -99.196705) (xy 164.665787 -99.171204)
			(xy 164.620429 -99.138753) (xy 164.58028 -99.100044) (xy 164.546194 -99.055901) (xy 164.518898 -99.007266)
			(xy 164.498975 -98.955175) (xy 164.486849 -98.900738) (xy 164.482778 -98.845116) (xy 163.514278 -98.845116)
			(xy 163.513769 -98.873002) (xy 163.505649 -98.928178) (xy 163.489581 -98.981585) (xy 163.465909 -99.032082)
			(xy 163.435136 -99.078595) (xy 163.397919 -99.120132) (xy 163.355051 -99.155807) (xy 163.307445 -99.184861)
			(xy 163.256116 -99.206673) (xy 163.202159 -99.220779) (xy 163.146722 -99.226879) (xy 163.090988 -99.224842)
			(xy 163.036145 -99.214712) (xy 162.983361 -99.196705) (xy 162.933761 -99.171204) (xy 162.888403 -99.138753)
			(xy 162.848254 -99.100044) (xy 162.814168 -99.055901) (xy 162.786872 -99.007266) (xy 162.766949 -98.955175)
			(xy 162.754823 -98.900738) (xy 162.750752 -98.845116) (xy 161.533078 -98.845116) (xy 161.532569 -98.873002)
			(xy 161.524449 -98.928178) (xy 161.508381 -98.981585) (xy 161.484709 -99.032082) (xy 161.453936 -99.078595)
			(xy 161.416719 -99.120132) (xy 161.373851 -99.155807) (xy 161.326245 -99.184861) (xy 161.274916 -99.206673)
			(xy 161.220959 -99.220779) (xy 161.165522 -99.226879) (xy 161.109788 -99.224842) (xy 161.054945 -99.214712)
			(xy 161.002161 -99.196705) (xy 160.952561 -99.171204) (xy 160.907203 -99.138753) (xy 160.867054 -99.100044)
			(xy 160.832968 -99.055901) (xy 160.805672 -99.007266) (xy 160.785749 -98.955175) (xy 160.773623 -98.900738)
			(xy 160.769552 -98.845116) (xy 154.796754 -98.845116) (xy 154.823421 -98.875887) (xy 154.854407 -98.924098)
			(xy 154.878217 -98.976229) (xy 154.894364 -99.031218) (xy 154.902521 -99.087945) (xy 154.902521 -99.145255)
			(xy 154.894364 -99.201982) (xy 154.878217 -99.256971) (xy 154.854407 -99.309102) (xy 154.823421 -99.357313)
			(xy 154.785888 -99.400623) (xy 154.742573 -99.438151) (xy 154.694358 -99.469131) (xy 154.642224 -99.492934)
			(xy 154.587233 -99.509075) (xy 154.530505 -99.517225) (xy 154.50185 -99.517708) (xy 154.486932 -99.517539)
			(xy 154.457183 -99.51525) (xy 154.442414 -99.513136) (xy 154.431238 -99.511358) (xy 154.410156 -99.517454)
			(xy 154.343354 -99.575112) (xy 154.335375 -99.582693) (xy 154.326299 -99.602722) (xy 154.325828 -99.61372)
			(xy 154.325828 -99.878388) (xy 154.326331 -99.889377) (xy 154.335407 -99.90939) (xy 154.343354 -99.916996)
			(xy 154.410156 -99.974654) (xy 154.431238 -99.98075) (xy 154.442414 -99.978972) (xy 154.457183 -99.97686)
			(xy 154.486932 -99.974574) (xy 154.50185 -99.9744) (xy 154.5305 -99.974951) (xy 154.587217 -99.983099)
			(xy 154.642198 -99.999237) (xy 154.694321 -100.023035) (xy 154.742527 -100.05401) (xy 154.785834 -100.09153)
			(xy 154.82336 -100.134833) (xy 154.854341 -100.183035) (xy 154.878146 -100.235156) (xy 154.89429 -100.290134)
			(xy 154.902445 -100.34685) (xy 154.902445 -100.40415) (xy 154.89429 -100.460866) (xy 154.878146 -100.515844)
			(xy 154.854341 -100.567965) (xy 154.82336 -100.616167) (xy 154.798408 -100.64496) (xy 160.769552 -100.64496)
			(xy 160.773623 -100.589338) (xy 160.785749 -100.534901) (xy 160.805672 -100.48281) (xy 160.832968 -100.434175)
			(xy 160.867054 -100.390032) (xy 160.907203 -100.351323) (xy 160.952561 -100.318872) (xy 161.002161 -100.293371)
			(xy 161.054945 -100.275364) (xy 161.109788 -100.265234) (xy 161.165522 -100.263197) (xy 161.220959 -100.269297)
			(xy 161.274916 -100.283403) (xy 161.326245 -100.305215) (xy 161.373851 -100.334269) (xy 161.416719 -100.369944)
			(xy 161.453936 -100.411481) (xy 161.484709 -100.457994) (xy 161.508381 -100.508491) (xy 161.524449 -100.561898)
			(xy 161.532569 -100.617074) (xy 161.533078 -100.64496) (xy 162.750752 -100.64496) (xy 162.754823 -100.589338)
			(xy 162.766949 -100.534901) (xy 162.786872 -100.48281) (xy 162.814168 -100.434175) (xy 162.848254 -100.390032)
			(xy 162.888403 -100.351323) (xy 162.933761 -100.318872) (xy 162.983361 -100.293371) (xy 163.036145 -100.275364)
			(xy 163.090988 -100.265234) (xy 163.146722 -100.263197) (xy 163.202159 -100.269297) (xy 163.256116 -100.283403)
			(xy 163.307445 -100.305215) (xy 163.355051 -100.334269) (xy 163.397919 -100.369944) (xy 163.435136 -100.411481)
			(xy 163.465909 -100.457994) (xy 163.489581 -100.508491) (xy 163.505649 -100.561898) (xy 163.513769 -100.617074)
			(xy 163.514278 -100.64496) (xy 164.109398 -100.64496) (xy 164.113469 -100.589338) (xy 164.125595 -100.534901)
			(xy 164.145518 -100.48281) (xy 164.172814 -100.434175) (xy 164.2069 -100.390032) (xy 164.247049 -100.351323)
			(xy 164.292407 -100.318872) (xy 164.342007 -100.293371) (xy 164.394791 -100.275364) (xy 164.449634 -100.265234)
			(xy 164.505368 -100.263197) (xy 164.560805 -100.269297) (xy 164.614762 -100.283403) (xy 164.666091 -100.305215)
			(xy 164.713697 -100.334269) (xy 164.756565 -100.369944) (xy 164.793782 -100.411481) (xy 164.824555 -100.457994)
			(xy 164.848227 -100.508491) (xy 164.864295 -100.561898) (xy 164.872415 -100.617074) (xy 164.872924 -100.64496)
			(xy 164.872415 -100.672846) (xy 164.864295 -100.728022) (xy 164.848227 -100.781429) (xy 164.824555 -100.831926)
			(xy 164.793782 -100.878439) (xy 164.756565 -100.919976) (xy 164.713697 -100.955651) (xy 164.666091 -100.984705)
			(xy 164.614762 -101.006517) (xy 164.560805 -101.020623) (xy 164.505368 -101.026723) (xy 164.449634 -101.024686)
			(xy 164.394791 -101.014556) (xy 164.342007 -100.996549) (xy 164.292407 -100.971048) (xy 164.247049 -100.938597)
			(xy 164.2069 -100.899888) (xy 164.172814 -100.855745) (xy 164.145518 -100.80711) (xy 164.125595 -100.755019)
			(xy 164.113469 -100.700582) (xy 164.109398 -100.64496) (xy 163.514278 -100.64496) (xy 163.513769 -100.672846)
			(xy 163.505649 -100.728022) (xy 163.489581 -100.781429) (xy 163.465909 -100.831926) (xy 163.435136 -100.878439)
			(xy 163.397919 -100.919976) (xy 163.355051 -100.955651) (xy 163.307445 -100.984705) (xy 163.256116 -101.006517)
			(xy 163.202159 -101.020623) (xy 163.146722 -101.026723) (xy 163.090988 -101.024686) (xy 163.036145 -101.014556)
			(xy 162.983361 -100.996549) (xy 162.933761 -100.971048) (xy 162.888403 -100.938597) (xy 162.848254 -100.899888)
			(xy 162.814168 -100.855745) (xy 162.786872 -100.80711) (xy 162.766949 -100.755019) (xy 162.754823 -100.700582)
			(xy 162.750752 -100.64496) (xy 161.533078 -100.64496) (xy 161.532569 -100.672846) (xy 161.524449 -100.728022)
			(xy 161.508381 -100.781429) (xy 161.484709 -100.831926) (xy 161.453936 -100.878439) (xy 161.416719 -100.919976)
			(xy 161.373851 -100.955651) (xy 161.326245 -100.984705) (xy 161.274916 -101.006517) (xy 161.220959 -101.020623)
			(xy 161.165522 -101.026723) (xy 161.109788 -101.024686) (xy 161.054945 -101.014556) (xy 161.002161 -100.996549)
			(xy 160.952561 -100.971048) (xy 160.907203 -100.938597) (xy 160.867054 -100.899888) (xy 160.832968 -100.855745)
			(xy 160.805672 -100.80711) (xy 160.785749 -100.755019) (xy 160.773623 -100.700582) (xy 160.769552 -100.64496)
			(xy 154.798408 -100.64496) (xy 154.785834 -100.65947) (xy 154.742527 -100.69699) (xy 154.694321 -100.727965)
			(xy 154.642198 -100.751763) (xy 154.587217 -100.767901) (xy 154.5305 -100.776049) (xy 154.50185 -100.776532)
			(xy 154.474469 -100.77609) (xy 154.420218 -100.768616) (xy 154.367489 -100.753829) (xy 154.317264 -100.732002)
			(xy 154.270476 -100.703543) (xy 154.227997 -100.668981) (xy 154.190617 -100.628959) (xy 154.174444 -100.60686)
			(xy 154.168888 -100.599593) (xy 154.153775 -100.589311) (xy 154.14498 -100.586794) (xy 154.115008 -100.579428)
			(xy 154.106057 -100.577688) (xy 154.087969 -100.579899) (xy 154.079702 -100.583746) (xy 154.055102 -100.596136)
			(xy 154.003576 -100.615605) (xy 153.950087 -100.628753) (xy 153.895407 -100.63539) (xy 153.867866 -100.635816)
			(xy 153.840325 -100.63539) (xy 153.785645 -100.628754) (xy 153.732155 -100.615607) (xy 153.680629 -100.596138)
			(xy 153.65603 -100.583746) (xy 153.647764 -100.579884) (xy 153.629673 -100.577658) (xy 153.620724 -100.579428)
			(xy 153.590752 -100.586794) (xy 153.581959 -100.589307) (xy 153.566863 -100.59961) (xy 153.561288 -100.60686)
			(xy 153.545118 -100.628964) (xy 153.507747 -100.668997) (xy 153.465272 -100.703566) (xy 153.418483 -100.732028)
			(xy 153.368254 -100.753851) (xy 153.31552 -100.768629) (xy 153.261265 -100.776086) (xy 153.233882 -100.776532)
			(xy 153.205232 -100.776088) (xy 153.148516 -100.767931) (xy 153.093538 -100.751786) (xy 153.041417 -100.727981)
			(xy 152.993214 -100.697001) (xy 152.949911 -100.659477) (xy 152.912388 -100.616171) (xy 152.88141 -100.567967)
			(xy 152.857608 -100.515845) (xy 152.841465 -100.460866) (xy 152.833311 -100.40415) (xy 119.919628 -100.40415)
			(xy 119.915323 -100.413334) (xy 119.88455 -100.459847) (xy 119.847333 -100.501384) (xy 119.804465 -100.537059)
			(xy 119.756859 -100.566113) (xy 119.70553 -100.587925) (xy 119.651573 -100.602031) (xy 119.596136 -100.608131)
			(xy 119.540402 -100.606094) (xy 119.485559 -100.595964) (xy 119.432775 -100.577957) (xy 119.383175 -100.552456)
			(xy 119.337817 -100.520005) (xy 119.297668 -100.481296) (xy 119.263582 -100.437153) (xy 119.236286 -100.388518)
			(xy 119.216363 -100.336427) (xy 119.204237 -100.28199) (xy 119.200166 -100.226368) (xy 96.098643 -100.226368)
			(xy 96.112779 -100.256523) (xy 96.128847 -100.30993) (xy 96.136967 -100.365106) (xy 96.137476 -100.392992)
			(xy 96.136967 -100.420878) (xy 96.128847 -100.476054) (xy 96.112779 -100.529461) (xy 96.089107 -100.579958)
			(xy 96.058334 -100.626471) (xy 96.021117 -100.668008) (xy 95.978249 -100.703683) (xy 95.930643 -100.732737)
			(xy 95.879314 -100.754549) (xy 95.825357 -100.768655) (xy 95.76992 -100.774755) (xy 95.714186 -100.772718)
			(xy 95.659343 -100.762588) (xy 95.606559 -100.744581) (xy 95.556959 -100.71908) (xy 95.511601 -100.686629)
			(xy 95.471452 -100.64792) (xy 95.437366 -100.603777) (xy 95.41007 -100.555142) (xy 95.390147 -100.503051)
			(xy 95.378021 -100.448614) (xy 95.37395 -100.392992) (xy 91.5035 -100.392992) (xy 91.5035 -100.422202)
			(xy 91.504008 -100.42906) (xy 91.506313 -100.44034) (xy 91.51941 -100.459249) (xy 91.529154 -100.465382)
			(xy 91.578684 -100.489512) (xy 91.616784 -100.508054) (xy 91.622663 -100.510344) (xy 91.635127 -100.512282)
			(xy 91.641422 -100.511864) (xy 91.648026 -100.511356) (xy 91.661234 -100.506276) (xy 91.66733 -100.50145)
			(xy 91.687416 -100.486516) (xy 91.730755 -100.461472) (xy 91.776994 -100.442307) (xy 91.825341 -100.429349)
			(xy 91.874967 -100.42282) (xy 91.899994 -100.422456) (xy 91.907106 -100.422456) (xy 91.934022 -100.423421)
			(xy 91.987194 -100.43199) (xy 92.038632 -100.447954) (xy 92.087313 -100.470995) (xy 92.132268 -100.500655)
			(xy 92.172604 -100.536344) (xy 92.207518 -100.577353) (xy 92.236315 -100.622865) (xy 92.258424 -100.671976)
			(xy 92.273404 -100.723709) (xy 92.280958 -100.777035) (xy 92.281502 -100.803964) (xy 92.281041 -100.831218)
			(xy 92.273288 -100.885173) (xy 92.257935 -100.937475) (xy 92.235295 -100.987059) (xy 92.205828 -101.032916)
			(xy 92.170134 -101.074113) (xy 92.12894 -101.10981) (xy 92.083085 -101.13928) (xy 92.033503 -101.161925)
			(xy 91.981202 -101.177282) (xy 91.927248 -101.185039) (xy 91.899994 -101.185472) (xy 91.89974 -101.185472)
			(xy 91.874706 -101.185057) (xy 91.825073 -101.178474) (xy 91.776724 -101.165468) (xy 91.730487 -101.146261)
			(xy 91.687153 -101.121183) (xy 91.667076 -101.106224) (xy 91.657424 -101.098858) (xy 91.655392 -101.097334)
			(xy 91.641422 -101.096064) (xy 91.634431 -101.095578) (xy 91.620635 -101.098017) (xy 91.614244 -101.10089)
			(xy 91.564206 -101.125274) (xy 91.528646 -101.1428) (xy 91.51917 -101.149046) (xy 91.506396 -101.167771)
			(xy 91.504008 -101.178868) (xy 91.5035 -101.185726) (xy 91.5035 -101.189848) (xy 96.99349 -101.189848)
			(xy 96.99349 -101.135352) (xy 97.001245 -101.08141) (xy 97.016598 -101.02912) (xy 97.039235 -100.979547)
			(xy 97.068696 -100.933701) (xy 97.104382 -100.892513) (xy 97.145565 -100.856822) (xy 97.191409 -100.827356)
			(xy 97.240979 -100.804713) (xy 97.293266 -100.789355) (xy 97.347208 -100.781593) (xy 97.374456 -100.781104)
			(xy 97.401825 -100.781595) (xy 97.456003 -100.789407) (xy 97.508506 -100.80489) (xy 97.558254 -100.827726)
			(xy 97.604221 -100.857445) (xy 97.625154 -100.875084) (xy 97.625408 -100.875338) (xy 97.632485 -100.880938)
			(xy 97.649409 -100.887176) (xy 97.658428 -100.88753) (xy 97.725484 -100.88753) (xy 97.734499 -100.887159)
			(xy 97.751416 -100.88092) (xy 97.758504 -100.875338) (xy 97.758504 -100.875084) (xy 97.758758 -100.875084)
			(xy 97.779693 -100.857449) (xy 97.825665 -100.827737) (xy 97.875412 -100.8049) (xy 97.927912 -100.789408)
			(xy 97.982087 -100.781579) (xy 98.009456 -100.781104) (xy 98.036712 -100.78154) (xy 98.090669 -100.789292)
			(xy 98.142974 -100.804645) (xy 98.192561 -100.827285) (xy 98.238422 -100.856753) (xy 98.279621 -100.892448)
			(xy 98.31532 -100.933643) (xy 98.344793 -100.9795) (xy 98.36744 -101.029085) (xy 98.382799 -101.081388)
			(xy 98.390557 -101.135344) (xy 98.390557 -101.189856) (xy 98.382799 -101.243812) (xy 98.36744 -101.296115)
			(xy 98.350572 -101.333046) (xy 99.933758 -101.333046) (xy 99.937829 -101.277424) (xy 99.949955 -101.222987)
			(xy 99.969878 -101.170896) (xy 99.997174 -101.122261) (xy 100.03126 -101.078118) (xy 100.071409 -101.039409)
			(xy 100.116767 -101.006958) (xy 100.166367 -100.981457) (xy 100.219151 -100.96345) (xy 100.273994 -100.95332)
			(xy 100.329728 -100.951283) (xy 100.385165 -100.957383) (xy 100.439122 -100.971489) (xy 100.490451 -100.993301)
			(xy 100.538057 -101.022355) (xy 100.580925 -101.05803) (xy 100.618142 -101.099567) (xy 100.648915 -101.14608)
			(xy 100.672587 -101.196577) (xy 100.688655 -101.249984) (xy 100.696775 -101.30516) (xy 100.697284 -101.333046)
			(xy 100.696775 -101.360932) (xy 100.688655 -101.416108) (xy 100.672587 -101.469515) (xy 100.648915 -101.520012)
			(xy 100.618142 -101.566525) (xy 100.580925 -101.608062) (xy 100.538057 -101.643737) (xy 100.490451 -101.672791)
			(xy 100.439122 -101.694603) (xy 100.385165 -101.708709) (xy 100.329728 -101.714809) (xy 100.273994 -101.712772)
			(xy 100.219151 -101.702642) (xy 100.166367 -101.684635) (xy 100.116767 -101.659134) (xy 100.071409 -101.626683)
			(xy 100.03126 -101.587974) (xy 99.997174 -101.543831) (xy 99.969878 -101.495196) (xy 99.949955 -101.443105)
			(xy 99.937829 -101.388668) (xy 99.933758 -101.333046) (xy 98.350572 -101.333046) (xy 98.344793 -101.3457)
			(xy 98.31532 -101.391557) (xy 98.279621 -101.432752) (xy 98.238422 -101.468447) (xy 98.192561 -101.497915)
			(xy 98.142974 -101.520555) (xy 98.090669 -101.535908) (xy 98.036712 -101.54366) (xy 98.009456 -101.54412)
			(xy 97.982086 -101.543641) (xy 97.927907 -101.535829) (xy 97.875403 -101.520344) (xy 97.825656 -101.497505)
			(xy 97.779689 -101.467781) (xy 97.758758 -101.45014) (xy 97.758504 -101.449886) (xy 97.751422 -101.444293)
			(xy 97.734502 -101.438051) (xy 97.725484 -101.437694) (xy 97.658428 -101.437694) (xy 97.649413 -101.438066)
			(xy 97.632496 -101.444303) (xy 97.625408 -101.449886) (xy 97.625408 -101.45014) (xy 97.625154 -101.45014)
			(xy 97.604218 -101.467774) (xy 97.558246 -101.497485) (xy 97.508499 -101.520322) (xy 97.455999 -101.535814)
			(xy 97.401825 -101.543645) (xy 97.374456 -101.54412) (xy 97.347208 -101.543607) (xy 97.293266 -101.535845)
			(xy 97.240979 -101.520487) (xy 97.191409 -101.497844) (xy 97.145565 -101.468378) (xy 97.104382 -101.432687)
			(xy 97.068696 -101.391499) (xy 97.039235 -101.345653) (xy 97.016598 -101.29608) (xy 97.001245 -101.24379)
			(xy 96.99349 -101.189848) (xy 91.5035 -101.189848) (xy 91.5035 -101.868478) (xy 91.503691 -101.870764)
			(xy 93.23908 -101.870764) (xy 93.243151 -101.815142) (xy 93.255277 -101.760705) (xy 93.2752 -101.708614)
			(xy 93.302496 -101.659979) (xy 93.336582 -101.615836) (xy 93.376731 -101.577127) (xy 93.422089 -101.544676)
			(xy 93.471689 -101.519175) (xy 93.524473 -101.501168) (xy 93.579316 -101.491038) (xy 93.63505 -101.489001)
			(xy 93.690487 -101.495101) (xy 93.744444 -101.509207) (xy 93.795773 -101.531019) (xy 93.843379 -101.560073)
			(xy 93.886247 -101.595748) (xy 93.923464 -101.637285) (xy 93.954237 -101.683798) (xy 93.977909 -101.734295)
			(xy 93.993977 -101.787702) (xy 94.002097 -101.842878) (xy 94.002606 -101.870764) (xy 94.002097 -101.89865)
			(xy 93.993977 -101.953826) (xy 93.977909 -102.007233) (xy 93.954237 -102.05773) (xy 93.923464 -102.104243)
			(xy 93.899978 -102.130455) (xy 96.543029 -102.130455) (xy 96.543029 -102.075945) (xy 96.550787 -102.021989)
			(xy 96.566145 -101.969686) (xy 96.58879 -101.920102) (xy 96.618261 -101.874245) (xy 96.653959 -101.833049)
			(xy 96.695156 -101.797353) (xy 96.741014 -101.767883) (xy 96.790599 -101.74524) (xy 96.842902 -101.729884)
			(xy 96.896859 -101.722128) (xy 96.924114 -101.721666) (xy 96.951485 -101.722108) (xy 97.005666 -101.729929)
			(xy 97.05817 -101.745423) (xy 97.107917 -101.76827) (xy 97.153882 -101.798001) (xy 97.174812 -101.815646)
			(xy 97.175066 -101.8159) (xy 97.182158 -101.821478) (xy 97.199071 -101.82773) (xy 97.208086 -101.828092)
			(xy 97.275142 -101.828092) (xy 97.284156 -101.827709) (xy 97.301073 -101.82148) (xy 97.308162 -101.8159)
			(xy 97.308162 -101.815646) (xy 97.308416 -101.815646) (xy 97.329375 -101.79804) (xy 97.37534 -101.768322)
			(xy 97.42508 -101.745479) (xy 97.477575 -101.72998) (xy 97.531747 -101.722144) (xy 97.559114 -101.721666)
			(xy 97.586363 -101.722205) (xy 97.640305 -101.729963) (xy 97.692595 -101.745318) (xy 97.742167 -101.767958)
			(xy 97.788012 -101.797423) (xy 97.829198 -101.833112) (xy 97.864885 -101.874299) (xy 97.894348 -101.920146)
			(xy 97.916987 -101.969719) (xy 97.93234 -102.022009) (xy 97.940096 -102.075951) (xy 97.940096 -102.095046)
			(xy 99.298758 -102.095046) (xy 99.302829 -102.039424) (xy 99.314955 -101.984987) (xy 99.334878 -101.932896)
			(xy 99.362174 -101.884261) (xy 99.39626 -101.840118) (xy 99.436409 -101.801409) (xy 99.481767 -101.768958)
			(xy 99.531367 -101.743457) (xy 99.584151 -101.72545) (xy 99.638994 -101.71532) (xy 99.694728 -101.713283)
			(xy 99.750165 -101.719383) (xy 99.804122 -101.733489) (xy 99.855451 -101.755301) (xy 99.903057 -101.784355)
			(xy 99.945925 -101.82003) (xy 99.983142 -101.861567) (xy 100.013915 -101.90808) (xy 100.037587 -101.958577)
			(xy 100.053655 -102.011984) (xy 100.061775 -102.06716) (xy 100.062284 -102.095046) (xy 100.061775 -102.122932)
			(xy 100.053655 -102.178108) (xy 100.037587 -102.231515) (xy 100.013915 -102.282012) (xy 100.003104 -102.298352)
			(xy 101.096546 -102.298352) (xy 101.096546 -102.243848) (xy 101.104302 -102.189898) (xy 101.119657 -102.137601)
			(xy 101.142298 -102.088022) (xy 101.171764 -102.042169) (xy 101.207456 -102.000976) (xy 101.248646 -101.965281)
			(xy 101.294497 -101.935812) (xy 101.344075 -101.913167) (xy 101.396371 -101.897808) (xy 101.45032 -101.890048)
			(xy 101.477572 -101.88956) (xy 101.504942 -101.890028) (xy 101.559122 -101.897843) (xy 101.611626 -101.913331)
			(xy 101.661373 -101.936173) (xy 101.707339 -101.965898) (xy 101.72827 -101.98354) (xy 101.728524 -101.983794)
			(xy 101.7356 -101.989396) (xy 101.752525 -101.995634) (xy 101.761544 -101.995986) (xy 101.8286 -101.995986)
			(xy 101.837617 -101.995632) (xy 101.854534 -101.989383) (xy 101.86162 -101.983794) (xy 101.86162 -101.98354)
			(xy 101.861874 -101.98354) (xy 101.88281 -101.965906) (xy 101.928781 -101.936192) (xy 101.978528 -101.913354)
			(xy 102.031028 -101.897862) (xy 102.085203 -101.890034) (xy 102.112572 -101.88956) (xy 102.139824 -101.890085)
			(xy 102.193773 -101.897838) (xy 102.24607 -101.913191) (xy 102.29565 -101.93583) (xy 102.341502 -101.965295)
			(xy 102.382695 -102.000985) (xy 102.400814 -102.021894) (xy 102.956614 -102.021894) (xy 102.957073 -101.994523)
			(xy 102.964892 -101.940344) (xy 102.980383 -101.887841) (xy 103.003226 -101.838094) (xy 103.032952 -101.792127)
			(xy 103.050594 -101.771196) (xy 103.050848 -101.770942) (xy 103.056429 -101.763852) (xy 103.062678 -101.746938)
			(xy 103.06304 -101.737922) (xy 103.06304 -101.670866) (xy 103.062712 -101.661846) (xy 103.056446 -101.644928)
			(xy 103.050848 -101.637846) (xy 103.050594 -101.637846) (xy 103.050594 -101.637592) (xy 103.032949 -101.616663)
			(xy 103.003227 -101.570694) (xy 102.980384 -101.520947) (xy 102.964889 -101.468445) (xy 102.957062 -101.414266)
			(xy 102.957063 -101.359525) (xy 102.964891 -101.305347) (xy 102.980387 -101.252845) (xy 103.003231 -101.203098)
			(xy 103.032954 -101.157129) (xy 103.050594 -101.136196) (xy 103.050848 -101.135942) (xy 103.056429 -101.128852)
			(xy 103.062678 -101.111938) (xy 103.06304 -101.102922) (xy 103.06304 -101.035866) (xy 103.062712 -101.026846)
			(xy 103.056446 -101.009928) (xy 103.050848 -101.002846) (xy 103.050594 -101.002846) (xy 103.050594 -101.002592)
			(xy 103.032937 -100.981675) (xy 103.003228 -100.935698) (xy 102.980396 -100.885946) (xy 102.964909 -100.833443)
			(xy 102.957085 -100.779264) (xy 102.956614 -100.751894) (xy 102.9571 -100.724643) (xy 102.964856 -100.670695)
			(xy 102.980211 -100.6184) (xy 103.002853 -100.568823) (xy 103.032319 -100.522973) (xy 103.06801 -100.481782)
			(xy 103.109201 -100.446091) (xy 103.155051 -100.416625) (xy 103.204628 -100.393983) (xy 103.256923 -100.378628)
			(xy 103.310871 -100.370872) (xy 103.365373 -100.370872) (xy 103.419321 -100.378628) (xy 103.471616 -100.393983)
			(xy 103.521193 -100.416625) (xy 103.567043 -100.446091) (xy 103.608234 -100.481782) (xy 103.643925 -100.522973)
			(xy 103.673391 -100.568823) (xy 103.696033 -100.6184) (xy 103.711388 -100.670695) (xy 103.719144 -100.724643)
			(xy 103.71963 -100.751894) (xy 103.719177 -100.779265) (xy 103.711359 -100.833445) (xy 103.695868 -100.885949)
			(xy 103.673023 -100.935696) (xy 103.643294 -100.981661) (xy 103.62565 -101.002592) (xy 103.625396 -101.002846)
			(xy 103.619825 -101.009944) (xy 103.613569 -101.026852) (xy 103.613204 -101.035866) (xy 103.613204 -101.102922)
			(xy 103.61355 -101.11194) (xy 103.619805 -101.128857) (xy 103.625396 -101.135942) (xy 103.62565 -101.135942)
			(xy 103.62565 -101.136196) (xy 103.643286 -101.157133) (xy 103.673013 -101.2031) (xy 103.69586 -101.252845)
			(xy 103.711357 -101.305347) (xy 103.719187 -101.359525) (xy 103.719188 -101.414266) (xy 103.711359 -101.468445)
			(xy 103.695863 -101.520947) (xy 103.673017 -101.570693) (xy 103.643291 -101.61666) (xy 103.62565 -101.637592)
			(xy 103.625396 -101.637846) (xy 103.619825 -101.644944) (xy 103.613569 -101.661852) (xy 103.613204 -101.670866)
			(xy 103.613204 -101.737922) (xy 103.61355 -101.74694) (xy 103.619805 -101.763857) (xy 103.625396 -101.770942)
			(xy 103.62565 -101.770942) (xy 103.62565 -101.771196) (xy 103.643293 -101.792125) (xy 103.673006 -101.838098)
			(xy 103.695842 -101.887846) (xy 103.711332 -101.940348) (xy 103.719158 -101.994524) (xy 103.71963 -102.021894)
			(xy 106.012996 -102.021894) (xy 106.01346 -101.994524) (xy 106.021278 -101.940345) (xy 106.036768 -101.887841)
			(xy 106.05961 -101.838095) (xy 106.089335 -101.792128) (xy 106.106976 -101.771196) (xy 106.10723 -101.770942)
			(xy 106.112808 -101.76385) (xy 106.119059 -101.746937) (xy 106.119422 -101.737922) (xy 106.119422 -101.670866)
			(xy 106.119077 -101.661848) (xy 106.112821 -101.644931) (xy 106.10723 -101.637846) (xy 106.106976 -101.637846)
			(xy 106.106976 -101.637592) (xy 106.089327 -101.616665) (xy 106.059599 -101.570697) (xy 106.036751 -101.520951)
			(xy 106.021253 -101.468447) (xy 106.013424 -101.414267) (xy 106.013425 -101.359524) (xy 106.021255 -101.305344)
			(xy 106.036754 -101.252841) (xy 106.059603 -101.203095) (xy 106.089333 -101.157128) (xy 106.106976 -101.136196)
			(xy 106.10723 -101.135942) (xy 106.112808 -101.12885) (xy 106.119059 -101.111937) (xy 106.119422 -101.102922)
			(xy 106.119422 -101.035866) (xy 106.119077 -101.026848) (xy 106.112821 -101.009931) (xy 106.10723 -101.002846)
			(xy 106.106976 -101.002846) (xy 106.106976 -101.002592) (xy 106.089316 -100.981677) (xy 106.059608 -100.935699)
			(xy 106.036777 -100.885947) (xy 106.02129 -100.833443) (xy 106.013467 -100.779264) (xy 106.012996 -100.751894)
			(xy 106.013482 -100.724643) (xy 106.021238 -100.670695) (xy 106.036593 -100.6184) (xy 106.059235 -100.568823)
			(xy 106.088701 -100.522973) (xy 106.124392 -100.481782) (xy 106.165583 -100.446091) (xy 106.211433 -100.416625)
			(xy 106.26101 -100.393983) (xy 106.313305 -100.378628) (xy 106.367253 -100.370872) (xy 106.421755 -100.370872)
			(xy 106.475703 -100.378628) (xy 106.527998 -100.393983) (xy 106.577575 -100.416625) (xy 106.623425 -100.446091)
			(xy 106.664616 -100.481782) (xy 106.700307 -100.522973) (xy 106.729773 -100.568823) (xy 106.752415 -100.6184)
			(xy 106.76777 -100.670695) (xy 106.775526 -100.724643) (xy 106.776012 -100.751894) (xy 106.775539 -100.779264)
			(xy 106.767723 -100.833443) (xy 106.752235 -100.885946) (xy 106.729395 -100.935693) (xy 106.699672 -100.98166)
			(xy 106.682032 -101.002592) (xy 106.681778 -101.002846) (xy 106.679734 -101.005449) (xy 134.744986 -101.005449)
			(xy 134.744986 -100.950951) (xy 134.752741 -100.897007) (xy 134.768094 -100.844716) (xy 134.790733 -100.795142)
			(xy 134.820195 -100.749294) (xy 134.855883 -100.708105) (xy 134.897068 -100.672415) (xy 134.942914 -100.642948)
			(xy 134.992486 -100.620306) (xy 135.044776 -100.604948) (xy 135.098719 -100.597188) (xy 135.125968 -100.5967)
			(xy 135.152571 -100.597173) (xy 135.205263 -100.60455) (xy 135.256418 -100.619181) (xy 135.305043 -100.640779)
			(xy 135.350194 -100.668927) (xy 135.390994 -100.703077) (xy 135.42665 -100.742568) (xy 135.441944 -100.76434)
			(xy 135.450278 -100.77582) (xy 135.472022 -100.794024) (xy 135.497935 -100.805542) (xy 135.526018 -100.809482)
			(xy 135.554101 -100.805542) (xy 135.580014 -100.794024) (xy 135.601758 -100.77582) (xy 135.610092 -100.76434)
			(xy 135.62538 -100.742565) (xy 135.661047 -100.703086) (xy 135.701852 -100.668943) (xy 135.747003 -100.640798)
			(xy 135.795626 -100.619196) (xy 135.846777 -100.604557) (xy 135.899466 -100.597163) (xy 135.926068 -100.5967)
			(xy 135.953323 -100.597145) (xy 136.007278 -100.604899) (xy 136.059581 -100.620252) (xy 136.109166 -100.642893)
			(xy 136.155024 -100.672361) (xy 136.196222 -100.708055) (xy 136.23192 -100.74925) (xy 136.261391 -100.795105)
			(xy 136.284037 -100.844689) (xy 136.299395 -100.89699) (xy 136.307153 -100.950945) (xy 136.307153 -100.951748)
			(xy 150.800835 -100.951748) (xy 150.800835 -100.894452) (xy 150.808988 -100.83774) (xy 150.82513 -100.782765)
			(xy 150.84893 -100.730646) (xy 150.879905 -100.682446) (xy 150.917425 -100.639143) (xy 150.960725 -100.601621)
			(xy 151.008924 -100.570643) (xy 151.06104 -100.546839) (xy 151.116014 -100.530694) (xy 151.172726 -100.522536)
			(xy 151.201374 -100.522024) (xy 151.228753 -100.522542) (xy 151.282999 -100.530004) (xy 151.335726 -100.54478)
			(xy 151.38595 -100.566594) (xy 151.432739 -100.595041) (xy 151.47522 -100.629592) (xy 151.512604 -100.669602)
			(xy 151.52878 -100.691696) (xy 151.534351 -100.698949) (xy 151.549454 -100.709237) (xy 151.558244 -100.711762)
			(xy 151.588216 -100.719128) (xy 151.597165 -100.720885) (xy 151.615256 -100.718664) (xy 151.623522 -100.71481)
			(xy 151.64812 -100.702415) (xy 151.699646 -100.682947) (xy 151.753136 -100.6698) (xy 151.807817 -100.663164)
			(xy 151.835358 -100.66274) (xy 151.862899 -100.663162) (xy 151.917579 -100.6698) (xy 151.971069 -100.682948)
			(xy 152.022595 -100.702418) (xy 152.047194 -100.71481) (xy 152.055454 -100.718685) (xy 152.07355 -100.720901)
			(xy 152.0825 -100.719128) (xy 152.112472 -100.711762) (xy 152.121248 -100.709202) (xy 152.136351 -100.698932)
			(xy 152.141936 -100.691696) (xy 152.158078 -100.669571) (xy 152.195455 -100.629541) (xy 152.237936 -100.594974)
			(xy 152.28473 -100.566516) (xy 152.334963 -100.544696) (xy 152.3877 -100.529922) (xy 152.441958 -100.522468)
			(xy 152.469342 -100.522024) (xy 152.497988 -100.522558) (xy 152.554695 -100.530717) (xy 152.609664 -100.546862)
			(xy 152.661776 -100.570666) (xy 152.709971 -100.601643) (xy 152.753266 -100.639163) (xy 152.790782 -100.682463)
			(xy 152.821754 -100.730661) (xy 152.845552 -100.782775) (xy 152.861692 -100.837746) (xy 152.869845 -100.894454)
			(xy 152.869845 -100.951746) (xy 152.861692 -101.008454) (xy 152.845552 -101.063425) (xy 152.821754 -101.115539)
			(xy 152.790782 -101.163737) (xy 152.753266 -101.207037) (xy 152.709971 -101.244557) (xy 152.661776 -101.275534)
			(xy 152.609664 -101.299338) (xy 152.554695 -101.315483) (xy 152.497988 -101.323642) (xy 152.469342 -101.324156)
			(xy 152.454424 -101.323988) (xy 152.424675 -101.321698) (xy 152.409906 -101.319584) (xy 152.39873 -101.317806)
			(xy 152.377648 -101.323902) (xy 152.310846 -101.38156) (xy 152.302889 -101.389161) (xy 152.293801 -101.409175)
			(xy 152.29332 -101.420168) (xy 152.29332 -101.684836) (xy 152.293799 -101.695828) (xy 152.302892 -101.715841)
			(xy 152.310846 -101.723444) (xy 152.377648 -101.781102) (xy 152.39873 -101.787198) (xy 152.409906 -101.78542)
			(xy 152.424675 -101.783309) (xy 152.454424 -101.781022) (xy 152.469342 -101.780848) (xy 152.497989 -101.781334)
			(xy 152.5547 -101.789493) (xy 152.609673 -101.805639) (xy 152.661788 -101.829444) (xy 152.709985 -101.860424)
			(xy 152.753284 -101.897946) (xy 152.790802 -101.941248) (xy 152.821776 -101.989449) (xy 152.845575 -102.041567)
			(xy 152.861716 -102.096541) (xy 152.869869 -102.153253) (xy 152.869869 -102.210547) (xy 152.861716 -102.267259)
			(xy 152.845575 -102.322233) (xy 152.821776 -102.374351) (xy 152.790802 -102.422552) (xy 152.753284 -102.465854)
			(xy 152.709985 -102.503376) (xy 152.661788 -102.534356) (xy 152.609673 -102.558161) (xy 152.5547 -102.574307)
			(xy 152.497989 -102.582466) (xy 152.469342 -102.58298) (xy 152.441961 -102.582524) (xy 152.387712 -102.57505)
			(xy 152.334985 -102.560263) (xy 152.28476 -102.538439) (xy 152.237972 -102.509982) (xy 152.195493 -102.475424)
			(xy 152.158111 -102.435406) (xy 152.141936 -102.413308) (xy 152.136358 -102.406061) (xy 152.12126 -102.395769)
			(xy 152.112472 -102.393242) (xy 152.0825 -102.385876) (xy 152.07355 -102.384127) (xy 152.055461 -102.386343)
			(xy 152.047194 -102.390194) (xy 152.022594 -102.402583) (xy 151.971068 -102.422053) (xy 151.917579 -102.435201)
			(xy 151.862899 -102.441839) (xy 151.835358 -102.442264) (xy 151.807817 -102.441835) (xy 151.753137 -102.4352)
			(xy 151.699648 -102.422053) (xy 151.648121 -102.402585) (xy 151.623522 -102.390194) (xy 151.615259 -102.386327)
			(xy 151.597165 -102.384106) (xy 151.588216 -102.385876) (xy 151.558244 -102.393242) (xy 151.549456 -102.395768)
			(xy 151.534359 -102.406062) (xy 151.52878 -102.413308) (xy 151.512629 -102.435426) (xy 151.475254 -102.475457)
			(xy 151.432774 -102.510023) (xy 151.385982 -102.538483) (xy 151.33575 -102.560303) (xy 151.283014 -102.575079)
			(xy 151.228757 -102.582535) (xy 151.201374 -102.58298) (xy 151.172728 -102.582439) (xy 151.116019 -102.574282)
			(xy 151.061049 -102.558138) (xy 151.008935 -102.534336) (xy 150.960739 -102.503359) (xy 150.917442 -102.465839)
			(xy 150.879925 -102.42254) (xy 150.848952 -102.374342) (xy 150.825153 -102.322227) (xy 150.809012 -102.267255)
			(xy 150.800859 -102.210546) (xy 150.800859 -102.153254) (xy 150.809012 -102.096545) (xy 150.825153 -102.041573)
			(xy 150.848952 -101.989458) (xy 150.879925 -101.94126) (xy 150.917442 -101.897961) (xy 150.960739 -101.860441)
			(xy 151.008935 -101.829464) (xy 151.061049 -101.805662) (xy 151.116019 -101.789518) (xy 151.172728 -101.781361)
			(xy 151.201374 -101.780848) (xy 151.216292 -101.781014) (xy 151.246041 -101.783305) (xy 151.26081 -101.78542)
			(xy 151.271986 -101.787198) (xy 151.293068 -101.781102) (xy 151.35987 -101.723444) (xy 151.367828 -101.715844)
			(xy 151.376915 -101.695829) (xy 151.377396 -101.684836) (xy 151.377396 -101.420168) (xy 151.376909 -101.409177)
			(xy 151.367821 -101.389165) (xy 151.35987 -101.38156) (xy 151.293068 -101.323902) (xy 151.271986 -101.317806)
			(xy 151.26081 -101.319584) (xy 151.246041 -101.321694) (xy 151.216292 -101.323981) (xy 151.201374 -101.324156)
			(xy 151.172726 -101.323664) (xy 151.116014 -101.315506) (xy 151.06104 -101.299361) (xy 151.008924 -101.275557)
			(xy 150.960725 -101.244579) (xy 150.917425 -101.207057) (xy 150.879905 -101.163754) (xy 150.84893 -101.115554)
			(xy 150.82513 -101.063435) (xy 150.808988 -101.00846) (xy 150.800835 -100.951748) (xy 136.307153 -100.951748)
			(xy 136.307153 -101.005455) (xy 136.299395 -101.05941) (xy 136.284037 -101.111711) (xy 136.261391 -101.161295)
			(xy 136.23192 -101.20715) (xy 136.196222 -101.248345) (xy 136.155024 -101.284039) (xy 136.109166 -101.313507)
			(xy 136.059581 -101.336148) (xy 136.007278 -101.351501) (xy 135.953323 -101.359255) (xy 135.926068 -101.359716)
			(xy 135.899466 -101.359209) (xy 135.846776 -101.351836) (xy 135.795622 -101.337212) (xy 135.746997 -101.315619)
			(xy 135.701846 -101.287476) (xy 135.661045 -101.253331) (xy 135.625387 -101.213846) (xy 135.610092 -101.192076)
			(xy 135.601758 -101.180596) (xy 135.580014 -101.162392) (xy 135.554101 -101.150874) (xy 135.526018 -101.146934)
			(xy 135.497935 -101.150874) (xy 135.472022 -101.162392) (xy 135.450278 -101.180596) (xy 135.441944 -101.192076)
			(xy 135.426638 -101.213838) (xy 135.390973 -101.253317) (xy 135.350171 -101.28746) (xy 135.305023 -101.315606)
			(xy 135.256404 -101.33721) (xy 135.205256 -101.351853) (xy 135.152569 -101.35925) (xy 135.125968 -101.359716)
			(xy 135.098719 -101.359212) (xy 135.044776 -101.351452) (xy 134.992486 -101.336094) (xy 134.942914 -101.313452)
			(xy 134.897068 -101.283985) (xy 134.855883 -101.248295) (xy 134.820195 -101.207106) (xy 134.790733 -101.161258)
			(xy 134.768094 -101.111684) (xy 134.752741 -101.059393) (xy 134.744986 -101.005449) (xy 106.679734 -101.005449)
			(xy 106.676205 -101.009942) (xy 106.669951 -101.026852) (xy 106.669586 -101.035866) (xy 106.669586 -101.102922)
			(xy 106.669936 -101.11194) (xy 106.676189 -101.128856) (xy 106.681778 -101.135942) (xy 106.682032 -101.135942)
			(xy 106.682032 -101.136196) (xy 106.699669 -101.157133) (xy 106.729397 -101.203099) (xy 106.752245 -101.252844)
			(xy 106.767743 -101.305346) (xy 106.775573 -101.359525) (xy 106.775574 -101.414266) (xy 106.767745 -101.468445)
			(xy 106.752248 -101.520947) (xy 106.729401 -101.570693) (xy 106.699674 -101.61666) (xy 106.682032 -101.637592)
			(xy 106.681778 -101.637846) (xy 106.676205 -101.644942) (xy 106.669951 -101.661852) (xy 106.669586 -101.670866)
			(xy 106.669586 -101.737922) (xy 106.669936 -101.74694) (xy 106.676189 -101.763856) (xy 106.681778 -101.770942)
			(xy 106.682032 -101.770942) (xy 106.682032 -101.771196) (xy 106.699688 -101.792115) (xy 106.729396 -101.838092)
			(xy 106.752228 -101.887843) (xy 106.767715 -101.940346) (xy 106.77554 -101.994524) (xy 106.776012 -102.021894)
			(xy 106.775526 -102.049145) (xy 106.76777 -102.103093) (xy 106.752415 -102.155388) (xy 106.729773 -102.204965)
			(xy 106.700307 -102.250815) (xy 106.664616 -102.292006) (xy 106.623425 -102.327697) (xy 106.577575 -102.357163)
			(xy 106.527998 -102.379805) (xy 106.475703 -102.39516) (xy 106.421755 -102.402916) (xy 106.367253 -102.402916)
			(xy 106.313305 -102.39516) (xy 106.26101 -102.379805) (xy 106.211433 -102.357163) (xy 106.165583 -102.327697)
			(xy 106.124392 -102.292006) (xy 106.088701 -102.250815) (xy 106.059235 -102.204965) (xy 106.036593 -102.155388)
			(xy 106.021238 -102.103093) (xy 106.013482 -102.049145) (xy 106.012996 -102.021894) (xy 103.71963 -102.021894)
			(xy 103.719144 -102.049145) (xy 103.711388 -102.103093) (xy 103.696033 -102.155388) (xy 103.673391 -102.204965)
			(xy 103.643925 -102.250815) (xy 103.608234 -102.292006) (xy 103.567043 -102.327697) (xy 103.521193 -102.357163)
			(xy 103.471616 -102.379805) (xy 103.419321 -102.39516) (xy 103.365373 -102.402916) (xy 103.310871 -102.402916)
			(xy 103.256923 -102.39516) (xy 103.204628 -102.379805) (xy 103.155051 -102.357163) (xy 103.109201 -102.327697)
			(xy 103.06801 -102.292006) (xy 103.032319 -102.250815) (xy 103.002853 -102.204965) (xy 102.980211 -102.155388)
			(xy 102.964856 -102.103093) (xy 102.9571 -102.049145) (xy 102.956614 -102.021894) (xy 102.400814 -102.021894)
			(xy 102.418389 -102.042175) (xy 102.447857 -102.088026) (xy 102.470499 -102.137604) (xy 102.485856 -102.189899)
			(xy 102.493613 -102.243848) (xy 102.493613 -102.298352) (xy 102.485856 -102.352301) (xy 102.470499 -102.404596)
			(xy 102.447857 -102.454174) (xy 102.418389 -102.500025) (xy 102.382695 -102.541215) (xy 102.341502 -102.576905)
			(xy 102.29565 -102.60637) (xy 102.24607 -102.629009) (xy 102.193773 -102.644362) (xy 102.139824 -102.652115)
			(xy 102.112572 -102.652576) (xy 102.085201 -102.652132) (xy 102.031021 -102.64431) (xy 101.978517 -102.628816)
			(xy 101.928771 -102.605969) (xy 101.882805 -102.57624) (xy 101.861874 -102.558596) (xy 101.86162 -102.558342)
			(xy 101.854537 -102.552751) (xy 101.837617 -102.546508) (xy 101.8286 -102.54615) (xy 101.761544 -102.54615)
			(xy 101.752528 -102.546517) (xy 101.73561 -102.552756) (xy 101.728524 -102.558342) (xy 101.728524 -102.558596)
			(xy 101.72827 -102.558596) (xy 101.707322 -102.576215) (xy 101.661354 -102.60593) (xy 101.61161 -102.62877)
			(xy 101.559113 -102.644266) (xy 101.50494 -102.652099) (xy 101.477572 -102.652576) (xy 101.45032 -102.652152)
			(xy 101.396371 -102.644392) (xy 101.344075 -102.629033) (xy 101.294497 -102.606388) (xy 101.248646 -102.576919)
			(xy 101.207456 -102.541224) (xy 101.171764 -102.500031) (xy 101.142298 -102.454178) (xy 101.119657 -102.404599)
			(xy 101.104302 -102.352302) (xy 101.096546 -102.298352) (xy 100.003104 -102.298352) (xy 99.983142 -102.328525)
			(xy 99.945925 -102.370062) (xy 99.903057 -102.405737) (xy 99.855451 -102.434791) (xy 99.804122 -102.456603)
			(xy 99.750165 -102.470709) (xy 99.694728 -102.476809) (xy 99.638994 -102.474772) (xy 99.584151 -102.464642)
			(xy 99.531367 -102.446635) (xy 99.481767 -102.421134) (xy 99.436409 -102.388683) (xy 99.39626 -102.349974)
			(xy 99.362174 -102.305831) (xy 99.334878 -102.257196) (xy 99.314955 -102.205105) (xy 99.302829 -102.150668)
			(xy 99.298758 -102.095046) (xy 97.940096 -102.095046) (xy 97.940096 -102.130449) (xy 97.93234 -102.184391)
			(xy 97.916987 -102.236681) (xy 97.894348 -102.286254) (xy 97.864885 -102.332101) (xy 97.829198 -102.373288)
			(xy 97.788012 -102.408977) (xy 97.742167 -102.438442) (xy 97.692595 -102.461082) (xy 97.640305 -102.476437)
			(xy 97.586363 -102.484195) (xy 97.559114 -102.484682) (xy 97.531744 -102.484212) (xy 97.477565 -102.476396)
			(xy 97.425062 -102.460908) (xy 97.375315 -102.438067) (xy 97.329348 -102.408343) (xy 97.308416 -102.390702)
			(xy 97.308162 -102.390448) (xy 97.301066 -102.384875) (xy 97.284156 -102.378621) (xy 97.275142 -102.378256)
			(xy 97.208086 -102.378256) (xy 97.199067 -102.378594) (xy 97.18215 -102.384854) (xy 97.175066 -102.390448)
			(xy 97.175066 -102.390702) (xy 97.174812 -102.390702) (xy 97.153886 -102.408349) (xy 97.107912 -102.43806)
			(xy 97.058163 -102.460894) (xy 97.005661 -102.476383) (xy 96.951484 -102.484209) (xy 96.924114 -102.484682)
			(xy 96.896859 -102.484272) (xy 96.842902 -102.476516) (xy 96.790599 -102.46116) (xy 96.741014 -102.438517)
			(xy 96.695156 -102.409047) (xy 96.653959 -102.373351) (xy 96.618261 -102.332155) (xy 96.58879 -102.286298)
			(xy 96.566145 -102.236714) (xy 96.550787 -102.184411) (xy 96.543029 -102.130455) (xy 93.899978 -102.130455)
			(xy 93.886247 -102.14578) (xy 93.843379 -102.181455) (xy 93.795773 -102.210509) (xy 93.744444 -102.232321)
			(xy 93.690487 -102.246427) (xy 93.63505 -102.252527) (xy 93.579316 -102.25049) (xy 93.524473 -102.24036)
			(xy 93.471689 -102.222353) (xy 93.422089 -102.196852) (xy 93.376731 -102.164401) (xy 93.336582 -102.125692)
			(xy 93.302496 -102.081549) (xy 93.2752 -102.032914) (xy 93.255277 -101.980823) (xy 93.243151 -101.926386)
			(xy 93.23908 -101.870764) (xy 91.503691 -101.870764) (xy 91.504008 -101.874574) (xy 91.504008 -101.875082)
			(xy 91.505159 -101.882187) (xy 91.510962 -101.895354) (xy 91.515438 -101.90099) (xy 91.517216 -101.903022)
			(xy 91.517724 -101.90353) (xy 91.517978 -101.903784) (xy 91.520772 -101.906832) (xy 91.522296 -101.908102)
			(xy 91.593162 -101.95941) (xy 91.599551 -101.963296) (xy 91.613881 -101.967544) (xy 91.621356 -101.967792)
			(xy 91.634818 -101.965506) (xy 91.636596 -101.964998) (xy 91.63812 -101.96449) (xy 91.664536 -101.957124)
			(xy 91.694 -101.951282) (xy 91.707882 -101.94924) (xy 91.73585 -101.946948) (xy 91.74988 -101.94671)
			(xy 91.755722 -101.94671) (xy 91.782858 -101.947353) (xy 91.836541 -101.955374) (xy 91.888545 -101.970922)
			(xy 91.93782 -101.993684) (xy 91.983371 -102.0232) (xy 92.024279 -102.058875) (xy 92.059718 -102.099987)
			(xy 92.088972 -102.145708) (xy 92.11145 -102.195113) (xy 92.126699 -102.247206) (xy 92.13441 -102.300934)
			(xy 92.134428 -102.355213) (xy 92.126752 -102.408946) (xy 92.111538 -102.461048) (xy 92.089093 -102.510469)
			(xy 92.05987 -102.556209) (xy 92.024459 -102.597345) (xy 91.983574 -102.633047) (xy 91.938042 -102.662594)
			(xy 91.888782 -102.685388) (xy 91.836789 -102.700971) (xy 91.783111 -102.709027) (xy 91.755976 -102.709726)
			(xy 91.752928 -102.709726) (xy 91.723755 -102.709156) (xy 91.666096 -102.700233) (xy 91.63812 -102.691946)
			(xy 91.636596 -102.691438) (xy 91.634818 -102.69093) (xy 91.621356 -102.688644) (xy 91.613803 -102.688927)
			(xy 91.599349 -102.693323) (xy 91.592908 -102.69728) (xy 91.591384 -102.698296) (xy 91.590114 -102.699312)
			(xy 91.52646 -102.74523) (xy 152.833583 -102.74523) (xy 152.833583 -102.68797) (xy 152.841731 -102.631291)
			(xy 152.857863 -102.57635) (xy 152.88165 -102.524263) (xy 152.912606 -102.476092) (xy 152.950103 -102.432816)
			(xy 152.993377 -102.395317) (xy 153.041547 -102.364358) (xy 153.093633 -102.340569) (xy 153.148574 -102.324435)
			(xy 153.205252 -102.316284) (xy 153.233882 -102.315772) (xy 153.261253 -102.316233) (xy 153.315485 -102.323677)
			(xy 153.368202 -102.338428) (xy 153.418421 -102.360213) (xy 153.465211 -102.388627) (xy 153.5077 -102.423141)
			(xy 153.5451 -102.463114) (xy 153.561288 -102.48519) (xy 153.566858 -102.492444) (xy 153.581962 -102.502732)
			(xy 153.590752 -102.505256) (xy 153.620724 -102.512622) (xy 153.629672 -102.514384) (xy 153.647764 -102.512159)
			(xy 153.65603 -102.508304) (xy 153.680643 -102.495959) (xy 153.732176 -102.476555) (xy 153.785663 -102.463468)
			(xy 153.840333 -102.456887) (xy 153.867866 -102.456488) (xy 153.8954 -102.456862) (xy 153.950075 -102.463433)
			(xy 154.003566 -102.476522) (xy 154.055098 -102.495937) (xy 154.079702 -102.508304) (xy 154.087961 -102.512183)
			(xy 154.106058 -102.514397) (xy 154.115008 -102.512622) (xy 154.14498 -102.505256) (xy 154.153757 -102.502701)
			(xy 154.16886 -102.492427) (xy 154.174444 -102.48519) (xy 154.190676 -102.463149) (xy 154.228069 -102.423175)
			(xy 154.270551 -102.388658) (xy 154.317333 -102.360241) (xy 154.367545 -102.338451) (xy 154.420255 -102.323693)
			(xy 154.474482 -102.316241) (xy 154.50185 -102.315772) (xy 154.530483 -102.316287) (xy 154.587167 -102.324431)
			(xy 154.642115 -102.340559) (xy 154.694208 -102.364343) (xy 154.742386 -102.395299) (xy 154.785667 -102.432798)
			(xy 154.796292 -102.445058) (xy 160.769552 -102.445058) (xy 160.773623 -102.389436) (xy 160.785749 -102.334999)
			(xy 160.805672 -102.282908) (xy 160.832968 -102.234273) (xy 160.867054 -102.19013) (xy 160.907203 -102.151421)
			(xy 160.952561 -102.11897) (xy 161.002161 -102.093469) (xy 161.054945 -102.075462) (xy 161.109788 -102.065332)
			(xy 161.165522 -102.063295) (xy 161.220959 -102.069395) (xy 161.274916 -102.083501) (xy 161.326245 -102.105313)
			(xy 161.373851 -102.134367) (xy 161.416719 -102.170042) (xy 161.453936 -102.211579) (xy 161.484709 -102.258092)
			(xy 161.508381 -102.308589) (xy 161.524449 -102.361996) (xy 161.532569 -102.417172) (xy 161.533078 -102.445058)
			(xy 161.532569 -102.472944) (xy 161.524449 -102.52812) (xy 161.508381 -102.581527) (xy 161.484709 -102.632024)
			(xy 161.453936 -102.678537) (xy 161.416719 -102.720074) (xy 161.373851 -102.755749) (xy 161.326245 -102.784803)
			(xy 161.274916 -102.806615) (xy 161.220959 -102.820721) (xy 161.165522 -102.826821) (xy 161.109788 -102.824784)
			(xy 161.054945 -102.814654) (xy 161.002161 -102.796647) (xy 160.952561 -102.771146) (xy 160.907203 -102.738695)
			(xy 160.867054 -102.699986) (xy 160.832968 -102.655843) (xy 160.805672 -102.607208) (xy 160.785749 -102.555117)
			(xy 160.773623 -102.50068) (xy 160.769552 -102.445058) (xy 154.796292 -102.445058) (xy 154.823171 -102.476074)
			(xy 154.854133 -102.524248) (xy 154.877924 -102.576338) (xy 154.894059 -102.631284) (xy 154.902209 -102.687967)
			(xy 154.902209 -102.745233) (xy 154.894059 -102.801916) (xy 154.880704 -102.847394) (xy 163.075618 -102.847394)
			(xy 163.079689 -102.791772) (xy 163.091815 -102.737335) (xy 163.111738 -102.685244) (xy 163.139034 -102.636609)
			(xy 163.17312 -102.592466) (xy 163.213269 -102.553757) (xy 163.258627 -102.521306) (xy 163.308227 -102.495805)
			(xy 163.361011 -102.477798) (xy 163.415854 -102.467668) (xy 163.471588 -102.465631) (xy 163.527025 -102.471731)
			(xy 163.529404 -102.472353) (xy 167.351936 -102.472353) (xy 167.351936 -102.417847) (xy 167.359692 -102.363897)
			(xy 167.375047 -102.311599) (xy 167.397688 -102.262019) (xy 167.427154 -102.216165) (xy 167.462846 -102.174971)
			(xy 167.504036 -102.139276) (xy 167.549887 -102.109805) (xy 167.599465 -102.08716) (xy 167.651762 -102.0718)
			(xy 167.705711 -102.064038) (xy 167.732964 -102.06355) (xy 167.750076 -102.063741) (xy 167.784163 -102.066793)
			(xy 167.801036 -102.069646) (xy 167.812364 -102.071056) (xy 167.834378 -102.065138) (xy 167.843454 -102.058216)
			(xy 167.867838 -102.037134) (xy 167.876281 -102.029169) (xy 167.8854 -102.007849) (xy 167.885364 -101.99624)
			(xy 167.884856 -101.976428) (xy 167.884856 -101.112828) (xy 167.885364 -101.093524) (xy 167.88531 -101.081933)
			(xy 167.876207 -101.060646) (xy 167.867838 -101.05263) (xy 167.843454 -101.031802) (xy 167.834441 -101.024889)
			(xy 167.812556 -101.01894) (xy 167.80129 -101.020372) (xy 167.784356 -101.023252) (xy 167.75014 -101.026304)
			(xy 167.732964 -101.026468) (xy 167.705712 -101.02606) (xy 167.651762 -101.018298) (xy 167.599466 -101.002938)
			(xy 167.549888 -100.980293) (xy 167.504038 -100.950822) (xy 167.462847 -100.915127) (xy 167.427156 -100.873934)
			(xy 167.39769 -100.82808) (xy 167.375049 -100.7785) (xy 167.359694 -100.726203) (xy 167.351938 -100.672252)
			(xy 167.351938 -100.617748) (xy 167.359694 -100.563797) (xy 167.375049 -100.5115) (xy 167.39769 -100.46192)
			(xy 167.427156 -100.416066) (xy 167.462847 -100.374873) (xy 167.504038 -100.339178) (xy 167.549888 -100.309707)
			(xy 167.599466 -100.287062) (xy 167.651762 -100.271702) (xy 167.705712 -100.26394) (xy 167.732964 -100.263452)
			(xy 167.759943 -100.263867) (xy 167.813364 -100.271456) (xy 167.865181 -100.286504) (xy 167.914359 -100.308708)
			(xy 167.959914 -100.337624) (xy 168.000936 -100.372676) (xy 168.036605 -100.413162) (xy 168.066208 -100.458274)
			(xy 168.089155 -100.50711) (xy 168.104985 -100.558693) (xy 168.109646 -100.58527) (xy 168.109646 -100.585524)
			(xy 168.111846 -100.595787) (xy 168.123267 -100.61337) (xy 168.131744 -100.61956) (xy 168.203118 -100.667058)
			(xy 168.223692 -100.670614) (xy 168.234106 -100.668074) (xy 168.260871 -100.661993) (xy 168.315373 -100.655496)
			(xy 168.342818 -100.65512) (xy 168.36616 -100.655393) (xy 168.412606 -100.660102) (xy 168.435528 -100.664518)
			(xy 168.435782 -100.664518) (xy 168.445896 -100.666116) (xy 168.465946 -100.662047) (xy 168.474644 -100.656644)
			(xy 168.543986 -100.608892) (xy 168.554908 -100.59162) (xy 168.556432 -100.581206) (xy 168.561365 -100.553311)
			(xy 168.578116 -100.499196) (xy 168.602315 -100.447976) (xy 168.63348 -100.400671) (xy 168.670992 -100.358222)
			(xy 168.714105 -100.321474) (xy 168.761959 -100.291158) (xy 168.813602 -100.267877) (xy 168.868008 -100.252096)
			(xy 168.924094 -100.244127) (xy 168.952418 -100.24364) (xy 168.981788 -100.244153) (xy 169.039896 -100.252754)
			(xy 169.096126 -100.269742) (xy 169.149277 -100.294751) (xy 169.19821 -100.327248) (xy 169.220388 -100.34651)
			(xy 169.227568 -100.352403) (xy 169.244891 -100.359056) (xy 169.25417 -100.359464) (xy 169.285666 -100.359464)
			(xy 169.294937 -100.35901) (xy 169.312255 -100.352375) (xy 169.319448 -100.34651) (xy 169.341633 -100.327259)
			(xy 169.390569 -100.294771) (xy 169.443718 -100.269766) (xy 169.499946 -100.252779) (xy 169.55805 -100.244173)
			(xy 169.587418 -100.24364) (xy 169.604459 -100.243833) (xy 169.638414 -100.246754) (xy 169.655236 -100.249482)
			(xy 169.666291 -100.250852) (xy 169.687772 -100.245051) (xy 169.696638 -100.238306) (xy 169.721022 -100.217478)
			(xy 169.729189 -100.209833) (xy 169.738539 -100.189537) (xy 169.739056 -100.178362) (xy 169.739056 -100.17633)
			(xy 169.739056 -99.310952) (xy 169.73856 -99.299773) (xy 169.729199 -99.279476) (xy 169.721022 -99.271836)
			(xy 169.696638 -99.251008) (xy 169.687774 -99.244269) (xy 169.666292 -99.238491) (xy 169.655236 -99.239832)
			(xy 169.638409 -99.242489) (xy 169.604453 -99.245283) (xy 169.587418 -99.24542) (xy 169.558786 -99.244919)
			(xy 169.502104 -99.236771) (xy 169.447159 -99.22064) (xy 169.395069 -99.196854) (xy 169.346894 -99.165896)
			(xy 169.303616 -99.128397) (xy 169.266115 -99.08512) (xy 169.235155 -99.036947) (xy 169.211366 -98.984858)
			(xy 169.195232 -98.929913) (xy 169.187083 -98.873232) (xy 169.187083 -98.815968) (xy 169.195232 -98.759287)
			(xy 169.211366 -98.704342) (xy 169.235155 -98.652253) (xy 169.266115 -98.60408) (xy 169.303616 -98.560803)
			(xy 169.346894 -98.523304) (xy 169.395069 -98.492346) (xy 169.447159 -98.46856) (xy 169.502104 -98.452429)
			(xy 169.558786 -98.444281) (xy 169.587418 -98.443796) (xy 169.615731 -98.444287) (xy 169.671794 -98.452242)
			(xy 169.726182 -98.468004) (xy 169.77781 -98.491261) (xy 169.825654 -98.52155) (xy 169.86876 -98.558269)
			(xy 169.906273 -98.600686) (xy 169.937445 -98.647959) (xy 169.961656 -98.699147) (xy 169.978426 -98.753232)
			(xy 169.983404 -98.781108) (xy 169.984928 -98.791522) (xy 169.99585 -98.808794) (xy 170.065192 -98.856546)
			(xy 170.073889 -98.86195) (xy 170.093939 -98.866013) (xy 170.104054 -98.86442) (xy 170.104562 -98.86442)
			(xy 170.127415 -98.859946) (xy 170.173734 -98.855108) (xy 170.197018 -98.854768) (xy 170.220366 -98.855108)
			(xy 170.266811 -98.859941) (xy 170.289728 -98.86442) (xy 170.289982 -98.86442) (xy 170.300096 -98.866018)
			(xy 170.320146 -98.861949) (xy 170.328844 -98.856546) (xy 170.398186 -98.808794) (xy 170.409108 -98.791522)
			(xy 170.410632 -98.781108) (xy 170.415586 -98.753228) (xy 170.432365 -98.699146) (xy 170.456584 -98.647961)
			(xy 170.487762 -98.600691) (xy 170.525277 -98.558276) (xy 170.568385 -98.521559) (xy 170.616228 -98.49127)
			(xy 170.667856 -98.46801) (xy 170.722242 -98.452243) (xy 170.778305 -98.444281) (xy 170.806618 -98.443796)
			(xy 170.835248 -98.444292) (xy 170.891924 -98.452443) (xy 170.946864 -98.468577) (xy 170.998949 -98.492365)
			(xy 171.047118 -98.523324) (xy 171.090391 -98.560822) (xy 171.127887 -98.604097) (xy 171.158843 -98.652267)
			(xy 171.182629 -98.704353) (xy 171.198761 -98.759293) (xy 171.20691 -98.81597) (xy 171.20691 -98.87323)
			(xy 171.198761 -98.929907) (xy 171.182629 -98.984847) (xy 171.158843 -99.036933) (xy 171.127887 -99.085103)
			(xy 171.090391 -99.128378) (xy 171.047118 -99.165876) (xy 170.998949 -99.196835) (xy 170.946864 -99.220623)
			(xy 170.891924 -99.236757) (xy 170.835248 -99.244908) (xy 170.806618 -99.24542) (xy 170.789582 -99.245294)
			(xy 170.755626 -99.242498) (xy 170.7388 -99.239832) (xy 170.727744 -99.238481) (xy 170.706265 -99.244269)
			(xy 170.697398 -99.251008) (xy 170.673014 -99.271836) (xy 170.664846 -99.279481) (xy 170.655495 -99.299776)
			(xy 170.65498 -99.310952) (xy 170.65498 -99.31273) (xy 170.65498 -100.178362) (xy 170.655456 -100.189544)
			(xy 170.66483 -100.209841) (xy 170.673014 -100.217478) (xy 170.697398 -100.238306) (xy 170.706283 -100.245012)
			(xy 170.727748 -100.25081) (xy 170.7388 -100.249482) (xy 170.755625 -100.246775) (xy 170.789578 -100.243846)
			(xy 170.806618 -100.24364) (xy 170.835266 -100.24414) (xy 170.891978 -100.252297) (xy 170.946952 -100.268441)
			(xy 170.99907 -100.292244) (xy 171.047269 -100.323222) (xy 171.090569 -100.360744) (xy 171.128089 -100.404046)
			(xy 171.159065 -100.452246) (xy 171.182865 -100.504365) (xy 171.199007 -100.55934) (xy 171.207161 -100.616052)
			(xy 171.207161 -100.673348) (xy 171.199007 -100.73006) (xy 171.182865 -100.785035) (xy 171.159065 -100.837154)
			(xy 171.128089 -100.885354) (xy 171.090569 -100.928656) (xy 171.047269 -100.966178) (xy 170.99907 -100.997156)
			(xy 170.946952 -101.020959) (xy 170.891978 -101.037103) (xy 170.835266 -101.04526) (xy 170.806618 -101.045772)
			(xy 170.778294 -101.045334) (xy 170.72221 -101.037352) (xy 170.667808 -101.02156) (xy 170.616168 -100.99827)
			(xy 170.568319 -100.967947) (xy 170.525211 -100.931193) (xy 170.487704 -100.888741) (xy 170.456542 -100.841433)
			(xy 170.432346 -100.790212) (xy 170.415598 -100.736096) (xy 170.410632 -100.708206) (xy 170.409108 -100.697792)
			(xy 170.397932 -100.680012) (xy 170.328844 -100.632514) (xy 170.320135 -100.627132) (xy 170.300094 -100.623054)
			(xy 170.289982 -100.62464) (xy 170.289474 -100.62464) (xy 170.266622 -100.629123) (xy 170.220303 -100.633955)
			(xy 170.197018 -100.634292) (xy 170.17367 -100.633962) (xy 170.127224 -100.629122) (xy 170.104308 -100.62464)
			(xy 170.104054 -100.62464) (xy 170.093938 -100.62307) (xy 170.073892 -100.627121) (xy 170.065192 -100.632514)
			(xy 169.996104 -100.680012) (xy 169.984928 -100.697792) (xy 169.983404 -100.708206) (xy 169.978369 -100.736082)
			(xy 169.961632 -100.790194) (xy 169.937447 -100.841413) (xy 169.906294 -100.888718) (xy 169.868794 -100.931169)
			(xy 169.825693 -100.967919) (xy 169.777849 -100.998238) (xy 169.726214 -101.021523) (xy 169.671817 -101.037309)
			(xy 169.615739 -101.045283) (xy 169.587418 -101.045772) (xy 169.558049 -101.045235) (xy 169.499943 -101.036639)
			(xy 169.443712 -101.019657) (xy 169.390561 -100.994653) (xy 169.341627 -100.962162) (xy 169.319448 -100.942902)
			(xy 169.312286 -100.936983) (xy 169.294949 -100.930345) (xy 169.285666 -100.929948) (xy 169.25417 -100.929948)
			(xy 169.244896 -100.930368) (xy 169.227578 -100.937026) (xy 169.220388 -100.942902) (xy 169.19819 -100.962138)
			(xy 169.149258 -100.994628) (xy 169.096112 -101.019635) (xy 169.039887 -101.036626) (xy 168.981786 -101.045236)
			(xy 168.952418 -101.045772) (xy 168.935377 -101.045589) (xy 168.901421 -101.042661) (xy 168.8846 -101.03993)
			(xy 168.873544 -101.038579) (xy 168.852065 -101.044367) (xy 168.843198 -101.051106) (xy 168.818814 -101.071934)
			(xy 168.810647 -101.07958) (xy 168.801295 -101.099874) (xy 168.80078 -101.11105) (xy 168.80078 -101.112828)
			(xy 168.80078 -101.97846) (xy 168.801257 -101.989642) (xy 168.81063 -102.009939) (xy 168.818814 -102.017576)
			(xy 168.843198 -102.038404) (xy 168.852083 -102.045109) (xy 168.873548 -102.050908) (xy 168.8846 -102.04958)
			(xy 168.901428 -102.046931) (xy 168.935383 -102.044132) (xy 168.952418 -102.043992) (xy 168.981776 -102.044512)
			(xy 169.039864 -102.053081) (xy 169.096084 -102.070019) (xy 169.149238 -102.094964) (xy 169.198192 -102.127385)
			(xy 169.220388 -102.146608) (xy 169.227568 -102.152501) (xy 169.244891 -102.159154) (xy 169.25417 -102.159562)
			(xy 169.285412 -102.159562) (xy 169.294685 -102.159131) (xy 169.312003 -102.15248) (xy 169.319194 -102.146608)
			(xy 169.341398 -102.127325) (xy 169.390362 -102.094754) (xy 169.443557 -102.069683) (xy 169.499844 -102.05265)
			(xy 169.558015 -102.044021) (xy 169.587418 -102.043484) (xy 169.615739 -102.044018) (xy 169.671817 -102.05199)
			(xy 169.726215 -102.067772) (xy 169.777852 -102.091051) (xy 169.8257 -102.121363) (xy 169.868807 -102.158106)
			(xy 169.906316 -102.200548) (xy 169.937481 -102.247846) (xy 169.961681 -102.299057) (xy 169.978435 -102.353164)
			(xy 169.983404 -102.38105) (xy 169.984928 -102.391464) (xy 169.99585 -102.408736) (xy 170.065192 -102.456488)
			(xy 170.073891 -102.461889) (xy 170.09394 -102.465955) (xy 170.104054 -102.464362) (xy 170.104308 -102.464362)
			(xy 170.127228 -102.459931) (xy 170.173675 -102.455227) (xy 170.197018 -102.454964) (xy 170.22036 -102.455237)
			(xy 170.266806 -102.459946) (xy 170.289728 -102.464362) (xy 170.289982 -102.464362) (xy 170.300096 -102.465953)
			(xy 170.320145 -102.461888) (xy 170.328844 -102.456488) (xy 170.398186 -102.408736) (xy 170.409108 -102.391464)
			(xy 170.410632 -102.38105) (xy 170.415599 -102.353161) (xy 170.432344 -102.299046) (xy 170.456537 -102.247826)
			(xy 170.487698 -102.20052) (xy 170.525206 -102.15807) (xy 170.568315 -102.121321) (xy 170.616166 -102.091004)
			(xy 170.667807 -102.067722) (xy 170.722211 -102.05194) (xy 170.778295 -102.043971) (xy 170.806618 -102.043484)
			(xy 170.835269 -102.043896) (xy 170.891987 -102.052053) (xy 170.946968 -102.068199) (xy 170.999091 -102.092005)
			(xy 171.047296 -102.122986) (xy 171.090601 -102.160512) (xy 171.128125 -102.203819) (xy 171.159104 -102.252025)
			(xy 171.182907 -102.304149) (xy 171.199051 -102.35913) (xy 171.207205 -102.415849) (xy 171.207205 -102.473151)
			(xy 171.199051 -102.52987) (xy 171.182907 -102.584851) (xy 171.159104 -102.636975) (xy 171.128125 -102.685181)
			(xy 171.090601 -102.728488) (xy 171.047296 -102.766014) (xy 170.999091 -102.796995) (xy 170.946968 -102.820801)
			(xy 170.891987 -102.836947) (xy 170.835269 -102.845104) (xy 170.806618 -102.845616) (xy 170.789577 -102.845432)
			(xy 170.755622 -102.842505) (xy 170.7388 -102.839774) (xy 170.727744 -102.838436) (xy 170.706267 -102.844217)
			(xy 170.697398 -102.85095) (xy 170.673014 -102.871778) (xy 170.664873 -102.879447) (xy 170.655506 -102.899724)
			(xy 170.65498 -102.910894) (xy 170.65498 -102.912672) (xy 170.65498 -103.778304) (xy 170.655489 -103.789482)
			(xy 170.66484 -103.80978) (xy 170.673014 -103.81742) (xy 170.697398 -103.838248) (xy 170.706287 -103.844949)
			(xy 170.727749 -103.850752) (xy 170.7388 -103.849424) (xy 170.755629 -103.846775) (xy 170.789583 -103.843976)
			(xy 170.806618 -103.843836) (xy 170.835251 -103.844252) (xy 170.891933 -103.852404) (xy 170.946878 -103.868539)
			(xy 170.998968 -103.89233) (xy 171.047142 -103.923292) (xy 171.090419 -103.960794) (xy 171.127919 -104.004073)
			(xy 171.158879 -104.052248) (xy 171.182667 -104.104339) (xy 171.1988 -104.159285) (xy 171.206949 -104.215967)
			(xy 171.206949 -104.273233) (xy 171.1988 -104.329915) (xy 171.182667 -104.384861) (xy 171.158879 -104.436952)
			(xy 171.127919 -104.485127) (xy 171.090419 -104.528406) (xy 171.047142 -104.565908) (xy 170.998968 -104.59687)
			(xy 170.946878 -104.620661) (xy 170.891933 -104.636796) (xy 170.835251 -104.644948) (xy 170.806618 -104.64546)
			(xy 170.778306 -104.644981) (xy 170.722244 -104.637019) (xy 170.667859 -104.621251) (xy 170.616233 -104.59799)
			(xy 170.568392 -104.567699) (xy 170.525286 -104.53098) (xy 170.487774 -104.488563) (xy 170.456601 -104.441292)
			(xy 170.432387 -104.390106) (xy 170.415613 -104.336023) (xy 170.410632 -104.308148) (xy 170.409108 -104.297734)
			(xy 170.397932 -104.279954) (xy 170.328844 -104.232456) (xy 170.320137 -104.227071) (xy 170.300095 -104.222996)
			(xy 170.289982 -104.224582) (xy 170.289728 -104.224582) (xy 170.266807 -104.229008) (xy 170.220361 -104.233716)
			(xy 170.197018 -104.23398) (xy 170.173676 -104.233701) (xy 170.12723 -104.228996) (xy 170.104308 -104.224582)
			(xy 170.104054 -104.224582) (xy 170.093939 -104.223004) (xy 170.073891 -104.227059) (xy 170.065192 -104.232456)
			(xy 169.996104 -104.279954) (xy 169.984928 -104.297734) (xy 169.983404 -104.308148) (xy 169.978382 -104.336014)
			(xy 169.96161 -104.390094) (xy 169.937399 -104.441277) (xy 169.90623 -104.488546) (xy 169.868723 -104.530962)
			(xy 169.825623 -104.56768) (xy 169.777786 -104.597972) (xy 169.726165 -104.621235) (xy 169.671786 -104.637006)
			(xy 169.615728 -104.644972) (xy 169.587418 -104.64546) (xy 169.558061 -104.644905) (xy 169.499976 -104.636343)
			(xy 169.443756 -104.619412) (xy 169.390602 -104.594475) (xy 169.341645 -104.562062) (xy 169.319448 -104.542844)
			(xy 169.312292 -104.536918) (xy 169.29495 -104.530286) (xy 169.285666 -104.52989) (xy 169.25417 -104.52989)
			(xy 169.244897 -104.530323) (xy 169.22758 -104.536974) (xy 169.220388 -104.542844) (xy 169.19821 -104.56209)
			(xy 169.149259 -104.594524) (xy 169.096101 -104.619472) (xy 169.039874 -104.636403) (xy 168.981779 -104.644954)
			(xy 168.952418 -104.64546) (xy 168.935382 -104.645334) (xy 168.901426 -104.642537) (xy 168.8846 -104.639872)
			(xy 168.873544 -104.638534) (xy 168.852067 -104.644315) (xy 168.843198 -104.651048) (xy 168.818814 -104.671876)
			(xy 168.810674 -104.679545) (xy 168.801307 -104.699822) (xy 168.80078 -104.710992) (xy 168.80078 -104.71277)
			(xy 168.80078 -105.578402) (xy 168.80129 -105.58958) (xy 168.81064 -105.609878) (xy 168.818814 -105.617518)
			(xy 168.843198 -105.638346) (xy 168.852087 -105.645046) (xy 168.873549 -105.65085) (xy 168.8846 -105.649522)
			(xy 168.901425 -105.646815) (xy 168.935378 -105.643886) (xy 168.952418 -105.64368) (xy 168.981787 -105.644208)
			(xy 169.039894 -105.652808) (xy 169.096124 -105.669793) (xy 169.149275 -105.694799) (xy 169.198209 -105.72729)
			(xy 169.220388 -105.74655) (xy 169.227564 -105.752448) (xy 169.24489 -105.759097) (xy 169.25417 -105.759504)
			(xy 169.285412 -105.759504) (xy 169.294684 -105.759063) (xy 169.312001 -105.752418) (xy 169.319194 -105.74655)
			(xy 169.341387 -105.727268) (xy 169.390371 -105.694759) (xy 169.443576 -105.669749) (xy 169.499862 -105.652772)
			(xy 169.558023 -105.644193) (xy 169.587418 -105.64368) (xy 169.61573 -105.644185) (xy 169.671793 -105.652139)
			(xy 169.726179 -105.667901) (xy 169.777807 -105.691157) (xy 169.825649 -105.721444) (xy 169.868756 -105.758161)
			(xy 169.906268 -105.800576) (xy 169.937441 -105.847848) (xy 169.961654 -105.899034) (xy 169.978425 -105.953117)
			(xy 169.983404 -105.980992) (xy 169.984928 -105.991406) (xy 169.99585 -106.008678) (xy 170.065192 -106.05643)
			(xy 170.07389 -106.061833) (xy 170.093939 -106.065897) (xy 170.104054 -106.064304) (xy 170.104562 -106.064304)
			(xy 170.127415 -106.059831) (xy 170.173734 -106.054993) (xy 170.197018 -106.054652) (xy 170.220366 -106.054991)
			(xy 170.266811 -106.059825) (xy 170.289728 -106.064304) (xy 170.289982 -106.064304) (xy 170.300096 -106.065888)
			(xy 170.320144 -106.061826) (xy 170.328844 -106.05643) (xy 170.398186 -106.008678) (xy 170.409108 -105.991406)
			(xy 170.410632 -105.980992) (xy 170.415574 -105.95311) (xy 170.432355 -105.899028) (xy 170.456576 -105.847843)
			(xy 170.487755 -105.800574) (xy 170.525272 -105.758159) (xy 170.568381 -105.721442) (xy 170.616226 -105.691153)
			(xy 170.667854 -105.667894) (xy 170.722241 -105.652127) (xy 170.778305 -105.644165) (xy 170.806618 -105.64368)
			(xy 170.835247 -105.644208) (xy 170.891921 -105.652359) (xy 170.946859 -105.668492) (xy 170.998941 -105.692279)
			(xy 171.047108 -105.723236) (xy 171.09038 -105.760733) (xy 171.127874 -105.804006) (xy 171.158829 -105.852175)
			(xy 171.182614 -105.904258) (xy 171.198745 -105.959197) (xy 171.206894 -106.015871) (xy 171.206894 -106.073129)
			(xy 171.198745 -106.129803) (xy 171.182614 -106.184742) (xy 171.158829 -106.236825) (xy 171.127874 -106.284994)
			(xy 171.09038 -106.328267) (xy 171.047108 -106.365764) (xy 170.998941 -106.396721) (xy 170.946859 -106.420508)
			(xy 170.891921 -106.436641) (xy 170.835247 -106.444792) (xy 170.806618 -106.445304) (xy 170.789582 -106.445177)
			(xy 170.755627 -106.442381) (xy 170.7388 -106.439716) (xy 170.727744 -106.438368) (xy 170.706266 -106.444155)
			(xy 170.697398 -106.450892) (xy 170.673014 -106.47172) (xy 170.664854 -106.479371) (xy 170.655498 -106.499662)
			(xy 170.65498 -106.510836) (xy 170.65498 -106.512614) (xy 170.65498 -107.378246) (xy 170.655465 -107.389427)
			(xy 170.664833 -107.409724) (xy 170.673014 -107.417362) (xy 170.697398 -107.43819) (xy 170.706284 -107.444894)
			(xy 170.727749 -107.450694) (xy 170.7388 -107.449366) (xy 170.755625 -107.446659) (xy 170.789578 -107.44373)
			(xy 170.806618 -107.443524) (xy 170.835265 -107.444056) (xy 170.891975 -107.452212) (xy 170.946947 -107.468356)
			(xy 170.999062 -107.492158) (xy 171.047259 -107.523135) (xy 171.090558 -107.560655) (xy 171.128076 -107.603955)
			(xy 171.159051 -107.652154) (xy 171.18285 -107.70427) (xy 171.198991 -107.759243) (xy 171.207145 -107.815953)
			(xy 171.207145 -107.873247) (xy 171.198991 -107.929957) (xy 171.18285 -107.98493) (xy 171.159051 -108.037046)
			(xy 171.128076 -108.085245) (xy 171.090558 -108.128545) (xy 171.047259 -108.166065) (xy 170.999062 -108.197042)
			(xy 170.946947 -108.220844) (xy 170.891975 -108.236988) (xy 170.835265 -108.245144) (xy 170.806618 -108.245656)
			(xy 170.778293 -108.245231) (xy 170.722209 -108.237249) (xy 170.667805 -108.221456) (xy 170.616164 -108.198165)
			(xy 170.568314 -108.167841) (xy 170.525207 -108.131086) (xy 170.4877 -108.088631) (xy 170.456539 -108.041321)
			(xy 170.432344 -107.990098) (xy 170.415597 -107.935981) (xy 170.410632 -107.90809) (xy 170.409108 -107.897676)
			(xy 170.397932 -107.879896) (xy 170.328844 -107.832398) (xy 170.320135 -107.827015) (xy 170.300095 -107.822938)
			(xy 170.289982 -107.824524) (xy 170.289474 -107.824524) (xy 170.266622 -107.829007) (xy 170.220303 -107.833839)
			(xy 170.197018 -107.834176) (xy 170.17367 -107.833846) (xy 170.127224 -107.829006) (xy 170.104308 -107.824524)
			(xy 170.104054 -107.824524) (xy 170.093938 -107.822956) (xy 170.073892 -107.827006) (xy 170.065192 -107.832398)
			(xy 169.996104 -107.879896) (xy 169.984928 -107.897676) (xy 169.983404 -107.90809) (xy 169.978433 -107.935977)
			(xy 169.961685 -107.99009) (xy 169.93749 -108.041308) (xy 169.906328 -108.088612) (xy 169.86882 -108.13106)
			(xy 169.825713 -108.167809) (xy 169.777863 -108.198126) (xy 169.726224 -108.221409) (xy 169.671822 -108.237194)
			(xy 169.615741 -108.245167) (xy 169.587418 -108.245656) (xy 169.558049 -108.245123) (xy 169.499942 -108.236526)
			(xy 169.443711 -108.219544) (xy 169.39056 -108.194539) (xy 169.341626 -108.162046) (xy 169.319448 -108.142786)
			(xy 169.312288 -108.136865) (xy 169.29495 -108.130229) (xy 169.285666 -108.129832) (xy 169.25417 -108.129832)
			(xy 169.244896 -108.130256) (xy 169.227578 -108.136912) (xy 169.220388 -108.142786) (xy 169.198188 -108.162019)
			(xy 169.149257 -108.19451) (xy 169.096111 -108.219518) (xy 169.039887 -108.236509) (xy 168.981785 -108.24512)
			(xy 168.952418 -108.245656) (xy 168.935377 -108.245472) (xy 168.901422 -108.242545) (xy 168.8846 -108.239814)
			(xy 168.873544 -108.238466) (xy 168.852065 -108.244252) (xy 168.843198 -108.25099) (xy 168.818814 -108.271818)
			(xy 168.810655 -108.27947) (xy 168.801298 -108.29976) (xy 168.80078 -108.310934) (xy 168.80078 -108.312712)
			(xy 168.80078 -109.178344) (xy 168.801267 -109.189525) (xy 168.810633 -109.209822) (xy 168.818814 -109.21746)
			(xy 168.843198 -109.238288) (xy 168.852084 -109.244992) (xy 168.873549 -109.250792) (xy 168.8846 -109.249464)
			(xy 168.901428 -109.246815) (xy 168.935383 -109.244016) (xy 168.952418 -109.243876) (xy 168.981776 -109.2444)
			(xy 169.039863 -109.252969) (xy 169.096084 -109.269906) (xy 169.149238 -109.29485) (xy 169.198192 -109.32727)
			(xy 169.220388 -109.346492) (xy 169.22757 -109.352383) (xy 169.244891 -109.359037) (xy 169.25417 -109.359446)
			(xy 169.285666 -109.359446) (xy 169.294937 -109.358996) (xy 169.312256 -109.352359) (xy 169.319448 -109.346492)
			(xy 169.341642 -109.327266) (xy 169.39059 -109.294832) (xy 169.443744 -109.26988) (xy 169.499967 -109.252944)
			(xy 169.558059 -109.244387) (xy 169.587418 -109.243876) (xy 169.61573 -109.244384) (xy 169.671792 -109.252338)
			(xy 169.726178 -109.2681) (xy 169.777806 -109.291355) (xy 169.825648 -109.321643) (xy 169.868755 -109.358359)
			(xy 169.906267 -109.400774) (xy 169.93744 -109.448045) (xy 169.961653 -109.49923) (xy 169.978424 -109.553313)
			(xy 169.983404 -109.581188) (xy 169.984928 -109.591602) (xy 169.99585 -109.608874) (xy 170.065192 -109.656626)
			(xy 170.07389 -109.662029) (xy 170.093939 -109.666093) (xy 170.104054 -109.6645) (xy 170.104562 -109.6645)
			(xy 170.127415 -109.660027) (xy 170.173734 -109.655189) (xy 170.197018 -109.654848) (xy 170.220366 -109.655187)
			(xy 170.266811 -109.660021) (xy 170.289728 -109.6645) (xy 170.289982 -109.6645) (xy 170.300096 -109.666084)
			(xy 170.320144 -109.662022) (xy 170.328844 -109.656626) (xy 170.398186 -109.608874) (xy 170.409108 -109.591602)
			(xy 170.410632 -109.581188) (xy 170.415571 -109.553305) (xy 170.432353 -109.499223) (xy 170.456574 -109.448038)
			(xy 170.487753 -109.400769) (xy 170.525271 -109.358354) (xy 170.56838 -109.321638) (xy 170.616225 -109.291349)
			(xy 170.667854 -109.26809) (xy 170.722241 -109.252323) (xy 170.778305 -109.244361) (xy 170.806618 -109.243876)
			(xy 170.835246 -109.244412) (xy 170.89192 -109.252563) (xy 170.946857 -109.268696) (xy 170.998939 -109.292483)
			(xy 171.047106 -109.32344) (xy 171.090377 -109.360936) (xy 171.127871 -109.404209) (xy 171.158826 -109.452377)
			(xy 171.182611 -109.50446) (xy 171.198741 -109.559397) (xy 171.20689 -109.616072) (xy 171.20689 -109.673328)
			(xy 171.198741 -109.730003) (xy 171.182611 -109.78494) (xy 171.158826 -109.837023) (xy 171.127871 -109.885191)
			(xy 171.090377 -109.928464) (xy 171.047106 -109.96596) (xy 170.998939 -109.996917) (xy 170.946857 -110.020704)
			(xy 170.89192 -110.036837) (xy 170.835246 -110.044988) (xy 170.806618 -110.0455) (xy 170.789582 -110.045373)
			(xy 170.755627 -110.042577) (xy 170.7388 -110.039912) (xy 170.727744 -110.038565) (xy 170.706266 -110.044351)
			(xy 170.697398 -110.051088) (xy 170.673014 -110.071916) (xy 170.664855 -110.079569) (xy 170.655499 -110.099858)
			(xy 170.65498 -110.111032) (xy 170.65498 -110.11281) (xy 170.65498 -110.978442) (xy 170.655468 -110.989623)
			(xy 170.664833 -111.00992) (xy 170.673014 -111.017558) (xy 170.697398 -111.038386) (xy 170.706284 -111.04509)
			(xy 170.727749 -111.05089) (xy 170.7388 -111.049562) (xy 170.755625 -111.046855) (xy 170.789578 -111.043926)
			(xy 170.806618 -111.04372) (xy 170.835264 -111.04426) (xy 170.891974 -111.052416) (xy 170.946945 -111.06856)
			(xy 170.99906 -111.092362) (xy 171.047257 -111.123338) (xy 171.090555 -111.160858) (xy 171.128073 -111.204158)
			(xy 171.159047 -111.252356) (xy 171.182847 -111.304472) (xy 171.198988 -111.359444) (xy 171.207141 -111.416154)
			(xy 171.207141 -111.473446) (xy 171.198988 -111.530156) (xy 171.182847 -111.585128) (xy 171.159047 -111.637244)
			(xy 171.128073 -111.685442) (xy 171.090555 -111.728742) (xy 171.047257 -111.766262) (xy 170.99906 -111.797238)
			(xy 170.946945 -111.82104) (xy 170.891974 -111.837184) (xy 170.835264 -111.84534) (xy 170.806618 -111.845852)
			(xy 170.778293 -111.84543) (xy 170.722208 -111.837449) (xy 170.667804 -111.821655) (xy 170.616163 -111.798364)
			(xy 170.568313 -111.768039) (xy 170.525206 -111.731284) (xy 170.487699 -111.688828) (xy 170.456538 -111.641519)
			(xy 170.432343 -111.590295) (xy 170.415596 -111.536177) (xy 170.410632 -111.508286) (xy 170.409108 -111.497872)
			(xy 170.397932 -111.480092) (xy 170.328844 -111.432594) (xy 170.320136 -111.427211) (xy 170.300095 -111.423134)
			(xy 170.289982 -111.42472) (xy 170.289474 -111.42472) (xy 170.266622 -111.429203) (xy 170.220303 -111.434035)
			(xy 170.197018 -111.434372) (xy 170.17367 -111.434043) (xy 170.127224 -111.429202) (xy 170.104308 -111.42472)
			(xy 170.104054 -111.42472) (xy 170.093938 -111.423153) (xy 170.073892 -111.427202) (xy 170.065192 -111.432594)
			(xy 169.996104 -111.480092) (xy 169.984928 -111.497872) (xy 169.983404 -111.508286) (xy 169.97843 -111.536173)
			(xy 169.961683 -111.590286) (xy 169.937488 -111.641504) (xy 169.906326 -111.688808) (xy 169.868819 -111.731256)
			(xy 169.825712 -111.768005) (xy 169.777862 -111.798322) (xy 169.726223 -111.821605) (xy 169.671822 -111.83739)
			(xy 169.615741 -111.845363) (xy 169.587418 -111.845852) (xy 169.558049 -111.84532) (xy 169.499942 -111.836723)
			(xy 169.443711 -111.81974) (xy 169.39056 -111.794735) (xy 169.341626 -111.762242) (xy 169.319448 -111.742982)
			(xy 169.312288 -111.737061) (xy 169.29495 -111.730425) (xy 169.285666 -111.730028) (xy 169.25417 -111.730028)
			(xy 169.244896 -111.730452) (xy 169.227578 -111.737108) (xy 169.220388 -111.742982) (xy 169.198187 -111.762215)
			(xy 169.149257 -111.794706) (xy 169.096111 -111.819714) (xy 169.039886 -111.836705) (xy 168.981785 -111.845316)
			(xy 168.952418 -111.845852) (xy 168.935377 -111.845668) (xy 168.901422 -111.842741) (xy 168.8846 -111.84001)
			(xy 168.873544 -111.838663) (xy 168.852066 -111.844449) (xy 168.843198 -111.851186) (xy 168.818814 -111.872014)
			(xy 168.810656 -111.879668) (xy 168.801299 -111.899956) (xy 168.80078 -111.91113) (xy 168.80078 -111.912908)
			(xy 168.80078 -112.77854) (xy 168.801269 -112.789721) (xy 168.810634 -112.810018) (xy 168.818814 -112.817656)
			(xy 168.843198 -112.838484) (xy 168.852084 -112.845188) (xy 168.873549 -112.850988) (xy 168.8846 -112.84966)
			(xy 168.901428 -112.847011) (xy 168.935383 -112.844212) (xy 168.952418 -112.844072) (xy 168.981046 -112.844616)
			(xy 169.037719 -112.852766) (xy 169.092656 -112.868899) (xy 169.144737 -112.892686) (xy 169.192903 -112.923643)
			(xy 169.236174 -112.961139) (xy 169.273668 -113.004411) (xy 169.304622 -113.052579) (xy 169.328407 -113.104661)
			(xy 169.344537 -113.159598) (xy 169.352686 -113.216272) (xy 169.352686 -113.273528) (xy 169.344537 -113.330202)
			(xy 169.328407 -113.385139) (xy 169.304622 -113.437221) (xy 169.273668 -113.485389) (xy 169.236174 -113.528661)
			(xy 169.192903 -113.566157) (xy 169.144737 -113.597114) (xy 169.092656 -113.620901) (xy 169.037719 -113.637034)
			(xy 168.981046 -113.645184) (xy 168.952418 -113.645696) (xy 168.924103 -113.64527) (xy 168.868037 -113.637307)
			(xy 168.813648 -113.621536) (xy 168.762018 -113.59827) (xy 168.714175 -113.567974) (xy 168.671069 -113.531248)
			(xy 168.633557 -113.488824) (xy 168.602387 -113.441545) (xy 168.578177 -113.390352) (xy 168.561409 -113.336262)
			(xy 168.556432 -113.308384) (xy 168.554908 -113.29797) (xy 168.543732 -113.28019) (xy 168.474644 -113.232692)
			(xy 168.465936 -113.227309) (xy 168.445895 -113.223232) (xy 168.435782 -113.224818) (xy 168.435528 -113.224818)
			(xy 168.412607 -113.229243) (xy 168.366161 -113.233952) (xy 168.342818 -113.234216) (xy 168.315436 -113.233836)
			(xy 168.26106 -113.227345) (xy 168.23436 -113.221262) (xy 168.223946 -113.218722) (xy 168.203372 -113.222278)
			(xy 168.122854 -113.275872) (xy 168.111424 -113.293652) (xy 168.1099 -113.30432) (xy 168.105248 -113.330925)
			(xy 168.089415 -113.382562) (xy 168.066459 -113.431452) (xy 168.036841 -113.476616) (xy 168.001151 -113.517154)
			(xy 167.960102 -113.552255) (xy 167.914514 -113.581218) (xy 167.865299 -113.603464) (xy 167.813438 -113.61855)
			(xy 167.759969 -113.626174) (xy 167.732964 -113.626646) (xy 167.705717 -113.626081) (xy 167.651779 -113.618321)
			(xy 167.599494 -113.602965) (xy 167.549926 -113.580324) (xy 167.504085 -113.55086) (xy 167.462903 -113.515172)
			(xy 167.427219 -113.473986) (xy 167.397759 -113.428142) (xy 167.375123 -113.378573) (xy 167.359771 -113.326286)
			(xy 167.352016 -113.272347) (xy 167.352016 -113.217853) (xy 167.359771 -113.163914) (xy 167.375123 -113.111627)
			(xy 167.397759 -113.062058) (xy 167.427219 -113.016214) (xy 167.462903 -112.975028) (xy 167.504085 -112.93934)
			(xy 167.549926 -112.909876) (xy 167.599494 -112.887235) (xy 167.651779 -112.871879) (xy 167.705717 -112.864119)
			(xy 167.732964 -112.86363) (xy 167.750076 -112.863821) (xy 167.784163 -112.866874) (xy 167.801036 -112.869726)
			(xy 167.812364 -112.871141) (xy 167.834379 -112.86522) (xy 167.843454 -112.858296) (xy 167.867838 -112.837214)
			(xy 167.876242 -112.829215) (xy 167.885383 -112.807921) (xy 167.885364 -112.79632) (xy 167.884856 -112.776508)
			(xy 167.884856 -111.912908) (xy 167.885364 -111.893604) (xy 167.885322 -111.882013) (xy 167.87621 -111.860725)
			(xy 167.867838 -111.85271) (xy 167.843454 -111.831882) (xy 167.834443 -111.824967) (xy 167.812556 -111.81902)
			(xy 167.80129 -111.820452) (xy 167.784356 -111.823332) (xy 167.75014 -111.826384) (xy 167.732964 -111.826548)
			(xy 167.705717 -111.825979) (xy 167.651779 -111.81822) (xy 167.599494 -111.802863) (xy 167.549927 -111.780222)
			(xy 167.504086 -111.750758) (xy 167.462904 -111.71507) (xy 167.42722 -111.673885) (xy 167.397761 -111.628041)
			(xy 167.375125 -111.578472) (xy 167.359773 -111.526186) (xy 167.352018 -111.472247) (xy 167.352018 -111.417753)
			(xy 167.359773 -111.363814) (xy 167.375125 -111.311528) (xy 167.397761 -111.261959) (xy 167.42722 -111.216115)
			(xy 167.462904 -111.17493) (xy 167.504086 -111.139242) (xy 167.549927 -111.109778) (xy 167.599494 -111.087137)
			(xy 167.651779 -111.07178) (xy 167.705717 -111.064021) (xy 167.732964 -111.063532) (xy 167.759942 -111.063963)
			(xy 167.813362 -111.071553) (xy 167.865178 -111.086599) (xy 167.914354 -111.108802) (xy 167.959908 -111.137717)
			(xy 168.00093 -111.172766) (xy 168.036599 -111.21325) (xy 168.066204 -111.25836) (xy 168.089151 -111.307193)
			(xy 168.104984 -111.358774) (xy 168.109646 -111.38535) (xy 168.109646 -111.385604) (xy 168.111856 -111.395864)
			(xy 168.12327 -111.413449) (xy 168.131744 -111.41964) (xy 168.203118 -111.467138) (xy 168.223692 -111.470694)
			(xy 168.234106 -111.468154) (xy 168.260871 -111.462072) (xy 168.315373 -111.455576) (xy 168.342818 -111.4552)
			(xy 168.36616 -111.455474) (xy 168.412606 -111.460182) (xy 168.435528 -111.464598) (xy 168.435782 -111.464598)
			(xy 168.445896 -111.466182) (xy 168.465944 -111.46212) (xy 168.474644 -111.456724) (xy 168.543986 -111.408972)
			(xy 168.554908 -111.3917) (xy 168.556432 -111.381286) (xy 168.561426 -111.353402) (xy 168.578166 -111.299287)
			(xy 168.602356 -111.248067) (xy 168.633513 -111.20076) (xy 168.671018 -111.158309) (xy 168.714123 -111.121559)
			(xy 168.761972 -111.091241) (xy 168.813612 -111.067959) (xy 168.868014 -111.052176) (xy 168.924095 -111.044207)
			(xy 168.952418 -111.04372) (xy 168.981788 -111.044238) (xy 169.039895 -111.052839) (xy 169.096125 -111.069826)
			(xy 169.149276 -111.094834) (xy 169.19821 -111.127329) (xy 169.220388 -111.14659) (xy 169.22757 -111.15248)
			(xy 169.244892 -111.159135) (xy 169.25417 -111.159544) (xy 169.285666 -111.159544) (xy 169.294937 -111.159095)
			(xy 169.312256 -111.152457) (xy 169.319448 -111.14659) (xy 169.341631 -111.127336) (xy 169.390567 -111.094849)
			(xy 169.443717 -111.069845) (xy 169.499945 -111.052859) (xy 169.558049 -111.044253) (xy 169.587418 -111.04372)
			(xy 169.604459 -111.043912) (xy 169.638414 -111.046833) (xy 169.655236 -111.049562) (xy 169.666291 -111.050937)
			(xy 169.687773 -111.045133) (xy 169.696638 -111.038386) (xy 169.721022 -111.017558) (xy 169.729198 -111.009921)
			(xy 169.738543 -110.989619) (xy 169.739056 -110.978442) (xy 169.739056 -110.97641) (xy 169.739056 -110.111032)
			(xy 169.738571 -110.099851) (xy 169.729202 -110.079555) (xy 169.721022 -110.071916) (xy 169.696638 -110.051088)
			(xy 169.687769 -110.044357) (xy 169.666291 -110.03857) (xy 169.655236 -110.039912) (xy 169.638409 -110.042569)
			(xy 169.604453 -110.045363) (xy 169.587418 -110.0455) (xy 169.558061 -110.04496) (xy 169.499974 -110.036397)
			(xy 169.443753 -110.019463) (xy 169.390599 -109.994522) (xy 169.341644 -109.962105) (xy 169.319448 -109.942884)
			(xy 169.312288 -109.936963) (xy 169.29495 -109.930327) (xy 169.285666 -109.92993) (xy 169.25417 -109.92993)
			(xy 169.244896 -109.930354) (xy 169.227578 -109.93701) (xy 169.220388 -109.942884) (xy 169.198216 -109.962137)
			(xy 169.149262 -109.994568) (xy 169.096103 -110.019515) (xy 169.039875 -110.036444) (xy 168.981779 -110.044994)
			(xy 168.952418 -110.0455) (xy 168.924103 -110.045071) (xy 168.868037 -110.037108) (xy 168.813648 -110.021337)
			(xy 168.762019 -109.998072) (xy 168.714176 -109.967775) (xy 168.67107 -109.93105) (xy 168.633559 -109.888627)
			(xy 168.602388 -109.841348) (xy 168.578178 -109.790155) (xy 168.56141 -109.736066) (xy 168.556432 -109.708188)
			(xy 168.554908 -109.697774) (xy 168.543732 -109.679994) (xy 168.474644 -109.632496) (xy 168.465936 -109.627113)
			(xy 168.445895 -109.623036) (xy 168.435782 -109.624622) (xy 168.435528 -109.624622) (xy 168.412607 -109.629047)
			(xy 168.366161 -109.633756) (xy 168.342818 -109.63402) (xy 168.315436 -109.63364) (xy 168.26106 -109.627149)
			(xy 168.23436 -109.621066) (xy 168.223946 -109.618526) (xy 168.203372 -109.622082) (xy 168.122854 -109.675676)
			(xy 168.111424 -109.693456) (xy 168.1099 -109.704124) (xy 168.105251 -109.73073) (xy 168.089417 -109.782367)
			(xy 168.066461 -109.831256) (xy 168.036842 -109.87642) (xy 168.001152 -109.916958) (xy 167.960103 -109.952059)
			(xy 167.914515 -109.981022) (xy 167.865299 -110.003268) (xy 167.813439 -110.018354) (xy 167.759969 -110.025978)
			(xy 167.732964 -110.02645) (xy 167.705717 -110.025877) (xy 167.65178 -110.018118) (xy 167.599495 -110.002761)
			(xy 167.549928 -109.98012) (xy 167.504087 -109.950656) (xy 167.462906 -109.914969) (xy 167.427222 -109.873784)
			(xy 167.397762 -109.827941) (xy 167.375126 -109.778371) (xy 167.359775 -109.726085) (xy 167.35202 -109.672147)
			(xy 167.35202 -109.617653) (xy 167.359775 -109.563715) (xy 167.375126 -109.511429) (xy 167.397762 -109.461859)
			(xy 167.427222 -109.416016) (xy 167.462906 -109.374831) (xy 167.504087 -109.339144) (xy 167.549928 -109.30968)
			(xy 167.599495 -109.287039) (xy 167.65178 -109.271682) (xy 167.705717 -109.263923) (xy 167.732964 -109.263434)
			(xy 167.750076 -109.263625) (xy 167.784163 -109.266678) (xy 167.801036 -109.26953) (xy 167.812364 -109.270944)
			(xy 167.834379 -109.265024) (xy 167.843454 -109.2581) (xy 167.867838 -109.237018) (xy 167.87624 -109.229017)
			(xy 167.885383 -109.207724) (xy 167.885364 -109.196124) (xy 167.884856 -109.176312) (xy 167.884856 -108.312712)
			(xy 167.885364 -108.293408) (xy 167.88532 -108.281817) (xy 167.87621 -108.260529) (xy 167.867838 -108.252514)
			(xy 167.843454 -108.231686) (xy 167.834443 -108.224771) (xy 167.812556 -108.218824) (xy 167.80129 -108.220256)
			(xy 167.784356 -108.223136) (xy 167.75014 -108.226188) (xy 167.732964 -108.226352) (xy 167.705718 -108.225775)
			(xy 167.65178 -108.218016) (xy 167.599496 -108.202659) (xy 167.549929 -108.180019) (xy 167.504088 -108.150555)
			(xy 167.462907 -108.114867) (xy 167.427224 -108.073683) (xy 167.397764 -108.02784) (xy 167.375128 -107.978271)
			(xy 167.359777 -107.925985) (xy 167.352022 -107.872046) (xy 167.352022 -107.817554) (xy 167.359777 -107.763615)
			(xy 167.375128 -107.711329) (xy 167.397764 -107.66176) (xy 167.427224 -107.615917) (xy 167.462907 -107.574733)
			(xy 167.504088 -107.539045) (xy 167.549929 -107.509581) (xy 167.599496 -107.486941) (xy 167.65178 -107.471584)
			(xy 167.705718 -107.463825) (xy 167.732964 -107.463336) (xy 167.759942 -107.463764) (xy 167.813362 -107.471354)
			(xy 167.865178 -107.4864) (xy 167.914355 -107.508603) (xy 167.959909 -107.537518) (xy 168.000931 -107.572568)
			(xy 168.0366 -107.613053) (xy 168.066205 -107.658163) (xy 168.089152 -107.706996) (xy 168.104984 -107.758578)
			(xy 168.109646 -107.785154) (xy 168.109646 -107.785408) (xy 168.111854 -107.795669) (xy 168.123269 -107.813253)
			(xy 168.131744 -107.819444) (xy 168.203118 -107.866942) (xy 168.223692 -107.870498) (xy 168.234106 -107.867958)
			(xy 168.260871 -107.861876) (xy 168.315373 -107.85538) (xy 168.342818 -107.855004) (xy 168.36616 -107.855278)
			(xy 168.412606 -107.859986) (xy 168.435528 -107.864402) (xy 168.435782 -107.864402) (xy 168.445896 -107.865986)
			(xy 168.465944 -107.861924) (xy 168.474644 -107.856528) (xy 168.543986 -107.808776) (xy 168.554908 -107.791504)
			(xy 168.556432 -107.78109) (xy 168.561429 -107.753207) (xy 168.578169 -107.699092) (xy 168.602358 -107.647871)
			(xy 168.633514 -107.600564) (xy 168.671019 -107.558114) (xy 168.714124 -107.521363) (xy 168.761973 -107.491045)
			(xy 168.813612 -107.467763) (xy 168.868014 -107.45198) (xy 168.924095 -107.444011) (xy 168.952418 -107.443524)
			(xy 168.981788 -107.444041) (xy 169.039895 -107.452642) (xy 169.096126 -107.469629) (xy 169.149276 -107.494637)
			(xy 169.19821 -107.527133) (xy 169.220388 -107.546394) (xy 169.22757 -107.552285) (xy 169.244891 -107.558939)
			(xy 169.25417 -107.559348) (xy 169.285666 -107.559348) (xy 169.294937 -107.558898) (xy 169.312256 -107.552261)
			(xy 169.319448 -107.546394) (xy 169.341631 -107.52714) (xy 169.390567 -107.494653) (xy 169.443717 -107.469649)
			(xy 169.499945 -107.452663) (xy 169.558049 -107.444057) (xy 169.587418 -107.443524) (xy 169.604459 -107.443716)
			(xy 169.638414 -107.446637) (xy 169.655236 -107.449366) (xy 169.666291 -107.45074) (xy 169.687773 -107.444937)
			(xy 169.696638 -107.43819) (xy 169.721022 -107.417362) (xy 169.729196 -107.409723) (xy 169.738543 -107.389423)
			(xy 169.739056 -107.378246) (xy 169.739056 -107.376214) (xy 169.739056 -106.510836) (xy 169.738569 -106.499656)
			(xy 169.729202 -106.479359) (xy 169.721022 -106.47172) (xy 169.696638 -106.450892) (xy 169.687775 -106.444152)
			(xy 169.666292 -106.438374) (xy 169.655236 -106.439716) (xy 169.638409 -106.442373) (xy 169.604453 -106.445167)
			(xy 169.587418 -106.445304) (xy 169.558061 -106.444763) (xy 169.499974 -106.4362) (xy 169.443754 -106.419267)
			(xy 169.390599 -106.394326) (xy 169.341644 -106.361909) (xy 169.319448 -106.342688) (xy 169.312288 -106.336767)
			(xy 169.29495 -106.330131) (xy 169.285666 -106.329734) (xy 169.254424 -106.329734) (xy 169.245153 -106.330183)
			(xy 169.227835 -106.336822) (xy 169.220642 -106.342688) (xy 169.198463 -106.362001) (xy 169.149492 -106.394568)
			(xy 169.09629 -106.419633) (xy 169.039998 -106.436659) (xy 168.981823 -106.44528) (xy 168.952418 -106.445812)
			(xy 168.924095 -106.44534) (xy 168.868015 -106.43736) (xy 168.813615 -106.421569) (xy 168.761977 -106.398282)
			(xy 168.714129 -106.367963) (xy 168.671023 -106.331213) (xy 168.633515 -106.288765) (xy 168.602351 -106.241462)
			(xy 168.578153 -106.190245) (xy 168.5614 -106.136134) (xy 168.556432 -106.108246) (xy 168.554908 -106.097832)
			(xy 168.543732 -106.080052) (xy 168.474644 -106.032554) (xy 168.465937 -106.027168) (xy 168.445895 -106.023094)
			(xy 168.435782 -106.02468) (xy 168.435274 -106.02468) (xy 168.412423 -106.029164) (xy 168.366103 -106.033995)
			(xy 168.342818 -106.034332) (xy 168.31543 -106.033889) (xy 168.261054 -106.027267) (xy 168.23436 -106.021124)
			(xy 168.223946 -106.018584) (xy 168.203372 -106.02214) (xy 168.122854 -106.075734) (xy 168.111424 -106.093514)
			(xy 168.1099 -106.104182) (xy 168.105219 -106.130782) (xy 168.089391 -106.182419) (xy 168.06644 -106.231308)
			(xy 168.036825 -106.276474) (xy 168.001139 -106.317012) (xy 167.960093 -106.352114) (xy 167.914508 -106.381078)
			(xy 167.865294 -106.403325) (xy 167.813436 -106.418412) (xy 167.759968 -106.426036) (xy 167.732964 -106.426508)
			(xy 167.705714 -106.42602) (xy 167.651771 -106.418259) (xy 167.59948 -106.402901) (xy 167.549907 -106.380258)
			(xy 167.504062 -106.35079) (xy 167.462876 -106.315099) (xy 167.427188 -106.27391) (xy 167.397725 -106.228061)
			(xy 167.375087 -106.178486) (xy 167.359733 -106.126194) (xy 167.351978 -106.07225) (xy 167.351978 -106.01775)
			(xy 167.359733 -105.963806) (xy 167.375087 -105.911514) (xy 167.397725 -105.861939) (xy 167.427188 -105.81609)
			(xy 167.462876 -105.774901) (xy 167.504062 -105.73921) (xy 167.549907 -105.709742) (xy 167.59948 -105.687099)
			(xy 167.651771 -105.671741) (xy 167.705714 -105.66398) (xy 167.732964 -105.663492) (xy 167.750076 -105.663684)
			(xy 167.784163 -105.666736) (xy 167.801036 -105.669588) (xy 167.812364 -105.670988) (xy 167.834377 -105.665075)
			(xy 167.843454 -105.658158) (xy 167.867838 -105.637076) (xy 167.87626 -105.629093) (xy 167.885391 -105.607786)
			(xy 167.885364 -105.596182) (xy 167.884856 -105.57637) (xy 167.884856 -104.71277) (xy 167.885364 -104.693466)
			(xy 167.885344 -104.681873) (xy 167.876217 -104.660585) (xy 167.867838 -104.652572) (xy 167.843454 -104.631744)
			(xy 167.834438 -104.624835) (xy 167.812555 -104.618882) (xy 167.80129 -104.620314) (xy 167.784356 -104.623195)
			(xy 167.75014 -104.626246) (xy 167.732964 -104.62641) (xy 167.705715 -104.625918) (xy 167.651771 -104.618157)
			(xy 167.599481 -104.602799) (xy 167.549908 -104.580156) (xy 167.504063 -104.550689) (xy 167.462877 -104.514997)
			(xy 167.42719 -104.473808) (xy 167.397727 -104.42796) (xy 167.375088 -104.378385) (xy 167.359735 -104.326094)
			(xy 167.35198 -104.272149) (xy 167.35198 -104.217651) (xy 167.359735 -104.163706) (xy 167.375088 -104.111415)
			(xy 167.397727 -104.06184) (xy 167.42719 -104.015992) (xy 167.462877 -103.974803) (xy 167.504063 -103.939111)
			(xy 167.549908 -103.909644) (xy 167.599481 -103.887001) (xy 167.651771 -103.871643) (xy 167.705715 -103.863882)
			(xy 167.732964 -103.863394) (xy 167.759941 -103.863857) (xy 167.813358 -103.871446) (xy 167.865171 -103.88649)
			(xy 167.914345 -103.90869) (xy 167.959898 -103.937602) (xy 168.000919 -103.972648) (xy 168.036589 -104.013127)
			(xy 168.066195 -104.058232) (xy 168.089145 -104.107061) (xy 168.104981 -104.158638) (xy 168.109646 -104.185212)
			(xy 168.109646 -104.185466) (xy 168.111827 -104.195734) (xy 168.123262 -104.213315) (xy 168.131744 -104.219502)
			(xy 168.203118 -104.267) (xy 168.223692 -104.270556) (xy 168.234106 -104.268016) (xy 168.260865 -104.261873)
			(xy 168.315367 -104.255246) (xy 168.342818 -104.254808) (xy 168.366166 -104.255148) (xy 168.412612 -104.259981)
			(xy 168.435528 -104.26446) (xy 168.435782 -104.26446) (xy 168.445896 -104.266051) (xy 168.465945 -104.261986)
			(xy 168.474644 -104.256586) (xy 168.543986 -104.208834) (xy 168.554908 -104.191562) (xy 168.556432 -104.181148)
			(xy 168.561417 -104.153274) (xy 168.578191 -104.099192) (xy 168.602405 -104.048007) (xy 168.633578 -104.000736)
			(xy 168.67109 -103.95832) (xy 168.714195 -103.921602) (xy 168.762035 -103.891312) (xy 168.813661 -103.868052)
			(xy 168.868045 -103.852284) (xy 168.924106 -103.844322) (xy 168.952418 -103.843836) (xy 168.981775 -103.84437)
			(xy 169.039862 -103.852938) (xy 169.096082 -103.869873) (xy 169.149236 -103.894815) (xy 169.198191 -103.927232)
			(xy 169.220388 -103.946452) (xy 169.227564 -103.95235) (xy 169.24489 -103.958999) (xy 169.25417 -103.959406)
			(xy 169.285666 -103.959406) (xy 169.294935 -103.958942) (xy 169.312253 -103.952313) (xy 169.319448 -103.946452)
			(xy 169.34165 -103.927235) (xy 169.390595 -103.894798) (xy 169.443746 -103.869843) (xy 169.499968 -103.852906)
			(xy 169.558059 -103.844347) (xy 169.587418 -103.843836) (xy 169.604454 -103.843958) (xy 169.63841 -103.846757)
			(xy 169.655236 -103.849424) (xy 169.666291 -103.850785) (xy 169.68777 -103.844988) (xy 169.696638 -103.838248)
			(xy 169.721022 -103.81742) (xy 169.72917 -103.809757) (xy 169.738531 -103.789475) (xy 169.739056 -103.778304)
			(xy 169.739056 -103.776272) (xy 169.739056 -102.910894) (xy 169.738536 -102.899717) (xy 169.729192 -102.87942)
			(xy 169.721022 -102.871778) (xy 169.696638 -102.85095) (xy 169.687771 -102.844215) (xy 169.666291 -102.838432)
			(xy 169.655236 -102.839774) (xy 169.638413 -102.84249) (xy 169.604458 -102.845413) (xy 169.587418 -102.845616)
			(xy 169.558049 -102.845068) (xy 169.499944 -102.836472) (xy 169.443714 -102.819493) (xy 169.390563 -102.794491)
			(xy 169.341628 -102.762004) (xy 169.319448 -102.742746) (xy 169.312292 -102.73682) (xy 169.29495 -102.730188)
			(xy 169.285666 -102.729792) (xy 169.254424 -102.729792) (xy 169.245154 -102.730251) (xy 169.227837 -102.736884)
			(xy 169.220642 -102.742746) (xy 169.198434 -102.76201) (xy 169.149454 -102.794522) (xy 169.096253 -102.819536)
			(xy 169.03997 -102.836517) (xy 168.981812 -102.8451) (xy 168.952418 -102.845616) (xy 168.924104 -102.845174)
			(xy 168.868039 -102.837211) (xy 168.813651 -102.82144) (xy 168.762023 -102.798176) (xy 168.71418 -102.767882)
			(xy 168.671074 -102.731158) (xy 168.633563 -102.688736) (xy 168.602391 -102.64146) (xy 168.57818 -102.590269)
			(xy 168.561411 -102.536181) (xy 168.556432 -102.508304) (xy 168.554908 -102.49789) (xy 168.543732 -102.48011)
			(xy 168.474644 -102.432612) (xy 168.465935 -102.42723) (xy 168.445894 -102.423152) (xy 168.435782 -102.424738)
			(xy 168.435528 -102.424738) (xy 168.412607 -102.429163) (xy 168.366161 -102.433872) (xy 168.342818 -102.434136)
			(xy 168.315436 -102.433755) (xy 168.26106 -102.427265) (xy 168.23436 -102.421182) (xy 168.223946 -102.418642)
			(xy 168.203372 -102.422198) (xy 168.122854 -102.475792) (xy 168.111424 -102.493572) (xy 168.1099 -102.50424)
			(xy 168.105187 -102.530834) (xy 168.089364 -102.582471) (xy 168.066418 -102.631361) (xy 168.036808 -102.676527)
			(xy 168.001126 -102.717066) (xy 167.960083 -102.752169) (xy 167.914501 -102.781134) (xy 167.86529 -102.803382)
			(xy 167.813433 -102.818469) (xy 167.759967 -102.826093) (xy 167.732964 -102.826566) (xy 167.705711 -102.826162)
			(xy 167.651762 -102.8184) (xy 167.599465 -102.80304) (xy 167.549887 -102.780395) (xy 167.504036 -102.750924)
			(xy 167.462846 -102.715229) (xy 167.427154 -102.674035) (xy 167.397688 -102.628181) (xy 167.375047 -102.578601)
			(xy 167.359692 -102.526303) (xy 167.351936 -102.472353) (xy 163.529404 -102.472353) (xy 163.580982 -102.485837)
			(xy 163.632311 -102.507649) (xy 163.679917 -102.536703) (xy 163.722785 -102.572378) (xy 163.760002 -102.613915)
			(xy 163.790775 -102.660428) (xy 163.814447 -102.710925) (xy 163.830515 -102.764332) (xy 163.838635 -102.819508)
			(xy 163.839144 -102.847394) (xy 163.838635 -102.87528) (xy 163.830515 -102.930456) (xy 163.814447 -102.983863)
			(xy 163.790775 -103.03436) (xy 163.760002 -103.080873) (xy 163.722785 -103.12241) (xy 163.679917 -103.158085)
			(xy 163.632311 -103.187139) (xy 163.580982 -103.208951) (xy 163.527025 -103.223057) (xy 163.471588 -103.229157)
			(xy 163.415854 -103.22712) (xy 163.361011 -103.21699) (xy 163.308227 -103.198983) (xy 163.258627 -103.173482)
			(xy 163.213269 -103.141031) (xy 163.17312 -103.102322) (xy 163.139034 -103.058179) (xy 163.111738 -103.009544)
			(xy 163.091815 -102.957453) (xy 163.079689 -102.903016) (xy 163.075618 -102.847394) (xy 154.880704 -102.847394)
			(xy 154.877924 -102.856862) (xy 154.854133 -102.908952) (xy 154.823171 -102.957126) (xy 154.785667 -103.000402)
			(xy 154.742386 -103.037901) (xy 154.694208 -103.068857) (xy 154.642115 -103.092641) (xy 154.587167 -103.108769)
			(xy 154.530483 -103.116913) (xy 154.50185 -103.117396) (xy 154.486936 -103.117287) (xy 154.457187 -103.115126)
			(xy 154.442414 -103.113078) (xy 154.431238 -103.1113) (xy 154.410156 -103.117396) (xy 154.343354 -103.175054)
			(xy 154.335401 -103.182658) (xy 154.32631 -103.20267) (xy 154.325828 -103.213662) (xy 154.325828 -103.47833)
			(xy 154.326308 -103.489322) (xy 154.3354 -103.509335) (xy 154.343354 -103.516938) (xy 154.410156 -103.574596)
			(xy 154.431238 -103.580692) (xy 154.442414 -103.578914) (xy 154.457187 -103.576869) (xy 154.486936 -103.574706)
			(xy 154.50185 -103.574596) (xy 154.530485 -103.575063) (xy 154.587172 -103.583207) (xy 154.642123 -103.599336)
			(xy 154.694219 -103.623122) (xy 154.7424 -103.65408) (xy 154.785684 -103.691581) (xy 154.82319 -103.73486)
			(xy 154.854154 -103.783037) (xy 154.877946 -103.83513) (xy 154.894082 -103.890079) (xy 154.902233 -103.946765)
			(xy 154.902233 -104.004035) (xy 154.894082 -104.060721) (xy 154.877946 -104.11567) (xy 154.854154 -104.167763)
			(xy 154.82319 -104.21594) (xy 154.798091 -104.244902) (xy 160.769552 -104.244902) (xy 160.773623 -104.18928)
			(xy 160.785749 -104.134843) (xy 160.805672 -104.082752) (xy 160.832968 -104.034117) (xy 160.867054 -103.989974)
			(xy 160.907203 -103.951265) (xy 160.952561 -103.918814) (xy 161.002161 -103.893313) (xy 161.054945 -103.875306)
			(xy 161.109788 -103.865176) (xy 161.165522 -103.863139) (xy 161.220959 -103.869239) (xy 161.274916 -103.883345)
			(xy 161.326245 -103.905157) (xy 161.373851 -103.934211) (xy 161.416719 -103.969886) (xy 161.453936 -104.011423)
			(xy 161.484709 -104.057936) (xy 161.508381 -104.108433) (xy 161.524449 -104.16184) (xy 161.532569 -104.217016)
			(xy 161.533078 -104.244902) (xy 161.532569 -104.272788) (xy 161.524449 -104.327964) (xy 161.508381 -104.381371)
			(xy 161.484709 -104.431868) (xy 161.453936 -104.478381) (xy 161.416719 -104.519918) (xy 161.373851 -104.555593)
			(xy 161.326245 -104.584647) (xy 161.274916 -104.606459) (xy 161.220959 -104.620565) (xy 161.165522 -104.626665)
			(xy 161.109788 -104.624628) (xy 161.054945 -104.614498) (xy 161.002161 -104.596491) (xy 160.952561 -104.57099)
			(xy 160.907203 -104.538539) (xy 160.867054 -104.49983) (xy 160.832968 -104.455687) (xy 160.805672 -104.407052)
			(xy 160.785749 -104.354961) (xy 160.773623 -104.300524) (xy 160.769552 -104.244902) (xy 154.798091 -104.244902)
			(xy 154.785684 -104.259219) (xy 154.7424 -104.29672) (xy 154.694219 -104.327678) (xy 154.642123 -104.351464)
			(xy 154.587172 -104.367593) (xy 154.530485 -104.375737) (xy 154.50185 -104.37622) (xy 154.47448 -104.375738)
			(xy 154.420248 -104.368299) (xy 154.367532 -104.353551) (xy 154.317312 -104.331769) (xy 154.270523 -104.303359)
			(xy 154.228032 -104.268847) (xy 154.190632 -104.228877) (xy 154.174444 -104.206802) (xy 154.1689 -104.199525)
			(xy 154.153778 -104.18925) (xy 154.14498 -104.186736) (xy 154.115008 -104.17937) (xy 154.106057 -104.177625)
			(xy 154.087969 -104.179839) (xy 154.079702 -104.183688) (xy 154.0551 -104.196057) (xy 154.003563 -104.215456)
			(xy 153.950073 -104.228536) (xy 153.8954 -104.235109) (xy 153.867866 -104.235504) (xy 153.840332 -104.235118)
			(xy 153.785657 -104.22855) (xy 153.732167 -104.215466) (xy 153.680634 -104.196053) (xy 153.65603 -104.183688)
			(xy 153.647765 -104.179825) (xy 153.629673 -104.177601) (xy 153.620724 -104.17937) (xy 153.590752 -104.186736)
			(xy 153.581966 -104.189267) (xy 153.566868 -104.199558) (xy 153.561288 -104.206802) (xy 153.545125 -104.228896)
			(xy 153.507718 -104.268864) (xy 153.465222 -104.303373) (xy 153.418429 -104.331783) (xy 153.368206 -104.353564)
			(xy 153.315488 -104.368313) (xy 153.261253 -104.375756) (xy 153.233882 -104.37622) (xy 153.205253 -104.375692)
			(xy 153.148579 -104.367541) (xy 153.093641 -104.351408) (xy 153.041559 -104.327621) (xy 152.993392 -104.296664)
			(xy 152.95012 -104.259167) (xy 152.912626 -104.215894) (xy 152.881671 -104.167725) (xy 152.857886 -104.115642)
			(xy 152.841755 -104.060703) (xy 152.833606 -104.004029) (xy 152.833606 -103.946771) (xy 152.841755 -103.890097)
			(xy 152.857886 -103.835158) (xy 152.881671 -103.783075) (xy 152.912626 -103.734906) (xy 152.95012 -103.691633)
			(xy 152.993392 -103.654136) (xy 153.041559 -103.623179) (xy 153.093641 -103.599392) (xy 153.148579 -103.583259)
			(xy 153.205253 -103.575108) (xy 153.233882 -103.574596) (xy 153.248796 -103.574702) (xy 153.278545 -103.576865)
			(xy 153.293318 -103.578914) (xy 153.304494 -103.580692) (xy 153.325576 -103.574596) (xy 153.392378 -103.516938)
			(xy 153.40034 -103.509342) (xy 153.409425 -103.489324) (xy 153.409904 -103.47833) (xy 153.409904 -103.213662)
			(xy 153.409418 -103.202671) (xy 153.400329 -103.182659) (xy 153.392378 -103.175054) (xy 153.325576 -103.117396)
			(xy 153.304494 -103.1113) (xy 153.293318 -103.113078) (xy 153.278545 -103.11513) (xy 153.248796 -103.117289)
			(xy 153.233882 -103.117396) (xy 153.205252 -103.116916) (xy 153.148574 -103.108765) (xy 153.093633 -103.092631)
			(xy 153.041547 -103.068842) (xy 152.993377 -103.037883) (xy 152.950103 -103.000384) (xy 152.912606 -102.957108)
			(xy 152.88165 -102.908937) (xy 152.857863 -102.85685) (xy 152.841731 -102.801909) (xy 152.833583 -102.74523)
			(xy 91.52646 -102.74523) (xy 91.523566 -102.747318) (xy 91.519248 -102.751128) (xy 91.517724 -102.752906)
			(xy 91.517216 -102.753414) (xy 91.515438 -102.755446) (xy 91.511024 -102.76112) (xy 91.505231 -102.77427)
			(xy 91.504008 -102.781354) (xy 91.504008 -102.781862) (xy 91.5035 -102.787958) (xy 91.5035 -103.894128)
			(xy 92.213936 -103.894128) (xy 92.218007 -103.838506) (xy 92.230133 -103.784069) (xy 92.250056 -103.731978)
			(xy 92.277352 -103.683343) (xy 92.311438 -103.6392) (xy 92.351587 -103.600491) (xy 92.396945 -103.56804)
			(xy 92.446545 -103.542539) (xy 92.499329 -103.524532) (xy 92.554172 -103.514402) (xy 92.609906 -103.512365)
			(xy 92.665343 -103.518465) (xy 92.7193 -103.532571) (xy 92.770629 -103.554383) (xy 92.818235 -103.583437)
			(xy 92.861103 -103.619112) (xy 92.89832 -103.660649) (xy 92.929093 -103.707162) (xy 92.952765 -103.757659)
			(xy 92.968833 -103.811066) (xy 92.976953 -103.866242) (xy 92.977388 -103.890064) (xy 93.23908 -103.890064)
			(xy 93.243151 -103.834442) (xy 93.255277 -103.780005) (xy 93.2752 -103.727914) (xy 93.302496 -103.679279)
			(xy 93.336582 -103.635136) (xy 93.376731 -103.596427) (xy 93.422089 -103.563976) (xy 93.471689 -103.538475)
			(xy 93.524473 -103.520468) (xy 93.579316 -103.510338) (xy 93.63505 -103.508301) (xy 93.690487 -103.514401)
			(xy 93.744444 -103.528507) (xy 93.795773 -103.550319) (xy 93.843379 -103.579373) (xy 93.886247 -103.615048)
			(xy 93.923464 -103.656585) (xy 93.954237 -103.703098) (xy 93.977909 -103.753595) (xy 93.993977 -103.807002)
			(xy 94.002097 -103.862178) (xy 94.002606 -103.890064) (xy 94.002097 -103.91795) (xy 93.993977 -103.973126)
			(xy 93.979 -104.022906) (xy 95.86595 -104.022906) (xy 95.866405 -103.996591) (xy 95.873641 -103.944462)
			(xy 95.887961 -103.893818) (xy 95.909095 -103.845619) (xy 95.936644 -103.800776) (xy 95.970087 -103.760138)
			(xy 95.98914 -103.741982) (xy 95.996543 -103.734461) (xy 96.005069 -103.715181) (xy 96.00565 -103.704644)
			(xy 96.00565 -103.629968) (xy 96.005083 -103.619423) (xy 95.996573 -103.600128) (xy 95.98914 -103.59263)
			(xy 95.970095 -103.574465) (xy 95.936639 -103.533836) (xy 95.90908 -103.488997) (xy 95.88794 -103.440798)
			(xy 95.87362 -103.390153) (xy 95.866391 -103.338021) (xy 95.86595 -103.311706) (xy 95.866483 -103.284457)
			(xy 95.874238 -103.230513) (xy 95.88959 -103.178222) (xy 95.912227 -103.128647) (xy 95.941689 -103.082799)
			(xy 95.977376 -103.04161) (xy 96.01856 -103.005918) (xy 96.064405 -102.97645) (xy 96.113977 -102.953807)
			(xy 96.166266 -102.938448) (xy 96.220209 -102.930687) (xy 96.247458 -102.930198) (xy 96.275122 -102.930744)
			(xy 96.329869 -102.938737) (xy 96.38289 -102.954548) (xy 96.433074 -102.977846) (xy 96.47937 -103.008142)
			(xy 96.520809 -103.044802) (xy 96.556524 -103.087059) (xy 96.571562 -103.110284) (xy 96.578207 -103.119953)
			(xy 96.598063 -103.1324) (xy 96.609662 -103.13416) (xy 96.689672 -103.142034) (xy 96.70131 -103.142646)
			(xy 96.723146 -103.13458) (xy 96.731582 -103.12654) (xy 96.731836 -103.126286) (xy 96.749915 -103.107703)
			(xy 96.790247 -103.075125) (xy 96.834622 -103.048312) (xy 96.882221 -103.02776) (xy 96.932166 -103.013847)
			(xy 96.983535 -103.00683) (xy 97.009458 -103.006398) (xy 97.03671 -103.006894) (xy 97.09066 -103.014646)
			(xy 97.142958 -103.029997) (xy 97.192538 -103.052635) (xy 97.238392 -103.082099) (xy 97.279585 -103.117789)
			(xy 97.315279 -103.158979) (xy 97.344748 -103.20483) (xy 97.367391 -103.254408) (xy 97.382747 -103.306705)
			(xy 97.390503 -103.360654) (xy 97.390966 -103.387906) (xy 97.390512 -103.415277) (xy 97.382692 -103.469457)
			(xy 97.367201 -103.52196) (xy 97.344356 -103.571707) (xy 97.314629 -103.617673) (xy 97.296986 -103.638604)
			(xy 97.296732 -103.638858) (xy 97.291149 -103.645947) (xy 97.284902 -103.662862) (xy 97.28454 -103.671878)
			(xy 97.28454 -103.738934) (xy 97.284872 -103.747954) (xy 97.291136 -103.764871) (xy 97.296732 -103.771954)
			(xy 97.296986 -103.771954) (xy 97.296986 -103.772208) (xy 97.31464 -103.793128) (xy 97.34435 -103.839104)
			(xy 97.367183 -103.888854) (xy 97.382671 -103.941358) (xy 97.390495 -103.995536) (xy 97.390966 -104.022906)
			(xy 97.39055 -104.050161) (xy 97.382791 -104.104116) (xy 97.379414 -104.115616) (xy 100.297234 -104.115616)
			(xy 100.297701 -104.089302) (xy 100.304935 -104.037173) (xy 100.319253 -103.98653) (xy 100.340385 -103.938331)
			(xy 100.367932 -103.893487) (xy 100.401372 -103.852848) (xy 100.420424 -103.834692) (xy 100.42782 -103.827165)
			(xy 100.43635 -103.80789) (xy 100.436934 -103.797354) (xy 100.436934 -103.722678) (xy 100.436366 -103.712133)
			(xy 100.427857 -103.692838) (xy 100.420424 -103.68534) (xy 100.401351 -103.667202) (xy 100.367894 -103.626569)
			(xy 100.340337 -103.581725) (xy 100.319202 -103.533521) (xy 100.304888 -103.48287) (xy 100.297669 -103.430733)
			(xy 100.297234 -103.404416) (xy 100.29772 -103.377165) (xy 100.305476 -103.323217) (xy 100.320831 -103.270922)
			(xy 100.343473 -103.221345) (xy 100.372939 -103.175495) (xy 100.40863 -103.134304) (xy 100.449821 -103.098613)
			(xy 100.495671 -103.069147) (xy 100.545248 -103.046505) (xy 100.597543 -103.03115) (xy 100.651491 -103.023394)
			(xy 100.705993 -103.023394) (xy 100.759941 -103.03115) (xy 100.812236 -103.046505) (xy 100.861813 -103.069147)
			(xy 100.907663 -103.098613) (xy 100.948854 -103.134304) (xy 100.984545 -103.175495) (xy 101.014011 -103.221345)
			(xy 101.036653 -103.270922) (xy 101.052008 -103.323217) (xy 101.059764 -103.377165) (xy 101.06025 -103.404416)
			(xy 101.059809 -103.430731) (xy 101.052571 -103.482861) (xy 101.038248 -103.533505) (xy 101.017111 -103.581704)
			(xy 100.989559 -103.626547) (xy 100.956115 -103.667185) (xy 100.93706 -103.68534) (xy 100.929648 -103.692853)
			(xy 100.921127 -103.712139) (xy 100.920683 -103.720253) (xy 103.573038 -103.720253) (xy 103.573038 -103.665747)
			(xy 103.580794 -103.611796) (xy 103.59615 -103.559498) (xy 103.618791 -103.509918) (xy 103.648258 -103.464064)
			(xy 103.68395 -103.42287) (xy 103.725141 -103.387175) (xy 103.770993 -103.357705) (xy 103.820572 -103.33506)
			(xy 103.872869 -103.3197) (xy 103.926819 -103.31194) (xy 103.954072 -103.311452) (xy 103.981442 -103.311922)
			(xy 104.035622 -103.319737) (xy 104.088125 -103.335224) (xy 104.137872 -103.358066) (xy 104.183839 -103.38779)
			(xy 104.20477 -103.405432) (xy 104.205024 -103.405686) (xy 104.212101 -103.411287) (xy 104.229025 -103.417526)
			(xy 104.238044 -103.417878) (xy 104.3051 -103.417878) (xy 104.314117 -103.417526) (xy 104.331035 -103.411276)
			(xy 104.33812 -103.405686) (xy 104.33812 -103.405432) (xy 104.338374 -103.405432) (xy 104.359307 -103.387791)
			(xy 104.405275 -103.358067) (xy 104.455021 -103.335221) (xy 104.507523 -103.319725) (xy 104.561701 -103.311896)
			(xy 104.616443 -103.311896) (xy 104.670621 -103.319725) (xy 104.723123 -103.335221) (xy 104.772869 -103.358067)
			(xy 104.818837 -103.387791) (xy 104.83977 -103.405432) (xy 104.840024 -103.405686) (xy 104.847101 -103.411287)
			(xy 104.864025 -103.417526) (xy 104.873044 -103.417878) (xy 104.9401 -103.417878) (xy 104.949117 -103.417526)
			(xy 104.966035 -103.411276) (xy 104.97312 -103.405686) (xy 104.97312 -103.405432) (xy 104.973374 -103.405432)
			(xy 104.994309 -103.387797) (xy 105.040281 -103.358083) (xy 105.090027 -103.335246) (xy 105.142527 -103.319754)
			(xy 105.196703 -103.311926) (xy 105.224072 -103.311452) (xy 105.251323 -103.311993) (xy 105.305272 -103.319746)
			(xy 105.357567 -103.335098) (xy 105.407146 -103.357737) (xy 105.452998 -103.387201) (xy 105.494189 -103.422891)
			(xy 105.529882 -103.46408) (xy 105.55935 -103.50993) (xy 105.581992 -103.559506) (xy 105.597348 -103.611801)
			(xy 105.605105 -103.665749) (xy 105.605105 -103.68565) (xy 108.492794 -103.68565) (xy 108.492794 -103.63115)
			(xy 108.50055 -103.577205) (xy 108.515905 -103.524912) (xy 108.538545 -103.475338) (xy 108.56801 -103.429489)
			(xy 108.603699 -103.388301) (xy 108.644888 -103.352611) (xy 108.690736 -103.323146) (xy 108.740311 -103.300505)
			(xy 108.792603 -103.285151) (xy 108.846548 -103.277394) (xy 108.873798 -103.276908) (xy 108.900112 -103.277374)
			(xy 108.952241 -103.284609) (xy 109.002884 -103.298928) (xy 109.051083 -103.320061) (xy 109.095926 -103.347607)
			(xy 109.136566 -103.381046) (xy 109.154722 -103.400098) (xy 109.162234 -103.407511) (xy 109.181521 -103.416029)
			(xy 109.19206 -103.416608) (xy 109.266736 -103.416608) (xy 109.277283 -103.416056) (xy 109.296579 -103.407537)
			(xy 109.304074 -103.400098) (xy 109.323894 -103.37931) (xy 109.368666 -103.343335) (xy 109.418324 -103.314475)
			(xy 109.471746 -103.293382) (xy 109.527725 -103.280533) (xy 109.584998 -103.276218) (xy 109.642271 -103.280533)
			(xy 109.69825 -103.293382) (xy 109.751672 -103.314475) (xy 109.80133 -103.343335) (xy 109.846102 -103.37931)
			(xy 109.865922 -103.400098) (xy 109.873434 -103.407511) (xy 109.892721 -103.416029) (xy 109.90326 -103.416608)
			(xy 109.977936 -103.416608) (xy 109.988483 -103.416056) (xy 110.007779 -103.407537) (xy 110.015274 -103.400098)
			(xy 110.033449 -103.381062) (xy 110.074074 -103.347603) (xy 110.118911 -103.320041) (xy 110.167108 -103.2989)
			(xy 110.217752 -103.284578) (xy 110.269883 -103.277349) (xy 110.296198 -103.276908) (xy 110.323452 -103.277339)
			(xy 110.377406 -103.285096) (xy 110.429706 -103.300452) (xy 110.479288 -103.323096) (xy 110.525144 -103.352565)
			(xy 110.566338 -103.38826) (xy 110.602034 -103.429455) (xy 110.631503 -103.47531) (xy 110.654147 -103.524892)
			(xy 110.669504 -103.577192) (xy 110.677261 -103.631146) (xy 110.677261 -103.685654) (xy 110.669504 -103.739608)
			(xy 110.654147 -103.791908) (xy 110.631503 -103.84149) (xy 110.602034 -103.887345) (xy 110.566338 -103.92854)
			(xy 110.525144 -103.964235) (xy 110.479288 -103.993704) (xy 110.429706 -104.016348) (xy 110.377406 -104.031704)
			(xy 110.323452 -104.039461) (xy 110.296198 -104.039924) (xy 110.269884 -104.03945) (xy 110.217756 -104.032216)
			(xy 110.167114 -104.017897) (xy 110.118915 -103.996766) (xy 110.074072 -103.969221) (xy 110.033431 -103.935785)
			(xy 110.015274 -103.916734) (xy 110.00776 -103.909324) (xy 109.988474 -103.900803) (xy 109.977936 -103.900224)
			(xy 109.90326 -103.900224) (xy 109.892712 -103.900765) (xy 109.873416 -103.909291) (xy 109.865922 -103.916734)
			(xy 109.846102 -103.937522) (xy 109.80133 -103.973497) (xy 109.751672 -104.002357) (xy 109.69825 -104.02345)
			(xy 109.642271 -104.036299) (xy 109.584998 -104.040614) (xy 109.527725 -104.036299) (xy 109.471746 -104.02345)
			(xy 109.418324 -104.002357) (xy 109.368666 -103.973497) (xy 109.323894 -103.937522) (xy 109.304074 -103.916734)
			(xy 109.29656 -103.909324) (xy 109.277274 -103.900803) (xy 109.266736 -103.900224) (xy 109.19206 -103.900224)
			(xy 109.181512 -103.900765) (xy 109.162216 -103.909291) (xy 109.154722 -103.916734) (xy 109.136555 -103.935778)
			(xy 109.095927 -103.969235) (xy 109.051089 -103.996795) (xy 109.002891 -104.017935) (xy 108.952245 -104.032255)
			(xy 108.900113 -104.039483) (xy 108.873798 -104.039924) (xy 108.846548 -104.039406) (xy 108.792603 -104.031649)
			(xy 108.740311 -104.016295) (xy 108.690736 -103.993654) (xy 108.644888 -103.964189) (xy 108.603699 -103.928499)
			(xy 108.56801 -103.887311) (xy 108.538545 -103.841462) (xy 108.515905 -103.791888) (xy 108.50055 -103.739595)
			(xy 108.492794 -103.68565) (xy 105.605105 -103.68565) (xy 105.605105 -103.720251) (xy 105.597348 -103.774199)
			(xy 105.581992 -103.826494) (xy 105.55935 -103.87607) (xy 105.529882 -103.92192) (xy 105.494189 -103.963109)
			(xy 105.452998 -103.998799) (xy 105.407146 -104.028263) (xy 105.357567 -104.050902) (xy 105.305272 -104.066254)
			(xy 105.251323 -104.074007) (xy 105.224072 -104.074468) (xy 105.196701 -104.074026) (xy 105.14252 -104.066204)
			(xy 105.090017 -104.050709) (xy 105.04027 -104.027862) (xy 104.994305 -103.998132) (xy 104.973374 -103.980488)
			(xy 104.97312 -103.980234) (xy 104.966038 -103.974642) (xy 104.949117 -103.9684) (xy 104.9401 -103.968042)
			(xy 104.873044 -103.968042) (xy 104.864028 -103.968411) (xy 104.847111 -103.974649) (xy 104.840024 -103.980234)
			(xy 104.83977 -103.980488) (xy 104.818837 -103.998129) (xy 104.772869 -104.027853) (xy 104.723123 -104.050699)
			(xy 104.670621 -104.066195) (xy 104.616443 -104.074024) (xy 104.561701 -104.074024) (xy 104.507523 -104.066195)
			(xy 104.455021 -104.050699) (xy 104.405275 -104.027853) (xy 104.359307 -103.998129) (xy 104.338374 -103.980488)
			(xy 104.33812 -103.980234) (xy 104.331038 -103.974642) (xy 104.314117 -103.9684) (xy 104.3051 -103.968042)
			(xy 104.238044 -103.968042) (xy 104.229028 -103.968411) (xy 104.212111 -103.974649) (xy 104.205024 -103.980234)
			(xy 104.205024 -103.980488) (xy 104.20477 -103.980488) (xy 104.183821 -103.998106) (xy 104.137853 -104.027821)
			(xy 104.08811 -104.050662) (xy 104.035613 -104.066158) (xy 103.98144 -104.073991) (xy 103.954072 -104.074468)
			(xy 103.926819 -104.07406) (xy 103.872869 -104.0663) (xy 103.820572 -104.05094) (xy 103.770993 -104.028295)
			(xy 103.725141 -103.998825) (xy 103.68395 -103.96313) (xy 103.648258 -103.921936) (xy 103.618791 -103.876082)
			(xy 103.59615 -103.826502) (xy 103.580794 -103.774204) (xy 103.573038 -103.720253) (xy 100.920683 -103.720253)
			(xy 100.92055 -103.722678) (xy 100.92055 -103.797354) (xy 100.921105 -103.8079) (xy 100.929624 -103.827195)
			(xy 100.93706 -103.834692) (xy 100.956116 -103.852847) (xy 100.989571 -103.893478) (xy 101.017128 -103.938319)
			(xy 101.038266 -103.98652) (xy 101.052584 -104.037167) (xy 101.05981 -104.0893) (xy 101.06025 -104.115616)
			(xy 101.059764 -104.142867) (xy 101.052008 -104.196815) (xy 101.036653 -104.24911) (xy 101.014011 -104.298687)
			(xy 100.984545 -104.344537) (xy 100.948854 -104.385728) (xy 100.907663 -104.421419) (xy 100.861813 -104.450885)
			(xy 100.812236 -104.473527) (xy 100.759941 -104.488882) (xy 100.705993 -104.496638) (xy 100.651491 -104.496638)
			(xy 100.597543 -104.488882) (xy 100.545248 -104.473527) (xy 100.495671 -104.450885) (xy 100.449821 -104.421419)
			(xy 100.40863 -104.385728) (xy 100.372939 -104.344537) (xy 100.343473 -104.298687) (xy 100.320831 -104.24911)
			(xy 100.305476 -104.196815) (xy 100.29772 -104.142867) (xy 100.297234 -104.115616) (xy 97.379414 -104.115616)
			(xy 97.367432 -104.156417) (xy 97.344786 -104.206) (xy 97.315314 -104.251855) (xy 97.279615 -104.293049)
			(xy 97.238417 -104.328742) (xy 97.192558 -104.358209) (xy 97.142972 -104.380849) (xy 97.090669 -104.396201)
			(xy 97.036713 -104.403954) (xy 97.009458 -104.404414) (xy 96.980541 -104.403886) (xy 96.923369 -104.395164)
			(xy 96.868169 -104.37791) (xy 96.816206 -104.35252) (xy 96.768673 -104.319576) (xy 96.726657 -104.279834)
			(xy 96.708468 -104.257348) (xy 96.700874 -104.248527) (xy 96.679963 -104.238353) (xy 96.668336 -104.23779)
			(xy 96.58858 -104.23779) (xy 96.576949 -104.238336) (xy 96.55604 -104.24852) (xy 96.548448 -104.257348)
			(xy 96.530242 -104.279818) (xy 96.488224 -104.319552) (xy 96.440692 -104.352491) (xy 96.388734 -104.377882)
			(xy 96.333539 -104.395141) (xy 96.276373 -104.403876) (xy 96.247458 -104.404414) (xy 96.220206 -104.403961)
			(xy 96.166257 -104.396199) (xy 96.113962 -104.380839) (xy 96.064385 -104.358193) (xy 96.018536 -104.328723)
			(xy 95.977346 -104.293029) (xy 95.941655 -104.251836) (xy 95.912189 -104.205983) (xy 95.889548 -104.156404)
			(xy 95.874193 -104.104107) (xy 95.866436 -104.050158) (xy 95.86595 -104.022906) (xy 93.979 -104.022906)
			(xy 93.977909 -104.026533) (xy 93.954237 -104.07703) (xy 93.923464 -104.123543) (xy 93.886247 -104.16508)
			(xy 93.843379 -104.200755) (xy 93.795773 -104.229809) (xy 93.744444 -104.251621) (xy 93.690487 -104.265727)
			(xy 93.63505 -104.271827) (xy 93.579316 -104.26979) (xy 93.524473 -104.25966) (xy 93.471689 -104.241653)
			(xy 93.422089 -104.216152) (xy 93.376731 -104.183701) (xy 93.336582 -104.144992) (xy 93.302496 -104.100849)
			(xy 93.2752 -104.052214) (xy 93.255277 -104.000123) (xy 93.243151 -103.945686) (xy 93.23908 -103.890064)
			(xy 92.977388 -103.890064) (xy 92.977462 -103.894128) (xy 92.976953 -103.922014) (xy 92.968833 -103.97719)
			(xy 92.952765 -104.030597) (xy 92.929093 -104.081094) (xy 92.89832 -104.127607) (xy 92.861103 -104.169144)
			(xy 92.818235 -104.204819) (xy 92.770629 -104.233873) (xy 92.7193 -104.255685) (xy 92.665343 -104.269791)
			(xy 92.609906 -104.275891) (xy 92.554172 -104.273854) (xy 92.499329 -104.263724) (xy 92.446545 -104.245717)
			(xy 92.396945 -104.220216) (xy 92.351587 -104.187765) (xy 92.311438 -104.149056) (xy 92.277352 -104.104913)
			(xy 92.250056 -104.056278) (xy 92.230133 -104.004187) (xy 92.218007 -103.94975) (xy 92.213936 -103.894128)
			(xy 91.5035 -103.894128) (xy 91.5035 -105.084455) (xy 95.743949 -105.084455) (xy 95.743949 -105.029945)
			(xy 95.751707 -104.975991) (xy 95.767065 -104.92369) (xy 95.78971 -104.874107) (xy 95.819181 -104.828252)
			(xy 95.854879 -104.787058) (xy 95.896076 -104.751363) (xy 95.941933 -104.721896) (xy 95.991518 -104.699255)
			(xy 96.04382 -104.683901) (xy 96.097775 -104.676147) (xy 96.12503 -104.675686) (xy 96.152401 -104.676138)
			(xy 96.20658 -104.68396) (xy 96.259083 -104.699452) (xy 96.30883 -104.722297) (xy 96.354796 -104.752024)
			(xy 96.375728 -104.769666) (xy 96.375982 -104.76992) (xy 96.383068 -104.775507) (xy 96.399985 -104.781753)
			(xy 96.409002 -104.782112) (xy 96.476058 -104.782112) (xy 96.485073 -104.781732) (xy 96.50199 -104.7755)
			(xy 96.509078 -104.76992) (xy 96.509078 -104.769666) (xy 96.509332 -104.769666) (xy 96.530265 -104.752025)
			(xy 96.576233 -104.722301) (xy 96.625979 -104.699455) (xy 96.678481 -104.683959) (xy 96.732659 -104.67613)
			(xy 96.787401 -104.67613) (xy 96.841579 -104.683959) (xy 96.894081 -104.699455) (xy 96.943827 -104.722301)
			(xy 96.989795 -104.752025) (xy 97.010728 -104.769666) (xy 97.010982 -104.76992) (xy 97.018068 -104.775507)
			(xy 97.034985 -104.781753) (xy 97.044002 -104.782112) (xy 97.111058 -104.782112) (xy 97.120073 -104.781732)
			(xy 97.13699 -104.7755) (xy 97.144078 -104.76992) (xy 97.144078 -104.769666) (xy 97.144332 -104.769666)
			(xy 97.165265 -104.752025) (xy 97.211233 -104.722301) (xy 97.260979 -104.699455) (xy 97.313481 -104.683959)
			(xy 97.367659 -104.67613) (xy 97.422401 -104.67613) (xy 97.476579 -104.683959) (xy 97.529081 -104.699455)
			(xy 97.578827 -104.722301) (xy 97.624795 -104.752025) (xy 97.645728 -104.769666) (xy 97.645982 -104.76992)
			(xy 97.653068 -104.775507) (xy 97.669985 -104.781753) (xy 97.679002 -104.782112) (xy 97.746058 -104.782112)
			(xy 97.755073 -104.781732) (xy 97.77199 -104.7755) (xy 97.779078 -104.76992) (xy 97.779078 -104.769666)
			(xy 97.779332 -104.769666) (xy 97.800275 -104.75204) (xy 97.846245 -104.722327) (xy 97.89599 -104.699489)
			(xy 97.948488 -104.683995) (xy 98.002662 -104.676163) (xy 98.03003 -104.675686) (xy 98.057279 -104.676186)
			(xy 98.111223 -104.683946) (xy 98.163513 -104.699303) (xy 98.213086 -104.721946) (xy 98.258932 -104.751412)
			(xy 98.300118 -104.787103) (xy 98.335806 -104.828292) (xy 98.365269 -104.87414) (xy 98.387907 -104.923715)
			(xy 98.403261 -104.976006) (xy 98.411016 -105.029951) (xy 98.411016 -105.084449) (xy 98.411015 -105.084454)
			(xy 99.667749 -105.084454) (xy 99.667749 -105.029946) (xy 99.675507 -104.975992) (xy 99.690864 -104.923692)
			(xy 99.713509 -104.874109) (xy 99.742979 -104.828254) (xy 99.778676 -104.78706) (xy 99.819872 -104.751366)
			(xy 99.865729 -104.721898) (xy 99.915312 -104.699257) (xy 99.967614 -104.683902) (xy 100.021568 -104.676148)
			(xy 100.048822 -104.675686) (xy 100.075136 -104.676143) (xy 100.127265 -104.683381) (xy 100.177908 -104.697702)
			(xy 100.226107 -104.718837) (xy 100.27095 -104.746384) (xy 100.311589 -104.779824) (xy 100.329746 -104.798876)
			(xy 100.337252 -104.806296) (xy 100.356544 -104.814811) (xy 100.367084 -104.815386) (xy 100.44176 -104.815386)
			(xy 100.452309 -104.814853) (xy 100.471605 -104.806321) (xy 100.479098 -104.798876) (xy 100.497257 -104.779824)
			(xy 100.537886 -104.746367) (xy 100.582726 -104.718808) (xy 100.630926 -104.69767) (xy 100.681573 -104.683351)
			(xy 100.733706 -104.676125) (xy 100.760022 -104.675686) (xy 100.787393 -104.676143) (xy 100.841572 -104.683963)
			(xy 100.894075 -104.699455) (xy 100.943822 -104.722298) (xy 100.989788 -104.752024) (xy 101.01072 -104.769666)
			(xy 101.010974 -104.76992) (xy 101.018062 -104.775504) (xy 101.034978 -104.781752) (xy 101.043994 -104.782112)
			(xy 101.11105 -104.782112) (xy 101.120064 -104.781729) (xy 101.136981 -104.775499) (xy 101.14407 -104.76992)
			(xy 101.14407 -104.769666) (xy 101.144324 -104.769666) (xy 101.165257 -104.752025) (xy 101.211225 -104.722301)
			(xy 101.260971 -104.699455) (xy 101.313473 -104.683959) (xy 101.367651 -104.67613) (xy 101.422393 -104.67613)
			(xy 101.476571 -104.683959) (xy 101.529073 -104.699455) (xy 101.578819 -104.722301) (xy 101.624787 -104.752025)
			(xy 101.64572 -104.769666) (xy 101.645974 -104.76992) (xy 101.653062 -104.775504) (xy 101.669978 -104.781752)
			(xy 101.678994 -104.782112) (xy 101.74605 -104.782112) (xy 101.755064 -104.781729) (xy 101.771981 -104.775499)
			(xy 101.77907 -104.76992) (xy 101.77907 -104.769666) (xy 101.779324 -104.769666) (xy 101.80027 -104.752044)
			(xy 101.846239 -104.722331) (xy 101.895983 -104.699492) (xy 101.948481 -104.683997) (xy 102.002654 -104.676163)
			(xy 102.030022 -104.675686) (xy 102.057272 -104.676185) (xy 102.111216 -104.683944) (xy 102.163508 -104.699301)
			(xy 102.213081 -104.721943) (xy 102.233191 -104.734868) (xy 124.328172 -104.734868) (xy 124.332243 -104.679246)
			(xy 124.344369 -104.624809) (xy 124.364292 -104.572718) (xy 124.391588 -104.524083) (xy 124.425674 -104.47994)
			(xy 124.465823 -104.441231) (xy 124.511181 -104.40878) (xy 124.560781 -104.383279) (xy 124.613565 -104.365272)
			(xy 124.668408 -104.355142) (xy 124.724142 -104.353105) (xy 124.779579 -104.359205) (xy 124.833536 -104.373311)
			(xy 124.884865 -104.395123) (xy 124.932471 -104.424177) (xy 124.975339 -104.459852) (xy 125.012556 -104.501389)
			(xy 125.043329 -104.547902) (xy 125.045226 -104.551948) (xy 150.191231 -104.551948) (xy 150.191231 -104.494652)
			(xy 150.199384 -104.437939) (xy 150.215526 -104.382963) (xy 150.239327 -104.330844) (xy 150.270302 -104.282643)
			(xy 150.307822 -104.23934) (xy 150.351122 -104.201818) (xy 150.399322 -104.170839) (xy 150.451439 -104.147035)
			(xy 150.506413 -104.13089) (xy 150.563126 -104.122732) (xy 150.591774 -104.12222) (xy 150.619153 -104.122739)
			(xy 150.673399 -104.130202) (xy 150.726125 -104.144977) (xy 150.77635 -104.166792) (xy 150.823138 -104.195238)
			(xy 150.86562 -104.229788) (xy 150.903004 -104.269798) (xy 150.91918 -104.291892) (xy 150.924752 -104.299144)
			(xy 150.939854 -104.309433) (xy 150.948644 -104.311958) (xy 150.978616 -104.319324) (xy 150.987565 -104.321081)
			(xy 151.005656 -104.31886) (xy 151.013922 -104.315006) (xy 151.038519 -104.302611) (xy 151.090046 -104.283143)
			(xy 151.143536 -104.269996) (xy 151.198217 -104.26336) (xy 151.225758 -104.262936) (xy 151.253299 -104.263358)
			(xy 151.307979 -104.269996) (xy 151.361469 -104.283145) (xy 151.412995 -104.302614) (xy 151.437594 -104.315006)
			(xy 151.445854 -104.318881) (xy 151.46395 -104.321097) (xy 151.4729 -104.319324) (xy 151.502872 -104.311958)
			(xy 151.511648 -104.309399) (xy 151.526752 -104.299128) (xy 151.532336 -104.291892) (xy 151.548477 -104.269766)
			(xy 151.585854 -104.229736) (xy 151.628336 -104.19517) (xy 151.675129 -104.166712) (xy 151.725363 -104.144892)
			(xy 151.7781 -104.130118) (xy 151.832358 -104.122664) (xy 151.859742 -104.12222) (xy 151.888387 -104.122762)
			(xy 151.945094 -104.130921) (xy 152.000063 -104.147066) (xy 152.052174 -104.170869) (xy 152.100368 -104.201846)
			(xy 152.143663 -104.239366) (xy 152.181179 -104.282665) (xy 152.212151 -104.330863) (xy 152.235949 -104.382977)
			(xy 152.252088 -104.437947) (xy 152.260241 -104.494655) (xy 152.260241 -104.551945) (xy 152.252088 -104.608653)
			(xy 152.235949 -104.663623) (xy 152.212151 -104.715737) (xy 152.181179 -104.763935) (xy 152.155966 -104.793034)
			(xy 162.809934 -104.793034) (xy 162.814005 -104.737412) (xy 162.826131 -104.682975) (xy 162.846054 -104.630884)
			(xy 162.87335 -104.582249) (xy 162.907436 -104.538106) (xy 162.947585 -104.499397) (xy 162.992943 -104.466946)
			(xy 163.042543 -104.441445) (xy 163.095327 -104.423438) (xy 163.15017 -104.413308) (xy 163.205904 -104.411271)
			(xy 163.261341 -104.417371) (xy 163.315298 -104.431477) (xy 163.366627 -104.453289) (xy 163.414233 -104.482343)
			(xy 163.457101 -104.518018) (xy 163.494318 -104.559555) (xy 163.525091 -104.606068) (xy 163.548763 -104.656565)
			(xy 163.564831 -104.709972) (xy 163.572951 -104.765148) (xy 163.57346 -104.793034) (xy 163.572951 -104.82092)
			(xy 163.564831 -104.876096) (xy 163.548763 -104.929503) (xy 163.525091 -104.98) (xy 163.494318 -105.026513)
			(xy 163.457101 -105.06805) (xy 163.414233 -105.103725) (xy 163.366627 -105.132779) (xy 163.315298 -105.154591)
			(xy 163.261341 -105.168697) (xy 163.205904 -105.174797) (xy 163.15017 -105.17276) (xy 163.095327 -105.16263)
			(xy 163.042543 -105.144623) (xy 162.992943 -105.119122) (xy 162.947585 -105.086671) (xy 162.907436 -105.047962)
			(xy 162.87335 -105.003819) (xy 162.846054 -104.955184) (xy 162.826131 -104.903093) (xy 162.814005 -104.848656)
			(xy 162.809934 -104.793034) (xy 152.155966 -104.793034) (xy 152.143663 -104.807234) (xy 152.100368 -104.844754)
			(xy 152.052174 -104.875731) (xy 152.000063 -104.899534) (xy 151.945094 -104.915679) (xy 151.888387 -104.923838)
			(xy 151.859742 -104.924352) (xy 151.844824 -104.924184) (xy 151.815075 -104.921894) (xy 151.800306 -104.91978)
			(xy 151.78913 -104.918002) (xy 151.768048 -104.924098) (xy 151.701246 -104.981756) (xy 151.693291 -104.989359)
			(xy 151.684202 -105.009371) (xy 151.68372 -105.020364) (xy 151.68372 -105.285032) (xy 151.684201 -105.296024)
			(xy 151.693293 -105.316036) (xy 151.701246 -105.32364) (xy 151.749214 -105.365042) (xy 165.322756 -105.365042)
			(xy 165.326827 -105.30942) (xy 165.338953 -105.254983) (xy 165.358876 -105.202892) (xy 165.386172 -105.154257)
			(xy 165.420258 -105.110114) (xy 165.460407 -105.071405) (xy 165.505765 -105.038954) (xy 165.555365 -105.013453)
			(xy 165.608149 -104.995446) (xy 165.662992 -104.985316) (xy 165.718726 -104.983279) (xy 165.774163 -104.989379)
			(xy 165.82812 -105.003485) (xy 165.879449 -105.025297) (xy 165.927055 -105.054351) (xy 165.969923 -105.090026)
			(xy 166.00714 -105.131563) (xy 166.037913 -105.178076) (xy 166.061585 -105.228573) (xy 166.077653 -105.28198)
			(xy 166.085773 -105.337156) (xy 166.086282 -105.365042) (xy 166.085773 -105.392928) (xy 166.077653 -105.448104)
			(xy 166.061585 -105.501511) (xy 166.037913 -105.552008) (xy 166.00714 -105.598521) (xy 165.969923 -105.640058)
			(xy 165.927055 -105.675733) (xy 165.879449 -105.704787) (xy 165.82812 -105.726599) (xy 165.774163 -105.740705)
			(xy 165.718726 -105.746805) (xy 165.662992 -105.744768) (xy 165.608149 -105.734638) (xy 165.555365 -105.716631)
			(xy 165.505765 -105.69113) (xy 165.460407 -105.658679) (xy 165.420258 -105.61997) (xy 165.386172 -105.575827)
			(xy 165.358876 -105.527192) (xy 165.338953 -105.475101) (xy 165.326827 -105.420664) (xy 165.322756 -105.365042)
			(xy 151.749214 -105.365042) (xy 151.768048 -105.381298) (xy 151.78913 -105.387394) (xy 151.800306 -105.385616)
			(xy 151.815075 -105.383505) (xy 151.844824 -105.381218) (xy 151.859742 -105.381044) (xy 151.888389 -105.381538)
			(xy 151.945099 -105.389697) (xy 152.000071 -105.405843) (xy 152.052186 -105.429648) (xy 152.100383 -105.460627)
			(xy 152.143681 -105.498149) (xy 152.181198 -105.541451) (xy 152.212172 -105.589651) (xy 152.235972 -105.641768)
			(xy 152.252112 -105.696742) (xy 152.260265 -105.753453) (xy 152.260265 -105.810747) (xy 152.252112 -105.867458)
			(xy 152.235972 -105.922432) (xy 152.212172 -105.974549) (xy 152.181198 -106.022749) (xy 152.143681 -106.066051)
			(xy 152.100383 -106.103573) (xy 152.052186 -106.134552) (xy 152.000071 -106.158357) (xy 151.945099 -106.174503)
			(xy 151.888389 -106.182662) (xy 151.859742 -106.183176) (xy 151.832361 -106.182721) (xy 151.778112 -106.175248)
			(xy 151.725384 -106.160461) (xy 151.675159 -106.138636) (xy 151.628372 -106.110179) (xy 151.585892 -106.07562)
			(xy 151.548511 -106.035602) (xy 151.532336 -106.013504) (xy 151.526759 -106.006256) (xy 151.51166 -105.995965)
			(xy 151.502872 -105.993438) (xy 151.4729 -105.986072) (xy 151.46395 -105.984323) (xy 151.445861 -105.986539)
			(xy 151.437594 -105.99039) (xy 151.412994 -106.002779) (xy 151.361468 -106.022248) (xy 151.307979 -106.035397)
			(xy 151.253299 -106.042035) (xy 151.225758 -106.04246) (xy 151.198217 -106.042032) (xy 151.143537 -106.035396)
			(xy 151.090048 -106.022249) (xy 151.038521 -106.002781) (xy 151.013922 -105.99039) (xy 151.005659 -105.986523)
			(xy 150.987565 -105.984302) (xy 150.978616 -105.986072) (xy 150.948644 -105.993438) (xy 150.939857 -105.995965)
			(xy 150.924759 -106.006259) (xy 150.91918 -106.013504) (xy 150.903028 -106.035621) (xy 150.865653 -106.075652)
			(xy 150.823173 -106.110219) (xy 150.776382 -106.138678) (xy 150.72615 -106.160499) (xy 150.673414 -106.175275)
			(xy 150.619157 -106.182731) (xy 150.591774 -106.183176) (xy 150.563128 -106.182643) (xy 150.506419 -106.174486)
			(xy 150.451448 -106.158342) (xy 150.399333 -106.134539) (xy 150.351137 -106.103563) (xy 150.307839 -106.066042)
			(xy 150.270322 -106.022742) (xy 150.239348 -105.974544) (xy 150.215549 -105.922428) (xy 150.199408 -105.867456)
			(xy 150.191255 -105.810746) (xy 150.191255 -105.753454) (xy 150.199408 -105.696744) (xy 150.215549 -105.641772)
			(xy 150.239348 -105.589656) (xy 150.270322 -105.541458) (xy 150.307839 -105.498158) (xy 150.351137 -105.460637)
			(xy 150.399333 -105.429661) (xy 150.451448 -105.405858) (xy 150.506419 -105.389714) (xy 150.563128 -105.381557)
			(xy 150.591774 -105.381044) (xy 150.606692 -105.38121) (xy 150.636441 -105.383501) (xy 150.65121 -105.385616)
			(xy 150.662386 -105.387394) (xy 150.683468 -105.381298) (xy 150.75027 -105.32364) (xy 150.75823 -105.316042)
			(xy 150.767316 -105.296026) (xy 150.767796 -105.285032) (xy 150.767796 -105.020364) (xy 150.767312 -105.009373)
			(xy 150.758222 -104.98936) (xy 150.75027 -104.981756) (xy 150.683468 -104.924098) (xy 150.662386 -104.918002)
			(xy 150.65121 -104.91978) (xy 150.636441 -104.92189) (xy 150.606692 -104.924177) (xy 150.591774 -104.924352)
			(xy 150.563126 -104.923868) (xy 150.506413 -104.91571) (xy 150.451439 -104.899565) (xy 150.399322 -104.875761)
			(xy 150.351122 -104.844782) (xy 150.307822 -104.80726) (xy 150.270302 -104.763957) (xy 150.239327 -104.715756)
			(xy 150.215526 -104.663637) (xy 150.199384 -104.608661) (xy 150.191231 -104.551948) (xy 125.045226 -104.551948)
			(xy 125.067001 -104.598399) (xy 125.083069 -104.651806) (xy 125.091189 -104.706982) (xy 125.091698 -104.734868)
			(xy 125.091189 -104.762754) (xy 125.083069 -104.81793) (xy 125.067001 -104.871337) (xy 125.043329 -104.921834)
			(xy 125.012556 -104.968347) (xy 124.975339 -105.009884) (xy 124.932471 -105.045559) (xy 124.884865 -105.074613)
			(xy 124.833536 -105.096425) (xy 124.779579 -105.110531) (xy 124.724142 -105.116631) (xy 124.668408 -105.114594)
			(xy 124.613565 -105.104464) (xy 124.560781 -105.086457) (xy 124.511181 -105.060956) (xy 124.465823 -105.028505)
			(xy 124.425674 -104.989796) (xy 124.391588 -104.945653) (xy 124.364292 -104.897018) (xy 124.344369 -104.844927)
			(xy 124.332243 -104.79049) (xy 124.328172 -104.734868) (xy 102.233191 -104.734868) (xy 102.258928 -104.751409)
			(xy 102.300115 -104.7871) (xy 102.335804 -104.828289) (xy 102.365268 -104.874138) (xy 102.387907 -104.923713)
			(xy 102.40326 -104.976005) (xy 102.411016 -105.02995) (xy 102.411016 -105.08445) (xy 102.40326 -105.138395)
			(xy 102.387907 -105.190687) (xy 102.365268 -105.240262) (xy 102.335804 -105.286111) (xy 102.300115 -105.3273)
			(xy 102.258928 -105.362991) (xy 102.213081 -105.392457) (xy 102.163508 -105.415099) (xy 102.111216 -105.430456)
			(xy 102.057272 -105.438215) (xy 102.030022 -105.438702) (xy 102.002652 -105.438223) (xy 101.948474 -105.430408)
			(xy 101.895971 -105.414922) (xy 101.846224 -105.392083) (xy 101.800256 -105.362362) (xy 101.779324 -105.344722)
			(xy 101.77907 -105.344468) (xy 101.77197 -105.338901) (xy 101.755063 -105.332644) (xy 101.74605 -105.332276)
			(xy 101.678994 -105.332276) (xy 101.669978 -105.332636) (xy 101.653061 -105.338882) (xy 101.645974 -105.344468)
			(xy 101.64572 -105.344722) (xy 101.624787 -105.362363) (xy 101.578819 -105.392087) (xy 101.529073 -105.414933)
			(xy 101.476571 -105.430429) (xy 101.422393 -105.438258) (xy 101.367651 -105.438258) (xy 101.313473 -105.430429)
			(xy 101.260971 -105.414933) (xy 101.211225 -105.392087) (xy 101.165257 -105.362363) (xy 101.144324 -105.344722)
			(xy 101.14407 -105.344468) (xy 101.13697 -105.338901) (xy 101.120063 -105.332644) (xy 101.11105 -105.332276)
			(xy 101.043994 -105.332276) (xy 101.034978 -105.332636) (xy 101.018061 -105.338882) (xy 101.010974 -105.344468)
			(xy 101.010974 -105.344722) (xy 101.01072 -105.344722) (xy 100.989794 -105.362369) (xy 100.943819 -105.392079)
			(xy 100.89407 -105.414913) (xy 100.841568 -105.430402) (xy 100.787392 -105.438229) (xy 100.760022 -105.438702)
			(xy 100.733709 -105.438219) (xy 100.681581 -105.430987) (xy 100.630938 -105.416671) (xy 100.582739 -105.395542)
			(xy 100.537895 -105.367998) (xy 100.497255 -105.334562) (xy 100.479098 -105.315512) (xy 100.471577 -105.308109)
			(xy 100.452297 -105.299585) (xy 100.44176 -105.299002) (xy 100.367084 -105.299002) (xy 100.356532 -105.299508)
			(xy 100.337236 -105.308059) (xy 100.329746 -105.315512) (xy 100.311612 -105.334589) (xy 100.270977 -105.368044)
			(xy 100.226133 -105.3956) (xy 100.177928 -105.416734) (xy 100.127276 -105.431047) (xy 100.075139 -105.438266)
			(xy 100.048822 -105.438702) (xy 100.021568 -105.438252) (xy 99.967614 -105.430498) (xy 99.915312 -105.415143)
			(xy 99.865729 -105.392502) (xy 99.819872 -105.363034) (xy 99.778676 -105.32734) (xy 99.742979 -105.286146)
			(xy 99.713509 -105.240291) (xy 99.690864 -105.190708) (xy 99.675507 -105.138408) (xy 99.667749 -105.084454)
			(xy 98.411015 -105.084454) (xy 98.403261 -105.138394) (xy 98.387907 -105.190685) (xy 98.365269 -105.24026)
			(xy 98.335806 -105.286108) (xy 98.300118 -105.327297) (xy 98.258932 -105.362988) (xy 98.213086 -105.392454)
			(xy 98.163513 -105.415097) (xy 98.111223 -105.430454) (xy 98.057279 -105.438214) (xy 98.03003 -105.438702)
			(xy 98.00266 -105.438218) (xy 97.948482 -105.430404) (xy 97.895979 -105.414919) (xy 97.846232 -105.392082)
			(xy 97.800264 -105.362361) (xy 97.779332 -105.344722) (xy 97.779078 -105.344468) (xy 97.772005 -105.338863)
			(xy 97.755078 -105.332628) (xy 97.746058 -105.332276) (xy 97.679002 -105.332276) (xy 97.669986 -105.332639)
			(xy 97.653069 -105.338883) (xy 97.645982 -105.344468) (xy 97.645728 -105.344722) (xy 97.624795 -105.362363)
			(xy 97.578827 -105.392087) (xy 97.529081 -105.414933) (xy 97.476579 -105.430429) (xy 97.422401 -105.438258)
			(xy 97.367659 -105.438258) (xy 97.313481 -105.430429) (xy 97.260979 -105.414933) (xy 97.211233 -105.392087)
			(xy 97.165265 -105.362363) (xy 97.144332 -105.344722) (xy 97.144078 -105.344468) (xy 97.137005 -105.338863)
			(xy 97.120078 -105.332628) (xy 97.111058 -105.332276) (xy 97.044002 -105.332276) (xy 97.034986 -105.332639)
			(xy 97.018069 -105.338883) (xy 97.010982 -105.344468) (xy 97.010982 -105.344722) (xy 97.010728 -105.344722)
			(xy 96.989795 -105.362363) (xy 96.943827 -105.392087) (xy 96.894081 -105.414933) (xy 96.841579 -105.430429)
			(xy 96.787401 -105.438258) (xy 96.732659 -105.438258) (xy 96.678481 -105.430429) (xy 96.625979 -105.414933)
			(xy 96.576233 -105.392087) (xy 96.530265 -105.362363) (xy 96.509332 -105.344722) (xy 96.509078 -105.344468)
			(xy 96.502005 -105.338863) (xy 96.485078 -105.332628) (xy 96.476058 -105.332276) (xy 96.409002 -105.332276)
			(xy 96.399986 -105.332639) (xy 96.383069 -105.338883) (xy 96.375982 -105.344468) (xy 96.375982 -105.344722)
			(xy 96.375728 -105.344722) (xy 96.354799 -105.362365) (xy 96.308825 -105.392075) (xy 96.259077 -105.41491)
			(xy 96.206575 -105.4304) (xy 96.152399 -105.438228) (xy 96.12503 -105.438702) (xy 96.097775 -105.438253)
			(xy 96.04382 -105.430499) (xy 95.991518 -105.415145) (xy 95.941933 -105.392504) (xy 95.896076 -105.363037)
			(xy 95.854879 -105.327342) (xy 95.819181 -105.286148) (xy 95.78971 -105.240293) (xy 95.767065 -105.19071)
			(xy 95.751707 -105.138409) (xy 95.743949 -105.084455) (xy 91.5035 -105.084455) (xy 91.5035 -106.289856)
			(xy 122.18111 -106.289856) (xy 122.185181 -106.234234) (xy 122.197307 -106.179797) (xy 122.21723 -106.127706)
			(xy 122.244526 -106.079071) (xy 122.278612 -106.034928) (xy 122.318761 -105.996219) (xy 122.364119 -105.963768)
			(xy 122.413719 -105.938267) (xy 122.466503 -105.92026) (xy 122.521346 -105.91013) (xy 122.57708 -105.908093)
			(xy 122.632517 -105.914193) (xy 122.686474 -105.928299) (xy 122.737803 -105.950111) (xy 122.785409 -105.979165)
			(xy 122.828277 -106.01484) (xy 122.865494 -106.056377) (xy 122.896267 -106.10289) (xy 122.919939 -106.153387)
			(xy 122.936007 -106.206794) (xy 122.944127 -106.26197) (xy 122.944418 -106.277918) (xy 123.681234 -106.277918)
			(xy 123.685305 -106.222296) (xy 123.697431 -106.167859) (xy 123.717354 -106.115768) (xy 123.74465 -106.067133)
			(xy 123.778736 -106.02299) (xy 123.818885 -105.984281) (xy 123.864243 -105.95183) (xy 123.913843 -105.926329)
			(xy 123.966627 -105.908322) (xy 124.02147 -105.898192) (xy 124.077204 -105.896155) (xy 124.132641 -105.902255)
			(xy 124.186598 -105.916361) (xy 124.237927 -105.938173) (xy 124.285533 -105.967227) (xy 124.328401 -106.002902)
			(xy 124.365618 -106.044439) (xy 124.396391 -106.090952) (xy 124.420063 -106.141449) (xy 124.436131 -106.194856)
			(xy 124.444251 -106.250032) (xy 124.44476 -106.277918) (xy 124.444251 -106.305804) (xy 124.438461 -106.345146)
			(xy 152.833371 -106.345146) (xy 152.833371 -106.287854) (xy 152.841524 -106.231146) (xy 152.857665 -106.176176)
			(xy 152.881463 -106.124062) (xy 152.912437 -106.075865) (xy 152.949953 -106.032566) (xy 152.99325 -105.995047)
			(xy 153.041446 -105.964072) (xy 153.093559 -105.940271) (xy 153.148529 -105.924128) (xy 153.205236 -105.915972)
			(xy 153.233882 -105.91546) (xy 153.261262 -105.915956) (xy 153.31551 -105.923421) (xy 153.368237 -105.938199)
			(xy 153.418462 -105.960017) (xy 153.465251 -105.988467) (xy 153.507731 -106.023021) (xy 153.545113 -106.063036)
			(xy 153.561288 -106.085132) (xy 153.56687 -106.092376) (xy 153.581964 -106.102671) (xy 153.590752 -106.105198)
			(xy 153.620724 -106.112564) (xy 153.629673 -106.114322) (xy 153.647763 -106.112099) (xy 153.65603 -106.108246)
			(xy 153.680624 -106.095843) (xy 153.732152 -106.076378) (xy 153.785643 -106.063234) (xy 153.840325 -106.0566)
			(xy 153.867866 -106.056176) (xy 153.895407 -106.05659) (xy 153.950088 -106.06323) (xy 154.003577 -106.076381)
			(xy 154.055103 -106.095853) (xy 154.079702 -106.108246) (xy 154.087961 -106.112124) (xy 154.106058 -106.11434)
			(xy 154.115008 -106.112564) (xy 154.14498 -106.105198) (xy 154.153753 -106.10263) (xy 154.168857 -106.092365)
			(xy 154.174444 -106.085132) (xy 154.190592 -106.063011) (xy 154.227967 -106.022979) (xy 154.270446 -105.988411)
			(xy 154.317239 -105.959952) (xy 154.367471 -105.938131) (xy 154.420208 -105.923357) (xy 154.474466 -105.915903)
			(xy 154.50185 -105.91546) (xy 154.530504 -105.915891) (xy 154.58723 -105.924041) (xy 154.642219 -105.940181)
			(xy 154.69435 -105.963983) (xy 154.742563 -105.994962) (xy 154.785877 -106.032488) (xy 154.79672 -106.045)
			(xy 160.769552 -106.045) (xy 160.773623 -105.989378) (xy 160.785749 -105.934941) (xy 160.805672 -105.88285)
			(xy 160.832968 -105.834215) (xy 160.867054 -105.790072) (xy 160.907203 -105.751363) (xy 160.952561 -105.718912)
			(xy 161.002161 -105.693411) (xy 161.054945 -105.675404) (xy 161.109788 -105.665274) (xy 161.165522 -105.663237)
			(xy 161.220959 -105.669337) (xy 161.274916 -105.683443) (xy 161.326245 -105.705255) (xy 161.373851 -105.734309)
			(xy 161.416719 -105.769984) (xy 161.453936 -105.811521) (xy 161.484709 -105.858034) (xy 161.508381 -105.908531)
			(xy 161.524449 -105.961938) (xy 161.532569 -106.017114) (xy 161.533078 -106.045) (xy 161.532569 -106.072886)
			(xy 161.524449 -106.128062) (xy 161.508381 -106.181469) (xy 161.484709 -106.231966) (xy 161.453936 -106.278479)
			(xy 161.416719 -106.320016) (xy 161.373851 -106.355691) (xy 161.326245 -106.384745) (xy 161.274916 -106.406557)
			(xy 161.220959 -106.420663) (xy 161.165522 -106.426763) (xy 161.109788 -106.424726) (xy 161.054945 -106.414596)
			(xy 161.002161 -106.396589) (xy 160.952561 -106.371088) (xy 160.907203 -106.338637) (xy 160.867054 -106.299928)
			(xy 160.832968 -106.255785) (xy 160.805672 -106.20715) (xy 160.785749 -106.155059) (xy 160.773623 -106.100622)
			(xy 160.769552 -106.045) (xy 154.79672 -106.045) (xy 154.823408 -106.075797) (xy 154.854393 -106.124006)
			(xy 154.878202 -106.176135) (xy 154.894349 -106.231121) (xy 154.902505 -106.287846) (xy 154.902505 -106.345154)
			(xy 154.894349 -106.401879) (xy 154.878202 -106.456865) (xy 154.854393 -106.508994) (xy 154.823408 -106.557203)
			(xy 154.785877 -106.600512) (xy 154.742563 -106.638038) (xy 154.69435 -106.669017) (xy 154.642219 -106.692819)
			(xy 154.58723 -106.708959) (xy 154.530504 -106.717109) (xy 154.50185 -106.717592) (xy 154.486932 -106.717423)
			(xy 154.457183 -106.715134) (xy 154.442414 -106.71302) (xy 154.431238 -106.711242) (xy 154.410156 -106.717338)
			(xy 154.343354 -106.774996) (xy 154.335382 -106.782584) (xy 154.326302 -106.802608) (xy 154.325828 -106.813604)
			(xy 154.325828 -107.078272) (xy 154.326285 -107.089267) (xy 154.335393 -107.109279) (xy 154.343354 -107.11688)
			(xy 154.410156 -107.174538) (xy 154.431238 -107.180634) (xy 154.442414 -107.178856) (xy 154.457183 -107.176743)
			(xy 154.486932 -107.174458) (xy 154.50185 -107.174284) (xy 154.530506 -107.174667) (xy 154.587235 -107.182817)
			(xy 154.642227 -107.198958) (xy 154.694362 -107.222762) (xy 154.742578 -107.253743) (xy 154.785894 -107.291271)
			(xy 154.823427 -107.334582) (xy 154.854414 -107.382794) (xy 154.865678 -107.407456) (xy 165.146988 -107.407456)
			(xy 165.151059 -107.351834) (xy 165.163185 -107.297397) (xy 165.183108 -107.245306) (xy 165.210404 -107.196671)
			(xy 165.24449 -107.152528) (xy 165.284639 -107.113819) (xy 165.329997 -107.081368) (xy 165.379597 -107.055867)
			(xy 165.432381 -107.03786) (xy 165.487224 -107.02773) (xy 165.542958 -107.025693) (xy 165.598395 -107.031793)
			(xy 165.652352 -107.045899) (xy 165.703681 -107.067711) (xy 165.751287 -107.096765) (xy 165.794155 -107.13244)
			(xy 165.831372 -107.173977) (xy 165.862145 -107.22049) (xy 165.885817 -107.270987) (xy 165.901885 -107.324394)
			(xy 165.910005 -107.37957) (xy 165.910514 -107.407456) (xy 165.910005 -107.435342) (xy 165.901885 -107.490518)
			(xy 165.885817 -107.543925) (xy 165.862145 -107.594422) (xy 165.831372 -107.640935) (xy 165.794155 -107.682472)
			(xy 165.751287 -107.718147) (xy 165.703681 -107.747201) (xy 165.652352 -107.769013) (xy 165.598395 -107.783119)
			(xy 165.542958 -107.789219) (xy 165.487224 -107.787182) (xy 165.432381 -107.777052) (xy 165.379597 -107.759045)
			(xy 165.329997 -107.733544) (xy 165.284639 -107.701093) (xy 165.24449 -107.662384) (xy 165.210404 -107.618241)
			(xy 165.183108 -107.569606) (xy 165.163185 -107.517515) (xy 165.151059 -107.463078) (xy 165.146988 -107.407456)
			(xy 154.865678 -107.407456) (xy 154.878224 -107.434926) (xy 154.894372 -107.489916) (xy 154.902529 -107.546644)
			(xy 154.902529 -107.603956) (xy 154.894372 -107.660684) (xy 154.878224 -107.715674) (xy 154.854414 -107.767806)
			(xy 154.823427 -107.816018) (xy 154.798226 -107.845098) (xy 160.769552 -107.845098) (xy 160.773623 -107.789476)
			(xy 160.785749 -107.735039) (xy 160.805672 -107.682948) (xy 160.832968 -107.634313) (xy 160.867054 -107.59017)
			(xy 160.907203 -107.551461) (xy 160.952561 -107.51901) (xy 161.002161 -107.493509) (xy 161.054945 -107.475502)
			(xy 161.109788 -107.465372) (xy 161.165522 -107.463335) (xy 161.220959 -107.469435) (xy 161.274916 -107.483541)
			(xy 161.326245 -107.505353) (xy 161.373851 -107.534407) (xy 161.416719 -107.570082) (xy 161.453936 -107.611619)
			(xy 161.484709 -107.658132) (xy 161.508381 -107.708629) (xy 161.524449 -107.762036) (xy 161.532569 -107.817212)
			(xy 161.533078 -107.845098) (xy 161.532569 -107.872984) (xy 161.524449 -107.92816) (xy 161.508381 -107.981567)
			(xy 161.484709 -108.032064) (xy 161.453936 -108.078577) (xy 161.416719 -108.120114) (xy 161.373851 -108.155789)
			(xy 161.326245 -108.184843) (xy 161.274916 -108.206655) (xy 161.220959 -108.220761) (xy 161.165522 -108.226861)
			(xy 161.109788 -108.224824) (xy 161.054945 -108.214694) (xy 161.002161 -108.196687) (xy 160.952561 -108.171186)
			(xy 160.907203 -108.138735) (xy 160.867054 -108.100026) (xy 160.832968 -108.055883) (xy 160.805672 -108.007248)
			(xy 160.785749 -107.955157) (xy 160.773623 -107.90072) (xy 160.769552 -107.845098) (xy 154.798226 -107.845098)
			(xy 154.785894 -107.859329) (xy 154.742578 -107.896857) (xy 154.694362 -107.927838) (xy 154.642227 -107.951642)
			(xy 154.587235 -107.967783) (xy 154.530506 -107.975933) (xy 154.50185 -107.976416) (xy 154.474468 -107.975981)
			(xy 154.420217 -107.968507) (xy 154.367488 -107.953718) (xy 154.317262 -107.931891) (xy 154.270475 -107.903431)
			(xy 154.227996 -107.868867) (xy 154.190617 -107.828844) (xy 154.174444 -107.806744) (xy 154.168891 -107.799475)
			(xy 154.153776 -107.789194) (xy 154.14498 -107.786678) (xy 154.115008 -107.779312) (xy 154.106057 -107.777573)
			(xy 154.087969 -107.779784) (xy 154.079702 -107.78363) (xy 154.055102 -107.796019) (xy 154.003576 -107.815488)
			(xy 153.950087 -107.828636) (xy 153.895406 -107.835274) (xy 153.867866 -107.8357) (xy 153.840325 -107.835275)
			(xy 153.785645 -107.828639) (xy 153.732155 -107.815492) (xy 153.680629 -107.796022) (xy 153.65603 -107.78363)
			(xy 153.647765 -107.779768) (xy 153.629673 -107.777542) (xy 153.620724 -107.779312) (xy 153.590752 -107.786678)
			(xy 153.581961 -107.789196) (xy 153.566865 -107.799495) (xy 153.561288 -107.806744) (xy 153.545114 -107.828844)
			(xy 153.507744 -107.868878) (xy 153.465269 -107.903448) (xy 153.418481 -107.931911) (xy 153.368253 -107.953735)
			(xy 153.315519 -107.968513) (xy 153.261265 -107.97597) (xy 153.233882 -107.976416) (xy 153.205238 -107.975804)
			(xy 153.148534 -107.967649) (xy 153.093567 -107.951507) (xy 153.041457 -107.927707) (xy 152.993265 -107.896733)
			(xy 152.94997 -107.859217) (xy 152.912456 -107.815921) (xy 152.881485 -107.767727) (xy 152.857687 -107.715616)
			(xy 152.841548 -107.660649) (xy 152.833395 -107.603944) (xy 152.833395 -107.546656) (xy 152.841548 -107.489951)
			(xy 152.857687 -107.434984) (xy 152.881485 -107.382873) (xy 152.912456 -107.334679) (xy 152.94997 -107.291383)
			(xy 152.993265 -107.253867) (xy 153.041457 -107.222893) (xy 153.093567 -107.199093) (xy 153.148534 -107.182951)
			(xy 153.205238 -107.174796) (xy 153.233882 -107.174284) (xy 153.2488 -107.174449) (xy 153.278549 -107.176741)
			(xy 153.293318 -107.178856) (xy 153.304494 -107.180634) (xy 153.325576 -107.174538) (xy 153.392378 -107.11688)
			(xy 153.400366 -107.109307) (xy 153.409436 -107.089272) (xy 153.409904 -107.078272) (xy 153.409904 -106.813604)
			(xy 153.409395 -106.802616) (xy 153.400322 -106.782603) (xy 153.392378 -106.774996) (xy 153.325576 -106.717338)
			(xy 153.304494 -106.711242) (xy 153.293318 -106.71302) (xy 153.278549 -106.715129) (xy 153.2488 -106.717417)
			(xy 153.233882 -106.717592) (xy 153.205236 -106.717028) (xy 153.148529 -106.708872) (xy 153.093559 -106.692729)
			(xy 153.041446 -106.668928) (xy 152.99325 -106.637953) (xy 152.949953 -106.600434) (xy 152.912437 -106.557135)
			(xy 152.881463 -106.508938) (xy 152.857665 -106.456824) (xy 152.841524 -106.401854) (xy 152.833371 -106.345146)
			(xy 124.438461 -106.345146) (xy 124.436131 -106.36098) (xy 124.420063 -106.414387) (xy 124.396391 -106.464884)
			(xy 124.365618 -106.511397) (xy 124.328401 -106.552934) (xy 124.285533 -106.588609) (xy 124.237927 -106.617663)
			(xy 124.186598 -106.639475) (xy 124.132641 -106.653581) (xy 124.077204 -106.659681) (xy 124.02147 -106.657644)
			(xy 123.966627 -106.647514) (xy 123.913843 -106.629507) (xy 123.864243 -106.604006) (xy 123.818885 -106.571555)
			(xy 123.778736 -106.532846) (xy 123.74465 -106.488703) (xy 123.717354 -106.440068) (xy 123.697431 -106.387977)
			(xy 123.685305 -106.33354) (xy 123.681234 -106.277918) (xy 122.944418 -106.277918) (xy 122.944636 -106.289856)
			(xy 122.944127 -106.317742) (xy 122.936007 -106.372918) (xy 122.919939 -106.426325) (xy 122.896267 -106.476822)
			(xy 122.865494 -106.523335) (xy 122.828277 -106.564872) (xy 122.785409 -106.600547) (xy 122.737803 -106.629601)
			(xy 122.686474 -106.651413) (xy 122.632517 -106.665519) (xy 122.57708 -106.671619) (xy 122.521346 -106.669582)
			(xy 122.466503 -106.659452) (xy 122.413719 -106.641445) (xy 122.364119 -106.615944) (xy 122.318761 -106.583493)
			(xy 122.278612 -106.544784) (xy 122.244526 -106.500641) (xy 122.21723 -106.452006) (xy 122.197307 -106.399915)
			(xy 122.185181 -106.345478) (xy 122.18111 -106.289856) (xy 91.5035 -106.289856) (xy 91.5035 -106.807053)
			(xy 103.602977 -106.807053) (xy 103.602977 -106.752547) (xy 103.610735 -106.698595) (xy 103.626092 -106.646297)
			(xy 103.648737 -106.596716) (xy 103.678207 -106.550864) (xy 103.713904 -106.509672) (xy 103.755099 -106.473981)
			(xy 103.800955 -106.444516) (xy 103.850538 -106.421877) (xy 103.902838 -106.406526) (xy 103.956791 -106.398774)
			(xy 103.984044 -106.398314) (xy 104.011413 -106.398809) (xy 104.065591 -106.40662) (xy 104.118094 -106.422102)
			(xy 104.167841 -106.444937) (xy 104.213809 -106.474656) (xy 104.234742 -106.492294) (xy 104.234996 -106.492548)
			(xy 104.242075 -106.498145) (xy 104.258998 -106.504384) (xy 104.268016 -106.50474) (xy 104.335072 -106.50474)
			(xy 104.344089 -106.504383) (xy 104.361007 -106.498137) (xy 104.368092 -106.492548) (xy 104.368092 -106.492294)
			(xy 104.368346 -106.492294) (xy 104.389279 -106.474653) (xy 104.435247 -106.444929) (xy 104.484993 -106.422083)
			(xy 104.537495 -106.406587) (xy 104.591673 -106.398758) (xy 104.646415 -106.398758) (xy 104.700593 -106.406587)
			(xy 104.753095 -106.422083) (xy 104.802841 -106.444929) (xy 104.848809 -106.474653) (xy 104.869742 -106.492294)
			(xy 104.869996 -106.492548) (xy 104.877075 -106.498145) (xy 104.893998 -106.504384) (xy 104.903016 -106.50474)
			(xy 104.970072 -106.50474) (xy 104.979089 -106.504383) (xy 104.996007 -106.498137) (xy 105.003092 -106.492548)
			(xy 105.003092 -106.492294) (xy 105.003346 -106.492294) (xy 105.024287 -106.474666) (xy 105.070257 -106.444953)
			(xy 105.120003 -106.422115) (xy 105.172501 -106.406621) (xy 105.226675 -106.39879) (xy 105.254044 -106.398314)
			(xy 105.281295 -106.398759) (xy 105.335241 -106.406521) (xy 105.387533 -106.421881) (xy 105.437108 -106.444526)
			(xy 105.482955 -106.473995) (xy 105.524143 -106.509688) (xy 105.559832 -106.55088) (xy 105.589295 -106.596731)
			(xy 105.611935 -106.646308) (xy 105.627288 -106.698602) (xy 105.635044 -106.752549) (xy 105.635044 -106.80245)
			(xy 108.420905 -106.80245) (xy 108.420905 -106.74795) (xy 108.428662 -106.694005) (xy 108.444016 -106.641712)
			(xy 108.466657 -106.592138) (xy 108.496123 -106.54629) (xy 108.531814 -106.505102) (xy 108.573003 -106.469413)
			(xy 108.618852 -106.439949) (xy 108.668427 -106.417311) (xy 108.72072 -106.401958) (xy 108.774666 -106.394204)
			(xy 108.801916 -106.393742) (xy 108.828231 -106.394185) (xy 108.880361 -106.401423) (xy 108.931005 -106.415746)
			(xy 108.979204 -106.436883) (xy 109.024047 -106.464434) (xy 109.064685 -106.497878) (xy 109.08284 -106.516932)
			(xy 109.090354 -106.524343) (xy 109.109639 -106.532865) (xy 109.120178 -106.533442) (xy 109.194854 -106.533442)
			(xy 109.205401 -106.532889) (xy 109.224695 -106.524369) (xy 109.232192 -106.516932) (xy 109.252012 -106.496144)
			(xy 109.296784 -106.460169) (xy 109.346442 -106.431309) (xy 109.399864 -106.410216) (xy 109.455843 -106.397367)
			(xy 109.513116 -106.393052) (xy 109.570389 -106.397367) (xy 109.626368 -106.410216) (xy 109.67979 -106.431309)
			(xy 109.729448 -106.460169) (xy 109.77422 -106.496144) (xy 109.79404 -106.516932) (xy 109.801554 -106.524343)
			(xy 109.820839 -106.532865) (xy 109.831378 -106.533442) (xy 109.906054 -106.533442) (xy 109.916601 -106.532889)
			(xy 109.935895 -106.524369) (xy 109.943392 -106.516932) (xy 109.961565 -106.497893) (xy 110.00219 -106.464434)
			(xy 110.047026 -106.436871) (xy 110.095224 -106.41573) (xy 110.145869 -106.401409) (xy 110.198001 -106.394182)
			(xy 110.224316 -106.393742) (xy 110.25157 -106.394129) (xy 110.305523 -106.401888) (xy 110.357823 -106.417247)
			(xy 110.407405 -106.439892) (xy 110.453259 -106.469362) (xy 110.494453 -106.505059) (xy 110.530147 -106.546254)
			(xy 110.559616 -106.59211) (xy 110.582259 -106.641692) (xy 110.597615 -106.693993) (xy 110.605372 -106.747946)
			(xy 110.605372 -106.802454) (xy 110.597615 -106.856407) (xy 110.582259 -106.908708) (xy 110.559616 -106.95829)
			(xy 110.530147 -107.004146) (xy 110.494453 -107.045341) (xy 110.453259 -107.081038) (xy 110.407405 -107.110508)
			(xy 110.357823 -107.133153) (xy 110.305523 -107.148512) (xy 110.25157 -107.156271) (xy 110.224316 -107.156758)
			(xy 110.198002 -107.156293) (xy 110.145873 -107.14906) (xy 110.095229 -107.134741) (xy 110.04703 -107.113608)
			(xy 110.002187 -107.086061) (xy 109.961548 -107.052621) (xy 109.943392 -107.033568) (xy 109.935866 -107.026171)
			(xy 109.91659 -107.017642) (xy 109.906054 -107.017058) (xy 109.831378 -107.017058) (xy 109.820833 -107.017628)
			(xy 109.801538 -107.026136) (xy 109.79404 -107.033568) (xy 109.77422 -107.054356) (xy 109.729448 -107.090331)
			(xy 109.67979 -107.119191) (xy 109.626368 -107.140284) (xy 109.570389 -107.153133) (xy 109.513116 -107.157448)
			(xy 109.455843 -107.153133) (xy 109.399864 -107.140284) (xy 109.346442 -107.119191) (xy 109.296784 -107.090331)
			(xy 109.252012 -107.054356) (xy 109.232192 -107.033568) (xy 109.224666 -107.026171) (xy 109.20539 -107.017642)
			(xy 109.194854 -107.017058) (xy 109.120178 -107.017058) (xy 109.109633 -107.017628) (xy 109.090338 -107.026136)
			(xy 109.08284 -107.033568) (xy 109.0647 -107.05264) (xy 109.024068 -107.086096) (xy 108.979225 -107.113654)
			(xy 108.931021 -107.13479) (xy 108.88037 -107.149103) (xy 108.828233 -107.156323) (xy 108.801916 -107.156758)
			(xy 108.774666 -107.156196) (xy 108.72072 -107.148442) (xy 108.668427 -107.133089) (xy 108.618852 -107.110451)
			(xy 108.573003 -107.080987) (xy 108.531813 -107.045298) (xy 108.496123 -107.00411) (xy 108.466657 -106.958262)
			(xy 108.444016 -106.908688) (xy 108.428662 -106.856395) (xy 108.420905 -106.80245) (xy 105.635044 -106.80245)
			(xy 105.635044 -106.807051) (xy 105.627288 -106.860998) (xy 105.611935 -106.913292) (xy 105.589295 -106.962869)
			(xy 105.559832 -107.00872) (xy 105.524143 -107.049912) (xy 105.482955 -107.085605) (xy 105.437108 -107.115074)
			(xy 105.387533 -107.137719) (xy 105.335241 -107.153079) (xy 105.281295 -107.160841) (xy 105.254044 -107.16133)
			(xy 105.226674 -107.160855) (xy 105.172494 -107.153042) (xy 105.119991 -107.137556) (xy 105.070244 -107.114716)
			(xy 105.024277 -107.084991) (xy 105.003346 -107.06735) (xy 105.003092 -107.067096) (xy 104.996012 -107.061499)
			(xy 104.97909 -107.055259) (xy 104.970072 -107.054904) (xy 104.903016 -107.054904) (xy 104.894 -107.055268)
			(xy 104.877083 -107.06151) (xy 104.869996 -107.067096) (xy 104.869742 -107.06735) (xy 104.848809 -107.084991)
			(xy 104.802841 -107.114715) (xy 104.753095 -107.137561) (xy 104.700593 -107.153057) (xy 104.646415 -107.160886)
			(xy 104.591673 -107.160886) (xy 104.537495 -107.153057) (xy 104.484993 -107.137561) (xy 104.435247 -107.114715)
			(xy 104.389279 -107.084991) (xy 104.368346 -107.06735) (xy 104.368092 -107.067096) (xy 104.361012 -107.061499)
			(xy 104.34409 -107.055259) (xy 104.335072 -107.054904) (xy 104.268016 -107.054904) (xy 104.259 -107.055268)
			(xy 104.242083 -107.06151) (xy 104.234996 -107.067096) (xy 104.234996 -107.06735) (xy 104.234742 -107.06735)
			(xy 104.213798 -107.084975) (xy 104.16783 -107.114691) (xy 104.118085 -107.13753) (xy 104.065587 -107.153024)
			(xy 104.011413 -107.160855) (xy 103.984044 -107.16133) (xy 103.956791 -107.160826) (xy 103.902838 -107.153074)
			(xy 103.850538 -107.137723) (xy 103.800955 -107.115084) (xy 103.755099 -107.085619) (xy 103.713904 -107.049928)
			(xy 103.678207 -107.008736) (xy 103.648737 -106.962883) (xy 103.626092 -106.913303) (xy 103.610735 -106.861005)
			(xy 103.602977 -106.807053) (xy 91.5035 -106.807053) (xy 91.5035 -107.740253) (xy 95.684273 -107.740253)
			(xy 95.684273 -107.685747) (xy 95.692031 -107.631795) (xy 95.707388 -107.579496) (xy 95.730033 -107.529916)
			(xy 95.759503 -107.484063) (xy 95.795199 -107.442871) (xy 95.836395 -107.407179) (xy 95.882251 -107.377714)
			(xy 95.931834 -107.355074) (xy 95.984134 -107.339723) (xy 96.038087 -107.331971) (xy 96.06534 -107.33151)
			(xy 96.092709 -107.332009) (xy 96.146887 -107.339818) (xy 96.19939 -107.3553) (xy 96.249137 -107.378134)
			(xy 96.295105 -107.407852) (xy 96.316038 -107.42549) (xy 96.316292 -107.425744) (xy 96.323373 -107.431339)
			(xy 96.340294 -107.437579) (xy 96.349312 -107.437936) (xy 96.416368 -107.437936) (xy 96.425382 -107.437556)
			(xy 96.442299 -107.431323) (xy 96.449388 -107.425744) (xy 96.449388 -107.42549) (xy 96.449642 -107.42549)
			(xy 96.470575 -107.407849) (xy 96.516543 -107.378125) (xy 96.566289 -107.355279) (xy 96.618791 -107.339783)
			(xy 96.672969 -107.331954) (xy 96.727711 -107.331954) (xy 96.781889 -107.339783) (xy 96.834391 -107.355279)
			(xy 96.884137 -107.378125) (xy 96.930105 -107.407849) (xy 96.951038 -107.42549) (xy 96.951292 -107.425744)
			(xy 96.958373 -107.431339) (xy 96.975294 -107.437579) (xy 96.984312 -107.437936) (xy 97.051368 -107.437936)
			(xy 97.060382 -107.437556) (xy 97.077299 -107.431323) (xy 97.084388 -107.425744) (xy 97.084388 -107.42549)
			(xy 97.084642 -107.42549) (xy 97.105575 -107.407849) (xy 97.151543 -107.378125) (xy 97.201289 -107.355279)
			(xy 97.253791 -107.339783) (xy 97.307969 -107.331954) (xy 97.362711 -107.331954) (xy 97.416889 -107.339783)
			(xy 97.469391 -107.355279) (xy 97.519137 -107.378125) (xy 97.565105 -107.407849) (xy 97.586038 -107.42549)
			(xy 97.586292 -107.425744) (xy 97.593373 -107.431339) (xy 97.610294 -107.437579) (xy 97.619312 -107.437936)
			(xy 97.686368 -107.437936) (xy 97.695382 -107.437556) (xy 97.712299 -107.431323) (xy 97.719388 -107.425744)
			(xy 97.719388 -107.42549) (xy 97.719642 -107.42549) (xy 97.740584 -107.407863) (xy 97.786554 -107.37815)
			(xy 97.836299 -107.355312) (xy 97.888798 -107.339818) (xy 97.942972 -107.331986) (xy 97.97034 -107.33151)
			(xy 97.997591 -107.331963) (xy 98.051537 -107.339724) (xy 98.103829 -107.355083) (xy 98.153404 -107.377728)
			(xy 98.199251 -107.407197) (xy 98.240438 -107.44289) (xy 98.276127 -107.484081) (xy 98.305591 -107.529932)
			(xy 98.328231 -107.579508) (xy 98.343584 -107.631803) (xy 98.35134 -107.685749) (xy 98.35134 -107.709052)
			(xy 99.652554 -107.709052) (xy 99.652554 -107.654548) (xy 99.66031 -107.600598) (xy 99.675666 -107.548302)
			(xy 99.698307 -107.498723) (xy 99.727773 -107.45287) (xy 99.763465 -107.411678) (xy 99.804656 -107.375984)
			(xy 99.850507 -107.346515) (xy 99.900085 -107.323872) (xy 99.952381 -107.308514) (xy 100.00633 -107.300755)
			(xy 100.033582 -107.300268) (xy 100.059895 -107.300758) (xy 100.112022 -107.307989) (xy 100.162664 -107.322305)
			(xy 100.210863 -107.343433) (xy 100.255707 -107.370975) (xy 100.296348 -107.404409) (xy 100.314506 -107.423458)
			(xy 100.322029 -107.430858) (xy 100.341308 -107.439385) (xy 100.351844 -107.439968) (xy 100.42652 -107.439968)
			(xy 100.437068 -107.439419) (xy 100.456364 -107.430899) (xy 100.463858 -107.423458) (xy 100.481984 -107.404373)
			(xy 100.522621 -107.37092) (xy 100.567468 -107.343366) (xy 100.615674 -107.322233) (xy 100.666326 -107.307922)
			(xy 100.718464 -107.300703) (xy 100.744782 -107.300268) (xy 100.772153 -107.300728) (xy 100.826333 -107.308545)
			(xy 100.878836 -107.324034) (xy 100.928583 -107.346878) (xy 100.974549 -107.376605) (xy 100.99548 -107.394248)
			(xy 100.995734 -107.394502) (xy 101.002835 -107.400067) (xy 101.019741 -107.406327) (xy 101.028754 -107.406694)
			(xy 101.09581 -107.406694) (xy 101.104828 -107.406343) (xy 101.121744 -107.400091) (xy 101.12883 -107.394502)
			(xy 101.12883 -107.394248) (xy 101.129084 -107.394248) (xy 101.150017 -107.376607) (xy 101.195985 -107.346883)
			(xy 101.245731 -107.324037) (xy 101.298233 -107.308541) (xy 101.352411 -107.300712) (xy 101.407153 -107.300712)
			(xy 101.461331 -107.308541) (xy 101.513833 -107.324037) (xy 101.563579 -107.346883) (xy 101.609547 -107.376607)
			(xy 101.63048 -107.394248) (xy 101.630734 -107.394502) (xy 101.637835 -107.400067) (xy 101.654741 -107.406327)
			(xy 101.663754 -107.406694) (xy 101.73081 -107.406694) (xy 101.739828 -107.406343) (xy 101.756744 -107.400091)
			(xy 101.76383 -107.394502) (xy 101.76383 -107.394248) (xy 101.764084 -107.394248) (xy 101.785017 -107.37661)
			(xy 101.830989 -107.346897) (xy 101.880736 -107.32406) (xy 101.933237 -107.308568) (xy 101.987413 -107.300741)
			(xy 102.014782 -107.300268) (xy 102.042034 -107.300778) (xy 102.095983 -107.308532) (xy 102.14828 -107.323886)
			(xy 102.197859 -107.346526) (xy 102.243712 -107.375992) (xy 102.284904 -107.411683) (xy 102.320598 -107.452874)
			(xy 102.350065 -107.498725) (xy 102.372708 -107.548303) (xy 102.388064 -107.600599) (xy 102.395821 -107.654548)
			(xy 102.395821 -107.709052) (xy 102.388064 -107.763001) (xy 102.372708 -107.815297) (xy 102.350065 -107.864875)
			(xy 102.320598 -107.910726) (xy 102.284904 -107.951917) (xy 102.243712 -107.987608) (xy 102.197859 -108.017074)
			(xy 102.14828 -108.039714) (xy 102.095983 -108.055068) (xy 102.042034 -108.062822) (xy 102.014782 -108.063284)
			(xy 101.987411 -108.062832) (xy 101.933231 -108.055012) (xy 101.880728 -108.039519) (xy 101.830981 -108.016674)
			(xy 101.785015 -107.986947) (xy 101.764084 -107.969304) (xy 101.76383 -107.96905) (xy 101.756743 -107.963464)
			(xy 101.739826 -107.957218) (xy 101.73081 -107.956858) (xy 101.663754 -107.956858) (xy 101.654738 -107.957228)
			(xy 101.63782 -107.963465) (xy 101.630734 -107.96905) (xy 101.63048 -107.969304) (xy 101.609547 -107.986945)
			(xy 101.563579 -108.016669) (xy 101.513833 -108.039515) (xy 101.461331 -108.055011) (xy 101.407153 -108.06284)
			(xy 101.352411 -108.06284) (xy 101.298233 -108.055011) (xy 101.245731 -108.039515) (xy 101.195985 -108.016669)
			(xy 101.150017 -107.986945) (xy 101.129084 -107.969304) (xy 101.12883 -107.96905) (xy 101.121743 -107.963464)
			(xy 101.104826 -107.957218) (xy 101.09581 -107.956858) (xy 101.028754 -107.956858) (xy 101.019738 -107.957228)
			(xy 101.00282 -107.963465) (xy 100.995734 -107.96905) (xy 100.995734 -107.969304) (xy 100.99548 -107.969304)
			(xy 100.974529 -107.98692) (xy 100.928561 -108.016635) (xy 100.878819 -108.039475) (xy 100.826322 -108.054972)
			(xy 100.77215 -108.062806) (xy 100.744782 -108.063284) (xy 100.718467 -108.062834) (xy 100.666338 -108.055596)
			(xy 100.615695 -108.041274) (xy 100.567496 -108.020138) (xy 100.522653 -107.992589) (xy 100.482014 -107.959147)
			(xy 100.463858 -107.940094) (xy 100.456355 -107.932671) (xy 100.437061 -107.924159) (xy 100.42652 -107.923584)
			(xy 100.351844 -107.923584) (xy 100.341296 -107.924128) (xy 100.322001 -107.932653) (xy 100.314506 -107.940094)
			(xy 100.296339 -107.959139) (xy 100.255712 -107.992597) (xy 100.210874 -108.020158) (xy 100.162676 -108.041298)
			(xy 100.11203 -108.055617) (xy 100.059898 -108.062844) (xy 100.033582 -108.063284) (xy 100.00633 -108.062845)
			(xy 99.952381 -108.055086) (xy 99.900085 -108.039728) (xy 99.850507 -108.017085) (xy 99.804656 -107.987616)
			(xy 99.763465 -107.951922) (xy 99.727773 -107.91073) (xy 99.698307 -107.864877) (xy 99.675666 -107.815298)
			(xy 99.66031 -107.763002) (xy 99.652554 -107.709052) (xy 98.35134 -107.709052) (xy 98.35134 -107.740251)
			(xy 98.343584 -107.794197) (xy 98.328231 -107.846492) (xy 98.305591 -107.896068) (xy 98.276127 -107.941919)
			(xy 98.240438 -107.98311) (xy 98.199251 -108.018803) (xy 98.153404 -108.048272) (xy 98.103829 -108.070917)
			(xy 98.051537 -108.086276) (xy 97.997591 -108.094037) (xy 97.97034 -108.094526) (xy 97.94297 -108.094055)
			(xy 97.88879 -108.086241) (xy 97.836286 -108.070754) (xy 97.786539 -108.047913) (xy 97.740573 -108.018188)
			(xy 97.719642 -108.000546) (xy 97.719388 -108.000292) (xy 97.71231 -107.994693) (xy 97.695387 -107.988454)
			(xy 97.686368 -107.9881) (xy 97.619312 -107.9881) (xy 97.610296 -107.988463) (xy 97.593379 -107.994706)
			(xy 97.586292 -108.000292) (xy 97.586038 -108.000546) (xy 97.565105 -108.018187) (xy 97.519137 -108.047911)
			(xy 97.469391 -108.070757) (xy 97.416889 -108.086253) (xy 97.362711 -108.094082) (xy 97.307969 -108.094082)
			(xy 97.253791 -108.086253) (xy 97.201289 -108.070757) (xy 97.151543 -108.047911) (xy 97.105575 -108.018187)
			(xy 97.084642 -108.000546) (xy 97.084388 -108.000292) (xy 97.07731 -107.994693) (xy 97.060387 -107.988454)
			(xy 97.051368 -107.9881) (xy 96.984312 -107.9881) (xy 96.975296 -107.988463) (xy 96.958379 -107.994706)
			(xy 96.951292 -108.000292) (xy 96.951292 -108.000546) (xy 96.951038 -108.000546) (xy 96.930105 -108.018187)
			(xy 96.884137 -108.047911) (xy 96.834391 -108.070757) (xy 96.781889 -108.086253) (xy 96.727711 -108.094082)
			(xy 96.672969 -108.094082) (xy 96.618791 -108.086253) (xy 96.566289 -108.070757) (xy 96.516543 -108.047911)
			(xy 96.470575 -108.018187) (xy 96.449642 -108.000546) (xy 96.449388 -108.000292) (xy 96.44231 -107.994693)
			(xy 96.425387 -107.988454) (xy 96.416368 -107.9881) (xy 96.349312 -107.9881) (xy 96.340296 -107.988463)
			(xy 96.323379 -107.994706) (xy 96.316292 -108.000292) (xy 96.316292 -108.000546) (xy 96.316038 -108.000546)
			(xy 96.295095 -108.018172) (xy 96.249126 -108.047888) (xy 96.199382 -108.070727) (xy 96.146883 -108.086221)
			(xy 96.092709 -108.094051) (xy 96.06534 -108.094526) (xy 96.038087 -108.094029) (xy 95.984134 -108.086277)
			(xy 95.931834 -108.070926) (xy 95.882251 -108.048286) (xy 95.836395 -108.018821) (xy 95.795199 -107.983129)
			(xy 95.759503 -107.941937) (xy 95.730033 -107.896084) (xy 95.707388 -107.846504) (xy 95.692031 -107.794205)
			(xy 95.684273 -107.740253) (xy 91.5035 -107.740253) (xy 91.5035 -108.39196) (xy 104.22763 -108.39196)
			(xy 104.228124 -108.364591) (xy 104.235934 -108.310413) (xy 104.251416 -108.257909) (xy 104.274252 -108.208162)
			(xy 104.303971 -108.162194) (xy 104.32161 -108.141262) (xy 104.321864 -108.141008) (xy 104.327461 -108.133929)
			(xy 104.3337 -108.117006) (xy 104.334056 -108.107988) (xy 104.334056 -108.040932) (xy 104.333693 -108.031916)
			(xy 104.327451 -108.014998) (xy 104.321864 -108.007912) (xy 104.32161 -108.007912) (xy 104.32161 -108.007658)
			(xy 104.303986 -107.986714) (xy 104.274272 -107.940744) (xy 104.251433 -107.891) (xy 104.235938 -107.838502)
			(xy 104.228106 -107.784328) (xy 104.22763 -107.75696) (xy 104.228116 -107.729709) (xy 104.235872 -107.675761)
			(xy 104.251227 -107.623466) (xy 104.273869 -107.573889) (xy 104.303335 -107.528039) (xy 104.339026 -107.486848)
			(xy 104.380217 -107.451157) (xy 104.426067 -107.421691) (xy 104.475644 -107.399049) (xy 104.527939 -107.383694)
			(xy 104.581887 -107.375938) (xy 104.636389 -107.375938) (xy 104.690337 -107.383694) (xy 104.742632 -107.399049)
			(xy 104.792209 -107.421691) (xy 104.838059 -107.451157) (xy 104.87925 -107.486848) (xy 104.914941 -107.528039)
			(xy 104.944407 -107.573889) (xy 104.967049 -107.623466) (xy 104.982404 -107.675761) (xy 104.99016 -107.729709)
			(xy 104.990646 -107.75696) (xy 104.99017 -107.78433) (xy 104.982356 -107.838509) (xy 104.96687 -107.891013)
			(xy 104.944031 -107.94076) (xy 104.914307 -107.986727) (xy 104.896666 -108.007658) (xy 104.896412 -108.007912)
			(xy 104.890816 -108.014992) (xy 104.884574 -108.031914) (xy 104.88422 -108.040932) (xy 104.88422 -108.107988)
			(xy 104.884578 -108.117005) (xy 104.890824 -108.133922) (xy 104.896412 -108.141008) (xy 104.896666 -108.141008)
			(xy 104.896666 -108.141262) (xy 104.914295 -108.162202) (xy 104.94401 -108.208172) (xy 104.966848 -108.257917)
			(xy 104.982341 -108.310417) (xy 104.990171 -108.364591) (xy 104.990646 -108.39196) (xy 104.99016 -108.419211)
			(xy 104.982404 -108.473159) (xy 104.967049 -108.525454) (xy 104.94693 -108.569506) (xy 106.861102 -108.569506)
			(xy 106.861571 -108.542136) (xy 106.869388 -108.487957) (xy 106.884876 -108.435454) (xy 106.907718 -108.385707)
			(xy 106.937441 -108.33974) (xy 106.955082 -108.318808) (xy 106.955336 -108.318554) (xy 106.96091 -108.311459)
			(xy 106.967163 -108.294549) (xy 106.967528 -108.285534) (xy 106.967528 -108.218478) (xy 106.967176 -108.209461)
			(xy 106.960924 -108.192544) (xy 106.955336 -108.185458) (xy 106.955082 -108.185458) (xy 106.955082 -108.185204)
			(xy 106.937429 -108.164284) (xy 106.907719 -108.118307) (xy 106.884887 -108.068557) (xy 106.869399 -108.016054)
			(xy 106.861574 -107.961876) (xy 106.861102 -107.934506) (xy 106.861588 -107.907255) (xy 106.869344 -107.853307)
			(xy 106.884699 -107.801012) (xy 106.907341 -107.751435) (xy 106.936807 -107.705585) (xy 106.972498 -107.664394)
			(xy 107.013689 -107.628703) (xy 107.059539 -107.599237) (xy 107.109116 -107.576595) (xy 107.161411 -107.56124)
			(xy 107.215359 -107.553484) (xy 107.269861 -107.553484) (xy 107.323809 -107.56124) (xy 107.376104 -107.576595)
			(xy 107.425681 -107.599237) (xy 107.471531 -107.628703) (xy 107.512722 -107.664394) (xy 107.548413 -107.705585)
			(xy 107.577879 -107.751435) (xy 107.600521 -107.801012) (xy 107.615876 -107.853307) (xy 107.623632 -107.907255)
			(xy 107.624118 -107.934506) (xy 107.623675 -107.961877) (xy 107.615855 -108.016058) (xy 107.60057 -108.067856)
			(xy 123.681234 -108.067856) (xy 123.685305 -108.012234) (xy 123.697431 -107.957797) (xy 123.717354 -107.905706)
			(xy 123.74465 -107.857071) (xy 123.778736 -107.812928) (xy 123.818885 -107.774219) (xy 123.864243 -107.741768)
			(xy 123.913843 -107.716267) (xy 123.966627 -107.69826) (xy 124.02147 -107.68813) (xy 124.077204 -107.686093)
			(xy 124.132641 -107.692193) (xy 124.186598 -107.706299) (xy 124.237927 -107.728111) (xy 124.285533 -107.757165)
			(xy 124.328401 -107.79284) (xy 124.365618 -107.834377) (xy 124.396391 -107.88089) (xy 124.420063 -107.931387)
			(xy 124.436131 -107.984794) (xy 124.444251 -108.03997) (xy 124.44476 -108.067856) (xy 124.444251 -108.095742)
			(xy 124.436131 -108.150918) (xy 124.420063 -108.204325) (xy 124.396391 -108.254822) (xy 124.365618 -108.301335)
			(xy 124.328401 -108.342872) (xy 124.285533 -108.378547) (xy 124.237927 -108.407601) (xy 124.186598 -108.429413)
			(xy 124.132641 -108.443519) (xy 124.077204 -108.449619) (xy 124.02147 -108.447582) (xy 123.966627 -108.437452)
			(xy 123.913843 -108.419445) (xy 123.864243 -108.393944) (xy 123.818885 -108.361493) (xy 123.778736 -108.322784)
			(xy 123.74465 -108.278641) (xy 123.717354 -108.230006) (xy 123.697431 -108.177915) (xy 123.685305 -108.123478)
			(xy 123.681234 -108.067856) (xy 107.60057 -108.067856) (xy 107.600362 -108.068562) (xy 107.577514 -108.118309)
			(xy 107.547783 -108.164274) (xy 107.530138 -108.185204) (xy 107.529884 -108.185458) (xy 107.524307 -108.192551)
			(xy 107.518055 -108.209463) (xy 107.517692 -108.218478) (xy 107.517692 -108.285534) (xy 107.518035 -108.294552)
			(xy 107.524293 -108.311469) (xy 107.529884 -108.318554) (xy 107.530138 -108.318554) (xy 107.530138 -108.318808)
			(xy 107.547801 -108.339721) (xy 107.577508 -108.3857) (xy 107.600339 -108.435452) (xy 107.615824 -108.487957)
			(xy 107.623647 -108.542136) (xy 107.624118 -108.569506) (xy 107.623632 -108.596757) (xy 107.615876 -108.650705)
			(xy 107.600521 -108.703) (xy 107.577879 -108.752577) (xy 107.548413 -108.798427) (xy 107.512722 -108.839618)
			(xy 107.471531 -108.875309) (xy 107.425681 -108.904775) (xy 107.376104 -108.927417) (xy 107.323809 -108.942772)
			(xy 107.269861 -108.950528) (xy 107.215359 -108.950528) (xy 107.161411 -108.942772) (xy 107.109116 -108.927417)
			(xy 107.059539 -108.904775) (xy 107.013689 -108.875309) (xy 106.972498 -108.839618) (xy 106.936807 -108.798427)
			(xy 106.907341 -108.752577) (xy 106.884699 -108.703) (xy 106.869344 -108.650705) (xy 106.861588 -108.596757)
			(xy 106.861102 -108.569506) (xy 104.94693 -108.569506) (xy 104.944407 -108.575031) (xy 104.914941 -108.620881)
			(xy 104.87925 -108.662072) (xy 104.838059 -108.697763) (xy 104.792209 -108.727229) (xy 104.742632 -108.749871)
			(xy 104.690337 -108.765226) (xy 104.636389 -108.772982) (xy 104.581887 -108.772982) (xy 104.527939 -108.765226)
			(xy 104.475644 -108.749871) (xy 104.426067 -108.727229) (xy 104.380217 -108.697763) (xy 104.339026 -108.662072)
			(xy 104.303335 -108.620881) (xy 104.273869 -108.575031) (xy 104.251227 -108.525454) (xy 104.235872 -108.473159)
			(xy 104.228116 -108.419211) (xy 104.22763 -108.39196) (xy 91.5035 -108.39196) (xy 91.5035 -109.502448)
			(xy 109.415072 -109.502448) (xy 109.415558 -109.475197) (xy 109.423314 -109.421249) (xy 109.438669 -109.368954)
			(xy 109.461311 -109.319377) (xy 109.490777 -109.273527) (xy 109.526468 -109.232336) (xy 109.567659 -109.196645)
			(xy 109.613509 -109.167179) (xy 109.663086 -109.144537) (xy 109.715381 -109.129182) (xy 109.769329 -109.121426)
			(xy 109.823831 -109.121426) (xy 109.877779 -109.129182) (xy 109.930074 -109.144537) (xy 109.979651 -109.167179)
			(xy 110.025501 -109.196645) (xy 110.066692 -109.232336) (xy 110.102383 -109.273527) (xy 110.131849 -109.319377)
			(xy 110.154491 -109.368954) (xy 110.169846 -109.421249) (xy 110.177602 -109.475197) (xy 110.178088 -109.502448)
			(xy 110.17766 -109.527979) (xy 110.170855 -109.578587) (xy 110.15736 -109.627834) (xy 110.137415 -109.674841)
			(xy 110.124748 -109.697012) (xy 110.118894 -109.706918) (xy 121.915172 -109.706918) (xy 121.919243 -109.651296)
			(xy 121.931369 -109.596859) (xy 121.951292 -109.544768) (xy 121.978588 -109.496133) (xy 122.012674 -109.45199)
			(xy 122.052823 -109.413281) (xy 122.098181 -109.38083) (xy 122.147781 -109.355329) (xy 122.200565 -109.337322)
			(xy 122.255408 -109.327192) (xy 122.311142 -109.325155) (xy 122.366579 -109.331255) (xy 122.420536 -109.345361)
			(xy 122.471865 -109.367173) (xy 122.519471 -109.396227) (xy 122.562339 -109.431902) (xy 122.599556 -109.473439)
			(xy 122.630329 -109.519952) (xy 122.654001 -109.570449) (xy 122.65685 -109.579918) (xy 123.947172 -109.579918)
			(xy 123.951243 -109.524296) (xy 123.963369 -109.469859) (xy 123.983292 -109.417768) (xy 124.010588 -109.369133)
			(xy 124.044674 -109.32499) (xy 124.084823 -109.286281) (xy 124.130181 -109.25383) (xy 124.179781 -109.228329)
			(xy 124.232565 -109.210322) (xy 124.287408 -109.200192) (xy 124.343142 -109.198155) (xy 124.398579 -109.204255)
			(xy 124.452536 -109.218361) (xy 124.503865 -109.240173) (xy 124.551471 -109.269227) (xy 124.594339 -109.304902)
			(xy 124.631556 -109.346439) (xy 124.662329 -109.392952) (xy 124.679962 -109.430566) (xy 140.055852 -109.430566)
			(xy 140.059923 -109.374944) (xy 140.072049 -109.320507) (xy 140.091972 -109.268416) (xy 140.119268 -109.219781)
			(xy 140.153354 -109.175638) (xy 140.193503 -109.136929) (xy 140.238861 -109.104478) (xy 140.288461 -109.078977)
			(xy 140.341245 -109.06097) (xy 140.396088 -109.05084) (xy 140.451822 -109.048803) (xy 140.507259 -109.054903)
			(xy 140.561216 -109.069009) (xy 140.612545 -109.090821) (xy 140.660151 -109.119875) (xy 140.703019 -109.15555)
			(xy 140.740236 -109.197087) (xy 140.771009 -109.2436) (xy 140.794681 -109.294097) (xy 140.810749 -109.347504)
			(xy 140.818869 -109.40268) (xy 140.819016 -109.410732) (xy 150.191451 -109.410732) (xy 150.191451 -109.353468)
			(xy 150.1996 -109.296786) (xy 150.215733 -109.24184) (xy 150.23952 -109.18975) (xy 150.270479 -109.141575)
			(xy 150.307978 -109.098296) (xy 150.351254 -109.060794) (xy 150.399427 -109.029833) (xy 150.451516 -109.006042)
			(xy 150.50646 -108.989905) (xy 150.563142 -108.981752) (xy 150.591774 -108.98124) (xy 150.606688 -108.981346)
			(xy 150.636437 -108.983509) (xy 150.65121 -108.985558) (xy 150.662386 -108.987336) (xy 150.683468 -108.98124)
			(xy 150.75027 -108.923582) (xy 150.758256 -108.916007) (xy 150.767328 -108.895973) (xy 150.767796 -108.884974)
			(xy 150.767796 -108.620306) (xy 150.767288 -108.609317) (xy 150.758215 -108.589305) (xy 150.75027 -108.581698)
			(xy 150.683468 -108.52404) (xy 150.662386 -108.517944) (xy 150.65121 -108.519722) (xy 150.636438 -108.521776)
			(xy 150.606688 -108.523933) (xy 150.591774 -108.52404) (xy 150.563147 -108.523472) (xy 150.506476 -108.51532)
			(xy 150.451543 -108.499187) (xy 150.399464 -108.475401) (xy 150.3513 -108.444445) (xy 150.308032 -108.40695)
			(xy 150.27054 -108.363679) (xy 150.239587 -108.315513) (xy 150.215804 -108.263433) (xy 150.199674 -108.208498)
			(xy 150.191526 -108.151827) (xy 150.191526 -108.094573) (xy 150.199674 -108.037902) (xy 150.215804 -107.982967)
			(xy 150.239587 -107.930887) (xy 150.27054 -107.882721) (xy 150.308032 -107.83945) (xy 150.3513 -107.801955)
			(xy 150.399464 -107.770999) (xy 150.451543 -107.747213) (xy 150.506476 -107.73108) (xy 150.563147 -107.722928)
			(xy 150.591774 -107.722416) (xy 150.619143 -107.722907) (xy 150.673374 -107.730348) (xy 150.726088 -107.745096)
			(xy 150.776307 -107.766877) (xy 150.823097 -107.795286) (xy 150.865588 -107.829794) (xy 150.902991 -107.869761)
			(xy 150.91918 -107.891834) (xy 150.924764 -107.899076) (xy 150.939857 -107.909372) (xy 150.948644 -107.9119)
			(xy 150.978616 -107.919266) (xy 150.987565 -107.921019) (xy 151.005655 -107.918799) (xy 151.013922 -107.914948)
			(xy 151.038521 -107.902573) (xy 151.090059 -107.883175) (xy 151.14355 -107.870097) (xy 151.198224 -107.863525)
			(xy 151.225758 -107.863132) (xy 151.253293 -107.863504) (xy 151.307968 -107.870075) (xy 151.361458 -107.883164)
			(xy 151.41299 -107.90258) (xy 151.437594 -107.914948) (xy 151.445855 -107.918822) (xy 151.463951 -107.92104)
			(xy 151.4729 -107.919266) (xy 151.502872 -107.9119) (xy 151.511643 -107.909328) (xy 151.526749 -107.899066)
			(xy 151.532336 -107.891834) (xy 151.548495 -107.869737) (xy 151.585902 -107.829767) (xy 151.628397 -107.795257)
			(xy 151.675192 -107.766847) (xy 151.725415 -107.745066) (xy 151.778135 -107.730319) (xy 151.83237 -107.722879)
			(xy 151.859742 -107.722416) (xy 151.888372 -107.722873) (xy 151.945049 -107.731028) (xy 151.999989 -107.747165)
			(xy 152.052073 -107.770956) (xy 152.100241 -107.801916) (xy 152.143514 -107.839416) (xy 152.181009 -107.882692)
			(xy 152.211965 -107.930864) (xy 152.23575 -107.982951) (xy 152.251881 -108.037892) (xy 152.26003 -108.09457)
			(xy 152.26003 -108.15183) (xy 152.251881 -108.208508) (xy 152.23575 -108.263449) (xy 152.228217 -108.279946)
			(xy 163.111432 -108.279946) (xy 163.115503 -108.224324) (xy 163.127629 -108.169887) (xy 163.147552 -108.117796)
			(xy 163.174848 -108.069161) (xy 163.208934 -108.025018) (xy 163.249083 -107.986309) (xy 163.294441 -107.953858)
			(xy 163.344041 -107.928357) (xy 163.396825 -107.91035) (xy 163.451668 -107.90022) (xy 163.507402 -107.898183)
			(xy 163.562839 -107.904283) (xy 163.616796 -107.918389) (xy 163.668125 -107.940201) (xy 163.715731 -107.969255)
			(xy 163.758599 -108.00493) (xy 163.795816 -108.046467) (xy 163.826589 -108.09298) (xy 163.850261 -108.143477)
			(xy 163.866329 -108.196884) (xy 163.874449 -108.25206) (xy 163.874958 -108.279946) (xy 163.874449 -108.307832)
			(xy 163.866329 -108.363008) (xy 163.850261 -108.416415) (xy 163.826589 -108.466912) (xy 163.795816 -108.513425)
			(xy 163.758599 -108.554962) (xy 163.715731 -108.590637) (xy 163.668125 -108.619691) (xy 163.616796 -108.641503)
			(xy 163.562839 -108.655609) (xy 163.507402 -108.661709) (xy 163.451668 -108.659672) (xy 163.396825 -108.649542)
			(xy 163.344041 -108.631535) (xy 163.294441 -108.606034) (xy 163.249083 -108.573583) (xy 163.208934 -108.534874)
			(xy 163.174848 -108.490731) (xy 163.147552 -108.442096) (xy 163.127629 -108.390005) (xy 163.115503 -108.335568)
			(xy 163.111432 -108.279946) (xy 152.228217 -108.279946) (xy 152.211965 -108.315536) (xy 152.181009 -108.363708)
			(xy 152.143514 -108.406984) (xy 152.100241 -108.444484) (xy 152.052073 -108.475444) (xy 151.999989 -108.499235)
			(xy 151.945049 -108.515372) (xy 151.888372 -108.523527) (xy 151.859742 -108.52404) (xy 151.844828 -108.523932)
			(xy 151.815079 -108.52177) (xy 151.800306 -108.519722) (xy 151.78913 -108.517944) (xy 151.768048 -108.52404)
			(xy 151.701246 -108.581698) (xy 151.693272 -108.589284) (xy 151.684193 -108.609309) (xy 151.68372 -108.620306)
			(xy 151.68372 -108.884974) (xy 151.684178 -108.895969) (xy 151.693286 -108.915981) (xy 151.701246 -108.923582)
			(xy 151.768048 -108.98124) (xy 151.78913 -108.987336) (xy 151.800306 -108.985558) (xy 151.81508 -108.983514)
			(xy 151.844828 -108.98135) (xy 151.859742 -108.98124) (xy 151.888367 -108.981849) (xy 151.945033 -108.990002)
			(xy 151.999962 -109.006136) (xy 152.052036 -109.029922) (xy 152.100196 -109.060877) (xy 152.14346 -109.09837)
			(xy 152.180948 -109.141638) (xy 152.203883 -109.177328) (xy 165.164768 -109.177328) (xy 165.168839 -109.121706)
			(xy 165.180965 -109.067269) (xy 165.200888 -109.015178) (xy 165.228184 -108.966543) (xy 165.26227 -108.9224)
			(xy 165.302419 -108.883691) (xy 165.347777 -108.85124) (xy 165.397377 -108.825739) (xy 165.450161 -108.807732)
			(xy 165.505004 -108.797602) (xy 165.560738 -108.795565) (xy 165.616175 -108.801665) (xy 165.670132 -108.815771)
			(xy 165.721461 -108.837583) (xy 165.769067 -108.866637) (xy 165.811935 -108.902312) (xy 165.849152 -108.943849)
			(xy 165.879925 -108.990362) (xy 165.903597 -109.040859) (xy 165.919665 -109.094266) (xy 165.927785 -109.149442)
			(xy 165.928294 -109.177328) (xy 165.927785 -109.205214) (xy 165.919665 -109.26039) (xy 165.903597 -109.313797)
			(xy 165.879925 -109.364294) (xy 165.849152 -109.410807) (xy 165.811935 -109.452344) (xy 165.769067 -109.488019)
			(xy 165.721461 -109.517073) (xy 165.670132 -109.538885) (xy 165.616175 -109.552991) (xy 165.560738 -109.559091)
			(xy 165.505004 -109.557054) (xy 165.450161 -109.546924) (xy 165.397377 -109.528917) (xy 165.347777 -109.503416)
			(xy 165.302419 -109.470965) (xy 165.26227 -109.432256) (xy 165.228184 -109.388113) (xy 165.200888 -109.339478)
			(xy 165.180965 -109.287387) (xy 165.168839 -109.23295) (xy 165.164768 -109.177328) (xy 152.203883 -109.177328)
			(xy 152.211898 -109.189801) (xy 152.235679 -109.241877) (xy 152.251807 -109.296808) (xy 152.259954 -109.353475)
			(xy 152.259954 -109.410725) (xy 152.251807 -109.467392) (xy 152.235679 -109.522323) (xy 152.211898 -109.574399)
			(xy 152.180948 -109.622562) (xy 152.14346 -109.66583) (xy 152.100196 -109.703323) (xy 152.052036 -109.734278)
			(xy 151.999962 -109.758064) (xy 151.945033 -109.774198) (xy 151.888367 -109.782351) (xy 151.859742 -109.782864)
			(xy 151.832373 -109.78237) (xy 151.778142 -109.77493) (xy 151.725427 -109.760183) (xy 151.675208 -109.738403)
			(xy 151.628418 -109.709995) (xy 151.585927 -109.675486) (xy 151.548525 -109.635519) (xy 151.532336 -109.613446)
			(xy 151.526751 -109.606205) (xy 151.511658 -109.595909) (xy 151.502872 -109.59338) (xy 151.4729 -109.586014)
			(xy 151.463949 -109.584271) (xy 151.445861 -109.586484) (xy 151.437594 -109.590332) (xy 151.412992 -109.6027)
			(xy 151.361455 -109.622099) (xy 151.307965 -109.63518) (xy 151.253292 -109.641754) (xy 151.225758 -109.642148)
			(xy 151.198224 -109.641772) (xy 151.143549 -109.635202) (xy 151.090058 -109.622115) (xy 151.038526 -109.602699)
			(xy 151.013922 -109.590332) (xy 151.005658 -109.586466) (xy 150.987565 -109.584243) (xy 150.978616 -109.586014)
			(xy 150.948644 -109.59338) (xy 150.939852 -109.595894) (xy 150.924756 -109.606196) (xy 150.91918 -109.613446)
			(xy 150.903005 -109.635531) (xy 150.865602 -109.675502) (xy 150.823109 -109.710014) (xy 150.776318 -109.738425)
			(xy 150.726096 -109.760208) (xy 150.673379 -109.774958) (xy 150.619145 -109.7824) (xy 150.591774 -109.782864)
			(xy 150.563142 -109.782448) (xy 150.50646 -109.774295) (xy 150.451516 -109.758158) (xy 150.399427 -109.734367)
			(xy 150.351254 -109.703406) (xy 150.307978 -109.665904) (xy 150.270479 -109.622625) (xy 150.23952 -109.57445)
			(xy 150.215733 -109.52236) (xy 150.1996 -109.467414) (xy 150.191451 -109.410732) (xy 140.819016 -109.410732)
			(xy 140.819378 -109.430566) (xy 140.818869 -109.458452) (xy 140.810749 -109.513628) (xy 140.794681 -109.567035)
			(xy 140.771009 -109.617532) (xy 140.740236 -109.664045) (xy 140.703019 -109.705582) (xy 140.660151 -109.741257)
			(xy 140.612545 -109.770311) (xy 140.561216 -109.792123) (xy 140.507259 -109.806229) (xy 140.451822 -109.812329)
			(xy 140.396088 -109.810292) (xy 140.341245 -109.800162) (xy 140.288461 -109.782155) (xy 140.238861 -109.756654)
			(xy 140.193503 -109.724203) (xy 140.153354 -109.685494) (xy 140.119268 -109.641351) (xy 140.091972 -109.592716)
			(xy 140.072049 -109.540625) (xy 140.059923 -109.486188) (xy 140.055852 -109.430566) (xy 124.679962 -109.430566)
			(xy 124.686001 -109.443449) (xy 124.702069 -109.496856) (xy 124.710189 -109.552032) (xy 124.710698 -109.579918)
			(xy 124.710189 -109.607804) (xy 124.702069 -109.66298) (xy 124.686001 -109.716387) (xy 124.662329 -109.766884)
			(xy 124.631556 -109.813397) (xy 124.594339 -109.854934) (xy 124.551471 -109.890609) (xy 124.503865 -109.919663)
			(xy 124.452536 -109.941475) (xy 124.437729 -109.945346) (xy 152.833367 -109.945346) (xy 152.833367 -109.888054)
			(xy 152.84152 -109.831346) (xy 152.857661 -109.776374) (xy 152.88146 -109.72426) (xy 152.912433 -109.676062)
			(xy 152.949951 -109.632763) (xy 152.993248 -109.595244) (xy 153.041444 -109.564269) (xy 153.093558 -109.540467)
			(xy 153.148528 -109.524324) (xy 153.205236 -109.516168) (xy 153.233882 -109.515656) (xy 153.261261 -109.516154)
			(xy 153.315509 -109.523618) (xy 153.368237 -109.538397) (xy 153.418462 -109.560214) (xy 153.46525 -109.588664)
			(xy 153.507731 -109.623218) (xy 153.545113 -109.663232) (xy 153.561288 -109.685328) (xy 153.56687 -109.692571)
			(xy 153.581964 -109.702867) (xy 153.590752 -109.705394) (xy 153.620724 -109.71276) (xy 153.629673 -109.714518)
			(xy 153.647763 -109.712295) (xy 153.65603 -109.708442) (xy 153.680624 -109.696039) (xy 153.732152 -109.676574)
			(xy 153.785643 -109.66343) (xy 153.840325 -109.656796) (xy 153.867866 -109.656372) (xy 153.895407 -109.656787)
			(xy 153.950088 -109.663426) (xy 154.003577 -109.676577) (xy 154.055103 -109.696049) (xy 154.079702 -109.708442)
			(xy 154.087962 -109.712319) (xy 154.106058 -109.714535) (xy 154.115008 -109.71276) (xy 154.14498 -109.705394)
			(xy 154.153753 -109.702827) (xy 154.168858 -109.692561) (xy 154.174444 -109.685328) (xy 154.19059 -109.663207)
			(xy 154.227966 -109.623175) (xy 154.270446 -109.588607) (xy 154.317238 -109.560147) (xy 154.367471 -109.538327)
			(xy 154.420208 -109.523553) (xy 154.474466 -109.516099) (xy 154.50185 -109.515656) (xy 154.530504 -109.516095)
			(xy 154.587229 -109.524245) (xy 154.642217 -109.540385) (xy 154.694348 -109.564186) (xy 154.742561 -109.595165)
			(xy 154.785874 -109.632691) (xy 154.796491 -109.644942) (xy 160.769552 -109.644942) (xy 160.773623 -109.58932)
			(xy 160.785749 -109.534883) (xy 160.805672 -109.482792) (xy 160.832968 -109.434157) (xy 160.867054 -109.390014)
			(xy 160.907203 -109.351305) (xy 160.952561 -109.318854) (xy 161.002161 -109.293353) (xy 161.054945 -109.275346)
			(xy 161.109788 -109.265216) (xy 161.165522 -109.263179) (xy 161.220959 -109.269279) (xy 161.274916 -109.283385)
			(xy 161.326245 -109.305197) (xy 161.373851 -109.334251) (xy 161.416719 -109.369926) (xy 161.453936 -109.411463)
			(xy 161.484709 -109.457976) (xy 161.508381 -109.508473) (xy 161.524449 -109.56188) (xy 161.532569 -109.617056)
			(xy 161.533078 -109.644942) (xy 161.532569 -109.672828) (xy 161.524449 -109.728004) (xy 161.508381 -109.781411)
			(xy 161.484709 -109.831908) (xy 161.453936 -109.878421) (xy 161.416719 -109.919958) (xy 161.373851 -109.955633)
			(xy 161.326245 -109.984687) (xy 161.274916 -110.006499) (xy 161.220959 -110.020605) (xy 161.165522 -110.026705)
			(xy 161.109788 -110.024668) (xy 161.054945 -110.014538) (xy 161.002161 -109.996531) (xy 160.952561 -109.97103)
			(xy 160.907203 -109.938579) (xy 160.867054 -109.89987) (xy 160.832968 -109.855727) (xy 160.805672 -109.807092)
			(xy 160.785749 -109.755001) (xy 160.773623 -109.700564) (xy 160.769552 -109.644942) (xy 154.796491 -109.644942)
			(xy 154.823405 -109.675999) (xy 154.85439 -109.724208) (xy 154.878198 -109.776336) (xy 154.894345 -109.831322)
			(xy 154.902501 -109.888046) (xy 154.902501 -109.945354) (xy 154.894345 -110.002078) (xy 154.878198 -110.057064)
			(xy 154.85439 -110.109192) (xy 154.823405 -110.157401) (xy 154.785874 -110.200709) (xy 154.742561 -110.238235)
			(xy 154.694348 -110.269214) (xy 154.642217 -110.293015) (xy 154.587229 -110.309155) (xy 154.530504 -110.317305)
			(xy 154.50185 -110.317788) (xy 154.486932 -110.317619) (xy 154.457183 -110.31533) (xy 154.442414 -110.313216)
			(xy 154.431238 -110.311438) (xy 154.410156 -110.317534) (xy 154.343354 -110.375192) (xy 154.335384 -110.382781)
			(xy 154.326303 -110.402804) (xy 154.325828 -110.4138) (xy 154.325828 -110.678468) (xy 154.326287 -110.689463)
			(xy 154.335394 -110.709475) (xy 154.343354 -110.717076) (xy 154.410156 -110.774734) (xy 154.431238 -110.78083)
			(xy 154.442414 -110.779052) (xy 154.457183 -110.776939) (xy 154.486932 -110.774654) (xy 154.50185 -110.77448)
			(xy 154.530506 -110.774871) (xy 154.587234 -110.783021) (xy 154.642226 -110.799162) (xy 154.69436 -110.822965)
			(xy 154.742575 -110.853946) (xy 154.746721 -110.857538) (xy 165.064438 -110.857538) (xy 165.068509 -110.801916)
			(xy 165.080635 -110.747479) (xy 165.100558 -110.695388) (xy 165.127854 -110.646753) (xy 165.16194 -110.60261)
			(xy 165.202089 -110.563901) (xy 165.247447 -110.53145) (xy 165.297047 -110.505949) (xy 165.349831 -110.487942)
			(xy 165.404674 -110.477812) (xy 165.460408 -110.475775) (xy 165.515845 -110.481875) (xy 165.569802 -110.495981)
			(xy 165.621131 -110.517793) (xy 165.668737 -110.546847) (xy 165.711605 -110.582522) (xy 165.748822 -110.624059)
			(xy 165.779595 -110.670572) (xy 165.803267 -110.721069) (xy 165.819335 -110.774476) (xy 165.827455 -110.829652)
			(xy 165.827964 -110.857538) (xy 165.827455 -110.885424) (xy 165.819335 -110.9406) (xy 165.803267 -110.994007)
			(xy 165.779595 -111.044504) (xy 165.748822 -111.091017) (xy 165.711605 -111.132554) (xy 165.668737 -111.168229)
			(xy 165.621131 -111.197283) (xy 165.569802 -111.219095) (xy 165.515845 -111.233201) (xy 165.460408 -111.239301)
			(xy 165.404674 -111.237264) (xy 165.349831 -111.227134) (xy 165.297047 -111.209127) (xy 165.247447 -111.183626)
			(xy 165.202089 -111.151175) (xy 165.16194 -111.112466) (xy 165.127854 -111.068323) (xy 165.100558 -111.019688)
			(xy 165.080635 -110.967597) (xy 165.068509 -110.91316) (xy 165.064438 -110.857538) (xy 154.746721 -110.857538)
			(xy 154.785891 -110.891474) (xy 154.823424 -110.934785) (xy 154.854411 -110.982996) (xy 154.87822 -111.035128)
			(xy 154.894368 -111.090117) (xy 154.902525 -111.146844) (xy 154.902525 -111.204156) (xy 154.894368 -111.260883)
			(xy 154.87822 -111.315872) (xy 154.854411 -111.368004) (xy 154.823424 -111.416215) (xy 154.798444 -111.44504)
			(xy 160.769552 -111.44504) (xy 160.773623 -111.389418) (xy 160.785749 -111.334981) (xy 160.805672 -111.28289)
			(xy 160.832968 -111.234255) (xy 160.867054 -111.190112) (xy 160.907203 -111.151403) (xy 160.952561 -111.118952)
			(xy 161.002161 -111.093451) (xy 161.054945 -111.075444) (xy 161.109788 -111.065314) (xy 161.165522 -111.063277)
			(xy 161.220959 -111.069377) (xy 161.274916 -111.083483) (xy 161.326245 -111.105295) (xy 161.373851 -111.134349)
			(xy 161.416719 -111.170024) (xy 161.453936 -111.211561) (xy 161.484709 -111.258074) (xy 161.508381 -111.308571)
			(xy 161.524449 -111.361978) (xy 161.532569 -111.417154) (xy 161.533078 -111.44504) (xy 161.532569 -111.472926)
			(xy 161.524449 -111.528102) (xy 161.508381 -111.581509) (xy 161.484709 -111.632006) (xy 161.453936 -111.678519)
			(xy 161.416719 -111.720056) (xy 161.373851 -111.755731) (xy 161.326245 -111.784785) (xy 161.274916 -111.806597)
			(xy 161.220959 -111.820703) (xy 161.165522 -111.826803) (xy 161.109788 -111.824766) (xy 161.054945 -111.814636)
			(xy 161.002161 -111.796629) (xy 160.952561 -111.771128) (xy 160.907203 -111.738677) (xy 160.867054 -111.699968)
			(xy 160.832968 -111.655825) (xy 160.805672 -111.60719) (xy 160.785749 -111.555099) (xy 160.773623 -111.500662)
			(xy 160.769552 -111.44504) (xy 154.798444 -111.44504) (xy 154.785891 -111.459526) (xy 154.742575 -111.497054)
			(xy 154.69436 -111.528035) (xy 154.642226 -111.551838) (xy 154.587234 -111.567979) (xy 154.530506 -111.576129)
			(xy 154.50185 -111.576612) (xy 154.474468 -111.576178) (xy 154.420217 -111.568704) (xy 154.367488 -111.553916)
			(xy 154.317262 -111.532088) (xy 154.270474 -111.503628) (xy 154.227996 -111.469064) (xy 154.190617 -111.42904)
			(xy 154.174444 -111.40694) (xy 154.168892 -111.39967) (xy 154.153776 -111.38939) (xy 154.14498 -111.386874)
			(xy 154.115008 -111.379508) (xy 154.106057 -111.37777) (xy 154.087969 -111.37998) (xy 154.079702 -111.383826)
			(xy 154.055102 -111.396215) (xy 154.003576 -111.415684) (xy 153.950086 -111.428832) (xy 153.895406 -111.43547)
			(xy 153.867866 -111.435896) (xy 153.840325 -111.435472) (xy 153.785645 -111.428836) (xy 153.732155 -111.415688)
			(xy 153.680629 -111.396218) (xy 153.65603 -111.383826) (xy 153.647765 -111.379964) (xy 153.629673 -111.377739)
			(xy 153.620724 -111.379508) (xy 153.590752 -111.386874) (xy 153.581962 -111.389393) (xy 153.566865 -111.399692)
			(xy 153.561288 -111.40694) (xy 153.545112 -111.429039) (xy 153.507743 -111.469073) (xy 153.465269 -111.503644)
			(xy 153.418481 -111.532107) (xy 153.368252 -111.55393) (xy 153.315519 -111.568709) (xy 153.261264 -111.576166)
			(xy 153.233882 -111.576612) (xy 153.205238 -111.576008) (xy 153.148533 -111.567852) (xy 153.093566 -111.55171)
			(xy 153.041455 -111.52791) (xy 152.993262 -111.496937) (xy 152.949968 -111.45942) (xy 152.912453 -111.416123)
			(xy 152.881481 -111.367929) (xy 152.857683 -111.315817) (xy 152.841544 -111.260849) (xy 152.833391 -111.204144)
			(xy 152.833391 -111.146856) (xy 152.841544 -111.090151) (xy 152.857683 -111.035183) (xy 152.881481 -110.983071)
			(xy 152.912453 -110.934877) (xy 152.949968 -110.89158) (xy 152.993262 -110.854063) (xy 153.041455 -110.82309)
			(xy 153.093566 -110.79929) (xy 153.148533 -110.783148) (xy 153.205238 -110.774992) (xy 153.233882 -110.77448)
			(xy 153.2488 -110.774645) (xy 153.278549 -110.776937) (xy 153.293318 -110.779052) (xy 153.304494 -110.78083)
			(xy 153.325576 -110.774734) (xy 153.392378 -110.717076) (xy 153.400368 -110.709504) (xy 153.409437 -110.689468)
			(xy 153.409904 -110.678468) (xy 153.409904 -110.4138) (xy 153.409397 -110.402811) (xy 153.400323 -110.382799)
			(xy 153.392378 -110.375192) (xy 153.325576 -110.317534) (xy 153.304494 -110.311438) (xy 153.293318 -110.313216)
			(xy 153.278549 -110.315325) (xy 153.2488 -110.317613) (xy 153.233882 -110.317788) (xy 153.205236 -110.317232)
			(xy 153.148528 -110.309076) (xy 153.093558 -110.292933) (xy 153.041444 -110.269131) (xy 152.993248 -110.238156)
			(xy 152.949951 -110.200637) (xy 152.912433 -110.157338) (xy 152.88146 -110.10914) (xy 152.857661 -110.057026)
			(xy 152.84152 -110.002054) (xy 152.833367 -109.945346) (xy 124.437729 -109.945346) (xy 124.398579 -109.955581)
			(xy 124.343142 -109.961681) (xy 124.287408 -109.959644) (xy 124.232565 -109.949514) (xy 124.179781 -109.931507)
			(xy 124.130181 -109.906006) (xy 124.084823 -109.873555) (xy 124.044674 -109.834846) (xy 124.010588 -109.790703)
			(xy 123.983292 -109.742068) (xy 123.963369 -109.689977) (xy 123.951243 -109.63554) (xy 123.947172 -109.579918)
			(xy 122.65685 -109.579918) (xy 122.670069 -109.623856) (xy 122.678189 -109.679032) (xy 122.678698 -109.706918)
			(xy 122.678189 -109.734804) (xy 122.670069 -109.78998) (xy 122.654001 -109.843387) (xy 122.630329 -109.893884)
			(xy 122.599556 -109.940397) (xy 122.562339 -109.981934) (xy 122.519471 -110.017609) (xy 122.471865 -110.046663)
			(xy 122.420536 -110.068475) (xy 122.366579 -110.082581) (xy 122.311142 -110.088681) (xy 122.255408 -110.086644)
			(xy 122.200565 -110.076514) (xy 122.147781 -110.058507) (xy 122.098181 -110.033006) (xy 122.052823 -110.000555)
			(xy 122.012674 -109.961846) (xy 121.978588 -109.917703) (xy 121.951292 -109.869068) (xy 121.931369 -109.816977)
			(xy 121.919243 -109.76254) (xy 121.915172 -109.706918) (xy 110.118894 -109.706918) (xy 110.118144 -109.708188)
			(xy 110.117128 -109.734096) (xy 110.161832 -109.822234) (xy 110.165963 -109.829712) (xy 110.178262 -109.841559)
			(xy 110.193755 -109.84874) (xy 110.202218 -109.84992) (xy 110.202472 -109.84992) (xy 110.230448 -109.853053)
			(xy 110.285083 -109.866627) (xy 110.33713 -109.888083) (xy 110.385459 -109.916954) (xy 110.429021 -109.952614)
			(xy 110.466869 -109.994288) (xy 110.498182 -110.041072) (xy 110.522279 -110.09195) (xy 110.538639 -110.145816)
			(xy 110.546904 -110.201502) (xy 110.547404 -110.22965) (xy 110.546865 -110.257812) (xy 110.53859 -110.313524)
			(xy 110.522213 -110.367413) (xy 110.498091 -110.418309) (xy 110.466747 -110.465105) (xy 110.428862 -110.506783)
			(xy 110.418014 -110.515654) (xy 110.828072 -110.515654) (xy 110.832143 -110.460032) (xy 110.844269 -110.405595)
			(xy 110.864192 -110.353504) (xy 110.891488 -110.304869) (xy 110.925574 -110.260726) (xy 110.965723 -110.222017)
			(xy 111.011081 -110.189566) (xy 111.060681 -110.164065) (xy 111.113465 -110.146058) (xy 111.168308 -110.135928)
			(xy 111.224042 -110.133891) (xy 111.279479 -110.139991) (xy 111.333436 -110.154097) (xy 111.384765 -110.175909)
			(xy 111.432371 -110.204963) (xy 111.475239 -110.240638) (xy 111.512456 -110.282175) (xy 111.543229 -110.328688)
			(xy 111.560266 -110.365032) (xy 129.880612 -110.365032) (xy 129.884683 -110.30941) (xy 129.896809 -110.254973)
			(xy 129.916732 -110.202882) (xy 129.944028 -110.154247) (xy 129.978114 -110.110104) (xy 130.018263 -110.071395)
			(xy 130.063621 -110.038944) (xy 130.113221 -110.013443) (xy 130.166005 -109.995436) (xy 130.220848 -109.985306)
			(xy 130.276582 -109.983269) (xy 130.332019 -109.989369) (xy 130.385976 -110.003475) (xy 130.437305 -110.025287)
			(xy 130.484911 -110.054341) (xy 130.527779 -110.090016) (xy 130.564996 -110.131553) (xy 130.595769 -110.178066)
			(xy 130.619441 -110.228563) (xy 130.635509 -110.28197) (xy 130.643629 -110.337146) (xy 130.644138 -110.365032)
			(xy 130.896612 -110.365032) (xy 130.900683 -110.30941) (xy 130.912809 -110.254973) (xy 130.932732 -110.202882)
			(xy 130.960028 -110.154247) (xy 130.994114 -110.110104) (xy 131.034263 -110.071395) (xy 131.079621 -110.038944)
			(xy 131.129221 -110.013443) (xy 131.182005 -109.995436) (xy 131.236848 -109.985306) (xy 131.292582 -109.983269)
			(xy 131.348019 -109.989369) (xy 131.401976 -110.003475) (xy 131.453305 -110.025287) (xy 131.500911 -110.054341)
			(xy 131.543779 -110.090016) (xy 131.580996 -110.131553) (xy 131.611769 -110.178066) (xy 131.635441 -110.228563)
			(xy 131.651509 -110.28197) (xy 131.659629 -110.337146) (xy 131.660138 -110.365032) (xy 131.912612 -110.365032)
			(xy 131.916683 -110.30941) (xy 131.928809 -110.254973) (xy 131.948732 -110.202882) (xy 131.976028 -110.154247)
			(xy 132.010114 -110.110104) (xy 132.050263 -110.071395) (xy 132.095621 -110.038944) (xy 132.145221 -110.013443)
			(xy 132.198005 -109.995436) (xy 132.252848 -109.985306) (xy 132.308582 -109.983269) (xy 132.364019 -109.989369)
			(xy 132.417976 -110.003475) (xy 132.469305 -110.025287) (xy 132.516911 -110.054341) (xy 132.559779 -110.090016)
			(xy 132.596996 -110.131553) (xy 132.627769 -110.178066) (xy 132.651441 -110.228563) (xy 132.667509 -110.28197)
			(xy 132.675629 -110.337146) (xy 132.676138 -110.365032) (xy 132.675629 -110.392918) (xy 132.667509 -110.448094)
			(xy 132.651441 -110.501501) (xy 132.627769 -110.551998) (xy 132.596996 -110.598511) (xy 132.559779 -110.640048)
			(xy 132.516911 -110.675723) (xy 132.469305 -110.704777) (xy 132.417976 -110.726589) (xy 132.364019 -110.740695)
			(xy 132.308582 -110.746795) (xy 132.252848 -110.744758) (xy 132.198005 -110.734628) (xy 132.145221 -110.716621)
			(xy 132.095621 -110.69112) (xy 132.050263 -110.658669) (xy 132.010114 -110.61996) (xy 131.976028 -110.575817)
			(xy 131.948732 -110.527182) (xy 131.928809 -110.475091) (xy 131.916683 -110.420654) (xy 131.912612 -110.365032)
			(xy 131.660138 -110.365032) (xy 131.659629 -110.392918) (xy 131.651509 -110.448094) (xy 131.635441 -110.501501)
			(xy 131.611769 -110.551998) (xy 131.580996 -110.598511) (xy 131.543779 -110.640048) (xy 131.500911 -110.675723)
			(xy 131.453305 -110.704777) (xy 131.401976 -110.726589) (xy 131.348019 -110.740695) (xy 131.292582 -110.746795)
			(xy 131.236848 -110.744758) (xy 131.182005 -110.734628) (xy 131.129221 -110.716621) (xy 131.079621 -110.69112)
			(xy 131.034263 -110.658669) (xy 130.994114 -110.61996) (xy 130.960028 -110.575817) (xy 130.932732 -110.527182)
			(xy 130.912809 -110.475091) (xy 130.900683 -110.420654) (xy 130.896612 -110.365032) (xy 130.644138 -110.365032)
			(xy 130.643629 -110.392918) (xy 130.635509 -110.448094) (xy 130.619441 -110.501501) (xy 130.595769 -110.551998)
			(xy 130.564996 -110.598511) (xy 130.527779 -110.640048) (xy 130.484911 -110.675723) (xy 130.437305 -110.704777)
			(xy 130.385976 -110.726589) (xy 130.332019 -110.740695) (xy 130.276582 -110.746795) (xy 130.220848 -110.744758)
			(xy 130.166005 -110.734628) (xy 130.113221 -110.716621) (xy 130.063621 -110.69112) (xy 130.018263 -110.658669)
			(xy 129.978114 -110.61996) (xy 129.944028 -110.575817) (xy 129.916732 -110.527182) (xy 129.896809 -110.475091)
			(xy 129.884683 -110.420654) (xy 129.880612 -110.365032) (xy 111.560266 -110.365032) (xy 111.566901 -110.379185)
			(xy 111.582969 -110.432592) (xy 111.591089 -110.487768) (xy 111.591598 -110.515654) (xy 111.591089 -110.54354)
			(xy 111.582969 -110.598716) (xy 111.566901 -110.652123) (xy 111.543229 -110.70262) (xy 111.512456 -110.749133)
			(xy 111.475239 -110.79067) (xy 111.432371 -110.826345) (xy 111.384765 -110.855399) (xy 111.333436 -110.877211)
			(xy 111.279479 -110.891317) (xy 111.224042 -110.897417) (xy 111.168308 -110.89538) (xy 111.113465 -110.88525)
			(xy 111.060681 -110.867243) (xy 111.011081 -110.841742) (xy 110.965723 -110.809291) (xy 110.925574 -110.770582)
			(xy 110.891488 -110.726439) (xy 110.864192 -110.677804) (xy 110.844269 -110.625713) (xy 110.832143 -110.571276)
			(xy 110.828072 -110.515654) (xy 110.418014 -110.515654) (xy 110.385261 -110.542438) (xy 110.336892 -110.571293)
			(xy 110.284805 -110.592723) (xy 110.25759 -110.599982) (xy 110.248331 -110.602693) (xy 110.232669 -110.613939)
			(xy 110.22711 -110.621826) (xy 110.18393 -110.688374) (xy 110.18012 -110.706916) (xy 110.181898 -110.716822)
			(xy 110.184849 -110.733878) (xy 110.188029 -110.768348) (xy 110.188248 -110.785656) (xy 110.187762 -110.812907)
			(xy 110.180006 -110.866855) (xy 110.164651 -110.91915) (xy 110.142009 -110.968727) (xy 110.112543 -111.014577)
			(xy 110.076852 -111.055768) (xy 110.035661 -111.091459) (xy 109.989811 -111.120925) (xy 109.940234 -111.143567)
			(xy 109.887939 -111.158922) (xy 109.833991 -111.166678) (xy 109.779489 -111.166678) (xy 109.725541 -111.158922)
			(xy 109.673246 -111.143567) (xy 109.623669 -111.120925) (xy 109.577819 -111.091459) (xy 109.536628 -111.055768)
			(xy 109.500937 -111.014577) (xy 109.471471 -110.968727) (xy 109.448829 -110.91915) (xy 109.433474 -110.866855)
			(xy 109.425718 -110.812907) (xy 109.425232 -110.785656) (xy 109.42575 -110.757493) (xy 109.434024 -110.701779)
			(xy 109.450402 -110.647887) (xy 109.474526 -110.59699) (xy 109.505873 -110.550193) (xy 109.543761 -110.508515)
			(xy 109.587365 -110.472861) (xy 109.635739 -110.444007) (xy 109.68783 -110.422581) (xy 109.715046 -110.415324)
			(xy 109.724295 -110.412585) (xy 109.739962 -110.401359) (xy 109.745526 -110.39348) (xy 109.788706 -110.326932)
			(xy 109.792516 -110.30839) (xy 109.790738 -110.298484) (xy 109.787789 -110.281428) (xy 109.784607 -110.246958)
			(xy 109.784388 -110.22965) (xy 109.784818 -110.204119) (xy 109.791623 -110.153511) (xy 109.805118 -110.104264)
			(xy 109.825062 -110.057258) (xy 109.837728 -110.035086) (xy 109.844332 -110.02391) (xy 109.845348 -109.998002)
			(xy 109.800644 -109.909864) (xy 109.796528 -109.902376) (xy 109.784222 -109.890531) (xy 109.768723 -109.883354)
			(xy 109.760258 -109.882178) (xy 109.760004 -109.882178) (xy 109.732035 -109.878984) (xy 109.677401 -109.86542)
			(xy 109.625354 -109.843974) (xy 109.577024 -109.815112) (xy 109.533461 -109.779459) (xy 109.495611 -109.737791)
			(xy 109.464297 -109.691012) (xy 109.440198 -109.640139) (xy 109.423838 -109.586277) (xy 109.415572 -109.530594)
			(xy 109.415072 -109.502448) (xy 91.5035 -109.502448) (xy 91.5035 -112.297972) (xy 93.069918 -112.297972)
			(xy 93.070361 -112.271657) (xy 93.0776 -112.219527) (xy 93.091924 -112.168884) (xy 93.113061 -112.120685)
			(xy 93.140611 -112.075842) (xy 93.174054 -112.035204) (xy 93.193108 -112.017048) (xy 93.200536 -112.009549)
			(xy 93.209045 -111.990252) (xy 93.209618 -111.97971) (xy 93.209618 -111.905034) (xy 93.209079 -111.894486)
			(xy 93.20055 -111.875191) (xy 93.193108 -111.867696) (xy 93.174059 -111.849534) (xy 93.140601 -111.808906)
			(xy 93.113041 -111.764067) (xy 93.091901 -111.715867) (xy 93.077583 -111.665221) (xy 93.070357 -111.613088)
			(xy 93.069918 -111.586772) (xy 93.070404 -111.559521) (xy 93.07816 -111.505573) (xy 93.093515 -111.453278)
			(xy 93.116157 -111.403701) (xy 93.145623 -111.357851) (xy 93.181314 -111.31666) (xy 93.222505 -111.280969)
			(xy 93.268355 -111.251503) (xy 93.317932 -111.228861) (xy 93.370227 -111.213506) (xy 93.424175 -111.20575)
			(xy 93.478677 -111.20575) (xy 93.532625 -111.213506) (xy 93.58492 -111.228861) (xy 93.634497 -111.251503)
			(xy 93.680347 -111.280969) (xy 93.721538 -111.31666) (xy 93.757229 -111.357851) (xy 93.786695 -111.403701)
			(xy 93.809337 -111.453278) (xy 93.824692 -111.505573) (xy 93.832448 -111.559521) (xy 93.832934 -111.586772)
			(xy 93.832504 -111.613087) (xy 93.82526 -111.665217) (xy 93.810933 -111.71586) (xy 93.789793 -111.764058)
			(xy 93.762241 -111.808901) (xy 93.728798 -111.84954) (xy 93.709744 -111.867696) (xy 93.702349 -111.875223)
			(xy 93.693819 -111.894499) (xy 93.693234 -111.905034) (xy 93.693234 -111.97971) (xy 93.693734 -111.990263)
			(xy 93.702289 -112.009559) (xy 93.709744 -112.017048) (xy 93.728824 -112.035179) (xy 93.762277 -112.075815)
			(xy 93.789832 -112.12066) (xy 93.810966 -112.168866) (xy 93.825278 -112.219517) (xy 93.832498 -112.271655)
			(xy 93.832934 -112.297972) (xy 95.101918 -112.297972) (xy 95.102361 -112.271657) (xy 95.1096 -112.219527)
			(xy 95.123924 -112.168884) (xy 95.145061 -112.120685) (xy 95.172611 -112.075842) (xy 95.206054 -112.035204)
			(xy 95.225108 -112.017048) (xy 95.232536 -112.009549) (xy 95.241045 -111.990252) (xy 95.241618 -111.97971)
			(xy 95.241618 -111.905034) (xy 95.241079 -111.894486) (xy 95.23255 -111.875191) (xy 95.225108 -111.867696)
			(xy 95.206059 -111.849534) (xy 95.172601 -111.808906) (xy 95.145041 -111.764067) (xy 95.123901 -111.715867)
			(xy 95.109583 -111.665221) (xy 95.102357 -111.613088) (xy 95.101918 -111.586772) (xy 95.102404 -111.559521)
			(xy 95.11016 -111.505573) (xy 95.125515 -111.453278) (xy 95.148157 -111.403701) (xy 95.177623 -111.357851)
			(xy 95.213314 -111.31666) (xy 95.254505 -111.280969) (xy 95.300355 -111.251503) (xy 95.349932 -111.228861)
			(xy 95.402227 -111.213506) (xy 95.456175 -111.20575) (xy 95.510677 -111.20575) (xy 95.564625 -111.213506)
			(xy 95.61692 -111.228861) (xy 95.666497 -111.251503) (xy 95.712347 -111.280969) (xy 95.753538 -111.31666)
			(xy 95.789229 -111.357851) (xy 95.818695 -111.403701) (xy 95.841337 -111.453278) (xy 95.856692 -111.505573)
			(xy 95.864448 -111.559521) (xy 95.864934 -111.586772) (xy 95.864504 -111.613087) (xy 95.85726 -111.665217)
			(xy 95.842933 -111.71586) (xy 95.821793 -111.764058) (xy 95.794241 -111.808901) (xy 95.760798 -111.84954)
			(xy 95.741744 -111.867696) (xy 95.734349 -111.875223) (xy 95.725819 -111.894499) (xy 95.725234 -111.905034)
			(xy 95.725234 -111.97971) (xy 95.725734 -111.990263) (xy 95.734289 -112.009559) (xy 95.741744 -112.017048)
			(xy 95.760824 -112.035179) (xy 95.762829 -112.037615) (xy 97.556142 -112.037615) (xy 97.560456 -111.980343)
			(xy 97.573304 -111.924365) (xy 97.594396 -111.870944) (xy 97.623255 -111.821288) (xy 97.65923 -111.776517)
			(xy 97.680018 -111.756698) (xy 97.687425 -111.749182) (xy 97.695946 -111.729897) (xy 97.696528 -111.71936)
			(xy 97.696528 -111.644684) (xy 97.696013 -111.634133) (xy 97.687467 -111.614838) (xy 97.680018 -111.607346)
			(xy 97.660947 -111.589206) (xy 97.62749 -111.548573) (xy 97.599933 -111.50373) (xy 97.578797 -111.455526)
			(xy 97.564484 -111.404876) (xy 97.557264 -111.352739) (xy 97.556828 -111.326422) (xy 97.557314 -111.299171)
			(xy 97.56507 -111.245223) (xy 97.580425 -111.192928) (xy 97.603067 -111.143351) (xy 97.632533 -111.097501)
			(xy 97.668224 -111.05631) (xy 97.709415 -111.020619) (xy 97.755265 -110.991153) (xy 97.804842 -110.968511)
			(xy 97.857137 -110.953156) (xy 97.911085 -110.9454) (xy 97.965587 -110.9454) (xy 98.019535 -110.953156)
			(xy 98.07183 -110.968511) (xy 98.121407 -110.991153) (xy 98.167257 -111.020619) (xy 98.208448 -111.05631)
			(xy 98.244139 -111.097501) (xy 98.273605 -111.143351) (xy 98.296247 -111.192928) (xy 98.311602 -111.245223)
			(xy 98.319358 -111.299171) (xy 98.319844 -111.326422) (xy 98.319409 -111.352737) (xy 98.31217 -111.404868)
			(xy 98.297846 -111.455512) (xy 98.276707 -111.503711) (xy 98.249155 -111.548554) (xy 98.215709 -111.589191)
			(xy 98.196654 -111.607346) (xy 98.189238 -111.614856) (xy 98.18072 -111.634144) (xy 98.180144 -111.644684)
			(xy 98.180144 -111.71936) (xy 98.180668 -111.729911) (xy 98.189206 -111.749207) (xy 98.196654 -111.756698)
			(xy 98.217462 -111.776497) (xy 98.253434 -111.821274) (xy 98.28229 -111.870935) (xy 98.303379 -111.924359)
			(xy 98.316226 -111.980341) (xy 98.320539 -112.037615) (xy 100.09439 -112.037615) (xy 100.098702 -111.980346)
			(xy 100.111547 -111.924369) (xy 100.132634 -111.87095) (xy 100.161488 -111.821292) (xy 100.197456 -111.776519)
			(xy 100.21824 -111.756698) (xy 100.225636 -111.749171) (xy 100.234165 -111.729895) (xy 100.23475 -111.71936)
			(xy 100.23475 -111.644684) (xy 100.234228 -111.634134) (xy 100.225686 -111.614839) (xy 100.21824 -111.607346)
			(xy 100.199154 -111.589222) (xy 100.165702 -111.548584) (xy 100.138148 -111.503737) (xy 100.117016 -111.45553)
			(xy 100.102704 -111.404878) (xy 100.095486 -111.35274) (xy 100.09505 -111.326422) (xy 100.095536 -111.299171)
			(xy 100.103292 -111.245223) (xy 100.118647 -111.192928) (xy 100.141289 -111.143351) (xy 100.170755 -111.097501)
			(xy 100.206446 -111.05631) (xy 100.247637 -111.020619) (xy 100.293487 -110.991153) (xy 100.343064 -110.968511)
			(xy 100.395359 -110.953156) (xy 100.449307 -110.9454) (xy 100.503809 -110.9454) (xy 100.557757 -110.953156)
			(xy 100.610052 -110.968511) (xy 100.659629 -110.991153) (xy 100.705479 -111.020619) (xy 100.74667 -111.05631)
			(xy 100.782361 -111.097501) (xy 100.811827 -111.143351) (xy 100.834469 -111.192928) (xy 100.849824 -111.245223)
			(xy 100.85758 -111.299171) (xy 100.858066 -111.326422) (xy 100.857624 -111.352737) (xy 100.850386 -111.404867)
			(xy 100.836062 -111.455511) (xy 100.814925 -111.50371) (xy 100.787374 -111.548553) (xy 100.75393 -111.589191)
			(xy 100.734876 -111.607346) (xy 100.727463 -111.614859) (xy 100.718942 -111.634145) (xy 100.718366 -111.644684)
			(xy 100.718366 -111.71936) (xy 100.718913 -111.729907) (xy 100.727437 -111.749202) (xy 100.734876 -111.756698)
			(xy 100.755688 -111.776495) (xy 100.791667 -111.821269) (xy 100.820529 -111.87093) (xy 100.841623 -111.924355)
			(xy 100.854472 -111.980338) (xy 100.855495 -111.993923) (xy 104.297324 -111.993923) (xy 104.301636 -111.936654)
			(xy 104.314481 -111.880678) (xy 104.335569 -111.827258) (xy 104.364423 -111.777602) (xy 104.400393 -111.73283)
			(xy 104.421178 -111.71301) (xy 104.428574 -111.705484) (xy 104.437102 -111.686207) (xy 104.437688 -111.675672)
			(xy 104.437688 -111.600996) (xy 104.437178 -111.590444) (xy 104.42863 -111.571149) (xy 104.421178 -111.563658)
			(xy 104.400424 -111.543804) (xy 104.364449 -111.499036) (xy 104.335589 -111.449383) (xy 104.314494 -111.395966)
			(xy 104.301643 -111.339992) (xy 104.297324 -111.282723) (xy 104.301636 -111.225454) (xy 104.314481 -111.169478)
			(xy 104.335569 -111.116058) (xy 104.364423 -111.066402) (xy 104.400393 -111.02163) (xy 104.421178 -111.00181)
			(xy 104.428574 -110.994284) (xy 104.437102 -110.975007) (xy 104.437688 -110.964472) (xy 104.437688 -110.889796)
			(xy 104.437178 -110.879244) (xy 104.42863 -110.859949) (xy 104.421178 -110.852458) (xy 104.402105 -110.83432)
			(xy 104.36865 -110.793686) (xy 104.341094 -110.748842) (xy 104.319959 -110.700638) (xy 104.305645 -110.649987)
			(xy 104.298424 -110.597851) (xy 104.297988 -110.571534) (xy 104.298487 -110.544282) (xy 104.306239 -110.490333)
			(xy 104.321591 -110.438036) (xy 104.344229 -110.388456) (xy 104.373693 -110.342603) (xy 104.409383 -110.30141)
			(xy 104.450572 -110.265716) (xy 104.496423 -110.236247) (xy 104.546 -110.213604) (xy 104.598296 -110.198247)
			(xy 104.652244 -110.19049) (xy 104.679496 -110.190026) (xy 104.70581 -110.190488) (xy 104.757939 -110.197723)
			(xy 104.808583 -110.212042) (xy 104.856782 -110.233176) (xy 104.901625 -110.260723) (xy 104.942264 -110.294164)
			(xy 104.96042 -110.313216) (xy 104.96793 -110.320631) (xy 104.987219 -110.329147) (xy 104.997758 -110.329726)
			(xy 105.072434 -110.329726) (xy 105.08298 -110.329167) (xy 105.102275 -110.320652) (xy 105.109772 -110.313216)
			(xy 105.127951 -110.294184) (xy 105.168576 -110.260724) (xy 105.213411 -110.233162) (xy 105.261607 -110.212019)
			(xy 105.31225 -110.197697) (xy 105.364381 -110.190467) (xy 105.390696 -110.190026) (xy 105.41795 -110.190459)
			(xy 105.471904 -110.198216) (xy 105.524205 -110.213574) (xy 105.573787 -110.236218) (xy 105.613417 -110.261688)
			(xy 106.914421 -110.261688) (xy 106.914421 -110.209712) (xy 106.922553 -110.158377) (xy 106.938615 -110.108946)
			(xy 106.962213 -110.062636) (xy 106.992766 -110.020588) (xy 107.02952 -109.983839) (xy 107.071572 -109.953291)
			(xy 107.117884 -109.929699) (xy 107.167318 -109.913643) (xy 107.218654 -109.905518) (xy 107.244642 -109.905038)
			(xy 107.271287 -109.905526) (xy 107.323889 -109.914057) (xy 107.374439 -109.930922) (xy 107.421625 -109.955684)
			(xy 107.464224 -109.987701) (xy 107.50113 -110.026141) (xy 107.516676 -110.047786) (xy 107.52504 -110.059072)
			(xy 107.546713 -110.076927) (xy 107.572427 -110.08821) (xy 107.600242 -110.092068) (xy 107.628057 -110.08821)
			(xy 107.653771 -110.076927) (xy 107.675444 -110.059072) (xy 107.683808 -110.047786) (xy 107.699397 -110.026178)
			(xy 107.73631 -109.987761) (xy 107.778906 -109.95576) (xy 107.826082 -109.931002) (xy 107.876617 -109.914129)
			(xy 107.929203 -109.905578) (xy 107.955842 -109.905038) (xy 107.981831 -109.905459) (xy 108.033167 -109.913596)
			(xy 108.082599 -109.929663) (xy 108.128909 -109.953264) (xy 108.170957 -109.983819) (xy 108.207709 -110.020575)
			(xy 108.238258 -110.062627) (xy 108.261853 -110.10894) (xy 108.277914 -110.158374) (xy 108.286044 -110.209711)
			(xy 108.286044 -110.261689) (xy 108.277914 -110.313026) (xy 108.261853 -110.36246) (xy 108.238258 -110.408773)
			(xy 108.207709 -110.450825) (xy 108.170957 -110.487581) (xy 108.128909 -110.518136) (xy 108.082599 -110.541737)
			(xy 108.033167 -110.557804) (xy 107.981831 -110.565941) (xy 107.955842 -110.566454) (xy 107.929197 -110.565981)
			(xy 107.876594 -110.557448) (xy 107.826043 -110.54058) (xy 107.778857 -110.515815) (xy 107.736259 -110.483795)
			(xy 107.699354 -110.445352) (xy 107.683808 -110.423706) (xy 107.675444 -110.41242) (xy 107.653771 -110.394565)
			(xy 107.628057 -110.383282) (xy 107.600242 -110.379424) (xy 107.572427 -110.383282) (xy 107.546713 -110.394565)
			(xy 107.52504 -110.41242) (xy 107.516676 -110.423706) (xy 107.501095 -110.44532) (xy 107.46418 -110.483737)
			(xy 107.421583 -110.515738) (xy 107.374405 -110.540494) (xy 107.323869 -110.557366) (xy 107.271281 -110.565916)
			(xy 107.244642 -110.566454) (xy 107.218654 -110.565882) (xy 107.167318 -110.557757) (xy 107.117884 -110.541701)
			(xy 107.071572 -110.518109) (xy 107.02952 -110.487561) (xy 106.992766 -110.450812) (xy 106.962213 -110.408764)
			(xy 106.938615 -110.362454) (xy 106.922553 -110.313023) (xy 106.914421 -110.261688) (xy 105.613417 -110.261688)
			(xy 105.619642 -110.265689) (xy 105.660835 -110.301386) (xy 105.696529 -110.342582) (xy 105.725996 -110.388439)
			(xy 105.748637 -110.438024) (xy 105.76399 -110.490325) (xy 105.771743 -110.54428) (xy 105.772204 -110.571534)
			(xy 105.771758 -110.597849) (xy 105.764519 -110.649978) (xy 105.750195 -110.700621) (xy 105.729059 -110.74882)
			(xy 105.701509 -110.793663) (xy 105.668067 -110.834302) (xy 105.649014 -110.852458) (xy 105.641631 -110.859995)
			(xy 105.633095 -110.879263) (xy 105.632504 -110.889796) (xy 105.632504 -110.964472) (xy 105.633034 -110.975022)
			(xy 105.641568 -110.994317) (xy 105.649014 -111.00181) (xy 105.669836 -111.021596) (xy 105.705811 -111.066373)
			(xy 105.73467 -111.116036) (xy 105.752772 -111.16189) (xy 106.914397 -111.16189) (xy 106.914397 -111.10991)
			(xy 106.922529 -111.058571) (xy 106.938593 -111.009136) (xy 106.962193 -110.962823) (xy 106.992748 -110.920773)
			(xy 107.029505 -110.88402) (xy 107.071559 -110.853471) (xy 107.117875 -110.829877) (xy 107.167312 -110.813819)
			(xy 107.218652 -110.805694) (xy 107.244642 -110.805214) (xy 107.271286 -110.805713) (xy 107.323887 -110.814242)
			(xy 107.374436 -110.831106) (xy 107.421622 -110.855866) (xy 107.464222 -110.887881) (xy 107.501129 -110.926319)
			(xy 107.516676 -110.947962) (xy 107.52504 -110.959248) (xy 107.546713 -110.977103) (xy 107.572427 -110.988386)
			(xy 107.600242 -110.992244) (xy 107.628057 -110.988386) (xy 107.653771 -110.977103) (xy 107.675444 -110.959248)
			(xy 107.683808 -110.947962) (xy 107.69939 -110.926349) (xy 107.736306 -110.887933) (xy 107.778903 -110.855933)
			(xy 107.82608 -110.831177) (xy 107.876616 -110.814305) (xy 107.929203 -110.805754) (xy 107.955842 -110.805214)
			(xy 107.981829 -110.805683) (xy 108.033162 -110.813819) (xy 108.08259 -110.829885) (xy 108.128897 -110.853484)
			(xy 108.170942 -110.884037) (xy 108.20769 -110.92079) (xy 108.238238 -110.962839) (xy 108.261831 -111.009149)
			(xy 108.277891 -111.058579) (xy 108.286021 -111.109913) (xy 108.286021 -111.161887) (xy 108.277891 -111.213221)
			(xy 108.261831 -111.262651) (xy 108.238238 -111.308961) (xy 108.20769 -111.35101) (xy 108.170942 -111.387763)
			(xy 108.128897 -111.418316) (xy 108.08259 -111.441915) (xy 108.033162 -111.457981) (xy 107.981829 -111.466117)
			(xy 107.955842 -111.46663) (xy 107.929196 -111.466167) (xy 107.876592 -111.457633) (xy 107.826041 -111.440764)
			(xy 107.778855 -111.415997) (xy 107.736257 -111.383975) (xy 107.699353 -111.345529) (xy 107.683808 -111.323882)
			(xy 107.675444 -111.312596) (xy 107.653771 -111.294741) (xy 107.628057 -111.283458) (xy 107.600242 -111.2796)
			(xy 107.572427 -111.283458) (xy 107.546713 -111.294741) (xy 107.52504 -111.312596) (xy 107.516676 -111.323882)
			(xy 107.501117 -111.345512) (xy 107.464195 -111.383925) (xy 107.421592 -111.415922) (xy 107.374411 -111.440675)
			(xy 107.323872 -111.457543) (xy 107.271282 -111.466092) (xy 107.244642 -111.46663) (xy 107.218652 -111.466106)
			(xy 107.167312 -111.457981) (xy 107.117875 -111.441923) (xy 107.071559 -111.418329) (xy 107.029505 -111.38778)
			(xy 106.992748 -111.351027) (xy 106.962193 -111.308977) (xy 106.938593 -111.262664) (xy 106.922529 -111.213229)
			(xy 106.914397 -111.16189) (xy 105.752772 -111.16189) (xy 105.755761 -111.169462) (xy 105.768608 -111.225446)
			(xy 105.77292 -111.282723) (xy 105.768601 -111.339999) (xy 105.755748 -111.395982) (xy 105.73465 -111.449406)
			(xy 105.705785 -111.499065) (xy 105.669805 -111.543838) (xy 105.649014 -111.563658) (xy 105.641631 -111.571195)
			(xy 105.633095 -111.590463) (xy 105.632504 -111.600996) (xy 105.632504 -111.675672) (xy 105.633034 -111.686222)
			(xy 105.641568 -111.705517) (xy 105.649014 -111.71301) (xy 105.669836 -111.732796) (xy 105.705811 -111.777573)
			(xy 105.73467 -111.827236) (xy 105.755761 -111.880662) (xy 105.768608 -111.936646) (xy 105.77292 -111.993923)
			(xy 105.768601 -112.051199) (xy 105.76617 -112.061788) (xy 106.914419 -112.061788) (xy 106.914419 -112.009812)
			(xy 106.922551 -111.958476) (xy 106.938613 -111.909045) (xy 106.962212 -111.862735) (xy 106.992764 -111.820687)
			(xy 107.029519 -111.783937) (xy 107.071571 -111.75339) (xy 107.117884 -111.729797) (xy 107.167317 -111.713741)
			(xy 107.218654 -111.705616) (xy 107.244642 -111.705136) (xy 107.271287 -111.705625) (xy 107.323888 -111.714156)
			(xy 107.374438 -111.73102) (xy 107.421625 -111.755782) (xy 107.464224 -111.787799) (xy 107.501129 -111.826239)
			(xy 107.516676 -111.847884) (xy 107.52504 -111.85917) (xy 107.546713 -111.877025) (xy 107.572427 -111.888308)
			(xy 107.600242 -111.892166) (xy 107.628057 -111.888308) (xy 107.653771 -111.877025) (xy 107.675444 -111.85917)
			(xy 107.683808 -111.847884) (xy 107.699396 -111.826275) (xy 107.73631 -111.787859) (xy 107.778906 -111.755857)
			(xy 107.826082 -111.7311) (xy 107.876617 -111.714227) (xy 107.929203 -111.705676) (xy 107.955842 -111.705136)
			(xy 107.98183 -111.705561) (xy 108.033167 -111.713698) (xy 108.082598 -111.729765) (xy 108.128908 -111.753366)
			(xy 108.170956 -111.78392) (xy 108.17269 -111.785654) (xy 109.457742 -111.785654) (xy 109.461813 -111.730032)
			(xy 109.473939 -111.675595) (xy 109.493862 -111.623504) (xy 109.521158 -111.574869) (xy 109.555244 -111.530726)
			(xy 109.595393 -111.492017) (xy 109.640751 -111.459566) (xy 109.690351 -111.434065) (xy 109.743135 -111.416058)
			(xy 109.797978 -111.405928) (xy 109.853712 -111.403891) (xy 109.909149 -111.409991) (xy 109.963106 -111.424097)
			(xy 110.014435 -111.445909) (xy 110.062041 -111.474963) (xy 110.104909 -111.510638) (xy 110.142126 -111.552175)
			(xy 110.172899 -111.598688) (xy 110.196571 -111.649185) (xy 110.212639 -111.702592) (xy 110.217349 -111.7346)
			(xy 121.915172 -111.7346) (xy 121.919243 -111.678978) (xy 121.931369 -111.624541) (xy 121.951292 -111.57245)
			(xy 121.978588 -111.523815) (xy 122.012674 -111.479672) (xy 122.052823 -111.440963) (xy 122.098181 -111.408512)
			(xy 122.147781 -111.383011) (xy 122.200565 -111.365004) (xy 122.255408 -111.354874) (xy 122.311142 -111.352837)
			(xy 122.366579 -111.358937) (xy 122.420536 -111.373043) (xy 122.471865 -111.394855) (xy 122.519471 -111.423909)
			(xy 122.562339 -111.459584) (xy 122.599556 -111.501121) (xy 122.630329 -111.547634) (xy 122.654001 -111.598131)
			(xy 122.670069 -111.651538) (xy 122.678189 -111.706714) (xy 122.678698 -111.7346) (xy 122.678189 -111.762486)
			(xy 122.670069 -111.817662) (xy 122.654001 -111.871069) (xy 122.630329 -111.921566) (xy 122.599556 -111.968079)
			(xy 122.562339 -112.009616) (xy 122.519471 -112.045291) (xy 122.471865 -112.074345) (xy 122.420536 -112.096157)
			(xy 122.366579 -112.110263) (xy 122.311142 -112.116363) (xy 122.255408 -112.114326) (xy 122.200565 -112.104196)
			(xy 122.147781 -112.086189) (xy 122.098181 -112.060688) (xy 122.052823 -112.028237) (xy 122.012674 -111.989528)
			(xy 121.978588 -111.945385) (xy 121.951292 -111.89675) (xy 121.931369 -111.844659) (xy 121.919243 -111.790222)
			(xy 121.915172 -111.7346) (xy 110.217349 -111.7346) (xy 110.220759 -111.757768) (xy 110.221268 -111.785654)
			(xy 110.220759 -111.81354) (xy 110.212639 -111.868716) (xy 110.196571 -111.922123) (xy 110.172899 -111.97262)
			(xy 110.142126 -112.019133) (xy 110.104909 -112.06067) (xy 110.062041 -112.096345) (xy 110.014435 -112.125399)
			(xy 109.963106 -112.147211) (xy 109.909149 -112.161317) (xy 109.853712 -112.167417) (xy 109.797978 -112.16538)
			(xy 109.743135 -112.15525) (xy 109.690351 -112.137243) (xy 109.640751 -112.111742) (xy 109.595393 -112.079291)
			(xy 109.555244 -112.040582) (xy 109.521158 -111.996439) (xy 109.493862 -111.947804) (xy 109.473939 -111.895713)
			(xy 109.461813 -111.841276) (xy 109.457742 -111.785654) (xy 108.17269 -111.785654) (xy 108.207707 -111.820676)
			(xy 108.238256 -111.862728) (xy 108.261852 -111.909041) (xy 108.277912 -111.958474) (xy 108.286042 -112.009811)
			(xy 108.286042 -112.061789) (xy 108.277912 -112.113126) (xy 108.261852 -112.162559) (xy 108.238256 -112.208872)
			(xy 108.207707 -112.250924) (xy 108.170956 -112.28768) (xy 108.15819 -112.296956) (xy 110.894874 -112.296956)
			(xy 110.898945 -112.241334) (xy 110.911071 -112.186897) (xy 110.930994 -112.134806) (xy 110.95829 -112.086171)
			(xy 110.992376 -112.042028) (xy 111.032525 -112.003319) (xy 111.077883 -111.970868) (xy 111.127483 -111.945367)
			(xy 111.180267 -111.92736) (xy 111.23511 -111.91723) (xy 111.290844 -111.915193) (xy 111.346281 -111.921293)
			(xy 111.400238 -111.935399) (xy 111.451567 -111.957211) (xy 111.499173 -111.986265) (xy 111.542041 -112.02194)
			(xy 111.579258 -112.063477) (xy 111.610031 -112.10999) (xy 111.633703 -112.160487) (xy 111.649771 -112.213894)
			(xy 111.657891 -112.26907) (xy 111.6584 -112.296956) (xy 111.657891 -112.324842) (xy 111.649771 -112.380018)
			(xy 111.633703 -112.433425) (xy 111.610031 -112.483922) (xy 111.579258 -112.530435) (xy 111.542041 -112.571972)
			(xy 111.499173 -112.607647) (xy 111.451567 -112.636701) (xy 111.400238 -112.658513) (xy 111.346281 -112.672619)
			(xy 111.290844 -112.678719) (xy 111.23511 -112.676682) (xy 111.180267 -112.666552) (xy 111.127483 -112.648545)
			(xy 111.077883 -112.623044) (xy 111.032525 -112.590593) (xy 110.992376 -112.551884) (xy 110.95829 -112.507741)
			(xy 110.930994 -112.459106) (xy 110.911071 -112.407015) (xy 110.898945 -112.352578) (xy 110.894874 -112.296956)
			(xy 108.15819 -112.296956) (xy 108.128908 -112.318234) (xy 108.082598 -112.341835) (xy 108.033167 -112.357902)
			(xy 107.98183 -112.366039) (xy 107.955842 -112.366552) (xy 107.929197 -112.36608) (xy 107.876594 -112.357547)
			(xy 107.826043 -112.340679) (xy 107.778857 -112.315913) (xy 107.736259 -112.283894) (xy 107.699354 -112.24545)
			(xy 107.683808 -112.223804) (xy 107.675444 -112.212518) (xy 107.653771 -112.194663) (xy 107.628057 -112.18338)
			(xy 107.600242 -112.179522) (xy 107.572427 -112.18338) (xy 107.546713 -112.194663) (xy 107.52504 -112.212518)
			(xy 107.516676 -112.223804) (xy 107.501094 -112.245417) (xy 107.46418 -112.283835) (xy 107.421582 -112.315836)
			(xy 107.374405 -112.340592) (xy 107.323869 -112.357464) (xy 107.271281 -112.366014) (xy 107.244642 -112.366552)
			(xy 107.218654 -112.365984) (xy 107.167317 -112.357859) (xy 107.117884 -112.341803) (xy 107.071571 -112.31821)
			(xy 107.029519 -112.287663) (xy 106.992764 -112.250913) (xy 106.962212 -112.208865) (xy 106.938613 -112.162555)
			(xy 106.922551 -112.113124) (xy 106.914419 -112.061788) (xy 105.76617 -112.061788) (xy 105.755748 -112.107182)
			(xy 105.73465 -112.160606) (xy 105.705785 -112.210265) (xy 105.669805 -112.255038) (xy 105.649014 -112.274858)
			(xy 105.641631 -112.282395) (xy 105.633095 -112.301663) (xy 105.632504 -112.312196) (xy 105.632504 -112.386872)
			(xy 105.633034 -112.397422) (xy 105.641568 -112.416717) (xy 105.649014 -112.42421) (xy 105.66807 -112.442365)
			(xy 105.701527 -112.482995) (xy 105.729085 -112.527836) (xy 105.750224 -112.576036) (xy 105.764541 -112.626684)
			(xy 105.771765 -112.678818) (xy 105.772204 -112.705134) (xy 105.771754 -112.732386) (xy 105.763993 -112.786335)
			(xy 105.748633 -112.838631) (xy 105.725988 -112.888209) (xy 105.696517 -112.934059) (xy 105.672482 -112.961794)
			(xy 106.914341 -112.961794) (xy 106.914341 -112.909806) (xy 106.922475 -112.858458) (xy 106.938541 -112.809015)
			(xy 106.962145 -112.762694) (xy 106.992705 -112.720636) (xy 107.029468 -112.683878) (xy 107.07153 -112.653323)
			(xy 107.117854 -112.629725) (xy 107.167299 -112.613665) (xy 107.218648 -112.605538) (xy 107.244642 -112.605058)
			(xy 107.271287 -112.605538) (xy 107.32389 -112.614069) (xy 107.37444 -112.630935) (xy 107.421627 -112.655699)
			(xy 107.464225 -112.687717) (xy 107.50113 -112.72616) (xy 107.516676 -112.747806) (xy 107.52504 -112.759092)
			(xy 107.546713 -112.776947) (xy 107.572427 -112.78823) (xy 107.600242 -112.792088) (xy 107.628057 -112.78823)
			(xy 107.653771 -112.776947) (xy 107.675444 -112.759092) (xy 107.683808 -112.747806) (xy 107.699373 -112.72618)
			(xy 107.736294 -112.687768) (xy 107.778896 -112.655771) (xy 107.826076 -112.631018) (xy 107.876614 -112.614148)
			(xy 107.929202 -112.605598) (xy 107.955842 -112.605058) (xy 107.981824 -112.605639) (xy 108.033148 -112.613774)
			(xy 108.082568 -112.629837) (xy 108.128867 -112.653432) (xy 108.170905 -112.68398) (xy 108.207648 -112.720727)
			(xy 108.23819 -112.762769) (xy 108.26178 -112.809071) (xy 108.277836 -112.858492) (xy 108.285569 -112.907318)
			(xy 122.168918 -112.907318) (xy 122.172989 -112.851696) (xy 122.185115 -112.797259) (xy 122.205038 -112.745168)
			(xy 122.232334 -112.696533) (xy 122.26642 -112.65239) (xy 122.306569 -112.613681) (xy 122.351927 -112.58123)
			(xy 122.401527 -112.555729) (xy 122.454311 -112.537722) (xy 122.509154 -112.527592) (xy 122.564888 -112.525555)
			(xy 122.620325 -112.531655) (xy 122.674282 -112.545761) (xy 122.725611 -112.567573) (xy 122.773217 -112.596627)
			(xy 122.816085 -112.632302) (xy 122.853302 -112.673839) (xy 122.884075 -112.720352) (xy 122.907747 -112.770849)
			(xy 122.923815 -112.824256) (xy 122.931935 -112.879432) (xy 122.932444 -112.907318) (xy 122.931935 -112.935204)
			(xy 122.923815 -112.99038) (xy 122.907747 -113.043787) (xy 122.884075 -113.094284) (xy 122.853302 -113.140797)
			(xy 122.816085 -113.182334) (xy 122.773217 -113.218009) (xy 122.725611 -113.247063) (xy 122.674282 -113.268875)
			(xy 122.620325 -113.282981) (xy 122.564888 -113.289081) (xy 122.509154 -113.287044) (xy 122.454311 -113.276914)
			(xy 122.401527 -113.258907) (xy 122.351927 -113.233406) (xy 122.306569 -113.200955) (xy 122.26642 -113.162246)
			(xy 122.232334 -113.118103) (xy 122.205038 -113.069468) (xy 122.185115 -113.017377) (xy 122.172989 -112.96294)
			(xy 122.168918 -112.907318) (xy 108.285569 -112.907318) (xy 108.285965 -112.909818) (xy 108.285965 -112.961782)
			(xy 108.277836 -113.013108) (xy 108.26178 -113.062529) (xy 108.23819 -113.108831) (xy 108.207648 -113.150873)
			(xy 108.170905 -113.18762) (xy 108.128867 -113.218168) (xy 108.082568 -113.241763) (xy 108.033148 -113.257826)
			(xy 107.981824 -113.265961) (xy 107.955842 -113.266474) (xy 107.929197 -113.265992) (xy 107.876595 -113.25746)
			(xy 107.826045 -113.240593) (xy 107.778859 -113.21583) (xy 107.73626 -113.183812) (xy 107.699355 -113.145371)
			(xy 107.683808 -113.123726) (xy 107.675444 -113.11244) (xy 107.653771 -113.094585) (xy 107.628057 -113.083302)
			(xy 107.600242 -113.079444) (xy 107.572427 -113.083302) (xy 107.546713 -113.094585) (xy 107.52504 -113.11244)
			(xy 107.516676 -113.123726) (xy 107.501101 -113.145344) (xy 107.464184 -113.18376) (xy 107.421585 -113.21576)
			(xy 107.374407 -113.240516) (xy 107.32387 -113.257386) (xy 107.271281 -113.265936) (xy 107.244642 -113.266474)
			(xy 107.218648 -113.266062) (xy 107.167299 -113.257935) (xy 107.117854 -113.241875) (xy 107.07153 -113.218277)
			(xy 107.029468 -113.187722) (xy 106.992705 -113.150964) (xy 106.962145 -113.108906) (xy 106.938541 -113.062585)
			(xy 106.922475 -113.013142) (xy 106.914341 -112.961794) (xy 105.672482 -112.961794) (xy 105.660822 -112.975249)
			(xy 105.619629 -113.01094) (xy 105.573775 -113.040406) (xy 105.524195 -113.063046) (xy 105.471898 -113.078401)
			(xy 105.417948 -113.086157) (xy 105.390696 -113.086642) (xy 105.364381 -113.086196) (xy 105.312251 -113.078959)
			(xy 105.261607 -113.064637) (xy 105.213408 -113.043501) (xy 105.168565 -113.01595) (xy 105.127927 -112.982506)
			(xy 105.109772 -112.963452) (xy 105.102256 -112.956044) (xy 105.082972 -112.947521) (xy 105.072434 -112.946942)
			(xy 104.997758 -112.946942) (xy 104.987209 -112.947477) (xy 104.967912 -112.956007) (xy 104.96042 -112.963452)
			(xy 104.942258 -112.982501) (xy 104.901628 -113.015957) (xy 104.856789 -113.043515) (xy 104.80859 -113.064654)
			(xy 104.757944 -113.078974) (xy 104.705812 -113.086202) (xy 104.679496 -113.086642) (xy 104.652246 -113.086126)
			(xy 104.598301 -113.07837) (xy 104.546009 -113.063016) (xy 104.496434 -113.040377) (xy 104.450585 -113.010913)
			(xy 104.409396 -112.975225) (xy 104.373705 -112.934039) (xy 104.344238 -112.888192) (xy 104.321595 -112.838619)
			(xy 104.306237 -112.786328) (xy 104.298476 -112.732384) (xy 104.297988 -112.705134) (xy 104.298415 -112.678819)
			(xy 104.305659 -112.626689) (xy 104.319986 -112.576045) (xy 104.341126 -112.527847) (xy 104.368679 -112.483004)
			(xy 104.402124 -112.442366) (xy 104.421178 -112.42421) (xy 104.428574 -112.416684) (xy 104.437102 -112.397407)
			(xy 104.437688 -112.386872) (xy 104.437688 -112.312196) (xy 104.437178 -112.301644) (xy 104.42863 -112.282349)
			(xy 104.421178 -112.274858) (xy 104.400424 -112.255004) (xy 104.364449 -112.210236) (xy 104.335589 -112.160583)
			(xy 104.314494 -112.107166) (xy 104.301643 -112.051192) (xy 104.297324 -111.993923) (xy 100.855495 -111.993923)
			(xy 100.858786 -112.037615) (xy 100.854467 -112.094891) (xy 100.841614 -112.150873) (xy 100.820516 -112.204297)
			(xy 100.79165 -112.253956) (xy 100.755667 -112.298727) (xy 100.734876 -112.318546) (xy 100.727463 -112.326059)
			(xy 100.718942 -112.345345) (xy 100.718366 -112.355884) (xy 100.718366 -112.43056) (xy 100.718913 -112.441107)
			(xy 100.727437 -112.460402) (xy 100.734876 -112.467898) (xy 100.753919 -112.486066) (xy 100.787378 -112.526693)
			(xy 100.814939 -112.57153) (xy 100.83608 -112.619729) (xy 100.8504 -112.670374) (xy 100.857627 -112.722506)
			(xy 100.858066 -112.748822) (xy 100.85758 -112.776073) (xy 100.849824 -112.830021) (xy 100.834469 -112.882316)
			(xy 100.811827 -112.931893) (xy 100.782361 -112.977743) (xy 100.74667 -113.018934) (xy 100.705479 -113.054625)
			(xy 100.659629 -113.084091) (xy 100.610052 -113.106733) (xy 100.557757 -113.122088) (xy 100.503809 -113.129844)
			(xy 100.449307 -113.129844) (xy 100.395359 -113.122088) (xy 100.343064 -113.106733) (xy 100.293487 -113.084091)
			(xy 100.247637 -113.054625) (xy 100.206446 -113.018934) (xy 100.170755 -112.977743) (xy 100.141289 -112.931893)
			(xy 100.118647 -112.882316) (xy 100.103292 -112.830021) (xy 100.095536 -112.776073) (xy 100.09505 -112.748822)
			(xy 100.095516 -112.722508) (xy 100.102749 -112.670379) (xy 100.117067 -112.619735) (xy 100.1382 -112.571536)
			(xy 100.165747 -112.526693) (xy 100.199187 -112.486054) (xy 100.21824 -112.467898) (xy 100.225636 -112.460371)
			(xy 100.234165 -112.441095) (xy 100.23475 -112.43056) (xy 100.23475 -112.355884) (xy 100.234228 -112.345334)
			(xy 100.225686 -112.326039) (xy 100.21824 -112.318546) (xy 100.197476 -112.298703) (xy 100.161505 -112.253932)
			(xy 100.132647 -112.204277) (xy 100.111556 -112.150859) (xy 100.098707 -112.094884) (xy 100.09439 -112.037615)
			(xy 98.320539 -112.037615) (xy 98.316221 -112.094889) (xy 98.303371 -112.150869) (xy 98.282277 -112.204292)
			(xy 98.253417 -112.253951) (xy 98.217442 -112.298725) (xy 98.196654 -112.318546) (xy 98.189238 -112.326056)
			(xy 98.18072 -112.345344) (xy 98.180144 -112.355884) (xy 98.180144 -112.43056) (xy 98.180668 -112.441111)
			(xy 98.189206 -112.460407) (xy 98.196654 -112.467898) (xy 98.215712 -112.486051) (xy 98.249167 -112.526682)
			(xy 98.276724 -112.571524) (xy 98.297862 -112.619725) (xy 98.312179 -112.670372) (xy 98.319405 -112.722506)
			(xy 98.319844 -112.748822) (xy 98.319358 -112.776073) (xy 98.311602 -112.830021) (xy 98.296247 -112.882316)
			(xy 98.273605 -112.931893) (xy 98.244139 -112.977743) (xy 98.208448 -113.018934) (xy 98.167257 -113.054625)
			(xy 98.121407 -113.084091) (xy 98.07183 -113.106733) (xy 98.019535 -113.122088) (xy 97.965587 -113.129844)
			(xy 97.911085 -113.129844) (xy 97.857137 -113.122088) (xy 97.804842 -113.106733) (xy 97.755265 -113.084091)
			(xy 97.709415 -113.054625) (xy 97.668224 -113.018934) (xy 97.632533 -112.977743) (xy 97.603067 -112.931893)
			(xy 97.580425 -112.882316) (xy 97.56507 -112.830021) (xy 97.557314 -112.776073) (xy 97.556828 -112.748822)
			(xy 97.557301 -112.722508) (xy 97.564534 -112.67038) (xy 97.578851 -112.619737) (xy 97.599982 -112.571537)
			(xy 97.627528 -112.526694) (xy 97.660966 -112.486054) (xy 97.680018 -112.467898) (xy 97.687425 -112.460382)
			(xy 97.695946 -112.441097) (xy 97.696528 -112.43056) (xy 97.696528 -112.355884) (xy 97.696013 -112.345333)
			(xy 97.687467 -112.326038) (xy 97.680018 -112.318546) (xy 97.65925 -112.298705) (xy 97.623272 -112.253937)
			(xy 97.594409 -112.204283) (xy 97.573313 -112.150863) (xy 97.560461 -112.094886) (xy 97.556142 -112.037615)
			(xy 95.762829 -112.037615) (xy 95.794277 -112.075815) (xy 95.821832 -112.12066) (xy 95.842966 -112.168866)
			(xy 95.857278 -112.219517) (xy 95.864498 -112.271655) (xy 95.864934 -112.297972) (xy 95.864448 -112.325223)
			(xy 95.856692 -112.379171) (xy 95.841337 -112.431466) (xy 95.818695 -112.481043) (xy 95.789229 -112.526893)
			(xy 95.753538 -112.568084) (xy 95.712347 -112.603775) (xy 95.666497 -112.633241) (xy 95.61692 -112.655883)
			(xy 95.564625 -112.671238) (xy 95.510677 -112.678994) (xy 95.456175 -112.678994) (xy 95.402227 -112.671238)
			(xy 95.349932 -112.655883) (xy 95.300355 -112.633241) (xy 95.254505 -112.603775) (xy 95.213314 -112.568084)
			(xy 95.177623 -112.526893) (xy 95.148157 -112.481043) (xy 95.125515 -112.431466) (xy 95.11016 -112.379171)
			(xy 95.102404 -112.325223) (xy 95.101918 -112.297972) (xy 93.832934 -112.297972) (xy 93.832448 -112.325223)
			(xy 93.824692 -112.379171) (xy 93.809337 -112.431466) (xy 93.786695 -112.481043) (xy 93.757229 -112.526893)
			(xy 93.721538 -112.568084) (xy 93.680347 -112.603775) (xy 93.634497 -112.633241) (xy 93.58492 -112.655883)
			(xy 93.532625 -112.671238) (xy 93.478677 -112.678994) (xy 93.424175 -112.678994) (xy 93.370227 -112.671238)
			(xy 93.317932 -112.655883) (xy 93.268355 -112.633241) (xy 93.222505 -112.603775) (xy 93.181314 -112.568084)
			(xy 93.145623 -112.526893) (xy 93.116157 -112.481043) (xy 93.093515 -112.431466) (xy 93.07816 -112.379171)
			(xy 93.070404 -112.325223) (xy 93.069918 -112.297972) (xy 91.5035 -112.297972) (xy 91.5035 -113.224056)
			(xy 91.505278 -113.237772) (xy 91.506548 -113.241328) (xy 91.518486 -113.269522) (xy 91.519756 -113.271046)
			(xy 91.523058 -113.274602) (xy 91.541016 -113.294056) (xy 91.571945 -113.337025) (xy 91.596639 -113.383856)
			(xy 91.614626 -113.43365) (xy 91.62556 -113.485451) (xy 91.629231 -113.538267) (xy 91.625569 -113.591083)
			(xy 91.614644 -113.642886) (xy 91.596666 -113.692683) (xy 91.57198 -113.739518) (xy 91.541059 -113.782493)
			(xy 91.523058 -113.801906) (xy 91.519756 -113.805462) (xy 91.518486 -113.806986) (xy 91.506548 -113.83518)
			(xy 91.505278 -113.838736) (xy 91.5035 -113.852452) (xy 91.5035 -113.932462) (xy 91.503953 -113.938399)
			(xy 91.507279 -113.949828) (xy 91.510104 -113.955068) (xy 91.511374 -113.9571) (xy 91.514616 -113.961859)
			(xy 91.522824 -113.969929) (xy 91.52763 -113.973102) (xy 91.612466 -114.017044) (xy 91.612974 -114.017044)
			(xy 91.617546 -114.019584) (xy 91.631008 -114.022378) (xy 91.63812 -114.02187) (xy 91.64955 -114.019584)
			(xy 91.654884 -114.017044) (xy 91.660726 -114.01425) (xy 91.663774 -114.012472) (xy 91.665806 -114.010948)
			(xy 91.668346 -114.00917) (xy 91.69241 -113.993187) (xy 91.744348 -113.967896) (xy 91.79951 -113.950742)
			(xy 91.856631 -113.942121) (xy 91.885516 -113.941606) (xy 91.890342 -113.941606) (xy 91.909941 -113.942124)
			(xy 91.948881 -113.946709) (xy 91.968066 -113.95075) (xy 91.997518 -113.957869) (xy 92.053857 -113.980161)
			(xy 92.105959 -114.011088) (xy 92.15251 -114.04987) (xy 92.192338 -114.09553) (xy 92.208858 -114.12093)
			(xy 92.216434 -114.129647) (xy 92.237199 -114.139706) (xy 92.248736 -114.140234) (xy 92.337382 -114.140234)
			(xy 92.348172 -114.139149) (xy 92.36739 -114.129147) (xy 92.374466 -114.12093) (xy 92.389117 -114.098363)
			(xy 92.423756 -114.057194) (xy 92.463826 -114.021288) (xy 92.508535 -113.991355) (xy 92.556998 -113.967987)
			(xy 92.582492 -113.959386) (xy 92.591128 -113.956846) (xy 92.607483 -113.952253) (xy 92.640806 -113.945638)
			(xy 92.657676 -113.943638) (xy 92.69222 -113.941606) (xy 92.69857 -113.941606) (xy 92.724433 -113.942017)
			(xy 92.775687 -113.948972) (xy 92.825529 -113.962799) (xy 92.873042 -113.983245) (xy 92.89542 -113.996216)
			(xy 92.909644 -114.004852) (xy 92.913454 -114.007392) (xy 92.92336 -114.014758) (xy 92.92717 -114.017552)
			(xy 92.928948 -114.018822) (xy 92.929202 -114.019076) (xy 92.933922 -114.022263) (xy 92.944439 -114.02663)
			(xy 92.95003 -114.027712) (xy 92.961714 -114.029744) (xy 93.013276 -114.01298) (xy 93.013784 -114.01298)
			(xy 93.057218 -113.998248) (xy 93.061805 -113.9962) (xy 93.070121 -113.990568) (xy 93.073728 -113.987072)
			(xy 93.078046 -113.9825) (xy 93.083888 -113.972594) (xy 93.08592 -113.966244) (xy 93.093273 -113.943026)
			(xy 93.113068 -113.898528) (xy 93.138368 -113.856913) (xy 93.168761 -113.818859) (xy 93.185996 -113.801652)
			(xy 93.193362 -113.794794) (xy 93.2053 -113.767362) (xy 93.207303 -113.762522) (xy 93.209482 -113.752278)
			(xy 93.209618 -113.747042) (xy 93.209618 -113.693702) (xy 93.209568 -113.689832) (xy 93.208415 -113.682178)
			(xy 93.207332 -113.678462) (xy 93.205046 -113.673128) (xy 93.204792 -113.672874) (xy 93.197426 -113.655856)
			(xy 93.19546 -113.651429) (xy 93.190094 -113.643365) (xy 93.186758 -113.639854) (xy 93.185996 -113.639092)
			(xy 93.167987 -113.621025) (xy 93.136429 -113.580945) (xy 93.11048 -113.537024) (xy 93.090602 -113.490044)
			(xy 93.077147 -113.440837) (xy 93.070355 -113.390278) (xy 93.069918 -113.364772) (xy 93.070404 -113.337521)
			(xy 93.07816 -113.283573) (xy 93.093515 -113.231278) (xy 93.116157 -113.181701) (xy 93.145623 -113.135851)
			(xy 93.181314 -113.09466) (xy 93.222505 -113.058969) (xy 93.268355 -113.029503) (xy 93.317932 -113.006861)
			(xy 93.370227 -112.991506) (xy 93.424175 -112.98375) (xy 93.478677 -112.98375) (xy 93.532625 -112.991506)
			(xy 93.58492 -113.006861) (xy 93.634497 -113.029503) (xy 93.680347 -113.058969) (xy 93.721538 -113.09466)
			(xy 93.757229 -113.135851) (xy 93.786695 -113.181701) (xy 93.809337 -113.231278) (xy 93.824692 -113.283573)
			(xy 93.832448 -113.337521) (xy 93.832934 -113.364772) (xy 93.832514 -113.390249) (xy 93.825744 -113.440752)
			(xy 93.812321 -113.489907) (xy 93.792483 -113.536841) (xy 93.766581 -113.580721) (xy 93.735077 -113.620769)
			(xy 93.71711 -113.638838) (xy 93.716602 -113.639346) (xy 93.709236 -113.646712) (xy 93.69806 -113.672874)
			(xy 93.697806 -113.673128) (xy 93.69552 -113.678462) (xy 93.694452 -113.682181) (xy 93.693303 -113.689833)
			(xy 93.693234 -113.693702) (xy 93.693234 -113.747042) (xy 93.69328 -113.750913) (xy 93.694426 -113.758569)
			(xy 93.69552 -113.762282) (xy 93.697806 -113.767616) (xy 93.69806 -113.76787) (xy 93.705426 -113.784888)
			(xy 93.707397 -113.789312) (xy 93.712772 -113.797366) (xy 93.716094 -113.80089) (xy 93.716856 -113.801652)
			(xy 93.734866 -113.81972) (xy 93.766426 -113.8598) (xy 93.792377 -113.90372) (xy 93.812259 -113.9507)
			(xy 93.825719 -113.999906) (xy 93.832518 -114.050465) (xy 93.832934 -114.075972) (xy 95.101918 -114.075972)
			(xy 95.102361 -114.049657) (xy 95.1096 -113.997527) (xy 95.123924 -113.946884) (xy 95.145061 -113.898685)
			(xy 95.172611 -113.853842) (xy 95.206054 -113.813204) (xy 95.225108 -113.795048) (xy 95.232536 -113.787549)
			(xy 95.241045 -113.768252) (xy 95.241618 -113.75771) (xy 95.241618 -113.683034) (xy 95.241079 -113.672486)
			(xy 95.23255 -113.653191) (xy 95.225108 -113.645696) (xy 95.206059 -113.627534) (xy 95.172601 -113.586906)
			(xy 95.145041 -113.542067) (xy 95.123901 -113.493867) (xy 95.109583 -113.443221) (xy 95.102357 -113.391088)
			(xy 95.101918 -113.364772) (xy 95.102404 -113.337521) (xy 95.11016 -113.283573) (xy 95.125515 -113.231278)
			(xy 95.148157 -113.181701) (xy 95.177623 -113.135851) (xy 95.213314 -113.09466) (xy 95.254505 -113.058969)
			(xy 95.300355 -113.029503) (xy 95.349932 -113.006861) (xy 95.402227 -112.991506) (xy 95.456175 -112.98375)
			(xy 95.510677 -112.98375) (xy 95.564625 -112.991506) (xy 95.61692 -113.006861) (xy 95.666497 -113.029503)
			(xy 95.712347 -113.058969) (xy 95.753538 -113.09466) (xy 95.789229 -113.135851) (xy 95.818695 -113.181701)
			(xy 95.841337 -113.231278) (xy 95.856692 -113.283573) (xy 95.864448 -113.337521) (xy 95.864934 -113.364772)
			(xy 95.864504 -113.391087) (xy 95.85726 -113.443217) (xy 95.842933 -113.49386) (xy 95.821793 -113.542058)
			(xy 95.805403 -113.568734) (xy 110.889794 -113.568734) (xy 110.893865 -113.513112) (xy 110.905991 -113.458675)
			(xy 110.925914 -113.406584) (xy 110.95321 -113.357949) (xy 110.987296 -113.313806) (xy 111.027445 -113.275097)
			(xy 111.072803 -113.242646) (xy 111.122403 -113.217145) (xy 111.175187 -113.199138) (xy 111.23003 -113.189008)
			(xy 111.285764 -113.186971) (xy 111.341201 -113.193071) (xy 111.395158 -113.207177) (xy 111.446487 -113.228989)
			(xy 111.494093 -113.258043) (xy 111.536961 -113.293718) (xy 111.574178 -113.335255) (xy 111.604951 -113.381768)
			(xy 111.628623 -113.432265) (xy 111.644691 -113.485672) (xy 111.652811 -113.540848) (xy 111.653227 -113.563654)
			(xy 112.947448 -113.563654) (xy 112.951519 -113.508032) (xy 112.963645 -113.453595) (xy 112.983568 -113.401504)
			(xy 113.010864 -113.352869) (xy 113.04495 -113.308726) (xy 113.085099 -113.270017) (xy 113.130457 -113.237566)
			(xy 113.180057 -113.212065) (xy 113.232841 -113.194058) (xy 113.287684 -113.183928) (xy 113.343418 -113.181891)
			(xy 113.398855 -113.187991) (xy 113.452812 -113.202097) (xy 113.504141 -113.223909) (xy 113.551747 -113.252963)
			(xy 113.594615 -113.288638) (xy 113.631832 -113.330175) (xy 113.662605 -113.376688) (xy 113.686277 -113.427185)
			(xy 113.702345 -113.480592) (xy 113.710465 -113.535768) (xy 113.710974 -113.563654) (xy 113.710465 -113.59154)
			(xy 113.702345 -113.646716) (xy 113.686277 -113.700123) (xy 113.662605 -113.75062) (xy 113.631832 -113.797133)
			(xy 113.594615 -113.83867) (xy 113.551747 -113.874345) (xy 113.504141 -113.903399) (xy 113.452812 -113.925211)
			(xy 113.398855 -113.939317) (xy 113.343418 -113.945417) (xy 113.287684 -113.94338) (xy 113.232841 -113.93325)
			(xy 113.180057 -113.915243) (xy 113.130457 -113.889742) (xy 113.085099 -113.857291) (xy 113.04495 -113.818582)
			(xy 113.010864 -113.774439) (xy 112.983568 -113.725804) (xy 112.963645 -113.673713) (xy 112.951519 -113.619276)
			(xy 112.947448 -113.563654) (xy 111.653227 -113.563654) (xy 111.65332 -113.568734) (xy 111.652811 -113.59662)
			(xy 111.644691 -113.651796) (xy 111.628623 -113.705203) (xy 111.604951 -113.7557) (xy 111.574178 -113.802213)
			(xy 111.536961 -113.84375) (xy 111.494093 -113.879425) (xy 111.446487 -113.908479) (xy 111.395158 -113.930291)
			(xy 111.341201 -113.944397) (xy 111.285764 -113.950497) (xy 111.23003 -113.94846) (xy 111.175187 -113.93833)
			(xy 111.122403 -113.920323) (xy 111.072803 -113.894822) (xy 111.027445 -113.862371) (xy 110.987296 -113.823662)
			(xy 110.95321 -113.779519) (xy 110.925914 -113.730884) (xy 110.905991 -113.678793) (xy 110.893865 -113.624356)
			(xy 110.889794 -113.568734) (xy 95.805403 -113.568734) (xy 95.794241 -113.586901) (xy 95.760798 -113.62754)
			(xy 95.741744 -113.645696) (xy 95.734349 -113.653223) (xy 95.725819 -113.672499) (xy 95.725234 -113.683034)
			(xy 95.725234 -113.75771) (xy 95.725734 -113.768263) (xy 95.734289 -113.787559) (xy 95.741744 -113.795048)
			(xy 95.760824 -113.813179) (xy 95.794277 -113.853815) (xy 95.821832 -113.89866) (xy 95.842966 -113.946866)
			(xy 95.857278 -113.997517) (xy 95.864498 -114.049655) (xy 95.864934 -114.075972) (xy 95.864448 -114.103223)
			(xy 95.856692 -114.157171) (xy 95.841337 -114.209466) (xy 95.818695 -114.259043) (xy 95.789229 -114.304893)
			(xy 95.753538 -114.346084) (xy 95.712347 -114.381775) (xy 95.666497 -114.411241) (xy 95.61692 -114.433883)
			(xy 95.564625 -114.449238) (xy 95.510677 -114.456994) (xy 95.456175 -114.456994) (xy 95.402227 -114.449238)
			(xy 95.349932 -114.433883) (xy 95.300355 -114.411241) (xy 95.254505 -114.381775) (xy 95.213314 -114.346084)
			(xy 95.177623 -114.304893) (xy 95.148157 -114.259043) (xy 95.125515 -114.209466) (xy 95.11016 -114.157171)
			(xy 95.102404 -114.103223) (xy 95.101918 -114.075972) (xy 93.832934 -114.075972) (xy 93.832463 -114.102946)
			(xy 93.824855 -114.156356) (xy 93.809802 -114.208162) (xy 93.787602 -114.257332) (xy 93.758699 -114.302886)
			(xy 93.723669 -114.343915) (xy 93.68321 -114.379602) (xy 93.638128 -114.409235) (xy 93.589323 -114.432224)
			(xy 93.537766 -114.44811) (xy 93.484485 -114.456578) (xy 93.457522 -114.45748) (xy 93.451172 -114.45748)
			(xy 93.425309 -114.457072) (xy 93.374052 -114.450122) (xy 93.324207 -114.436299) (xy 93.276692 -114.415857)
			(xy 93.254322 -114.40287) (xy 93.240098 -114.394234) (xy 93.236288 -114.391694) (xy 93.226382 -114.384328)
			(xy 93.225366 -114.383566) (xy 93.223334 -114.382042) (xy 93.222826 -114.381788) (xy 93.222572 -114.381534)
			(xy 93.218254 -114.378486) (xy 93.213968 -114.375903) (xy 93.204627 -114.372315) (xy 93.199712 -114.371374)
			(xy 93.188282 -114.369342) (xy 93.096588 -114.399314) (xy 93.090737 -114.401382) (xy 93.080207 -114.407939)
			(xy 93.07576 -114.412268) (xy 93.071696 -114.416586) (xy 93.065854 -114.425984) (xy 93.063822 -114.432842)
			(xy 93.055501 -114.458883) (xy 93.032447 -114.508452) (xy 93.002557 -114.554225) (xy 92.966442 -114.595266)
			(xy 92.924842 -114.630735) (xy 92.878608 -114.659905) (xy 92.828684 -114.682182) (xy 92.776093 -114.697108)
			(xy 92.721911 -114.704379) (xy 92.667246 -114.703845) (xy 92.613216 -114.695518) (xy 92.560926 -114.679568)
			(xy 92.511447 -114.656321) (xy 92.465791 -114.626253) (xy 92.424891 -114.589979) (xy 92.389585 -114.548241)
			(xy 92.37472 -114.525298) (xy 92.367568 -114.517077) (xy 92.348225 -114.507088) (xy 92.337382 -114.505994)
			(xy 92.24645 -114.505994) (xy 92.235654 -114.50707) (xy 92.216417 -114.517055) (xy 92.209366 -114.525298)
			(xy 92.195143 -114.547261) (xy 92.161628 -114.587443) (xy 92.122944 -114.622676) (xy 92.079813 -114.652301)
			(xy 92.033044 -114.675763) (xy 91.98351 -114.692623) (xy 91.957906 -114.698018) (xy 91.927983 -114.703165)
			(xy 91.867299 -114.705009) (xy 91.807091 -114.697195) (xy 91.77782 -114.689128) (xy 91.74861 -114.679222)
			(xy 91.726265 -114.670239) (xy 91.683845 -114.64744) (xy 91.664028 -114.633756) (xy 91.663774 -114.633756)
			(xy 91.66352 -114.633502) (xy 91.657798 -114.629747) (xy 91.644922 -114.625121) (xy 91.63812 -114.624358)
			(xy 91.62415 -114.623342) (xy 91.604592 -114.633502) (xy 91.529154 -114.672364) (xy 91.521496 -114.677124)
			(xy 91.509909 -114.690922) (xy 91.506548 -114.699288) (xy 91.505142 -114.703467) (xy 91.503617 -114.712152)
			(xy 91.5035 -114.71656) (xy 91.5035 -115.832636) (xy 92.979748 -115.832636) (xy 92.980235 -115.804078)
			(xy 92.988733 -115.747598) (xy 93.005558 -115.693017) (xy 93.030334 -115.641555) (xy 93.062508 -115.594364)
			(xy 93.10136 -115.552498) (xy 93.146021 -115.516895) (xy 93.170502 -115.502182) (xy 93.183387 -115.494085)
			(xy 93.204065 -115.471781) (xy 93.217255 -115.444375) (xy 93.221786 -115.414299) (xy 93.217255 -115.384223)
			(xy 93.204064 -115.356818) (xy 93.183385 -115.334514) (xy 93.170502 -115.326414) (xy 93.14606 -115.311646)
			(xy 93.101418 -115.276037) (xy 93.062581 -115.234174) (xy 93.030415 -115.186991) (xy 93.005638 -115.135543)
			(xy 92.988803 -115.080977) (xy 92.980285 -115.024512) (xy 92.979748 -114.99596) (xy 92.980234 -114.968709)
			(xy 92.98799 -114.914761) (xy 93.003345 -114.862466) (xy 93.025987 -114.812889) (xy 93.055453 -114.767039)
			(xy 93.091144 -114.725848) (xy 93.132335 -114.690157) (xy 93.178185 -114.660691) (xy 93.227762 -114.638049)
			(xy 93.280057 -114.622694) (xy 93.334005 -114.614938) (xy 93.388507 -114.614938) (xy 93.442455 -114.622694)
			(xy 93.49475 -114.638049) (xy 93.544327 -114.660691) (xy 93.590177 -114.690157) (xy 93.631368 -114.725848)
			(xy 93.667059 -114.767039) (xy 93.696525 -114.812889) (xy 93.719167 -114.862466) (xy 93.734522 -114.914761)
			(xy 93.742278 -114.968709) (xy 93.742764 -114.99596) (xy 93.742268 -115.024518) (xy 93.733771 -115.080997)
			(xy 93.716947 -115.135577) (xy 93.692172 -115.187039) (xy 93.66 -115.23423) (xy 93.62115 -115.276096)
			(xy 93.576491 -115.311701) (xy 93.55201 -115.326414) (xy 93.539128 -115.334516) (xy 93.518447 -115.356818)
			(xy 93.505255 -115.384223) (xy 93.503709 -115.394486) (xy 95.147128 -115.394486) (xy 95.151199 -115.338864)
			(xy 95.163325 -115.284427) (xy 95.183248 -115.232336) (xy 95.210544 -115.183701) (xy 95.24463 -115.139558)
			(xy 95.284779 -115.100849) (xy 95.330137 -115.068398) (xy 95.379737 -115.042897) (xy 95.432521 -115.02489)
			(xy 95.487364 -115.01476) (xy 95.543098 -115.012723) (xy 95.598535 -115.018823) (xy 95.609192 -115.021609)
			(xy 97.556137 -115.021609) (xy 97.560451 -114.964337) (xy 97.5733 -114.908358) (xy 97.594393 -114.854937)
			(xy 97.623253 -114.80528) (xy 97.659229 -114.760509) (xy 97.680018 -114.74069) (xy 97.687429 -114.733176)
			(xy 97.695947 -114.71389) (xy 97.696528 -114.703352) (xy 97.696528 -114.628676) (xy 97.695963 -114.618131)
			(xy 97.687452 -114.598835) (xy 97.680018 -114.591338) (xy 97.660943 -114.573202) (xy 97.627487 -114.532569)
			(xy 97.59993 -114.487724) (xy 97.578795 -114.43952) (xy 97.564482 -114.388868) (xy 97.557263 -114.336731)
			(xy 97.556828 -114.310414) (xy 97.557314 -114.283163) (xy 97.56507 -114.229215) (xy 97.580425 -114.17692)
			(xy 97.603067 -114.127343) (xy 97.632533 -114.081493) (xy 97.668224 -114.040302) (xy 97.709415 -114.004611)
			(xy 97.755265 -113.975145) (xy 97.804842 -113.952503) (xy 97.857137 -113.937148) (xy 97.911085 -113.929392)
			(xy 97.965587 -113.929392) (xy 98.019535 -113.937148) (xy 98.07183 -113.952503) (xy 98.121407 -113.975145)
			(xy 98.167257 -114.004611) (xy 98.208448 -114.040302) (xy 98.244139 -114.081493) (xy 98.273605 -114.127343)
			(xy 98.296247 -114.17692) (xy 98.311602 -114.229215) (xy 98.319358 -114.283163) (xy 98.319844 -114.310414)
			(xy 98.319404 -114.336729) (xy 98.312166 -114.388859) (xy 98.297843 -114.439503) (xy 98.276705 -114.487703)
			(xy 98.249153 -114.532545) (xy 98.215709 -114.573183) (xy 98.196654 -114.591338) (xy 98.189242 -114.598851)
			(xy 98.180722 -114.618137) (xy 98.180144 -114.628676) (xy 98.180144 -114.703352) (xy 98.180673 -114.713902)
			(xy 98.189207 -114.733198) (xy 98.196654 -114.74069) (xy 98.217454 -114.760497) (xy 98.253426 -114.805273)
			(xy 98.282282 -114.854933) (xy 98.303372 -114.908356) (xy 98.316219 -114.964336) (xy 98.320533 -115.021609)
			(xy 100.094384 -115.021609) (xy 100.098697 -114.96434) (xy 100.111543 -114.908362) (xy 100.132631 -114.854942)
			(xy 100.161486 -114.805285) (xy 100.197455 -114.760511) (xy 100.21824 -114.74069) (xy 100.225639 -114.733166)
			(xy 100.234167 -114.713888) (xy 100.23475 -114.703352) (xy 100.23475 -114.628676) (xy 100.234178 -114.618132)
			(xy 100.225671 -114.598837) (xy 100.21824 -114.591338) (xy 100.19915 -114.573217) (xy 100.165698 -114.532579)
			(xy 100.138145 -114.487731) (xy 100.117013 -114.439523) (xy 100.102703 -114.38887) (xy 100.095485 -114.336732)
			(xy 100.09505 -114.310414) (xy 100.095536 -114.283163) (xy 100.103292 -114.229215) (xy 100.118647 -114.17692)
			(xy 100.141289 -114.127343) (xy 100.170755 -114.081493) (xy 100.206446 -114.040302) (xy 100.247637 -114.004611)
			(xy 100.293487 -113.975145) (xy 100.343064 -113.952503) (xy 100.395359 -113.937148) (xy 100.449307 -113.929392)
			(xy 100.503809 -113.929392) (xy 100.557757 -113.937148) (xy 100.610052 -113.952503) (xy 100.659629 -113.975145)
			(xy 100.705479 -114.004611) (xy 100.733019 -114.028474) (xy 105.005122 -114.028474) (xy 105.009193 -113.972852)
			(xy 105.021319 -113.918415) (xy 105.041242 -113.866324) (xy 105.068538 -113.817689) (xy 105.102624 -113.773546)
			(xy 105.142773 -113.734837) (xy 105.188131 -113.702386) (xy 105.237731 -113.676885) (xy 105.290515 -113.658878)
			(xy 105.345358 -113.648748) (xy 105.401092 -113.646711) (xy 105.456529 -113.652811) (xy 105.510486 -113.666917)
			(xy 105.561815 -113.688729) (xy 105.609421 -113.717783) (xy 105.652289 -113.753458) (xy 105.689506 -113.794995)
			(xy 105.720279 -113.841508) (xy 105.743951 -113.892005) (xy 105.760019 -113.945412) (xy 105.768139 -114.000588)
			(xy 105.768648 -114.028474) (xy 105.768139 -114.05636) (xy 105.760019 -114.111536) (xy 105.743951 -114.164943)
			(xy 105.720279 -114.21544) (xy 105.689506 -114.261953) (xy 105.652289 -114.30349) (xy 105.609421 -114.339165)
			(xy 105.561815 -114.368219) (xy 105.510486 -114.390031) (xy 105.456529 -114.404137) (xy 105.401092 -114.410237)
			(xy 105.345358 -114.4082) (xy 105.290515 -114.39807) (xy 105.237731 -114.380063) (xy 105.188131 -114.354562)
			(xy 105.142773 -114.322111) (xy 105.102624 -114.283402) (xy 105.068538 -114.239259) (xy 105.041242 -114.190624)
			(xy 105.021319 -114.138533) (xy 105.009193 -114.084096) (xy 105.005122 -114.028474) (xy 100.733019 -114.028474)
			(xy 100.74667 -114.040302) (xy 100.782361 -114.081493) (xy 100.811827 -114.127343) (xy 100.834469 -114.17692)
			(xy 100.849824 -114.229215) (xy 100.85758 -114.283163) (xy 100.858066 -114.310414) (xy 100.857619 -114.336729)
			(xy 100.850381 -114.388859) (xy 100.836059 -114.439502) (xy 100.814923 -114.487701) (xy 100.787373 -114.532544)
			(xy 100.75393 -114.573182) (xy 100.734876 -114.591338) (xy 100.727467 -114.598854) (xy 100.718944 -114.618138)
			(xy 100.718366 -114.628676) (xy 100.718366 -114.703352) (xy 100.718918 -114.713899) (xy 100.727438 -114.733194)
			(xy 100.734876 -114.74069) (xy 100.75568 -114.760495) (xy 100.791659 -114.805268) (xy 100.820521 -114.854927)
			(xy 100.841616 -114.908352) (xy 100.854465 -114.964334) (xy 100.857977 -115.010946) (xy 106.6198 -115.010946)
			(xy 106.623871 -114.955324) (xy 106.635997 -114.900887) (xy 106.65592 -114.848796) (xy 106.683216 -114.800161)
			(xy 106.717302 -114.756018) (xy 106.757451 -114.717309) (xy 106.802809 -114.684858) (xy 106.852409 -114.659357)
			(xy 106.905193 -114.64135) (xy 106.960036 -114.63122) (xy 107.01577 -114.629183) (xy 107.071207 -114.635283)
			(xy 107.125164 -114.649389) (xy 107.176493 -114.671201) (xy 107.224099 -114.700255) (xy 107.266967 -114.73593)
			(xy 107.304184 -114.777467) (xy 107.334957 -114.82398) (xy 107.358629 -114.874477) (xy 107.374697 -114.927884)
			(xy 107.382817 -114.98306) (xy 107.383326 -115.010946) (xy 107.382817 -115.038832) (xy 107.379893 -115.058698)
			(xy 107.98632 -115.058698) (xy 107.990391 -115.003076) (xy 108.002517 -114.948639) (xy 108.02244 -114.896548)
			(xy 108.049736 -114.847913) (xy 108.083822 -114.80377) (xy 108.123971 -114.765061) (xy 108.169329 -114.73261)
			(xy 108.218929 -114.707109) (xy 108.271713 -114.689102) (xy 108.326556 -114.678972) (xy 108.38229 -114.676935)
			(xy 108.437727 -114.683035) (xy 108.491684 -114.697141) (xy 108.543013 -114.718953) (xy 108.590619 -114.748007)
			(xy 108.633487 -114.783682) (xy 108.670704 -114.825219) (xy 108.701477 -114.871732) (xy 108.725149 -114.922229)
			(xy 108.741217 -114.975636) (xy 108.743386 -114.990372) (xy 109.365032 -114.990372) (xy 109.369103 -114.93475)
			(xy 109.381229 -114.880313) (xy 109.401152 -114.828222) (xy 109.428448 -114.779587) (xy 109.462534 -114.735444)
			(xy 109.502683 -114.696735) (xy 109.548041 -114.664284) (xy 109.597641 -114.638783) (xy 109.650425 -114.620776)
			(xy 109.705268 -114.610646) (xy 109.761002 -114.608609) (xy 109.816439 -114.614709) (xy 109.870396 -114.628815)
			(xy 109.921725 -114.650627) (xy 109.969331 -114.679681) (xy 110.012199 -114.715356) (xy 110.049416 -114.756893)
			(xy 110.080189 -114.803406) (xy 110.103861 -114.853903) (xy 110.119929 -114.90731) (xy 110.127779 -114.960654)
			(xy 110.891826 -114.960654) (xy 110.895897 -114.905032) (xy 110.908023 -114.850595) (xy 110.927946 -114.798504)
			(xy 110.955242 -114.749869) (xy 110.989328 -114.705726) (xy 111.029477 -114.667017) (xy 111.074835 -114.634566)
			(xy 111.124435 -114.609065) (xy 111.177219 -114.591058) (xy 111.232062 -114.580928) (xy 111.287796 -114.578891)
			(xy 111.343233 -114.584991) (xy 111.39719 -114.599097) (xy 111.448519 -114.620909) (xy 111.496125 -114.649963)
			(xy 111.538993 -114.685638) (xy 111.57621 -114.727175) (xy 111.606983 -114.773688) (xy 111.630655 -114.824185)
			(xy 111.646723 -114.877592) (xy 111.654843 -114.932768) (xy 111.655352 -114.960654) (xy 111.654843 -114.98854)
			(xy 111.646723 -115.043716) (xy 111.630655 -115.097123) (xy 111.606983 -115.14762) (xy 111.57621 -115.194133)
			(xy 111.538993 -115.23567) (xy 111.496125 -115.271345) (xy 111.448519 -115.300399) (xy 111.39719 -115.322211)
			(xy 111.343233 -115.336317) (xy 111.287796 -115.342417) (xy 111.232062 -115.34038) (xy 111.177219 -115.33025)
			(xy 111.124435 -115.312243) (xy 111.074835 -115.286742) (xy 111.029477 -115.254291) (xy 110.989328 -115.215582)
			(xy 110.955242 -115.171439) (xy 110.927946 -115.122804) (xy 110.908023 -115.070713) (xy 110.895897 -115.016276)
			(xy 110.891826 -114.960654) (xy 110.127779 -114.960654) (xy 110.128049 -114.962486) (xy 110.128558 -114.990372)
			(xy 110.128049 -115.018258) (xy 110.119929 -115.073434) (xy 110.103861 -115.126841) (xy 110.080189 -115.177338)
			(xy 110.049416 -115.223851) (xy 110.012199 -115.265388) (xy 109.969331 -115.301063) (xy 109.921725 -115.330117)
			(xy 109.870396 -115.351929) (xy 109.816439 -115.366035) (xy 109.761002 -115.372135) (xy 109.705268 -115.370098)
			(xy 109.650425 -115.359968) (xy 109.597641 -115.341961) (xy 109.548041 -115.31646) (xy 109.502683 -115.284009)
			(xy 109.462534 -115.2453) (xy 109.428448 -115.201157) (xy 109.401152 -115.152522) (xy 109.381229 -115.100431)
			(xy 109.369103 -115.045994) (xy 109.365032 -114.990372) (xy 108.743386 -114.990372) (xy 108.749337 -115.030812)
			(xy 108.749846 -115.058698) (xy 108.749337 -115.086584) (xy 108.741217 -115.14176) (xy 108.725149 -115.195167)
			(xy 108.701477 -115.245664) (xy 108.670704 -115.292177) (xy 108.633487 -115.333714) (xy 108.590619 -115.369389)
			(xy 108.543013 -115.398443) (xy 108.491684 -115.420255) (xy 108.437727 -115.434361) (xy 108.38229 -115.440461)
			(xy 108.326556 -115.438424) (xy 108.271713 -115.428294) (xy 108.218929 -115.410287) (xy 108.169329 -115.384786)
			(xy 108.123971 -115.352335) (xy 108.083822 -115.313626) (xy 108.049736 -115.269483) (xy 108.02244 -115.220848)
			(xy 108.002517 -115.168757) (xy 107.990391 -115.11432) (xy 107.98632 -115.058698) (xy 107.379893 -115.058698)
			(xy 107.374697 -115.094008) (xy 107.358629 -115.147415) (xy 107.334957 -115.197912) (xy 107.304184 -115.244425)
			(xy 107.266967 -115.285962) (xy 107.224099 -115.321637) (xy 107.176493 -115.350691) (xy 107.125164 -115.372503)
			(xy 107.071207 -115.386609) (xy 107.01577 -115.392709) (xy 106.960036 -115.390672) (xy 106.905193 -115.380542)
			(xy 106.852409 -115.362535) (xy 106.802809 -115.337034) (xy 106.757451 -115.304583) (xy 106.717302 -115.265874)
			(xy 106.683216 -115.221731) (xy 106.65592 -115.173096) (xy 106.635997 -115.121005) (xy 106.623871 -115.066568)
			(xy 106.6198 -115.010946) (xy 100.857977 -115.010946) (xy 100.85878 -115.021609) (xy 100.854462 -115.078885)
			(xy 100.84161 -115.134866) (xy 100.820513 -115.18829) (xy 100.791648 -115.237948) (xy 100.755667 -115.282719)
			(xy 100.734876 -115.302538) (xy 100.727467 -115.310054) (xy 100.718944 -115.329338) (xy 100.718366 -115.339876)
			(xy 100.718366 -115.414552) (xy 100.718918 -115.425099) (xy 100.727438 -115.444394) (xy 100.734876 -115.45189)
			(xy 100.753915 -115.470062) (xy 100.787375 -115.510688) (xy 100.814936 -115.555524) (xy 100.825631 -115.579906)
			(xy 105.143044 -115.579906) (xy 105.147115 -115.524284) (xy 105.159241 -115.469847) (xy 105.179164 -115.417756)
			(xy 105.20646 -115.369121) (xy 105.240546 -115.324978) (xy 105.280695 -115.286269) (xy 105.326053 -115.253818)
			(xy 105.375653 -115.228317) (xy 105.428437 -115.21031) (xy 105.48328 -115.20018) (xy 105.539014 -115.198143)
			(xy 105.594451 -115.204243) (xy 105.648408 -115.218349) (xy 105.699737 -115.240161) (xy 105.747343 -115.269215)
			(xy 105.790211 -115.30489) (xy 105.827428 -115.346427) (xy 105.858201 -115.39294) (xy 105.881873 -115.443437)
			(xy 105.897941 -115.496844) (xy 105.906061 -115.55202) (xy 105.90657 -115.579906) (xy 105.906061 -115.607792)
			(xy 105.897941 -115.662968) (xy 105.881873 -115.716375) (xy 105.858201 -115.766872) (xy 105.827428 -115.813385)
			(xy 105.790211 -115.854922) (xy 105.747343 -115.890597) (xy 105.699737 -115.919651) (xy 105.648408 -115.941463)
			(xy 105.594451 -115.955569) (xy 105.539014 -115.961669) (xy 105.48328 -115.959632) (xy 105.428437 -115.949502)
			(xy 105.375653 -115.931495) (xy 105.326053 -115.905994) (xy 105.280695 -115.873543) (xy 105.240546 -115.834834)
			(xy 105.20646 -115.790691) (xy 105.179164 -115.742056) (xy 105.159241 -115.689965) (xy 105.147115 -115.635528)
			(xy 105.143044 -115.579906) (xy 100.825631 -115.579906) (xy 100.836078 -115.603722) (xy 100.850398 -115.654367)
			(xy 100.857626 -115.706499) (xy 100.858066 -115.732814) (xy 100.85758 -115.760065) (xy 100.849824 -115.814013)
			(xy 100.834469 -115.866308) (xy 100.811827 -115.915885) (xy 100.782361 -115.961735) (xy 100.74667 -116.002926)
			(xy 100.705479 -116.038617) (xy 100.659629 -116.068083) (xy 100.610052 -116.090725) (xy 100.557757 -116.10608)
			(xy 100.503809 -116.113836) (xy 100.449307 -116.113836) (xy 100.395359 -116.10608) (xy 100.343064 -116.090725)
			(xy 100.293487 -116.068083) (xy 100.247637 -116.038617) (xy 100.206446 -116.002926) (xy 100.170755 -115.961735)
			(xy 100.141289 -115.915885) (xy 100.118647 -115.866308) (xy 100.103292 -115.814013) (xy 100.095536 -115.760065)
			(xy 100.09505 -115.732814) (xy 100.095511 -115.7065) (xy 100.102745 -115.65437) (xy 100.117064 -115.603727)
			(xy 100.138198 -115.555527) (xy 100.165746 -115.510684) (xy 100.199187 -115.470046) (xy 100.21824 -115.45189)
			(xy 100.225639 -115.444366) (xy 100.234167 -115.425088) (xy 100.23475 -115.414552) (xy 100.23475 -115.339876)
			(xy 100.234178 -115.329332) (xy 100.225671 -115.310037) (xy 100.21824 -115.302538) (xy 100.197468 -115.282703)
			(xy 100.161497 -115.237931) (xy 100.13264 -115.188275) (xy 100.111549 -115.134856) (xy 100.0987 -115.078879)
			(xy 100.094384 -115.021609) (xy 98.320533 -115.021609) (xy 98.316216 -115.078882) (xy 98.303367 -115.134862)
			(xy 98.282274 -115.188284) (xy 98.253415 -115.237943) (xy 98.217441 -115.282717) (xy 98.196654 -115.302538)
			(xy 98.189242 -115.310051) (xy 98.180722 -115.329337) (xy 98.180144 -115.339876) (xy 98.180144 -115.414552)
			(xy 98.180673 -115.425102) (xy 98.189207 -115.444398) (xy 98.196654 -115.45189) (xy 98.215708 -115.470047)
			(xy 98.249163 -115.510678) (xy 98.276721 -115.555518) (xy 98.297859 -115.603718) (xy 98.312178 -115.654365)
			(xy 98.319404 -115.706498) (xy 98.319844 -115.732814) (xy 98.319358 -115.760065) (xy 98.311602 -115.814013)
			(xy 98.296247 -115.866308) (xy 98.273605 -115.915885) (xy 98.244139 -115.961735) (xy 98.208448 -116.002926)
			(xy 98.167257 -116.038617) (xy 98.121407 -116.068083) (xy 98.07183 -116.090725) (xy 98.019535 -116.10608)
			(xy 97.965587 -116.113836) (xy 97.911085 -116.113836) (xy 97.857137 -116.10608) (xy 97.804842 -116.090725)
			(xy 97.755265 -116.068083) (xy 97.709415 -116.038617) (xy 97.668224 -116.002926) (xy 97.632533 -115.961735)
			(xy 97.603067 -115.915885) (xy 97.580425 -115.866308) (xy 97.56507 -115.814013) (xy 97.557314 -115.760065)
			(xy 97.556828 -115.732814) (xy 97.557296 -115.7065) (xy 97.564529 -115.654371) (xy 97.578848 -115.603728)
			(xy 97.59998 -115.555529) (xy 97.627527 -115.510685) (xy 97.660966 -115.470046) (xy 97.680018 -115.45189)
			(xy 97.687429 -115.444376) (xy 97.695947 -115.42509) (xy 97.696528 -115.414552) (xy 97.696528 -115.339876)
			(xy 97.695963 -115.329331) (xy 97.687452 -115.310035) (xy 97.680018 -115.302538) (xy 97.659242 -115.282705)
			(xy 97.623264 -115.237936) (xy 97.594401 -115.18828) (xy 97.573305 -115.13486) (xy 97.560454 -115.078882)
			(xy 97.556137 -115.021609) (xy 95.609192 -115.021609) (xy 95.652492 -115.032929) (xy 95.703821 -115.054741)
			(xy 95.751427 -115.083795) (xy 95.794295 -115.11947) (xy 95.831512 -115.161007) (xy 95.862285 -115.20752)
			(xy 95.885957 -115.258017) (xy 95.902025 -115.311424) (xy 95.910145 -115.3666) (xy 95.910654 -115.394486)
			(xy 95.910145 -115.422372) (xy 95.902025 -115.477548) (xy 95.885957 -115.530955) (xy 95.862285 -115.581452)
			(xy 95.831512 -115.627965) (xy 95.794295 -115.669502) (xy 95.751427 -115.705177) (xy 95.703821 -115.734231)
			(xy 95.652492 -115.756043) (xy 95.598535 -115.770149) (xy 95.543098 -115.776249) (xy 95.487364 -115.774212)
			(xy 95.432521 -115.764082) (xy 95.379737 -115.746075) (xy 95.330137 -115.720574) (xy 95.284779 -115.688123)
			(xy 95.24463 -115.649414) (xy 95.210544 -115.605271) (xy 95.183248 -115.556636) (xy 95.163325 -115.504545)
			(xy 95.151199 -115.450108) (xy 95.147128 -115.394486) (xy 93.503709 -115.394486) (xy 93.500723 -115.414299)
			(xy 93.505254 -115.444375) (xy 93.518446 -115.47178) (xy 93.539126 -115.494083) (xy 93.55201 -115.502182)
			(xy 93.576453 -115.516949) (xy 93.621094 -115.552559) (xy 93.659931 -115.594422) (xy 93.692097 -115.641605)
			(xy 93.716874 -115.693053) (xy 93.733709 -115.747619) (xy 93.742226 -115.804084) (xy 93.742764 -115.832636)
			(xy 93.742278 -115.859887) (xy 93.734522 -115.913835) (xy 93.719167 -115.96613) (xy 93.696525 -116.015707)
			(xy 93.667059 -116.061557) (xy 93.631368 -116.102748) (xy 93.590177 -116.138439) (xy 93.544327 -116.167905)
			(xy 93.49475 -116.190547) (xy 93.442455 -116.205902) (xy 93.388507 -116.213658) (xy 93.334005 -116.213658)
			(xy 93.280057 -116.205902) (xy 93.227762 -116.190547) (xy 93.178185 -116.167905) (xy 93.132335 -116.138439)
			(xy 93.091144 -116.102748) (xy 93.055453 -116.061557) (xy 93.025987 -116.015707) (xy 93.003345 -115.96613)
			(xy 92.98799 -115.913835) (xy 92.980234 -115.859887) (xy 92.979748 -115.832636) (xy 91.5035 -115.832636)
			(xy 91.5035 -116.410486) (xy 95.147128 -116.410486) (xy 95.151199 -116.354864) (xy 95.163325 -116.300427)
			(xy 95.183248 -116.248336) (xy 95.210544 -116.199701) (xy 95.24463 -116.155558) (xy 95.284779 -116.116849)
			(xy 95.330137 -116.084398) (xy 95.379737 -116.058897) (xy 95.432521 -116.04089) (xy 95.487364 -116.03076)
			(xy 95.543098 -116.028723) (xy 95.598535 -116.034823) (xy 95.652492 -116.048929) (xy 95.703821 -116.070741)
			(xy 95.751427 -116.099795) (xy 95.794295 -116.13547) (xy 95.831512 -116.177007) (xy 95.862285 -116.22352)
			(xy 95.885957 -116.274017) (xy 95.902025 -116.327424) (xy 95.910145 -116.3826) (xy 95.910654 -116.410486)
			(xy 95.910145 -116.438372) (xy 95.902025 -116.493548) (xy 95.885957 -116.546955) (xy 95.862285 -116.597452)
			(xy 95.841294 -116.62918) (xy 105.137964 -116.62918) (xy 105.142035 -116.573558) (xy 105.154161 -116.519121)
			(xy 105.174084 -116.46703) (xy 105.20138 -116.418395) (xy 105.235466 -116.374252) (xy 105.275615 -116.335543)
			(xy 105.320973 -116.303092) (xy 105.370573 -116.277591) (xy 105.423357 -116.259584) (xy 105.4782 -116.249454)
			(xy 105.533934 -116.247417) (xy 105.589371 -116.253517) (xy 105.643328 -116.267623) (xy 105.694657 -116.289435)
			(xy 105.742263 -116.318489) (xy 105.785131 -116.354164) (xy 105.822348 -116.395701) (xy 105.853121 -116.442214)
			(xy 105.876793 -116.492711) (xy 105.892861 -116.546118) (xy 105.900981 -116.601294) (xy 105.90149 -116.62918)
			(xy 105.900981 -116.657066) (xy 105.892861 -116.712242) (xy 105.876793 -116.765649) (xy 105.853121 -116.816146)
			(xy 105.822348 -116.862659) (xy 105.785131 -116.904196) (xy 105.742263 -116.939871) (xy 105.694657 -116.968925)
			(xy 105.643328 -116.990737) (xy 105.589371 -117.004843) (xy 105.533934 -117.010943) (xy 105.4782 -117.008906)
			(xy 105.423357 -116.998776) (xy 105.370573 -116.980769) (xy 105.320973 -116.955268) (xy 105.275615 -116.922817)
			(xy 105.235466 -116.884108) (xy 105.20138 -116.839965) (xy 105.174084 -116.79133) (xy 105.154161 -116.739239)
			(xy 105.142035 -116.684802) (xy 105.137964 -116.62918) (xy 95.841294 -116.62918) (xy 95.831512 -116.643965)
			(xy 95.794295 -116.685502) (xy 95.751427 -116.721177) (xy 95.703821 -116.750231) (xy 95.652492 -116.772043)
			(xy 95.598535 -116.786149) (xy 95.543098 -116.792249) (xy 95.487364 -116.790212) (xy 95.432521 -116.780082)
			(xy 95.379737 -116.762075) (xy 95.330137 -116.736574) (xy 95.284779 -116.704123) (xy 95.24463 -116.665414)
			(xy 95.210544 -116.621271) (xy 95.183248 -116.572636) (xy 95.163325 -116.520545) (xy 95.151199 -116.466108)
			(xy 95.147128 -116.410486) (xy 91.5035 -116.410486) (xy 91.5035 -116.972588) (xy 91.503955 -116.978524)
			(xy 91.507287 -116.98995) (xy 91.510104 -116.995194) (xy 91.511374 -116.997226) (xy 91.514612 -117.001989)
			(xy 91.522814 -117.01007) (xy 91.52763 -117.013228) (xy 91.612466 -117.05717) (xy 91.612974 -117.05717)
			(xy 91.617546 -117.05971) (xy 91.631008 -117.062504) (xy 91.63812 -117.061996) (xy 91.64955 -117.05971)
			(xy 91.654884 -117.056916) (xy 91.660726 -117.054376) (xy 91.663774 -117.052598) (xy 91.665806 -117.051074)
			(xy 91.668346 -117.049296) (xy 91.69241 -117.033312) (xy 91.744347 -117.008019) (xy 91.79951 -116.990865)
			(xy 91.856631 -116.982243) (xy 91.885516 -116.981732) (xy 91.890342 -116.981732) (xy 91.917366 -116.982546)
			(xy 91.970789 -116.990858) (xy 92.022503 -117.006628) (xy 92.071472 -117.029542) (xy 92.116716 -117.05914)
			(xy 92.157327 -117.094829) (xy 92.164013 -117.102636) (xy 92.979238 -117.102636) (xy 92.983309 -117.047014)
			(xy 92.995435 -116.992577) (xy 93.015358 -116.940486) (xy 93.042654 -116.891851) (xy 93.07674 -116.847708)
			(xy 93.116889 -116.808999) (xy 93.162247 -116.776548) (xy 93.211847 -116.751047) (xy 93.264631 -116.73304)
			(xy 93.319474 -116.72291) (xy 93.375208 -116.720873) (xy 93.430645 -116.726973) (xy 93.484602 -116.741079)
			(xy 93.535931 -116.762891) (xy 93.583537 -116.791945) (xy 93.626405 -116.82762) (xy 93.663622 -116.869157)
			(xy 93.694395 -116.91567) (xy 93.718067 -116.966167) (xy 93.734135 -117.019574) (xy 93.742255 -117.07475)
			(xy 93.742764 -117.102636) (xy 93.742255 -117.130522) (xy 93.734135 -117.185698) (xy 93.718067 -117.239105)
			(xy 93.694395 -117.289602) (xy 93.663622 -117.336115) (xy 93.626405 -117.377652) (xy 93.583537 -117.413327)
			(xy 93.561976 -117.426486) (xy 95.147128 -117.426486) (xy 95.151199 -117.370864) (xy 95.163325 -117.316427)
			(xy 95.183248 -117.264336) (xy 95.210544 -117.215701) (xy 95.24463 -117.171558) (xy 95.284779 -117.132849)
			(xy 95.330137 -117.100398) (xy 95.379737 -117.074897) (xy 95.432521 -117.05689) (xy 95.487364 -117.04676)
			(xy 95.543098 -117.044723) (xy 95.598535 -117.050823) (xy 95.652492 -117.064929) (xy 95.703821 -117.086741)
			(xy 95.751427 -117.115795) (xy 95.794295 -117.15147) (xy 95.831512 -117.193007) (xy 95.850018 -117.220979)
			(xy 107.73981 -117.220979) (xy 107.747563 -117.167021) (xy 107.762917 -117.114715) (xy 107.785558 -117.065127)
			(xy 107.815025 -117.019266) (xy 107.85072 -116.978065) (xy 107.891915 -116.942364) (xy 107.937771 -116.912888)
			(xy 107.987355 -116.890239) (xy 108.039658 -116.874877) (xy 108.093615 -116.867115) (xy 108.148128 -116.867111)
			(xy 108.202086 -116.874865) (xy 108.254391 -116.890219) (xy 108.303979 -116.912861) (xy 108.34984 -116.942329)
			(xy 108.39104 -116.978024) (xy 108.42674 -117.01922) (xy 108.456215 -117.065077) (xy 108.478863 -117.114661)
			(xy 108.494224 -117.166965) (xy 108.501985 -117.220922) (xy 108.50245 -117.248178) (xy 108.50245 -117.24894)
			(xy 108.501954 -117.276119) (xy 108.494171 -117.329919) (xy 108.486956 -117.356128) (xy 108.483146 -117.368828)
			(xy 108.488734 -117.394228) (xy 108.562394 -117.478302) (xy 108.586524 -117.487446) (xy 108.599478 -117.485414)
			(xy 108.613615 -117.483393) (xy 108.642094 -117.481234) (xy 108.656374 -117.481096) (xy 108.656882 -117.481096)
			(xy 108.66882 -117.48135) (xy 108.669074 -117.48135) (xy 108.681031 -117.481012) (xy 108.702632 -117.470821)
			(xy 108.710476 -117.461792) (xy 108.761022 -117.397022) (xy 108.767826 -117.387258) (xy 108.772458 -117.363944)
			(xy 108.769912 -117.352318) (xy 108.769912 -117.35181) (xy 108.763178 -117.326431) (xy 108.755909 -117.27443)
			(xy 108.755434 -117.248178) (xy 108.75592 -117.220927) (xy 108.763676 -117.166979) (xy 108.779031 -117.114684)
			(xy 108.801673 -117.065107) (xy 108.831139 -117.019257) (xy 108.86683 -116.978066) (xy 108.908021 -116.942375)
			(xy 108.953871 -116.912909) (xy 109.003448 -116.890267) (xy 109.055743 -116.874912) (xy 109.109691 -116.867156)
			(xy 109.164193 -116.867156) (xy 109.218141 -116.874912) (xy 109.270436 -116.890267) (xy 109.320013 -116.912909)
			(xy 109.365863 -116.942375) (xy 109.407054 -116.978066) (xy 109.442745 -117.019257) (xy 109.472211 -117.065107)
			(xy 109.494853 -117.114684) (xy 109.510208 -117.166979) (xy 109.517964 -117.220927) (xy 109.51845 -117.248178)
			(xy 109.770924 -117.248178) (xy 109.774995 -117.192556) (xy 109.787121 -117.138119) (xy 109.807044 -117.086028)
			(xy 109.83434 -117.037393) (xy 109.868426 -116.99325) (xy 109.908575 -116.954541) (xy 109.953933 -116.92209)
			(xy 110.003533 -116.896589) (xy 110.056317 -116.878582) (xy 110.11116 -116.868452) (xy 110.166894 -116.866415)
			(xy 110.222331 -116.872515) (xy 110.276288 -116.886621) (xy 110.327617 -116.908433) (xy 110.375223 -116.937487)
			(xy 110.418091 -116.973162) (xy 110.455308 -117.014699) (xy 110.486081 -117.061212) (xy 110.509753 -117.111709)
			(xy 110.525821 -117.165116) (xy 110.533941 -117.220292) (xy 110.53445 -117.248178) (xy 110.533941 -117.276064)
			(xy 110.525821 -117.33124) (xy 110.523759 -117.338094) (xy 114.818158 -117.338094) (xy 114.822229 -117.282472)
			(xy 114.834355 -117.228035) (xy 114.854278 -117.175944) (xy 114.881574 -117.127309) (xy 114.91566 -117.083166)
			(xy 114.955809 -117.044457) (xy 115.001167 -117.012006) (xy 115.050767 -116.986505) (xy 115.103551 -116.968498)
			(xy 115.158394 -116.958368) (xy 115.214128 -116.956331) (xy 115.269565 -116.962431) (xy 115.323522 -116.976537)
			(xy 115.326386 -116.977754) (xy 116.998945 -116.977754) (xy 116.998945 -116.923246) (xy 117.006702 -116.869293)
			(xy 117.022059 -116.816994) (xy 117.044702 -116.767412) (xy 117.074171 -116.721558) (xy 117.109866 -116.680364)
			(xy 117.151061 -116.644669) (xy 117.196916 -116.6152) (xy 117.246498 -116.592557) (xy 117.298797 -116.577201)
			(xy 117.35275 -116.569445) (xy 117.380004 -116.568982) (xy 117.408923 -116.569466) (xy 117.466097 -116.578198)
			(xy 117.521298 -116.595461) (xy 117.57326 -116.620859) (xy 117.620793 -116.65381) (xy 117.662806 -116.693559)
			(xy 117.680994 -116.716048) (xy 117.688605 -116.72485) (xy 117.709503 -116.735035) (xy 117.721126 -116.735606)
			(xy 117.800882 -116.735606) (xy 117.81251 -116.73504) (xy 117.83342 -116.72487) (xy 117.841014 -116.716048)
			(xy 117.859184 -116.693547) (xy 117.90121 -116.653815) (xy 117.948749 -116.62088) (xy 118.000715 -116.595495)
			(xy 118.055915 -116.578242) (xy 118.113087 -116.569516) (xy 118.142004 -116.568982) (xy 118.169254 -116.569489)
			(xy 118.2232 -116.577245) (xy 118.275493 -116.5926) (xy 118.325068 -116.615241) (xy 118.370917 -116.644707)
			(xy 118.412106 -116.680397) (xy 118.447796 -116.721586) (xy 118.477261 -116.767435) (xy 118.499901 -116.817011)
			(xy 118.515256 -116.869304) (xy 118.523012 -116.92325) (xy 118.523012 -116.97775) (xy 118.515256 -117.031696)
			(xy 118.499901 -117.083989) (xy 118.477261 -117.133565) (xy 118.447796 -117.179414) (xy 118.412106 -117.220603)
			(xy 118.370917 -117.256293) (xy 118.325068 -117.285759) (xy 118.275493 -117.3084) (xy 118.2232 -117.323755)
			(xy 118.169254 -117.331511) (xy 118.142004 -117.331998) (xy 118.113087 -117.331477) (xy 118.055916 -117.322749)
			(xy 118.000717 -117.305491) (xy 117.948756 -117.2801) (xy 117.901222 -117.247157) (xy 117.859204 -117.207417)
			(xy 117.841014 -117.184932) (xy 117.833403 -117.17613) (xy 117.812505 -117.165946) (xy 117.800882 -117.165374)
			(xy 117.721126 -117.165374) (xy 117.709494 -117.165916) (xy 117.688582 -117.1761) (xy 117.680994 -117.184932)
			(xy 117.662814 -117.207425) (xy 117.620791 -117.247158) (xy 117.573254 -117.280095) (xy 117.52129 -117.305482)
			(xy 117.466091 -117.322736) (xy 117.408921 -117.331464) (xy 117.380004 -117.331998) (xy 117.35275 -117.331555)
			(xy 117.298797 -117.323799) (xy 117.246498 -117.308443) (xy 117.196916 -117.2858) (xy 117.151061 -117.256331)
			(xy 117.109866 -117.220636) (xy 117.074171 -117.179442) (xy 117.044702 -117.133588) (xy 117.022059 -117.084006)
			(xy 117.006702 -117.031707) (xy 116.998945 -116.977754) (xy 115.326386 -116.977754) (xy 115.374851 -116.998349)
			(xy 115.422457 -117.027403) (xy 115.465325 -117.063078) (xy 115.502542 -117.104615) (xy 115.533315 -117.151128)
			(xy 115.556987 -117.201625) (xy 115.573055 -117.255032) (xy 115.581175 -117.310208) (xy 115.581684 -117.338094)
			(xy 115.581175 -117.36598) (xy 115.573055 -117.421156) (xy 115.556987 -117.474563) (xy 115.533315 -117.52506)
			(xy 115.502542 -117.571573) (xy 115.465325 -117.61311) (xy 115.422457 -117.648785) (xy 115.374851 -117.677839)
			(xy 115.323522 -117.699651) (xy 115.269565 -117.713757) (xy 115.214128 -117.719857) (xy 115.158394 -117.71782)
			(xy 115.103551 -117.70769) (xy 115.050767 -117.689683) (xy 115.001167 -117.664182) (xy 114.955809 -117.631731)
			(xy 114.91566 -117.593022) (xy 114.881574 -117.548879) (xy 114.854278 -117.500244) (xy 114.834355 -117.448153)
			(xy 114.822229 -117.393716) (xy 114.818158 -117.338094) (xy 110.523759 -117.338094) (xy 110.509753 -117.384647)
			(xy 110.486081 -117.435144) (xy 110.455308 -117.481657) (xy 110.418091 -117.523194) (xy 110.375223 -117.558869)
			(xy 110.327617 -117.587923) (xy 110.276288 -117.609735) (xy 110.222331 -117.623841) (xy 110.166894 -117.629941)
			(xy 110.11116 -117.627904) (xy 110.056317 -117.617774) (xy 110.003533 -117.599767) (xy 109.953933 -117.574266)
			(xy 109.908575 -117.541815) (xy 109.868426 -117.503106) (xy 109.83434 -117.458963) (xy 109.807044 -117.410328)
			(xy 109.787121 -117.358237) (xy 109.774995 -117.3038) (xy 109.770924 -117.248178) (xy 109.51845 -117.248178)
			(xy 109.517902 -117.275415) (xy 109.510156 -117.329336) (xy 109.494819 -117.381607) (xy 109.472202 -117.431164)
			(xy 109.442766 -117.477) (xy 109.407108 -117.518183) (xy 109.365955 -117.553875) (xy 109.320144 -117.58335)
			(xy 109.270605 -117.606008) (xy 109.218347 -117.621389) (xy 109.164433 -117.62918) (xy 109.137196 -117.629686)
			(xy 109.136688 -117.629686) (xy 109.12475 -117.629432) (xy 109.124496 -117.629432) (xy 109.112538 -117.629759)
			(xy 109.090937 -117.639959) (xy 109.083094 -117.64899) (xy 109.032548 -117.71376) (xy 109.025752 -117.723528)
			(xy 109.023654 -117.73408) (xy 116.39626 -117.73408) (xy 116.400331 -117.678458) (xy 116.412457 -117.624021)
			(xy 116.43238 -117.57193) (xy 116.459676 -117.523295) (xy 116.493762 -117.479152) (xy 116.533911 -117.440443)
			(xy 116.579269 -117.407992) (xy 116.628869 -117.382491) (xy 116.681653 -117.364484) (xy 116.736496 -117.354354)
			(xy 116.79223 -117.352317) (xy 116.847667 -117.358417) (xy 116.901624 -117.372523) (xy 116.952953 -117.394335)
			(xy 117.000559 -117.423389) (xy 117.043427 -117.459064) (xy 117.080644 -117.500601) (xy 117.111417 -117.547114)
			(xy 117.135089 -117.597611) (xy 117.151157 -117.651018) (xy 117.159277 -117.706194) (xy 117.159786 -117.73408)
			(xy 117.159277 -117.761966) (xy 117.151157 -117.817142) (xy 117.135089 -117.870549) (xy 117.111417 -117.921046)
			(xy 117.080644 -117.967559) (xy 117.043427 -118.009096) (xy 117.021849 -118.027053) (xy 117.690342 -118.027053)
			(xy 117.690342 -117.972547) (xy 117.698099 -117.918594) (xy 117.713455 -117.866295) (xy 117.736098 -117.816714)
			(xy 117.765566 -117.77086) (xy 117.80126 -117.729666) (xy 117.842453 -117.693971) (xy 117.888307 -117.664502)
			(xy 117.937888 -117.641858) (xy 117.990187 -117.626501) (xy 118.044139 -117.618742) (xy 118.071392 -117.618256)
			(xy 118.10031 -117.618759) (xy 118.157483 -117.627488) (xy 118.212683 -117.644748) (xy 118.264645 -117.670142)
			(xy 118.312178 -117.703089) (xy 118.354193 -117.742834) (xy 118.372382 -117.765322) (xy 118.380003 -117.774115)
			(xy 118.400893 -117.784306) (xy 118.412514 -117.78488) (xy 118.49227 -117.78488) (xy 118.503899 -117.784316)
			(xy 118.524809 -117.774146) (xy 118.532402 -117.765322) (xy 118.550597 -117.742842) (xy 118.592616 -117.703106)
			(xy 118.640149 -117.670166) (xy 118.69211 -117.644776) (xy 118.747307 -117.62752) (xy 118.804476 -117.618791)
			(xy 118.833392 -117.618256) (xy 118.860636 -117.61873) (xy 118.91457 -117.626487) (xy 118.966851 -117.641843)
			(xy 119.016412 -117.664487) (xy 119.062245 -117.693955) (xy 119.103415 -117.729649) (xy 119.139084 -117.770841)
			(xy 119.154194 -117.793516) (xy 119.159066 -117.800522) (xy 119.172461 -117.811075) (xy 119.188592 -117.816608)
			(xy 119.19712 -117.816884) (xy 119.282464 -117.816884) (xy 119.290987 -117.8166) (xy 119.307101 -117.811037)
			(xy 119.320508 -117.80051) (xy 119.32539 -117.793516) (xy 119.340502 -117.770842) (xy 119.37617 -117.729648)
			(xy 119.41734 -117.693953) (xy 119.463172 -117.664482) (xy 119.512733 -117.641837) (xy 119.565013 -117.626479)
			(xy 119.618947 -117.61872) (xy 119.646192 -117.618256) (xy 119.673443 -117.618791) (xy 119.727389 -117.626546)
			(xy 119.779683 -117.6419) (xy 119.82926 -117.66454) (xy 119.875109 -117.694005) (xy 119.916299 -117.729695)
			(xy 119.95199 -117.770884) (xy 119.981456 -117.816733) (xy 120.004097 -117.866309) (xy 120.019452 -117.918603)
			(xy 120.027209 -117.972549) (xy 120.027209 -118.027051) (xy 120.019452 -118.080997) (xy 120.004097 -118.133291)
			(xy 119.981456 -118.182867) (xy 119.95199 -118.228716) (xy 119.916299 -118.269905) (xy 119.875109 -118.305595)
			(xy 119.82926 -118.33506) (xy 119.779683 -118.3577) (xy 119.727389 -118.373054) (xy 119.673443 -118.380809)
			(xy 119.646192 -118.381272) (xy 119.618948 -118.380797) (xy 119.565014 -118.373039) (xy 119.512735 -118.357682)
			(xy 119.463174 -118.335038) (xy 119.417341 -118.30557) (xy 119.376171 -118.269877) (xy 119.340501 -118.228686)
			(xy 119.32539 -118.206012) (xy 119.320547 -118.198984) (xy 119.307136 -118.188441) (xy 119.290996 -118.182916)
			(xy 119.282464 -118.182644) (xy 119.19712 -118.182644) (xy 119.188599 -118.182949) (xy 119.17249 -118.188508)
			(xy 119.15908 -118.199024) (xy 119.154194 -118.206012) (xy 119.139069 -118.228678) (xy 119.103406 -118.269874)
			(xy 119.062239 -118.305573) (xy 119.01641 -118.335046) (xy 118.96685 -118.357692) (xy 118.91457 -118.373051)
			(xy 118.860636 -118.380809) (xy 118.833392 -118.381272) (xy 118.804477 -118.380698) (xy 118.747308 -118.371982)
			(xy 118.69211 -118.354736) (xy 118.640148 -118.329355) (xy 118.592612 -118.29642) (xy 118.550594 -118.256687)
			(xy 118.532402 -118.234206) (xy 118.524783 -118.225411) (xy 118.503891 -118.21522) (xy 118.49227 -118.214648)
			(xy 118.412514 -118.214648) (xy 118.400882 -118.215193) (xy 118.379972 -118.225376) (xy 118.372382 -118.234206)
			(xy 118.354203 -118.256699) (xy 118.31218 -118.296434) (xy 118.264643 -118.329371) (xy 118.212679 -118.354758)
			(xy 118.15748 -118.372012) (xy 118.100309 -118.380738) (xy 118.071392 -118.381272) (xy 118.044139 -118.380858)
			(xy 117.990187 -118.373099) (xy 117.937888 -118.357742) (xy 117.888307 -118.335098) (xy 117.842453 -118.305629)
			(xy 117.80126 -118.269934) (xy 117.765566 -118.22874) (xy 117.736098 -118.182886) (xy 117.713455 -118.133305)
			(xy 117.698099 -118.081006) (xy 117.690342 -118.027053) (xy 117.021849 -118.027053) (xy 117.000559 -118.044771)
			(xy 116.952953 -118.073825) (xy 116.901624 -118.095637) (xy 116.847667 -118.109743) (xy 116.79223 -118.115843)
			(xy 116.736496 -118.113806) (xy 116.681653 -118.103676) (xy 116.628869 -118.085669) (xy 116.579269 -118.060168)
			(xy 116.533911 -118.027717) (xy 116.493762 -117.989008) (xy 116.459676 -117.944865) (xy 116.43238 -117.89623)
			(xy 116.412457 -117.844139) (xy 116.400331 -117.789702) (xy 116.39626 -117.73408) (xy 109.023654 -117.73408)
			(xy 109.021117 -117.746839) (xy 109.023658 -117.758464) (xy 109.023658 -117.758972) (xy 109.030408 -117.784347)
			(xy 109.037666 -117.836351) (xy 109.038136 -117.862604) (xy 109.03765 -117.889855) (xy 109.029894 -117.943803)
			(xy 109.014539 -117.996098) (xy 108.991897 -118.045675) (xy 108.962431 -118.091525) (xy 108.92674 -118.132716)
			(xy 108.885549 -118.168407) (xy 108.839699 -118.197873) (xy 108.790122 -118.220515) (xy 108.737827 -118.23587)
			(xy 108.683879 -118.243626) (xy 108.629377 -118.243626) (xy 108.575429 -118.23587) (xy 108.523134 -118.220515)
			(xy 108.473557 -118.197873) (xy 108.427707 -118.168407) (xy 108.386516 -118.132716) (xy 108.350825 -118.091525)
			(xy 108.321359 -118.045675) (xy 108.298717 -117.996098) (xy 108.283362 -117.943803) (xy 108.275606 -117.889855)
			(xy 108.27512 -117.862604) (xy 108.27512 -117.861842) (xy 108.275608 -117.834662) (xy 108.283381 -117.780859)
			(xy 108.290614 -117.754654) (xy 108.294424 -117.741954) (xy 108.288836 -117.716554) (xy 108.215176 -117.63248)
			(xy 108.191046 -117.623336) (xy 108.178092 -117.625368) (xy 108.163891 -117.62739) (xy 108.135286 -117.629553)
			(xy 108.120942 -117.629686) (xy 108.093686 -117.62929) (xy 108.039727 -117.621538) (xy 107.987422 -117.606186)
			(xy 107.937833 -117.583546) (xy 107.891971 -117.554079) (xy 107.85077 -117.518385) (xy 107.815068 -117.477191)
			(xy 107.785592 -117.431335) (xy 107.762941 -117.381751) (xy 107.747578 -117.329448) (xy 107.739815 -117.275491)
			(xy 107.73981 -117.220979) (xy 95.850018 -117.220979) (xy 95.862285 -117.23952) (xy 95.885957 -117.290017)
			(xy 95.902025 -117.343424) (xy 95.910145 -117.3986) (xy 95.910654 -117.426486) (xy 95.910145 -117.454372)
			(xy 95.902025 -117.509548) (xy 95.885957 -117.562955) (xy 95.862285 -117.613452) (xy 95.831512 -117.659965)
			(xy 95.794295 -117.701502) (xy 95.751427 -117.737177) (xy 95.703821 -117.766231) (xy 95.652492 -117.788043)
			(xy 95.598535 -117.802149) (xy 95.543098 -117.808249) (xy 95.487364 -117.806212) (xy 95.432521 -117.796082)
			(xy 95.379737 -117.778075) (xy 95.330137 -117.752574) (xy 95.284779 -117.720123) (xy 95.24463 -117.681414)
			(xy 95.210544 -117.637271) (xy 95.183248 -117.588636) (xy 95.163325 -117.536545) (xy 95.151199 -117.482108)
			(xy 95.147128 -117.426486) (xy 93.561976 -117.426486) (xy 93.535931 -117.442381) (xy 93.484602 -117.464193)
			(xy 93.430645 -117.478299) (xy 93.375208 -117.484399) (xy 93.319474 -117.482362) (xy 93.264631 -117.472232)
			(xy 93.211847 -117.454225) (xy 93.162247 -117.428724) (xy 93.116889 -117.396273) (xy 93.07674 -117.357564)
			(xy 93.042654 -117.313421) (xy 93.015358 -117.264786) (xy 92.995435 -117.212695) (xy 92.983309 -117.158258)
			(xy 92.979238 -117.102636) (xy 92.164013 -117.102636) (xy 92.192494 -117.135894) (xy 92.22151 -117.181513)
			(xy 92.243796 -117.230772) (xy 92.258903 -117.282683) (xy 92.266531 -117.336207) (xy 92.267024 -117.36324)
			(xy 92.266536 -117.39049) (xy 92.258774 -117.444434) (xy 92.243416 -117.496725) (xy 92.220773 -117.546298)
			(xy 92.191306 -117.592145) (xy 92.155614 -117.633331) (xy 92.114425 -117.66902) (xy 92.068577 -117.698484)
			(xy 92.019002 -117.721124) (xy 91.966711 -117.73648) (xy 91.912766 -117.744237) (xy 91.885516 -117.744748)
			(xy 91.855961 -117.744195) (xy 91.797556 -117.735084) (xy 91.741255 -117.717076) (xy 91.688404 -117.690604)
			(xy 91.664028 -117.673882) (xy 91.663774 -117.673882) (xy 91.66352 -117.673628) (xy 91.657799 -117.669871)
			(xy 91.644923 -117.665243) (xy 91.63812 -117.664484) (xy 91.62415 -117.663468) (xy 91.604592 -117.673628)
			(xy 91.529154 -117.71249) (xy 91.521489 -117.717245) (xy 91.509884 -117.731035) (xy 91.506548 -117.739414)
			(xy 91.505136 -117.743592) (xy 91.503598 -117.752277) (xy 91.5035 -117.756686) (xy 91.5035 -118.894352)
			(xy 93.41612 -118.894352) (xy 93.416549 -118.868037) (xy 93.423791 -118.815906) (xy 93.438117 -118.765263)
			(xy 93.459257 -118.717064) (xy 93.48681 -118.672221) (xy 93.520255 -118.631583) (xy 93.53931 -118.613428)
			(xy 93.546703 -118.605899) (xy 93.555232 -118.586625) (xy 93.55582 -118.57609) (xy 93.55582 -118.501414)
			(xy 93.555291 -118.490864) (xy 93.546755 -118.471569) (xy 93.53931 -118.464076) (xy 93.520252 -118.445923)
			(xy 93.486794 -118.405293) (xy 93.459236 -118.360452) (xy 93.438097 -118.312251) (xy 93.423781 -118.261603)
			(xy 93.416558 -118.209468) (xy 93.41612 -118.183152) (xy 93.416606 -118.155901) (xy 93.424362 -118.101953)
			(xy 93.439717 -118.049658) (xy 93.462359 -118.000081) (xy 93.491825 -117.954231) (xy 93.527516 -117.91304)
			(xy 93.568707 -117.877349) (xy 93.614557 -117.847883) (xy 93.664134 -117.825241) (xy 93.716429 -117.809886)
			(xy 93.770377 -117.80213) (xy 93.824879 -117.80213) (xy 93.878827 -117.809886) (xy 93.931122 -117.825241)
			(xy 93.980699 -117.847883) (xy 94.026549 -117.877349) (xy 94.06774 -117.91304) (xy 94.103431 -117.954231)
			(xy 94.132897 -118.000081) (xy 94.155539 -118.049658) (xy 94.170894 -118.101953) (xy 94.17865 -118.155901)
			(xy 94.179136 -118.183152) (xy 94.178692 -118.209467) (xy 94.171451 -118.261596) (xy 94.157126 -118.312238)
			(xy 94.135989 -118.360437) (xy 94.10844 -118.40528) (xy 94.074999 -118.445919) (xy 94.055946 -118.464076)
			(xy 94.052211 -118.467886) (xy 97.482404 -118.467886) (xy 97.486475 -118.412264) (xy 97.498601 -118.357827)
			(xy 97.518524 -118.305736) (xy 97.54582 -118.257101) (xy 97.579906 -118.212958) (xy 97.620055 -118.174249)
			(xy 97.665413 -118.141798) (xy 97.715013 -118.116297) (xy 97.767797 -118.09829) (xy 97.82264 -118.08816)
			(xy 97.878374 -118.086123) (xy 97.933811 -118.092223) (xy 97.987768 -118.106329) (xy 98.039097 -118.128141)
			(xy 98.086703 -118.157195) (xy 98.129571 -118.19287) (xy 98.166788 -118.234407) (xy 98.197561 -118.28092)
			(xy 98.221233 -118.331417) (xy 98.237301 -118.384824) (xy 98.245421 -118.44) (xy 98.24593 -118.467886)
			(xy 99.65258 -118.467886) (xy 99.656651 -118.412264) (xy 99.668777 -118.357827) (xy 99.6887 -118.305736)
			(xy 99.715996 -118.257101) (xy 99.750082 -118.212958) (xy 99.790231 -118.174249) (xy 99.835589 -118.141798)
			(xy 99.885189 -118.116297) (xy 99.937973 -118.09829) (xy 99.992816 -118.08816) (xy 100.04855 -118.086123)
			(xy 100.103987 -118.092223) (xy 100.157944 -118.106329) (xy 100.209273 -118.128141) (xy 100.256879 -118.157195)
			(xy 100.299747 -118.19287) (xy 100.336964 -118.234407) (xy 100.367737 -118.28092) (xy 100.391409 -118.331417)
			(xy 100.407477 -118.384824) (xy 100.415597 -118.44) (xy 100.416106 -118.467886) (xy 100.415597 -118.495772)
			(xy 100.407477 -118.550948) (xy 100.391409 -118.604355) (xy 100.367737 -118.654852) (xy 100.336964 -118.701365)
			(xy 100.299747 -118.742902) (xy 100.278913 -118.76024) (xy 102.564436 -118.76024) (xy 102.568507 -118.704618)
			(xy 102.580633 -118.650181) (xy 102.600556 -118.59809) (xy 102.627852 -118.549455) (xy 102.661938 -118.505312)
			(xy 102.702087 -118.466603) (xy 102.747445 -118.434152) (xy 102.797045 -118.408651) (xy 102.849829 -118.390644)
			(xy 102.904672 -118.380514) (xy 102.960406 -118.378477) (xy 103.015843 -118.384577) (xy 103.0698 -118.398683)
			(xy 103.121129 -118.420495) (xy 103.168735 -118.449549) (xy 103.211603 -118.485224) (xy 103.24882 -118.526761)
			(xy 103.279593 -118.573274) (xy 103.303265 -118.623771) (xy 103.319333 -118.677178) (xy 103.327453 -118.732354)
			(xy 103.327962 -118.76024) (xy 103.327453 -118.788126) (xy 103.319333 -118.843302) (xy 103.303265 -118.896709)
			(xy 103.279593 -118.947206) (xy 103.24882 -118.993719) (xy 103.219737 -119.026178) (xy 105.981498 -119.026178)
			(xy 105.985569 -118.970556) (xy 105.997695 -118.916119) (xy 106.017618 -118.864028) (xy 106.044914 -118.815393)
			(xy 106.079 -118.77125) (xy 106.119149 -118.732541) (xy 106.164507 -118.70009) (xy 106.214107 -118.674589)
			(xy 106.266891 -118.656582) (xy 106.321734 -118.646452) (xy 106.377468 -118.644415) (xy 106.432905 -118.650515)
			(xy 106.486862 -118.664621) (xy 106.538191 -118.686433) (xy 106.585797 -118.715487) (xy 106.628665 -118.751162)
			(xy 106.665882 -118.792699) (xy 106.696655 -118.839212) (xy 106.720327 -118.889709) (xy 106.736395 -118.943116)
			(xy 106.744515 -118.998292) (xy 106.745024 -119.026178) (xy 106.744515 -119.054064) (xy 106.741068 -119.077486)
			(xy 114.208558 -119.077486) (xy 114.212629 -119.021864) (xy 114.224755 -118.967427) (xy 114.244678 -118.915336)
			(xy 114.271974 -118.866701) (xy 114.30606 -118.822558) (xy 114.346209 -118.783849) (xy 114.391567 -118.751398)
			(xy 114.441167 -118.725897) (xy 114.493951 -118.70789) (xy 114.548794 -118.69776) (xy 114.604528 -118.695723)
			(xy 114.659965 -118.701823) (xy 114.713922 -118.715929) (xy 114.765251 -118.737741) (xy 114.812857 -118.766795)
			(xy 114.855725 -118.80247) (xy 114.892942 -118.844007) (xy 114.923715 -118.89052) (xy 114.947387 -118.941017)
			(xy 114.963455 -118.994424) (xy 114.971193 -119.047006) (xy 116.309138 -119.047006) (xy 116.313209 -118.991384)
			(xy 116.325335 -118.936947) (xy 116.345258 -118.884856) (xy 116.372554 -118.836221) (xy 116.40664 -118.792078)
			(xy 116.446789 -118.753369) (xy 116.492147 -118.720918) (xy 116.541747 -118.695417) (xy 116.594531 -118.67741)
			(xy 116.649374 -118.66728) (xy 116.705108 -118.665243) (xy 116.760545 -118.671343) (xy 116.814502 -118.685449)
			(xy 116.865831 -118.707261) (xy 116.913437 -118.736315) (xy 116.956305 -118.77199) (xy 116.993522 -118.813527)
			(xy 117.024295 -118.86004) (xy 117.047967 -118.910537) (xy 117.064035 -118.963944) (xy 117.072155 -119.01912)
			(xy 117.072664 -119.047006) (xy 117.072155 -119.074892) (xy 117.064035 -119.130068) (xy 117.047967 -119.183475)
			(xy 117.024295 -119.233972) (xy 116.993522 -119.280485) (xy 116.956305 -119.322022) (xy 116.913437 -119.357697)
			(xy 116.865831 -119.386751) (xy 116.814502 -119.408563) (xy 116.760545 -119.422669) (xy 116.705108 -119.428769)
			(xy 116.649374 -119.426732) (xy 116.594531 -119.416602) (xy 116.541747 -119.398595) (xy 116.492147 -119.373094)
			(xy 116.446789 -119.340643) (xy 116.40664 -119.301934) (xy 116.372554 -119.257791) (xy 116.345258 -119.209156)
			(xy 116.325335 -119.157065) (xy 116.313209 -119.102628) (xy 116.309138 -119.047006) (xy 114.971193 -119.047006)
			(xy 114.971575 -119.0496) (xy 114.972084 -119.077486) (xy 114.971575 -119.105372) (xy 114.963455 -119.160548)
			(xy 114.947387 -119.213955) (xy 114.923715 -119.264452) (xy 114.892942 -119.310965) (xy 114.855725 -119.352502)
			(xy 114.812857 -119.388177) (xy 114.765251 -119.417231) (xy 114.713922 -119.439043) (xy 114.659965 -119.453149)
			(xy 114.604528 -119.459249) (xy 114.548794 -119.457212) (xy 114.493951 -119.447082) (xy 114.441167 -119.429075)
			(xy 114.391567 -119.403574) (xy 114.346209 -119.371123) (xy 114.30606 -119.332414) (xy 114.271974 -119.288271)
			(xy 114.244678 -119.239636) (xy 114.224755 -119.187545) (xy 114.212629 -119.133108) (xy 114.208558 -119.077486)
			(xy 106.741068 -119.077486) (xy 106.736395 -119.10924) (xy 106.720327 -119.162647) (xy 106.696655 -119.213144)
			(xy 106.665882 -119.259657) (xy 106.628665 -119.301194) (xy 106.585797 -119.336869) (xy 106.538191 -119.365923)
			(xy 106.486862 -119.387735) (xy 106.432905 -119.401841) (xy 106.377468 -119.407941) (xy 106.321734 -119.405904)
			(xy 106.266891 -119.395774) (xy 106.214107 -119.377767) (xy 106.164507 -119.352266) (xy 106.119149 -119.319815)
			(xy 106.079 -119.281106) (xy 106.044914 -119.236963) (xy 106.017618 -119.188328) (xy 105.997695 -119.136237)
			(xy 105.985569 -119.0818) (xy 105.981498 -119.026178) (xy 103.219737 -119.026178) (xy 103.211603 -119.035256)
			(xy 103.168735 -119.070931) (xy 103.121129 -119.099985) (xy 103.0698 -119.121797) (xy 103.015843 -119.135903)
			(xy 102.960406 -119.142003) (xy 102.904672 -119.139966) (xy 102.849829 -119.129836) (xy 102.797045 -119.111829)
			(xy 102.747445 -119.086328) (xy 102.702087 -119.053877) (xy 102.661938 -119.015168) (xy 102.627852 -118.971025)
			(xy 102.600556 -118.92239) (xy 102.580633 -118.870299) (xy 102.568507 -118.815862) (xy 102.564436 -118.76024)
			(xy 100.278913 -118.76024) (xy 100.256879 -118.778577) (xy 100.209273 -118.807631) (xy 100.157944 -118.829443)
			(xy 100.103987 -118.843549) (xy 100.04855 -118.849649) (xy 99.992816 -118.847612) (xy 99.937973 -118.837482)
			(xy 99.885189 -118.819475) (xy 99.835589 -118.793974) (xy 99.790231 -118.761523) (xy 99.750082 -118.722814)
			(xy 99.715996 -118.678671) (xy 99.6887 -118.630036) (xy 99.668777 -118.577945) (xy 99.656651 -118.523508)
			(xy 99.65258 -118.467886) (xy 98.24593 -118.467886) (xy 98.245421 -118.495772) (xy 98.237301 -118.550948)
			(xy 98.221233 -118.604355) (xy 98.197561 -118.654852) (xy 98.166788 -118.701365) (xy 98.129571 -118.742902)
			(xy 98.086703 -118.778577) (xy 98.039097 -118.807631) (xy 97.987768 -118.829443) (xy 97.933811 -118.843549)
			(xy 97.878374 -118.849649) (xy 97.82264 -118.847612) (xy 97.767797 -118.837482) (xy 97.715013 -118.819475)
			(xy 97.665413 -118.793974) (xy 97.620055 -118.761523) (xy 97.579906 -118.722814) (xy 97.54582 -118.678671)
			(xy 97.518524 -118.630036) (xy 97.498601 -118.577945) (xy 97.486475 -118.523508) (xy 97.482404 -118.467886)
			(xy 94.052211 -118.467886) (xy 94.04856 -118.471611) (xy 94.040025 -118.490881) (xy 94.039436 -118.501414)
			(xy 94.039436 -118.57609) (xy 94.039946 -118.586642) (xy 94.048494 -118.605938) (xy 94.055946 -118.613428)
			(xy 94.075017 -118.631568) (xy 94.108471 -118.672202) (xy 94.136027 -118.717046) (xy 94.157162 -118.76525)
			(xy 94.171477 -118.815899) (xy 94.178699 -118.868035) (xy 94.179136 -118.894352) (xy 94.17865 -118.921603)
			(xy 94.170894 -118.975551) (xy 94.155539 -119.027846) (xy 94.132897 -119.077423) (xy 94.103431 -119.123273)
			(xy 94.06774 -119.164464) (xy 94.026549 -119.200155) (xy 93.980699 -119.229621) (xy 93.931122 -119.252263)
			(xy 93.878827 -119.267618) (xy 93.824879 -119.275374) (xy 93.770377 -119.275374) (xy 93.716429 -119.267618)
			(xy 93.664134 -119.252263) (xy 93.614557 -119.229621) (xy 93.568707 -119.200155) (xy 93.527516 -119.164464)
			(xy 93.491825 -119.123273) (xy 93.462359 -119.077423) (xy 93.439717 -119.027846) (xy 93.424362 -118.975551)
			(xy 93.416606 -118.921603) (xy 93.41612 -118.894352) (xy 91.5035 -118.894352) (xy 91.5035 -119.407554)
			(xy 94.499632 -119.407554) (xy 94.499632 -119.353046) (xy 94.507389 -119.299093) (xy 94.522745 -119.246794)
			(xy 94.545388 -119.197211) (xy 94.574856 -119.151356) (xy 94.61055 -119.110162) (xy 94.651743 -119.074466)
			(xy 94.697597 -119.044995) (xy 94.747179 -119.022351) (xy 94.799478 -119.006992) (xy 94.85343 -118.999233)
			(xy 94.880684 -118.998746) (xy 94.908054 -118.99921) (xy 94.962234 -119.007027) (xy 95.014738 -119.022516)
			(xy 95.064484 -119.045358) (xy 95.110451 -119.075084) (xy 95.131382 -119.092726) (xy 95.131636 -119.09298)
			(xy 95.13873 -119.098555) (xy 95.155641 -119.104807) (xy 95.164656 -119.105172) (xy 95.231712 -119.105172)
			(xy 95.24073 -119.104827) (xy 95.257647 -119.098572) (xy 95.264732 -119.09298) (xy 95.264732 -119.092726)
			(xy 95.264986 -119.092726) (xy 95.285916 -119.075084) (xy 95.331889 -119.045372) (xy 95.381637 -119.022536)
			(xy 95.434138 -119.007046) (xy 95.488315 -118.999219) (xy 95.515684 -118.998746) (xy 95.542934 -118.9993)
			(xy 95.59688 -119.007054) (xy 95.649174 -119.022407) (xy 95.69875 -119.045046) (xy 95.7446 -119.07451)
			(xy 95.785789 -119.110199) (xy 95.82148 -119.151387) (xy 95.850946 -119.197236) (xy 95.873587 -119.246811)
			(xy 95.888942 -119.299104) (xy 95.896699 -119.35305) (xy 95.896699 -119.40755) (xy 95.888942 -119.461496)
			(xy 95.884381 -119.477028) (xy 99.60813 -119.477028) (xy 99.612201 -119.421406) (xy 99.624327 -119.366969)
			(xy 99.64425 -119.314878) (xy 99.671546 -119.266243) (xy 99.705632 -119.2221) (xy 99.745781 -119.183391)
			(xy 99.791139 -119.15094) (xy 99.840739 -119.125439) (xy 99.893523 -119.107432) (xy 99.948366 -119.097302)
			(xy 100.0041 -119.095265) (xy 100.059537 -119.101365) (xy 100.113494 -119.115471) (xy 100.164823 -119.137283)
			(xy 100.212429 -119.166337) (xy 100.255297 -119.202012) (xy 100.292514 -119.243549) (xy 100.323287 -119.290062)
			(xy 100.346959 -119.340559) (xy 100.363027 -119.393966) (xy 100.371147 -119.449142) (xy 100.371656 -119.477028)
			(xy 100.371147 -119.504914) (xy 100.363027 -119.56009) (xy 100.346959 -119.613497) (xy 100.323287 -119.663994)
			(xy 100.292514 -119.710507) (xy 100.255297 -119.752044) (xy 100.226222 -119.77624) (xy 100.535992 -119.77624)
			(xy 100.540063 -119.720618) (xy 100.552189 -119.666181) (xy 100.572112 -119.61409) (xy 100.599408 -119.565455)
			(xy 100.633494 -119.521312) (xy 100.673643 -119.482603) (xy 100.719001 -119.450152) (xy 100.768601 -119.424651)
			(xy 100.821385 -119.406644) (xy 100.876228 -119.396514) (xy 100.931962 -119.394477) (xy 100.987399 -119.400577)
			(xy 101.041356 -119.414683) (xy 101.092685 -119.436495) (xy 101.140291 -119.465549) (xy 101.183159 -119.501224)
			(xy 101.220376 -119.542761) (xy 101.251149 -119.589274) (xy 101.274821 -119.639771) (xy 101.290889 -119.693178)
			(xy 101.294665 -119.718836) (xy 107.536486 -119.718836) (xy 107.540557 -119.663214) (xy 107.552683 -119.608777)
			(xy 107.572606 -119.556686) (xy 107.599902 -119.508051) (xy 107.633988 -119.463908) (xy 107.674137 -119.425199)
			(xy 107.719495 -119.392748) (xy 107.769095 -119.367247) (xy 107.821879 -119.34924) (xy 107.876722 -119.33911)
			(xy 107.932456 -119.337073) (xy 107.987893 -119.343173) (xy 108.04185 -119.357279) (xy 108.093179 -119.379091)
			(xy 108.140785 -119.408145) (xy 108.183653 -119.44382) (xy 108.22087 -119.485357) (xy 108.236701 -119.509286)
			(xy 119.927624 -119.509286) (xy 119.928163 -119.48073) (xy 119.936652 -119.424253) (xy 119.953469 -119.369674)
			(xy 119.978237 -119.318213) (xy 120.010403 -119.271021) (xy 120.049247 -119.229153) (xy 120.0939 -119.193547)
			(xy 120.118378 -119.178832) (xy 120.131218 -119.170668) (xy 120.151898 -119.14838) (xy 120.165093 -119.120988)
			(xy 120.16963 -119.090924) (xy 120.165107 -119.060858) (xy 120.151926 -119.03346) (xy 120.131256 -119.011162)
			(xy 120.118378 -119.003064) (xy 120.093908 -118.98834) (xy 120.049268 -118.952722) (xy 120.010433 -118.910851)
			(xy 119.97827 -118.863662) (xy 119.953498 -118.812206) (xy 119.936668 -118.757634) (xy 119.928158 -118.701164)
			(xy 119.927624 -118.67261) (xy 119.92811 -118.645359) (xy 119.935866 -118.591411) (xy 119.951221 -118.539116)
			(xy 119.973863 -118.489539) (xy 120.003329 -118.443689) (xy 120.03902 -118.402498) (xy 120.080211 -118.366807)
			(xy 120.126061 -118.337341) (xy 120.175638 -118.314699) (xy 120.227933 -118.299344) (xy 120.281881 -118.291588)
			(xy 120.336383 -118.291588) (xy 120.390331 -118.299344) (xy 120.442626 -118.314699) (xy 120.492203 -118.337341)
			(xy 120.538053 -118.366807) (xy 120.579244 -118.402498) (xy 120.614935 -118.443689) (xy 120.644401 -118.489539)
			(xy 120.667043 -118.539116) (xy 120.682398 -118.591411) (xy 120.690154 -118.645359) (xy 120.69064 -118.67261)
			(xy 120.690195 -118.70117) (xy 120.681691 -118.757652) (xy 120.664859 -118.812234) (xy 120.640075 -118.863696)
			(xy 120.607895 -118.910887) (xy 120.569037 -118.952751) (xy 120.52437 -118.988353) (xy 120.499886 -119.003064)
			(xy 120.48696 -119.0111) (xy 120.46628 -119.033418) (xy 120.453093 -119.060837) (xy 120.451544 -119.071136)
			(xy 122.095004 -119.071136) (xy 122.099075 -119.015514) (xy 122.111201 -118.961077) (xy 122.131124 -118.908986)
			(xy 122.15842 -118.860351) (xy 122.192506 -118.816208) (xy 122.232655 -118.777499) (xy 122.278013 -118.745048)
			(xy 122.327613 -118.719547) (xy 122.380397 -118.70154) (xy 122.43524 -118.69141) (xy 122.490974 -118.689373)
			(xy 122.546411 -118.695473) (xy 122.600368 -118.709579) (xy 122.651697 -118.731391) (xy 122.699303 -118.760445)
			(xy 122.742171 -118.79612) (xy 122.779388 -118.837657) (xy 122.810161 -118.88417) (xy 122.833833 -118.934667)
			(xy 122.849901 -118.988074) (xy 122.858021 -119.04325) (xy 122.85853 -119.071136) (xy 122.858021 -119.099022)
			(xy 122.849901 -119.154198) (xy 122.833833 -119.207605) (xy 122.810161 -119.258102) (xy 122.779388 -119.304615)
			(xy 122.742171 -119.346152) (xy 122.699303 -119.381827) (xy 122.651697 -119.410881) (xy 122.600368 -119.432693)
			(xy 122.546411 -119.446799) (xy 122.490974 -119.452899) (xy 122.43524 -119.450862) (xy 122.380397 -119.440732)
			(xy 122.327613 -119.422725) (xy 122.278013 -119.397224) (xy 122.232655 -119.364773) (xy 122.192506 -119.326064)
			(xy 122.15842 -119.281921) (xy 122.131124 -119.233286) (xy 122.111201 -119.181195) (xy 122.099075 -119.126758)
			(xy 122.095004 -119.071136) (xy 120.451544 -119.071136) (xy 120.448568 -119.090924) (xy 120.453107 -119.121009)
			(xy 120.466308 -119.148422) (xy 120.486997 -119.17073) (xy 120.499886 -119.178832) (xy 120.524369 -119.193535)
			(xy 120.569006 -119.229159) (xy 120.607838 -119.271034) (xy 120.639998 -119.318228) (xy 120.664768 -119.369686)
			(xy 120.681596 -119.42426) (xy 120.690106 -119.480731) (xy 120.69064 -119.509286) (xy 120.690154 -119.536537)
			(xy 120.682398 -119.590485) (xy 120.667043 -119.64278) (xy 120.644401 -119.692357) (xy 120.614935 -119.738207)
			(xy 120.579244 -119.779398) (xy 120.538053 -119.815089) (xy 120.492203 -119.844555) (xy 120.442626 -119.867197)
			(xy 120.390331 -119.882552) (xy 120.336383 -119.890308) (xy 120.281881 -119.890308) (xy 120.227933 -119.882552)
			(xy 120.175638 -119.867197) (xy 120.126061 -119.844555) (xy 120.080211 -119.815089) (xy 120.03902 -119.779398)
			(xy 120.003329 -119.738207) (xy 119.973863 -119.692357) (xy 119.951221 -119.64278) (xy 119.935866 -119.590485)
			(xy 119.92811 -119.536537) (xy 119.927624 -119.509286) (xy 108.236701 -119.509286) (xy 108.251643 -119.53187)
			(xy 108.275315 -119.582367) (xy 108.291383 -119.635774) (xy 108.299503 -119.69095) (xy 108.300012 -119.718836)
			(xy 108.299503 -119.746722) (xy 108.291383 -119.801898) (xy 108.275315 -119.855305) (xy 108.251643 -119.905802)
			(xy 108.22087 -119.952315) (xy 108.183653 -119.993852) (xy 108.140785 -120.029527) (xy 108.093179 -120.058581)
			(xy 108.04185 -120.080393) (xy 107.991768 -120.093486) (xy 114.208558 -120.093486) (xy 114.212629 -120.037864)
			(xy 114.224755 -119.983427) (xy 114.244678 -119.931336) (xy 114.271974 -119.882701) (xy 114.30606 -119.838558)
			(xy 114.346209 -119.799849) (xy 114.391567 -119.767398) (xy 114.441167 -119.741897) (xy 114.493951 -119.72389)
			(xy 114.548794 -119.71376) (xy 114.604528 -119.711723) (xy 114.659965 -119.717823) (xy 114.713922 -119.731929)
			(xy 114.765251 -119.753741) (xy 114.812857 -119.782795) (xy 114.855725 -119.81847) (xy 114.892942 -119.860007)
			(xy 114.923715 -119.90652) (xy 114.947387 -119.957017) (xy 114.963455 -120.010424) (xy 114.971575 -120.0656)
			(xy 114.972084 -120.093486) (xy 114.971575 -120.121372) (xy 114.963455 -120.176548) (xy 114.947387 -120.229955)
			(xy 114.923715 -120.280452) (xy 114.892942 -120.326965) (xy 114.875466 -120.34647) (xy 116.321076 -120.34647)
			(xy 116.325147 -120.290848) (xy 116.337273 -120.236411) (xy 116.357196 -120.18432) (xy 116.384492 -120.135685)
			(xy 116.418578 -120.091542) (xy 116.458727 -120.052833) (xy 116.504085 -120.020382) (xy 116.553685 -119.994881)
			(xy 116.606469 -119.976874) (xy 116.661312 -119.966744) (xy 116.717046 -119.964707) (xy 116.772483 -119.970807)
			(xy 116.82644 -119.984913) (xy 116.877769 -120.006725) (xy 116.925375 -120.035779) (xy 116.968243 -120.071454)
			(xy 116.982294 -120.087136) (xy 122.095004 -120.087136) (xy 122.099075 -120.031514) (xy 122.111201 -119.977077)
			(xy 122.131124 -119.924986) (xy 122.15842 -119.876351) (xy 122.192506 -119.832208) (xy 122.232655 -119.793499)
			(xy 122.278013 -119.761048) (xy 122.327613 -119.735547) (xy 122.380397 -119.71754) (xy 122.43524 -119.70741)
			(xy 122.490974 -119.705373) (xy 122.546411 -119.711473) (xy 122.600368 -119.725579) (xy 122.651697 -119.747391)
			(xy 122.699303 -119.776445) (xy 122.742171 -119.81212) (xy 122.779388 -119.853657) (xy 122.810161 -119.90017)
			(xy 122.833833 -119.950667) (xy 122.849901 -120.004074) (xy 122.858021 -120.05925) (xy 122.85853 -120.087136)
			(xy 122.858021 -120.115022) (xy 122.849901 -120.170198) (xy 122.833833 -120.223605) (xy 122.810161 -120.274102)
			(xy 122.779388 -120.320615) (xy 122.742171 -120.362152) (xy 122.699303 -120.397827) (xy 122.651697 -120.426881)
			(xy 122.600368 -120.448693) (xy 122.546411 -120.462799) (xy 122.490974 -120.468899) (xy 122.43524 -120.466862)
			(xy 122.380397 -120.456732) (xy 122.327613 -120.438725) (xy 122.278013 -120.413224) (xy 122.232655 -120.380773)
			(xy 122.192506 -120.342064) (xy 122.15842 -120.297921) (xy 122.131124 -120.249286) (xy 122.111201 -120.197195)
			(xy 122.099075 -120.142758) (xy 122.095004 -120.087136) (xy 116.982294 -120.087136) (xy 117.00546 -120.112991)
			(xy 117.036233 -120.159504) (xy 117.059905 -120.210001) (xy 117.075973 -120.263408) (xy 117.084093 -120.318584)
			(xy 117.084602 -120.34647) (xy 117.084093 -120.374356) (xy 117.075973 -120.429532) (xy 117.059905 -120.482939)
			(xy 117.036233 -120.533436) (xy 117.00546 -120.579949) (xy 116.968243 -120.621486) (xy 116.925375 -120.657161)
			(xy 116.877769 -120.686215) (xy 116.82644 -120.708027) (xy 116.772483 -120.722133) (xy 116.717046 -120.728233)
			(xy 116.661312 -120.726196) (xy 116.606469 -120.716066) (xy 116.553685 -120.698059) (xy 116.504085 -120.672558)
			(xy 116.458727 -120.640107) (xy 116.418578 -120.601398) (xy 116.384492 -120.557255) (xy 116.357196 -120.50862)
			(xy 116.337273 -120.456529) (xy 116.325147 -120.402092) (xy 116.321076 -120.34647) (xy 114.875466 -120.34647)
			(xy 114.855725 -120.368502) (xy 114.812857 -120.404177) (xy 114.765251 -120.433231) (xy 114.713922 -120.455043)
			(xy 114.659965 -120.469149) (xy 114.604528 -120.475249) (xy 114.548794 -120.473212) (xy 114.493951 -120.463082)
			(xy 114.441167 -120.445075) (xy 114.391567 -120.419574) (xy 114.346209 -120.387123) (xy 114.30606 -120.348414)
			(xy 114.271974 -120.304271) (xy 114.244678 -120.255636) (xy 114.224755 -120.203545) (xy 114.212629 -120.149108)
			(xy 114.208558 -120.093486) (xy 107.991768 -120.093486) (xy 107.987893 -120.094499) (xy 107.932456 -120.100599)
			(xy 107.876722 -120.098562) (xy 107.821879 -120.088432) (xy 107.769095 -120.070425) (xy 107.719495 -120.044924)
			(xy 107.674137 -120.012473) (xy 107.633988 -119.973764) (xy 107.599902 -119.929621) (xy 107.572606 -119.880986)
			(xy 107.552683 -119.828895) (xy 107.540557 -119.774458) (xy 107.536486 -119.718836) (xy 101.294665 -119.718836)
			(xy 101.299009 -119.748354) (xy 101.299518 -119.77624) (xy 101.299009 -119.804126) (xy 101.290889 -119.859302)
			(xy 101.274821 -119.912709) (xy 101.251149 -119.963206) (xy 101.220376 -120.009719) (xy 101.183159 -120.051256)
			(xy 101.140291 -120.086931) (xy 101.092685 -120.115985) (xy 101.041356 -120.137797) (xy 100.987399 -120.151903)
			(xy 100.931962 -120.158003) (xy 100.876228 -120.155966) (xy 100.821385 -120.145836) (xy 100.768601 -120.127829)
			(xy 100.719001 -120.102328) (xy 100.673643 -120.069877) (xy 100.633494 -120.031168) (xy 100.599408 -119.987025)
			(xy 100.572112 -119.93839) (xy 100.552189 -119.886299) (xy 100.540063 -119.831862) (xy 100.535992 -119.77624)
			(xy 100.226222 -119.77624) (xy 100.212429 -119.787719) (xy 100.164823 -119.816773) (xy 100.113494 -119.838585)
			(xy 100.059537 -119.852691) (xy 100.0041 -119.858791) (xy 99.948366 -119.856754) (xy 99.893523 -119.846624)
			(xy 99.840739 -119.828617) (xy 99.791139 -119.803116) (xy 99.745781 -119.770665) (xy 99.705632 -119.731956)
			(xy 99.671546 -119.687813) (xy 99.64425 -119.639178) (xy 99.624327 -119.587087) (xy 99.612201 -119.53265)
			(xy 99.60813 -119.477028) (xy 95.884381 -119.477028) (xy 95.873587 -119.513789) (xy 95.850946 -119.563364)
			(xy 95.82148 -119.609213) (xy 95.785789 -119.650401) (xy 95.7446 -119.68609) (xy 95.69875 -119.715554)
			(xy 95.649174 -119.738193) (xy 95.59688 -119.753546) (xy 95.542934 -119.7613) (xy 95.515684 -119.761762)
			(xy 95.488313 -119.761315) (xy 95.434133 -119.753494) (xy 95.381629 -119.738001) (xy 95.331882 -119.715155)
			(xy 95.285917 -119.685426) (xy 95.264986 -119.667782) (xy 95.264732 -119.667528) (xy 95.257647 -119.66194)
			(xy 95.240729 -119.655696) (xy 95.231712 -119.655336) (xy 95.164656 -119.655336) (xy 95.155641 -119.655712)
			(xy 95.138723 -119.661946) (xy 95.131636 -119.667528) (xy 95.131636 -119.667782) (xy 95.131382 -119.667782)
			(xy 95.110428 -119.685393) (xy 95.064461 -119.71511) (xy 95.014719 -119.737952) (xy 94.962224 -119.753449)
			(xy 94.908052 -119.761284) (xy 94.880684 -119.761762) (xy 94.85343 -119.761367) (xy 94.799478 -119.753608)
			(xy 94.747179 -119.738249) (xy 94.697597 -119.715605) (xy 94.651743 -119.686134) (xy 94.61055 -119.650438)
			(xy 94.574856 -119.609244) (xy 94.545388 -119.563389) (xy 94.522745 -119.513806) (xy 94.507389 -119.461507)
			(xy 94.499632 -119.407554) (xy 91.5035 -119.407554) (xy 91.5035 -119.936006) (xy 92.694504 -119.936006)
			(xy 92.698575 -119.880384) (xy 92.710701 -119.825947) (xy 92.730624 -119.773856) (xy 92.75792 -119.725221)
			(xy 92.792006 -119.681078) (xy 92.832155 -119.642369) (xy 92.877513 -119.609918) (xy 92.927113 -119.584417)
			(xy 92.979897 -119.56641) (xy 93.03474 -119.55628) (xy 93.090474 -119.554243) (xy 93.145911 -119.560343)
			(xy 93.199868 -119.574449) (xy 93.251197 -119.596261) (xy 93.298803 -119.625315) (xy 93.341671 -119.66099)
			(xy 93.378888 -119.702527) (xy 93.409661 -119.74904) (xy 93.433333 -119.799537) (xy 93.449401 -119.852944)
			(xy 93.455308 -119.89308) (xy 97.569018 -119.89308) (xy 97.573089 -119.837458) (xy 97.585215 -119.783021)
			(xy 97.605138 -119.73093) (xy 97.632434 -119.682295) (xy 97.66652 -119.638152) (xy 97.706669 -119.599443)
			(xy 97.752027 -119.566992) (xy 97.801627 -119.541491) (xy 97.854411 -119.523484) (xy 97.909254 -119.513354)
			(xy 97.964988 -119.511317) (xy 98.020425 -119.517417) (xy 98.074382 -119.531523) (xy 98.125711 -119.553335)
			(xy 98.173317 -119.582389) (xy 98.216185 -119.618064) (xy 98.253402 -119.659601) (xy 98.284175 -119.706114)
			(xy 98.307847 -119.756611) (xy 98.323915 -119.810018) (xy 98.332035 -119.865194) (xy 98.332544 -119.89308)
			(xy 98.332035 -119.920966) (xy 98.323915 -119.976142) (xy 98.307847 -120.029549) (xy 98.284175 -120.080046)
			(xy 98.253402 -120.126559) (xy 98.216185 -120.168096) (xy 98.173317 -120.203771) (xy 98.125711 -120.232825)
			(xy 98.074382 -120.254637) (xy 98.020425 -120.268743) (xy 97.964988 -120.274843) (xy 97.909254 -120.272806)
			(xy 97.854411 -120.262676) (xy 97.801627 -120.244669) (xy 97.752027 -120.219168) (xy 97.706669 -120.186717)
			(xy 97.66652 -120.148008) (xy 97.632434 -120.103865) (xy 97.605138 -120.05523) (xy 97.585215 -120.003139)
			(xy 97.573089 -119.948702) (xy 97.569018 -119.89308) (xy 93.455308 -119.89308) (xy 93.457521 -119.90812)
			(xy 93.45803 -119.936006) (xy 93.457521 -119.963892) (xy 93.449401 -120.019068) (xy 93.433333 -120.072475)
			(xy 93.409661 -120.122972) (xy 93.378888 -120.169485) (xy 93.341671 -120.211022) (xy 93.298803 -120.246697)
			(xy 93.251197 -120.275751) (xy 93.199868 -120.297563) (xy 93.145911 -120.311669) (xy 93.090474 -120.317769)
			(xy 93.03474 -120.315732) (xy 92.979897 -120.305602) (xy 92.927113 -120.287595) (xy 92.877513 -120.262094)
			(xy 92.832155 -120.229643) (xy 92.792006 -120.190934) (xy 92.75792 -120.146791) (xy 92.730624 -120.098156)
			(xy 92.710701 -120.046065) (xy 92.698575 -119.991628) (xy 92.694504 -119.936006) (xy 91.5035 -119.936006)
			(xy 91.5035 -120.493028) (xy 99.604066 -120.493028) (xy 99.608137 -120.437406) (xy 99.620263 -120.382969)
			(xy 99.640186 -120.330878) (xy 99.667482 -120.282243) (xy 99.701568 -120.2381) (xy 99.741717 -120.199391)
			(xy 99.787075 -120.16694) (xy 99.836675 -120.141439) (xy 99.889459 -120.123432) (xy 99.944302 -120.113302)
			(xy 100.000036 -120.111265) (xy 100.055473 -120.117365) (xy 100.10943 -120.131471) (xy 100.160759 -120.153283)
			(xy 100.208365 -120.182337) (xy 100.251233 -120.218012) (xy 100.28845 -120.259549) (xy 100.319223 -120.306062)
			(xy 100.342895 -120.356559) (xy 100.358963 -120.409966) (xy 100.367083 -120.465142) (xy 100.367592 -120.493028)
			(xy 100.367083 -120.520914) (xy 100.358963 -120.57609) (xy 100.342895 -120.629497) (xy 100.319223 -120.679994)
			(xy 100.28845 -120.726507) (xy 100.251233 -120.768044) (xy 100.222158 -120.79224) (xy 100.535992 -120.79224)
			(xy 100.540063 -120.736618) (xy 100.552189 -120.682181) (xy 100.572112 -120.63009) (xy 100.599408 -120.581455)
			(xy 100.633494 -120.537312) (xy 100.673643 -120.498603) (xy 100.719001 -120.466152) (xy 100.768601 -120.440651)
			(xy 100.821385 -120.422644) (xy 100.876228 -120.412514) (xy 100.931962 -120.410477) (xy 100.987399 -120.416577)
			(xy 101.041356 -120.430683) (xy 101.092685 -120.452495) (xy 101.140291 -120.481549) (xy 101.183159 -120.517224)
			(xy 101.220376 -120.558761) (xy 101.251149 -120.605274) (xy 101.274821 -120.655771) (xy 101.290889 -120.709178)
			(xy 101.299009 -120.764354) (xy 101.299518 -120.79224) (xy 102.691436 -120.79224) (xy 102.695507 -120.736618)
			(xy 102.707633 -120.682181) (xy 102.727556 -120.63009) (xy 102.754852 -120.581455) (xy 102.788938 -120.537312)
			(xy 102.829087 -120.498603) (xy 102.874445 -120.466152) (xy 102.924045 -120.440651) (xy 102.976829 -120.422644)
			(xy 103.031672 -120.412514) (xy 103.087406 -120.410477) (xy 103.142843 -120.416577) (xy 103.1968 -120.430683)
			(xy 103.248129 -120.452495) (xy 103.295735 -120.481549) (xy 103.338603 -120.517224) (xy 103.346737 -120.526302)
			(xy 104.203498 -120.526302) (xy 104.207569 -120.47068) (xy 104.219695 -120.416243) (xy 104.239618 -120.364152)
			(xy 104.266914 -120.315517) (xy 104.301 -120.271374) (xy 104.341149 -120.232665) (xy 104.386507 -120.200214)
			(xy 104.436107 -120.174713) (xy 104.488891 -120.156706) (xy 104.543734 -120.146576) (xy 104.599468 -120.144539)
			(xy 104.654905 -120.150639) (xy 104.708862 -120.164745) (xy 104.760191 -120.186557) (xy 104.807797 -120.215611)
			(xy 104.850665 -120.251286) (xy 104.887882 -120.292823) (xy 104.918655 -120.339336) (xy 104.942327 -120.389833)
			(xy 104.958395 -120.44324) (xy 104.966515 -120.498416) (xy 104.967024 -120.526302) (xy 105.993436 -120.526302)
			(xy 105.997507 -120.47068) (xy 106.009633 -120.416243) (xy 106.029556 -120.364152) (xy 106.056852 -120.315517)
			(xy 106.090938 -120.271374) (xy 106.131087 -120.232665) (xy 106.176445 -120.200214) (xy 106.226045 -120.174713)
			(xy 106.278829 -120.156706) (xy 106.333672 -120.146576) (xy 106.389406 -120.144539) (xy 106.444843 -120.150639)
			(xy 106.4988 -120.164745) (xy 106.550129 -120.186557) (xy 106.597735 -120.215611) (xy 106.640603 -120.251286)
			(xy 106.67782 -120.292823) (xy 106.708593 -120.339336) (xy 106.732265 -120.389833) (xy 106.748333 -120.44324)
			(xy 106.756453 -120.498416) (xy 106.756962 -120.526302) (xy 106.756453 -120.554188) (xy 106.748333 -120.609364)
			(xy 106.732265 -120.662771) (xy 106.708593 -120.713268) (xy 106.67782 -120.759781) (xy 106.660344 -120.779286)
			(xy 119.927114 -120.779286) (xy 119.931185 -120.723664) (xy 119.943311 -120.669227) (xy 119.963234 -120.617136)
			(xy 119.99053 -120.568501) (xy 120.024616 -120.524358) (xy 120.064765 -120.485649) (xy 120.110123 -120.453198)
			(xy 120.159723 -120.427697) (xy 120.212507 -120.40969) (xy 120.26735 -120.39956) (xy 120.323084 -120.397523)
			(xy 120.378521 -120.403623) (xy 120.432478 -120.417729) (xy 120.483807 -120.439541) (xy 120.531413 -120.468595)
			(xy 120.574281 -120.50427) (xy 120.611498 -120.545807) (xy 120.642271 -120.59232) (xy 120.665943 -120.642817)
			(xy 120.682011 -120.696224) (xy 120.690131 -120.7514) (xy 120.69064 -120.779286) (xy 120.690131 -120.807172)
			(xy 120.682011 -120.862348) (xy 120.665943 -120.915755) (xy 120.642271 -120.966252) (xy 120.611498 -121.012765)
			(xy 120.574281 -121.054302) (xy 120.531413 -121.089977) (xy 120.509852 -121.103136) (xy 122.095004 -121.103136)
			(xy 122.099075 -121.047514) (xy 122.111201 -120.993077) (xy 122.131124 -120.940986) (xy 122.15842 -120.892351)
			(xy 122.192506 -120.848208) (xy 122.232655 -120.809499) (xy 122.278013 -120.777048) (xy 122.327613 -120.751547)
			(xy 122.380397 -120.73354) (xy 122.43524 -120.72341) (xy 122.490974 -120.721373) (xy 122.546411 -120.727473)
			(xy 122.600368 -120.741579) (xy 122.651697 -120.763391) (xy 122.699303 -120.792445) (xy 122.742171 -120.82812)
			(xy 122.779388 -120.869657) (xy 122.810161 -120.91617) (xy 122.833833 -120.966667) (xy 122.849901 -121.020074)
			(xy 122.858021 -121.07525) (xy 122.85853 -121.103136) (xy 122.858021 -121.131022) (xy 122.849901 -121.186198)
			(xy 122.833833 -121.239605) (xy 122.810161 -121.290102) (xy 122.779388 -121.336615) (xy 122.742171 -121.378152)
			(xy 122.699303 -121.413827) (xy 122.651697 -121.442881) (xy 122.600368 -121.464693) (xy 122.546411 -121.478799)
			(xy 122.490974 -121.484899) (xy 122.43524 -121.482862) (xy 122.380397 -121.472732) (xy 122.327613 -121.454725)
			(xy 122.278013 -121.429224) (xy 122.232655 -121.396773) (xy 122.192506 -121.358064) (xy 122.15842 -121.313921)
			(xy 122.131124 -121.265286) (xy 122.111201 -121.213195) (xy 122.099075 -121.158758) (xy 122.095004 -121.103136)
			(xy 120.509852 -121.103136) (xy 120.483807 -121.119031) (xy 120.432478 -121.140843) (xy 120.378521 -121.154949)
			(xy 120.323084 -121.161049) (xy 120.26735 -121.159012) (xy 120.212507 -121.148882) (xy 120.159723 -121.130875)
			(xy 120.110123 -121.105374) (xy 120.064765 -121.072923) (xy 120.024616 -121.034214) (xy 119.99053 -120.990071)
			(xy 119.963234 -120.941436) (xy 119.943311 -120.889345) (xy 119.931185 -120.834908) (xy 119.927114 -120.779286)
			(xy 106.660344 -120.779286) (xy 106.640603 -120.801318) (xy 106.597735 -120.836993) (xy 106.550129 -120.866047)
			(xy 106.4988 -120.887859) (xy 106.444843 -120.901965) (xy 106.389406 -120.908065) (xy 106.333672 -120.906028)
			(xy 106.278829 -120.895898) (xy 106.226045 -120.877891) (xy 106.176445 -120.85239) (xy 106.131087 -120.819939)
			(xy 106.090938 -120.78123) (xy 106.056852 -120.737087) (xy 106.029556 -120.688452) (xy 106.009633 -120.636361)
			(xy 105.997507 -120.581924) (xy 105.993436 -120.526302) (xy 104.967024 -120.526302) (xy 104.966515 -120.554188)
			(xy 104.958395 -120.609364) (xy 104.942327 -120.662771) (xy 104.918655 -120.713268) (xy 104.887882 -120.759781)
			(xy 104.850665 -120.801318) (xy 104.807797 -120.836993) (xy 104.760191 -120.866047) (xy 104.708862 -120.887859)
			(xy 104.654905 -120.901965) (xy 104.599468 -120.908065) (xy 104.543734 -120.906028) (xy 104.488891 -120.895898)
			(xy 104.436107 -120.877891) (xy 104.386507 -120.85239) (xy 104.341149 -120.819939) (xy 104.301 -120.78123)
			(xy 104.266914 -120.737087) (xy 104.239618 -120.688452) (xy 104.219695 -120.636361) (xy 104.207569 -120.581924)
			(xy 104.203498 -120.526302) (xy 103.346737 -120.526302) (xy 103.37582 -120.558761) (xy 103.406593 -120.605274)
			(xy 103.430265 -120.655771) (xy 103.446333 -120.709178) (xy 103.454453 -120.764354) (xy 103.454962 -120.79224)
			(xy 103.454453 -120.820126) (xy 103.446333 -120.875302) (xy 103.430265 -120.928709) (xy 103.406593 -120.979206)
			(xy 103.37582 -121.025719) (xy 103.338603 -121.067256) (xy 103.295735 -121.102931) (xy 103.248129 -121.131985)
			(xy 103.1968 -121.153797) (xy 103.142843 -121.167903) (xy 103.087406 -121.174003) (xy 103.031672 -121.171966)
			(xy 102.976829 -121.161836) (xy 102.924045 -121.143829) (xy 102.874445 -121.118328) (xy 102.829087 -121.085877)
			(xy 102.788938 -121.047168) (xy 102.754852 -121.003025) (xy 102.727556 -120.95439) (xy 102.707633 -120.902299)
			(xy 102.695507 -120.847862) (xy 102.691436 -120.79224) (xy 101.299518 -120.79224) (xy 101.299009 -120.820126)
			(xy 101.290889 -120.875302) (xy 101.274821 -120.928709) (xy 101.251149 -120.979206) (xy 101.220376 -121.025719)
			(xy 101.183159 -121.067256) (xy 101.140291 -121.102931) (xy 101.092685 -121.131985) (xy 101.041356 -121.153797)
			(xy 100.987399 -121.167903) (xy 100.931962 -121.174003) (xy 100.876228 -121.171966) (xy 100.821385 -121.161836)
			(xy 100.768601 -121.143829) (xy 100.719001 -121.118328) (xy 100.673643 -121.085877) (xy 100.633494 -121.047168)
			(xy 100.599408 -121.003025) (xy 100.572112 -120.95439) (xy 100.552189 -120.902299) (xy 100.540063 -120.847862)
			(xy 100.535992 -120.79224) (xy 100.222158 -120.79224) (xy 100.208365 -120.803719) (xy 100.160759 -120.832773)
			(xy 100.10943 -120.854585) (xy 100.055473 -120.868691) (xy 100.000036 -120.874791) (xy 99.944302 -120.872754)
			(xy 99.889459 -120.862624) (xy 99.836675 -120.844617) (xy 99.787075 -120.819116) (xy 99.741717 -120.786665)
			(xy 99.701568 -120.747956) (xy 99.667482 -120.703813) (xy 99.640186 -120.655178) (xy 99.620263 -120.603087)
			(xy 99.608137 -120.54865) (xy 99.604066 -120.493028) (xy 91.5035 -120.493028) (xy 91.5035 -120.746266)
			(xy 91.504444 -120.754523) (xy 91.510924 -120.769816) (xy 91.5162 -120.776238) (xy 91.522296 -120.783096)
			(xy 91.538298 -120.791478) (xy 91.548204 -120.792748) (xy 91.57558 -120.796618) (xy 91.628902 -120.811232)
			(xy 91.679556 -120.833387) (xy 91.726483 -120.86262) (xy 91.768701 -120.898319) (xy 91.805325 -120.939737)
			(xy 91.83559 -120.986005) (xy 91.858861 -121.036157) (xy 91.874651 -121.089142) (xy 91.88263 -121.143851)
			(xy 91.88263 -121.199139) (xy 91.874653 -121.253849) (xy 91.858864 -121.306834) (xy 91.835594 -121.356986)
			(xy 91.805331 -121.403256) (xy 91.768708 -121.444674) (xy 91.726491 -121.480374) (xy 91.679564 -121.509608)
			(xy 91.62891 -121.531765) (xy 91.575589 -121.54638) (xy 91.548204 -121.550176) (xy 91.547188 -121.55043)
			(xy 91.538258 -121.551972) (xy 91.522245 -121.560426) (xy 91.515946 -121.56694) (xy 91.510104 -121.573798)
			(xy 91.507093 -121.581672) (xy 91.994736 -121.581672) (xy 91.995177 -121.554301) (xy 92.002999 -121.50012)
			(xy 92.018494 -121.447617) (xy 92.041341 -121.39787) (xy 92.071072 -121.351905) (xy 92.088716 -121.330974)
			(xy 92.08897 -121.33072) (xy 92.094563 -121.323638) (xy 92.100804 -121.306717) (xy 92.101162 -121.2977)
			(xy 92.101162 -121.230644) (xy 92.100792 -121.221628) (xy 92.094554 -121.204711) (xy 92.08897 -121.197624)
			(xy 92.088716 -121.197624) (xy 92.088716 -121.19737) (xy 92.071099 -121.17642) (xy 92.041383 -121.130453)
			(xy 92.018543 -121.08071) (xy 92.003047 -121.028213) (xy 91.995213 -120.97404) (xy 91.994736 -120.946672)
			(xy 91.995129 -120.919416) (xy 92.002891 -120.865461) (xy 92.018253 -120.813159) (xy 92.040902 -120.763576)
			(xy 92.070377 -120.71772) (xy 92.106078 -120.676527) (xy 92.147278 -120.640834) (xy 92.193139 -120.611367)
			(xy 92.242726 -120.588728) (xy 92.295031 -120.573376) (xy 92.348988 -120.565624) (xy 92.376244 -120.565164)
			(xy 92.405365 -120.565735) (xy 92.462934 -120.574566) (xy 92.518491 -120.592047) (xy 92.570744 -120.617772)
			(xy 92.618478 -120.651142) (xy 92.660584 -120.691381) (xy 92.696083 -120.737554) (xy 92.724149 -120.788588)
			(xy 92.74413 -120.843295) (xy 92.750386 -120.871742) (xy 92.752672 -120.883426) (xy 92.76715 -120.902222)
			(xy 92.851224 -120.942608) (xy 92.862036 -120.947177) (xy 92.885477 -120.946915) (xy 92.896182 -120.9421)
			(xy 92.89669 -120.9421) (xy 92.923744 -120.928808) (xy 92.981022 -120.910034) (xy 93.040542 -120.900519)
			(xy 93.07068 -120.899936) (xy 93.097934 -120.900374) (xy 93.151888 -120.908129) (xy 93.20419 -120.923485)
			(xy 93.253772 -120.946129) (xy 93.299628 -120.975599) (xy 93.340822 -121.011295) (xy 93.376516 -121.052491)
			(xy 93.405983 -121.098349) (xy 93.428623 -121.147933) (xy 93.443976 -121.200235) (xy 93.449513 -121.238772)
			(xy 97.584258 -121.238772) (xy 97.588329 -121.18315) (xy 97.600455 -121.128713) (xy 97.620378 -121.076622)
			(xy 97.647674 -121.027987) (xy 97.68176 -120.983844) (xy 97.721909 -120.945135) (xy 97.767267 -120.912684)
			(xy 97.816867 -120.887183) (xy 97.869651 -120.869176) (xy 97.924494 -120.859046) (xy 97.980228 -120.857009)
			(xy 98.035665 -120.863109) (xy 98.089622 -120.877215) (xy 98.140951 -120.899027) (xy 98.188557 -120.928081)
			(xy 98.231425 -120.963756) (xy 98.268642 -121.005293) (xy 98.299415 -121.051806) (xy 98.323087 -121.102303)
			(xy 98.339155 -121.15571) (xy 98.347275 -121.210886) (xy 98.347784 -121.238772) (xy 98.347275 -121.266658)
			(xy 98.339155 -121.321834) (xy 98.323087 -121.375241) (xy 98.299415 -121.425738) (xy 98.268642 -121.472251)
			(xy 98.23569 -121.509028) (xy 99.629466 -121.509028) (xy 99.633537 -121.453406) (xy 99.645663 -121.398969)
			(xy 99.665586 -121.346878) (xy 99.692882 -121.298243) (xy 99.726968 -121.2541) (xy 99.767117 -121.215391)
			(xy 99.812475 -121.18294) (xy 99.862075 -121.157439) (xy 99.914859 -121.139432) (xy 99.969702 -121.129302)
			(xy 100.025436 -121.127265) (xy 100.080873 -121.133365) (xy 100.13483 -121.147471) (xy 100.186159 -121.169283)
			(xy 100.233765 -121.198337) (xy 100.276633 -121.234012) (xy 100.31385 -121.275549) (xy 100.344623 -121.322062)
			(xy 100.368295 -121.372559) (xy 100.384363 -121.425966) (xy 100.392483 -121.481142) (xy 100.392992 -121.509028)
			(xy 100.392483 -121.536914) (xy 100.384363 -121.59209) (xy 100.368295 -121.645497) (xy 100.344623 -121.695994)
			(xy 100.31385 -121.742507) (xy 100.276633 -121.784044) (xy 100.247558 -121.80824) (xy 100.535992 -121.80824)
			(xy 100.540063 -121.752618) (xy 100.552189 -121.698181) (xy 100.572112 -121.64609) (xy 100.599408 -121.597455)
			(xy 100.633494 -121.553312) (xy 100.673643 -121.514603) (xy 100.719001 -121.482152) (xy 100.768601 -121.456651)
			(xy 100.821385 -121.438644) (xy 100.876228 -121.428514) (xy 100.931962 -121.426477) (xy 100.987399 -121.432577)
			(xy 101.041356 -121.446683) (xy 101.092685 -121.468495) (xy 101.140291 -121.497549) (xy 101.183159 -121.533224)
			(xy 101.220376 -121.574761) (xy 101.251149 -121.621274) (xy 101.274821 -121.671771) (xy 101.290889 -121.725178)
			(xy 101.299009 -121.780354) (xy 101.299518 -121.80824) (xy 101.299009 -121.836126) (xy 101.290889 -121.891302)
			(xy 101.274821 -121.944709) (xy 101.251149 -121.995206) (xy 101.220376 -122.041719) (xy 101.183159 -122.083256)
			(xy 101.140291 -122.118931) (xy 101.092685 -122.147985) (xy 101.041356 -122.169797) (xy 100.987399 -122.183903)
			(xy 100.931962 -122.190003) (xy 100.876228 -122.187966) (xy 100.821385 -122.177836) (xy 100.768601 -122.159829)
			(xy 100.719001 -122.134328) (xy 100.673643 -122.101877) (xy 100.633494 -122.063168) (xy 100.599408 -122.019025)
			(xy 100.572112 -121.97039) (xy 100.552189 -121.918299) (xy 100.540063 -121.863862) (xy 100.535992 -121.80824)
			(xy 100.247558 -121.80824) (xy 100.233765 -121.819719) (xy 100.186159 -121.848773) (xy 100.13483 -121.870585)
			(xy 100.080873 -121.884691) (xy 100.025436 -121.890791) (xy 99.969702 -121.888754) (xy 99.914859 -121.878624)
			(xy 99.862075 -121.860617) (xy 99.812475 -121.835116) (xy 99.767117 -121.802665) (xy 99.726968 -121.763956)
			(xy 99.692882 -121.719813) (xy 99.665586 -121.671178) (xy 99.645663 -121.619087) (xy 99.633537 -121.56465)
			(xy 99.629466 -121.509028) (xy 98.23569 -121.509028) (xy 98.231425 -121.513788) (xy 98.188557 -121.549463)
			(xy 98.140951 -121.578517) (xy 98.089622 -121.600329) (xy 98.035665 -121.614435) (xy 97.980228 -121.620535)
			(xy 97.924494 -121.618498) (xy 97.869651 -121.608368) (xy 97.816867 -121.590361) (xy 97.767267 -121.56486)
			(xy 97.721909 -121.532409) (xy 97.68176 -121.4937) (xy 97.647674 -121.449557) (xy 97.620378 -121.400922)
			(xy 97.600455 -121.348831) (xy 97.588329 -121.294394) (xy 97.584258 -121.238772) (xy 93.449513 -121.238772)
			(xy 93.451728 -121.25419) (xy 93.452188 -121.281444) (xy 93.451692 -121.308813) (xy 93.443882 -121.362991)
			(xy 93.4284 -121.415494) (xy 93.405565 -121.465241) (xy 93.375846 -121.511209) (xy 93.358208 -121.532142)
			(xy 93.357954 -121.532396) (xy 93.352357 -121.539476) (xy 93.346118 -121.556398) (xy 93.345762 -121.565416)
			(xy 93.345762 -121.632472) (xy 93.346141 -121.641486) (xy 93.352374 -121.658403) (xy 93.357954 -121.665492)
			(xy 93.358208 -121.665492) (xy 93.358208 -121.665746) (xy 93.375836 -121.686687) (xy 93.40555 -121.732657)
			(xy 93.428387 -121.782403) (xy 93.443881 -121.834901) (xy 93.451712 -121.889075) (xy 93.452188 -121.916444)
			(xy 93.451763 -121.943697) (xy 93.444 -121.997648) (xy 93.428638 -122.049945) (xy 93.405991 -122.099524)
			(xy 93.376518 -122.145375) (xy 93.34082 -122.186565) (xy 93.299624 -122.222256) (xy 93.253768 -122.251721)
			(xy 93.204185 -122.274361) (xy 93.151886 -122.289714) (xy 93.097933 -122.297468) (xy 93.07068 -122.297952)
			(xy 93.041557 -122.297438) (xy 92.983987 -122.288596) (xy 92.928429 -122.271105) (xy 92.876177 -122.245372)
			(xy 92.828443 -122.211995) (xy 92.786338 -122.171749) (xy 92.75084 -122.125571) (xy 92.722774 -122.074533)
			(xy 92.702793 -122.019822) (xy 92.696538 -121.991374) (xy 92.694252 -121.97969) (xy 92.679774 -121.960894)
			(xy 92.5957 -121.920508) (xy 92.584883 -121.915953) (xy 92.561446 -121.916206) (xy 92.550742 -121.921016)
			(xy 92.550234 -121.921016) (xy 92.523177 -121.934301) (xy 92.4659 -121.953077) (xy 92.406381 -121.962596)
			(xy 92.376244 -121.96318) (xy 92.348991 -121.962704) (xy 92.295039 -121.954952) (xy 92.24274 -121.9396)
			(xy 92.193158 -121.916961) (xy 92.147303 -121.887495) (xy 92.106109 -121.851802) (xy 92.070415 -121.81061)
			(xy 92.040947 -121.764756) (xy 92.018305 -121.715175) (xy 92.002951 -121.662877) (xy 91.995197 -121.608925)
			(xy 91.994736 -121.581672) (xy 91.507093 -121.581672) (xy 91.506802 -121.582434) (xy 91.50604 -121.584212)
			(xy 91.50477 -121.588784) (xy 91.5035 -121.59996) (xy 91.5035 -122.525028) (xy 99.60559 -122.525028)
			(xy 99.609661 -122.469406) (xy 99.621787 -122.414969) (xy 99.64171 -122.362878) (xy 99.669006 -122.314243)
			(xy 99.703092 -122.2701) (xy 99.743241 -122.231391) (xy 99.788599 -122.19894) (xy 99.838199 -122.173439)
			(xy 99.890983 -122.155432) (xy 99.945826 -122.145302) (xy 100.00156 -122.143265) (xy 100.056997 -122.149365)
			(xy 100.110954 -122.163471) (xy 100.162283 -122.185283) (xy 100.209889 -122.214337) (xy 100.252757 -122.250012)
			(xy 100.289974 -122.291549) (xy 100.320747 -122.338062) (xy 100.344419 -122.388559) (xy 100.360487 -122.441966)
			(xy 100.368607 -122.497142) (xy 100.369116 -122.525028) (xy 100.368607 -122.552914) (xy 100.360487 -122.60809)
			(xy 100.344419 -122.661497) (xy 100.320747 -122.711994) (xy 100.289974 -122.758507) (xy 100.252757 -122.800044)
			(xy 100.209889 -122.835719) (xy 100.162283 -122.864773) (xy 100.110954 -122.886585) (xy 100.056997 -122.900691)
			(xy 100.00156 -122.906791) (xy 99.945826 -122.904754) (xy 99.890983 -122.894624) (xy 99.838199 -122.876617)
			(xy 99.788599 -122.851116) (xy 99.743241 -122.818665) (xy 99.703092 -122.779956) (xy 99.669006 -122.735813)
			(xy 99.64171 -122.687178) (xy 99.621787 -122.635087) (xy 99.609661 -122.58065) (xy 99.60559 -122.525028)
			(xy 91.5035 -122.525028) (xy 91.5035 -123.364553) (xy 94.064275 -123.364553) (xy 94.064275 -123.310047)
			(xy 94.072033 -123.256097) (xy 94.087389 -123.203799) (xy 94.110033 -123.15422) (xy 94.139502 -123.108368)
			(xy 94.175197 -123.067177) (xy 94.21639 -123.031485) (xy 94.262245 -123.002019) (xy 94.311826 -122.97938)
			(xy 94.364124 -122.964027) (xy 94.418075 -122.956273) (xy 94.445328 -122.955812) (xy 94.472699 -122.956259)
			(xy 94.526879 -122.964081) (xy 94.579382 -122.979574) (xy 94.629129 -123.00242) (xy 94.675095 -123.032149)
			(xy 94.696026 -123.049792) (xy 94.69628 -123.050046) (xy 94.703364 -123.055636) (xy 94.720283 -123.061879)
			(xy 94.7293 -123.062238) (xy 94.796356 -123.062238) (xy 94.80537 -123.061852) (xy 94.822286 -123.055624)
			(xy 94.829376 -123.050046) (xy 94.829376 -123.049792) (xy 94.82963 -123.049792) (xy 94.850563 -123.032151)
			(xy 94.896531 -123.002427) (xy 94.946277 -122.979581) (xy 94.998779 -122.964085) (xy 95.052957 -122.956256)
			(xy 95.107699 -122.956256) (xy 95.161877 -122.964085) (xy 95.214379 -122.979581) (xy 95.264125 -123.002427)
			(xy 95.310093 -123.032151) (xy 95.331026 -123.049792) (xy 95.33128 -123.050046) (xy 95.338364 -123.055636)
			(xy 95.355283 -123.061879) (xy 95.3643 -123.062238) (xy 95.431356 -123.062238) (xy 95.44037 -123.061852)
			(xy 95.457286 -123.055624) (xy 95.464376 -123.050046) (xy 95.464376 -123.049792) (xy 95.46463 -123.049792)
			(xy 95.485577 -123.032171) (xy 95.531546 -123.002457) (xy 95.581289 -122.979617) (xy 95.633787 -122.964122)
			(xy 95.68796 -122.956289) (xy 95.715328 -122.955812) (xy 95.742579 -122.95626) (xy 95.796527 -122.96402)
			(xy 95.848821 -122.979378) (xy 95.898397 -123.002022) (xy 95.944247 -123.031491) (xy 95.985436 -123.067184)
			(xy 96.021126 -123.108376) (xy 96.050591 -123.154227) (xy 96.073232 -123.203805) (xy 96.088586 -123.256101)
			(xy 96.096342 -123.310049) (xy 96.096342 -123.364551) (xy 96.088586 -123.4185) (xy 96.073232 -123.470795)
			(xy 96.050591 -123.520373) (xy 96.021126 -123.566224) (xy 95.985436 -123.607416) (xy 95.944247 -123.643109)
			(xy 95.898397 -123.672578) (xy 95.848821 -123.695222) (xy 95.796527 -123.71058) (xy 95.742579 -123.71834)
			(xy 95.715328 -123.718828) (xy 95.687958 -123.718363) (xy 95.633778 -123.710548) (xy 95.581274 -123.695059)
			(xy 95.531527 -123.672217) (xy 95.485561 -123.64249) (xy 95.46463 -123.624848) (xy 95.464376 -123.624594)
			(xy 95.457301 -123.618991) (xy 95.440375 -123.612754) (xy 95.431356 -123.612402) (xy 95.3643 -123.612402)
			(xy 95.355283 -123.612759) (xy 95.338366 -123.619006) (xy 95.33128 -123.624594) (xy 95.331026 -123.624848)
			(xy 95.310093 -123.642489) (xy 95.264125 -123.672213) (xy 95.214379 -123.695059) (xy 95.161877 -123.710555)
			(xy 95.107699 -123.718384) (xy 95.052957 -123.718384) (xy 94.998779 -123.710555) (xy 94.946277 -123.695059)
			(xy 94.896531 -123.672213) (xy 94.850563 -123.642489) (xy 94.82963 -123.624848) (xy 94.829376 -123.624594)
			(xy 94.822301 -123.618991) (xy 94.805375 -123.612754) (xy 94.796356 -123.612402) (xy 94.7293 -123.612402)
			(xy 94.720283 -123.612759) (xy 94.703366 -123.619006) (xy 94.69628 -123.624594) (xy 94.69628 -123.624848)
			(xy 94.696026 -123.624848) (xy 94.675088 -123.64248) (xy 94.629118 -123.672195) (xy 94.579372 -123.695033)
			(xy 94.526872 -123.710525) (xy 94.472697 -123.718354) (xy 94.445328 -123.718828) (xy 94.418075 -123.718327)
			(xy 94.364124 -123.710573) (xy 94.311826 -123.69522) (xy 94.262245 -123.672581) (xy 94.21639 -123.643115)
			(xy 94.175197 -123.607423) (xy 94.139502 -123.566232) (xy 94.110033 -123.52038) (xy 94.087389 -123.470801)
			(xy 94.072033 -123.418503) (xy 94.064275 -123.364553) (xy 91.5035 -123.364553) (xy 91.5035 -124.47778)
			(xy 92.41282 -124.47778) (xy 92.413269 -124.450409) (xy 92.421091 -124.396229) (xy 92.436583 -124.343726)
			(xy 92.459429 -124.293979) (xy 92.489157 -124.248013) (xy 92.5068 -124.227082) (xy 92.507054 -124.226828)
			(xy 92.512641 -124.219742) (xy 92.518886 -124.202825) (xy 92.519246 -124.193808) (xy 92.519246 -124.126752)
			(xy 92.518876 -124.117736) (xy 92.512639 -124.100818) (xy 92.507054 -124.093732) (xy 92.5068 -124.093732)
			(xy 92.5068 -124.093478) (xy 92.489184 -124.072527) (xy 92.459469 -124.02656) (xy 92.436628 -123.976817)
			(xy 92.421132 -123.92432) (xy 92.413297 -123.870148) (xy 92.41282 -123.84278) (xy 92.413306 -123.815529)
			(xy 92.421062 -123.761581) (xy 92.436417 -123.709286) (xy 92.459059 -123.659709) (xy 92.488525 -123.613859)
			(xy 92.524216 -123.572668) (xy 92.565407 -123.536977) (xy 92.611257 -123.507511) (xy 92.660834 -123.484869)
			(xy 92.713129 -123.469514) (xy 92.767077 -123.461758) (xy 92.821579 -123.461758) (xy 92.875527 -123.469514)
			(xy 92.927822 -123.484869) (xy 92.977399 -123.507511) (xy 93.023249 -123.536977) (xy 93.06444 -123.572668)
			(xy 93.100131 -123.613859) (xy 93.129597 -123.659709) (xy 93.152239 -123.709286) (xy 93.167594 -123.761581)
			(xy 93.168482 -123.76776) (xy 97.442306 -123.76776) (xy 97.45006 -123.713817) (xy 97.465412 -123.661528)
			(xy 97.488049 -123.611955) (xy 97.51751 -123.566108) (xy 97.553197 -123.524921) (xy 97.594381 -123.489231)
			(xy 97.640225 -123.459765) (xy 97.689796 -123.437124) (xy 97.742084 -123.421767) (xy 97.796026 -123.414008)
			(xy 97.823274 -123.41352) (xy 97.823782 -123.41352) (xy 97.834154 -123.413603) (xy 97.854866 -123.414745)
			(xy 97.865184 -123.415806) (xy 97.879729 -123.41691) (xy 97.908422 -123.411704) (xy 97.934478 -123.398612)
			(xy 97.955781 -123.378698) (xy 97.970599 -123.353583) (xy 97.977727 -123.325307) (xy 97.976586 -123.296168)
			(xy 97.972372 -123.282202) (xy 97.963011 -123.252595) (xy 97.952934 -123.191327) (xy 97.952306 -123.160282)
			(xy 97.952306 -123.160028) (xy 97.952725 -123.132773) (xy 97.960479 -123.078817) (xy 97.975832 -123.026514)
			(xy 97.998473 -122.976928) (xy 98.02794 -122.931069) (xy 98.063634 -122.889871) (xy 98.104828 -122.854171)
			(xy 98.150683 -122.824698) (xy 98.200266 -122.80205) (xy 98.252567 -122.78669) (xy 98.306522 -122.778929)
			(xy 98.361032 -122.778925) (xy 98.414988 -122.78668) (xy 98.467291 -122.802034) (xy 98.516876 -122.824675)
			(xy 98.562735 -122.854143) (xy 98.603933 -122.889837) (xy 98.639632 -122.931032) (xy 98.669105 -122.976887)
			(xy 98.691751 -123.02647) (xy 98.707111 -123.078771) (xy 98.714872 -123.132726) (xy 98.714874 -123.187236)
			(xy 98.707119 -123.241192) (xy 98.691765 -123.293495) (xy 98.669122 -123.34308) (xy 98.639654 -123.388939)
			(xy 98.603959 -123.430136) (xy 98.562765 -123.465834) (xy 98.516909 -123.495307) (xy 98.467326 -123.517953)
			(xy 98.415024 -123.533312) (xy 98.361069 -123.541072) (xy 98.333814 -123.541536) (xy 98.333306 -123.541536)
			(xy 98.322934 -123.541454) (xy 98.302222 -123.540311) (xy 98.291904 -123.53925) (xy 98.277358 -123.538193)
			(xy 98.248676 -123.5434) (xy 98.222628 -123.556487) (xy 98.20133 -123.576392) (xy 98.186512 -123.601496)
			(xy 98.179379 -123.629761) (xy 98.18051 -123.658891) (xy 98.184716 -123.672854) (xy 98.194067 -123.702464)
			(xy 98.204151 -123.763729) (xy 98.204782 -123.794774) (xy 98.204782 -123.795028) (xy 99.649024 -123.795028)
			(xy 99.653095 -123.739406) (xy 99.665221 -123.684969) (xy 99.685144 -123.632878) (xy 99.71244 -123.584243)
			(xy 99.746526 -123.5401) (xy 99.786675 -123.501391) (xy 99.832033 -123.46894) (xy 99.881633 -123.443439)
			(xy 99.934417 -123.425432) (xy 99.98926 -123.415302) (xy 100.044994 -123.413265) (xy 100.100431 -123.419365)
			(xy 100.154388 -123.433471) (xy 100.205717 -123.455283) (xy 100.253323 -123.484337) (xy 100.296191 -123.520012)
			(xy 100.333408 -123.561549) (xy 100.364181 -123.608062) (xy 100.387853 -123.658559) (xy 100.403921 -123.711966)
			(xy 100.412041 -123.767142) (xy 100.41255 -123.795028) (xy 100.412041 -123.822914) (xy 100.403921 -123.87809)
			(xy 100.387853 -123.931497) (xy 100.364181 -123.981994) (xy 100.333408 -124.028507) (xy 100.296191 -124.070044)
			(xy 100.253323 -124.105719) (xy 100.205717 -124.134773) (xy 100.154388 -124.156585) (xy 100.100431 -124.170691)
			(xy 100.044994 -124.176791) (xy 99.98926 -124.174754) (xy 99.934417 -124.164624) (xy 99.881633 -124.146617)
			(xy 99.832033 -124.121116) (xy 99.786675 -124.088665) (xy 99.746526 -124.049956) (xy 99.71244 -124.005813)
			(xy 99.685144 -123.957178) (xy 99.665221 -123.905087) (xy 99.653095 -123.85065) (xy 99.649024 -123.795028)
			(xy 98.204782 -123.795028) (xy 98.204292 -123.822276) (xy 98.196532 -123.876218) (xy 98.181176 -123.928506)
			(xy 98.158534 -123.978077) (xy 98.129068 -124.023921) (xy 98.093378 -124.065105) (xy 98.05219 -124.100791)
			(xy 98.006343 -124.130252) (xy 97.956771 -124.152889) (xy 97.904481 -124.168241) (xy 97.850538 -124.175995)
			(xy 97.796042 -124.175993) (xy 97.7421 -124.168236) (xy 97.689811 -124.152882) (xy 97.640239 -124.130242)
			(xy 97.594394 -124.100779) (xy 97.553208 -124.065091) (xy 97.51752 -124.023905) (xy 97.488057 -123.978059)
			(xy 97.465417 -123.928487) (xy 97.450063 -123.876198) (xy 97.442307 -123.822256) (xy 97.442306 -123.76776)
			(xy 93.168482 -123.76776) (xy 93.17535 -123.815529) (xy 93.175836 -123.84278) (xy 93.175374 -123.870151)
			(xy 93.167557 -123.92433) (xy 93.152068 -123.976834) (xy 93.129225 -124.026581) (xy 93.099499 -124.072547)
			(xy 93.081856 -124.093478) (xy 93.081602 -124.093732) (xy 93.076038 -124.100834) (xy 93.069778 -124.117739)
			(xy 93.06941 -124.126752) (xy 93.06941 -124.193808) (xy 93.069761 -124.202826) (xy 93.074313 -124.215144)
			(xy 94.606616 -124.215144) (xy 94.610687 -124.159522) (xy 94.622813 -124.105085) (xy 94.642736 -124.052994)
			(xy 94.670032 -124.004359) (xy 94.704118 -123.960216) (xy 94.744267 -123.921507) (xy 94.789625 -123.889056)
			(xy 94.839225 -123.863555) (xy 94.892009 -123.845548) (xy 94.946852 -123.835418) (xy 95.002586 -123.833381)
			(xy 95.058023 -123.839481) (xy 95.11198 -123.853587) (xy 95.163309 -123.875399) (xy 95.210915 -123.904453)
			(xy 95.253783 -123.940128) (xy 95.291 -123.981665) (xy 95.321773 -124.028178) (xy 95.345445 -124.078675)
			(xy 95.361513 -124.132082) (xy 95.369633 -124.187258) (xy 95.370142 -124.215144) (xy 95.369633 -124.24303)
			(xy 95.361513 -124.298206) (xy 95.345445 -124.351613) (xy 95.321773 -124.40211) (xy 95.291 -124.448623)
			(xy 95.253783 -124.49016) (xy 95.210915 -124.525835) (xy 95.163309 -124.554889) (xy 95.11198 -124.576701)
			(xy 95.058023 -124.590807) (xy 95.002586 -124.596907) (xy 94.946852 -124.59487) (xy 94.892009 -124.58474)
			(xy 94.839225 -124.566733) (xy 94.789625 -124.541232) (xy 94.744267 -124.508781) (xy 94.704118 -124.470072)
			(xy 94.670032 -124.425929) (xy 94.642736 -124.377294) (xy 94.622813 -124.325203) (xy 94.610687 -124.270766)
			(xy 94.606616 -124.215144) (xy 93.074313 -124.215144) (xy 93.076012 -124.219743) (xy 93.081602 -124.226828)
			(xy 93.081856 -124.226828) (xy 93.081856 -124.227082) (xy 93.099493 -124.248016) (xy 93.129207 -124.293987)
			(xy 93.152044 -124.343734) (xy 93.167535 -124.396235) (xy 93.175363 -124.450411) (xy 93.175836 -124.47778)
			(xy 93.17535 -124.505031) (xy 93.167594 -124.558979) (xy 93.152239 -124.611274) (xy 93.129597 -124.660851)
			(xy 93.100131 -124.706701) (xy 93.06444 -124.747892) (xy 93.029976 -124.777754) (xy 112.163858 -124.777754)
			(xy 112.167929 -124.722132) (xy 112.180055 -124.667695) (xy 112.199978 -124.615604) (xy 112.227274 -124.566969)
			(xy 112.26136 -124.522826) (xy 112.301509 -124.484117) (xy 112.346867 -124.451666) (xy 112.396467 -124.426165)
			(xy 112.449251 -124.408158) (xy 112.504094 -124.398028) (xy 112.559828 -124.395991) (xy 112.615265 -124.402091)
			(xy 112.669222 -124.416197) (xy 112.720551 -124.438009) (xy 112.768157 -124.467063) (xy 112.811025 -124.502738)
			(xy 112.848242 -124.544275) (xy 112.879015 -124.590788) (xy 112.902687 -124.641285) (xy 112.918755 -124.694692)
			(xy 112.926875 -124.749868) (xy 112.927384 -124.777754) (xy 112.926875 -124.80564) (xy 112.918755 -124.860816)
			(xy 112.911802 -124.883926) (xy 116.439948 -124.883926) (xy 116.444019 -124.828304) (xy 116.456145 -124.773867)
			(xy 116.476068 -124.721776) (xy 116.503364 -124.673141) (xy 116.53745 -124.628998) (xy 116.577599 -124.590289)
			(xy 116.622957 -124.557838) (xy 116.672557 -124.532337) (xy 116.725341 -124.51433) (xy 116.780184 -124.5042)
			(xy 116.835918 -124.502163) (xy 116.891355 -124.508263) (xy 116.945312 -124.522369) (xy 116.996641 -124.544181)
			(xy 117.044247 -124.573235) (xy 117.087115 -124.60891) (xy 117.124332 -124.650447) (xy 117.155105 -124.69696)
			(xy 117.178777 -124.747457) (xy 117.194845 -124.800864) (xy 117.202965 -124.85604) (xy 117.203474 -124.883926)
			(xy 118.631714 -124.883926) (xy 118.635785 -124.828304) (xy 118.647911 -124.773867) (xy 118.667834 -124.721776)
			(xy 118.69513 -124.673141) (xy 118.729216 -124.628998) (xy 118.769365 -124.590289) (xy 118.814723 -124.557838)
			(xy 118.864323 -124.532337) (xy 118.917107 -124.51433) (xy 118.97195 -124.5042) (xy 119.027684 -124.502163)
			(xy 119.083121 -124.508263) (xy 119.137078 -124.522369) (xy 119.188407 -124.544181) (xy 119.236013 -124.573235)
			(xy 119.278881 -124.60891) (xy 119.316098 -124.650447) (xy 119.346871 -124.69696) (xy 119.370543 -124.747457)
			(xy 119.386611 -124.800864) (xy 119.394731 -124.85604) (xy 119.39524 -124.883926) (xy 119.394731 -124.911812)
			(xy 119.386611 -124.966988) (xy 119.370543 -125.020395) (xy 119.346871 -125.070892) (xy 119.316098 -125.117405)
			(xy 119.278881 -125.158942) (xy 119.236013 -125.194617) (xy 119.188407 -125.223671) (xy 119.137078 -125.245483)
			(xy 119.083121 -125.259589) (xy 119.027684 -125.265689) (xy 118.97195 -125.263652) (xy 118.917107 -125.253522)
			(xy 118.864323 -125.235515) (xy 118.814723 -125.210014) (xy 118.769365 -125.177563) (xy 118.729216 -125.138854)
			(xy 118.69513 -125.094711) (xy 118.667834 -125.046076) (xy 118.647911 -124.993985) (xy 118.635785 -124.939548)
			(xy 118.631714 -124.883926) (xy 117.203474 -124.883926) (xy 117.202965 -124.911812) (xy 117.194845 -124.966988)
			(xy 117.178777 -125.020395) (xy 117.155105 -125.070892) (xy 117.124332 -125.117405) (xy 117.087115 -125.158942)
			(xy 117.044247 -125.194617) (xy 116.996641 -125.223671) (xy 116.945312 -125.245483) (xy 116.891355 -125.259589)
			(xy 116.835918 -125.265689) (xy 116.780184 -125.263652) (xy 116.725341 -125.253522) (xy 116.672557 -125.235515)
			(xy 116.622957 -125.210014) (xy 116.577599 -125.177563) (xy 116.53745 -125.138854) (xy 116.503364 -125.094711)
			(xy 116.476068 -125.046076) (xy 116.456145 -124.993985) (xy 116.444019 -124.939548) (xy 116.439948 -124.883926)
			(xy 112.911802 -124.883926) (xy 112.902687 -124.914223) (xy 112.879015 -124.96472) (xy 112.848242 -125.011233)
			(xy 112.811025 -125.05277) (xy 112.768157 -125.088445) (xy 112.720551 -125.117499) (xy 112.669222 -125.139311)
			(xy 112.615265 -125.153417) (xy 112.559828 -125.159517) (xy 112.504094 -125.15748) (xy 112.449251 -125.14735)
			(xy 112.396467 -125.129343) (xy 112.346867 -125.103842) (xy 112.301509 -125.071391) (xy 112.26136 -125.032682)
			(xy 112.227274 -124.988539) (xy 112.199978 -124.939904) (xy 112.180055 -124.887813) (xy 112.167929 -124.833376)
			(xy 112.163858 -124.777754) (xy 93.029976 -124.777754) (xy 93.023249 -124.783583) (xy 92.977399 -124.813049)
			(xy 92.927822 -124.835691) (xy 92.875527 -124.851046) (xy 92.821579 -124.858802) (xy 92.767077 -124.858802)
			(xy 92.713129 -124.851046) (xy 92.660834 -124.835691) (xy 92.611257 -124.813049) (xy 92.565407 -124.783583)
			(xy 92.524216 -124.747892) (xy 92.488525 -124.706701) (xy 92.459059 -124.660851) (xy 92.436417 -124.611274)
			(xy 92.421062 -124.558979) (xy 92.413306 -124.505031) (xy 92.41282 -124.47778) (xy 91.5035 -124.47778)
			(xy 91.5035 -124.62383) (xy 91.504302 -124.633023) (xy 91.511586 -124.649961) (xy 91.517724 -124.65685)
			(xy 91.536362 -124.674955) (xy 91.569061 -124.715338) (xy 91.595978 -124.759784) (xy 91.616615 -124.807472)
			(xy 91.630589 -124.857519) (xy 91.637643 -124.908999) (xy 91.63812 -124.93498) (xy 91.637358 -124.959872)
			(xy 91.636596 -124.97308) (xy 91.641422 -124.984002) (xy 91.645486 -124.991368) (xy 91.64828 -124.994924)
			(xy 91.648788 -124.995432) (xy 91.656154 -125.002544) (xy 91.665552 -125.009402) (xy 91.6813 -125.020832)
			(xy 91.72194 -125.050296) (xy 91.729814 -125.055884) (xy 91.73485 -125.059059) (xy 91.746019 -125.063166)
			(xy 91.751912 -125.064012) (xy 91.764358 -125.065536) (xy 91.776296 -125.06071) (xy 91.776804 -125.06071)
			(xy 91.799529 -125.051952) (xy 91.846644 -125.039624) (xy 91.894947 -125.033403) (xy 91.919298 -125.033024)
			(xy 91.946332 -125.033494) (xy 91.999859 -125.041126) (xy 92.051772 -125.056237) (xy 92.101032 -125.078526)
			(xy 92.146653 -125.107544) (xy 92.187721 -125.142712) (xy 92.223413 -125.183325) (xy 92.253015 -125.22857)
			(xy 92.275933 -125.27754) (xy 92.29171 -125.329256) (xy 92.300028 -125.38268) (xy 92.300806 -125.409706)
			(xy 92.300806 -125.414532) (xy 92.30041 -125.440139) (xy 92.293592 -125.490898) (xy 92.280043 -125.540288)
			(xy 92.260007 -125.58742) (xy 92.233843 -125.631447) (xy 92.218256 -125.651768) (xy 92.218002 -125.652022)
			(xy 92.214954 -125.655832) (xy 92.210382 -125.664722) (xy 92.206826 -125.674882) (xy 92.206826 -125.716284)
			(xy 92.19565 -125.716284) (xy 92.19565 -125.77699) (xy 92.196949 -125.782039) (xy 92.201304 -125.791509)
			(xy 92.204286 -125.795786) (xy 92.206572 -125.79858) (xy 92.206826 -125.798834) (xy 92.224465 -125.819766)
			(xy 92.254185 -125.865734) (xy 92.266033 -125.891544) (xy 95.17507 -125.891544) (xy 95.17551 -125.865229)
			(xy 95.182752 -125.8131) (xy 95.197077 -125.762457) (xy 95.218214 -125.714258) (xy 95.245765 -125.669415)
			(xy 95.279207 -125.628776) (xy 95.29826 -125.61062) (xy 95.305649 -125.603087) (xy 95.314182 -125.583816)
			(xy 95.31477 -125.573282) (xy 95.31477 -125.498606) (xy 95.31426 -125.488054) (xy 95.305712 -125.468758)
			(xy 95.29826 -125.461268) (xy 95.279188 -125.443129) (xy 95.245734 -125.402495) (xy 95.218178 -125.357651)
			(xy 95.197043 -125.309447) (xy 95.182729 -125.258797) (xy 95.175507 -125.206661) (xy 95.17507 -125.180344)
			(xy 95.175556 -125.153093) (xy 95.183312 -125.099145) (xy 95.198667 -125.04685) (xy 95.221309 -124.997273)
			(xy 95.250775 -124.951423) (xy 95.286466 -124.910232) (xy 95.327657 -124.874541) (xy 95.373507 -124.845075)
			(xy 95.423084 -124.822433) (xy 95.475379 -124.807078) (xy 95.529327 -124.799322) (xy 95.583829 -124.799322)
			(xy 95.637777 -124.807078) (xy 95.690072 -124.822433) (xy 95.739649 -124.845075) (xy 95.785499 -124.874541)
			(xy 95.82669 -124.910232) (xy 95.862381 -124.951423) (xy 95.891847 -124.997273) (xy 95.914489 -125.04685)
			(xy 95.929844 -125.099145) (xy 95.9376 -125.153093) (xy 95.938086 -125.180344) (xy 95.937652 -125.206659)
			(xy 95.930411 -125.258789) (xy 95.916086 -125.309433) (xy 95.894947 -125.357632) (xy 95.867395 -125.402474)
			(xy 95.83395 -125.443112) (xy 95.814896 -125.461268) (xy 95.807506 -125.468799) (xy 95.798975 -125.488072)
			(xy 95.798386 -125.498606) (xy 95.798386 -125.573282) (xy 95.798916 -125.583831) (xy 95.807451 -125.603127)
			(xy 95.814896 -125.61062) (xy 95.833953 -125.628774) (xy 95.867411 -125.669404) (xy 95.894969 -125.714244)
			(xy 95.916108 -125.762445) (xy 95.930424 -125.813093) (xy 95.937648 -125.865228) (xy 95.938086 -125.891544)
			(xy 95.9376 -125.918795) (xy 95.929844 -125.972743) (xy 95.914489 -126.025038) (xy 95.891847 -126.074615)
			(xy 95.862381 -126.120465) (xy 95.82669 -126.161656) (xy 95.785499 -126.197347) (xy 95.784688 -126.197868)
			(xy 116.44579 -126.197868) (xy 116.449861 -126.142246) (xy 116.461987 -126.087809) (xy 116.48191 -126.035718)
			(xy 116.509206 -125.987083) (xy 116.543292 -125.94294) (xy 116.583441 -125.904231) (xy 116.628799 -125.87178)
			(xy 116.678399 -125.846279) (xy 116.731183 -125.828272) (xy 116.786026 -125.818142) (xy 116.84176 -125.816105)
			(xy 116.897197 -125.822205) (xy 116.951154 -125.836311) (xy 117.002483 -125.858123) (xy 117.050089 -125.887177)
			(xy 117.092957 -125.922852) (xy 117.130174 -125.964389) (xy 117.160947 -126.010902) (xy 117.184619 -126.061399)
			(xy 117.200687 -126.114806) (xy 117.208807 -126.169982) (xy 117.209316 -126.197868) (xy 117.208807 -126.225754)
			(xy 117.200687 -126.28093) (xy 117.184619 -126.334337) (xy 117.160947 -126.384834) (xy 117.130174 -126.431347)
			(xy 117.092957 -126.472884) (xy 117.050089 -126.508559) (xy 117.002483 -126.537613) (xy 116.951154 -126.559425)
			(xy 116.897197 -126.573531) (xy 116.84176 -126.579631) (xy 116.786026 -126.577594) (xy 116.731183 -126.567464)
			(xy 116.678399 -126.549457) (xy 116.628799 -126.523956) (xy 116.583441 -126.491505) (xy 116.543292 -126.452796)
			(xy 116.509206 -126.408653) (xy 116.48191 -126.360018) (xy 116.461987 -126.307927) (xy 116.449861 -126.25349)
			(xy 116.44579 -126.197868) (xy 95.784688 -126.197868) (xy 95.739649 -126.226813) (xy 95.690072 -126.249455)
			(xy 95.637777 -126.26481) (xy 95.583829 -126.272566) (xy 95.529327 -126.272566) (xy 95.475379 -126.26481)
			(xy 95.423084 -126.249455) (xy 95.373507 -126.226813) (xy 95.327657 -126.197347) (xy 95.286466 -126.161656)
			(xy 95.250775 -126.120465) (xy 95.221309 -126.074615) (xy 95.198667 -126.025038) (xy 95.183312 -125.972743)
			(xy 95.175556 -125.918795) (xy 95.17507 -125.891544) (xy 92.266033 -125.891544) (xy 92.277022 -125.915482)
			(xy 92.292507 -125.967984) (xy 92.30032 -126.022163) (xy 92.300806 -126.049532) (xy 92.300306 -126.077272)
			(xy 92.29227 -126.132166) (xy 92.276372 -126.185318) (xy 92.252946 -126.235609) (xy 92.222486 -126.281978)
			(xy 92.185635 -126.32345) (xy 92.143168 -126.35915) (xy 92.09598 -126.388326) (xy 92.045065 -126.410363)
			(xy 91.991497 -126.424797) (xy 91.964002 -126.4285) (xy 91.950286 -126.430024) (xy 91.919552 -126.431294)
			(xy 91.919044 -126.431294) (xy 91.886786 -126.42977) (xy 91.881452 -126.429262) (xy 91.867228 -126.427992)
			(xy 91.862148 -126.42723) (xy 91.85021 -126.424944) (xy 91.849956 -126.424944) (xy 91.824556 -126.419356)
			(xy 91.797577 -126.411942) (xy 91.745981 -126.390301) (xy 91.698094 -126.361364) (xy 91.67622 -126.343918)
			(xy 91.670886 -126.3396) (xy 91.644724 -126.327662) (xy 91.637866 -126.326646) (xy 91.631262 -126.327662)
			(xy 91.627655 -126.328236) (xy 91.62064 -126.330268) (xy 91.617292 -126.331726) (xy 91.560904 -126.357634)
			(xy 91.529408 -126.372112) (xy 91.52763 -126.373128) (xy 91.517887 -126.379874) (xy 91.50544 -126.400006)
			(xy 91.503754 -126.411736) (xy 91.503754 -126.412244) (xy 91.5035 -126.416054) (xy 91.5035 -126.915926)
			(xy 118.631714 -126.915926) (xy 118.635785 -126.860304) (xy 118.647911 -126.805867) (xy 118.667834 -126.753776)
			(xy 118.69513 -126.705141) (xy 118.729216 -126.660998) (xy 118.769365 -126.622289) (xy 118.814723 -126.589838)
			(xy 118.864323 -126.564337) (xy 118.917107 -126.54633) (xy 118.97195 -126.5362) (xy 119.027684 -126.534163)
			(xy 119.083121 -126.540263) (xy 119.137078 -126.554369) (xy 119.188407 -126.576181) (xy 119.236013 -126.605235)
			(xy 119.278881 -126.64091) (xy 119.316098 -126.682447) (xy 119.346871 -126.72896) (xy 119.370543 -126.779457)
			(xy 119.386611 -126.832864) (xy 119.394731 -126.88804) (xy 119.39524 -126.915926) (xy 119.394731 -126.943812)
			(xy 119.386611 -126.998988) (xy 119.370543 -127.052395) (xy 119.346871 -127.102892) (xy 119.316098 -127.149405)
			(xy 119.278881 -127.190942) (xy 119.236013 -127.226617) (xy 119.188407 -127.255671) (xy 119.137078 -127.277483)
			(xy 119.083121 -127.291589) (xy 119.027684 -127.297689) (xy 118.97195 -127.295652) (xy 118.917107 -127.285522)
			(xy 118.864323 -127.267515) (xy 118.814723 -127.242014) (xy 118.769365 -127.209563) (xy 118.729216 -127.170854)
			(xy 118.69513 -127.126711) (xy 118.667834 -127.078076) (xy 118.647911 -127.025985) (xy 118.635785 -126.971548)
			(xy 118.631714 -126.915926) (xy 91.5035 -126.915926) (xy 91.5035 -127.48387) (xy 116.59438 -127.48387)
			(xy 116.598451 -127.428248) (xy 116.610577 -127.373811) (xy 116.6305 -127.32172) (xy 116.657796 -127.273085)
			(xy 116.691882 -127.228942) (xy 116.732031 -127.190233) (xy 116.777389 -127.157782) (xy 116.826989 -127.132281)
			(xy 116.879773 -127.114274) (xy 116.934616 -127.104144) (xy 116.99035 -127.102107) (xy 117.045787 -127.108207)
			(xy 117.099744 -127.122313) (xy 117.151073 -127.144125) (xy 117.198679 -127.173179) (xy 117.241547 -127.208854)
			(xy 117.278764 -127.250391) (xy 117.309537 -127.296904) (xy 117.333209 -127.347401) (xy 117.349277 -127.400808)
			(xy 117.357397 -127.455984) (xy 117.357906 -127.48387) (xy 117.357397 -127.511756) (xy 117.349277 -127.566932)
			(xy 117.333209 -127.620339) (xy 117.309537 -127.670836) (xy 117.278764 -127.717349) (xy 117.241547 -127.758886)
			(xy 117.198679 -127.794561) (xy 117.151073 -127.823615) (xy 117.099744 -127.845427) (xy 117.045787 -127.859533)
			(xy 116.99035 -127.865633) (xy 116.934616 -127.863596) (xy 116.879773 -127.853466) (xy 116.826989 -127.835459)
			(xy 116.777389 -127.809958) (xy 116.732031 -127.777507) (xy 116.691882 -127.738798) (xy 116.657796 -127.694655)
			(xy 116.6305 -127.64602) (xy 116.610577 -127.593929) (xy 116.598451 -127.539492) (xy 116.59438 -127.48387)
			(xy 91.5035 -127.48387) (xy 91.5035 -127.931926) (xy 118.631714 -127.931926) (xy 118.635785 -127.876304)
			(xy 118.647911 -127.821867) (xy 118.667834 -127.769776) (xy 118.69513 -127.721141) (xy 118.729216 -127.676998)
			(xy 118.769365 -127.638289) (xy 118.814723 -127.605838) (xy 118.864323 -127.580337) (xy 118.917107 -127.56233)
			(xy 118.97195 -127.5522) (xy 119.027684 -127.550163) (xy 119.083121 -127.556263) (xy 119.137078 -127.570369)
			(xy 119.188407 -127.592181) (xy 119.236013 -127.621235) (xy 119.278881 -127.65691) (xy 119.316098 -127.698447)
			(xy 119.346871 -127.74496) (xy 119.370543 -127.795457) (xy 119.386611 -127.848864) (xy 119.394731 -127.90404)
			(xy 119.39524 -127.931926) (xy 119.394731 -127.959812) (xy 119.386611 -128.014988) (xy 119.370543 -128.068395)
			(xy 119.346871 -128.118892) (xy 119.316098 -128.165405) (xy 119.278881 -128.206942) (xy 119.236013 -128.242617)
			(xy 119.188407 -128.271671) (xy 119.137078 -128.293483) (xy 119.083121 -128.307589) (xy 119.027684 -128.313689)
			(xy 118.97195 -128.311652) (xy 118.917107 -128.301522) (xy 118.864323 -128.283515) (xy 118.814723 -128.258014)
			(xy 118.769365 -128.225563) (xy 118.729216 -128.186854) (xy 118.69513 -128.142711) (xy 118.667834 -128.094076)
			(xy 118.647911 -128.041985) (xy 118.635785 -127.987548) (xy 118.631714 -127.931926) (xy 91.5035 -127.931926)
			(xy 91.5035 -128.715008) (xy 91.504516 -128.724406) (xy 91.504516 -128.724914) (xy 91.506225 -128.732071)
			(xy 91.513065 -128.74509) (xy 91.517978 -128.750568) (xy 91.639136 -128.871726) (xy 91.645985 -128.879123)
			(xy 91.65372 -128.897722) (xy 91.654122 -128.907794) (xy 91.654122 -130.992118) (xy 104.844342 -130.992118)
			(xy 104.844808 -130.964748) (xy 104.852625 -130.910568) (xy 104.868113 -130.858065) (xy 104.890955 -130.808318)
			(xy 104.92068 -130.762351) (xy 104.938322 -130.74142) (xy 104.938576 -130.741166) (xy 104.94415 -130.734071)
			(xy 104.950402 -130.71716) (xy 104.950768 -130.708146) (xy 104.950768 -130.64109) (xy 104.950423 -130.632072)
			(xy 104.944168 -130.615154) (xy 104.938576 -130.60807) (xy 104.938322 -130.60807) (xy 104.938322 -130.607816)
			(xy 104.920699 -130.586869) (xy 104.890974 -130.540903) (xy 104.868128 -130.49116) (xy 104.85263 -130.43866)
			(xy 104.8448 -130.384483) (xy 104.844798 -130.329744) (xy 104.852625 -130.275567) (xy 104.868118 -130.223066)
			(xy 104.890961 -130.17332) (xy 104.920683 -130.127353) (xy 104.938322 -130.10642) (xy 104.938576 -130.106166)
			(xy 104.94415 -130.099071) (xy 104.950402 -130.08216) (xy 104.950768 -130.073146) (xy 104.950768 -130.00609)
			(xy 104.950423 -129.997072) (xy 104.944168 -129.980154) (xy 104.938576 -129.97307) (xy 104.938322 -129.97307)
			(xy 104.938322 -129.972816) (xy 104.920699 -129.951869) (xy 104.890974 -129.905903) (xy 104.868128 -129.85616)
			(xy 104.85263 -129.80366) (xy 104.8448 -129.749483) (xy 104.844798 -129.694744) (xy 104.852625 -129.640567)
			(xy 104.868118 -129.588066) (xy 104.890961 -129.53832) (xy 104.920683 -129.492353) (xy 104.938322 -129.47142)
			(xy 104.938576 -129.471166) (xy 104.94415 -129.464071) (xy 104.950402 -129.44716) (xy 104.950768 -129.438146)
			(xy 104.950768 -129.37109) (xy 104.950423 -129.362072) (xy 104.944168 -129.345154) (xy 104.938576 -129.33807)
			(xy 104.938322 -129.33807) (xy 104.938322 -129.337816) (xy 104.92068 -129.316886) (xy 104.890968 -129.270913)
			(xy 104.868132 -129.221165) (xy 104.852642 -129.168664) (xy 104.844815 -129.114487) (xy 104.844342 -129.087118)
			(xy 104.844828 -129.059867) (xy 104.852584 -129.005919) (xy 104.867939 -128.953624) (xy 104.890581 -128.904047)
			(xy 104.920047 -128.858197) (xy 104.955738 -128.817006) (xy 104.996929 -128.781315) (xy 105.042779 -128.751849)
			(xy 105.092356 -128.729207) (xy 105.144651 -128.713852) (xy 105.198599 -128.706096) (xy 105.253101 -128.706096)
			(xy 105.307049 -128.713852) (xy 105.359344 -128.729207) (xy 105.408921 -128.751849) (xy 105.454771 -128.781315)
			(xy 105.495962 -128.817006) (xy 105.531653 -128.858197) (xy 105.561119 -128.904047) (xy 105.583761 -128.953624)
			(xy 105.599116 -129.005919) (xy 105.606872 -129.059867) (xy 105.607358 -129.087118) (xy 105.606913 -129.114489)
			(xy 105.599091 -129.168669) (xy 105.583598 -129.221173) (xy 105.560751 -129.27092) (xy 105.531022 -129.316885)
			(xy 105.513378 -129.337816) (xy 105.513124 -129.33807) (xy 105.507535 -129.345155) (xy 105.501292 -129.362073)
			(xy 105.500932 -129.37109) (xy 105.500932 -129.438146) (xy 105.501308 -129.447161) (xy 105.507542 -129.464079)
			(xy 105.513124 -129.471166) (xy 105.513378 -129.471166) (xy 105.513378 -129.47142) (xy 105.531036 -129.492339)
			(xy 105.56076 -129.538309) (xy 105.583604 -129.588058) (xy 105.599098 -129.640562) (xy 105.606925 -129.694742)
			(xy 105.606923 -129.749485) (xy 105.599093 -129.803665) (xy 105.583594 -129.856168) (xy 105.560747 -129.905915)
			(xy 105.53102 -129.951883) (xy 105.513378 -129.972816) (xy 105.513124 -129.97307) (xy 105.507535 -129.980155)
			(xy 105.501292 -129.997073) (xy 105.500932 -130.00609) (xy 105.500932 -130.073146) (xy 105.501308 -130.082161)
			(xy 105.507542 -130.099079) (xy 105.513124 -130.106166) (xy 105.513378 -130.106166) (xy 105.513378 -130.10642)
			(xy 105.531036 -130.127339) (xy 105.56076 -130.173309) (xy 105.583604 -130.223058) (xy 105.599098 -130.275562)
			(xy 105.606925 -130.329742) (xy 105.606923 -130.384485) (xy 105.599093 -130.438665) (xy 105.583594 -130.491168)
			(xy 105.560747 -130.540915) (xy 105.53102 -130.586883) (xy 105.513378 -130.607816) (xy 105.513124 -130.60807)
			(xy 105.507535 -130.615155) (xy 105.501292 -130.632073) (xy 105.500932 -130.64109) (xy 105.500932 -130.708146)
			(xy 105.501308 -130.717161) (xy 105.507542 -130.734079) (xy 105.513124 -130.741166) (xy 105.513378 -130.741166)
			(xy 105.513378 -130.74142) (xy 105.53099 -130.762374) (xy 105.560706 -130.808341) (xy 105.583548 -130.858082)
			(xy 105.599045 -130.910578) (xy 105.60688 -130.96475) (xy 105.607358 -130.992118) (xy 105.606872 -131.019369)
			(xy 105.602208 -131.051808) (xy 107.500166 -131.051808) (xy 107.500621 -131.024437) (xy 107.508439 -130.970257)
			(xy 107.52393 -130.917753) (xy 107.546774 -130.868006) (xy 107.576503 -130.822041) (xy 107.594146 -130.80111)
			(xy 107.5944 -130.800856) (xy 107.599969 -130.793758) (xy 107.606226 -130.77685) (xy 107.606592 -130.767836)
			(xy 107.606592 -130.70078) (xy 107.606246 -130.691762) (xy 107.599991 -130.674845) (xy 107.5944 -130.66776)
			(xy 107.594146 -130.66776) (xy 107.594146 -130.667506) (xy 107.576512 -130.646567) (xy 107.546786 -130.600601)
			(xy 107.523939 -130.550856) (xy 107.508441 -130.498355) (xy 107.500611 -130.444176) (xy 107.50061 -130.389436)
			(xy 107.508439 -130.335257) (xy 107.523935 -130.282755) (xy 107.54678 -130.23301) (xy 107.576505 -130.187042)
			(xy 107.594146 -130.16611) (xy 107.5944 -130.165856) (xy 107.599969 -130.158758) (xy 107.606226 -130.14185)
			(xy 107.606592 -130.132836) (xy 107.606592 -130.06578) (xy 107.606246 -130.056762) (xy 107.599991 -130.039845)
			(xy 107.5944 -130.03276) (xy 107.594146 -130.03276) (xy 107.594146 -130.032506) (xy 107.576503 -130.011577)
			(xy 107.546791 -129.965604) (xy 107.523955 -129.915856) (xy 107.508464 -129.863354) (xy 107.500638 -129.809177)
			(xy 107.500166 -129.781808) (xy 107.50065 -129.755495) (xy 107.507883 -129.703367) (xy 107.522199 -129.652725)
			(xy 107.543329 -129.604527) (xy 107.570871 -129.559683) (xy 107.604306 -129.519042) (xy 107.623356 -129.500884)
			(xy 107.63076 -129.493364) (xy 107.639284 -129.474083) (xy 107.639866 -129.463546) (xy 107.639866 -129.38887)
			(xy 107.639323 -129.378322) (xy 107.630799 -129.359026) (xy 107.623356 -129.351532) (xy 107.604266 -129.333411)
			(xy 107.570814 -129.292773) (xy 107.54326 -129.247925) (xy 107.522128 -129.199718) (xy 107.507818 -129.149065)
			(xy 107.500601 -129.096926) (xy 107.500166 -129.070608) (xy 107.500685 -129.043358) (xy 107.50844 -128.989413)
			(xy 107.523793 -128.93712) (xy 107.546431 -128.887545) (xy 107.575894 -128.841696) (xy 107.611582 -128.800506)
			(xy 107.652768 -128.764814) (xy 107.698615 -128.735347) (xy 107.748188 -128.712705) (xy 107.80048 -128.697347)
			(xy 107.854424 -128.689588) (xy 107.881674 -128.6891) (xy 107.881928 -128.6891) (xy 107.910131 -128.689598)
			(xy 107.965919 -128.697928) (xy 108.019875 -128.714372) (xy 108.070826 -128.738574) (xy 108.094526 -128.75387)
			(xy 108.106464 -128.761998) (xy 108.134658 -128.763268) (xy 108.226606 -128.712722) (xy 108.234549 -128.707863)
			(xy 108.246531 -128.693631) (xy 108.252641 -128.676059) (xy 108.252768 -128.666748) (xy 108.252514 -128.656334)
			(xy 108.252514 -128.655826) (xy 108.252977 -128.628585) (xy 108.260766 -128.574662) (xy 108.276147 -128.522396)
			(xy 108.298806 -128.472849) (xy 108.328283 -128.42703) (xy 108.363979 -128.385869) (xy 108.405167 -128.350206)
			(xy 108.451009 -128.320764) (xy 108.500574 -128.298143) (xy 108.552852 -128.282803) (xy 108.606781 -128.275055)
			(xy 108.634022 -128.274572) (xy 108.661273 -128.275057) (xy 108.71522 -128.282816) (xy 108.767513 -128.298173)
			(xy 108.817089 -128.320815) (xy 108.862938 -128.350282) (xy 108.904128 -128.385974) (xy 108.939819 -128.427163)
			(xy 108.969286 -128.473013) (xy 108.991928 -128.522589) (xy 109.007284 -128.574882) (xy 109.015043 -128.628829)
			(xy 109.01553 -128.65608) (xy 109.015468 -128.659757) (xy 112.065713 -128.659757) (xy 112.065713 -128.605243)
			(xy 112.073471 -128.551285) (xy 112.08883 -128.49898) (xy 112.111476 -128.449393) (xy 112.140949 -128.403534)
			(xy 112.176648 -128.362337) (xy 112.217847 -128.326639) (xy 112.263707 -128.297168) (xy 112.313295 -128.274524)
			(xy 112.365601 -128.259168) (xy 112.419559 -128.251412) (xy 112.446816 -128.25095) (xy 112.474761 -128.251422)
			(xy 112.530052 -128.259585) (xy 112.583563 -128.275721) (xy 112.63415 -128.299484) (xy 112.680732 -128.330367)
			(xy 112.722316 -128.36771) (xy 112.758013 -128.410716) (xy 112.772952 -128.434338) (xy 112.777728 -128.441604)
			(xy 112.791113 -128.452676) (xy 112.807448 -128.458587) (xy 112.816132 -128.458976) (xy 112.915954 -128.459738)
			(xy 112.938814 -128.447038) (xy 112.945926 -128.435608) (xy 112.960922 -128.412462) (xy 112.996616 -128.370417)
			(xy 113.037993 -128.333951) (xy 113.08419 -128.303823) (xy 113.134244 -128.280663) (xy 113.187112 -128.264953)
			(xy 113.241692 -128.25702) (xy 113.269268 -128.256538) (xy 113.296638 -128.257014) (xy 113.350817 -128.264828)
			(xy 113.40332 -128.280314) (xy 113.453067 -128.303154) (xy 113.499034 -128.332877) (xy 113.519966 -128.350518)
			(xy 113.52022 -128.350772) (xy 113.527291 -128.356382) (xy 113.54422 -128.362612) (xy 113.55324 -128.362964)
			(xy 113.620296 -128.362964) (xy 113.629314 -128.362613) (xy 113.646231 -128.356362) (xy 113.653316 -128.350772)
			(xy 113.653316 -128.350518) (xy 113.65357 -128.350518) (xy 113.674503 -128.332877) (xy 113.720471 -128.303153)
			(xy 113.770217 -128.280307) (xy 113.822719 -128.264811) (xy 113.876897 -128.256982) (xy 113.931639 -128.256982)
			(xy 113.985817 -128.264811) (xy 114.038319 -128.280307) (xy 114.088065 -128.303153) (xy 114.134033 -128.332877)
			(xy 114.154966 -128.350518) (xy 114.15522 -128.350772) (xy 114.162291 -128.356382) (xy 114.17922 -128.362612)
			(xy 114.18824 -128.362964) (xy 114.255296 -128.362964) (xy 114.264314 -128.362613) (xy 114.281231 -128.356362)
			(xy 114.288316 -128.350772) (xy 114.288316 -128.350518) (xy 114.28857 -128.350518) (xy 114.309505 -128.332882)
			(xy 114.355477 -128.303169) (xy 114.405223 -128.280332) (xy 114.457724 -128.264841) (xy 114.511899 -128.257012)
			(xy 114.539268 -128.256538) (xy 114.566526 -128.256907) (xy 114.620487 -128.264661) (xy 114.672795 -128.280016)
			(xy 114.722385 -128.30266) (xy 114.768248 -128.33213) (xy 114.809449 -128.367828) (xy 114.845151 -128.409027)
			(xy 114.874625 -128.454887) (xy 114.897273 -128.504475) (xy 114.912632 -128.556782) (xy 114.920391 -128.610742)
			(xy 114.920391 -128.665258) (xy 114.912632 -128.719218) (xy 114.897273 -128.771525) (xy 114.874625 -128.821113)
			(xy 114.845151 -128.866973) (xy 114.809449 -128.908172) (xy 114.768248 -128.94387) (xy 114.761936 -128.947926)
			(xy 118.631714 -128.947926) (xy 118.635785 -128.892304) (xy 118.647911 -128.837867) (xy 118.667834 -128.785776)
			(xy 118.69513 -128.737141) (xy 118.729216 -128.692998) (xy 118.769365 -128.654289) (xy 118.814723 -128.621838)
			(xy 118.864323 -128.596337) (xy 118.917107 -128.57833) (xy 118.97195 -128.5682) (xy 119.027684 -128.566163)
			(xy 119.083121 -128.572263) (xy 119.137078 -128.586369) (xy 119.188407 -128.608181) (xy 119.236013 -128.637235)
			(xy 119.278881 -128.67291) (xy 119.316098 -128.714447) (xy 119.346871 -128.76096) (xy 119.370543 -128.811457)
			(xy 119.386611 -128.864864) (xy 119.394731 -128.92004) (xy 119.39524 -128.947926) (xy 119.394731 -128.975812)
			(xy 119.386611 -129.030988) (xy 119.370543 -129.084395) (xy 119.346871 -129.134892) (xy 119.316098 -129.181405)
			(xy 119.278881 -129.222942) (xy 119.236013 -129.258617) (xy 119.188407 -129.287671) (xy 119.137078 -129.309483)
			(xy 119.083121 -129.323589) (xy 119.027684 -129.329689) (xy 118.97195 -129.327652) (xy 118.917107 -129.317522)
			(xy 118.864323 -129.299515) (xy 118.814723 -129.274014) (xy 118.769365 -129.241563) (xy 118.729216 -129.202854)
			(xy 118.69513 -129.158711) (xy 118.667834 -129.110076) (xy 118.647911 -129.057985) (xy 118.635785 -129.003548)
			(xy 118.631714 -128.947926) (xy 114.761936 -128.947926) (xy 114.722385 -128.97334) (xy 114.672795 -128.995984)
			(xy 114.620487 -129.011339) (xy 114.566526 -129.019093) (xy 114.539268 -129.019554) (xy 114.511897 -129.019118)
			(xy 114.457716 -129.011295) (xy 114.405212 -128.995799) (xy 114.355465 -128.97295) (xy 114.3095 -128.943219)
			(xy 114.28857 -128.925574) (xy 114.288316 -128.92532) (xy 114.281236 -128.919725) (xy 114.264314 -128.913485)
			(xy 114.255296 -128.913128) (xy 114.18824 -128.913128) (xy 114.179224 -128.913498) (xy 114.162307 -128.919736)
			(xy 114.15522 -128.92532) (xy 114.15522 -128.925574) (xy 114.154966 -128.925574) (xy 114.134033 -128.943215)
			(xy 114.088065 -128.972939) (xy 114.038319 -128.995785) (xy 113.985817 -129.011281) (xy 113.931639 -129.01911)
			(xy 113.876897 -129.01911) (xy 113.822719 -129.011281) (xy 113.770217 -128.995785) (xy 113.720471 -128.972939)
			(xy 113.674503 -128.943215) (xy 113.65357 -128.925574) (xy 113.653316 -128.92532) (xy 113.646236 -128.919725)
			(xy 113.629314 -128.913485) (xy 113.620296 -128.913128) (xy 113.55324 -128.913128) (xy 113.544224 -128.913498)
			(xy 113.527307 -128.919736) (xy 113.52022 -128.92532) (xy 113.52022 -128.925574) (xy 113.519966 -128.925574)
			(xy 113.499017 -128.943192) (xy 113.453049 -128.972908) (xy 113.403306 -128.995748) (xy 113.350809 -129.011244)
			(xy 113.296636 -129.019077) (xy 113.269268 -129.019554) (xy 113.241323 -129.019093) (xy 113.186031 -129.010927)
			(xy 113.132521 -128.994789) (xy 113.081934 -128.971024) (xy 113.035351 -128.94014) (xy 112.993767 -128.902795)
			(xy 112.958071 -128.859788) (xy 112.943132 -128.836166) (xy 112.938395 -128.828873) (xy 112.924988 -128.817813)
			(xy 112.908641 -128.811913) (xy 112.899952 -128.811528) (xy 112.80013 -128.810766) (xy 112.77727 -128.823466)
			(xy 112.770158 -128.834896) (xy 112.755073 -128.857982) (xy 112.719397 -128.900032) (xy 112.678037 -128.936506)
			(xy 112.631855 -128.966642) (xy 112.581814 -128.989812) (xy 112.528958 -129.005533) (xy 112.474388 -129.013478)
			(xy 112.446816 -129.013966) (xy 112.419559 -129.013588) (xy 112.365601 -129.005832) (xy 112.313295 -128.990476)
			(xy 112.263707 -128.967832) (xy 112.217847 -128.938361) (xy 112.176648 -128.902663) (xy 112.140949 -128.861466)
			(xy 112.111476 -128.815607) (xy 112.08883 -128.76602) (xy 112.073471 -128.713715) (xy 112.065713 -128.659757)
			(xy 109.015468 -128.659757) (xy 109.015069 -128.683451) (xy 109.007253 -128.737631) (xy 108.991763 -128.790134)
			(xy 108.96892 -128.839881) (xy 108.939193 -128.885847) (xy 108.92155 -128.906778) (xy 108.921296 -128.907032)
			(xy 108.915731 -128.914134) (xy 108.909472 -128.931039) (xy 108.909104 -128.940052) (xy 108.909104 -129.007108)
			(xy 108.909456 -129.016125) (xy 108.915707 -129.033042) (xy 108.921296 -129.040128) (xy 108.92155 -129.040128)
			(xy 108.92155 -129.040382) (xy 108.939186 -129.061316) (xy 108.9689 -129.107288) (xy 108.991738 -129.157035)
			(xy 109.007229 -129.209535) (xy 109.015057 -129.263711) (xy 109.01553 -129.29108) (xy 109.015003 -129.31833)
			(xy 109.00725 -129.372275) (xy 108.991899 -129.424567) (xy 108.975467 -129.460553) (xy 110.320775 -129.460553)
			(xy 110.320775 -129.406047) (xy 110.328533 -129.352096) (xy 110.34389 -129.299798) (xy 110.366534 -129.250218)
			(xy 110.396004 -129.204365) (xy 110.431699 -129.163174) (xy 110.472894 -129.127482) (xy 110.518749 -129.098017)
			(xy 110.568331 -129.075377) (xy 110.620631 -129.060025) (xy 110.674583 -129.052273) (xy 110.701836 -129.051812)
			(xy 110.729697 -129.052353) (xy 110.784822 -129.060485) (xy 110.838185 -129.076528) (xy 110.863634 -129.08788)
			(xy 110.872524 -129.092198) (xy 110.89259 -129.093214) (xy 110.97895 -129.062226) (xy 110.993936 -129.049018)
			(xy 110.998254 -129.040382) (xy 110.998254 -129.039874) (xy 111.010259 -129.015994) (xy 111.040017 -128.971594)
			(xy 111.075682 -128.931785) (xy 111.116556 -128.897344) (xy 111.161839 -128.868947) (xy 111.210642 -128.84715)
			(xy 111.26201 -128.83238) (xy 111.314937 -128.824927) (xy 111.341662 -128.824482) (xy 111.368913 -128.824991)
			(xy 111.422862 -128.832742) (xy 111.475159 -128.848093) (xy 111.524738 -128.87073) (xy 111.570591 -128.900193)
			(xy 111.611784 -128.935882) (xy 111.647478 -128.977071) (xy 111.676947 -129.02292) (xy 111.69959 -129.072496)
			(xy 111.714948 -129.124791) (xy 111.722706 -129.178739) (xy 111.72317 -129.20599) (xy 111.722706 -129.23191)
			(xy 111.715676 -129.283272) (xy 111.701759 -129.33321) (xy 111.68121 -129.380804) (xy 111.663911 -129.409444)
			(xy 116.367812 -129.409444) (xy 116.371883 -129.353822) (xy 116.384009 -129.299385) (xy 116.403932 -129.247294)
			(xy 116.431228 -129.198659) (xy 116.465314 -129.154516) (xy 116.505463 -129.115807) (xy 116.550821 -129.083356)
			(xy 116.600421 -129.057855) (xy 116.653205 -129.039848) (xy 116.708048 -129.029718) (xy 116.763782 -129.027681)
			(xy 116.819219 -129.033781) (xy 116.873176 -129.047887) (xy 116.924505 -129.069699) (xy 116.972111 -129.098753)
			(xy 117.014979 -129.134428) (xy 117.052196 -129.175965) (xy 117.082969 -129.222478) (xy 117.106641 -129.272975)
			(xy 117.122709 -129.326382) (xy 117.130829 -129.381558) (xy 117.131338 -129.409444) (xy 117.130829 -129.43733)
			(xy 117.122709 -129.492506) (xy 117.106641 -129.545913) (xy 117.087504 -129.586736) (xy 117.524528 -129.586736)
			(xy 117.528599 -129.531114) (xy 117.540725 -129.476677) (xy 117.560648 -129.424586) (xy 117.587944 -129.375951)
			(xy 117.62203 -129.331808) (xy 117.662179 -129.293099) (xy 117.707537 -129.260648) (xy 117.757137 -129.235147)
			(xy 117.809921 -129.21714) (xy 117.864764 -129.20701) (xy 117.920498 -129.204973) (xy 117.975935 -129.211073)
			(xy 118.029892 -129.225179) (xy 118.081221 -129.246991) (xy 118.128827 -129.276045) (xy 118.171695 -129.31172)
			(xy 118.208912 -129.353257) (xy 118.239685 -129.39977) (xy 118.263357 -129.450267) (xy 118.279425 -129.503674)
			(xy 118.287545 -129.55885) (xy 118.288054 -129.586736) (xy 118.287545 -129.614622) (xy 118.279425 -129.669798)
			(xy 118.263357 -129.723205) (xy 118.239685 -129.773702) (xy 118.208912 -129.820215) (xy 118.171695 -129.861752)
			(xy 118.128827 -129.897427) (xy 118.081221 -129.926481) (xy 118.029892 -129.948293) (xy 117.975935 -129.962399)
			(xy 117.920498 -129.968499) (xy 117.864764 -129.966462) (xy 117.809921 -129.956332) (xy 117.757137 -129.938325)
			(xy 117.707537 -129.912824) (xy 117.662179 -129.880373) (xy 117.62203 -129.841664) (xy 117.587944 -129.797521)
			(xy 117.560648 -129.748886) (xy 117.540725 -129.696795) (xy 117.528599 -129.642358) (xy 117.524528 -129.586736)
			(xy 117.087504 -129.586736) (xy 117.082969 -129.59641) (xy 117.052196 -129.642923) (xy 117.014979 -129.68446)
			(xy 116.972111 -129.720135) (xy 116.924505 -129.749189) (xy 116.873176 -129.771001) (xy 116.819219 -129.785107)
			(xy 116.763782 -129.791207) (xy 116.708048 -129.78917) (xy 116.653205 -129.77904) (xy 116.600421 -129.761033)
			(xy 116.550821 -129.735532) (xy 116.505463 -129.703081) (xy 116.465314 -129.664372) (xy 116.431228 -129.620229)
			(xy 116.403932 -129.571594) (xy 116.384009 -129.519503) (xy 116.371883 -129.465066) (xy 116.367812 -129.409444)
			(xy 111.663911 -129.409444) (xy 111.654408 -129.425178) (xy 111.621846 -129.465517) (xy 111.603282 -129.483612)
			(xy 111.603028 -129.483866) (xy 111.595801 -129.491449) (xy 111.587679 -129.510736) (xy 111.58728 -129.521204)
			(xy 111.58855 -129.596388) (xy 111.589251 -129.606881) (xy 111.597888 -129.626028) (xy 111.605314 -129.633472)
			(xy 111.605568 -129.633726) (xy 111.625388 -129.651915) (xy 111.660244 -129.692887) (xy 111.689 -129.738349)
			(xy 111.711084 -129.7874) (xy 111.726058 -129.839067) (xy 111.733625 -129.892326) (xy 111.734092 -129.919222)
			(xy 111.733643 -129.946475) (xy 111.732957 -129.951246) (xy 112.909426 -129.951246) (xy 112.909426 -129.896754)
			(xy 112.91718 -129.842818) (xy 112.932531 -129.790534) (xy 112.955166 -129.740966) (xy 112.984623 -129.695124)
			(xy 113.020305 -129.65394) (xy 113.061484 -129.618253) (xy 113.107322 -129.58879) (xy 113.156887 -129.566148)
			(xy 113.209169 -129.550791) (xy 113.263105 -129.54303) (xy 113.29035 -129.54254) (xy 113.31772 -129.543026)
			(xy 113.371898 -129.550837) (xy 113.424402 -129.566321) (xy 113.474149 -129.589159) (xy 113.520116 -129.61888)
			(xy 113.541048 -129.63652) (xy 113.541302 -129.636774) (xy 113.548378 -129.642376) (xy 113.565303 -129.648612)
			(xy 113.574322 -129.648966) (xy 113.641378 -129.648966) (xy 113.650395 -129.648606) (xy 113.667312 -129.642361)
			(xy 113.674398 -129.636774) (xy 113.674398 -129.63652) (xy 113.674652 -129.63652) (xy 113.695594 -129.618893)
			(xy 113.741564 -129.589179) (xy 113.791309 -129.56634) (xy 113.843807 -129.550846) (xy 113.897981 -129.543015)
			(xy 113.92535 -129.54254) (xy 113.952609 -129.542904) (xy 114.006572 -129.550656) (xy 114.058882 -129.566009)
			(xy 114.108475 -129.588652) (xy 114.15434 -129.618122) (xy 114.195544 -129.65382) (xy 114.231248 -129.69502)
			(xy 114.260724 -129.740881) (xy 114.283373 -129.790471) (xy 114.298734 -129.842779) (xy 114.306493 -129.896741)
			(xy 114.306493 -129.951259) (xy 114.298734 -130.005221) (xy 114.283373 -130.057529) (xy 114.260724 -130.107119)
			(xy 114.231248 -130.15298) (xy 114.195544 -130.19418) (xy 114.168135 -130.217926) (xy 118.631714 -130.217926)
			(xy 118.635785 -130.162304) (xy 118.647911 -130.107867) (xy 118.667834 -130.055776) (xy 118.69513 -130.007141)
			(xy 118.729216 -129.962998) (xy 118.769365 -129.924289) (xy 118.814723 -129.891838) (xy 118.864323 -129.866337)
			(xy 118.917107 -129.84833) (xy 118.97195 -129.8382) (xy 119.027684 -129.836163) (xy 119.083121 -129.842263)
			(xy 119.137078 -129.856369) (xy 119.188407 -129.878181) (xy 119.236013 -129.907235) (xy 119.278881 -129.94291)
			(xy 119.316098 -129.984447) (xy 119.346871 -130.03096) (xy 119.370543 -130.081457) (xy 119.386611 -130.134864)
			(xy 119.394731 -130.19004) (xy 119.39524 -130.217926) (xy 119.394731 -130.245812) (xy 119.386611 -130.300988)
			(xy 119.370543 -130.354395) (xy 119.346871 -130.404892) (xy 119.316098 -130.451405) (xy 119.278881 -130.492942)
			(xy 119.236013 -130.528617) (xy 119.188407 -130.557671) (xy 119.137078 -130.579483) (xy 119.083121 -130.593589)
			(xy 119.027684 -130.599689) (xy 118.97195 -130.597652) (xy 118.917107 -130.587522) (xy 118.864323 -130.569515)
			(xy 118.814723 -130.544014) (xy 118.769365 -130.511563) (xy 118.729216 -130.472854) (xy 118.69513 -130.428711)
			(xy 118.667834 -130.380076) (xy 118.647911 -130.327985) (xy 118.635785 -130.273548) (xy 118.631714 -130.217926)
			(xy 114.168135 -130.217926) (xy 114.15434 -130.229878) (xy 114.108475 -130.259348) (xy 114.058882 -130.281991)
			(xy 114.006572 -130.297344) (xy 113.952609 -130.305096) (xy 113.92535 -130.305556) (xy 113.89798 -130.305071)
			(xy 113.843802 -130.29726) (xy 113.791298 -130.281776) (xy 113.741551 -130.258938) (xy 113.695584 -130.229216)
			(xy 113.674652 -130.211576) (xy 113.674398 -130.211322) (xy 113.667323 -130.205719) (xy 113.650397 -130.199484)
			(xy 113.641378 -130.19913) (xy 113.574322 -130.19913) (xy 113.565305 -130.199491) (xy 113.548388 -130.205735)
			(xy 113.541302 -130.211322) (xy 113.541302 -130.211576) (xy 113.541048 -130.211576) (xy 113.520106 -130.229202)
			(xy 113.474136 -130.258917) (xy 113.424391 -130.281756) (xy 113.371893 -130.29725) (xy 113.317719 -130.305081)
			(xy 113.29035 -130.305556) (xy 113.263105 -130.30497) (xy 113.209169 -130.297209) (xy 113.156887 -130.281852)
			(xy 113.107322 -130.259211) (xy 113.061484 -130.229747) (xy 113.020305 -130.19406) (xy 112.984623 -130.152876)
			(xy 112.955166 -130.107034) (xy 112.932531 -130.057466) (xy 112.91718 -130.005182) (xy 112.909426 -129.951246)
			(xy 111.732957 -129.951246) (xy 111.725883 -130.000424) (xy 111.710524 -130.052721) (xy 111.687879 -130.102299)
			(xy 111.658409 -130.14815) (xy 111.622714 -130.189341) (xy 111.58152 -130.225032) (xy 111.535666 -130.254497)
			(xy 111.486085 -130.277137) (xy 111.433787 -130.292491) (xy 111.379837 -130.300245) (xy 111.352584 -130.30073)
			(xy 111.325345 -130.300238) (xy 111.271421 -130.292487) (xy 111.219148 -130.277143) (xy 111.169589 -130.25452)
			(xy 111.123752 -130.225078) (xy 111.082569 -130.189415) (xy 111.046878 -130.148256) (xy 111.017404 -130.10244)
			(xy 110.994748 -130.052896) (xy 110.979369 -130.000633) (xy 110.971581 -129.946715) (xy 110.971076 -129.919476)
			(xy 110.971076 -129.918968) (xy 110.972092 -129.89306) (xy 110.972092 -129.892806) (xy 110.972165 -129.880091)
			(xy 110.96151 -129.85704) (xy 110.951772 -129.848864) (xy 110.872778 -129.789936) (xy 110.847378 -129.786126)
			(xy 110.835186 -129.790698) (xy 110.802993 -129.801912) (xy 110.735918 -129.814051) (xy 110.701836 -129.814828)
			(xy 110.674583 -129.814327) (xy 110.620631 -129.806575) (xy 110.568331 -129.791223) (xy 110.518749 -129.768583)
			(xy 110.472894 -129.739118) (xy 110.431699 -129.703426) (xy 110.396004 -129.662235) (xy 110.366534 -129.616382)
			(xy 110.34389 -129.566802) (xy 110.328533 -129.514504) (xy 110.320775 -129.460553) (xy 108.975467 -129.460553)
			(xy 108.969261 -129.474143) (xy 108.939799 -129.519992) (xy 108.904112 -129.561182) (xy 108.862926 -129.596874)
			(xy 108.81708 -129.626341) (xy 108.767507 -129.648984) (xy 108.715216 -129.664341) (xy 108.661272 -129.6721)
			(xy 108.634022 -129.672588) (xy 108.606916 -129.672096) (xy 108.553249 -129.664424) (xy 108.501209 -129.649231)
			(xy 108.451844 -129.626824) (xy 108.406149 -129.597653) (xy 108.365043 -129.562308) (xy 108.329356 -129.521498)
			(xy 108.299806 -129.476047) (xy 108.276988 -129.426871) (xy 108.261362 -129.374959) (xy 108.256832 -129.34823)
			(xy 108.255014 -129.338753) (xy 108.245248 -129.322122) (xy 108.230039 -129.310262) (xy 108.211529 -129.304843)
			(xy 108.192325 -129.306628) (xy 108.175132 -129.315366) (xy 108.16844 -129.322322) (xy 108.161675 -129.329954)
			(xy 108.14744 -129.344565) (xy 108.139992 -129.351532) (xy 108.132573 -129.359039) (xy 108.124059 -129.37833)
			(xy 108.123482 -129.38887) (xy 108.123482 -129.463546) (xy 108.124032 -129.474093) (xy 108.132553 -129.493388)
			(xy 108.139992 -129.500884) (xy 108.159031 -129.519056) (xy 108.19249 -129.559682) (xy 108.220052 -129.604519)
			(xy 108.241193 -129.652716) (xy 108.255513 -129.703361) (xy 108.262742 -129.755493) (xy 108.263182 -129.781808)
			(xy 108.262725 -129.809179) (xy 108.254906 -129.863358) (xy 108.239415 -129.915862) (xy 108.216571 -129.965608)
			(xy 108.186844 -130.011575) (xy 108.169202 -130.032506) (xy 108.168948 -130.03276) (xy 108.163366 -130.039849)
			(xy 108.157118 -130.056764) (xy 108.156756 -130.06578) (xy 108.156756 -130.132836) (xy 108.157083 -130.141856)
			(xy 108.16335 -130.158774) (xy 108.168948 -130.165856) (xy 108.169202 -130.165856) (xy 108.169202 -130.16611)
			(xy 108.186849 -130.187037) (xy 108.216572 -130.233006) (xy 108.239415 -130.282754) (xy 108.254909 -130.335257)
			(xy 108.262736 -130.389435) (xy 108.262735 -130.444177) (xy 108.254907 -130.498355) (xy 108.23941 -130.550857)
			(xy 108.216566 -130.600604) (xy 108.186842 -130.646573) (xy 108.169202 -130.667506) (xy 108.168948 -130.66776)
			(xy 108.163366 -130.674849) (xy 108.157118 -130.691764) (xy 108.156756 -130.70078) (xy 108.156756 -130.767836)
			(xy 108.157083 -130.776856) (xy 108.16335 -130.793774) (xy 108.168948 -130.800856) (xy 108.169202 -130.800856)
			(xy 108.169202 -130.80111) (xy 108.18686 -130.822027) (xy 108.216569 -130.868004) (xy 108.239401 -130.917755)
			(xy 108.254888 -130.970259) (xy 108.262711 -131.024438) (xy 108.263182 -131.051808) (xy 108.262696 -131.079059)
			(xy 108.25494 -131.133007) (xy 108.254543 -131.134358) (xy 109.523782 -131.134358) (xy 109.527853 -131.078736)
			(xy 109.539979 -131.024299) (xy 109.559902 -130.972208) (xy 109.587198 -130.923573) (xy 109.621284 -130.87943)
			(xy 109.661433 -130.840721) (xy 109.706791 -130.80827) (xy 109.756391 -130.782769) (xy 109.809175 -130.764762)
			(xy 109.864018 -130.754632) (xy 109.919752 -130.752595) (xy 109.975189 -130.758695) (xy 110.029146 -130.772801)
			(xy 110.080475 -130.794613) (xy 110.128081 -130.823667) (xy 110.170949 -130.859342) (xy 110.208166 -130.900879)
			(xy 110.238939 -130.947392) (xy 110.262611 -130.997889) (xy 110.278679 -131.051296) (xy 110.286799 -131.106472)
			(xy 110.287308 -131.134358) (xy 110.286799 -131.162244) (xy 110.278679 -131.21742) (xy 110.278298 -131.218686)
			(xy 118.631714 -131.218686) (xy 118.635785 -131.163064) (xy 118.647911 -131.108627) (xy 118.667834 -131.056536)
			(xy 118.69513 -131.007901) (xy 118.729216 -130.963758) (xy 118.769365 -130.925049) (xy 118.814723 -130.892598)
			(xy 118.864323 -130.867097) (xy 118.917107 -130.84909) (xy 118.97195 -130.83896) (xy 119.027684 -130.836923)
			(xy 119.083121 -130.843023) (xy 119.137078 -130.857129) (xy 119.188407 -130.878941) (xy 119.236013 -130.907995)
			(xy 119.278881 -130.94367) (xy 119.316098 -130.985207) (xy 119.346871 -131.03172) (xy 119.370543 -131.082217)
			(xy 119.386611 -131.135624) (xy 119.394731 -131.1908) (xy 119.39524 -131.218686) (xy 119.394731 -131.246572)
			(xy 119.386611 -131.301748) (xy 119.370543 -131.355155) (xy 119.346871 -131.405652) (xy 119.316098 -131.452165)
			(xy 119.278881 -131.493702) (xy 119.236013 -131.529377) (xy 119.188407 -131.558431) (xy 119.137078 -131.580243)
			(xy 119.083121 -131.594349) (xy 119.027684 -131.600449) (xy 118.97195 -131.598412) (xy 118.917107 -131.588282)
			(xy 118.864323 -131.570275) (xy 118.814723 -131.544774) (xy 118.769365 -131.512323) (xy 118.729216 -131.473614)
			(xy 118.69513 -131.429471) (xy 118.667834 -131.380836) (xy 118.647911 -131.328745) (xy 118.635785 -131.274308)
			(xy 118.631714 -131.218686) (xy 110.278298 -131.218686) (xy 110.262611 -131.270827) (xy 110.238939 -131.321324)
			(xy 110.208166 -131.367837) (xy 110.170949 -131.409374) (xy 110.128081 -131.445049) (xy 110.080475 -131.474103)
			(xy 110.029146 -131.495915) (xy 109.975189 -131.510021) (xy 109.919752 -131.516121) (xy 109.864018 -131.514084)
			(xy 109.809175 -131.503954) (xy 109.756391 -131.485947) (xy 109.706791 -131.460446) (xy 109.661433 -131.427995)
			(xy 109.621284 -131.389286) (xy 109.587198 -131.345143) (xy 109.559902 -131.296508) (xy 109.539979 -131.244417)
			(xy 109.527853 -131.18998) (xy 109.523782 -131.134358) (xy 108.254543 -131.134358) (xy 108.239585 -131.185302)
			(xy 108.216943 -131.234879) (xy 108.187477 -131.280729) (xy 108.151786 -131.32192) (xy 108.110595 -131.357611)
			(xy 108.064745 -131.387077) (xy 108.015168 -131.409719) (xy 107.962873 -131.425074) (xy 107.908925 -131.43283)
			(xy 107.854423 -131.43283) (xy 107.800475 -131.425074) (xy 107.74818 -131.409719) (xy 107.698603 -131.387077)
			(xy 107.652753 -131.357611) (xy 107.611562 -131.32192) (xy 107.575871 -131.280729) (xy 107.546405 -131.234879)
			(xy 107.523763 -131.185302) (xy 107.508408 -131.133007) (xy 107.500652 -131.079059) (xy 107.500166 -131.051808)
			(xy 105.602208 -131.051808) (xy 105.599116 -131.073317) (xy 105.583761 -131.125612) (xy 105.561119 -131.175189)
			(xy 105.531653 -131.221039) (xy 105.495962 -131.26223) (xy 105.454771 -131.297921) (xy 105.408921 -131.327387)
			(xy 105.359344 -131.350029) (xy 105.307049 -131.365384) (xy 105.253101 -131.37314) (xy 105.198599 -131.37314)
			(xy 105.144651 -131.365384) (xy 105.092356 -131.350029) (xy 105.042779 -131.327387) (xy 104.996929 -131.297921)
			(xy 104.955738 -131.26223) (xy 104.920047 -131.221039) (xy 104.890581 -131.175189) (xy 104.867939 -131.125612)
			(xy 104.852584 -131.073317) (xy 104.844828 -131.019369) (xy 104.844342 -130.992118) (xy 91.654122 -130.992118)
			(xy 91.654122 -131.560316) (xy 94.487998 -131.560316) (xy 94.492069 -131.504694) (xy 94.504195 -131.450257)
			(xy 94.524118 -131.398166) (xy 94.551414 -131.349531) (xy 94.5855 -131.305388) (xy 94.625649 -131.266679)
			(xy 94.671007 -131.234228) (xy 94.720607 -131.208727) (xy 94.773391 -131.19072) (xy 94.828234 -131.18059)
			(xy 94.883968 -131.178553) (xy 94.939405 -131.184653) (xy 94.993362 -131.198759) (xy 95.044691 -131.220571)
			(xy 95.092297 -131.249625) (xy 95.135165 -131.2853) (xy 95.172382 -131.326837) (xy 95.203155 -131.37335)
			(xy 95.226827 -131.423847) (xy 95.242895 -131.477254) (xy 95.251015 -131.53243) (xy 95.251524 -131.560316)
			(xy 95.251015 -131.588202) (xy 95.242895 -131.643378) (xy 95.226827 -131.696785) (xy 95.218168 -131.715256)
			(xy 95.345756 -131.715256) (xy 95.349827 -131.659634) (xy 95.361953 -131.605197) (xy 95.381876 -131.553106)
			(xy 95.409172 -131.504471) (xy 95.443258 -131.460328) (xy 95.483407 -131.421619) (xy 95.528765 -131.389168)
			(xy 95.578365 -131.363667) (xy 95.631149 -131.34566) (xy 95.685992 -131.33553) (xy 95.741726 -131.333493)
			(xy 95.797163 -131.339593) (xy 95.85112 -131.353699) (xy 95.902449 -131.375511) (xy 95.950055 -131.404565)
			(xy 95.992923 -131.44024) (xy 96.03014 -131.481777) (xy 96.060913 -131.52829) (xy 96.084585 -131.578787)
			(xy 96.100653 -131.632194) (xy 96.108773 -131.68737) (xy 96.109282 -131.715256) (xy 96.108773 -131.743142)
			(xy 96.100653 -131.798318) (xy 96.084585 -131.851725) (xy 96.060913 -131.902222) (xy 96.03014 -131.948735)
			(xy 95.992923 -131.990272) (xy 95.950055 -132.025947) (xy 95.942192 -132.030746) (xy 112.909424 -132.030746)
			(xy 112.909424 -131.976254) (xy 112.917178 -131.922318) (xy 112.932529 -131.870033) (xy 112.955164 -131.820465)
			(xy 112.984622 -131.774623) (xy 113.020304 -131.733439) (xy 113.061483 -131.697752) (xy 113.107321 -131.668288)
			(xy 113.156886 -131.645647) (xy 113.209169 -131.630289) (xy 113.263104 -131.622528) (xy 113.29035 -131.622038)
			(xy 113.31772 -131.622524) (xy 113.371898 -131.630336) (xy 113.424401 -131.64582) (xy 113.474149 -131.668657)
			(xy 113.520116 -131.698378) (xy 113.541048 -131.716018) (xy 113.541302 -131.716272) (xy 113.548378 -131.721874)
			(xy 113.565303 -131.728109) (xy 113.574322 -131.728464) (xy 113.641378 -131.728464) (xy 113.650395 -131.728104)
			(xy 113.667312 -131.721859) (xy 113.674398 -131.716272) (xy 113.674398 -131.716018) (xy 113.674652 -131.716018)
			(xy 113.695594 -131.698391) (xy 113.741564 -131.668677) (xy 113.791309 -131.645838) (xy 113.843807 -131.630344)
			(xy 113.897981 -131.622513) (xy 113.92535 -131.622038) (xy 113.952608 -131.622406) (xy 114.006571 -131.630158)
			(xy 114.058882 -131.645511) (xy 114.108474 -131.668154) (xy 114.154339 -131.697624) (xy 114.195543 -131.733322)
			(xy 114.231246 -131.774521) (xy 114.260722 -131.820382) (xy 114.283371 -131.869971) (xy 114.298732 -131.92228)
			(xy 114.306491 -131.976242) (xy 114.306491 -132.030758) (xy 114.298732 -132.08472) (xy 114.283371 -132.137029)
			(xy 114.260722 -132.186618) (xy 114.231246 -132.232479) (xy 114.195543 -132.273678) (xy 114.154339 -132.309376)
			(xy 114.108474 -132.338846) (xy 114.058882 -132.361489) (xy 114.006571 -132.376842) (xy 113.952609 -132.384594)
			(xy 113.92535 -132.385054) (xy 113.89798 -132.38457) (xy 113.843802 -132.376758) (xy 113.791298 -132.361274)
			(xy 113.741551 -132.338436) (xy 113.695584 -132.308714) (xy 113.674652 -132.291074) (xy 113.674398 -132.29082)
			(xy 113.667323 -132.285217) (xy 113.650397 -132.278982) (xy 113.641378 -132.278628) (xy 113.574322 -132.278628)
			(xy 113.565305 -132.27899) (xy 113.548388 -132.285233) (xy 113.541302 -132.29082) (xy 113.541302 -132.291074)
			(xy 113.541048 -132.291074) (xy 113.520105 -132.3087) (xy 113.474136 -132.338415) (xy 113.424391 -132.361254)
			(xy 113.371893 -132.376748) (xy 113.317719 -132.384579) (xy 113.29035 -132.385054) (xy 113.263104 -132.384472)
			(xy 113.209169 -132.376711) (xy 113.156886 -132.361353) (xy 113.107321 -132.338712) (xy 113.061483 -132.309248)
			(xy 113.020304 -132.273561) (xy 112.984622 -132.232377) (xy 112.955164 -132.186535) (xy 112.932529 -132.136967)
			(xy 112.917178 -132.084682) (xy 112.909424 -132.030746) (xy 95.942192 -132.030746) (xy 95.902449 -132.055001)
			(xy 95.85112 -132.076813) (xy 95.797163 -132.090919) (xy 95.741726 -132.097019) (xy 95.685992 -132.094982)
			(xy 95.631149 -132.084852) (xy 95.578365 -132.066845) (xy 95.528765 -132.041344) (xy 95.483407 -132.008893)
			(xy 95.443258 -131.970184) (xy 95.409172 -131.926041) (xy 95.381876 -131.877406) (xy 95.361953 -131.825315)
			(xy 95.349827 -131.770878) (xy 95.345756 -131.715256) (xy 95.218168 -131.715256) (xy 95.203155 -131.747282)
			(xy 95.172382 -131.793795) (xy 95.135165 -131.835332) (xy 95.092297 -131.871007) (xy 95.044691 -131.900061)
			(xy 94.993362 -131.921873) (xy 94.939405 -131.935979) (xy 94.883968 -131.942079) (xy 94.828234 -131.940042)
			(xy 94.773391 -131.929912) (xy 94.720607 -131.911905) (xy 94.671007 -131.886404) (xy 94.625649 -131.853953)
			(xy 94.5855 -131.815244) (xy 94.551414 -131.771101) (xy 94.524118 -131.722466) (xy 94.504195 -131.670375)
			(xy 94.492069 -131.615938) (xy 94.487998 -131.560316) (xy 91.654122 -131.560316) (xy 91.654122 -133.985762)
			(xy 91.651415 -133.988612) (xy 91.646819 -133.994989) (xy 91.644978 -133.998462) (xy 91.642398 -134.00389)
			(xy 91.63958 -134.015569) (xy 91.63939 -134.021576) (xy 91.63939 -168.714928) (xy 98.320604 -168.714928)
			(xy 98.324675 -168.659306) (xy 98.336801 -168.604869) (xy 98.356724 -168.552778) (xy 98.38402 -168.504143)
			(xy 98.418106 -168.46) (xy 98.458255 -168.421291) (xy 98.503613 -168.38884) (xy 98.553213 -168.363339)
			(xy 98.605997 -168.345332) (xy 98.66084 -168.335202) (xy 98.716574 -168.333165) (xy 98.772011 -168.339265)
			(xy 98.825968 -168.353371) (xy 98.877297 -168.375183) (xy 98.924903 -168.404237) (xy 98.967771 -168.439912)
			(xy 99.004988 -168.481449) (xy 99.035761 -168.527962) (xy 99.059433 -168.578459) (xy 99.075501 -168.631866)
			(xy 99.083621 -168.687042) (xy 99.08413 -168.714928) (xy 99.083621 -168.742814) (xy 99.075501 -168.79799)
			(xy 99.059433 -168.851397) (xy 99.035761 -168.901894) (xy 99.004988 -168.948407) (xy 98.967771 -168.989944)
			(xy 98.924903 -169.025619) (xy 98.877297 -169.054673) (xy 98.825968 -169.076485) (xy 98.772011 -169.090591)
			(xy 98.716574 -169.096691) (xy 98.66084 -169.094654) (xy 98.605997 -169.084524) (xy 98.553213 -169.066517)
			(xy 98.503613 -169.041016) (xy 98.458255 -169.008565) (xy 98.418106 -168.969856) (xy 98.38402 -168.925713)
			(xy 98.356724 -168.877078) (xy 98.336801 -168.824987) (xy 98.324675 -168.77055) (xy 98.320604 -168.714928)
			(xy 91.63939 -168.714928) (xy 91.63939 -175.43145) (xy 99.053394 -175.43145) (xy 99.057465 -175.375828)
			(xy 99.069591 -175.321391) (xy 99.089514 -175.2693) (xy 99.11681 -175.220665) (xy 99.150896 -175.176522)
			(xy 99.191045 -175.137813) (xy 99.236403 -175.105362) (xy 99.286003 -175.079861) (xy 99.338787 -175.061854)
			(xy 99.39363 -175.051724) (xy 99.449364 -175.049687) (xy 99.504801 -175.055787) (xy 99.558758 -175.069893)
			(xy 99.610087 -175.091705) (xy 99.657693 -175.120759) (xy 99.700561 -175.156434) (xy 99.737778 -175.197971)
			(xy 99.768551 -175.244484) (xy 99.792223 -175.294981) (xy 99.808291 -175.348388) (xy 99.816411 -175.403564)
			(xy 99.81692 -175.43145) (xy 99.816411 -175.459336) (xy 99.808291 -175.514512) (xy 99.792223 -175.567919)
			(xy 99.768551 -175.618416) (xy 99.737778 -175.664929) (xy 99.700561 -175.706466) (xy 99.657693 -175.742141)
			(xy 99.610087 -175.771195) (xy 99.558758 -175.793007) (xy 99.504801 -175.807113) (xy 99.449364 -175.813213)
			(xy 99.39363 -175.811176) (xy 99.338787 -175.801046) (xy 99.286003 -175.783039) (xy 99.236403 -175.757538)
			(xy 99.191045 -175.725087) (xy 99.150896 -175.686378) (xy 99.11681 -175.642235) (xy 99.089514 -175.5936)
			(xy 99.069591 -175.541509) (xy 99.057465 -175.487072) (xy 99.053394 -175.43145) (xy 91.63939 -175.43145)
			(xy 91.63939 -176.163986) (xy 97.750882 -176.163986) (xy 97.754953 -176.108364) (xy 97.767079 -176.053927)
			(xy 97.787002 -176.001836) (xy 97.814298 -175.953201) (xy 97.848384 -175.909058) (xy 97.888533 -175.870349)
			(xy 97.933891 -175.837898) (xy 97.983491 -175.812397) (xy 98.036275 -175.79439) (xy 98.091118 -175.78426)
			(xy 98.146852 -175.782223) (xy 98.202289 -175.788323) (xy 98.256246 -175.802429) (xy 98.307575 -175.824241)
			(xy 98.355181 -175.853295) (xy 98.398049 -175.88897) (xy 98.435266 -175.930507) (xy 98.466039 -175.97702)
			(xy 98.489711 -176.027517) (xy 98.505779 -176.080924) (xy 98.513899 -176.1361) (xy 98.514408 -176.163986)
			(xy 98.513899 -176.191872) (xy 98.505779 -176.247048) (xy 98.489711 -176.300455) (xy 98.466039 -176.350952)
			(xy 98.435266 -176.397465) (xy 98.398049 -176.439002) (xy 98.355181 -176.474677) (xy 98.307575 -176.503731)
			(xy 98.256246 -176.525543) (xy 98.202289 -176.539649) (xy 98.146852 -176.545749) (xy 98.091118 -176.543712)
			(xy 98.036275 -176.533582) (xy 97.983491 -176.515575) (xy 97.933891 -176.490074) (xy 97.888533 -176.457623)
			(xy 97.848384 -176.418914) (xy 97.814298 -176.374771) (xy 97.787002 -176.326136) (xy 97.767079 -176.274045)
			(xy 97.754953 -176.219608) (xy 97.750882 -176.163986) (xy 91.63939 -176.163986) (xy 91.63939 -183.933084)
			(xy 91.640406 -183.942482) (xy 91.640406 -183.94299) (xy 91.642111 -183.950149) (xy 91.648946 -183.963173)
			(xy 91.653868 -183.968644) (xy 91.812618 -184.127394) (xy 91.818116 -184.132383) (xy 91.831282 -184.13923)
			(xy 91.838526 -184.140856) (xy 91.848178 -184.141872) (xy 103.08463 -184.141872) (xy 103.08717 -184.141618)
			(xy 103.092349 -184.141073) (xy 103.102334 -184.138125) (xy 103.106982 -184.135776) (xy 103.110233 -184.133936)
			(xy 103.116219 -184.129467) (xy 103.11892 -184.126886) (xy 103.189024 -184.056782) (xy 103.193683 -184.051433)
			(xy 103.200128 -184.038802) (xy 103.201724 -184.03189) (xy 103.201724 -184.031382) (xy 103.20274 -184.021984)
			(xy 103.20274 -183.40959) (xy 103.202578 -183.403579) (xy 103.199764 -183.391892) (xy 103.197152 -183.386476)
			(xy 103.195311 -183.383003) (xy 103.190713 -183.376628) (xy 103.188008 -183.373776) (xy 100.52558 -180.711348)
			(xy 100.512118 -180.697124) (xy 100.509832 -180.694584) (xy 100.451412 -180.636164) (xy 100.451158 -180.63591)
			(xy 100.45065 -180.635402) (xy 100.448872 -180.633624) (xy 100.44811 -180.632608) (xy 100.4443 -180.628798)
			(xy 100.43668 -180.610256) (xy 100.43668 -180.520086) (xy 100.436426 -180.516784) (xy 100.436426 -180.515514)
			(xy 100.436172 -180.512212) (xy 100.436172 -180.511958) (xy 100.435664 -180.49494) (xy 100.435664 -152.884886)
			(xy 100.436426 -152.864312) (xy 100.436426 -152.863042) (xy 100.43668 -152.85974) (xy 100.43668 -152.76957)
			(xy 100.4443 -152.751028) (xy 100.44811 -152.747218) (xy 100.448872 -152.746202) (xy 100.45065 -152.744424)
			(xy 100.451158 -152.743916) (xy 100.451412 -152.743662) (xy 100.509832 -152.685242) (xy 100.512118 -152.682702)
			(xy 100.52558 -152.668478) (xy 103.187246 -150.006812) (xy 103.192219 -150.001378) (xy 103.199048 -149.988335)
			(xy 103.200708 -149.981158) (xy 103.200708 -149.98065) (xy 103.201724 -149.971252) (xy 103.201724 -134.44982)
			(xy 103.201863 -134.44493) (xy 103.203787 -134.43534) (xy 103.205534 -134.43077) (xy 103.244396 -134.334758)
			(xy 103.246521 -134.329952) (xy 103.252416 -134.321254) (xy 103.25608 -134.317486) (xy 103.29291 -134.281926)
			(xy 103.293418 -134.281418) (xy 104.340406 -133.23443) (xy 104.35772 -133.217727) (xy 104.396627 -133.189432)
			(xy 104.439487 -133.167584) (xy 104.485242 -133.152724) (xy 104.53276 -133.145218) (xy 104.556814 -133.144768)
			(xy 105.28681 -133.144768) (xy 105.296208 -133.143752) (xy 105.296716 -133.143752) (xy 105.303874 -133.142045)
			(xy 105.316899 -133.135212) (xy 105.32237 -133.13029) (xy 105.41381 -133.03885) (xy 105.421207 -133.032)
			(xy 105.439805 -133.024261) (xy 105.449878 -133.023864) (xy 117.745764 -133.023864) (xy 117.755828 -133.0243)
			(xy 117.774409 -133.032038) (xy 117.781832 -133.03885) (xy 117.873272 -133.13029) (xy 117.878703 -133.135269)
			(xy 117.891743 -133.14211) (xy 117.898926 -133.143752) (xy 117.899434 -133.143752) (xy 117.908832 -133.144768)
			(xy 119.27332 -133.144768) (xy 119.286528 -133.146546) (xy 119.290084 -133.147562) (xy 119.388128 -133.187186)
			(xy 119.393018 -133.189348) (xy 119.401853 -133.195364) (xy 119.405654 -133.199124) (xy 119.44096 -133.2357)
			(xy 119.441468 -133.236208) (xy 119.751602 -133.546342) (xy 119.768308 -133.563656) (xy 119.796608 -133.602561)
			(xy 119.818462 -133.645421) (xy 119.83333 -133.691176) (xy 119.840845 -133.738695) (xy 119.841264 -133.76275)
			(xy 119.841264 -154.770836) (xy 119.840756 -154.784552) (xy 119.840756 -154.886406) (xy 119.840537 -154.893215)
			(xy 119.836931 -154.906347) (xy 119.833644 -154.912314) (xy 119.830088 -154.91841) (xy 119.82831 -154.92476)
			(xy 119.826532 -154.937968) (xy 119.826532 -161.906458) (xy 119.827548 -161.915856) (xy 119.827548 -161.916364)
			(xy 119.829248 -161.923526) (xy 119.836073 -161.93656) (xy 119.84101 -161.942018) (xy 120.900698 -163.001706)
			(xy 120.913652 -163.015422) (xy 120.915938 -163.017962) (xy 120.975628 -163.077652) (xy 120.97766 -163.079684)
			(xy 120.982232 -163.084256) (xy 120.982486 -163.084764) (xy 120.989852 -163.091876) (xy 120.989852 -163.203636)
			(xy 120.99036 -163.21786) (xy 120.99036 -166.999158) (xy 121.98045 -166.999158) (xy 121.984521 -166.943536)
			(xy 121.996647 -166.889099) (xy 122.01657 -166.837008) (xy 122.043866 -166.788373) (xy 122.077952 -166.74423)
			(xy 122.118101 -166.705521) (xy 122.163459 -166.67307) (xy 122.213059 -166.647569) (xy 122.265843 -166.629562)
			(xy 122.320686 -166.619432) (xy 122.37642 -166.617395) (xy 122.431857 -166.623495) (xy 122.485814 -166.637601)
			(xy 122.537143 -166.659413) (xy 122.584749 -166.688467) (xy 122.627617 -166.724142) (xy 122.664834 -166.765679)
			(xy 122.695607 -166.812192) (xy 122.719279 -166.862689) (xy 122.735347 -166.916096) (xy 122.743467 -166.971272)
			(xy 122.743976 -166.999158) (xy 122.743467 -167.027044) (xy 122.735347 -167.08222) (xy 122.719279 -167.135627)
			(xy 122.695607 -167.186124) (xy 122.664834 -167.232637) (xy 122.627617 -167.274174) (xy 122.584749 -167.309849)
			(xy 122.537143 -167.338903) (xy 122.485814 -167.360715) (xy 122.431857 -167.374821) (xy 122.37642 -167.380921)
			(xy 122.320686 -167.378884) (xy 122.265843 -167.368754) (xy 122.213059 -167.350747) (xy 122.163459 -167.325246)
			(xy 122.118101 -167.292795) (xy 122.077952 -167.254086) (xy 122.043866 -167.209943) (xy 122.01657 -167.161308)
			(xy 121.996647 -167.109217) (xy 121.984521 -167.05478) (xy 121.98045 -166.999158) (xy 120.99036 -166.999158)
			(xy 120.99036 -168.340041) (xy 122.316024 -168.340041) (xy 122.316025 -168.285547) (xy 122.32378 -168.231608)
			(xy 122.339133 -168.179321) (xy 122.361771 -168.129752) (xy 122.391233 -168.083908) (xy 122.426918 -168.042724)
			(xy 122.468102 -168.007038) (xy 122.513945 -167.977575) (xy 122.563514 -167.954936) (xy 122.6158 -167.939582)
			(xy 122.669739 -167.931825) (xy 122.696986 -167.931338) (xy 122.728736 -167.932608) (xy 122.742435 -167.933283)
			(xy 122.769376 -167.928205) (xy 122.793989 -167.91613) (xy 122.814493 -167.897931) (xy 122.829404 -167.874925)
			(xy 122.837643 -167.848777) (xy 122.838614 -167.821379) (xy 122.832247 -167.794713) (xy 122.826018 -167.782494)
			(xy 122.813763 -167.759356) (xy 122.794499 -167.71067) (xy 122.781471 -167.659957) (xy 122.774884 -167.608013)
			(xy 122.774456 -167.581834) (xy 122.774942 -167.552933) (xy 122.782924 -167.495686) (xy 122.798738 -167.44009)
			(xy 122.822081 -167.387212) (xy 122.852506 -167.338067) (xy 122.88943 -167.293596) (xy 122.932143 -167.254654)
			(xy 122.979827 -167.221986) (xy 123.031568 -167.196219) (xy 123.086372 -167.177848) (xy 123.143188 -167.167225)
			(xy 123.200928 -167.164554) (xy 123.258482 -167.169886) (xy 123.314749 -167.183118) (xy 123.368647 -167.203997)
			(xy 123.419144 -167.232123) (xy 123.46527 -167.266955) (xy 123.506142 -167.307827) (xy 123.540975 -167.353953)
			(xy 123.569101 -167.404449) (xy 123.589981 -167.458348) (xy 123.603214 -167.514614) (xy 123.608546 -167.572168)
			(xy 123.605875 -167.629908) (xy 123.595253 -167.686724) (xy 123.576882 -167.741529) (xy 123.551116 -167.793269)
			(xy 123.518449 -167.840954) (xy 123.479506 -167.883667) (xy 123.435036 -167.920591) (xy 123.385891 -167.951017)
			(xy 123.333014 -167.974361) (xy 123.277418 -167.990176) (xy 123.220171 -167.998157) (xy 123.19127 -167.998648)
			(xy 123.178665 -167.998547) (xy 123.153502 -167.997025) (xy 123.140978 -167.9956) (xy 123.127327 -167.994378)
			(xy 123.100237 -167.998474) (xy 123.075214 -168.009631) (xy 123.054061 -168.027044) (xy 123.038305 -168.049458)
			(xy 123.02908 -168.075257) (xy 123.027053 -168.10258) (xy 123.032369 -168.129457) (xy 123.038108 -168.141904)
			(xy 123.050801 -168.168553) (xy 123.068783 -168.224769) (xy 123.077915 -168.283081) (xy 123.078494 -168.312592)
			(xy 123.078494 -168.312846) (xy 123.077973 -168.340093) (xy 123.070211 -168.394031) (xy 123.054853 -168.446316)
			(xy 123.03221 -168.495883) (xy 123.002743 -168.541724) (xy 122.967053 -168.582904) (xy 122.925866 -168.618586)
			(xy 122.88002 -168.648044) (xy 122.830449 -168.670678) (xy 122.778161 -168.686026) (xy 122.724221 -168.693778)
			(xy 122.669727 -168.693774) (xy 122.615788 -168.686015) (xy 122.563502 -168.67066) (xy 122.513934 -168.648019)
			(xy 122.468092 -168.618555) (xy 122.42691 -168.582867) (xy 122.391226 -168.541682) (xy 122.361765 -168.495838)
			(xy 122.339129 -168.446268) (xy 122.323778 -168.393981) (xy 122.316024 -168.340041) (xy 120.99036 -168.340041)
			(xy 120.99036 -173.187614) (xy 122.884944 -173.187614) (xy 122.889015 -173.131992) (xy 122.901141 -173.077555)
			(xy 122.921064 -173.025464) (xy 122.94836 -172.976829) (xy 122.982446 -172.932686) (xy 123.022595 -172.893977)
			(xy 123.067953 -172.861526) (xy 123.117553 -172.836025) (xy 123.170337 -172.818018) (xy 123.22518 -172.807888)
			(xy 123.280914 -172.805851) (xy 123.336351 -172.811951) (xy 123.390308 -172.826057) (xy 123.441637 -172.847869)
			(xy 123.489243 -172.876923) (xy 123.532111 -172.912598) (xy 123.569328 -172.954135) (xy 123.600101 -173.000648)
			(xy 123.623773 -173.051145) (xy 123.639841 -173.104552) (xy 123.647961 -173.159728) (xy 123.64847 -173.187614)
			(xy 123.647961 -173.2155) (xy 123.639841 -173.270676) (xy 123.623773 -173.324083) (xy 123.600101 -173.37458)
			(xy 123.569328 -173.421093) (xy 123.532111 -173.46263) (xy 123.489243 -173.498305) (xy 123.441637 -173.527359)
			(xy 123.390308 -173.549171) (xy 123.336351 -173.563277) (xy 123.280914 -173.569377) (xy 123.22518 -173.56734)
			(xy 123.170337 -173.55721) (xy 123.117553 -173.539203) (xy 123.067953 -173.513702) (xy 123.022595 -173.481251)
			(xy 122.982446 -173.442542) (xy 122.94836 -173.398399) (xy 122.921064 -173.349764) (xy 122.901141 -173.297673)
			(xy 122.889015 -173.243236) (xy 122.884944 -173.187614) (xy 120.99036 -173.187614) (xy 120.99036 -177.961353)
			(xy 122.641567 -177.961353) (xy 122.641567 -177.906847) (xy 122.649324 -177.852897) (xy 122.664681 -177.8006)
			(xy 122.687323 -177.75102) (xy 122.716792 -177.705168) (xy 122.752486 -177.663976) (xy 122.793679 -177.628283)
			(xy 122.839532 -177.598817) (xy 122.889113 -177.576176) (xy 122.941411 -177.560821) (xy 122.995361 -177.553066)
			(xy 123.022614 -177.552604) (xy 123.048521 -177.553081) (xy 123.099857 -177.560106) (xy 123.14977 -177.574012)
			(xy 123.197344 -177.594543) (xy 123.241702 -177.621321) (xy 123.282029 -177.653855) (xy 123.317585 -177.691545)
			(xy 123.333002 -177.71237) (xy 123.338735 -177.719707) (xy 123.354243 -177.729989) (xy 123.363228 -177.732436)
			(xy 123.393708 -177.739294) (xy 123.402987 -177.741025) (xy 123.421647 -177.738296) (xy 123.43003 -177.73396)
			(xy 123.456023 -177.719716) (xy 123.510887 -177.69729) (xy 123.568186 -177.682128) (xy 123.626962 -177.674483)
			(xy 123.656598 -177.674016) (xy 123.686571 -177.674529) (xy 123.746004 -177.68235) (xy 123.803908 -177.697859)
			(xy 123.859294 -177.720791) (xy 123.911215 -177.750753) (xy 123.950983 -177.781253) (xy 126.367981 -177.781253)
			(xy 126.367981 -177.726747) (xy 126.375739 -177.672795) (xy 126.391097 -177.620497) (xy 126.413741 -177.570917)
			(xy 126.443211 -177.525065) (xy 126.478908 -177.483874) (xy 126.520103 -177.448183) (xy 126.565959 -177.418718)
			(xy 126.615542 -177.39608) (xy 126.667842 -177.380729) (xy 126.721795 -177.372978) (xy 126.749048 -177.372518)
			(xy 126.77399 -177.372938) (xy 126.823449 -177.379433) (xy 126.871639 -177.39232) (xy 126.894844 -177.401474)
			(xy 126.909205 -177.406888) (xy 126.939766 -177.409619) (xy 126.969764 -177.403176) (xy 126.996507 -177.388135)
			(xy 127.017594 -177.365848) (xy 127.031133 -177.338315) (xy 127.034036 -177.323242) (xy 127.038683 -177.296624)
			(xy 127.05448 -177.244951) (xy 127.07741 -177.196024) (xy 127.107014 -177.150822) (xy 127.142699 -177.110248)
			(xy 127.183751 -177.075115) (xy 127.229349 -177.046125) (xy 127.278581 -177.023858) (xy 127.330463 -177.00876)
			(xy 127.383955 -177.001133) (xy 127.410972 -177.000662) (xy 127.438224 -177.001183) (xy 127.492174 -177.008936)
			(xy 127.544471 -177.024289) (xy 127.594051 -177.046928) (xy 127.639904 -177.076393) (xy 127.681096 -177.112084)
			(xy 127.71679 -177.153274) (xy 127.746259 -177.199125) (xy 127.768901 -177.248703) (xy 127.784258 -177.300999)
			(xy 127.792015 -177.354948) (xy 127.792015 -177.409452) (xy 127.784258 -177.463401) (xy 127.768901 -177.515697)
			(xy 127.746259 -177.565275) (xy 127.71679 -177.611126) (xy 127.681096 -177.652316) (xy 127.639904 -177.688007)
			(xy 127.594051 -177.717472) (xy 127.544471 -177.740111) (xy 127.492174 -177.755464) (xy 127.438224 -177.763217)
			(xy 127.410972 -177.763678) (xy 127.386029 -177.763285) (xy 127.33657 -177.756779) (xy 127.28838 -177.743881)
			(xy 127.265176 -177.734722) (xy 127.250806 -177.729335) (xy 127.22025 -177.7266) (xy 127.190256 -177.733038)
			(xy 127.163514 -177.748073) (xy 127.142428 -177.770355) (xy 127.128888 -177.797883) (xy 127.125984 -177.812954)
			(xy 127.121315 -177.839568) (xy 127.105519 -177.891239) (xy 127.082591 -177.940165) (xy 127.05299 -177.985367)
			(xy 127.017308 -178.02594) (xy 126.976258 -178.061073) (xy 126.930663 -178.090064) (xy 126.881433 -178.112332)
			(xy 126.829554 -178.127432) (xy 126.776064 -178.135062) (xy 126.749048 -178.135534) (xy 126.721795 -178.135022)
			(xy 126.667842 -178.127271) (xy 126.615542 -178.11192) (xy 126.565959 -178.089282) (xy 126.520103 -178.059817)
			(xy 126.478908 -178.024126) (xy 126.443211 -177.982935) (xy 126.413741 -177.937083) (xy 126.391097 -177.887503)
			(xy 126.375739 -177.835205) (xy 126.367981 -177.781253) (xy 123.950983 -177.781253) (xy 123.958782 -177.787234)
			(xy 124.001183 -177.829609) (xy 124.037692 -177.877154) (xy 124.067686 -177.929056) (xy 124.090651 -177.984428)
			(xy 124.106195 -178.042323) (xy 124.114053 -178.101752) (xy 124.11456 -178.131724) (xy 124.11456 -178.995324)
			(xy 124.114141 -179.025284) (xy 124.106319 -179.08469) (xy 124.090813 -179.142568) (xy 124.067887 -179.197928)
			(xy 124.064904 -179.203096) (xy 126.797052 -179.203096) (xy 126.801123 -179.147474) (xy 126.813249 -179.093037)
			(xy 126.833172 -179.040946) (xy 126.860468 -178.992311) (xy 126.894554 -178.948168) (xy 126.934703 -178.909459)
			(xy 126.980061 -178.877008) (xy 127.029661 -178.851507) (xy 127.082445 -178.8335) (xy 127.137288 -178.82337)
			(xy 127.193022 -178.821333) (xy 127.248459 -178.827433) (xy 127.302416 -178.841539) (xy 127.353745 -178.863351)
			(xy 127.401351 -178.892405) (xy 127.444219 -178.92808) (xy 127.481436 -178.969617) (xy 127.512209 -179.01613)
			(xy 127.535881 -179.066627) (xy 127.551949 -179.120034) (xy 127.560069 -179.17521) (xy 127.560578 -179.203096)
			(xy 127.560069 -179.230982) (xy 127.551949 -179.286158) (xy 127.535881 -179.339565) (xy 127.512209 -179.390062)
			(xy 127.481436 -179.436575) (xy 127.444219 -179.478112) (xy 127.401351 -179.513787) (xy 127.353745 -179.542841)
			(xy 127.302416 -179.564653) (xy 127.248459 -179.578759) (xy 127.193022 -179.584859) (xy 127.137288 -179.582822)
			(xy 127.082445 -179.572692) (xy 127.029661 -179.554685) (xy 126.980061 -179.529184) (xy 126.934703 -179.496733)
			(xy 126.894554 -179.458024) (xy 126.860468 -179.413881) (xy 126.833172 -179.365246) (xy 126.813249 -179.313155)
			(xy 126.801123 -179.258718) (xy 126.797052 -179.203096) (xy 124.064904 -179.203096) (xy 124.037933 -179.249823)
			(xy 124.001464 -179.297366) (xy 123.959103 -179.339744) (xy 123.911575 -179.376232) (xy 123.859692 -179.406206)
			(xy 123.804341 -179.429154) (xy 123.746469 -179.444684) (xy 123.687065 -179.452529) (xy 123.657106 -179.453032)
			(xy 123.656598 -179.453032) (xy 123.626963 -179.452542) (xy 123.568188 -179.444901) (xy 123.510889 -179.429747)
			(xy 123.456021 -179.407333) (xy 123.43003 -179.393088) (xy 123.421614 -179.388849) (xy 123.402987 -179.386109)
			(xy 123.393708 -179.387754) (xy 123.363228 -179.394612) (xy 123.354232 -179.397029) (xy 123.338729 -179.40733)
			(xy 123.333002 -179.414678) (xy 123.317603 -179.435521) (xy 123.28206 -179.473234) (xy 123.241737 -179.505785)
			(xy 123.197376 -179.532575) (xy 123.149795 -179.553108) (xy 123.099871 -179.567007) (xy 123.048525 -179.574015)
			(xy 123.022614 -179.574444) (xy 122.995363 -179.57391) (xy 122.941416 -179.566155) (xy 122.889121 -179.550802)
			(xy 122.839544 -179.528162) (xy 122.793693 -179.498697) (xy 122.752503 -179.463007) (xy 122.716811 -179.421818)
			(xy 122.687345 -179.375968) (xy 122.664703 -179.326392) (xy 122.649348 -179.274098) (xy 122.641591 -179.220151)
			(xy 122.641591 -179.165649) (xy 122.649348 -179.111702) (xy 122.664703 -179.059408) (xy 122.687345 -179.009832)
			(xy 122.716811 -178.963982) (xy 122.752503 -178.922793) (xy 122.793693 -178.887103) (xy 122.839544 -178.857638)
			(xy 122.889121 -178.834998) (xy 122.941416 -178.819645) (xy 122.995363 -178.81189) (xy 123.022614 -178.811428)
			(xy 123.037407 -178.81156) (xy 123.066905 -178.813851) (xy 123.081542 -178.816) (xy 123.092516 -178.817143)
			(xy 123.113709 -178.811071) (xy 123.122436 -178.804316) (xy 123.180856 -178.754278) (xy 123.188896 -178.746721)
			(xy 123.198102 -178.726692) (xy 123.198636 -178.71567) (xy 123.198636 -178.411378) (xy 123.198099 -178.400359)
			(xy 123.188877 -178.380344) (xy 123.180856 -178.37277) (xy 123.1138 -178.315366) (xy 123.092718 -178.30927)
			(xy 123.081542 -178.311048) (xy 123.066904 -178.313191) (xy 123.037407 -178.315477) (xy 123.022614 -178.31562)
			(xy 122.995361 -178.315134) (xy 122.941411 -178.307379) (xy 122.889113 -178.292024) (xy 122.839532 -178.269383)
			(xy 122.793679 -178.239917) (xy 122.752486 -178.204224) (xy 122.716792 -178.163032) (xy 122.687323 -178.11718)
			(xy 122.664681 -178.0676) (xy 122.649324 -178.015303) (xy 122.641567 -177.961353) (xy 120.99036 -177.961353)
			(xy 120.99036 -181.004718) (xy 135.60628 -181.004718) (xy 135.610351 -180.949096) (xy 135.622477 -180.894659)
			(xy 135.6424 -180.842568) (xy 135.669696 -180.793933) (xy 135.703782 -180.74979) (xy 135.743931 -180.711081)
			(xy 135.789289 -180.67863) (xy 135.838889 -180.653129) (xy 135.891673 -180.635122) (xy 135.946516 -180.624992)
			(xy 136.00225 -180.622955) (xy 136.057687 -180.629055) (xy 136.111644 -180.643161) (xy 136.162973 -180.664973)
			(xy 136.210579 -180.694027) (xy 136.253447 -180.729702) (xy 136.290664 -180.771239) (xy 136.321437 -180.817752)
			(xy 136.345109 -180.868249) (xy 136.361177 -180.921656) (xy 136.369297 -180.976832) (xy 136.369806 -181.004718)
			(xy 136.369297 -181.032604) (xy 136.361177 -181.08778) (xy 136.345109 -181.141187) (xy 136.321437 -181.191684)
			(xy 136.290664 -181.238197) (xy 136.253447 -181.279734) (xy 136.210579 -181.315409) (xy 136.162973 -181.344463)
			(xy 136.111644 -181.366275) (xy 136.057687 -181.380381) (xy 136.00225 -181.386481) (xy 135.946516 -181.384444)
			(xy 135.891673 -181.374314) (xy 135.838889 -181.356307) (xy 135.789289 -181.330806) (xy 135.743931 -181.298355)
			(xy 135.703782 -181.259646) (xy 135.669696 -181.215503) (xy 135.6424 -181.166868) (xy 135.622477 -181.114777)
			(xy 135.610351 -181.06034) (xy 135.60628 -181.004718) (xy 120.99036 -181.004718) (xy 120.99036 -181.775608)
			(xy 127.458976 -181.775608) (xy 127.463047 -181.719986) (xy 127.475173 -181.665549) (xy 127.495096 -181.613458)
			(xy 127.522392 -181.564823) (xy 127.556478 -181.52068) (xy 127.596627 -181.481971) (xy 127.641985 -181.44952)
			(xy 127.691585 -181.424019) (xy 127.744369 -181.406012) (xy 127.799212 -181.395882) (xy 127.854946 -181.393845)
			(xy 127.910383 -181.399945) (xy 127.96434 -181.414051) (xy 128.015669 -181.435863) (xy 128.063275 -181.464917)
			(xy 128.106143 -181.500592) (xy 128.14336 -181.542129) (xy 128.174133 -181.588642) (xy 128.197805 -181.639139)
			(xy 128.213873 -181.692546) (xy 128.221993 -181.747722) (xy 128.222502 -181.775608) (xy 128.221993 -181.803494)
			(xy 128.213873 -181.85867) (xy 128.197805 -181.912077) (xy 128.174133 -181.962574) (xy 128.14336 -182.009087)
			(xy 128.106143 -182.050624) (xy 128.063275 -182.086299) (xy 128.015669 -182.115353) (xy 127.96434 -182.137165)
			(xy 127.910383 -182.151271) (xy 127.854946 -182.157371) (xy 127.799212 -182.155334) (xy 127.744369 -182.145204)
			(xy 127.691585 -182.127197) (xy 127.641985 -182.101696) (xy 127.596627 -182.069245) (xy 127.556478 -182.030536)
			(xy 127.522392 -181.986393) (xy 127.495096 -181.937758) (xy 127.475173 -181.885667) (xy 127.463047 -181.83123)
			(xy 127.458976 -181.775608) (xy 120.99036 -181.775608) (xy 120.99036 -182.475757) (xy 129.801509 -182.475757)
			(xy 129.801509 -182.421243) (xy 129.809267 -182.367284) (xy 129.824626 -182.314978) (xy 129.847273 -182.26539)
			(xy 129.876747 -182.219531) (xy 129.912447 -182.178333) (xy 129.953647 -182.142635) (xy 129.999508 -182.113163)
			(xy 130.049097 -182.090519) (xy 130.101403 -182.075163) (xy 130.155363 -182.067408) (xy 130.18262 -182.066946)
			(xy 130.182874 -182.066946) (xy 130.202432 -182.067454) (xy 130.212846 -182.067962) (xy 130.232658 -182.06085)
			(xy 130.293618 -182.002684) (xy 130.300754 -181.995193) (xy 130.308881 -181.976188) (xy 130.309366 -181.965854)
			(xy 130.309797 -181.938567) (xy 130.317466 -181.884535) (xy 130.332755 -181.832148) (xy 130.355353 -181.782474)
			(xy 130.384799 -181.736526) (xy 130.420491 -181.695243) (xy 130.461701 -181.659467) (xy 130.507588 -181.629928)
			(xy 130.557216 -181.607228) (xy 130.609572 -181.591831) (xy 130.663588 -181.584052) (xy 130.690874 -181.583584)
			(xy 130.718127 -181.584062) (xy 130.77208 -181.591815) (xy 130.82438 -181.607169) (xy 130.873962 -181.629809)
			(xy 130.919818 -181.659276) (xy 130.961013 -181.694969) (xy 130.996708 -181.736161) (xy 131.026178 -181.782015)
			(xy 131.048822 -181.831596) (xy 131.064179 -181.883894) (xy 131.071937 -181.937847) (xy 131.071937 -181.992353)
			(xy 131.064179 -182.046306) (xy 131.048822 -182.098604) (xy 131.026178 -182.148185) (xy 130.996708 -182.194039)
			(xy 130.961013 -182.235231) (xy 130.919818 -182.270924) (xy 130.873962 -182.300391) (xy 130.82438 -182.323031)
			(xy 130.77208 -182.338385) (xy 130.718127 -182.346138) (xy 130.690874 -182.3466) (xy 130.69062 -182.3466)
			(xy 130.671062 -182.346092) (xy 130.660648 -182.345584) (xy 130.640836 -182.352696) (xy 130.579876 -182.410862)
			(xy 130.572719 -182.418335) (xy 130.564605 -182.437354) (xy 130.564128 -182.447692) (xy 130.563653 -182.474978)
			(xy 130.555991 -182.529009) (xy 130.540708 -182.581395) (xy 130.518116 -182.63107) (xy 130.488675 -182.677018)
			(xy 130.452988 -182.718302) (xy 130.411782 -182.754079) (xy 130.365898 -182.783619) (xy 130.316272 -182.806319)
			(xy 130.263919 -182.821716) (xy 130.209905 -182.829495) (xy 130.18262 -182.829962) (xy 130.155363 -182.829592)
			(xy 130.101403 -182.821837) (xy 130.049097 -182.806481) (xy 129.999508 -182.783837) (xy 129.953647 -182.754365)
			(xy 129.912447 -182.718667) (xy 129.876747 -182.677469) (xy 129.847273 -182.63161) (xy 129.824626 -182.582022)
			(xy 129.809267 -182.529716) (xy 129.801509 -182.475757) (xy 120.99036 -182.475757) (xy 120.99036 -183.220106)
			(xy 133.292086 -183.220106) (xy 133.296157 -183.164484) (xy 133.308283 -183.110047) (xy 133.328206 -183.057956)
			(xy 133.355502 -183.009321) (xy 133.389588 -182.965178) (xy 133.429737 -182.926469) (xy 133.475095 -182.894018)
			(xy 133.524695 -182.868517) (xy 133.577479 -182.85051) (xy 133.632322 -182.84038) (xy 133.688056 -182.838343)
			(xy 133.743493 -182.844443) (xy 133.79745 -182.858549) (xy 133.848779 -182.880361) (xy 133.896385 -182.909415)
			(xy 133.939253 -182.94509) (xy 133.97647 -182.986627) (xy 134.007243 -183.03314) (xy 134.027852 -183.077104)
			(xy 134.905494 -183.077104) (xy 134.909565 -183.021482) (xy 134.921691 -182.967045) (xy 134.941614 -182.914954)
			(xy 134.96891 -182.866319) (xy 135.002996 -182.822176) (xy 135.043145 -182.783467) (xy 135.088503 -182.751016)
			(xy 135.138103 -182.725515) (xy 135.190887 -182.707508) (xy 135.24573 -182.697378) (xy 135.301464 -182.695341)
			(xy 135.356901 -182.701441) (xy 135.410858 -182.715547) (xy 135.462187 -182.737359) (xy 135.509793 -182.766413)
			(xy 135.552661 -182.802088) (xy 135.589878 -182.843625) (xy 135.620651 -182.890138) (xy 135.644323 -182.940635)
			(xy 135.660391 -182.994042) (xy 135.668511 -183.049218) (xy 135.66902 -183.077104) (xy 135.668511 -183.10499)
			(xy 135.660391 -183.160166) (xy 135.644323 -183.213573) (xy 135.620651 -183.26407) (xy 135.589878 -183.310583)
			(xy 135.552661 -183.35212) (xy 135.509793 -183.387795) (xy 135.462187 -183.416849) (xy 135.410858 -183.438661)
			(xy 135.356901 -183.452767) (xy 135.301464 -183.458867) (xy 135.24573 -183.45683) (xy 135.190887 -183.4467)
			(xy 135.138103 -183.428693) (xy 135.088503 -183.403192) (xy 135.043145 -183.370741) (xy 135.002996 -183.332032)
			(xy 134.96891 -183.287889) (xy 134.941614 -183.239254) (xy 134.921691 -183.187163) (xy 134.909565 -183.132726)
			(xy 134.905494 -183.077104) (xy 134.027852 -183.077104) (xy 134.030915 -183.083637) (xy 134.046983 -183.137044)
			(xy 134.055103 -183.19222) (xy 134.055612 -183.220106) (xy 134.055103 -183.247992) (xy 134.046983 -183.303168)
			(xy 134.030915 -183.356575) (xy 134.007243 -183.407072) (xy 133.97647 -183.453585) (xy 133.939253 -183.495122)
			(xy 133.896385 -183.530797) (xy 133.848779 -183.559851) (xy 133.79745 -183.581663) (xy 133.743493 -183.595769)
			(xy 133.688056 -183.601869) (xy 133.632322 -183.599832) (xy 133.577479 -183.589702) (xy 133.524695 -183.571695)
			(xy 133.475095 -183.546194) (xy 133.429737 -183.513743) (xy 133.389588 -183.475034) (xy 133.355502 -183.430891)
			(xy 133.328206 -183.382256) (xy 133.308283 -183.330165) (xy 133.296157 -183.275728) (xy 133.292086 -183.220106)
			(xy 120.99036 -183.220106) (xy 120.99036 -183.44515) (xy 120.991376 -183.454548) (xy 120.991376 -183.455056)
			(xy 120.993076 -183.462218) (xy 120.999902 -183.475251) (xy 121.004838 -183.48071) (xy 121.314718 -183.79059)
			(xy 128.71018 -183.79059) (xy 128.714251 -183.734968) (xy 128.726377 -183.680531) (xy 128.7463 -183.62844)
			(xy 128.773596 -183.579805) (xy 128.807682 -183.535662) (xy 128.847831 -183.496953) (xy 128.893189 -183.464502)
			(xy 128.942789 -183.439001) (xy 128.995573 -183.420994) (xy 129.050416 -183.410864) (xy 129.10615 -183.408827)
			(xy 129.161587 -183.414927) (xy 129.215544 -183.429033) (xy 129.266873 -183.450845) (xy 129.314479 -183.479899)
			(xy 129.357347 -183.515574) (xy 129.394564 -183.557111) (xy 129.425337 -183.603624) (xy 129.449009 -183.654121)
			(xy 129.465077 -183.707528) (xy 129.473197 -183.762704) (xy 129.473706 -183.79059) (xy 129.473197 -183.818476)
			(xy 129.465077 -183.873652) (xy 129.449009 -183.927059) (xy 129.425337 -183.977556) (xy 129.394564 -184.024069)
			(xy 129.357347 -184.065606) (xy 129.314479 -184.101281) (xy 129.266873 -184.130335) (xy 129.215544 -184.152147)
			(xy 129.161587 -184.166253) (xy 129.10615 -184.172353) (xy 129.050416 -184.170316) (xy 128.995573 -184.160186)
			(xy 128.942789 -184.142179) (xy 128.893189 -184.116678) (xy 128.847831 -184.084227) (xy 128.807682 -184.045518)
			(xy 128.773596 -184.001375) (xy 128.7463 -183.95274) (xy 128.726377 -183.900649) (xy 128.714251 -183.846212)
			(xy 128.71018 -183.79059) (xy 121.314718 -183.79059) (xy 121.937272 -184.413144) (xy 121.940121 -184.415852)
			(xy 121.946497 -184.42045) (xy 121.949972 -184.422288) (xy 121.955399 -184.424869) (xy 121.967079 -184.427686)
			(xy 121.973086 -184.427876) (xy 137.541 -184.427876) (xy 137.565846 -184.428318) (xy 137.614983 -184.435728)
			(xy 137.662465 -184.450382) (xy 137.707232 -184.471953) (xy 137.748281 -184.499958) (xy 137.766806 -184.516522)
			(xy 137.772006 -184.520577) (xy 137.78397 -184.526109) (xy 137.790428 -184.527444) (xy 137.799318 -184.528206)
			(xy 138.06297 -184.528206)
		)
		(stroke
			(width 0)
			(type solid)
		)
		(fill yes)
		(layer "In13.Cu")
		(net "P3V3")
	)
	(gr_poly
		(pts
			(xy 53.023516 -418.034978) (xy 53.033534 -418.034555) (xy 53.052041 -418.026882) (xy 53.066203 -418.012709)
			(xy 53.073863 -417.994196) (xy 53.074316 -417.984178) (xy 53.074316 -417.722558) (xy 53.07415 -417.716548)
			(xy 53.071328 -417.704865) (xy 53.068728 -417.699444) (xy 53.066887 -417.695971) (xy 53.062292 -417.689593)
			(xy 53.059584 -417.686744) (xy 53.044598 -417.671758) (xy 53.039772 -417.671758) (xy 53.039772 -417.339272)
			(xy 53.040199 -417.329203) (xy 53.047918 -417.310604) (xy 53.054758 -417.303204) (xy 53.06949 -417.288472)
			(xy 53.073808 -417.288472) (xy 53.073808 -394.32992) (xy 53.073808 -394.27912) (xy 65.265554 -394.27912)
			(xy 65.273311 -394.277317) (xy 65.287286 -394.269695) (xy 65.292986 -394.264134) (xy 65.847214 -393.709906)
			(xy 65.850527 -393.706375) (xy 65.855893 -393.698318) (xy 65.857882 -393.693904) (xy 65.861946 -393.684506)
			(xy 65.861946 -392.248136) (xy 65.861778 -392.242127) (xy 65.858954 -392.230445) (xy 65.856358 -392.225022)
			(xy 65.854519 -392.221547) (xy 65.849927 -392.215167) (xy 65.847214 -392.212322) (xy 65.478406 -391.843514)
			(xy 65.472818 -391.838688) (xy 65.467205 -391.834755) (xy 65.45446 -391.829724) (xy 65.447672 -391.828782)
			(xy 65.440698 -391.828233) (xy 65.42691 -391.830563) (xy 65.420494 -391.833354) (xy 65.405762 -391.840466)
			(xy 65.404746 -391.840974) (xy 65.403984 -391.841228) (xy 65.392808 -391.845292) (xy 65.3923 -391.845292)
			(xy 65.386966 -391.846308) (xy 65.386458 -391.846308) (xy 65.38595 -391.846562) (xy 65.381632 -391.84707)
			(xy 65.37706 -391.847832) (xy 65.365376 -391.849356) (xy 65.34531 -391.863072) (xy 65.34404 -391.863834)
			(xy 65.332356 -391.870692) (xy 65.326006 -391.879328) (xy 65.32372 -391.882376) (xy 65.32245 -391.884408)
			(xy 65.307329 -391.907174) (xy 65.271611 -391.948539) (xy 65.230361 -391.98439) (xy 65.184422 -392.013994)
			(xy 65.134731 -392.036746) (xy 65.082304 -392.052181) (xy 65.028212 -392.059985) (xy 65.000886 -392.06043)
			(xy 64.97315 -392.059925) (xy 64.918263 -392.051879) (xy 64.865119 -392.035973) (xy 64.814837 -392.012543)
			(xy 64.768476 -391.982082) (xy 64.727012 -391.945231) (xy 64.691319 -391.902766) (xy 64.662148 -391.855582)
			(xy 64.640114 -391.804673) (xy 64.625681 -391.751111) (xy 64.621918 -391.723626) (xy 64.62014 -391.708386)
			(xy 64.619124 -391.678922) (xy 64.619631 -391.651125) (xy 64.627703 -391.59612) (xy 64.643667 -391.542866)
			(xy 64.667183 -391.49249) (xy 64.697756 -391.446057) (xy 64.734738 -391.404548) (xy 64.777349 -391.368839)
			(xy 64.800734 -391.353802) (xy 64.806068 -391.350754) (xy 64.815974 -391.340848) (xy 64.820273 -391.336339)
			(xy 64.826709 -391.325677) (xy 64.828674 -391.319766) (xy 64.830452 -391.311384) (xy 64.840612 -391.234168)
			(xy 64.841197 -391.228256) (xy 64.839917 -391.216447) (xy 64.838072 -391.2108) (xy 64.834262 -391.199878)
			(xy 64.82588 -391.191496) (xy 64.82461 -391.190226) (xy 64.82334 -391.188448) (xy 63.310008 -389.675116)
			(xy 63.307157 -389.672411) (xy 63.300778 -389.667818) (xy 63.297308 -389.665972) (xy 63.29188 -389.663395)
			(xy 63.2802 -389.660584) (xy 63.274194 -389.660384) (xy 63.249556 -389.660384) (xy 63.245886 -389.66043)
			(xy 63.238619 -389.661451) (xy 63.235078 -389.662416) (xy 63.227712 -389.664702) (xy 63.220854 -389.669528)
			(xy 63.196769 -389.685666) (xy 63.144747 -389.711255) (xy 63.089455 -389.728684) (xy 63.032162 -389.737552)
			(xy 63.003176 -389.738108) (xy 62.999112 -389.738108) (xy 62.969182 -389.737264) (xy 62.910128 -389.727397)
			(xy 62.853342 -389.708422) (xy 62.80022 -389.680806) (xy 62.752066 -389.645226) (xy 62.730634 -389.624316)
			(xy 62.723014 -389.616696) (xy 62.697614 -389.60552) (xy 62.69228 -389.603488) (xy 62.678818 -389.601202)
			(xy 62.618874 -389.598916) (xy 62.61481 -389.598916) (xy 62.604571 -389.599172) (xy 62.58557 -389.606771)
			(xy 62.57798 -389.613648) (xy 62.56401 -389.627618) (xy 62.543529 -389.643639) (xy 62.499051 -389.670575)
			(xy 62.451328 -389.691223) (xy 62.401244 -389.705201) (xy 62.349725 -389.71225) (xy 62.323726 -389.712708)
			(xy 62.323472 -389.712708) (xy 62.294828 -389.712192) (xy 62.238185 -389.703625) (xy 62.183459 -389.686687)
			(xy 62.13188 -389.661759) (xy 62.084606 -389.629401) (xy 62.042701 -389.59034) (xy 62.007105 -389.545454)
			(xy 61.978618 -389.495751) (xy 61.957881 -389.442348) (xy 61.951108 -389.414512) (xy 61.949838 -389.40867)
			(xy 61.943234 -389.395208) (xy 61.940876 -389.390619) (xy 61.934598 -389.382432) (xy 61.930788 -389.378952)
			(xy 61.929772 -389.377936) (xy 61.927486 -389.376158) (xy 61.924438 -389.374126) (xy 61.901491 -389.359063)
			(xy 61.859771 -389.323394) (xy 61.823599 -389.282108) (xy 61.793724 -389.236061) (xy 61.770763 -389.186204)
			(xy 61.755192 -389.133569) (xy 61.747332 -389.079245) (xy 61.746892 -389.0518) (xy 61.74697 -389.039062)
			(xy 61.748624 -389.013641) (xy 61.750194 -389.001) (xy 61.754359 -388.97367) (xy 61.769543 -388.920514)
			(xy 61.792237 -388.870105) (xy 61.821965 -388.823496) (xy 61.858106 -388.781664) (xy 61.899904 -388.745483)
			(xy 61.946484 -388.71571) (xy 61.996872 -388.692968) (xy 62.050013 -388.677733) (xy 62.077346 -388.673594)
			(xy 62.078108 -388.673594) (xy 62.084908 -388.672428) (xy 62.097539 -388.666888) (xy 62.103 -388.662672)
			(xy 62.108842 -388.657846) (xy 62.116716 -388.646416) (xy 62.130178 -388.606284) (xy 62.130178 -388.605776)
			(xy 62.145418 -388.561326) (xy 62.146702 -388.557319) (xy 62.148107 -388.549023) (xy 62.148212 -388.544816)
			(xy 62.148212 -388.534402) (xy 62.147738 -388.524434) (xy 62.140169 -388.505991) (xy 62.13348 -388.498588)
			(xy 60.40882 -386.773928) (xy 60.401413 -386.767238) (xy 60.382976 -386.759644) (xy 60.373006 -386.759196)
			(xy 60.36437 -386.759196) (xy 60.350908 -386.760974) (xy 60.293758 -386.777484) (xy 60.29325 -386.777484)
			(xy 60.271152 -386.784088) (xy 60.259814 -386.788225) (xy 60.242428 -386.804917) (xy 60.237878 -386.816092)
			(xy 60.236354 -386.820664) (xy 60.235846 -386.823204) (xy 60.228759 -386.850671) (xy 60.207576 -386.90329)
			(xy 60.178839 -386.952196) (xy 60.143183 -386.996312) (xy 60.101392 -387.034666) (xy 60.054385 -387.066414)
			(xy 60.003199 -387.090858) (xy 59.948959 -387.107459) (xy 59.89286 -387.115852) (xy 59.864498 -387.11632)
			(xy 59.837247 -387.115834) (xy 59.783298 -387.108077) (xy 59.731003 -387.092722) (xy 59.681425 -387.070081)
			(xy 59.635574 -387.040615) (xy 59.594383 -387.004924) (xy 59.558691 -386.963734) (xy 59.529224 -386.917883)
			(xy 59.506581 -386.868306) (xy 59.491225 -386.816011) (xy 59.483467 -386.762063) (xy 59.48299 -386.734812)
			(xy 59.483504 -386.706046) (xy 59.492124 -386.649163) (xy 59.509184 -386.594219) (xy 59.5343 -386.542459)
			(xy 59.5669 -386.495055) (xy 59.606247 -386.453082) (xy 59.651449 -386.417491) (xy 59.701482 -386.389088)
			(xy 59.755211 -386.368518) (xy 59.783218 -386.36194) (xy 59.7916 -386.359908) (xy 59.801252 -386.350764)
			(xy 59.806017 -386.346004) (xy 59.813092 -386.334548) (xy 59.815222 -386.328158) (xy 59.821826 -386.30606)
			(xy 59.821826 -386.305552) (xy 59.843162 -386.23113) (xy 59.84567 -386.220234) (xy 59.842125 -386.198184)
			(xy 59.829588 -386.179702) (xy 59.820302 -386.173472) (xy 59.79668 -386.159502) (xy 59.786774 -386.151882)
			(xy 57.6834 -384.048508) (xy 57.675991 -384.041823) (xy 57.657555 -384.034239) (xy 57.647586 -384.033776)
			(xy 57.647078 -384.033776) (xy 57.619804 -384.033309) (xy 57.565812 -384.025537) (xy 57.513479 -384.010153)
			(xy 57.463869 -383.987471) (xy 57.417997 -383.957955) (xy 57.376796 -383.922206) (xy 57.341108 -383.880953)
			(xy 57.311659 -383.835037) (xy 57.289051 -383.785394) (xy 57.273744 -383.733038) (xy 57.266051 -383.679035)
			(xy 57.26557 -383.65176) (xy 57.26557 -383.6416) (xy 57.261506 -383.631948) (xy 57.259497 -383.627442)
			(xy 57.253999 -383.619252) (xy 57.250584 -383.615692) (xy 56.750458 -383.115566) (xy 56.742816 -383.108652)
			(xy 56.723678 -383.101059) (xy 56.713374 -383.100834) (xy 56.71312 -383.100834) (xy 56.703468 -383.101088)
			(xy 56.701436 -383.101088) (xy 56.674209 -383.100585) (xy 56.620314 -383.092804) (xy 56.568072 -383.077439)
			(xy 56.518546 -383.054801) (xy 56.472743 -383.025351) (xy 56.431592 -382.989687) (xy 56.395931 -382.948533)
			(xy 56.366485 -382.902728) (xy 56.343851 -382.8532) (xy 56.32849 -382.800957) (xy 56.320713 -382.747061)
			(xy 56.320182 -382.719834) (xy 56.320182 -382.719326) (xy 56.320182 -382.716532) (xy 56.320182 -382.711198)
			(xy 56.320436 -382.70053) (xy 56.306212 -382.665732) (xy 56.304455 -382.661165) (xy 56.302531 -382.651573)
			(xy 56.302402 -382.646682) (xy 56.302402 -381.75057) (xy 56.300878 -381.73787) (xy 56.294782 -381.717042)
			(xy 56.291226 -381.7112) (xy 56.27656 -381.685669) (xy 56.254411 -381.631118) (xy 56.240907 -381.573811)
			(xy 56.236368 -381.51511) (xy 56.240904 -381.456409) (xy 56.254405 -381.399102) (xy 56.276551 -381.344549)
			(xy 56.291226 -381.319024) (xy 56.294782 -381.313182) (xy 56.300878 -381.292354) (xy 56.302402 -381.279654)
			(xy 56.302402 -380.860046) (xy 56.299608 -380.84887) (xy 56.29275 -380.827788) (xy 56.288432 -380.821438)
			(xy 56.288178 -380.821184) (xy 56.272229 -380.797137) (xy 56.246976 -380.745254) (xy 56.229811 -380.690164)
			(xy 56.221125 -380.633119) (xy 56.220614 -380.604268) (xy 56.221118 -380.575414) (xy 56.229769 -380.518359)
			(xy 56.246926 -380.463261) (xy 56.2722 -380.411383) (xy 56.288178 -380.387352) (xy 56.288432 -380.387098)
			(xy 56.29275 -380.380748) (xy 56.299608 -380.359666) (xy 56.302402 -380.34849) (xy 56.302402 -379.351794)
			(xy 56.302305 -379.348115) (xy 56.301158 -379.340846) (xy 56.300116 -379.337316) (xy 56.291226 -379.310646)
			(xy 56.286146 -379.304042) (xy 56.269638 -379.281681) (xy 56.242579 -379.233132) (xy 56.222842 -379.181174)
			(xy 56.210845 -379.126904) (xy 56.20684 -379.071468) (xy 56.210912 -379.016037) (xy 56.222976 -378.961781)
			(xy 56.242775 -378.909847) (xy 56.269893 -378.861331) (xy 56.2864 -378.838968) (xy 56.288432 -378.836428)
			(xy 56.291988 -378.831348) (xy 56.29275 -378.829062) (xy 56.299862 -378.807472) (xy 56.30102 -378.803637)
			(xy 56.302291 -378.795728) (xy 56.302402 -378.791724) (xy 56.302402 -378.594874) (xy 56.30037 -378.581158)
			(xy 56.29783 -378.573284) (xy 56.293258 -378.565918) (xy 56.287162 -378.558552) (xy 56.265572 -378.539248)
			(xy 56.264556 -378.525532) (xy 56.233314 -378.514356) (xy 56.208575 -378.50499) (xy 56.161739 -378.4804)
			(xy 56.11875 -378.449575) (xy 56.080431 -378.413107) (xy 56.047518 -378.371695) (xy 56.020641 -378.326133)
			(xy 56.000317 -378.277295) (xy 55.986934 -378.226117) (xy 55.983378 -378.199904) (xy 55.982108 -378.18949)
			(xy 55.980584 -378.155708) (xy 55.980584 -378.1552) (xy 55.981093 -378.126972) (xy 55.989408 -378.071132)
			(xy 56.005857 -378.017126) (xy 56.030082 -377.966132) (xy 56.061553 -377.919262) (xy 56.099584 -377.877538)
			(xy 56.143346 -377.841871) (xy 56.191884 -377.813039) (xy 56.21782 -377.801886) (xy 56.218328 -377.801886)
			(xy 56.229713 -377.797232) (xy 56.252973 -377.789227) (xy 56.26481 -377.785884) (xy 56.265064 -377.785884)
			(xy 56.273084 -377.783362) (xy 56.286954 -377.773879) (xy 56.292242 -377.767342) (xy 56.297068 -377.760992)
			(xy 56.302402 -377.745498) (xy 56.302402 -377.0122) (xy 56.300116 -377.001786) (xy 56.297322 -376.996198)
			(xy 56.28566 -376.970824) (xy 56.269058 -376.917506) (xy 56.260414 -376.862336) (xy 56.259913 -376.806495)
			(xy 56.263286 -376.778774) (xy 56.267096 -376.755914) (xy 56.26735 -376.755152) (xy 56.268112 -376.750834)
			(xy 56.277764 -376.713496) (xy 56.281871 -376.700694) (xy 56.291659 -376.675652) (xy 56.297322 -376.663458)
			(xy 56.300116 -376.657616) (xy 56.302402 -376.647202) (xy 56.302402 -367.12652) (xy 56.302231 -367.120511)
			(xy 56.299401 -367.108832) (xy 56.296814 -367.103406) (xy 56.294976 -367.099931) (xy 56.290386 -367.093548)
			(xy 56.28767 -367.090706) (xy 55.91937 -366.722406) (xy 55.912515 -366.715011) (xy 55.904767 -366.696412)
			(xy 55.904384 -366.686338) (xy 55.904384 -366.344962) (xy 55.904218 -366.338952) (xy 55.901396 -366.327269)
			(xy 55.898796 -366.321848) (xy 55.896954 -366.318375) (xy 55.892358 -366.312) (xy 55.889652 -366.309148)
			(xy 55.83555 -366.255046) (xy 55.832701 -366.252337) (xy 55.826326 -366.247738) (xy 55.82285 -366.245902)
			(xy 55.817423 -366.243319) (xy 55.805743 -366.240497) (xy 55.799736 -366.240314) (xy 53.525166 -366.240314)
			(xy 53.519156 -366.240479) (xy 53.507472 -366.243301) (xy 53.502052 -366.245902) (xy 53.498579 -366.247743)
			(xy 53.492203 -366.25234) (xy 53.489352 -366.255046) (xy 51.506882 -368.237516) (xy 51.502984 -368.24157)
			(xy 51.496947 -368.251057) (xy 51.494944 -368.256312) (xy 51.401777 -368.516662) (xy 53.966364 -368.516662)
			(xy 53.966364 -367.653062) (xy 53.96685 -367.625793) (xy 53.974612 -367.571809) (xy 53.989977 -367.519479)
			(xy 54.012634 -367.469869) (xy 54.04212 -367.423988) (xy 54.077835 -367.382771) (xy 54.119052 -367.347056)
			(xy 54.164933 -367.31757) (xy 54.214543 -367.294913) (xy 54.266873 -367.279548) (xy 54.320857 -367.271786)
			(xy 54.375395 -367.271786) (xy 54.429379 -367.279548) (xy 54.481709 -367.294913) (xy 54.531319 -367.31757)
			(xy 54.5772 -367.347056) (xy 54.618417 -367.382771) (xy 54.654132 -367.423988) (xy 54.683618 -367.469869)
			(xy 54.706275 -367.519479) (xy 54.72164 -367.571809) (xy 54.729402 -367.625793) (xy 54.729888 -367.653062)
			(xy 54.729888 -368.516662) (xy 54.729402 -368.543931) (xy 54.72164 -368.597915) (xy 54.706275 -368.650245)
			(xy 54.683618 -368.699855) (xy 54.654132 -368.745736) (xy 54.618417 -368.786953) (xy 54.5772 -368.822668)
			(xy 54.531319 -368.852154) (xy 54.481709 -368.874811) (xy 54.429379 -368.890176) (xy 54.375395 -368.897938)
			(xy 54.320857 -368.897938) (xy 54.266873 -368.890176) (xy 54.214543 -368.874811) (xy 54.164933 -368.852154)
			(xy 54.119052 -368.822668) (xy 54.077835 -368.786953) (xy 54.04212 -368.745736) (xy 54.012634 -368.699855)
			(xy 53.989977 -368.650245) (xy 53.974612 -368.597915) (xy 53.96685 -368.543931) (xy 53.966364 -368.516662)
			(xy 51.401777 -368.516662) (xy 50.401935 -371.310662) (xy 53.966364 -371.310662) (xy 53.966364 -370.447062)
			(xy 53.96685 -370.419793) (xy 53.974612 -370.365809) (xy 53.989977 -370.313479) (xy 54.012634 -370.263869)
			(xy 54.04212 -370.217988) (xy 54.077835 -370.176771) (xy 54.119052 -370.141056) (xy 54.164933 -370.11157)
			(xy 54.214543 -370.088913) (xy 54.266873 -370.073548) (xy 54.320857 -370.065786) (xy 54.375395 -370.065786)
			(xy 54.429379 -370.073548) (xy 54.481709 -370.088913) (xy 54.531319 -370.11157) (xy 54.5772 -370.141056)
			(xy 54.618417 -370.176771) (xy 54.654132 -370.217988) (xy 54.683618 -370.263869) (xy 54.706275 -370.313479)
			(xy 54.72164 -370.365809) (xy 54.729402 -370.419793) (xy 54.729888 -370.447062) (xy 54.729888 -371.310662)
			(xy 54.729402 -371.337931) (xy 54.72164 -371.391915) (xy 54.706275 -371.444245) (xy 54.683618 -371.493855)
			(xy 54.654132 -371.539736) (xy 54.618417 -371.580953) (xy 54.5772 -371.616668) (xy 54.531319 -371.646154)
			(xy 54.481709 -371.668811) (xy 54.429379 -371.684176) (xy 54.375395 -371.691938) (xy 54.320857 -371.691938)
			(xy 54.266873 -371.684176) (xy 54.214543 -371.668811) (xy 54.164933 -371.646154) (xy 54.119052 -371.616668)
			(xy 54.077835 -371.580953) (xy 54.04212 -371.539736) (xy 54.012634 -371.493855) (xy 53.989977 -371.444245)
			(xy 53.974612 -371.391915) (xy 53.96685 -371.337931) (xy 53.966364 -371.310662) (xy 50.401935 -371.310662)
			(xy 49.968912 -372.520718) (xy 49.967499 -372.524896) (xy 49.96596 -372.533581) (xy 49.965864 -372.53799)
			(xy 49.965864 -375.882154) (xy 49.965405 -375.925672) (xy 49.957821 -376.012378) (xy 49.942708 -376.098093)
			(xy 49.92018 -376.182164) (xy 49.890408 -376.263951) (xy 49.853621 -376.342831) (xy 49.810097 -376.418204)
			(xy 49.760167 -376.489495) (xy 49.704213 -376.556163) (xy 49.673764 -376.587258) (xy 49.565052 -376.69597)
			(xy 54.986172 -376.69597) (xy 54.990243 -376.640348) (xy 55.002369 -376.585911) (xy 55.022292 -376.53382)
			(xy 55.049588 -376.485185) (xy 55.083674 -376.441042) (xy 55.123823 -376.402333) (xy 55.169181 -376.369882)
			(xy 55.218781 -376.344381) (xy 55.271565 -376.326374) (xy 55.326408 -376.316244) (xy 55.382142 -376.314207)
			(xy 55.437579 -376.320307) (xy 55.491536 -376.334413) (xy 55.542865 -376.356225) (xy 55.590471 -376.385279)
			(xy 55.633339 -376.420954) (xy 55.670556 -376.462491) (xy 55.701329 -376.509004) (xy 55.725001 -376.559501)
			(xy 55.741069 -376.612908) (xy 55.749189 -376.668084) (xy 55.749698 -376.69597) (xy 55.749189 -376.723856)
			(xy 55.741069 -376.779032) (xy 55.725001 -376.832439) (xy 55.701329 -376.882936) (xy 55.670556 -376.929449)
			(xy 55.633339 -376.970986) (xy 55.590471 -377.006661) (xy 55.542865 -377.035715) (xy 55.491536 -377.057527)
			(xy 55.437579 -377.071633) (xy 55.382142 -377.077733) (xy 55.326408 -377.075696) (xy 55.271565 -377.065566)
			(xy 55.218781 -377.047559) (xy 55.169181 -377.022058) (xy 55.123823 -376.989607) (xy 55.083674 -376.950898)
			(xy 55.049588 -376.906755) (xy 55.022292 -376.85812) (xy 55.002369 -376.806029) (xy 54.990243 -376.751592)
			(xy 54.986172 -376.69597) (xy 49.565052 -376.69597) (xy 49.27473 -376.986292) (xy 49.241403 -377.018853)
			(xy 49.169652 -377.078303) (xy 49.092667 -377.130801) (xy 49.011121 -377.175886) (xy 48.925724 -377.213167)
			(xy 48.837221 -377.242318) (xy 48.746385 -377.263085) (xy 48.654007 -377.275287) (xy 48.607472 -377.27763)
			(xy 48.594813 -377.278824) (xy 48.572951 -377.291745) (xy 48.565816 -377.302268) (xy 48.54341 -377.338818)
			(xy 48.493232 -377.408339) (xy 48.43727 -377.473294) (xy 48.375937 -377.533204) (xy 48.309686 -377.587626)
			(xy 48.239007 -377.636158) (xy 48.164421 -377.678441) (xy 48.08648 -377.714164) (xy 48.005759 -377.743062)
			(xy 47.922855 -377.764923) (xy 47.838381 -377.779583) (xy 47.752959 -377.786936) (xy 47.71009 -377.787408)
			(xy 47.709328 -377.787408) (xy 47.666455 -377.786924) (xy 47.58103 -377.779513) (xy 47.496556 -377.764795)
			(xy 47.413659 -377.742878) (xy 47.332949 -377.713925) (xy 47.293784 -377.696476) (xy 47.286164 -377.697746)
			(xy 47.272194 -377.70308) (xy 47.2694 -377.703842) (xy 47.267876 -377.70435) (xy 47.266606 -377.704858)
			(xy 47.265082 -377.705366) (xy 47.262796 -377.706128) (xy 47.262542 -377.706128) (xy 47.25543 -377.70816)
			(xy 47.241714 -377.71197) (xy 47.210726 -377.718574) (xy 47.196979 -377.720732) (xy 47.169265 -377.723278)
			(xy 47.155354 -377.723654) (xy 47.14494 -377.723654) (xy 47.117833 -377.72296) (xy 47.064219 -377.714851)
			(xy 47.012294 -377.699232) (xy 46.963103 -377.676418) (xy 46.917639 -377.646868) (xy 46.876818 -377.611177)
			(xy 46.841462 -377.570066) (xy 46.812284 -377.524362) (xy 46.789872 -377.474987) (xy 46.774677 -377.422936)
			(xy 46.767006 -377.369258) (xy 46.76648 -377.342146) (xy 46.76648 -377.337574) (xy 46.766988 -377.32081)
			(xy 46.767993 -377.305765) (xy 46.772064 -377.275886) (xy 46.775116 -377.26112) (xy 46.77843 -377.246486)
			(xy 46.787074 -377.217748) (xy 46.792388 -377.203716) (xy 46.794166 -377.199652) (xy 46.794166 -377.199398)
			(xy 46.796198 -377.189492) (xy 46.780125 -377.151674) (xy 46.753513 -377.073924) (xy 46.733383 -376.994249)
			(xy 46.71987 -376.913189) (xy 46.713065 -376.831293) (xy 46.712632 -376.790204) (xy 46.712632 -376.408188)
			(xy 46.713213 -376.360839) (xy 46.722247 -376.266572) (xy 46.730666 -376.219974) (xy 46.731936 -376.211846)
			(xy 46.734222 -376.196606) (xy 46.735492 -376.188986) (xy 46.738794 -376.170698) (xy 46.693328 -376.132598)
			(xy 46.686399 -376.127224) (xy 46.669975 -376.121117) (xy 46.652453 -376.120938) (xy 46.644052 -376.123454)
			(xy 46.605607 -376.136359) (xy 46.52708 -376.15663) (xy 46.447166 -376.170459) (xy 46.406816 -376.174508)
			(xy 46.3677 -376.199146) (xy 46.345349 -376.235919) (xy 46.295214 -376.30587) (xy 46.239239 -376.371241)
			(xy 46.17784 -376.431547) (xy 46.111475 -376.48634) (xy 46.040636 -376.535212) (xy 45.965851 -376.577799)
			(xy 45.887674 -376.613786) (xy 45.806689 -376.642905) (xy 45.723495 -376.664938) (xy 45.638713 -376.679723)
			(xy 45.552973 -376.687149) (xy 45.509942 -376.687588) (xy 45.468965 -376.687162) (xy 45.387287 -376.680418)
			(xy 45.306439 -376.666997) (xy 45.226964 -376.646988) (xy 45.149398 -376.620528) (xy 45.11167 -376.60453)
			(xy 45.101764 -376.600212) (xy 45.07992 -376.600212) (xy 45.072046 -376.603006) (xy 45.042036 -376.612643)
			(xy 44.979862 -376.622977) (xy 44.948348 -376.62358) (xy 44.947332 -376.62358) (xy 44.920103 -376.623062)
			(xy 44.866208 -376.615251) (xy 44.813971 -376.599855) (xy 44.764454 -376.577187) (xy 44.718665 -376.547708)
			(xy 44.677533 -376.512016) (xy 44.641895 -376.470838) (xy 44.612475 -376.42501) (xy 44.589871 -376.375464)
			(xy 44.574543 -376.323207) (xy 44.566802 -376.269301) (xy 44.566332 -376.242072) (xy 44.566332 -376.2375)
			(xy 44.56684 -376.220736) (xy 44.567844 -376.205691) (xy 44.571912 -376.175811) (xy 44.574968 -376.161046)
			(xy 44.578286 -376.146413) (xy 44.586936 -376.117678) (xy 44.59224 -376.103642) (xy 44.594018 -376.099578)
			(xy 44.594018 -376.099324) (xy 44.59605 -376.089418) (xy 44.579977 -376.0516) (xy 44.553364 -375.97385)
			(xy 44.533233 -375.894175) (xy 44.519718 -375.813116) (xy 44.512912 -375.731219) (xy 44.512484 -375.69013)
			(xy 44.512484 -375.308114) (xy 44.513011 -375.263019) (xy 44.521197 -375.173199) (xy 44.537449 -375.084484)
			(xy 44.54906 -375.040906) (xy 44.549314 -375.03989) (xy 44.537641 -374.996235) (xy 44.521287 -374.907354)
			(xy 44.513033 -374.81736) (xy 44.512484 -374.772174) (xy 44.512484 -374.390158) (xy 44.512909 -374.34918)
			(xy 44.519652 -374.267503) (xy 44.533071 -374.186654) (xy 44.553078 -374.107178) (xy 44.579537 -374.029611)
			(xy 44.595542 -373.991886) (xy 44.59351 -373.981218) (xy 44.587922 -373.96547) (xy 44.587922 -373.965216)
			(xy 44.586398 -373.96039) (xy 44.585382 -373.95785) (xy 44.576483 -373.928941) (xy 44.566904 -373.86922)
			(xy 44.566332 -373.838978) (xy 44.566332 -373.838724) (xy 44.566332 -373.835676) (xy 44.566332 -373.827802)
			(xy 44.56811 -373.80037) (xy 44.568872 -373.79402) (xy 44.572642 -373.766268) (xy 44.58726 -373.712204)
			(xy 44.609615 -373.660855) (xy 44.639229 -373.61332) (xy 44.675467 -373.570619) (xy 44.717552 -373.533668)
			(xy 44.764581 -373.503258) (xy 44.815548 -373.480041) (xy 44.869358 -373.464516) (xy 44.89704 -373.460264)
			(xy 44.897294 -373.460264) (xy 44.899072 -373.46001) (xy 44.909849 -373.457596) (xy 44.92802 -373.445084)
			(xy 44.934124 -373.43588) (xy 44.95546 -373.397526) (xy 44.974764 -373.362982) (xy 44.977812 -373.355362)
			(xy 44.978574 -373.35206) (xy 44.979622 -373.346846) (xy 44.979755 -373.336214) (xy 44.978828 -373.330978)
			(xy 44.976542 -373.319548) (xy 44.975272 -373.3165) (xy 44.97451 -373.314722) (xy 44.968214 -373.299449)
			(xy 44.957157 -373.268316) (xy 44.952412 -373.252492) (xy 44.948094 -373.236744) (xy 44.94149 -373.209058)
			(xy 44.94149 -373.20855) (xy 44.937934 -373.19331) (xy 44.93768 -373.191278) (xy 44.937426 -373.189754)
			(xy 44.937426 -373.188484) (xy 44.935648 -373.1768) (xy 44.934124 -373.166132) (xy 44.934124 -373.165624)
			(xy 44.933616 -373.162068) (xy 44.931838 -373.14505) (xy 44.930568 -373.128794) (xy 44.929552 -373.111776)
			(xy 44.929298 -373.110506) (xy 44.929298 -373.090186) (xy 44.929809 -373.055409) (xy 44.938118 -372.986353)
			(xy 44.954614 -372.918784) (xy 44.979062 -372.853669) (xy 45.011112 -372.791939) (xy 45.050305 -372.73448)
			(xy 45.09608 -372.682112) (xy 45.147782 -372.635586) (xy 45.204671 -372.595568) (xy 45.265931 -372.56263)
			(xy 45.298106 -372.54942) (xy 45.325792 -372.538498) (xy 45.330364 -372.531894) (xy 45.330364 -372.420388)
			(xy 45.32285 -372.412559) (xy 45.303104 -372.403613) (xy 45.292264 -372.403116) (xy 45.151802 -372.403116)
			(xy 45.141633 -372.40269) (xy 45.122846 -372.394904) (xy 45.108472 -372.380517) (xy 45.100702 -372.361723)
			(xy 45.10024 -372.351554) (xy 45.10024 -372.068852) (xy 45.100169 -372.064642) (xy 45.098771 -372.056339)
			(xy 45.097446 -372.052342) (xy 45.093128 -372.039642) (xy 45.090588 -372.035324) (xy 45.074815 -372.007327)
			(xy 45.049974 -371.948063) (xy 45.033167 -371.88604) (xy 45.024689 -371.822342) (xy 45.024687 -371.758082)
			(xy 45.033163 -371.694384) (xy 45.049966 -371.63236) (xy 45.074805 -371.573095) (xy 45.090588 -371.545104)
			(xy 45.093128 -371.540786) (xy 45.097446 -371.528086) (xy 45.098726 -371.524078) (xy 45.100124 -371.515782)
			(xy 45.10024 -371.511576) (xy 45.10024 -370.768626) (xy 45.100166 -370.764416) (xy 45.098765 -370.756115)
			(xy 45.097446 -370.752116) (xy 45.093128 -370.739416) (xy 45.090588 -370.735098) (xy 45.074817 -370.707101)
			(xy 45.049979 -370.647838) (xy 45.033176 -370.585815) (xy 45.024701 -370.522119) (xy 45.024702 -370.457861)
			(xy 45.03318 -370.394164) (xy 45.049986 -370.332143) (xy 45.074826 -370.27288) (xy 45.090588 -370.244878)
			(xy 45.093128 -370.24056) (xy 45.097446 -370.22786) (xy 45.098732 -370.223853) (xy 45.100142 -370.215557)
			(xy 45.10024 -370.21135) (xy 45.10024 -369.928902) (xy 45.100665 -369.91873) (xy 45.10845 -369.899935)
			(xy 45.122835 -369.88555) (xy 45.14163 -369.877765) (xy 45.151802 -369.87734) (xy 45.292264 -369.87734)
			(xy 45.303097 -369.876824) (xy 45.322828 -369.867869) (xy 45.330364 -369.860068) (xy 45.330364 -369.748308)
			(xy 45.325792 -369.741704) (xy 45.298106 -369.730782) (xy 45.268064 -369.718532) (xy 45.210666 -369.688281)
			(xy 45.156999 -369.651821) (xy 45.10773 -369.609605) (xy 45.063474 -369.56216) (xy 45.024782 -369.510078)
			(xy 44.992137 -369.454008) (xy 44.965946 -369.394648) (xy 44.946535 -369.332738) (xy 44.934146 -369.26905)
			(xy 44.931076 -369.236752) (xy 44.930314 -369.226592) (xy 44.929298 -369.190016) (xy 44.929783 -369.155981)
			(xy 44.937736 -369.088376) (xy 44.953534 -369.022165) (xy 44.976961 -368.958252) (xy 45.007696 -368.897516)
			(xy 45.045319 -368.840787) (xy 45.089312 -368.788843) (xy 45.139074 -368.742396) (xy 45.193923 -368.702083)
			(xy 45.253107 -368.668455) (xy 45.315816 -368.641973) (xy 45.381189 -368.623001) (xy 45.414692 -368.616992)
			(xy 45.42155 -368.615722) (xy 45.43298 -368.610896) (xy 45.43425 -368.60988) (xy 45.441616 -368.603784)
			(xy 45.442632 -368.602768) (xy 45.446442 -368.599466) (xy 45.451622 -368.594523) (xy 45.45924 -368.582407)
			(xy 45.461428 -368.57559) (xy 45.691806 -367.792508) (xy 45.705726 -367.747038) (xy 45.741072 -367.65875)
			(xy 45.784659 -367.574227) (xy 45.809916 -367.533936) (xy 46.166024 -366.98047) (xy 46.168056 -366.973104)
			(xy 46.179738 -366.932895) (xy 46.20899 -366.854432) (xy 46.226476 -366.816386) (xy 46.415452 -366.41659)
			(xy 46.43344 -366.379487) (xy 46.474731 -366.308108) (xy 46.52182 -366.240412) (xy 46.574379 -366.17687)
			(xy 46.602904 -366.147096) (xy 46.608746 -366.141254) (xy 46.622716 -366.11433) (xy 46.623732 -366.104932)
			(xy 46.628575 -366.063855) (xy 46.644244 -365.982632) (xy 46.666642 -365.903003) (xy 46.695613 -365.825523)
			(xy 46.712886 -365.78794) (xy 46.901862 -365.388144) (xy 46.923303 -365.344188) (xy 46.973632 -365.260327)
			(xy 47.031988 -365.181839) (xy 47.097803 -365.109491) (xy 47.170433 -365.043989) (xy 47.209456 -365.01451)
			(xy 47.215298 -365.00943) (xy 47.223426 -365.001302) (xy 47.227744 -364.994444) (xy 50.401474 -358.284526)
			(xy 50.407292 -358.271099) (xy 50.411788 -358.242194) (xy 50.407912 -358.2132) (xy 50.395981 -358.186492)
			(xy 50.376972 -358.164259) (xy 50.352444 -358.14832) (xy 50.324405 -358.139984) (xy 50.30978 -358.139492)
			(xy 50.307748 -358.139492) (xy 50.280473 -358.139032) (xy 50.226476 -358.131275) (xy 50.174134 -358.115911)
			(xy 50.124511 -358.093255) (xy 50.078617 -358.063766) (xy 50.037388 -358.028046) (xy 50.001663 -357.986821)
			(xy 49.972168 -357.940932) (xy 49.949506 -357.891311) (xy 49.934136 -357.838971) (xy 49.926372 -357.784975)
			(xy 49.926372 -357.730425) (xy 49.934136 -357.676429) (xy 49.949506 -357.624089) (xy 49.972168 -357.574468)
			(xy 50.001663 -357.528579) (xy 50.037388 -357.487354) (xy 50.078617 -357.451634) (xy 50.124511 -357.422145)
			(xy 50.174134 -357.399489) (xy 50.226476 -357.384125) (xy 50.280473 -357.376368) (xy 50.307748 -357.375968)
			(xy 50.798984 -357.375968) (xy 50.802854 -357.375919) (xy 50.810508 -357.374767) (xy 50.814224 -357.373682)
			(xy 50.823841 -357.37018) (xy 50.83943 -357.356947) (xy 50.84445 -357.348028) (xy 53.244242 -352.274886)
			(xy 53.244242 -352.2599) (xy 53.243988 -352.24593) (xy 53.243988 -352.245168) (xy 53.244629 -352.215448)
			(xy 53.254589 -352.156846) (xy 53.2638 -352.128582) (xy 53.2638 -352.128074) (xy 53.264054 -352.12782)
			(xy 53.265837 -352.122159) (xy 53.267002 -352.11035) (xy 53.26634 -352.104452) (xy 53.264562 -352.09226)
			(xy 53.226716 -352.039174) (xy 53.220366 -352.026982) (xy 53.220366 -352.026728) (xy 53.220112 -352.026474)
			(xy 53.217235 -352.019376) (xy 53.207926 -352.007225) (xy 53.201824 -352.002598) (xy 53.195239 -351.998269)
			(xy 53.180235 -351.993478) (xy 53.17236 -351.9932) (xy 52.538884 -351.9932) (xy 52.511613 -351.992712)
			(xy 52.457625 -351.984948) (xy 52.405293 -351.96958) (xy 52.35568 -351.94692) (xy 52.309796 -351.917431)
			(xy 52.268576 -351.881712) (xy 52.232859 -351.840491) (xy 52.203372 -351.794606) (xy 52.180715 -351.744992)
			(xy 52.165349 -351.692659) (xy 52.157586 -351.638671) (xy 52.157586 -351.584129) (xy 52.165349 -351.530141)
			(xy 52.180715 -351.477808) (xy 52.203372 -351.428194) (xy 52.232859 -351.382309) (xy 52.268576 -351.341088)
			(xy 52.309796 -351.305369) (xy 52.35568 -351.27588) (xy 52.405293 -351.25322) (xy 52.457625 -351.237852)
			(xy 52.511613 -351.230088) (xy 52.538884 -351.229676) (xy 53.163216 -351.229676) (xy 53.173122 -351.22866)
			(xy 53.179472 -351.22739) (xy 53.188186 -351.225217) (xy 53.20342 -351.215728) (xy 53.20919 -351.208848)
			(xy 53.210714 -351.206816) (xy 53.227224 -351.183194) (xy 53.255926 -351.142046) (xy 53.257196 -351.140268)
			(xy 53.260252 -351.134503) (xy 53.263598 -351.121897) (xy 53.2638 -351.115376) (xy 53.2638 -351.103184)
			(xy 53.26126 -351.087436) (xy 53.260244 -351.08388) (xy 53.25999 -351.083372) (xy 53.252502 -351.057666)
			(xy 53.244459 -351.004732) (xy 53.243988 -350.977962) (xy 53.243988 -350.977454) (xy 53.244429 -350.951835)
			(xy 53.25176 -350.901125) (xy 53.266279 -350.851988) (xy 53.287687 -350.805437) (xy 53.315542 -350.762433)
			(xy 53.349269 -350.723862) (xy 53.388174 -350.69052) (xy 53.409596 -350.676464) (xy 53.415184 -350.672908)
			(xy 53.423566 -350.664018) (xy 53.427376 -350.65716) (xy 53.427376 -349.552514) (xy 53.427161 -349.546285)
			(xy 53.42407 -349.534213) (xy 53.42128 -349.528638) (xy 53.327554 -349.35287) (xy 53.322904 -349.344988)
			(xy 53.309163 -349.332921) (xy 53.292058 -349.326455) (xy 53.273771 -349.326413) (xy 53.26507 -349.329248)
			(xy 53.261514 -349.330518) (xy 53.2533 -349.303638) (xy 53.24449 -349.24813) (xy 53.243988 -349.220028)
			(xy 53.243988 -349.209868) (xy 53.245289 -349.182521) (xy 53.255239 -349.128685) (xy 53.2638 -349.10268)
			(xy 53.265832 -349.096838) (xy 53.267102 -349.0849) (xy 53.266086 -349.07855) (xy 53.265055 -349.072558)
			(xy 53.260555 -349.061266) (xy 53.257196 -349.056198) (xy 53.247036 -349.042228) (xy 53.23332 -349.022924)
			(xy 53.23332 -349.022416) (xy 53.211984 -348.992952) (xy 53.211984 -348.992698) (xy 53.203094 -348.98203)
			(xy 53.20157 -348.98076) (xy 53.201316 -348.980506) (xy 53.198776 -348.978474) (xy 53.191948 -348.973482)
			(xy 53.175986 -348.967915) (xy 53.167534 -348.967552) (xy 52.538884 -348.967552) (xy 52.511616 -348.967065)
			(xy 52.457636 -348.959301) (xy 52.405309 -348.943935) (xy 52.355703 -348.921278) (xy 52.309825 -348.891793)
			(xy 52.26861 -348.856078) (xy 52.232898 -348.814862) (xy 52.203414 -348.768983) (xy 52.18076 -348.719376)
			(xy 52.165395 -348.667049) (xy 52.157634 -348.613068) (xy 52.157634 -348.558532) (xy 52.165395 -348.504551)
			(xy 52.18076 -348.452224) (xy 52.203414 -348.402617) (xy 52.232898 -348.356738) (xy 52.26861 -348.315522)
			(xy 52.309825 -348.279807) (xy 52.355703 -348.250322) (xy 52.405309 -348.227665) (xy 52.457636 -348.212299)
			(xy 52.511616 -348.204535) (xy 52.538884 -348.204028) (xy 53.080412 -348.204028) (xy 53.094687 -348.203558)
			(xy 53.122122 -348.195666) (xy 53.146294 -348.180477) (xy 53.165307 -348.159181) (xy 53.17767 -348.133449)
			(xy 53.182414 -348.105297) (xy 53.179166 -348.076935) (xy 53.174138 -348.063566) (xy 51.253136 -343.427304)
			(xy 51.251164 -343.422824) (xy 51.245794 -343.41464) (xy 51.242468 -343.411048) (xy 51.235864 -343.404444)
			(xy 51.226466 -343.40038) (xy 51.202971 -343.389598) (xy 51.159097 -343.362261) (xy 51.119624 -343.328881)
			(xy 51.085378 -343.290158) (xy 51.057074 -343.246901) (xy 51.035305 -343.200015) (xy 51.020525 -343.150479)
			(xy 51.013044 -343.099329) (xy 51.012598 -343.073482) (xy 51.013868 -343.042748) (xy 51.01463 -343.038176)
			(xy 51.01463 -343.03716) (xy 51.0159 -343.026746) (xy 51.016916 -343.019634) (xy 51.016916 -343.01938)
			(xy 51.017772 -343.011552) (xy 51.015185 -342.996027) (xy 51.011836 -342.9889) (xy 51.000914 -342.967564)
			(xy 50.994564 -342.959436) (xy 50.993294 -342.95842) (xy 50.989992 -342.95588) (xy 50.988722 -342.954864)
			(xy 50.983642 -342.9508) (xy 50.966878 -342.94318) (xy 50.960528 -342.940132) (xy 50.945034 -342.937846)
			(xy 50.932444 -342.936988) (xy 50.908979 -342.946183) (xy 50.90033 -342.955372) (xy 50.899314 -342.956642)
			(xy 50.896012 -342.960198) (xy 50.895504 -342.960706) (xy 50.875401 -342.980512) (xy 50.830415 -343.01458)
			(xy 50.780903 -343.041654) (xy 50.727943 -343.061141) (xy 50.672692 -343.072618) (xy 50.644552 -343.074752)
			(xy 50.613564 -343.087452) (xy 50.591212 -343.107264) (xy 50.574956 -343.136474) (xy 50.56957 -343.163522)
			(xy 50.551564 -343.215649) (xy 50.525737 -343.264376) (xy 50.492706 -343.308539) (xy 50.45326 -343.34708)
			(xy 50.408344 -343.379079) (xy 50.359031 -343.403771) (xy 50.306502 -343.420564) (xy 50.252011 -343.429057)
			(xy 50.224436 -343.42959) (xy 50.223928 -343.42959) (xy 50.211503 -343.429454) (xy 50.186715 -343.427674)
			(xy 50.174398 -343.426034) (xy 50.170855 -343.425594) (xy 50.163717 -343.425594) (xy 50.160174 -343.426034)
			(xy 50.147858 -343.427686) (xy 50.12307 -343.429468) (xy 50.110644 -343.42959) (xy 50.110136 -343.42959)
			(xy 50.082332 -343.429051) (xy 50.0274 -343.420402) (xy 49.97448 -343.403323) (xy 49.924855 -343.37823)
			(xy 49.879731 -343.345732) (xy 49.840204 -343.306618) (xy 49.807233 -343.261838) (xy 49.781621 -343.21248)
			(xy 49.763987 -343.159741) (xy 49.758854 -343.13241) (xy 49.757584 -343.124282) (xy 49.754028 -343.117424)
			(xy 49.752156 -343.114028) (xy 49.747568 -343.107777) (xy 49.744884 -343.104978) (xy 49.72431 -343.084404)
			(xy 49.721381 -343.081518) (xy 49.714739 -343.07667) (xy 49.711102 -343.074752) (xy 49.704752 -343.071704)
			(xy 49.696624 -343.07018) (xy 49.696116 -343.07018) (xy 49.669727 -343.065287) (xy 49.618563 -343.049077)
			(xy 49.570171 -343.025866) (xy 49.525504 -342.996111) (xy 49.485441 -342.960397) (xy 49.45077 -342.919428)
			(xy 49.422175 -342.87401) (xy 49.400217 -342.825037) (xy 49.385329 -342.773473) (xy 49.377804 -342.720333)
			(xy 49.377346 -342.693498) (xy 49.377346 -342.693244) (xy 49.377801 -342.667012) (xy 49.385012 -342.615045)
			(xy 49.399249 -342.564549) (xy 49.40935 -342.540336) (xy 49.411382 -342.53551) (xy 49.412652 -342.529414)
			(xy 49.413922 -342.523572) (xy 49.414757 -342.51911) (xy 49.41502 -342.510038) (xy 49.41443 -342.505538)
			(xy 49.413668 -342.500712) (xy 49.413668 -342.500204) (xy 49.412906 -342.495886) (xy 49.410761 -342.482716)
			(xy 49.408346 -342.456141) (xy 49.40808 -342.4428) (xy 49.40808 -342.43645) (xy 49.408871 -342.409387)
			(xy 49.41818 -342.356055) (xy 49.436051 -342.304952) (xy 49.462006 -342.257441) (xy 49.495353 -342.214792)
			(xy 49.5352 -342.178144) (xy 49.580484 -342.148474) (xy 49.629996 -342.126576) (xy 49.682413 -342.113033)
			(xy 49.709324 -342.11006) (xy 49.713134 -342.109806) (xy 49.722024 -342.109044) (xy 49.732692 -342.102186)
			(xy 49.737708 -342.098656) (xy 49.746046 -342.089666) (xy 49.749202 -342.084406) (xy 49.76876 -342.049608)
			(xy 49.791366 -342.009222) (xy 49.794404 -342.002276) (xy 49.796715 -341.9873) (xy 49.795938 -341.979758)
			(xy 49.794414 -341.972646) (xy 49.792128 -341.966296) (xy 49.79035 -341.962486) (xy 49.78654 -341.954612)
			(xy 49.783492 -341.947754) (xy 49.778006 -341.934815) (xy 49.768853 -341.90824) (xy 49.765204 -341.894668)
			(xy 49.76368 -341.888572) (xy 49.76076 -341.875893) (xy 49.756567 -341.850213) (xy 49.755298 -341.837264)
			(xy 49.755044 -341.834978) (xy 49.753017 -341.823688) (xy 49.740452 -341.804523) (xy 49.730914 -341.798148)
			(xy 31.529528 -330.887832) (xy 31.528512 -330.887324) (xy 31.113984 -330.648818) (xy 31.099569 -330.640473)
			(xy 31.071242 -330.622943) (xy 31.057342 -330.613766) (xy 30.681422 -330.362814) (xy 30.675061 -330.358837)
			(xy 30.660725 -330.354448) (xy 30.653228 -330.354178) (xy 24.746712 -330.354178) (xy 24.736641 -330.353757)
			(xy 24.718036 -330.346043) (xy 24.710644 -330.339192) (xy 17.067276 -322.695824) (xy 17.060433 -322.688425)
			(xy 17.052715 -322.669826) (xy 17.05229 -322.659756) (xy 17.05229 -308.147212) (xy 17.050766 -308.13502)
			(xy 17.048988 -308.127908) (xy 17.041368 -308.106572) (xy 17.036034 -308.099714) (xy 17.018606 -308.077067)
			(xy 16.990016 -308.027591) (xy 16.969124 -307.974404) (xy 16.956399 -307.918696) (xy 16.952124 -307.861713)
			(xy 16.956395 -307.804729) (xy 16.969117 -307.74902) (xy 16.990005 -307.695832) (xy 17.018592 -307.646353)
			(xy 17.036034 -307.623718) (xy 17.041368 -307.61686) (xy 17.047464 -307.599842) (xy 17.048734 -307.595524)
			(xy 17.050512 -307.588666) (xy 17.05229 -307.575712) (xy 17.05229 -302.76927) (xy 17.052155 -302.764379)
			(xy 17.050241 -302.754785) (xy 17.04848 -302.75022) (xy 17.014819 -302.670939) (xy 16.95464 -302.509534)
			(xy 16.902766 -302.345273) (xy 16.85933 -302.178581) (xy 16.824446 -302.009891) (xy 16.798205 -301.839644)
			(xy 16.780674 -301.66828) (xy 16.771899 -301.496245) (xy 16.771366 -301.410116) (xy 16.771366 -301.3964)
			(xy 16.772246 -301.311202) (xy 16.781531 -301.141052) (xy 16.799377 -300.971586) (xy 16.82574 -300.803235)
			(xy 16.860553 -300.636426) (xy 16.903728 -300.471584) (xy 16.955154 -300.309126) (xy 17.014701 -300.149467)
			(xy 17.047972 -300.071028) (xy 17.050766 -300.064678) (xy 17.05229 -300.053756) (xy 17.05229 -278.776176)
			(xy 17.051798 -278.766172) (xy 17.044133 -278.74769) (xy 17.029981 -278.733547) (xy 17.011494 -278.725896)
			(xy 17.00149 -278.725376) (xy 10.813542 -278.725376) (xy 10.795 -278.717756) (xy 10.78992 -278.712676)
			(xy 10.788904 -278.71166) (xy 10.390124 -278.31288) (xy 10.383347 -278.305455) (xy 10.375757 -278.286858)
			(xy 10.375392 -278.276812) (xy 10.375392 -276.757892) (xy 10.375392 -276.75713) (xy 10.375392 -276.737318)
			(xy 10.382504 -276.730206) (xy 10.382758 -276.729698) (xy 10.386822 -276.725634) (xy 10.388346 -276.72411)
			(xy 10.92454 -276.187916) (xy 10.930131 -276.181916) (xy 10.937497 -276.167274) (xy 10.939018 -276.159214)
			(xy 10.940034 -276.151594) (xy 10.93724 -276.135338) (xy 10.933176 -276.127972) (xy 10.918742 -276.099942)
			(xy 10.89826 -276.040318) (xy 10.887868 -275.978137) (xy 10.887202 -275.946616) (xy 10.887705 -275.918879)
			(xy 10.895748 -275.863991) (xy 10.911651 -275.810845) (xy 10.93508 -275.760561) (xy 10.965541 -275.714199)
			(xy 11.002393 -275.672734) (xy 11.044859 -275.637041) (xy 11.092045 -275.60787) (xy 11.142956 -275.585838)
			(xy 11.19652 -275.571407) (xy 11.224006 -275.567648) (xy 11.237722 -275.566124) (xy 11.26871 -275.564854)
			(xy 11.29648 -275.565355) (xy 11.351432 -275.573409) (xy 11.404636 -275.589345) (xy 11.454968 -275.612826)
			(xy 11.501363 -275.643357) (xy 11.542841 -275.680292) (xy 11.561064 -275.701252) (xy 11.562334 -275.702776)
			(xy 11.569954 -275.710396) (xy 11.578844 -275.716238) (xy 11.594846 -275.724112) (xy 11.598829 -275.726349)
			(xy 11.60739 -275.729534) (xy 11.611864 -275.730462) (xy 11.616182 -275.731224) (xy 12.663932 -275.731224)
			(xy 12.676124 -275.7297) (xy 12.686792 -275.726398) (xy 12.708521 -275.720496) (xy 12.75296 -275.713238)
			(xy 12.775438 -275.71192) (xy 12.776962 -275.71192) (xy 12.783312 -275.711666) (xy 12.78763 -275.711666)
			(xy 12.79271 -275.711666) (xy 12.793472 -275.711666) (xy 12.822244 -275.712207) (xy 12.879132 -275.720876)
			(xy 12.906756 -275.728938) (xy 12.914122 -275.731224) (xy 13.806932 -275.731224) (xy 13.815822 -275.730462)
			(xy 13.829538 -275.727668) (xy 13.833602 -275.726144) (xy 13.855595 -275.718036) (xy 13.90106 -275.706626)
			(xy 13.947579 -275.700854) (xy 13.971016 -275.70049) (xy 13.995137 -275.700878) (xy 14.042992 -275.70699)
			(xy 14.089697 -275.719077) (xy 14.11224 -275.727668) (xy 14.121384 -275.731224) (xy 15.309596 -275.731224)
			(xy 15.321356 -275.730638) (xy 15.342422 -275.720183) (xy 15.349982 -275.711158) (xy 15.379446 -275.67255)
			(xy 15.379954 -275.672042) (xy 15.39875 -275.646896) (xy 15.402853 -275.640442) (xy 15.407369 -275.625837)
			(xy 15.40764 -275.618194) (xy 15.40764 -275.603208) (xy 15.406116 -275.597112) (xy 15.400542 -275.573888)
			(xy 15.394553 -275.526504) (xy 15.394178 -275.502624) (xy 15.394639 -275.47537) (xy 15.402393 -275.421415)
			(xy 15.417747 -275.369114) (xy 15.440388 -275.31953) (xy 15.469855 -275.273672) (xy 15.505549 -275.232476)
			(xy 15.546742 -275.196778) (xy 15.592596 -275.167306) (xy 15.642178 -275.14466) (xy 15.694478 -275.129301)
			(xy 15.748432 -275.121542) (xy 15.775686 -275.121116) (xy 15.80427 -275.121625) (xy 15.860797 -275.130158)
			(xy 15.915417 -275.147034) (xy 15.966906 -275.171876) (xy 16.014108 -275.204126) (xy 16.055967 -275.243062)
			(xy 16.074136 -275.265134) (xy 16.075914 -275.26742) (xy 16.078708 -275.270214) (xy 16.086172 -275.276699)
			(xy 16.104549 -275.283945) (xy 16.124301 -275.283739) (xy 16.142524 -275.276114) (xy 16.149828 -275.269452)
			(xy 16.1671 -275.25218) (xy 16.169803 -275.249327) (xy 16.174391 -275.242946) (xy 16.176244 -275.23948)
			(xy 16.178832 -275.234054) (xy 16.181664 -275.222375) (xy 16.181832 -275.216366) (xy 16.181832 -274.609306)
			(xy 16.18166 -274.603298) (xy 16.178829 -274.591619) (xy 16.176244 -274.586192) (xy 16.173704 -274.580858)
			(xy 16.166084 -274.571968) (xy 16.161258 -274.568412) (xy 16.159226 -274.566634) (xy 16.154908 -274.563078)
			(xy 16.126206 -274.549362) (xy 16.070834 -274.5232) (xy 16.057372 -274.518882) (xy 16.050514 -274.517866)
			(xy 16.043402 -274.518628) (xy 16.028162 -274.520152) (xy 16.007129 -274.537961) (xy 15.960913 -274.567985)
			(xy 15.91087 -274.591072) (xy 15.858033 -274.606745) (xy 15.803496 -274.614681) (xy 15.77594 -274.615148)
			(xy 15.775686 -274.615148) (xy 15.748361 -274.61466) (xy 15.694268 -274.60688) (xy 15.641832 -274.591482)
			(xy 15.592122 -274.568779) (xy 15.546148 -274.539232) (xy 15.504847 -274.503443) (xy 15.46906 -274.462141)
			(xy 15.439515 -274.416166) (xy 15.416813 -274.366455) (xy 15.401417 -274.314018) (xy 15.393639 -274.259925)
			(xy 15.393639 -274.205275) (xy 15.401417 -274.151182) (xy 15.416813 -274.098745) (xy 15.439515 -274.049034)
			(xy 15.46906 -274.003059) (xy 15.504847 -273.961757) (xy 15.546148 -273.925968) (xy 15.592122 -273.896421)
			(xy 15.641832 -273.873718) (xy 15.694268 -273.85832) (xy 15.748361 -273.85054) (xy 15.775686 -273.8501)
			(xy 15.801268 -273.850517) (xy 15.851971 -273.857361) (xy 15.901306 -273.870915) (xy 15.948389 -273.890937)
			(xy 15.992377 -273.917067) (xy 16.012668 -273.93265) (xy 16.01978 -273.938238) (xy 16.03121 -273.942048)
			(xy 16.03469 -273.942993) (xy 16.041829 -273.944007) (xy 16.045434 -273.94408) (xy 16.056102 -273.94408)
			(xy 16.061336 -273.943925) (xy 16.071579 -273.941752) (xy 16.076422 -273.939762) (xy 16.106648 -273.925284)
			(xy 16.152876 -273.903186) (xy 16.161341 -273.898738) (xy 16.174405 -273.884793) (xy 16.181423 -273.86702)
			(xy 16.181832 -273.857466) (xy 16.181832 -255.335786) (xy 16.181669 -255.329775) (xy 16.178854 -255.318088)
			(xy 16.176244 -255.312672) (xy 16.174402 -255.3092) (xy 16.169804 -255.302825) (xy 16.1671 -255.299972)
			(xy 16.09344 -255.226312) (xy 16.086587 -255.218916) (xy 16.078842 -255.200318) (xy 16.078454 -255.190244)
			(xy 16.078454 -238.564674) (xy 16.078883 -238.554607) (xy 16.08661 -238.536015) (xy 16.09344 -238.528606)
			(xy 17.271492 -237.350554) (xy 17.274896 -237.346984) (xy 17.280397 -237.338799) (xy 17.282414 -237.334298)
			(xy 17.286478 -237.324646) (xy 17.286478 -237.316772) (xy 17.505172 -237.098078) (xy 17.512571 -237.091235)
			(xy 17.53117 -237.083514) (xy 17.54124 -237.083092) (xy 92.891356 -237.083092) (xy 92.902532 -237.080298)
			(xy 92.924884 -237.072678) (xy 92.931234 -237.068106) (xy 92.953181 -237.052559) (xy 93.000568 -237.027122)
			(xy 93.051056 -237.008585) (xy 93.103644 -236.997314) (xy 93.157294 -236.993532) (xy 93.210944 -236.997314)
			(xy 93.263532 -237.008585) (xy 93.31402 -237.027122) (xy 93.361407 -237.052559) (xy 93.383354 -237.068106)
			(xy 93.389704 -237.072678) (xy 93.412056 -237.080298) (xy 93.423232 -237.083092) (xy 96.50603 -237.083092)
			(xy 96.515682 -237.082076) (xy 96.522924 -237.080445) (xy 96.536088 -237.073599) (xy 96.54159 -237.068614)
			(xy 97.555812 -236.054392) (xy 97.559124 -236.050861) (xy 97.564488 -236.042803) (xy 97.56648 -236.03839)
			(xy 97.570544 -236.028992) (xy 97.570544 -221.419166) (xy 97.570108 -221.41001) (xy 97.563595 -221.39289)
			(xy 97.551511 -221.379124) (xy 97.54362 -221.374462) (xy 97.506282 -221.354396) (xy 97.505774 -221.354396)
			(xy 97.480374 -221.340934) (xy 97.48012 -221.340934) (xy 97.474649 -221.338259) (xy 97.462838 -221.335303)
			(xy 97.456752 -221.335092) (xy 97.427542 -221.335092) (xy 97.414334 -221.33687) (xy 97.406714 -221.338902)
			(xy 97.400618 -221.342712) (xy 97.377944 -221.356235) (xy 97.329659 -221.377582) (xy 97.27889 -221.392059)
			(xy 97.226608 -221.399389) (xy 97.200212 -221.399862) (xy 97.19945 -221.399862) (xy 97.197164 -221.399862)
			(xy 97.00768 -221.399862) (xy 97.000934 -221.399622) (xy 96.987931 -221.39602) (xy 96.982026 -221.39275)
			(xy 96.970596 -221.386146) (xy 96.968894 -221.382892) (xy 96.966344 -221.376007) (xy 96.965516 -221.37243)
			(xy 96.965262 -221.37116) (xy 96.965008 -221.370144) (xy 96.962722 -221.359476) (xy 96.961706 -221.35084)
			(xy 96.96196 -221.345252) (xy 96.962722 -221.335346) (xy 96.959674 -221.32544) (xy 96.954086 -221.312994)
			(xy 96.95053 -221.30766) (xy 96.944942 -221.302834) (xy 96.925339 -221.284655) (xy 96.8909 -221.243761)
			(xy 96.862499 -221.198466) (xy 96.840691 -221.149653) (xy 96.825901 -221.098276) (xy 96.818418 -221.045339)
			(xy 96.817942 -221.018608) (xy 96.817942 -221.018354) (xy 96.818409 -220.991105) (xy 96.826171 -220.937161)
			(xy 96.841532 -220.884872) (xy 96.864177 -220.835301) (xy 96.893647 -220.789457) (xy 96.929342 -220.748274)
			(xy 96.970534 -220.71259) (xy 97.016385 -220.683131) (xy 97.065962 -220.660498) (xy 97.118255 -220.645151)
			(xy 97.1722 -220.637402) (xy 97.19945 -220.636846) (xy 97.199958 -220.636846) (xy 97.228131 -220.637365)
			(xy 97.283859 -220.645686) (xy 97.337754 -220.662122) (xy 97.388641 -220.686315) (xy 97.412302 -220.701616)
			(xy 97.41281 -220.701616) (xy 97.413064 -220.70187) (xy 97.418769 -220.705422) (xy 97.431514 -220.709673)
			(xy 97.43821 -220.710252) (xy 97.451926 -220.711014) (xy 97.503996 -220.683328) (xy 97.541588 -220.663262)
			(xy 97.543874 -220.661738) (xy 97.554288 -220.656404) (xy 97.55632 -220.655388) (xy 97.563432 -220.64345)
			(xy 97.566715 -220.637482) (xy 97.570317 -220.62435) (xy 97.570544 -220.617542) (xy 97.570544 -219.054172)
			(xy 97.570081 -219.043925) (xy 97.562095 -219.025051) (xy 97.55505 -219.017596) (xy 97.524062 -218.990418)
			(xy 97.495614 -218.96578) (xy 97.488494 -218.960094) (xy 97.471443 -218.953703) (xy 97.46234 -218.953334)
			(xy 97.454974 -218.953334) (xy 97.451418 -218.953842) (xy 97.438214 -218.955548) (xy 97.411646 -218.957329)
			(xy 97.398332 -218.957398) (xy 97.371126 -218.956846) (xy 97.317284 -218.948978) (xy 97.265106 -218.933539)
			(xy 97.215651 -218.910843) (xy 97.169923 -218.88135) (xy 97.128849 -218.845659) (xy 97.093263 -218.804494)
			(xy 97.063888 -218.75869) (xy 97.041318 -218.709177) (xy 97.026013 -218.656959) (xy 97.018283 -218.603097)
			(xy 97.01784 -218.57589) (xy 97.018304 -218.548639) (xy 97.026062 -218.494692) (xy 97.04142 -218.442398)
			(xy 97.064064 -218.392822) (xy 97.093533 -218.346973) (xy 97.129227 -218.305786) (xy 97.17042 -218.270098)
			(xy 97.216273 -218.240636) (xy 97.265852 -218.218) (xy 97.318148 -218.20265) (xy 97.372097 -218.1949)
			(xy 97.399348 -218.194382) (xy 97.412725 -218.194455) (xy 97.43942 -218.196231) (xy 97.452688 -218.197938)
			(xy 97.454466 -218.198192) (xy 97.461832 -218.1987) (xy 97.475294 -218.196922) (xy 97.486724 -218.193874)
			(xy 97.5233 -218.16187) (xy 97.524062 -218.161108) (xy 97.551494 -218.137486) (xy 97.554288 -218.134946)
			(xy 97.556066 -218.133168) (xy 97.561048 -218.127666) (xy 97.567881 -218.114498) (xy 97.569528 -218.10726)
			(xy 97.570544 -218.097608) (xy 97.570544 -213.917276) (xy 97.57038 -213.911265) (xy 97.567564 -213.899579)
			(xy 97.564956 -213.894162) (xy 97.563114 -213.89069) (xy 97.558516 -213.884315) (xy 97.555812 -213.881462)
			(xy 96.472248 -212.797898) (xy 96.46666 -212.793072) (xy 91.173554 -212.793072) (xy 91.169236 -212.795358)
			(xy 91.14081 -212.810275) (xy 91.08021 -212.831437) (xy 91.016927 -212.842189) (xy 90.984832 -212.842856)
			(xy 90.984578 -212.842856) (xy 90.955047 -212.842302) (xy 90.896692 -212.8332) (xy 90.840434 -212.815217)
			(xy 90.787619 -212.788783) (xy 90.739506 -212.754528) (xy 90.697245 -212.71327) (xy 90.661844 -212.665994)
			(xy 90.64752 -212.640164) (xy 90.64625 -212.637624) (xy 90.643202 -212.633306) (xy 90.635728 -212.623317)
			(xy 90.61375 -212.611573) (xy 90.601292 -212.610954) (xy 64.44996 -212.610954) (xy 64.441602 -212.611335)
			(xy 64.425792 -212.616776) (xy 64.418972 -212.621622) (xy 64.412622 -212.626448) (xy 64.403732 -212.639656)
			(xy 64.401192 -212.648292) (xy 64.393414 -212.674794) (xy 64.371274 -212.725391) (xy 64.342066 -212.772266)
			(xy 64.306402 -212.814438) (xy 64.265028 -212.851024) (xy 64.21881 -212.88126) (xy 64.168714 -212.904513)
			(xy 64.115787 -212.920296) (xy 64.061137 -212.928281) (xy 64.005907 -212.928298) (xy 63.951252 -212.920349)
			(xy 63.898316 -212.9046) (xy 63.848204 -212.881379) (xy 63.801967 -212.851173) (xy 63.760569 -212.814613)
			(xy 63.724879 -212.772464) (xy 63.695641 -212.725608) (xy 63.673468 -212.675025) (xy 63.665608 -212.648546)
			(xy 63.665608 -212.648038) (xy 63.665354 -212.64753) (xy 63.662855 -212.639856) (xy 63.65379 -212.626515)
			(xy 63.647574 -212.621368) (xy 63.641224 -212.616288) (xy 63.625222 -212.610954) (xy 60.97651 -212.610954)
			(xy 60.971684 -212.611208) (xy 60.961427 -212.612661) (xy 60.943271 -212.622592) (xy 60.930532 -212.638901)
			(xy 60.927488 -212.6488) (xy 60.92698 -212.65134) (xy 60.920867 -212.67804) (xy 60.902018 -212.729467)
			(xy 60.87601 -212.777672) (xy 60.843377 -212.821662) (xy 60.804789 -212.860535) (xy 60.76104 -212.893491)
			(xy 60.713029 -212.919853) (xy 60.661742 -212.93908) (xy 60.608232 -212.950777) (xy 60.5536 -212.954703)
			(xy 60.498968 -212.950777) (xy 60.445458 -212.93908) (xy 60.394171 -212.919853) (xy 60.34616 -212.893491)
			(xy 60.302411 -212.860535) (xy 60.263823 -212.821662) (xy 60.23119 -212.777672) (xy 60.205182 -212.729467)
			(xy 60.186333 -212.67804) (xy 60.18022 -212.65134) (xy 60.179712 -212.6488) (xy 60.176592 -212.638939)
			(xy 60.163856 -212.622669) (xy 60.145749 -212.612715) (xy 60.135516 -212.611208) (xy 60.13069 -212.610954)
			(xy 50.565812 -212.610954) (xy 50.560794 -212.61105) (xy 50.550944 -212.612975) (xy 50.546254 -212.614764)
			(xy 43.918852 -215.359996) (xy 69.499224 -215.359996) (xy 69.503295 -215.304374) (xy 69.515421 -215.249937)
			(xy 69.535344 -215.197846) (xy 69.56264 -215.149211) (xy 69.596726 -215.105068) (xy 69.636875 -215.066359)
			(xy 69.682233 -215.033908) (xy 69.731833 -215.008407) (xy 69.784617 -214.9904) (xy 69.83946 -214.98027)
			(xy 69.895194 -214.978233) (xy 69.950631 -214.984333) (xy 70.004588 -214.998439) (xy 70.055917 -215.020251)
			(xy 70.103523 -215.049305) (xy 70.146391 -215.08498) (xy 70.183608 -215.126517) (xy 70.214381 -215.17303)
			(xy 70.238053 -215.223527) (xy 70.254121 -215.276934) (xy 70.262241 -215.33211) (xy 70.26275 -215.359996)
			(xy 70.262241 -215.387882) (xy 70.254121 -215.443058) (xy 70.238053 -215.496465) (xy 70.214381 -215.546962)
			(xy 70.183608 -215.593475) (xy 70.146391 -215.635012) (xy 70.103523 -215.670687) (xy 70.055917 -215.699741)
			(xy 70.004588 -215.721553) (xy 69.950631 -215.735659) (xy 69.895194 -215.741759) (xy 69.83946 -215.739722)
			(xy 69.784617 -215.729592) (xy 69.731833 -215.711585) (xy 69.682233 -215.686084) (xy 69.636875 -215.653633)
			(xy 69.596726 -215.614924) (xy 69.56264 -215.570781) (xy 69.535344 -215.522146) (xy 69.515421 -215.470055)
			(xy 69.503295 -215.415618) (xy 69.499224 -215.359996) (xy 43.918852 -215.359996) (xy 41.957244 -216.172542)
			(xy 41.952681 -216.17455) (xy 41.944367 -216.180049) (xy 41.940734 -216.183464) (xy 41.92016 -216.204038)
			(xy 41.916428 -216.207557) (xy 41.907851 -216.21318) (xy 41.903142 -216.215214) (xy 40.72844 -216.6874)
			(xy 68.121782 -216.6874) (xy 68.125853 -216.631778) (xy 68.137979 -216.577341) (xy 68.157902 -216.52525)
			(xy 68.185198 -216.476615) (xy 68.219284 -216.432472) (xy 68.259433 -216.393763) (xy 68.304791 -216.361312)
			(xy 68.354391 -216.335811) (xy 68.407175 -216.317804) (xy 68.462018 -216.307674) (xy 68.517752 -216.305637)
			(xy 68.573189 -216.311737) (xy 68.627146 -216.325843) (xy 68.678475 -216.347655) (xy 68.726081 -216.376709)
			(xy 68.768949 -216.412384) (xy 68.806166 -216.453921) (xy 68.836939 -216.500434) (xy 68.860611 -216.550931)
			(xy 68.876679 -216.604338) (xy 68.884799 -216.659514) (xy 68.885308 -216.6874) (xy 68.884799 -216.715286)
			(xy 68.876679 -216.770462) (xy 68.860611 -216.823869) (xy 68.836939 -216.874366) (xy 68.806166 -216.920879)
			(xy 68.768949 -216.962416) (xy 68.726081 -216.998091) (xy 68.678475 -217.027145) (xy 68.627146 -217.048957)
			(xy 68.573189 -217.063063) (xy 68.517752 -217.069163) (xy 68.462018 -217.067126) (xy 68.407175 -217.056996)
			(xy 68.354391 -217.038989) (xy 68.304791 -217.013488) (xy 68.259433 -216.981037) (xy 68.219284 -216.942328)
			(xy 68.185198 -216.898185) (xy 68.157902 -216.84955) (xy 68.137979 -216.797459) (xy 68.125853 -216.743022)
			(xy 68.121782 -216.6874) (xy 40.72844 -216.6874) (xy 40.2463 -216.881202) (xy 40.245792 -216.881202)
			(xy 33.784806 -219.5576) (xy 69.569582 -219.5576) (xy 69.573653 -219.501978) (xy 69.585779 -219.447541)
			(xy 69.605702 -219.39545) (xy 69.632998 -219.346815) (xy 69.667084 -219.302672) (xy 69.707233 -219.263963)
			(xy 69.752591 -219.231512) (xy 69.802191 -219.206011) (xy 69.854975 -219.188004) (xy 69.909818 -219.177874)
			(xy 69.965552 -219.175837) (xy 70.020989 -219.181937) (xy 70.074946 -219.196043) (xy 70.126275 -219.217855)
			(xy 70.173881 -219.246909) (xy 70.216749 -219.282584) (xy 70.253966 -219.324121) (xy 70.284739 -219.370634)
			(xy 70.308411 -219.421131) (xy 70.324479 -219.474538) (xy 70.332599 -219.529714) (xy 70.333108 -219.5576)
			(xy 70.332599 -219.585486) (xy 70.324479 -219.640662) (xy 70.308411 -219.694069) (xy 70.284739 -219.744566)
			(xy 70.253966 -219.791079) (xy 70.216749 -219.832616) (xy 70.173881 -219.868291) (xy 70.126275 -219.897345)
			(xy 70.074946 -219.919157) (xy 70.020989 -219.933263) (xy 69.965552 -219.939363) (xy 69.909818 -219.937326)
			(xy 69.854975 -219.927196) (xy 69.802191 -219.909189) (xy 69.752591 -219.883688) (xy 69.707233 -219.851237)
			(xy 69.667084 -219.812528) (xy 69.632998 -219.768385) (xy 69.605702 -219.71975) (xy 69.585779 -219.667659)
			(xy 69.573653 -219.613222) (xy 69.569582 -219.5576) (xy 33.784806 -219.5576) (xy 33.7566 -219.569284)
			(xy 33.736391 -219.577287) (xy 33.694418 -219.588577) (xy 33.651332 -219.59431) (xy 33.6296 -219.594684)
			(xy 32.168084 -219.594684) (xy 32.158015 -219.595109) (xy 32.139413 -219.602826) (xy 32.132016 -219.60967)
			(xy 27.205484 -224.536) (xy 27.78328 -224.536) (xy 27.787351 -224.480378) (xy 27.799477 -224.425941)
			(xy 27.8194 -224.37385) (xy 27.846696 -224.325215) (xy 27.880782 -224.281072) (xy 27.920931 -224.242363)
			(xy 27.966289 -224.209912) (xy 28.015889 -224.184411) (xy 28.068673 -224.166404) (xy 28.123516 -224.156274)
			(xy 28.17925 -224.154237) (xy 28.234687 -224.160337) (xy 28.288644 -224.174443) (xy 28.339973 -224.196255)
			(xy 28.387579 -224.225309) (xy 28.430447 -224.260984) (xy 28.467664 -224.302521) (xy 28.498437 -224.349034)
			(xy 28.522109 -224.399531) (xy 28.538177 -224.452938) (xy 28.546297 -224.508114) (xy 28.546806 -224.536)
			(xy 28.546297 -224.563886) (xy 28.538177 -224.619062) (xy 28.522109 -224.672469) (xy 28.498437 -224.722966)
			(xy 28.467664 -224.769479) (xy 28.430447 -224.811016) (xy 28.387579 -224.846691) (xy 28.339973 -224.875745)
			(xy 28.288644 -224.897557) (xy 28.234687 -224.911663) (xy 28.17925 -224.917763) (xy 28.123516 -224.915726)
			(xy 28.068673 -224.905596) (xy 28.015889 -224.887589) (xy 27.966289 -224.862088) (xy 27.920931 -224.829637)
			(xy 27.880782 -224.790928) (xy 27.846696 -224.746785) (xy 27.8194 -224.69815) (xy 27.799477 -224.646059)
			(xy 27.787351 -224.591622) (xy 27.78328 -224.536) (xy 27.205484 -224.536) (xy 26.189442 -225.552)
			(xy 30.83128 -225.552) (xy 30.835351 -225.496378) (xy 30.847477 -225.441941) (xy 30.8674 -225.38985)
			(xy 30.894696 -225.341215) (xy 30.928782 -225.297072) (xy 30.968931 -225.258363) (xy 31.014289 -225.225912)
			(xy 31.063889 -225.200411) (xy 31.116673 -225.182404) (xy 31.171516 -225.172274) (xy 31.22725 -225.170237)
			(xy 31.282687 -225.176337) (xy 31.336644 -225.190443) (xy 31.387973 -225.212255) (xy 31.435579 -225.241309)
			(xy 31.478447 -225.276984) (xy 31.515664 -225.318521) (xy 31.546437 -225.365034) (xy 31.570109 -225.415531)
			(xy 31.586177 -225.468938) (xy 31.594297 -225.524114) (xy 31.594806 -225.552) (xy 31.594297 -225.579886)
			(xy 31.586177 -225.635062) (xy 31.570109 -225.688469) (xy 31.546437 -225.738966) (xy 31.515664 -225.785479)
			(xy 31.478447 -225.827016) (xy 31.435579 -225.862691) (xy 31.387973 -225.891745) (xy 31.336644 -225.913557)
			(xy 31.282687 -225.927663) (xy 31.22725 -225.933763) (xy 31.171516 -225.931726) (xy 31.116673 -225.921596)
			(xy 31.063889 -225.903589) (xy 31.014289 -225.878088) (xy 30.968931 -225.845637) (xy 30.928782 -225.806928)
			(xy 30.894696 -225.762785) (xy 30.8674 -225.71415) (xy 30.847477 -225.662059) (xy 30.835351 -225.607622)
			(xy 30.83128 -225.552) (xy 26.189442 -225.552) (xy 25.941274 -225.800158) (xy 25.940737 -225.804795)
			(xy 25.941125 -225.814121) (xy 25.942036 -225.8187) (xy 25.943814 -225.82505) (xy 25.964134 -225.880168)
			(xy 25.964134 -225.880676) (xy 25.9715 -225.89998) (xy 25.974293 -225.906014) (xy 25.982525 -225.916451)
			(xy 25.987756 -225.920554) (xy 25.990042 -225.922332) (xy 26.00833 -225.936302) (xy 26.020268 -225.942906)
			(xy 26.02611 -225.945192) (xy 26.032968 -225.945954) (xy 26.060516 -225.949632) (xy 26.114219 -225.963935)
			(xy 26.165279 -225.985878) (xy 26.212616 -226.014996) (xy 26.255227 -226.050673) (xy 26.292212 -226.092155)
			(xy 26.322787 -226.138563) (xy 26.346307 -226.188916) (xy 26.362272 -226.242149) (xy 26.370346 -226.297134)
			(xy 26.370788 -226.324922) (xy 26.370289 -226.352662) (xy 26.362254 -226.407556) (xy 26.346356 -226.460708)
			(xy 26.32293 -226.510999) (xy 26.292471 -226.557369) (xy 26.283024 -226.568) (xy 30.95828 -226.568)
			(xy 30.962351 -226.512378) (xy 30.974477 -226.457941) (xy 30.9944 -226.40585) (xy 31.021696 -226.357215)
			(xy 31.055782 -226.313072) (xy 31.095931 -226.274363) (xy 31.141289 -226.241912) (xy 31.190889 -226.216411)
			(xy 31.243673 -226.198404) (xy 31.298516 -226.188274) (xy 31.35425 -226.186237) (xy 31.409687 -226.192337)
			(xy 31.463644 -226.206443) (xy 31.514973 -226.228255) (xy 31.562579 -226.257309) (xy 31.581561 -226.273106)
			(xy 70.331582 -226.273106) (xy 70.335653 -226.217484) (xy 70.347779 -226.163047) (xy 70.367702 -226.110956)
			(xy 70.394998 -226.062321) (xy 70.429084 -226.018178) (xy 70.469233 -225.979469) (xy 70.514591 -225.947018)
			(xy 70.564191 -225.921517) (xy 70.616975 -225.90351) (xy 70.671818 -225.89338) (xy 70.727552 -225.891343)
			(xy 70.782989 -225.897443) (xy 70.836946 -225.911549) (xy 70.888275 -225.933361) (xy 70.935881 -225.962415)
			(xy 70.978749 -225.99809) (xy 71.015966 -226.039627) (xy 71.046739 -226.08614) (xy 71.070411 -226.136637)
			(xy 71.086479 -226.190044) (xy 71.094599 -226.24522) (xy 71.095108 -226.273106) (xy 71.094599 -226.300992)
			(xy 71.086479 -226.356168) (xy 71.070411 -226.409575) (xy 71.046739 -226.460072) (xy 71.015966 -226.506585)
			(xy 70.978749 -226.548122) (xy 70.935881 -226.583797) (xy 70.888275 -226.612851) (xy 70.836946 -226.634663)
			(xy 70.782989 -226.648769) (xy 70.727552 -226.654869) (xy 70.671818 -226.652832) (xy 70.616975 -226.642702)
			(xy 70.564191 -226.624695) (xy 70.514591 -226.599194) (xy 70.469233 -226.566743) (xy 70.429084 -226.528034)
			(xy 70.394998 -226.483891) (xy 70.367702 -226.435256) (xy 70.347779 -226.383165) (xy 70.335653 -226.328728)
			(xy 70.331582 -226.273106) (xy 31.581561 -226.273106) (xy 31.605447 -226.292984) (xy 31.642664 -226.334521)
			(xy 31.673437 -226.381034) (xy 31.697109 -226.431531) (xy 31.713177 -226.484938) (xy 31.721297 -226.540114)
			(xy 31.721806 -226.568) (xy 31.721297 -226.595886) (xy 31.713177 -226.651062) (xy 31.697109 -226.704469)
			(xy 31.673437 -226.754966) (xy 31.642664 -226.801479) (xy 31.605447 -226.843016) (xy 31.562579 -226.878691)
			(xy 31.514973 -226.907745) (xy 31.463644 -226.929557) (xy 31.409687 -226.943663) (xy 31.35425 -226.949763)
			(xy 31.298516 -226.947726) (xy 31.243673 -226.937596) (xy 31.190889 -226.919589) (xy 31.141289 -226.894088)
			(xy 31.095931 -226.861637) (xy 31.055782 -226.822928) (xy 31.021696 -226.778785) (xy 30.9944 -226.73015)
			(xy 30.974477 -226.678059) (xy 30.962351 -226.623622) (xy 30.95828 -226.568) (xy 26.283024 -226.568)
			(xy 26.255619 -226.59884) (xy 26.213151 -226.63454) (xy 26.165963 -226.663715) (xy 26.115047 -226.68575)
			(xy 26.061478 -226.700183) (xy 26.033984 -226.70389) (xy 26.020268 -226.705414) (xy 25.992744 -226.707159)
			(xy 25.937704 -226.703665) (xy 25.883739 -226.692294) (xy 25.83197 -226.673281) (xy 25.783472 -226.647023)
			(xy 25.739253 -226.614064) (xy 25.700233 -226.57509) (xy 25.667222 -226.53091) (xy 25.640906 -226.482444)
			(xy 25.630886 -226.456748) (xy 25.630378 -226.455224) (xy 25.62987 -226.453954) (xy 25.626314 -226.446842)
			(xy 25.624506 -226.443512) (xy 25.620036 -226.437395) (xy 25.617424 -226.43465) (xy 25.611836 -226.429062)
			(xy 25.607365 -226.425044) (xy 25.596968 -226.419016) (xy 25.591262 -226.417124) (xy 25.546812 -226.40671)
			(xy 25.546304 -226.40671) (xy 25.506426 -226.39782) (xy 25.494121 -226.396122) (xy 25.470412 -226.403443)
			(xy 25.461214 -226.41179) (xy 24.692356 -227.180648) (xy 24.687784 -227.185982) (xy 24.687784 -227.384102)
			(xy 24.687444 -227.403399) (xy 24.682862 -227.441723) (xy 24.67864 -227.460556) (xy 24.67737 -227.466398)
			(xy 24.67737 -227.49637) (xy 24.676883 -227.506331) (xy 24.669291 -227.524752) (xy 24.662638 -227.532184)
			(xy 24.641048 -227.553774) (xy 24.638 -227.558854) (xy 24.627676 -227.575007) (xy 24.603867 -227.605054)
			(xy 24.590502 -227.618798) (xy 23.53437 -228.67493) (xy 25.95575 -228.67493) (xy 25.959821 -228.619308)
			(xy 25.971947 -228.564871) (xy 25.99187 -228.51278) (xy 26.019166 -228.464145) (xy 26.053252 -228.420002)
			(xy 26.093401 -228.381293) (xy 26.138759 -228.348842) (xy 26.188359 -228.323341) (xy 26.241143 -228.305334)
			(xy 26.295986 -228.295204) (xy 26.35172 -228.293167) (xy 26.407157 -228.299267) (xy 26.461114 -228.313373)
			(xy 26.512443 -228.335185) (xy 26.560049 -228.364239) (xy 26.602917 -228.399914) (xy 26.640134 -228.441451)
			(xy 26.644202 -228.4476) (xy 69.569582 -228.4476) (xy 69.573653 -228.391978) (xy 69.585779 -228.337541)
			(xy 69.605702 -228.28545) (xy 69.632998 -228.236815) (xy 69.667084 -228.192672) (xy 69.707233 -228.153963)
			(xy 69.752591 -228.121512) (xy 69.802191 -228.096011) (xy 69.854975 -228.078004) (xy 69.909818 -228.067874)
			(xy 69.965552 -228.065837) (xy 70.020989 -228.071937) (xy 70.074946 -228.086043) (xy 70.126275 -228.107855)
			(xy 70.173881 -228.136909) (xy 70.216749 -228.172584) (xy 70.253966 -228.214121) (xy 70.284739 -228.260634)
			(xy 70.308411 -228.311131) (xy 70.324479 -228.364538) (xy 70.332599 -228.419714) (xy 70.333108 -228.4476)
			(xy 70.332599 -228.475486) (xy 70.324479 -228.530662) (xy 70.308411 -228.584069) (xy 70.284739 -228.634566)
			(xy 70.253966 -228.681079) (xy 70.216749 -228.722616) (xy 70.173881 -228.758291) (xy 70.126275 -228.787345)
			(xy 70.074946 -228.809157) (xy 70.020989 -228.823263) (xy 69.965552 -228.829363) (xy 69.909818 -228.827326)
			(xy 69.854975 -228.817196) (xy 69.802191 -228.799189) (xy 69.752591 -228.773688) (xy 69.707233 -228.741237)
			(xy 69.667084 -228.702528) (xy 69.632998 -228.658385) (xy 69.605702 -228.60975) (xy 69.585779 -228.557659)
			(xy 69.573653 -228.503222) (xy 69.569582 -228.4476) (xy 26.644202 -228.4476) (xy 26.670907 -228.487964)
			(xy 26.694579 -228.538461) (xy 26.710647 -228.591868) (xy 26.718767 -228.647044) (xy 26.719276 -228.67493)
			(xy 26.718767 -228.702816) (xy 26.710647 -228.757992) (xy 26.694579 -228.811399) (xy 26.670907 -228.861896)
			(xy 26.640134 -228.908409) (xy 26.602917 -228.949946) (xy 26.560049 -228.985621) (xy 26.512443 -229.014675)
			(xy 26.461114 -229.036487) (xy 26.407157 -229.050593) (xy 26.35172 -229.056693) (xy 26.295986 -229.054656)
			(xy 26.241143 -229.044526) (xy 26.188359 -229.026519) (xy 26.138759 -229.001018) (xy 26.093401 -228.968567)
			(xy 26.053252 -228.929858) (xy 26.019166 -228.885715) (xy 25.99187 -228.83708) (xy 25.971947 -228.784989)
			(xy 25.959821 -228.730552) (xy 25.95575 -228.67493) (xy 23.53437 -228.67493) (xy 22.26437 -229.94493)
			(xy 22.83028 -229.94493) (xy 22.834351 -229.889308) (xy 22.846477 -229.834871) (xy 22.8664 -229.78278)
			(xy 22.893696 -229.734145) (xy 22.927782 -229.690002) (xy 22.967931 -229.651293) (xy 23.013289 -229.618842)
			(xy 23.062889 -229.593341) (xy 23.115673 -229.575334) (xy 23.170516 -229.565204) (xy 23.22625 -229.563167)
			(xy 23.281687 -229.569267) (xy 23.335644 -229.583373) (xy 23.386973 -229.605185) (xy 23.434579 -229.634239)
			(xy 23.477447 -229.669914) (xy 23.514664 -229.711451) (xy 23.545437 -229.757964) (xy 23.569109 -229.808461)
			(xy 23.585177 -229.861868) (xy 23.593297 -229.917044) (xy 23.593806 -229.94493) (xy 23.593297 -229.972816)
			(xy 23.585177 -230.027992) (xy 23.569109 -230.081399) (xy 23.545437 -230.131896) (xy 23.514664 -230.178409)
			(xy 23.477447 -230.219946) (xy 23.434579 -230.255621) (xy 23.386973 -230.284675) (xy 23.335644 -230.306487)
			(xy 23.281687 -230.320593) (xy 23.22625 -230.326693) (xy 23.170516 -230.324656) (xy 23.115673 -230.314526)
			(xy 23.062889 -230.296519) (xy 23.013289 -230.271018) (xy 22.967931 -230.238567) (xy 22.927782 -230.199858)
			(xy 22.893696 -230.155715) (xy 22.8664 -230.10708) (xy 22.846477 -230.054989) (xy 22.834351 -230.000552)
			(xy 22.83028 -229.94493) (xy 22.26437 -229.94493) (xy 18.879566 -233.329734) (xy 18.865819 -233.343095)
			(xy 18.835772 -233.366904) (xy 18.819622 -233.377232) (xy 18.814542 -233.38028) (xy 18.792952 -233.40187)
			(xy 18.785547 -233.408566) (xy 18.76711 -233.416171) (xy 18.757138 -233.416602) (xy 18.727166 -233.416602)
			(xy 18.721324 -233.417872) (xy 18.702495 -233.422116) (xy 18.664169 -233.426702) (xy 18.64487 -233.427016)
			(xy 14.038072 -233.427016) (xy 14.018775 -233.426675) (xy 13.980452 -233.42209) (xy 13.961618 -233.417872)
			(xy 13.955776 -233.416602) (xy 13.925804 -233.416602) (xy 13.915836 -233.416128) (xy 13.897393 -233.408559)
			(xy 13.88999 -233.40187) (xy 13.8684 -233.38028) (xy 13.86332 -233.377232) (xy 13.847166 -233.366909)
			(xy 13.817118 -233.343101) (xy 13.803376 -233.329734) (xy 13.593826 -233.11993) (xy 13.586425 -233.113092)
			(xy 13.567826 -233.10538) (xy 13.557758 -233.104944) (xy 12.489942 -233.104944) (xy 12.485624 -233.10723)
			(xy 12.457199 -233.122147) (xy 12.396598 -233.143309) (xy 12.333314 -233.154059) (xy 12.30122 -233.154728)
			(xy 12.300966 -233.154728) (xy 12.273715 -233.154242) (xy 12.219768 -233.146485) (xy 12.167473 -233.131129)
			(xy 12.117897 -233.108488) (xy 12.072047 -233.079022) (xy 12.030857 -233.04333) (xy 11.995166 -233.00214)
			(xy 11.9657 -232.95629) (xy 11.943059 -232.906713) (xy 11.927704 -232.854418) (xy 11.919948 -232.800471)
			(xy 11.919948 -232.745969) (xy 11.927704 -232.692022) (xy 11.943059 -232.639727) (xy 11.9657 -232.59015)
			(xy 11.995166 -232.5443) (xy 12.030857 -232.50311) (xy 12.072047 -232.467418) (xy 12.117897 -232.437952)
			(xy 12.167473 -232.415311) (xy 12.219768 -232.399955) (xy 12.273715 -232.392198) (xy 12.300966 -232.391712)
			(xy 12.301728 -232.391712) (xy 12.326049 -232.392091) (xy 12.374298 -232.398268) (xy 12.42137 -232.410532)
			(xy 12.466499 -232.428683) (xy 12.48791 -232.440226) (xy 12.489942 -232.441496) (xy 13.716508 -232.441496)
			(xy 13.735737 -232.44176) (xy 13.773935 -232.446215) (xy 13.792708 -232.450386) (xy 13.79855 -232.451656)
			(xy 13.828268 -232.451656) (xy 13.838331 -232.452093) (xy 13.856913 -232.459831) (xy 13.864336 -232.466642)
			(xy 13.885164 -232.48747) (xy 13.890244 -232.490772) (xy 13.906604 -232.501125) (xy 13.937033 -232.525064)
			(xy 13.95095 -232.538524) (xy 14.1605 -232.748074) (xy 14.167897 -232.754923) (xy 14.186496 -232.762662)
			(xy 14.196568 -232.76306) (xy 18.486374 -232.76306) (xy 18.496437 -232.762622) (xy 18.515018 -232.754884)
			(xy 18.522442 -232.748074) (xy 20.51939 -230.75138) (xy 20.526197 -230.743952) (xy 20.533863 -230.725335)
			(xy 20.533811 -230.705202) (xy 20.530312 -230.695754) (xy 20.51939 -230.669338) (xy 20.514276 -230.667094)
			(xy 20.503382 -230.664651) (xy 20.4978 -230.664512) (xy 18.734278 -230.664512) (xy 18.724272 -230.66402)
			(xy 18.705786 -230.656357) (xy 18.691637 -230.642205) (xy 18.683978 -230.623718) (xy 18.683478 -230.613712)
			(xy 18.683478 -229.350062) (xy 18.683329 -229.343845) (xy 18.680371 -229.331771) (xy 18.677636 -229.326186)
			(xy 18.674842 -229.320852) (xy 18.66646 -229.311708) (xy 18.647918 -229.299008) (xy 18.641822 -229.296976)
			(xy 18.634964 -229.294436) (xy 18.634456 -229.294182) (xy 18.629122 -229.292404) (xy 18.613628 -229.286054)
			(xy 18.61312 -229.286054) (xy 18.584996 -229.273329) (xy 18.533838 -229.2388) (xy 18.51152 -229.217474)
			(xy 18.50644 -229.212394) (xy 18.500344 -229.206552) (xy 18.080736 -228.786944) (xy 18.074894 -228.780848)
			(xy 18.069306 -228.77526) (xy 18.051821 -228.757086) (xy 18.022158 -228.716303) (xy 17.999224 -228.67139)
			(xy 17.983581 -228.623448) (xy 17.975611 -228.573652) (xy 17.975072 -228.548438) (xy 17.975072 -228.545898)
			(xy 17.974564 -228.531166) (xy 17.974564 -228.440742) (xy 17.975072 -228.42728) (xy 17.975072 -228.403404)
			(xy 17.974564 -228.3968) (xy 17.972532 -228.381306) (xy 17.967452 -228.37267) (xy 17.95563 -228.35169)
			(xy 17.936777 -228.307376) (xy 17.923645 -228.261044) (xy 17.9197 -228.237288) (xy 17.917906 -228.22485)
			(xy 17.915745 -228.199811) (xy 17.915382 -228.18725) (xy 17.915382 -228.173534) (xy 17.916314 -228.146121)
			(xy 17.92507 -228.091974) (xy 17.941487 -228.039639) (xy 17.965226 -227.990192) (xy 17.9958 -227.944653)
			(xy 18.032577 -227.90396) (xy 18.0748 -227.86895) (xy 18.1216 -227.840345) (xy 18.172014 -227.818734)
			(xy 18.225001 -227.804562) (xy 18.252186 -227.800916) (xy 18.273776 -227.798376) (xy 18.278856 -227.798122)
			(xy 18.297144 -227.798122) (xy 18.326655 -227.798675) (xy 18.384975 -227.80776) (xy 18.441202 -227.825709)
			(xy 18.494 -227.852092) (xy 18.518378 -227.868734) (xy 18.52041 -227.870258) (xy 18.526252 -227.874068)
			(xy 18.537168 -227.879781) (xy 18.561723 -227.881235) (xy 18.573242 -227.876862) (xy 18.609056 -227.858574)
			(xy 18.609564 -227.858574) (xy 18.627598 -227.84943) (xy 18.631408 -227.847906) (xy 18.63471 -227.84689)
			(xy 18.634964 -227.84689) (xy 18.64233 -227.845112) (xy 18.647418 -227.843636) (xy 18.656896 -227.838903)
			(xy 18.661126 -227.835714) (xy 18.669762 -227.828856) (xy 18.674842 -227.81895) (xy 18.678652 -227.811584)
			(xy 18.680502 -227.807351) (xy 18.682796 -227.798404) (xy 18.683224 -227.793804) (xy 18.683478 -227.789994)
			(xy 18.683478 -226.219512) (xy 18.683224 -226.2121) (xy 18.678961 -226.197902) (xy 18.675096 -226.191572)
			(xy 18.671032 -226.185476) (xy 18.659856 -226.176078) (xy 18.652744 -226.17303) (xy 18.627384 -226.161619)
			(xy 18.579991 -226.132531) (xy 18.537325 -226.096867) (xy 18.500291 -226.055385) (xy 18.469675 -226.008964)
			(xy 18.446126 -225.958588) (xy 18.430144 -225.905326) (xy 18.422067 -225.850308) (xy 18.422066 -225.7947)
			(xy 18.430142 -225.739681) (xy 18.446124 -225.686419) (xy 18.469672 -225.636043) (xy 18.500287 -225.589621)
			(xy 18.537319 -225.548138) (xy 18.579985 -225.512474) (xy 18.627377 -225.483385) (xy 18.652744 -225.47199)
			(xy 18.652998 -225.47199) (xy 18.659727 -225.468838) (xy 18.671106 -225.459292) (xy 18.67535 -225.453194)
			(xy 18.679414 -225.447098) (xy 18.683478 -225.433128) (xy 18.683478 -215.81364) (xy 18.683911 -215.803574)
			(xy 18.691639 -215.784983) (xy 18.698464 -215.777572) (xy 20.131786 -214.34425) (xy 20.139187 -214.337411)
			(xy 20.157786 -214.3297) (xy 20.167854 -214.329264) (xy 29.441648 -214.329264) (xy 29.446667 -214.329172)
			(xy 29.456519 -214.327251) (xy 29.461206 -214.325454) (xy 41.755568 -209.232754) (xy 41.760131 -209.230745)
			(xy 41.768443 -209.225244) (xy 41.772078 -209.221832) (xy 51.480212 -199.513698) (xy 51.487611 -199.506854)
			(xy 51.506209 -199.499124) (xy 51.51628 -199.498712) (xy 87.917274 -199.498712) (xy 87.926926 -199.497696)
			(xy 87.934172 -199.496073) (xy 87.947349 -199.489239) (xy 87.952834 -199.484234) (xy 91.146376 -196.290692)
			(xy 91.14969 -196.287162) (xy 91.155058 -196.279106) (xy 91.157044 -196.27469) (xy 91.161108 -196.265292)
			(xy 91.161108 -185.572908) (xy 91.160621 -185.562899) (xy 91.152963 -185.544403) (xy 91.138811 -185.530246)
			(xy 91.120317 -185.522582) (xy 91.110308 -185.522108) (xy 38.25748 -185.522108) (xy 38.247412 -185.522535)
			(xy 38.228813 -185.530255) (xy 38.221412 -185.537094) (xy 32.158178 -191.600328) (xy 59.508642 -191.600328)
			(xy 59.512713 -191.544706) (xy 59.524839 -191.490269) (xy 59.544762 -191.438178) (xy 59.572058 -191.389543)
			(xy 59.606144 -191.3454) (xy 59.646293 -191.306691) (xy 59.691651 -191.27424) (xy 59.741251 -191.248739)
			(xy 59.794035 -191.230732) (xy 59.848878 -191.220602) (xy 59.904612 -191.218565) (xy 59.960049 -191.224665)
			(xy 60.014006 -191.238771) (xy 60.065335 -191.260583) (xy 60.112941 -191.289637) (xy 60.155809 -191.325312)
			(xy 60.193026 -191.366849) (xy 60.223799 -191.413362) (xy 60.247471 -191.463859) (xy 60.263539 -191.517266)
			(xy 60.271659 -191.572442) (xy 60.272168 -191.600328) (xy 60.271659 -191.628214) (xy 60.263539 -191.68339)
			(xy 60.247471 -191.736797) (xy 60.223799 -191.787294) (xy 60.193026 -191.833807) (xy 60.155809 -191.875344)
			(xy 60.112941 -191.911019) (xy 60.065335 -191.940073) (xy 60.014006 -191.961885) (xy 59.960049 -191.975991)
			(xy 59.904612 -191.982091) (xy 59.848878 -191.980054) (xy 59.794035 -191.969924) (xy 59.741251 -191.951917)
			(xy 59.691651 -191.926416) (xy 59.646293 -191.893965) (xy 59.606144 -191.855256) (xy 59.572058 -191.811113)
			(xy 59.544762 -191.762478) (xy 59.524839 -191.710387) (xy 59.512713 -191.65595) (xy 59.508642 -191.600328)
			(xy 32.158178 -191.600328) (xy 30.911546 -192.84696) (xy 30.90926 -192.85458) (xy 30.901025 -192.880476)
			(xy 30.878248 -192.929813) (xy 30.848707 -192.975422) (xy 30.812998 -193.016382) (xy 30.771842 -193.051865)
			(xy 30.726072 -193.081156) (xy 30.676611 -193.103662) (xy 30.624459 -193.118928) (xy 30.57067 -193.126646)
			(xy 30.5435 -193.127122) (xy 30.516248 -193.126636) (xy 30.4623 -193.11888) (xy 30.410004 -193.103525)
			(xy 30.360426 -193.080884) (xy 30.314575 -193.051418) (xy 30.273383 -193.015726) (xy 30.237691 -192.974536)
			(xy 30.208223 -192.928686) (xy 30.18558 -192.879109) (xy 30.170223 -192.826814) (xy 30.162465 -192.772866)
			(xy 30.161992 -192.745614) (xy 30.161992 -192.744852) (xy 30.162436 -192.719941) (xy 30.168994 -192.670552)
			(xy 30.181913 -192.622434) (xy 30.200976 -192.576402) (xy 30.213046 -192.554606) (xy 30.215078 -192.550796)
			(xy 30.21711 -192.543684) (xy 30.220158 -192.532762) (xy 30.221936 -192.519554) (xy 30.221936 -192.207896)
			(xy 30.221682 -192.202308) (xy 30.22 -192.192047) (xy 30.209658 -192.174032) (xy 30.193049 -192.161555)
			(xy 30.183074 -192.15862) (xy 30.180534 -192.158112) (xy 30.154653 -192.152777) (xy 30.104574 -192.135917)
			(xy 30.0573 -192.112307) (xy 30.013736 -192.082398) (xy 29.974718 -192.046764) (xy 29.94099 -192.006086)
			(xy 29.913199 -191.961143) (xy 29.891876 -191.912794) (xy 29.877429 -191.861965) (xy 29.870136 -191.809629)
			(xy 29.869638 -191.783208) (xy 29.869716 -191.77047) (xy 29.871369 -191.745049) (xy 29.87294 -191.732408)
			(xy 29.877024 -191.705578) (xy 29.891793 -191.653357) (xy 29.91381 -191.603755) (xy 29.942631 -191.557771)
			(xy 29.977676 -191.516334) (xy 29.997654 -191.497966) (xy 30.013867 -191.483963) (xy 30.048876 -191.459269)
			(xy 30.067504 -191.44869) (xy 30.084401 -191.439664) (xy 30.119647 -191.42465) (xy 30.137862 -191.418718)
			(xy 30.143704 -191.41694) (xy 30.154626 -191.41059) (xy 36.57346 -184.991756) (xy 36.578902 -184.985824)
			(xy 36.586154 -184.971465) (xy 36.587684 -184.963562) (xy 36.589436 -184.94906) (xy 36.585538 -184.920122)
			(xy 36.573619 -184.893466) (xy 36.554651 -184.871266) (xy 36.530181 -184.855333) (xy 36.502206 -184.846967)
			(xy 36.487608 -184.846468) (xy 32.60471 -184.846468) (xy 32.580859 -184.846043) (xy 32.533678 -184.839012)
			(xy 32.488053 -184.825088) (xy 32.444986 -184.804578) (xy 32.405421 -184.77793) (xy 32.38754 -184.76214)
			(xy 32.37992 -184.756298) (xy 32.363619 -184.745944) (xy 32.333311 -184.72201) (xy 32.319468 -184.708546)
			(xy 28.344876 -180.733954) (xy 28.338272 -180.731922) (xy 28.312301 -180.723737) (xy 28.262809 -180.701032)
			(xy 28.217043 -180.671527) (xy 28.175933 -180.635821) (xy 28.14031 -180.594639) (xy 28.110898 -180.548814)
			(xy 28.088293 -180.499276) (xy 28.072953 -180.447029) (xy 28.06519 -180.393134) (xy 28.064714 -180.365908)
			(xy 28.065177 -180.338655) (xy 28.072933 -180.284705) (xy 28.088289 -180.232407) (xy 28.110931 -180.182827)
			(xy 28.140399 -180.136975) (xy 28.176093 -180.095783) (xy 28.217286 -180.060091) (xy 28.26314 -180.030624)
			(xy 28.31272 -180.007984) (xy 28.365018 -179.99263) (xy 28.418969 -179.984876) (xy 28.446222 -179.9844)
			(xy 28.473451 -179.984879) (xy 28.527356 -179.992612) (xy 28.579615 -180.007931) (xy 28.629163 -180.030526)
			(xy 28.674996 -180.059938) (xy 28.71618 -180.095568) (xy 28.751878 -180.136692) (xy 28.781367 -180.182475)
			(xy 28.804045 -180.231986) (xy 28.812236 -180.257958) (xy 28.814268 -180.264562) (xy 32.676592 -184.126886)
			(xy 32.683989 -184.133735) (xy 32.702587 -184.141475) (xy 32.71266 -184.141872) (xy 91.110308 -184.141872)
			(xy 91.120326 -184.14145) (xy 91.138835 -184.133778) (xy 91.152998 -184.119605) (xy 91.160658 -184.10109)
			(xy 91.161108 -184.091072) (xy 91.161108 -125.343412) (xy 91.160237 -125.332958) (xy 91.151191 -125.314057)
			(xy 91.143582 -125.306836) (xy 91.136724 -125.301248) (xy 91.128088 -125.29439) (xy 91.120468 -125.291342)
			(xy 91.093784 -125.280584) (xy 91.043736 -125.25221) (xy 90.998515 -125.216644) (xy 90.959146 -125.174692)
			(xy 90.92652 -125.127306) (xy 90.901378 -125.075559) (xy 90.884288 -125.020624) (xy 90.87564 -124.963746)
			(xy 90.875104 -124.93498) (xy 90.875654 -124.905755) (xy 90.884549 -124.847985) (xy 90.902143 -124.792245)
			(xy 90.928025 -124.739837) (xy 90.961591 -124.691985) (xy 91.002056 -124.649807) (xy 91.048477 -124.614288)
			(xy 91.099767 -124.586257) (xy 91.127072 -124.575824) (xy 91.13393 -124.573284) (xy 91.138756 -124.569728)
			(xy 91.14197 -124.567396) (xy 91.147707 -124.561908) (xy 91.150186 -124.558806) (xy 91.151964 -124.556266)
			(xy 91.156142 -124.549765) (xy 91.160785 -124.535032) (xy 91.161108 -124.52731) (xy 91.161108 -121.613168)
			(xy 91.160371 -121.602607) (xy 91.151453 -121.583435) (xy 91.143836 -121.576084) (xy 91.137994 -121.571766)
			(xy 91.103704 -121.54916) (xy 91.103196 -121.54916) (xy 91.06789 -121.5263) (xy 91.062618 -121.523042)
			(xy 91.050926 -121.518939) (xy 91.044776 -121.518172) (xy 91.040885 -121.517884) (xy 91.033101 -121.518391)
			(xy 91.029282 -121.519188) (xy 91.019376 -121.52122) (xy 91.01455 -121.523252) (xy 90.991727 -121.532404)
			(xy 90.944313 -121.545439) (xy 90.89562 -121.552293) (xy 90.87104 -121.55297) (xy 90.86342 -121.55297)
			(xy 90.835837 -121.552261) (xy 90.781303 -121.543876) (xy 90.728545 -121.527726) (xy 90.678662 -121.504149)
			(xy 90.632693 -121.473634) (xy 90.591597 -121.436818) (xy 90.556231 -121.394469) (xy 90.52733 -121.347468)
			(xy 90.505499 -121.296797) (xy 90.49119 -121.243509) (xy 90.4875 -121.216166) (xy 90.486992 -121.211594)
			(xy 90.486017 -121.20159) (xy 90.484998 -121.181513) (xy 90.48496 -121.171462) (xy 90.485433 -121.144431)
			(xy 90.49307 -121.09091) (xy 90.508185 -121.039004) (xy 90.530476 -120.989751) (xy 90.559496 -120.944137)
			(xy 90.594665 -120.903077) (xy 90.635278 -120.867393) (xy 90.680521 -120.837799) (xy 90.729488 -120.814887)
			(xy 90.7812 -120.799117) (xy 90.834619 -120.790805) (xy 90.861642 -120.789954) (xy 90.866722 -120.789954)
			(xy 90.890388 -120.790328) (xy 90.937353 -120.796207) (xy 90.983234 -120.807835) (xy 91.005406 -120.816116)
			(xy 91.008708 -120.817386) (xy 91.019376 -120.821704) (xy 91.03106 -120.824244) (xy 91.040401 -120.825511)
			(xy 91.058902 -120.82199) (xy 91.067128 -120.817386) (xy 91.073732 -120.813068) (xy 91.138248 -120.77065)
			(xy 91.148439 -120.763135) (xy 91.160443 -120.740876) (xy 91.161108 -120.728232) (xy 91.161108 -117.815868)
			(xy 91.160663 -117.806081) (xy 91.153348 -117.787924) (xy 91.146884 -117.780562) (xy 91.131898 -117.765322)
			(xy 91.125548 -117.758718) (xy 91.108784 -117.750844) (xy 91.093798 -117.743732) (xy 91.084908 -117.742716)
			(xy 91.05291 -117.738809) (xy 90.990782 -117.721643) (xy 90.932425 -117.694274) (xy 90.905584 -117.676422)
			(xy 90.88023 -117.658009) (xy 90.835333 -117.614302) (xy 90.798175 -117.563852) (xy 90.78341 -117.536214)
			(xy 90.770356 -117.509266) (xy 90.751876 -117.452313) (xy 90.742518 -117.393173) (xy 90.742512 -117.333298)
			(xy 90.751859 -117.274156) (xy 90.770329 -117.2172) (xy 90.78341 -117.190266) (xy 90.796196 -117.166217)
			(xy 90.827555 -117.121686) (xy 90.864927 -117.082066) (xy 90.907552 -117.048161) (xy 90.954565 -117.020661)
			(xy 91.005009 -117.000125) (xy 91.057861 -116.986969) (xy 91.084908 -116.983764) (xy 91.093798 -116.982748)
			(xy 91.11742 -116.971318) (xy 91.12133 -116.969313) (xy 91.128476 -116.964203) (xy 91.131644 -116.961158)
			(xy 91.14663 -116.945664) (xy 91.153217 -116.938285) (xy 91.160678 -116.919986) (xy 91.161108 -116.910104)
			(xy 91.161108 -114.775742) (xy 91.160658 -114.765957) (xy 91.153337 -114.747807) (xy 91.146884 -114.740436)
			(xy 91.131898 -114.725196) (xy 91.125548 -114.718592) (xy 91.108784 -114.710718) (xy 91.093798 -114.703606)
			(xy 91.084908 -114.70259) (xy 91.056443 -114.699165) (xy 91.000922 -114.684877) (xy 90.948161 -114.662448)
			(xy 90.899348 -114.632381) (xy 90.855579 -114.595353) (xy 90.817838 -114.552197) (xy 90.786975 -114.503883)
			(xy 90.763684 -114.451497) (xy 90.748488 -114.396217) (xy 90.744548 -114.367818) (xy 90.743024 -114.354102)
			(xy 90.741754 -114.323368) (xy 90.741754 -114.302794) (xy 90.742516 -114.294412) (xy 90.742516 -114.293904)
			(xy 90.74506 -114.267055) (xy 90.756752 -114.214407) (xy 90.775746 -114.163932) (xy 90.801662 -114.116636)
			(xy 90.817446 -114.094768) (xy 90.835725 -114.071259) (xy 90.878349 -114.029679) (xy 90.926921 -113.995232)
			(xy 90.953336 -113.981484) (xy 90.961718 -113.97742) (xy 90.971575 -113.970859) (xy 90.984422 -113.951001)
			(xy 90.986356 -113.93932) (xy 90.986356 -113.939066) (xy 90.996262 -113.87709) (xy 90.996262 -113.876582)
			(xy 90.999056 -113.858548) (xy 90.999729 -113.852523) (xy 90.998578 -113.840458) (xy 90.99677 -113.834672)
			(xy 90.994992 -113.829084) (xy 90.988642 -113.818924) (xy 90.983816 -113.814352) (xy 90.9701 -113.800636)
			(xy 90.968068 -113.798604) (xy 90.965274 -113.795556) (xy 90.96375 -113.793778) (xy 90.962226 -113.792254)
			(xy 90.953082 -113.781586) (xy 90.946478 -113.773458) (xy 90.933524 -113.7666) (xy 90.930984 -113.76533)
			(xy 90.930222 -113.765076) (xy 90.919808 -113.759996) (xy 90.9193 -113.759996) (xy 90.915236 -113.757964)
			(xy 90.910237 -113.75578) (xy 90.899605 -113.753355) (xy 90.894154 -113.753138) (xy 90.837512 -113.753138)
			(xy 90.831647 -113.753307) (xy 90.820232 -113.756008) (xy 90.814906 -113.758472) (xy 90.796872 -113.767616)
			(xy 90.785696 -113.775236) (xy 90.779346 -113.781586) (xy 90.778584 -113.782856) (xy 90.776806 -113.784888)
			(xy 90.758574 -113.805659) (xy 90.717151 -113.842245) (xy 90.670889 -113.87248) (xy 90.620752 -113.895733)
			(xy 90.567787 -113.911518) (xy 90.513101 -113.919506) (xy 90.485468 -113.920016) (xy 90.485214 -113.920016)
			(xy 90.476832 -113.919762) (xy 90.476578 -113.919762) (xy 90.442979 -113.918296) (xy 90.377055 -113.905017)
			(xy 90.345514 -113.893346) (xy 90.34526 -113.893346) (xy 90.338986 -113.891062) (xy 90.325728 -113.889512)
			(xy 90.319098 -113.890298) (xy 90.306144 -113.89233) (xy 90.252296 -113.935256) (xy 90.251534 -113.936018)
			(xy 90.22715 -113.955068) (xy 90.218477 -113.962596) (xy 90.20843 -113.983223) (xy 90.207846 -113.994692)
			(xy 90.207846 -114.000534) (xy 90.208354 -114.003836) (xy 90.209989 -114.016473) (xy 90.211765 -114.041895)
			(xy 90.21191 -114.054636) (xy 90.21191 -114.058446) (xy 90.211353 -114.085648) (xy 90.203476 -114.139483)
			(xy 90.18803 -114.191652) (xy 90.16533 -114.241098) (xy 90.135835 -114.286818) (xy 90.100144 -114.327883)
			(xy 90.058981 -114.363462) (xy 90.013181 -114.392831) (xy 89.963673 -114.415396) (xy 89.911462 -114.430699)
			(xy 89.857606 -114.438429) (xy 89.830402 -114.438938) (xy 89.80315 -114.438452) (xy 89.7492 -114.430696)
			(xy 89.696904 -114.415342) (xy 89.647324 -114.392701) (xy 89.601471 -114.363235) (xy 89.560279 -114.327544)
			(xy 89.524584 -114.286354) (xy 89.495114 -114.240504) (xy 89.47247 -114.190926) (xy 89.457111 -114.138631)
			(xy 89.44935 -114.084682) (xy 89.448894 -114.05743) (xy 89.449369 -114.030304) (xy 89.45705 -113.976599)
			(xy 89.472262 -113.924524) (xy 89.494697 -113.875129) (xy 89.523904 -113.829411) (xy 89.559293 -113.788291)
			(xy 89.60015 -113.752599) (xy 89.645651 -113.723055) (xy 89.694879 -113.700254) (xy 89.74684 -113.684658)
			(xy 89.800486 -113.67658) (xy 89.827608 -113.675922) (xy 89.83091 -113.675922) (xy 89.854669 -113.676299)
			(xy 89.901815 -113.682233) (xy 89.947858 -113.693983) (xy 89.970102 -113.702338) (xy 89.970356 -113.702338)
			(xy 89.97663 -113.704621) (xy 89.989887 -113.706167) (xy 89.996518 -113.705386) (xy 90.009472 -113.703354)
			(xy 90.090752 -113.638584) (xy 90.097896 -113.631614) (xy 90.106661 -113.613705) (xy 90.10777 -113.603786)
			(xy 90.10777 -113.59515) (xy 90.107262 -113.591848) (xy 90.105624 -113.579211) (xy 90.103843 -113.55379)
			(xy 90.103706 -113.541048) (xy 90.103706 -113.537238) (xy 90.104277 -113.509551) (xy 90.112431 -113.454779)
			(xy 90.128415 -113.40176) (xy 90.151893 -113.351607) (xy 90.182371 -113.305373) (xy 90.219211 -113.264029)
			(xy 90.261638 -113.228442) (xy 90.308763 -113.19936) (xy 90.359595 -113.177392) (xy 90.413068 -113.163001)
			(xy 90.44051 -113.159286) (xy 90.454988 -113.157762) (xy 90.485214 -113.156492) (xy 90.485468 -113.156492)
			(xy 90.513268 -113.156993) (xy 90.568281 -113.165059) (xy 90.62154 -113.181025) (xy 90.671917 -113.204554)
			(xy 90.718345 -113.235146) (xy 90.759841 -113.272153) (xy 90.778076 -113.293144) (xy 90.781632 -113.29797)
			(xy 90.786204 -113.302034) (xy 90.796618 -113.308892) (xy 90.814906 -113.318036) (xy 90.820231 -113.320503)
			(xy 90.831647 -113.323207) (xy 90.837512 -113.32337) (xy 90.894662 -113.32337) (xy 90.899617 -113.323255)
			(xy 90.909342 -113.321346) (xy 90.913966 -113.31956) (xy 90.917014 -113.31829) (xy 90.933778 -113.310162)
			(xy 90.941144 -113.306352) (xy 90.949272 -113.299748) (xy 90.952828 -113.29543) (xy 90.970094 -113.275179)
			(xy 91.009297 -113.239192) (xy 91.053125 -113.209006) (xy 91.100724 -113.185209) (xy 91.125802 -113.176304)
			(xy 91.126056 -113.176304) (xy 91.128596 -113.175288) (xy 91.135375 -113.172319) (xy 91.146991 -113.163156)
			(xy 91.151456 -113.157254) (xy 91.151964 -113.156492) (xy 91.154823 -113.152196) (xy 91.158911 -113.14272)
			(xy 91.160092 -113.137696) (xy 91.161108 -113.127536) (xy 91.161108 -111.089948) (xy 91.160857 -111.082301)
			(xy 91.156347 -111.067687) (xy 91.152218 -111.061246) (xy 91.148408 -111.055658) (xy 91.134692 -111.04499)
			(xy 91.106498 -111.022892) (xy 91.078812 -111.001302) (xy 91.07218 -110.9969) (xy 91.057047 -110.991992)
			(xy 91.049094 -110.99165) (xy 91.035632 -110.99165) (xy 91.02979 -110.99292) (xy 91.00832 -110.997651)
			(xy 90.96465 -111.00274) (xy 90.942668 -111.00308) (xy 90.915419 -111.002592) (xy 90.861476 -110.994831)
			(xy 90.809187 -110.979473) (xy 90.759616 -110.95683) (xy 90.713771 -110.927362) (xy 90.672587 -110.89167)
			(xy 90.636902 -110.850481) (xy 90.607442 -110.804632) (xy 90.584806 -110.755057) (xy 90.569456 -110.702765)
			(xy 90.561704 -110.648821) (xy 90.56116 -110.621572) (xy 90.561582 -110.596144) (xy 90.568342 -110.54574)
			(xy 90.581738 -110.49668) (xy 90.601532 -110.449835) (xy 90.627374 -110.406035) (xy 90.658806 -110.366056)
			(xy 90.67673 -110.348014) (xy 90.677238 -110.347506) (xy 90.684604 -110.34014) (xy 90.694002 -110.319312)
			(xy 90.694002 -110.318804) (xy 90.69959 -110.306104) (xy 90.70086 -110.29569) (xy 90.70086 -110.243366)
			(xy 90.699336 -110.231428) (xy 90.697558 -110.223808) (xy 90.696542 -110.21822) (xy 90.691208 -110.206282)
			(xy 90.679524 -110.190026) (xy 90.660807 -110.171807) (xy 90.627971 -110.131186) (xy 90.60094 -110.086491)
			(xy 90.580213 -110.038547) (xy 90.566171 -109.988237) (xy 90.559072 -109.936488) (xy 90.55862 -109.910372)
			(xy 90.559111 -109.88294) (xy 90.566922 -109.828634) (xy 90.582382 -109.775993) (xy 90.605175 -109.726087)
			(xy 90.634838 -109.679933) (xy 90.670766 -109.638469) (xy 90.71223 -109.60254) (xy 90.758384 -109.572877)
			(xy 90.808289 -109.550083) (xy 90.86093 -109.534623) (xy 90.915236 -109.526811) (xy 90.942668 -109.526324)
			(xy 90.967333 -109.526752) (xy 91.016253 -109.533117) (xy 91.040204 -109.539024) (xy 91.053158 -109.540548)
			(xy 91.061032 -109.54004) (xy 91.067636 -109.539024) (xy 91.123262 -109.495844) (xy 91.123516 -109.49559)
			(xy 91.141296 -109.48162) (xy 91.14879 -109.475318) (xy 91.158722 -109.458464) (xy 91.1606 -109.448854)
			(xy 91.161108 -109.445044) (xy 91.161108 -108.825284) (xy 91.160901 -108.819197) (xy 91.157947 -108.807385)
			(xy 91.155266 -108.801916) (xy 91.14155 -108.77804) (xy 91.138207 -108.772793) (xy 91.129474 -108.763937)
			(xy 91.124278 -108.760514) (xy 91.064842 -108.72343) (xy 91.056056 -108.718454) (xy 91.036149 -108.715174)
			(xy 91.026234 -108.71708) (xy 91.020138 -108.718604) (xy 91.014804 -108.721144) (xy 91.01455 -108.721398)
			(xy 90.988074 -108.733911) (xy 90.932266 -108.751643) (xy 90.874409 -108.760669) (xy 90.845132 -108.761276)
			(xy 90.84437 -108.761276) (xy 90.817066 -108.760787) (xy 90.763013 -108.753011) (xy 90.710617 -108.737623)
			(xy 90.660944 -108.714935) (xy 90.615006 -108.685409) (xy 90.573736 -108.649647) (xy 90.537976 -108.608375)
			(xy 90.508453 -108.562434) (xy 90.485769 -108.51276) (xy 90.470384 -108.460363) (xy 90.462612 -108.40631)
			(xy 90.4621 -108.379006) (xy 90.46263 -108.351194) (xy 90.470752 -108.296165) (xy 90.486768 -108.242895)
			(xy 90.510339 -108.19251) (xy 90.540966 -108.146075) (xy 90.559128 -108.125006) (xy 90.562684 -108.120688)
			(xy 90.562938 -108.120434) (xy 90.564716 -108.118402) (xy 90.572082 -108.111036) (xy 90.575892 -108.101384)
			(xy 90.577645 -108.096817) (xy 90.579559 -108.087224) (xy 90.579702 -108.082334) (xy 90.579702 -108.02874)
			(xy 90.579565 -108.02385) (xy 90.577645 -108.014258) (xy 90.575892 -108.00969) (xy 90.572336 -108.0008)
			(xy 90.565224 -107.993434) (xy 90.54613 -107.973355) (xy 90.51321 -107.928787) (xy 90.486898 -107.880024)
			(xy 90.46772 -107.828041) (xy 90.456057 -107.773874) (xy 90.452143 -107.718604) (xy 90.456056 -107.663334)
			(xy 90.467717 -107.609167) (xy 90.486895 -107.557183) (xy 90.513205 -107.508421) (xy 90.546124 -107.463851)
			(xy 90.565224 -107.443778) (xy 90.572336 -107.436412) (xy 90.575892 -107.427522) (xy 90.577648 -107.422955)
			(xy 90.57957 -107.413363) (xy 90.579702 -107.408472) (xy 90.579702 -107.36834) (xy 90.579565 -107.36345)
			(xy 90.577645 -107.353858) (xy 90.575892 -107.34929) (xy 90.572336 -107.3404) (xy 90.565224 -107.333034)
			(xy 90.54613 -107.312955) (xy 90.51321 -107.268387) (xy 90.486898 -107.219624) (xy 90.46772 -107.167641)
			(xy 90.456057 -107.113474) (xy 90.452143 -107.058204) (xy 90.456056 -107.002934) (xy 90.467717 -106.948767)
			(xy 90.486895 -106.896783) (xy 90.513205 -106.848021) (xy 90.546124 -106.803451) (xy 90.565224 -106.783378)
			(xy 90.572336 -106.776012) (xy 90.575892 -106.767122) (xy 90.577648 -106.762555) (xy 90.57957 -106.752963)
			(xy 90.579702 -106.748072) (xy 90.579702 -106.70794) (xy 90.579565 -106.70305) (xy 90.577645 -106.693458)
			(xy 90.575892 -106.68889) (xy 90.572336 -106.68) (xy 90.565224 -106.672634) (xy 90.54613 -106.652555)
			(xy 90.51321 -106.607987) (xy 90.486898 -106.559224) (xy 90.46772 -106.507241) (xy 90.456057 -106.453074)
			(xy 90.452143 -106.397804) (xy 90.456056 -106.342534) (xy 90.467717 -106.288367) (xy 90.486895 -106.236383)
			(xy 90.513205 -106.187621) (xy 90.546124 -106.143051) (xy 90.565224 -106.122978) (xy 90.572336 -106.115612)
			(xy 90.575892 -106.106722) (xy 90.577648 -106.102155) (xy 90.57957 -106.092563) (xy 90.579702 -106.087672)
			(xy 90.579702 -106.04754) (xy 90.579565 -106.04265) (xy 90.577645 -106.033058) (xy 90.575892 -106.02849)
			(xy 90.572336 -106.0196) (xy 90.565224 -106.012234) (xy 90.54613 -105.992155) (xy 90.51321 -105.947587)
			(xy 90.486898 -105.898824) (xy 90.46772 -105.846841) (xy 90.456057 -105.792674) (xy 90.452143 -105.737404)
			(xy 90.456056 -105.682134) (xy 90.467717 -105.627967) (xy 90.486895 -105.575983) (xy 90.513205 -105.527221)
			(xy 90.546124 -105.482651) (xy 90.565224 -105.462578) (xy 90.572336 -105.455212) (xy 90.575892 -105.446322)
			(xy 90.577648 -105.441755) (xy 90.57957 -105.432163) (xy 90.579702 -105.427272) (xy 90.579702 -105.38714)
			(xy 90.579565 -105.38225) (xy 90.577645 -105.372658) (xy 90.575892 -105.36809) (xy 90.572336 -105.3592)
			(xy 90.565224 -105.351834) (xy 90.54613 -105.331755) (xy 90.51321 -105.287187) (xy 90.486898 -105.238424)
			(xy 90.46772 -105.186441) (xy 90.456057 -105.132274) (xy 90.452143 -105.077004) (xy 90.456056 -105.021734)
			(xy 90.467717 -104.967567) (xy 90.486895 -104.915583) (xy 90.513205 -104.866821) (xy 90.546124 -104.822251)
			(xy 90.565224 -104.802178) (xy 90.572336 -104.794812) (xy 90.575892 -104.785922) (xy 90.577648 -104.781355)
			(xy 90.57957 -104.771763) (xy 90.579702 -104.766872) (xy 90.579702 -104.72674) (xy 90.579565 -104.72185)
			(xy 90.577645 -104.712258) (xy 90.575892 -104.70769) (xy 90.572336 -104.6988) (xy 90.565224 -104.691434)
			(xy 90.54613 -104.671355) (xy 90.51321 -104.626787) (xy 90.486898 -104.578024) (xy 90.46772 -104.526041)
			(xy 90.456057 -104.471874) (xy 90.452143 -104.416604) (xy 90.456056 -104.361334) (xy 90.467717 -104.307167)
			(xy 90.486895 -104.255183) (xy 90.513205 -104.206421) (xy 90.546124 -104.161851) (xy 90.565224 -104.141778)
			(xy 90.572336 -104.134412) (xy 90.575892 -104.125522) (xy 90.577648 -104.120955) (xy 90.57957 -104.111363)
			(xy 90.579702 -104.106472) (xy 90.579702 -104.06634) (xy 90.579565 -104.06145) (xy 90.577645 -104.051858)
			(xy 90.575892 -104.04729) (xy 90.572336 -104.0384) (xy 90.565224 -104.031034) (xy 90.54613 -104.010955)
			(xy 90.51321 -103.966387) (xy 90.486898 -103.917624) (xy 90.46772 -103.865641) (xy 90.456057 -103.811474)
			(xy 90.452143 -103.756204) (xy 90.456056 -103.700934) (xy 90.467717 -103.646767) (xy 90.486895 -103.594783)
			(xy 90.513205 -103.546021) (xy 90.546124 -103.501451) (xy 90.565224 -103.481378) (xy 90.572336 -103.474012)
			(xy 90.575892 -103.465122) (xy 90.577648 -103.460555) (xy 90.57957 -103.450963) (xy 90.579702 -103.446072)
			(xy 90.579702 -103.406194) (xy 90.579601 -103.401318) (xy 90.577801 -103.391733) (xy 90.576146 -103.387144)
			(xy 90.572336 -103.378) (xy 90.565224 -103.370888) (xy 90.544225 -103.348748) (xy 90.508651 -103.299173)
			(xy 90.48119 -103.244683) (xy 90.462505 -103.186596) (xy 90.453047 -103.126315) (xy 90.452448 -103.095806)
			(xy 90.452966 -103.06723) (xy 90.461269 -103.010685) (xy 90.477701 -102.955947) (xy 90.501912 -102.904177)
			(xy 90.533389 -102.856474) (xy 90.571463 -102.813852) (xy 90.615326 -102.777214) (xy 90.639392 -102.761796)
			(xy 90.647856 -102.75612) (xy 90.659774 -102.73961) (xy 90.662506 -102.729792) (xy 90.667078 -102.709726)
			(xy 90.675206 -102.67442) (xy 90.67622 -102.669661) (xy 90.676608 -102.659939) (xy 90.675968 -102.655116)
			(xy 90.674444 -102.64521) (xy 90.66911 -102.636574) (xy 90.655909 -102.614068) (xy 90.635106 -102.566218)
			(xy 90.621018 -102.515979) (xy 90.613907 -102.464288) (xy 90.613484 -102.4382) (xy 90.61397 -102.410949)
			(xy 90.621726 -102.357) (xy 90.637081 -102.304705) (xy 90.659722 -102.255127) (xy 90.689188 -102.209276)
			(xy 90.72488 -102.168086) (xy 90.76607 -102.132393) (xy 90.81192 -102.102926) (xy 90.861498 -102.080284)
			(xy 90.913793 -102.064928) (xy 90.967741 -102.05717) (xy 90.994992 -102.056692) (xy 90.9955 -102.056692)
			(xy 91.007983 -102.0568) (xy 91.032896 -102.058452) (xy 91.045284 -102.059994) (xy 91.0463 -102.059994)
			(xy 91.054949 -102.060654) (xy 91.07184 -102.056765) (xy 91.07932 -102.052374) (xy 91.086178 -102.048056)
			(xy 91.127326 -102.011988) (xy 91.137486 -102.003098) (xy 91.138248 -102.002336) (xy 91.14409 -101.997256)
			(xy 91.150918 -101.990624) (xy 91.159524 -101.973661) (xy 91.160854 -101.964236) (xy 91.161108 -101.95941)
			(xy 91.161108 -98.204782) (xy 91.160875 -98.197829) (xy 91.157153 -98.184429) (xy 91.153742 -98.178366)
			(xy 91.150186 -98.172524) (xy 91.140026 -98.163126) (xy 91.133676 -98.159824) (xy 91.109243 -98.146579)
			(xy 91.06415 -98.114094) (xy 91.024248 -98.07541) (xy 90.990381 -98.031346) (xy 90.963266 -97.982834)
			(xy 90.943476 -97.930902) (xy 90.931432 -97.876647) (xy 90.927386 -97.821219) (xy 90.931426 -97.765791)
			(xy 90.943465 -97.711535) (xy 90.963249 -97.659601) (xy 90.99036 -97.611086) (xy 91.024222 -97.567019)
			(xy 91.06412 -97.528331) (xy 91.10921 -97.495841) (xy 91.133676 -97.48266) (xy 91.141718 -97.478055)
			(xy 91.154064 -97.464256) (xy 91.160673 -97.44696) (xy 91.161108 -97.437702) (xy 91.161108 -96.28505)
			(xy 91.160941 -96.27904) (xy 91.158117 -96.267358) (xy 91.15552 -96.261936) (xy 91.153684 -96.258459)
			(xy 91.149097 -96.252074) (xy 91.146376 -96.249236) (xy 91.120468 -96.223328) (xy 91.115642 -96.218756)
			(xy 91.094814 -96.198182) (xy 91.087404 -96.191498) (xy 91.068968 -96.183913) (xy 91.059 -96.18345)
			(xy 91.056714 -96.18345) (xy 91.029457 -96.182988) (xy 90.975499 -96.175232) (xy 90.923194 -96.159875)
			(xy 90.873606 -96.137231) (xy 90.827746 -96.10776) (xy 90.786547 -96.072063) (xy 90.750848 -96.030865)
			(xy 90.721376 -95.985006) (xy 90.69873 -95.935419) (xy 90.683371 -95.883115) (xy 90.675613 -95.829157)
			(xy 90.675613 -95.774643) (xy 90.683371 -95.720685) (xy 90.69873 -95.668381) (xy 90.721376 -95.618794)
			(xy 90.750848 -95.572935) (xy 90.786547 -95.531737) (xy 90.827746 -95.49604) (xy 90.873606 -95.466569)
			(xy 90.923194 -95.443925) (xy 90.975499 -95.428568) (xy 91.029457 -95.420812) (xy 91.056714 -95.420434)
			(xy 91.059 -95.420434) (xy 91.068423 -95.419998) (xy 91.086015 -95.41323) (xy 91.09329 -95.407226)
			(xy 91.119452 -95.381318) (xy 91.143582 -95.357442) (xy 91.152153 -95.349245) (xy 91.161287 -95.327391)
			(xy 91.161108 -95.315532) (xy 91.161108 -79.284576) (xy 91.160944 -79.278566) (xy 91.158126 -79.26688)
			(xy 91.15552 -79.261462) (xy 91.15368 -79.257988) (xy 91.149086 -79.25161) (xy 91.146376 -79.248762)
			(xy 90.506804 -78.60919) (xy 90.49941 -78.602333) (xy 90.480811 -78.594583) (xy 90.470736 -78.594204)
			(xy 90.424 -78.594204) (xy 90.390845 -78.59374) (xy 90.324951 -78.58632) (xy 90.260302 -78.571574)
			(xy 90.197708 -78.549686) (xy 90.137957 -78.520931) (xy 90.081799 -78.485672) (xy 90.029939 -78.444349)
			(xy 90.00617 -78.42123) (xy 88.56853 -76.98359) (xy 88.561132 -76.976745) (xy 88.542533 -76.969022)
			(xy 88.532462 -76.968604) (xy 83.529678 -76.968604) (xy 83.517835 -76.969228) (xy 83.496652 -76.979829)
			(xy 83.489038 -76.988924) (xy 83.432904 -77.063854) (xy 83.42884 -77.087222) (xy 83.430364 -77.092556)
			(xy 83.438417 -77.120183) (xy 83.447092 -77.177069) (xy 83.447636 -77.20584) (xy 83.447636 -77.206348)
			(xy 83.44715 -77.233599) (xy 83.439394 -77.287547) (xy 83.424039 -77.339842) (xy 83.401397 -77.389419)
			(xy 83.371931 -77.435269) (xy 83.33624 -77.47646) (xy 83.295049 -77.512151) (xy 83.249199 -77.541617)
			(xy 83.199622 -77.564259) (xy 83.147327 -77.579614) (xy 83.093379 -77.58737) (xy 83.038877 -77.58737)
			(xy 82.984929 -77.579614) (xy 82.932634 -77.564259) (xy 82.883057 -77.541617) (xy 82.837207 -77.512151)
			(xy 82.796016 -77.47646) (xy 82.760325 -77.435269) (xy 82.730859 -77.389419) (xy 82.708217 -77.339842)
			(xy 82.692862 -77.287547) (xy 82.685106 -77.233599) (xy 82.68462 -77.206348) (xy 82.68462 -77.190854)
			(xy 82.685886 -77.167529) (xy 82.693396 -77.121424) (xy 82.699606 -77.098906) (xy 82.703162 -77.087476)
			(xy 82.698844 -77.063854) (xy 82.642964 -76.988924) (xy 82.635363 -76.979814) (xy 82.614172 -76.969208)
			(xy 82.602324 -76.968604) (xy 41.07942 -76.968604) (xy 41.043709 -76.968048) (xy 40.972812 -76.959407)
			(xy 40.903473 -76.942285) (xy 40.836704 -76.91693) (xy 40.804846 -76.900786) (xy 40.801798 -76.899262)
			(xy 40.769727 -76.884347) (xy 40.70914 -76.847853) (xy 40.653428 -76.804276) (xy 40.628062 -76.779628)
			(xy 37.571172 -73.722738) (xy 37.547725 -73.698632) (xy 37.505965 -73.64592) (xy 37.48786 -73.617582)
			(xy 37.484558 -73.612756) (xy 37.46442 -73.586623) (xy 37.429448 -73.530676) (xy 37.400933 -73.471179)
			(xy 37.37923 -73.408873) (xy 37.36461 -73.344535) (xy 37.357255 -73.278969) (xy 37.356796 -73.24598)
			(xy 37.356796 -59.319668) (xy 37.340794 -59.054238) (xy 37.335206 -58.963052) (xy 37.335206 -58.96102)
			(xy 36.447476 -49.946814) (xy 36.445698 -49.937416) (xy 36.349432 -49.613566) (xy 36.338206 -49.573025)
			(xy 36.326217 -49.489765) (xy 36.325556 -49.447704) (xy 36.325556 -48.712374) (xy 36.325302 -48.707294)
			(xy 36.084002 -46.257718) (xy 36.082755 -46.249029) (xy 36.075216 -46.233189) (xy 36.06927 -46.22673)
			(xy 25.64257 -35.80003) (xy 25.618382 -35.775159) (xy 25.575383 -35.720711) (xy 25.539059 -35.6616)
			(xy 25.509912 -35.59864) (xy 25.488341 -35.532699) (xy 25.481026 -35.498786) (xy 25.479756 -35.494214)
			(xy 25.468588 -35.453921) (xy 25.456606 -35.371174) (xy 25.45588 -35.329368) (xy 25.45588 -32.413194)
			(xy 25.455718 -32.407183) (xy 25.452902 -32.395497) (xy 25.450292 -32.39008) (xy 25.448452 -32.386606)
			(xy 25.443858 -32.380228) (xy 25.441148 -32.37738) (xy 24.99868 -31.934912) (xy 24.996004 -31.932302)
			(xy 24.99001 -31.927836) (xy 24.986742 -31.926022) (xy 24.980646 -31.92272) (xy 24.97328 -31.921196)
			(xy 24.940656 -31.91373) (xy 24.877251 -31.892299) (xy 24.816725 -31.863733) (xy 24.759876 -31.828411)
			(xy 24.707456 -31.786798) (xy 24.683466 -31.763462) (xy 24.370792 -31.450788) (xy 24.344045 -31.423237)
			(xy 24.297282 -31.362331) (xy 24.277574 -31.329376) (xy 24.256746 -31.309564) (xy 24.229382 -31.295157)
			(xy 24.17754 -31.261431) (xy 24.129513 -31.222466) (xy 24.107394 -31.200852) (xy 23.756874 -30.850332)
			(xy 23.739031 -30.832112) (xy 23.706216 -30.793069) (xy 23.691342 -30.772354) (xy 23.688802 -30.768798)
			(xy 23.601934 -30.68193) (xy 23.576165 -30.655374) (xy 23.530863 -30.596864) (xy 23.493343 -30.533083)
			(xy 23.478236 -30.499304) (xy 23.449788 -30.471872) (xy 23.421229 -30.460411) (xy 23.366445 -30.432376)
			(xy 23.314877 -30.398789) (xy 23.267087 -30.360016) (xy 23.245064 -30.338522) (xy 22.894544 -29.988002)
			(xy 22.87656 -29.969601) (xy 22.843493 -29.930175) (xy 22.828504 -29.909262) (xy 22.823678 -29.90342)
			(xy 22.803684 -29.881963) (xy 22.767643 -29.835691) (xy 22.736448 -29.786022) (xy 22.723094 -29.75991)
			(xy 22.711932 -29.736854) (xy 22.693236 -29.689159) (xy 22.685756 -29.66466) (xy 22.649942 -29.629862)
			(xy 22.619886 -29.62151) (xy 22.56158 -29.599322) (xy 22.505935 -29.571116) (xy 22.453571 -29.537206)
			(xy 22.40507 -29.497969) (xy 22.382734 -29.476192) (xy 22.058884 -29.152596) (xy 22.054058 -29.149548)
			(xy 22.026857 -29.13182) (xy 21.97619 -29.091212) (xy 21.952966 -29.068522) (xy 21.640292 -28.755848)
			(xy 21.616456 -28.731424) (xy 21.574056 -28.677945) (xy 21.55571 -28.649168) (xy 21.546312 -28.637992)
			(xy 21.520658 -28.613862) (xy 21.170138 -28.263342) (xy 21.145572 -28.238051) (xy 21.102003 -28.182614)
			(xy 21.06534 -28.122386) (xy 21.036105 -28.058224) (xy 21.014713 -27.991039) (xy 21.007578 -27.95651)
			(xy 21.007578 -27.956256) (xy 21.005842 -27.948916) (xy 20.998751 -27.93561) (xy 20.993608 -27.930094)
			(xy 20.974304 -27.91079) (xy 20.96691 -27.903933) (xy 20.948311 -27.896183) (xy 20.938236 -27.895804)
			(xy 19.767296 -27.895804) (xy 19.758339 -27.896149) (xy 19.741513 -27.902294) (xy 19.727813 -27.913836)
			(xy 19.7231 -27.921458) (xy 19.712686 -27.94) (xy 19.712686 -27.940508) (xy 19.698716 -27.964638)
			(xy 19.696015 -27.970168) (xy 19.693049 -27.982109) (xy 19.692874 -27.98826) (xy 19.692874 -28.003246)
			(xy 19.699986 -28.018486) (xy 19.700748 -28.019756) (xy 19.701256 -28.020518) (xy 19.719596 -28.053574)
			(xy 19.746271 -28.124302) (xy 19.754342 -28.161234) (xy 19.758475 -28.183355) (xy 19.762924 -28.22814)
			(xy 19.763232 -28.250642) (xy 19.763232 -29.114242) (xy 19.762742 -29.144226) (xy 19.754914 -29.203682)
			(xy 19.739393 -29.261607) (xy 19.716444 -29.317011) (xy 19.68646 -29.368945) (xy 19.649954 -29.416521)
			(xy 19.607549 -29.458926) (xy 19.559973 -29.495432) (xy 19.508039 -29.525416) (xy 19.452635 -29.548365)
			(xy 19.39471 -29.563886) (xy 19.335254 -29.571714) (xy 19.275286 -29.571714) (xy 19.21583 -29.563886)
			(xy 19.157905 -29.548365) (xy 19.102501 -29.525416) (xy 19.050567 -29.495432) (xy 19.002991 -29.458926)
			(xy 18.960586 -29.416521) (xy 18.92408 -29.368945) (xy 18.894096 -29.317011) (xy 18.871147 -29.261607)
			(xy 18.855626 -29.203682) (xy 18.847798 -29.144226) (xy 18.847308 -29.114242) (xy 18.847308 -28.250642)
			(xy 18.8478 -28.219937) (xy 18.856002 -28.159078) (xy 18.872265 -28.099861) (xy 18.896296 -28.043349)
			(xy 18.91157 -28.016708) (xy 18.91157 -28.016454) (xy 18.91488 -28.010624) (xy 18.918612 -27.997751)
			(xy 18.918936 -27.991054) (xy 18.918936 -27.977592) (xy 18.892012 -27.930094) (xy 18.887186 -27.921458)
			(xy 18.882456 -27.913843) (xy 18.868778 -27.902273) (xy 18.851948 -27.89613) (xy 18.84299 -27.895804)
			(xy 18.3896 -27.895804) (xy 18.356445 -27.89534) (xy 18.290551 -27.88792) (xy 18.225902 -27.873174)
			(xy 18.163308 -27.851286) (xy 18.103557 -27.822531) (xy 18.047399 -27.787272) (xy 17.995539 -27.745949)
			(xy 17.97177 -27.72283) (xy 17.90573 -27.65679) (xy 17.898332 -27.649945) (xy 17.879733 -27.642222)
			(xy 17.869662 -27.641804) (xy 17.539208 -27.641804) (xy 17.529137 -27.642226) (xy 17.510531 -27.649939)
			(xy 17.50314 -27.65679) (xy 17.399254 -27.760676) (xy 17.375495 -27.783817) (xy 17.323652 -27.825187)
			(xy 17.267503 -27.860491) (xy 17.207753 -27.889286) (xy 17.145154 -27.911209) (xy 17.080495 -27.925983)
			(xy 17.014587 -27.933425) (xy 16.981424 -27.933904) (xy 16.94826 -27.933457) (xy 16.88235 -27.926031)
			(xy 16.817686 -27.91127) (xy 16.755082 -27.88936) (xy 16.695326 -27.860576) (xy 16.63917 -27.825281)
			(xy 16.58732 -27.783918) (xy 16.540429 -27.737008) (xy 16.499086 -27.685142) (xy 16.463813 -27.628972)
			(xy 16.435052 -27.569205) (xy 16.413166 -27.506593) (xy 16.39843 -27.441923) (xy 16.39103 -27.37601)
			(xy 16.39062 -27.342846) (xy 16.391045 -27.310542) (xy 16.398074 -27.246318) (xy 16.412064 -27.183243)
			(xy 16.432848 -27.12207) (xy 16.460179 -27.063528) (xy 16.49373 -27.008315) (xy 16.513048 -26.98242)
			(xy 16.518128 -26.975816) (xy 16.523716 -26.960068) (xy 16.523716 -26.862024) (xy 16.517874 -26.845768)
			(xy 16.513048 -26.839672) (xy 16.493722 -26.813834) (xy 16.460195 -26.7587) (xy 16.43288 -26.70024)
			(xy 16.412102 -26.63915) (xy 16.398109 -26.576159) (xy 16.391067 -26.512017) (xy 16.39062 -26.479754)
			(xy 16.39062 -26.479246) (xy 16.391159 -26.443536) (xy 16.399766 -26.372637) (xy 16.416853 -26.303291)
			(xy 16.442173 -26.23651) (xy 16.475355 -26.173267) (xy 16.515917 -26.114483) (xy 16.563266 -26.061015)
			(xy 16.616714 -26.013642) (xy 16.675481 -25.973056) (xy 16.73871 -25.939846) (xy 16.80548 -25.914499)
			(xy 16.874819 -25.897381) (xy 16.945714 -25.888744) (xy 16.981424 -25.888188) (xy 17.014585 -25.88867)
			(xy 17.080486 -25.896129) (xy 17.145139 -25.910916) (xy 17.207731 -25.932846) (xy 17.267475 -25.961643)
			(xy 17.323621 -25.996945) (xy 17.375463 -26.03831) (xy 17.399254 -26.061416) (xy 17.501108 -26.16327)
			(xy 17.508506 -26.170118) (xy 17.527104 -26.177855) (xy 17.537176 -26.178256) (xy 18.252948 -26.178256)
			(xy 18.286311 -26.178739) (xy 18.352609 -26.186297) (xy 18.417636 -26.201266) (xy 18.480566 -26.223456)
			(xy 18.540599 -26.252586) (xy 18.596973 -26.288285) (xy 18.62328 -26.308812) (xy 18.624296 -26.309828)
			(xy 18.640187 -26.322051) (xy 18.670437 -26.348366) (xy 18.684748 -26.362406) (xy 18.716752 -26.394156)
			(xy 18.732754 -26.410158) (xy 18.738257 -26.415138) (xy 18.751426 -26.421967) (xy 18.758662 -26.42362)
			(xy 18.768314 -26.424636) (xy 18.990056 -26.424636) (xy 18.999501 -26.424146) (xy 19.017092 -26.417243)
			(xy 19.024346 -26.411174) (xy 19.05889 -26.37917) (xy 19.059398 -26.378662) (xy 19.0754 -26.36393)
			(xy 19.078705 -26.36071) (xy 19.084196 -26.353294) (xy 19.086322 -26.349198) (xy 19.090386 -26.34107)
			(xy 19.091402 -26.33091) (xy 19.094172 -26.302571) (xy 19.107047 -26.247107) (xy 19.128019 -26.194172)
			(xy 19.156625 -26.144941) (xy 19.192228 -26.100508) (xy 19.234039 -26.061857) (xy 19.281129 -26.029849)
			(xy 19.332452 -26.005193) (xy 19.386868 -25.988437) (xy 19.443171 -25.979953) (xy 19.47164 -25.979374)
			(xy 19.499386 -25.97987) (xy 19.554292 -25.987911) (xy 19.60745 -26.003831) (xy 19.657737 -26.027294)
			(xy 19.667515 -26.03373) (xy 31.267906 -26.03373) (xy 31.271977 -25.978108) (xy 31.284103 -25.923671)
			(xy 31.304026 -25.87158) (xy 31.331322 -25.822945) (xy 31.365408 -25.778802) (xy 31.405557 -25.740093)
			(xy 31.450915 -25.707642) (xy 31.500515 -25.682141) (xy 31.553299 -25.664134) (xy 31.608142 -25.654004)
			(xy 31.663876 -25.651967) (xy 31.719313 -25.658067) (xy 31.77327 -25.672173) (xy 31.824599 -25.693985)
			(xy 31.872205 -25.723039) (xy 31.915073 -25.758714) (xy 31.95229 -25.800251) (xy 31.983063 -25.846764)
			(xy 32.006735 -25.897261) (xy 32.022803 -25.950668) (xy 32.030923 -26.005844) (xy 32.031432 -26.03373)
			(xy 32.030923 -26.061616) (xy 32.022803 -26.116792) (xy 32.006735 -26.170199) (xy 31.983063 -26.220696)
			(xy 31.952829 -26.266394) (xy 34.520632 -26.266394) (xy 34.521118 -26.239143) (xy 34.528874 -26.185195)
			(xy 34.544229 -26.1329) (xy 34.566871 -26.083323) (xy 34.596337 -26.037473) (xy 34.632028 -25.996282)
			(xy 34.673219 -25.960591) (xy 34.719069 -25.931125) (xy 34.768646 -25.908483) (xy 34.820941 -25.893128)
			(xy 34.874889 -25.885372) (xy 34.929391 -25.885372) (xy 34.983339 -25.893128) (xy 35.035634 -25.908483)
			(xy 35.085211 -25.931125) (xy 35.131061 -25.960591) (xy 35.172252 -25.996282) (xy 35.207943 -26.037473)
			(xy 35.237409 -26.083323) (xy 35.260051 -26.1329) (xy 35.275406 -26.185195) (xy 35.283162 -26.239143)
			(xy 35.283648 -26.266394) (xy 35.283077 -26.295881) (xy 35.273984 -26.354149) (xy 35.256028 -26.410324)
			(xy 35.229638 -26.463064) (xy 35.195444 -26.511112) (xy 35.15426 -26.553324) (xy 35.130994 -26.571448)
			(xy 35.119838 -26.580307) (xy 35.102651 -26.603017) (xy 35.092403 -26.629589) (xy 35.08989 -26.657958)
			(xy 35.095306 -26.685918) (xy 35.108232 -26.711296) (xy 35.127662 -26.732118) (xy 35.13963 -26.73985)
			(xy 35.163373 -26.754744) (xy 35.206607 -26.790413) (xy 35.244157 -26.832023) (xy 35.275216 -26.878679)
			(xy 35.299114 -26.929376) (xy 35.315339 -26.983025) (xy 35.323539 -27.03847) (xy 35.324034 -27.066494)
			(xy 35.323548 -27.093745) (xy 35.315792 -27.147693) (xy 35.300437 -27.199988) (xy 35.277795 -27.249565)
			(xy 35.248329 -27.295415) (xy 35.212638 -27.336606) (xy 35.171447 -27.372297) (xy 35.125597 -27.401763)
			(xy 35.07602 -27.424405) (xy 35.023725 -27.43976) (xy 34.969777 -27.447516) (xy 34.915275 -27.447516)
			(xy 34.861327 -27.43976) (xy 34.809032 -27.424405) (xy 34.759455 -27.401763) (xy 34.713605 -27.372297)
			(xy 34.672414 -27.336606) (xy 34.636723 -27.295415) (xy 34.607257 -27.249565) (xy 34.584615 -27.199988)
			(xy 34.56926 -27.147693) (xy 34.561504 -27.093745) (xy 34.561018 -27.066494) (xy 34.561554 -27.037005)
			(xy 34.570651 -26.978734) (xy 34.588612 -26.922558) (xy 34.615008 -26.869818) (xy 34.64921 -26.82177)
			(xy 34.690402 -26.779562) (xy 34.713672 -26.76144) (xy 34.724728 -26.752469) (xy 34.741902 -26.729782)
			(xy 34.752148 -26.703237) (xy 34.754672 -26.674896) (xy 34.749276 -26.646958) (xy 34.73638 -26.621594)
			(xy 34.716985 -26.600774) (xy 34.705036 -26.593038) (xy 34.681302 -26.578128) (xy 34.638065 -26.542465)
			(xy 34.600512 -26.500859) (xy 34.569451 -26.454206) (xy 34.545551 -26.40351) (xy 34.529326 -26.349862)
			(xy 34.521126 -26.294418) (xy 34.520632 -26.266394) (xy 31.952829 -26.266394) (xy 31.95229 -26.267209)
			(xy 31.915073 -26.308746) (xy 31.872205 -26.344421) (xy 31.824599 -26.373475) (xy 31.77327 -26.395287)
			(xy 31.719313 -26.409393) (xy 31.663876 -26.415493) (xy 31.608142 -26.413456) (xy 31.553299 -26.403326)
			(xy 31.500515 -26.385319) (xy 31.450915 -26.359818) (xy 31.405557 -26.327367) (xy 31.365408 -26.288658)
			(xy 31.331322 -26.244515) (xy 31.304026 -26.19588) (xy 31.284103 -26.143789) (xy 31.271977 -26.089352)
			(xy 31.267906 -26.03373) (xy 19.667515 -26.03373) (xy 19.704089 -26.057804) (xy 19.725132 -26.075894)
			(xy 19.747319 -26.096336) (xy 19.785584 -26.142973) (xy 19.816023 -26.195057) (xy 19.827494 -26.22296)
			(xy 19.836862 -26.248449) (xy 19.849103 -26.301356) (xy 19.851878 -26.32837) (xy 19.852132 -26.331926)
			(xy 19.853405 -26.341271) (xy 19.861898 -26.358097) (xy 19.868642 -26.364692) (xy 19.883882 -26.378662)
			(xy 19.88439 -26.37917) (xy 19.918934 -26.411174) (xy 19.926141 -26.417317) (xy 19.943762 -26.424222)
			(xy 19.953224 -26.424636) (xy 21.281898 -26.424636) (xy 21.311252 -26.42504) (xy 21.369657 -26.43102)
			(xy 21.398484 -26.436574) (xy 21.40204 -26.437082) (xy 21.434031 -26.441677) (xy 21.496833 -26.456952)
			(xy 21.557593 -26.47899) (xy 21.615584 -26.507528) (xy 21.670114 -26.542225) (xy 21.720532 -26.582666)
			(xy 21.74367 -26.60523) (xy 23.277576 -28.139136) (xy 28.39796 -28.139136) (xy 28.402031 -28.083514)
			(xy 28.414157 -28.029077) (xy 28.43408 -27.976986) (xy 28.461376 -27.928351) (xy 28.495462 -27.884208)
			(xy 28.535611 -27.845499) (xy 28.580969 -27.813048) (xy 28.630569 -27.787547) (xy 28.683353 -27.76954)
			(xy 28.738196 -27.75941) (xy 28.79393 -27.757373) (xy 28.849367 -27.763473) (xy 28.903324 -27.777579)
			(xy 28.954653 -27.799391) (xy 29.002259 -27.828445) (xy 29.045127 -27.86412) (xy 29.082344 -27.905657)
			(xy 29.113117 -27.95217) (xy 29.136789 -28.002667) (xy 29.152857 -28.056074) (xy 29.160977 -28.11125)
			(xy 29.161486 -28.139136) (xy 29.66796 -28.139136) (xy 29.672031 -28.083514) (xy 29.684157 -28.029077)
			(xy 29.70408 -27.976986) (xy 29.731376 -27.928351) (xy 29.765462 -27.884208) (xy 29.805611 -27.845499)
			(xy 29.850969 -27.813048) (xy 29.900569 -27.787547) (xy 29.953353 -27.76954) (xy 30.008196 -27.75941)
			(xy 30.06393 -27.757373) (xy 30.119367 -27.763473) (xy 30.173324 -27.777579) (xy 30.224653 -27.799391)
			(xy 30.272259 -27.828445) (xy 30.315127 -27.86412) (xy 30.352344 -27.905657) (xy 30.383117 -27.95217)
			(xy 30.406789 -28.002667) (xy 30.422857 -28.056074) (xy 30.430977 -28.11125) (xy 30.431486 -28.139136)
			(xy 30.430977 -28.167022) (xy 30.422857 -28.222198) (xy 30.406789 -28.275605) (xy 30.383117 -28.326102)
			(xy 30.352344 -28.372615) (xy 30.315127 -28.414152) (xy 30.272259 -28.449827) (xy 30.224653 -28.478881)
			(xy 30.173324 -28.500693) (xy 30.119367 -28.514799) (xy 30.06393 -28.520899) (xy 30.008196 -28.518862)
			(xy 29.953353 -28.508732) (xy 29.900569 -28.490725) (xy 29.850969 -28.465224) (xy 29.805611 -28.432773)
			(xy 29.765462 -28.394064) (xy 29.731376 -28.349921) (xy 29.70408 -28.301286) (xy 29.684157 -28.249195)
			(xy 29.672031 -28.194758) (xy 29.66796 -28.139136) (xy 29.161486 -28.139136) (xy 29.160977 -28.167022)
			(xy 29.152857 -28.222198) (xy 29.136789 -28.275605) (xy 29.113117 -28.326102) (xy 29.082344 -28.372615)
			(xy 29.045127 -28.414152) (xy 29.002259 -28.449827) (xy 28.954653 -28.478881) (xy 28.903324 -28.500693)
			(xy 28.849367 -28.514799) (xy 28.79393 -28.520899) (xy 28.738196 -28.518862) (xy 28.683353 -28.508732)
			(xy 28.630569 -28.490725) (xy 28.580969 -28.465224) (xy 28.535611 -28.432773) (xy 28.495462 -28.394064)
			(xy 28.461376 -28.349921) (xy 28.43408 -28.301286) (xy 28.414157 -28.249195) (xy 28.402031 -28.194758)
			(xy 28.39796 -28.139136) (xy 23.277576 -28.139136) (xy 24.26081 -29.12237) (xy 34.606992 -29.12237)
			(xy 34.606992 -28.25877) (xy 34.607482 -28.228802) (xy 34.615305 -28.16938) (xy 34.630818 -28.111487)
			(xy 34.653754 -28.056114) (xy 34.683721 -28.004208) (xy 34.720208 -27.956658) (xy 34.762588 -27.914278)
			(xy 34.810138 -27.877791) (xy 34.862044 -27.847824) (xy 34.917417 -27.824888) (xy 34.97531 -27.809375)
			(xy 35.034732 -27.801552) (xy 35.094668 -27.801552) (xy 35.15409 -27.809375) (xy 35.211983 -27.824888)
			(xy 35.267356 -27.847824) (xy 35.319262 -27.877791) (xy 35.366812 -27.914278) (xy 35.409192 -27.956658)
			(xy 35.445679 -28.004208) (xy 35.475646 -28.056114) (xy 35.498582 -28.111487) (xy 35.514095 -28.16938)
			(xy 35.521918 -28.228802) (xy 35.522408 -28.25877) (xy 35.522408 -29.12237) (xy 35.521918 -29.152338)
			(xy 35.514095 -29.21176) (xy 35.498582 -29.269653) (xy 35.475646 -29.325026) (xy 35.445679 -29.376932)
			(xy 35.409192 -29.424482) (xy 35.366812 -29.466862) (xy 35.319262 -29.503349) (xy 35.267356 -29.533316)
			(xy 35.211983 -29.556252) (xy 35.15409 -29.571765) (xy 35.094668 -29.579588) (xy 35.034732 -29.579588)
			(xy 34.97531 -29.571765) (xy 34.917417 -29.556252) (xy 34.862044 -29.533316) (xy 34.810138 -29.503349)
			(xy 34.762588 -29.466862) (xy 34.720208 -29.424482) (xy 34.683721 -29.376932) (xy 34.653754 -29.325026)
			(xy 34.630818 -29.269653) (xy 34.615305 -29.21176) (xy 34.607482 -29.152338) (xy 34.606992 -29.12237)
			(xy 24.26081 -29.12237) (xy 25.515316 -30.376876) (xy 26.888948 -30.376876) (xy 26.889503 -30.34796)
			(xy 26.898222 -30.29079) (xy 26.915471 -30.235591) (xy 26.940856 -30.183629) (xy 26.973794 -30.136094)
			(xy 27.013531 -30.094077) (xy 27.036014 -30.075886) (xy 27.04482 -30.068277) (xy 27.055003 -30.047378)
			(xy 27.055572 -30.035754) (xy 27.055572 -29.955998) (xy 27.055029 -29.944366) (xy 27.044844 -29.923456)
			(xy 27.036014 -29.915866) (xy 27.013517 -29.897691) (xy 26.973782 -29.855668) (xy 26.940844 -29.80813)
			(xy 26.915458 -29.756166) (xy 26.898205 -29.700965) (xy 26.88948 -29.643793) (xy 26.888948 -29.614876)
			(xy 26.889434 -29.587625) (xy 26.89719 -29.533677) (xy 26.912545 -29.481382) (xy 26.935187 -29.431805)
			(xy 26.964653 -29.385955) (xy 27.000344 -29.344764) (xy 27.041535 -29.309073) (xy 27.087385 -29.279607)
			(xy 27.136962 -29.256965) (xy 27.189257 -29.24161) (xy 27.243205 -29.233854) (xy 27.297707 -29.233854)
			(xy 27.351655 -29.24161) (xy 27.40395 -29.256965) (xy 27.453527 -29.279607) (xy 27.499377 -29.309073)
			(xy 27.540568 -29.344764) (xy 27.576259 -29.385955) (xy 27.605725 -29.431805) (xy 27.628367 -29.481382)
			(xy 27.643722 -29.533677) (xy 27.651478 -29.587625) (xy 27.651964 -29.614876) (xy 27.651442 -29.643793)
			(xy 27.642716 -29.700965) (xy 27.625459 -29.756164) (xy 27.600069 -29.808126) (xy 27.567125 -29.85566)
			(xy 27.527384 -29.897676) (xy 27.504898 -29.915866) (xy 27.496116 -29.923497) (xy 27.485919 -29.94438)
			(xy 27.48534 -29.955998) (xy 27.48534 -30.035754) (xy 27.485848 -30.04739) (xy 27.496058 -30.0683)
			(xy 27.504898 -30.075886) (xy 27.527374 -30.094085) (xy 27.56711 -30.136103) (xy 27.60005 -30.183637)
			(xy 27.62544 -30.235596) (xy 27.642697 -30.290792) (xy 27.651428 -30.34796) (xy 27.651964 -30.376876)
			(xy 29.929074 -30.376876) (xy 29.929619 -30.34796) (xy 29.938339 -30.290789) (xy 29.955589 -30.235589)
			(xy 29.980976 -30.183627) (xy 30.013916 -30.136092) (xy 30.053655 -30.094076) (xy 30.07614 -30.075886)
			(xy 30.08495 -30.068282) (xy 30.09513 -30.047379) (xy 30.095698 -30.035754) (xy 30.095698 -29.955998)
			(xy 30.095147 -29.944368) (xy 30.084967 -29.923458) (xy 30.07614 -29.915866) (xy 30.053649 -29.897684)
			(xy 30.013912 -29.855664) (xy 29.980973 -29.808127) (xy 29.955585 -29.756164) (xy 29.938332 -29.700964)
			(xy 29.929606 -29.643793) (xy 29.929074 -29.614876) (xy 29.92956 -29.587625) (xy 29.937316 -29.533677)
			(xy 29.952671 -29.481382) (xy 29.975313 -29.431805) (xy 30.004779 -29.385955) (xy 30.04047 -29.344764)
			(xy 30.081661 -29.309073) (xy 30.127511 -29.279607) (xy 30.177088 -29.256965) (xy 30.229383 -29.24161)
			(xy 30.283331 -29.233854) (xy 30.337833 -29.233854) (xy 30.391781 -29.24161) (xy 30.444076 -29.256965)
			(xy 30.493653 -29.279607) (xy 30.539503 -29.309073) (xy 30.580694 -29.344764) (xy 30.616385 -29.385955)
			(xy 30.645851 -29.431805) (xy 30.668493 -29.481382) (xy 30.683848 -29.533677) (xy 30.691604 -29.587625)
			(xy 30.69209 -29.614876) (xy 30.691558 -29.643792) (xy 30.682832 -29.700963) (xy 30.665577 -29.756162)
			(xy 30.640188 -29.808124) (xy 30.607247 -29.855658) (xy 30.567508 -29.897675) (xy 30.545024 -29.915866)
			(xy 30.53623 -29.923485) (xy 30.526042 -29.944377) (xy 30.525466 -29.955998) (xy 30.525466 -30.035754)
			(xy 30.525965 -30.047392) (xy 30.53618 -30.068302) (xy 30.545024 -30.075886) (xy 30.567506 -30.094079)
			(xy 30.60724 -30.136099) (xy 30.640178 -30.183634) (xy 30.665567 -30.235594) (xy 30.682824 -30.290791)
			(xy 30.691554 -30.34796) (xy 30.69209 -30.376876) (xy 30.691604 -30.404127) (xy 30.683848 -30.458075)
			(xy 30.668493 -30.51037) (xy 30.645851 -30.559947) (xy 30.616385 -30.605797) (xy 30.580694 -30.646988)
			(xy 30.539503 -30.682679) (xy 30.493653 -30.712145) (xy 30.444076 -30.734787) (xy 30.391781 -30.750142)
			(xy 30.337833 -30.757898) (xy 30.283331 -30.757898) (xy 30.229383 -30.750142) (xy 30.177088 -30.734787)
			(xy 30.127511 -30.712145) (xy 30.081661 -30.682679) (xy 30.04047 -30.646988) (xy 30.004779 -30.605797)
			(xy 29.975313 -30.559947) (xy 29.952671 -30.51037) (xy 29.937316 -30.458075) (xy 29.92956 -30.404127)
			(xy 29.929074 -30.376876) (xy 27.651964 -30.376876) (xy 27.651478 -30.404127) (xy 27.643722 -30.458075)
			(xy 27.628367 -30.51037) (xy 27.605725 -30.559947) (xy 27.576259 -30.605797) (xy 27.540568 -30.646988)
			(xy 27.499377 -30.682679) (xy 27.453527 -30.712145) (xy 27.40395 -30.734787) (xy 27.351655 -30.750142)
			(xy 27.297707 -30.757898) (xy 27.243205 -30.757898) (xy 27.189257 -30.750142) (xy 27.136962 -30.734787)
			(xy 27.087385 -30.712145) (xy 27.041535 -30.682679) (xy 27.000344 -30.646988) (xy 26.964653 -30.605797)
			(xy 26.935187 -30.559947) (xy 26.912545 -30.51037) (xy 26.89719 -30.458075) (xy 26.889434 -30.404127)
			(xy 26.888948 -30.376876) (xy 25.515316 -30.376876) (xy 26.060908 -30.922468) (xy 32.752792 -30.922468)
			(xy 32.752792 -30.058868) (xy 32.753282 -30.0289) (xy 32.761105 -29.969478) (xy 32.776618 -29.911585)
			(xy 32.799554 -29.856212) (xy 32.829521 -29.804306) (xy 32.866008 -29.756756) (xy 32.908388 -29.714376)
			(xy 32.955938 -29.677889) (xy 33.007844 -29.647922) (xy 33.063217 -29.624986) (xy 33.12111 -29.609473)
			(xy 33.180532 -29.60165) (xy 33.240468 -29.60165) (xy 33.29989 -29.609473) (xy 33.357783 -29.624986)
			(xy 33.413156 -29.647922) (xy 33.465062 -29.677889) (xy 33.512612 -29.714376) (xy 33.554992 -29.756756)
			(xy 33.591479 -29.804306) (xy 33.621446 -29.856212) (xy 33.644382 -29.911585) (xy 33.659895 -29.969478)
			(xy 33.667718 -30.0289) (xy 33.668208 -30.058868) (xy 33.668208 -30.92069) (xy 47.489364 -30.92069)
			(xy 47.489364 -30.05709) (xy 47.489854 -30.027106) (xy 47.497682 -29.96765) (xy 47.513203 -29.909725)
			(xy 47.536152 -29.854321) (xy 47.566136 -29.802387) (xy 47.602642 -29.754811) (xy 47.645047 -29.712406)
			(xy 47.692623 -29.6759) (xy 47.744557 -29.645916) (xy 47.799961 -29.622967) (xy 47.857886 -29.607446)
			(xy 47.917342 -29.599618) (xy 47.97731 -29.599618) (xy 48.036766 -29.607446) (xy 48.094691 -29.622967)
			(xy 48.150095 -29.645916) (xy 48.202029 -29.6759) (xy 48.249605 -29.712406) (xy 48.29201 -29.754811)
			(xy 48.328516 -29.802387) (xy 48.3585 -29.854321) (xy 48.381449 -29.909725) (xy 48.39697 -29.96765)
			(xy 48.404798 -30.027106) (xy 48.405288 -30.05709) (xy 48.405288 -30.92069) (xy 48.404798 -30.950674)
			(xy 48.39697 -31.01013) (xy 48.381449 -31.068055) (xy 48.3585 -31.123459) (xy 48.328516 -31.175393)
			(xy 48.29201 -31.222969) (xy 48.249605 -31.265374) (xy 48.202029 -31.30188) (xy 48.150095 -31.331864)
			(xy 48.094691 -31.354813) (xy 48.036766 -31.370334) (xy 47.97731 -31.378162) (xy 47.917342 -31.378162)
			(xy 47.857886 -31.370334) (xy 47.799961 -31.354813) (xy 47.744557 -31.331864) (xy 47.692623 -31.30188)
			(xy 47.645047 -31.265374) (xy 47.602642 -31.222969) (xy 47.566136 -31.175393) (xy 47.536152 -31.123459)
			(xy 47.513203 -31.068055) (xy 47.497682 -31.01013) (xy 47.489854 -30.950674) (xy 47.489364 -30.92069)
			(xy 33.668208 -30.92069) (xy 33.668208 -30.922468) (xy 33.667718 -30.952436) (xy 33.659895 -31.011858)
			(xy 33.644382 -31.069751) (xy 33.621446 -31.125124) (xy 33.591479 -31.17703) (xy 33.554992 -31.22458)
			(xy 33.512612 -31.26696) (xy 33.465062 -31.303447) (xy 33.413156 -31.333414) (xy 33.357783 -31.35635)
			(xy 33.29989 -31.371863) (xy 33.240468 -31.379686) (xy 33.180532 -31.379686) (xy 33.12111 -31.371863)
			(xy 33.063217 -31.35635) (xy 33.007844 -31.333414) (xy 32.955938 -31.303447) (xy 32.908388 -31.26696)
			(xy 32.866008 -31.22458) (xy 32.829521 -31.17703) (xy 32.799554 -31.125124) (xy 32.776618 -31.069751)
			(xy 32.761105 -31.011858) (xy 32.753282 -30.952436) (xy 32.752792 -30.922468) (xy 26.060908 -30.922468)
			(xy 26.706322 -31.567882) (xy 26.998674 -31.567882) (xy 27.002745 -31.51226) (xy 27.014871 -31.457823)
			(xy 27.034794 -31.405732) (xy 27.06209 -31.357097) (xy 27.096176 -31.312954) (xy 27.136325 -31.274245)
			(xy 27.181683 -31.241794) (xy 27.231283 -31.216293) (xy 27.284067 -31.198286) (xy 27.33891 -31.188156)
			(xy 27.394644 -31.186119) (xy 27.450081 -31.192219) (xy 27.504038 -31.206325) (xy 27.555367 -31.228137)
			(xy 27.602973 -31.257191) (xy 27.645841 -31.292866) (xy 27.683058 -31.334403) (xy 27.713831 -31.380916)
			(xy 27.737503 -31.431413) (xy 27.753571 -31.48482) (xy 27.761691 -31.539996) (xy 27.7622 -31.567882)
			(xy 27.761691 -31.595768) (xy 27.753571 -31.650944) (xy 27.737503 -31.704351) (xy 27.730511 -31.719266)
			(xy 28.285438 -31.719266) (xy 28.289509 -31.663644) (xy 28.301635 -31.609207) (xy 28.321558 -31.557116)
			(xy 28.348854 -31.508481) (xy 28.38294 -31.464338) (xy 28.423089 -31.425629) (xy 28.468447 -31.393178)
			(xy 28.518047 -31.367677) (xy 28.570831 -31.34967) (xy 28.625674 -31.33954) (xy 28.681408 -31.337503)
			(xy 28.736845 -31.343603) (xy 28.790802 -31.357709) (xy 28.842131 -31.379521) (xy 28.889737 -31.408575)
			(xy 28.932605 -31.44425) (xy 28.969822 -31.485787) (xy 29.000595 -31.5323) (xy 29.024267 -31.582797)
			(xy 29.040335 -31.636204) (xy 29.044485 -31.664402) (xy 29.561026 -31.664402) (xy 29.565097 -31.60878)
			(xy 29.577223 -31.554343) (xy 29.597146 -31.502252) (xy 29.624442 -31.453617) (xy 29.658528 -31.409474)
			(xy 29.698677 -31.370765) (xy 29.744035 -31.338314) (xy 29.793635 -31.312813) (xy 29.846419 -31.294806)
			(xy 29.901262 -31.284676) (xy 29.956996 -31.282639) (xy 30.012433 -31.288739) (xy 30.06639 -31.302845)
			(xy 30.117719 -31.324657) (xy 30.165325 -31.353711) (xy 30.208193 -31.389386) (xy 30.24541 -31.430923)
			(xy 30.276183 -31.477436) (xy 30.299855 -31.527933) (xy 30.315923 -31.58134) (xy 30.324043 -31.636516)
			(xy 30.324552 -31.664402) (xy 30.324043 -31.692288) (xy 30.315923 -31.747464) (xy 30.306983 -31.777178)
			(xy 30.8262 -31.777178) (xy 30.830271 -31.721556) (xy 30.842397 -31.667119) (xy 30.86232 -31.615028)
			(xy 30.889616 -31.566393) (xy 30.923702 -31.52225) (xy 30.963851 -31.483541) (xy 31.009209 -31.45109)
			(xy 31.058809 -31.425589) (xy 31.111593 -31.407582) (xy 31.166436 -31.397452) (xy 31.22217 -31.395415)
			(xy 31.277607 -31.401515) (xy 31.331564 -31.415621) (xy 31.382893 -31.437433) (xy 31.430499 -31.466487)
			(xy 31.473367 -31.502162) (xy 31.510584 -31.543699) (xy 31.541357 -31.590212) (xy 31.565029 -31.640709)
			(xy 31.581097 -31.694116) (xy 31.589217 -31.749292) (xy 31.589726 -31.777178) (xy 31.589217 -31.805064)
			(xy 31.581097 -31.86024) (xy 31.565029 -31.913647) (xy 31.541357 -31.964144) (xy 31.510584 -32.010657)
			(xy 31.473367 -32.052194) (xy 31.430499 -32.087869) (xy 31.382893 -32.116923) (xy 31.331564 -32.138735)
			(xy 31.277607 -32.152841) (xy 31.22217 -32.158941) (xy 31.166436 -32.156904) (xy 31.111593 -32.146774)
			(xy 31.058809 -32.128767) (xy 31.009209 -32.103266) (xy 30.963851 -32.070815) (xy 30.923702 -32.032106)
			(xy 30.889616 -31.987963) (xy 30.86232 -31.939328) (xy 30.842397 -31.887237) (xy 30.830271 -31.8328)
			(xy 30.8262 -31.777178) (xy 30.306983 -31.777178) (xy 30.299855 -31.800871) (xy 30.276183 -31.851368)
			(xy 30.24541 -31.897881) (xy 30.208193 -31.939418) (xy 30.165325 -31.975093) (xy 30.117719 -32.004147)
			(xy 30.06639 -32.025959) (xy 30.012433 -32.040065) (xy 29.956996 -32.046165) (xy 29.901262 -32.044128)
			(xy 29.846419 -32.033998) (xy 29.793635 -32.015991) (xy 29.744035 -31.99049) (xy 29.698677 -31.958039)
			(xy 29.658528 -31.91933) (xy 29.624442 -31.875187) (xy 29.597146 -31.826552) (xy 29.577223 -31.774461)
			(xy 29.565097 -31.720024) (xy 29.561026 -31.664402) (xy 29.044485 -31.664402) (xy 29.048455 -31.69138)
			(xy 29.048964 -31.719266) (xy 29.048455 -31.747152) (xy 29.040335 -31.802328) (xy 29.024267 -31.855735)
			(xy 29.000595 -31.906232) (xy 28.969822 -31.952745) (xy 28.932605 -31.994282) (xy 28.889737 -32.029957)
			(xy 28.842131 -32.059011) (xy 28.790802 -32.080823) (xy 28.736845 -32.094929) (xy 28.681408 -32.101029)
			(xy 28.625674 -32.098992) (xy 28.570831 -32.088862) (xy 28.518047 -32.070855) (xy 28.468447 -32.045354)
			(xy 28.423089 -32.012903) (xy 28.38294 -31.974194) (xy 28.348854 -31.930051) (xy 28.321558 -31.881416)
			(xy 28.301635 -31.829325) (xy 28.289509 -31.774888) (xy 28.285438 -31.719266) (xy 27.730511 -31.719266)
			(xy 27.713831 -31.754848) (xy 27.683058 -31.801361) (xy 27.645841 -31.842898) (xy 27.602973 -31.878573)
			(xy 27.555367 -31.907627) (xy 27.504038 -31.929439) (xy 27.450081 -31.943545) (xy 27.394644 -31.949645)
			(xy 27.33891 -31.947608) (xy 27.284067 -31.937478) (xy 27.231283 -31.919471) (xy 27.181683 -31.89397)
			(xy 27.136325 -31.861519) (xy 27.096176 -31.82281) (xy 27.06209 -31.778667) (xy 27.034794 -31.730032)
			(xy 27.014871 -31.677941) (xy 27.002745 -31.623504) (xy 26.998674 -31.567882) (xy 26.706322 -31.567882)
			(xy 26.76017 -31.62173) (xy 26.78328 -31.645509) (xy 26.824613 -31.697362) (xy 26.859882 -31.753516)
			(xy 26.888642 -31.813265) (xy 26.910533 -31.875859) (xy 26.92528 -31.940509) (xy 26.932696 -32.006404)
			(xy 26.933144 -32.03956) (xy 26.933144 -32.722312) (xy 34.606992 -32.722312) (xy 34.606992 -31.858712)
			(xy 34.607482 -31.828744) (xy 34.615305 -31.769322) (xy 34.630818 -31.711429) (xy 34.653754 -31.656056)
			(xy 34.683721 -31.60415) (xy 34.720208 -31.5566) (xy 34.762588 -31.51422) (xy 34.810138 -31.477733)
			(xy 34.862044 -31.447766) (xy 34.917417 -31.42483) (xy 34.97531 -31.409317) (xy 35.034732 -31.401494)
			(xy 35.094668 -31.401494) (xy 35.15409 -31.409317) (xy 35.211983 -31.42483) (xy 35.267356 -31.447766)
			(xy 35.319262 -31.477733) (xy 35.366812 -31.51422) (xy 35.409192 -31.5566) (xy 35.445679 -31.60415)
			(xy 35.475646 -31.656056) (xy 35.498582 -31.711429) (xy 35.514095 -31.769322) (xy 35.521918 -31.828744)
			(xy 35.522408 -31.858712) (xy 35.522408 -32.714184) (xy 44.847256 -32.714184) (xy 44.847256 -31.850584)
			(xy 44.847746 -31.8206) (xy 44.855574 -31.761144) (xy 44.871095 -31.703219) (xy 44.894044 -31.647815)
			(xy 44.924028 -31.595881) (xy 44.960534 -31.548305) (xy 45.002939 -31.5059) (xy 45.050515 -31.469394)
			(xy 45.102449 -31.43941) (xy 45.157853 -31.416461) (xy 45.215778 -31.40094) (xy 45.275234 -31.393112)
			(xy 45.335202 -31.393112) (xy 45.394658 -31.40094) (xy 45.452583 -31.416461) (xy 45.507987 -31.43941)
			(xy 45.559921 -31.469394) (xy 45.607497 -31.5059) (xy 45.649902 -31.548305) (xy 45.686408 -31.595881)
			(xy 45.716392 -31.647815) (xy 45.739341 -31.703219) (xy 45.754862 -31.761144) (xy 45.76269 -31.8206)
			(xy 45.76318 -31.850584) (xy 45.76318 -32.714184) (xy 45.76269 -32.744168) (xy 45.754862 -32.803624)
			(xy 45.739341 -32.861549) (xy 45.716392 -32.916953) (xy 45.686408 -32.968887) (xy 45.649902 -33.016463)
			(xy 45.607497 -33.058868) (xy 45.559921 -33.095374) (xy 45.507987 -33.125358) (xy 45.452583 -33.148307)
			(xy 45.394658 -33.163828) (xy 45.335202 -33.171656) (xy 45.275234 -33.171656) (xy 45.215778 -33.163828)
			(xy 45.157853 -33.148307) (xy 45.102449 -33.125358) (xy 45.050515 -33.095374) (xy 45.002939 -33.058868)
			(xy 44.960534 -33.016463) (xy 44.924028 -32.968887) (xy 44.894044 -32.916953) (xy 44.871095 -32.861549)
			(xy 44.855574 -32.803624) (xy 44.847746 -32.744168) (xy 44.847256 -32.714184) (xy 35.522408 -32.714184)
			(xy 35.522408 -32.722312) (xy 35.521918 -32.75228) (xy 35.514095 -32.811702) (xy 35.498582 -32.869595)
			(xy 35.475646 -32.924968) (xy 35.445679 -32.976874) (xy 35.409192 -33.024424) (xy 35.366812 -33.066804)
			(xy 35.319262 -33.103291) (xy 35.267356 -33.133258) (xy 35.211983 -33.156194) (xy 35.15409 -33.171707)
			(xy 35.094668 -33.17953) (xy 35.034732 -33.17953) (xy 34.97531 -33.171707) (xy 34.917417 -33.156194)
			(xy 34.862044 -33.133258) (xy 34.810138 -33.103291) (xy 34.762588 -33.066804) (xy 34.720208 -33.024424)
			(xy 34.683721 -32.976874) (xy 34.653754 -32.924968) (xy 34.630818 -32.869595) (xy 34.615305 -32.811702)
			(xy 34.607482 -32.75228) (xy 34.606992 -32.722312) (xy 26.933144 -32.722312) (xy 26.933144 -34.52241)
			(xy 32.752792 -34.52241) (xy 32.752792 -33.65881) (xy 32.753282 -33.628842) (xy 32.761105 -33.56942)
			(xy 32.776618 -33.511527) (xy 32.799554 -33.456154) (xy 32.829521 -33.404248) (xy 32.866008 -33.356698)
			(xy 32.908388 -33.314318) (xy 32.955938 -33.277831) (xy 33.007844 -33.247864) (xy 33.063217 -33.224928)
			(xy 33.12111 -33.209415) (xy 33.180532 -33.201592) (xy 33.240468 -33.201592) (xy 33.29989 -33.209415)
			(xy 33.357783 -33.224928) (xy 33.413156 -33.247864) (xy 33.465062 -33.277831) (xy 33.512612 -33.314318)
			(xy 33.554992 -33.356698) (xy 33.591479 -33.404248) (xy 33.621446 -33.456154) (xy 33.644382 -33.511527)
			(xy 33.659895 -33.56942) (xy 33.667718 -33.628842) (xy 33.668208 -33.65881) (xy 33.668208 -34.520886)
			(xy 47.489364 -34.520886) (xy 47.489364 -33.657286) (xy 47.489854 -33.627302) (xy 47.497682 -33.567846)
			(xy 47.513203 -33.509921) (xy 47.536152 -33.454517) (xy 47.566136 -33.402583) (xy 47.602642 -33.355007)
			(xy 47.645047 -33.312602) (xy 47.692623 -33.276096) (xy 47.744557 -33.246112) (xy 47.799961 -33.223163)
			(xy 47.857886 -33.207642) (xy 47.917342 -33.199814) (xy 47.97731 -33.199814) (xy 48.036766 -33.207642)
			(xy 48.094691 -33.223163) (xy 48.150095 -33.246112) (xy 48.202029 -33.276096) (xy 48.249605 -33.312602)
			(xy 48.29201 -33.355007) (xy 48.328516 -33.402583) (xy 48.3585 -33.454517) (xy 48.381449 -33.509921)
			(xy 48.39697 -33.567846) (xy 48.404798 -33.627302) (xy 48.405288 -33.657286) (xy 48.405288 -34.520886)
			(xy 48.404798 -34.55087) (xy 48.39697 -34.610326) (xy 48.381449 -34.668251) (xy 48.3585 -34.723655)
			(xy 48.328516 -34.775589) (xy 48.29201 -34.823165) (xy 48.249605 -34.86557) (xy 48.202029 -34.902076)
			(xy 48.150095 -34.93206) (xy 48.094691 -34.955009) (xy 48.036766 -34.97053) (xy 47.97731 -34.978358)
			(xy 47.917342 -34.978358) (xy 47.857886 -34.97053) (xy 47.799961 -34.955009) (xy 47.744557 -34.93206)
			(xy 47.692623 -34.902076) (xy 47.645047 -34.86557) (xy 47.602642 -34.823165) (xy 47.566136 -34.775589)
			(xy 47.536152 -34.723655) (xy 47.513203 -34.668251) (xy 47.497682 -34.610326) (xy 47.489854 -34.55087)
			(xy 47.489364 -34.520886) (xy 33.668208 -34.520886) (xy 33.668208 -34.52241) (xy 33.667718 -34.552378)
			(xy 33.659895 -34.6118) (xy 33.644382 -34.669693) (xy 33.621446 -34.725066) (xy 33.591479 -34.776972)
			(xy 33.554992 -34.824522) (xy 33.512612 -34.866902) (xy 33.465062 -34.903389) (xy 33.413156 -34.933356)
			(xy 33.357783 -34.956292) (xy 33.29989 -34.971805) (xy 33.240468 -34.979628) (xy 33.180532 -34.979628)
			(xy 33.12111 -34.971805) (xy 33.063217 -34.956292) (xy 33.007844 -34.933356) (xy 32.955938 -34.903389)
			(xy 32.908388 -34.866902) (xy 32.866008 -34.824522) (xy 32.829521 -34.776972) (xy 32.799554 -34.725066)
			(xy 32.776618 -34.669693) (xy 32.761105 -34.6118) (xy 32.753282 -34.552378) (xy 32.752792 -34.52241)
			(xy 26.933144 -34.52241) (xy 26.933144 -34.991802) (xy 26.933569 -35.001871) (xy 26.941289 -35.020471)
			(xy 26.94813 -35.02787) (xy 27.185112 -35.264852) (xy 29.902402 -35.264852) (xy 29.906473 -35.20923)
			(xy 29.918599 -35.154793) (xy 29.938522 -35.102702) (xy 29.965818 -35.054067) (xy 29.999904 -35.009924)
			(xy 30.040053 -34.971215) (xy 30.085411 -34.938764) (xy 30.135011 -34.913263) (xy 30.187795 -34.895256)
			(xy 30.242638 -34.885126) (xy 30.298372 -34.883089) (xy 30.353809 -34.889189) (xy 30.407766 -34.903295)
			(xy 30.459095 -34.925107) (xy 30.506701 -34.954161) (xy 30.549569 -34.989836) (xy 30.586786 -35.031373)
			(xy 30.617559 -35.077886) (xy 30.641231 -35.128383) (xy 30.657299 -35.18179) (xy 30.665419 -35.236966)
			(xy 30.665928 -35.264852) (xy 30.665419 -35.292738) (xy 30.657299 -35.347914) (xy 30.641231 -35.401321)
			(xy 30.617559 -35.451818) (xy 30.586786 -35.498331) (xy 30.549569 -35.539868) (xy 30.506701 -35.575543)
			(xy 30.459095 -35.604597) (xy 30.407766 -35.626409) (xy 30.353809 -35.640515) (xy 30.298372 -35.646615)
			(xy 30.242638 -35.644578) (xy 30.187795 -35.634448) (xy 30.135011 -35.616441) (xy 30.085411 -35.59094)
			(xy 30.040053 -35.558489) (xy 29.999904 -35.51978) (xy 29.965818 -35.475637) (xy 29.938522 -35.427002)
			(xy 29.918599 -35.374911) (xy 29.906473 -35.320474) (xy 29.902402 -35.264852) (xy 27.185112 -35.264852)
			(xy 28.207208 -36.286948) (xy 31.200342 -36.286948) (xy 31.204413 -36.231326) (xy 31.216539 -36.176889)
			(xy 31.236462 -36.124798) (xy 31.263758 -36.076163) (xy 31.297844 -36.03202) (xy 31.337993 -35.993311)
			(xy 31.383351 -35.96086) (xy 31.432951 -35.935359) (xy 31.485735 -35.917352) (xy 31.540578 -35.907222)
			(xy 31.596312 -35.905185) (xy 31.651749 -35.911285) (xy 31.705706 -35.925391) (xy 31.757035 -35.947203)
			(xy 31.804641 -35.976257) (xy 31.847509 -36.011932) (xy 31.884726 -36.053469) (xy 31.915499 -36.099982)
			(xy 31.939171 -36.150479) (xy 31.955239 -36.203886) (xy 31.963359 -36.259062) (xy 31.963868 -36.286948)
			(xy 31.963359 -36.314834) (xy 31.955239 -36.37001) (xy 31.939171 -36.423417) (xy 31.915499 -36.473914)
			(xy 31.887954 -36.515548) (xy 33.014156 -36.515548) (xy 33.018227 -36.459926) (xy 33.030353 -36.405489)
			(xy 33.050276 -36.353398) (xy 33.077572 -36.304763) (xy 33.111658 -36.26062) (xy 33.151807 -36.221911)
			(xy 33.197165 -36.18946) (xy 33.246765 -36.163959) (xy 33.299549 -36.145952) (xy 33.354392 -36.135822)
			(xy 33.410126 -36.133785) (xy 33.465563 -36.139885) (xy 33.51952 -36.153991) (xy 33.570849 -36.175803)
			(xy 33.618455 -36.204857) (xy 33.661323 -36.240532) (xy 33.69854 -36.282069) (xy 33.729313 -36.328582)
			(xy 33.752985 -36.379079) (xy 33.769053 -36.432486) (xy 33.777173 -36.487662) (xy 33.777682 -36.515548)
			(xy 33.777173 -36.543434) (xy 33.769053 -36.59861) (xy 33.768596 -36.60013) (xy 37.998153 -36.60013)
			(xy 38.002158 -36.512222) (xy 38.014141 -36.425042) (xy 38.034001 -36.339313) (xy 38.061576 -36.255745)
			(xy 38.096635 -36.175031) (xy 38.138888 -36.097839) (xy 38.187986 -36.02481) (xy 38.243522 -35.956548)
			(xy 38.305034 -35.893618) (xy 38.372015 -35.836544) (xy 38.443908 -35.785796) (xy 38.520117 -35.741796)
			(xy 38.600012 -35.704909) (xy 38.682931 -35.67544) (xy 38.768186 -35.653633) (xy 38.85507 -35.639669)
			(xy 38.942864 -35.633663) (xy 39.030841 -35.635667) (xy 39.118271 -35.645662) (xy 39.20443 -35.663566)
			(xy 39.288604 -35.68923) (xy 39.370095 -35.722443) (xy 39.448229 -35.762929) (xy 39.522357 -35.810351)
			(xy 39.591865 -35.864318) (xy 39.605164 -35.876738) (xy 44.717206 -35.876738) (xy 44.721277 -35.821116)
			(xy 44.733403 -35.766679) (xy 44.753326 -35.714588) (xy 44.780622 -35.665953) (xy 44.814708 -35.62181)
			(xy 44.854857 -35.583101) (xy 44.900215 -35.55065) (xy 44.949815 -35.525149) (xy 45.002599 -35.507142)
			(xy 45.057442 -35.497012) (xy 45.113176 -35.494975) (xy 45.168613 -35.501075) (xy 45.22257 -35.515181)
			(xy 45.273899 -35.536993) (xy 45.321505 -35.566047) (xy 45.364373 -35.601722) (xy 45.40159 -35.643259)
			(xy 45.432363 -35.689772) (xy 45.456035 -35.740269) (xy 45.472103 -35.793676) (xy 45.480223 -35.848852)
			(xy 45.480732 -35.876738) (xy 48.788826 -35.876738) (xy 48.792897 -35.821116) (xy 48.805023 -35.766679)
			(xy 48.824946 -35.714588) (xy 48.852242 -35.665953) (xy 48.886328 -35.62181) (xy 48.926477 -35.583101)
			(xy 48.971835 -35.55065) (xy 49.021435 -35.525149) (xy 49.074219 -35.507142) (xy 49.129062 -35.497012)
			(xy 49.184796 -35.494975) (xy 49.240233 -35.501075) (xy 49.29419 -35.515181) (xy 49.345519 -35.536993)
			(xy 49.393125 -35.566047) (xy 49.435993 -35.601722) (xy 49.47321 -35.643259) (xy 49.503983 -35.689772)
			(xy 49.527655 -35.740269) (xy 49.543723 -35.793676) (xy 49.551843 -35.848852) (xy 49.552352 -35.876738)
			(xy 49.551843 -35.904624) (xy 49.543723 -35.9598) (xy 49.527655 -36.013207) (xy 49.503983 -36.063704)
			(xy 49.47321 -36.110217) (xy 49.435993 -36.151754) (xy 49.393125 -36.187429) (xy 49.345519 -36.216483)
			(xy 49.29419 -36.238295) (xy 49.240233 -36.252401) (xy 49.184796 -36.258501) (xy 49.129062 -36.256464)
			(xy 49.074219 -36.246334) (xy 49.021435 -36.228327) (xy 48.971835 -36.202826) (xy 48.926477 -36.170375)
			(xy 48.886328 -36.131666) (xy 48.852242 -36.087523) (xy 48.824946 -36.038888) (xy 48.805023 -35.986797)
			(xy 48.792897 -35.93236) (xy 48.788826 -35.876738) (xy 45.480732 -35.876738) (xy 45.480223 -35.904624)
			(xy 45.472103 -35.9598) (xy 45.456035 -36.013207) (xy 45.432363 -36.063704) (xy 45.40159 -36.110217)
			(xy 45.364373 -36.151754) (xy 45.321505 -36.187429) (xy 45.273899 -36.216483) (xy 45.22257 -36.238295)
			(xy 45.168613 -36.252401) (xy 45.113176 -36.258501) (xy 45.057442 -36.256464) (xy 45.002599 -36.246334)
			(xy 44.949815 -36.228327) (xy 44.900215 -36.202826) (xy 44.854857 -36.170375) (xy 44.814708 -36.131666)
			(xy 44.780622 -36.087523) (xy 44.753326 -36.038888) (xy 44.733403 -35.986797) (xy 44.721277 -35.93236)
			(xy 44.717206 -35.876738) (xy 39.605164 -35.876738) (xy 39.656179 -35.924383) (xy 39.714763 -35.990047)
			(xy 39.767134 -36.060766) (xy 39.812857 -36.135954) (xy 39.851554 -36.214989) (xy 39.882903 -36.297215)
			(xy 39.906645 -36.381951) (xy 39.922583 -36.468495) (xy 39.926369 -36.50996) (xy 46.613824 -36.50996)
			(xy 46.617895 -36.454338) (xy 46.630021 -36.399901) (xy 46.649944 -36.34781) (xy 46.67724 -36.299175)
			(xy 46.711326 -36.255032) (xy 46.751475 -36.216323) (xy 46.796833 -36.183872) (xy 46.846433 -36.158371)
			(xy 46.899217 -36.140364) (xy 46.95406 -36.130234) (xy 47.009794 -36.128197) (xy 47.065231 -36.134297)
			(xy 47.119188 -36.148403) (xy 47.170517 -36.170215) (xy 47.218123 -36.199269) (xy 47.260991 -36.234944)
			(xy 47.298208 -36.276481) (xy 47.328981 -36.322994) (xy 47.352653 -36.373491) (xy 47.368721 -36.426898)
			(xy 47.372646 -36.453572) (xy 49.928524 -36.453572) (xy 49.932595 -36.39795) (xy 49.944721 -36.343513)
			(xy 49.964644 -36.291422) (xy 49.99194 -36.242787) (xy 50.026026 -36.198644) (xy 50.066175 -36.159935)
			(xy 50.111533 -36.127484) (xy 50.161133 -36.101983) (xy 50.213917 -36.083976) (xy 50.26876 -36.073846)
			(xy 50.324494 -36.071809) (xy 50.379931 -36.077909) (xy 50.433888 -36.092015) (xy 50.485217 -36.113827)
			(xy 50.532823 -36.142881) (xy 50.575691 -36.178556) (xy 50.612908 -36.220093) (xy 50.643681 -36.266606)
			(xy 50.667353 -36.317103) (xy 50.683421 -36.37051) (xy 50.691541 -36.425686) (xy 50.69205 -36.453572)
			(xy 50.691541 -36.481458) (xy 50.683421 -36.536634) (xy 50.667353 -36.590041) (xy 50.643681 -36.640538)
			(xy 50.612908 -36.687051) (xy 50.575691 -36.728588) (xy 50.532823 -36.764263) (xy 50.485217 -36.793317)
			(xy 50.433888 -36.815129) (xy 50.379931 -36.829235) (xy 50.324494 -36.835335) (xy 50.26876 -36.833298)
			(xy 50.213917 -36.823168) (xy 50.161133 -36.805161) (xy 50.111533 -36.77966) (xy 50.066175 -36.747209)
			(xy 50.026026 -36.7085) (xy 49.99194 -36.664357) (xy 49.964644 -36.615722) (xy 49.944721 -36.563631)
			(xy 49.932595 -36.509194) (xy 49.928524 -36.453572) (xy 47.372646 -36.453572) (xy 47.376841 -36.482074)
			(xy 47.37735 -36.50996) (xy 47.376841 -36.537846) (xy 47.368721 -36.593022) (xy 47.352653 -36.646429)
			(xy 47.328981 -36.696926) (xy 47.298208 -36.743439) (xy 47.260991 -36.784976) (xy 47.218123 -36.820651)
			(xy 47.170517 -36.849705) (xy 47.119188 -36.871517) (xy 47.065231 -36.885623) (xy 47.009794 -36.891723)
			(xy 46.95406 -36.889686) (xy 46.899217 -36.879556) (xy 46.846433 -36.861549) (xy 46.796833 -36.836048)
			(xy 46.751475 -36.803597) (xy 46.711326 -36.764888) (xy 46.67724 -36.720745) (xy 46.649944 -36.67211)
			(xy 46.630021 -36.620019) (xy 46.617895 -36.565582) (xy 46.613824 -36.50996) (xy 39.926369 -36.50996)
			(xy 39.930585 -36.55613) (xy 39.931086 -36.60013) (xy 39.930585 -36.64413) (xy 39.922583 -36.731765)
			(xy 39.906645 -36.818309) (xy 39.882903 -36.903045) (xy 39.851554 -36.985271) (xy 39.812857 -37.064306)
			(xy 39.767134 -37.139494) (xy 39.714763 -37.210213) (xy 39.656179 -37.275877) (xy 39.591865 -37.335942)
			(xy 39.522357 -37.389909) (xy 39.448229 -37.437331) (xy 39.375223 -37.47516) (xy 43.759118 -37.47516)
			(xy 43.763189 -37.419538) (xy 43.775315 -37.365101) (xy 43.795238 -37.31301) (xy 43.822534 -37.264375)
			(xy 43.85662 -37.220232) (xy 43.896769 -37.181523) (xy 43.942127 -37.149072) (xy 43.991727 -37.123571)
			(xy 44.044511 -37.105564) (xy 44.099354 -37.095434) (xy 44.155088 -37.093397) (xy 44.210525 -37.099497)
			(xy 44.264482 -37.113603) (xy 44.315811 -37.135415) (xy 44.363417 -37.164469) (xy 44.406285 -37.200144)
			(xy 44.443502 -37.241681) (xy 44.474275 -37.288194) (xy 44.497947 -37.338691) (xy 44.514015 -37.392098)
			(xy 44.522135 -37.447274) (xy 44.522644 -37.47516) (xy 44.522135 -37.503046) (xy 44.514015 -37.558222)
			(xy 44.497947 -37.611629) (xy 44.474275 -37.662126) (xy 44.474122 -37.662358) (xy 45.948344 -37.662358)
			(xy 45.952415 -37.606736) (xy 45.964541 -37.552299) (xy 45.984464 -37.500208) (xy 46.01176 -37.451573)
			(xy 46.045846 -37.40743) (xy 46.085995 -37.368721) (xy 46.131353 -37.33627) (xy 46.180953 -37.310769)
			(xy 46.233737 -37.292762) (xy 46.28858 -37.282632) (xy 46.344314 -37.280595) (xy 46.399751 -37.286695)
			(xy 46.453708 -37.300801) (xy 46.505037 -37.322613) (xy 46.552643 -37.351667) (xy 46.595511 -37.387342)
			(xy 46.632728 -37.428879) (xy 46.663501 -37.475392) (xy 46.687173 -37.525889) (xy 46.703241 -37.579296)
			(xy 46.711361 -37.634472) (xy 46.71187 -37.662358) (xy 46.711361 -37.690244) (xy 46.703241 -37.74542)
			(xy 46.687173 -37.798827) (xy 46.663501 -37.849324) (xy 46.632728 -37.895837) (xy 46.595511 -37.937374)
			(xy 46.552643 -37.973049) (xy 46.505037 -38.002103) (xy 46.453708 -38.023915) (xy 46.399751 -38.038021)
			(xy 46.344314 -38.044121) (xy 46.28858 -38.042084) (xy 46.233737 -38.031954) (xy 46.180953 -38.013947)
			(xy 46.131353 -37.988446) (xy 46.085995 -37.955995) (xy 46.045846 -37.917286) (xy 46.01176 -37.873143)
			(xy 45.984464 -37.824508) (xy 45.964541 -37.772417) (xy 45.952415 -37.71798) (xy 45.948344 -37.662358)
			(xy 44.474122 -37.662358) (xy 44.443502 -37.708639) (xy 44.406285 -37.750176) (xy 44.363417 -37.785851)
			(xy 44.315811 -37.814905) (xy 44.264482 -37.836717) (xy 44.210525 -37.850823) (xy 44.155088 -37.856923)
			(xy 44.099354 -37.854886) (xy 44.044511 -37.844756) (xy 43.991727 -37.826749) (xy 43.942127 -37.801248)
			(xy 43.896769 -37.768797) (xy 43.85662 -37.730088) (xy 43.822534 -37.685945) (xy 43.795238 -37.63731)
			(xy 43.775315 -37.585219) (xy 43.763189 -37.530782) (xy 43.759118 -37.47516) (xy 39.375223 -37.47516)
			(xy 39.370095 -37.477817) (xy 39.288604 -37.51103) (xy 39.20443 -37.536694) (xy 39.118271 -37.554598)
			(xy 39.030841 -37.564593) (xy 38.942864 -37.566597) (xy 38.85507 -37.560591) (xy 38.768186 -37.546627)
			(xy 38.682931 -37.52482) (xy 38.600012 -37.495351) (xy 38.520117 -37.458464) (xy 38.443908 -37.414464)
			(xy 38.372015 -37.363716) (xy 38.305034 -37.306642) (xy 38.243522 -37.243712) (xy 38.187986 -37.17545)
			(xy 38.138888 -37.102421) (xy 38.096635 -37.025229) (xy 38.061576 -36.944515) (xy 38.034001 -36.860947)
			(xy 38.014141 -36.775218) (xy 38.002158 -36.688038) (xy 37.998153 -36.60013) (xy 33.768596 -36.60013)
			(xy 33.752985 -36.652017) (xy 33.729313 -36.702514) (xy 33.69854 -36.749027) (xy 33.661323 -36.790564)
			(xy 33.618455 -36.826239) (xy 33.570849 -36.855293) (xy 33.51952 -36.877105) (xy 33.465563 -36.891211)
			(xy 33.410126 -36.897311) (xy 33.354392 -36.895274) (xy 33.299549 -36.885144) (xy 33.246765 -36.867137)
			(xy 33.197165 -36.841636) (xy 33.151807 -36.809185) (xy 33.111658 -36.770476) (xy 33.077572 -36.726333)
			(xy 33.050276 -36.677698) (xy 33.030353 -36.625607) (xy 33.018227 -36.57117) (xy 33.014156 -36.515548)
			(xy 31.887954 -36.515548) (xy 31.884726 -36.520427) (xy 31.847509 -36.561964) (xy 31.804641 -36.597639)
			(xy 31.757035 -36.626693) (xy 31.705706 -36.648505) (xy 31.651749 -36.662611) (xy 31.596312 -36.668711)
			(xy 31.540578 -36.666674) (xy 31.485735 -36.656544) (xy 31.432951 -36.638537) (xy 31.383351 -36.613036)
			(xy 31.337993 -36.580585) (xy 31.297844 -36.541876) (xy 31.263758 -36.497733) (xy 31.236462 -36.449098)
			(xy 31.216539 -36.397007) (xy 31.204413 -36.34257) (xy 31.200342 -36.286948) (xy 28.207208 -36.286948)
			(xy 29.694378 -37.774118) (xy 31.464756 -37.774118) (xy 31.468827 -37.718496) (xy 31.480953 -37.664059)
			(xy 31.500876 -37.611968) (xy 31.528172 -37.563333) (xy 31.562258 -37.51919) (xy 31.602407 -37.480481)
			(xy 31.647765 -37.44803) (xy 31.697365 -37.422529) (xy 31.750149 -37.404522) (xy 31.804992 -37.394392)
			(xy 31.860726 -37.392355) (xy 31.916163 -37.398455) (xy 31.97012 -37.412561) (xy 32.021449 -37.434373)
			(xy 32.069055 -37.463427) (xy 32.111923 -37.499102) (xy 32.14914 -37.540639) (xy 32.179913 -37.587152)
			(xy 32.203585 -37.637649) (xy 32.219653 -37.691056) (xy 32.227773 -37.746232) (xy 32.228282 -37.774118)
			(xy 32.227773 -37.802004) (xy 32.219653 -37.85718) (xy 32.203585 -37.910587) (xy 32.179913 -37.961084)
			(xy 32.14914 -38.007597) (xy 32.111923 -38.049134) (xy 32.069055 -38.084809) (xy 32.021449 -38.113863)
			(xy 31.97012 -38.135675) (xy 31.916163 -38.149781) (xy 31.860726 -38.155881) (xy 31.804992 -38.153844)
			(xy 31.750149 -38.143714) (xy 31.697365 -38.125707) (xy 31.647765 -38.100206) (xy 31.602407 -38.067755)
			(xy 31.562258 -38.029046) (xy 31.528172 -37.984903) (xy 31.500876 -37.936268) (xy 31.480953 -37.884177)
			(xy 31.468827 -37.82974) (xy 31.464756 -37.774118) (xy 29.694378 -37.774118) (xy 30.650212 -38.729952)
			(xy 49.700897 -38.729952) (xy 49.700897 -38.675448) (xy 49.708655 -38.6215) (xy 49.724011 -38.569204)
			(xy 49.746654 -38.519627) (xy 49.776123 -38.473777) (xy 49.811817 -38.432587) (xy 49.85301 -38.396898)
			(xy 49.898864 -38.367434) (xy 49.948444 -38.344796) (xy 50.000741 -38.329446) (xy 50.05469 -38.321694)
			(xy 50.081942 -38.321234) (xy 50.110245 -38.321753) (xy 50.166233 -38.330098) (xy 50.220372 -38.346627)
			(xy 50.271474 -38.370977) (xy 50.318414 -38.402613) (xy 50.360162 -38.440841) (xy 50.395801 -38.48482)
			(xy 50.410618 -38.50894) (xy 50.418226 -38.520968) (xy 50.438843 -38.540569) (xy 50.464072 -38.553712)
			(xy 50.491951 -38.559372) (xy 50.520309 -38.557109) (xy 50.546937 -38.5471) (xy 50.569764 -38.530123)
			(xy 50.578766 -38.5191) (xy 50.596977 -38.496244) (xy 50.639135 -38.455779) (xy 50.686965 -38.422209)
			(xy 50.739352 -38.396319) (xy 50.795072 -38.378712) (xy 50.852824 -38.3698) (xy 50.882042 -38.36924)
			(xy 50.909295 -38.369633) (xy 50.963245 -38.377395) (xy 51.015541 -38.392756) (xy 51.065119 -38.415402)
			(xy 51.11097 -38.444873) (xy 51.15216 -38.480569) (xy 51.187852 -38.521764) (xy 51.217318 -38.567618)
			(xy 51.239959 -38.617198) (xy 51.255314 -38.669496) (xy 51.26307 -38.723447) (xy 51.26307 -38.777953)
			(xy 51.255314 -38.831904) (xy 51.239959 -38.884202) (xy 51.217318 -38.933782) (xy 51.187852 -38.979636)
			(xy 51.15216 -39.020831) (xy 51.11097 -39.056527) (xy 51.065119 -39.085998) (xy 51.015541 -39.108644)
			(xy 50.963245 -39.124005) (xy 50.909295 -39.131767) (xy 50.882042 -39.132256) (xy 50.853738 -39.131754)
			(xy 50.797749 -39.123407) (xy 50.743609 -39.106876) (xy 50.692508 -39.082523) (xy 50.645568 -39.050883)
			(xy 50.60382 -39.012653) (xy 50.568183 -38.968671) (xy 50.553366 -38.94455) (xy 50.545779 -38.932508)
			(xy 50.525157 -38.912908) (xy 50.499923 -38.899767) (xy 50.472041 -38.894109) (xy 50.44368 -38.896374)
			(xy 50.417049 -38.906386) (xy 50.394221 -38.923366) (xy 50.385218 -38.93439) (xy 50.367014 -38.957251)
			(xy 50.324855 -38.997717) (xy 50.277023 -39.031286) (xy 50.224635 -39.057176) (xy 50.168913 -39.074781)
			(xy 50.11116 -39.083691) (xy 50.081942 -39.08425) (xy 50.05469 -39.083706) (xy 50.000741 -39.075954)
			(xy 49.948444 -39.060604) (xy 49.898864 -39.037966) (xy 49.85301 -39.008502) (xy 49.811817 -38.972813)
			(xy 49.776123 -38.931623) (xy 49.746654 -38.885773) (xy 49.724011 -38.836196) (xy 49.708655 -38.7839)
			(xy 49.700897 -38.729952) (xy 30.650212 -38.729952) (xy 31.89224 -39.97198) (xy 51.895754 -39.97198)
			(xy 51.899825 -39.916358) (xy 51.911951 -39.861921) (xy 51.931874 -39.80983) (xy 51.95917 -39.761195)
			(xy 51.993256 -39.717052) (xy 52.033405 -39.678343) (xy 52.078763 -39.645892) (xy 52.128363 -39.620391)
			(xy 52.181147 -39.602384) (xy 52.23599 -39.592254) (xy 52.291724 -39.590217) (xy 52.347161 -39.596317)
			(xy 52.401118 -39.610423) (xy 52.452447 -39.632235) (xy 52.500053 -39.661289) (xy 52.542921 -39.696964)
			(xy 52.580138 -39.738501) (xy 52.610911 -39.785014) (xy 52.634583 -39.835511) (xy 52.650651 -39.888918)
			(xy 52.658771 -39.944094) (xy 52.65928 -39.97198) (xy 52.658771 -39.999866) (xy 52.650651 -40.055042)
			(xy 52.634583 -40.108449) (xy 52.610911 -40.158946) (xy 52.580138 -40.205459) (xy 52.542921 -40.246996)
			(xy 52.500053 -40.282671) (xy 52.452447 -40.311725) (xy 52.401118 -40.333537) (xy 52.347161 -40.347643)
			(xy 52.291724 -40.353743) (xy 52.23599 -40.351706) (xy 52.181147 -40.341576) (xy 52.128363 -40.323569)
			(xy 52.078763 -40.298068) (xy 52.033405 -40.265617) (xy 51.993256 -40.226908) (xy 51.95917 -40.182765)
			(xy 51.931874 -40.13413) (xy 51.911951 -40.082039) (xy 51.899825 -40.027602) (xy 51.895754 -39.97198)
			(xy 31.89224 -39.97198) (xy 33.189011 -41.268751) (xy 41.84395 -41.268751) (xy 41.84395 -41.214249)
			(xy 41.851706 -41.1603) (xy 41.86706 -41.108005) (xy 41.8897 -41.058427) (xy 41.919165 -41.012575)
			(xy 41.954854 -40.971383) (xy 41.996043 -40.935689) (xy 42.041892 -40.906219) (xy 42.091467 -40.883574)
			(xy 42.143761 -40.868214) (xy 42.197709 -40.860453) (xy 42.22496 -40.859964) (xy 42.2537 -40.860461)
			(xy 42.310528 -40.869091) (xy 42.365419 -40.886148) (xy 42.41713 -40.911246) (xy 42.464492 -40.943815)
			(xy 42.485818 -40.963088) (xy 42.492676 -40.969692) (xy 42.51071 -40.976804) (xy 42.59961 -40.976804)
			(xy 42.617644 -40.969692) (xy 42.624502 -40.963088) (xy 42.645853 -40.943845) (xy 42.693207 -40.911273)
			(xy 42.744913 -40.886174) (xy 42.799799 -40.869117) (xy 42.856622 -40.860488) (xy 42.88536 -40.859964)
			(xy 42.912613 -40.860481) (xy 42.966564 -40.868232) (xy 43.018863 -40.883584) (xy 43.068444 -40.906222)
			(xy 43.114299 -40.935687) (xy 43.155494 -40.971378) (xy 43.191189 -41.012569) (xy 43.220658 -41.05842)
			(xy 43.243302 -41.108) (xy 43.258659 -41.160297) (xy 43.266417 -41.214247) (xy 43.266417 -41.268753)
			(xy 43.258659 -41.322703) (xy 43.243302 -41.375) (xy 43.220658 -41.42458) (xy 43.191189 -41.470431)
			(xy 43.155494 -41.511622) (xy 43.114299 -41.547313) (xy 43.068444 -41.576778) (xy 43.018863 -41.599416)
			(xy 42.966564 -41.614768) (xy 42.912613 -41.622519) (xy 42.88536 -41.62298) (xy 42.856621 -41.622459)
			(xy 42.799795 -41.613833) (xy 42.744905 -41.596781) (xy 42.693193 -41.571689) (xy 42.64583 -41.539126)
			(xy 42.624502 -41.519856) (xy 42.617644 -41.513252) (xy 42.59961 -41.50614) (xy 42.51071 -41.50614)
			(xy 42.492676 -41.513252) (xy 42.485818 -41.519856) (xy 42.464506 -41.539145) (xy 42.41714 -41.571709)
			(xy 42.365425 -41.596798) (xy 42.310531 -41.613844) (xy 42.2537 -41.622462) (xy 42.22496 -41.62298)
			(xy 42.197709 -41.622547) (xy 42.143761 -41.614786) (xy 42.091467 -41.599426) (xy 42.041892 -41.576781)
			(xy 41.996043 -41.547311) (xy 41.954854 -41.511617) (xy 41.919165 -41.470425) (xy 41.8897 -41.424573)
			(xy 41.86706 -41.374995) (xy 41.851706 -41.3227) (xy 41.84395 -41.268751) (xy 33.189011 -41.268751)
			(xy 35.225482 -43.305222) (xy 44.307252 -43.305222) (xy 44.307718 -43.277852) (xy 44.315534 -43.223672)
			(xy 44.331022 -43.171168) (xy 44.353864 -43.121422) (xy 44.38359 -43.075455) (xy 44.401232 -43.054524)
			(xy 44.401486 -43.05427) (xy 44.407048 -43.047166) (xy 44.41331 -43.030263) (xy 44.413678 -43.02125)
			(xy 44.413678 -42.954194) (xy 44.413329 -42.945176) (xy 44.407076 -42.928259) (xy 44.401486 -42.921174)
			(xy 44.401232 -42.921174) (xy 44.401232 -42.92092) (xy 44.383594 -42.899987) (xy 44.353881 -42.854015)
			(xy 44.331044 -42.804268) (xy 44.315553 -42.751767) (xy 44.307725 -42.697591) (xy 44.307252 -42.670222)
			(xy 44.307802 -42.641484) (xy 44.31642 -42.584659) (xy 44.333465 -42.529769) (xy 44.35855 -42.478057)
			(xy 44.391109 -42.430692) (xy 44.410376 -42.409364) (xy 44.41698 -42.402506) (xy 44.424092 -42.384472)
			(xy 44.424092 -42.295572) (xy 44.41698 -42.277538) (xy 44.410376 -42.27068) (xy 44.391129 -42.249333)
			(xy 44.358567 -42.201973) (xy 44.333478 -42.150264) (xy 44.316428 -42.095377) (xy 44.307805 -42.038553)
			(xy 44.307802 -41.981079) (xy 44.316421 -41.924255) (xy 44.333466 -41.869366) (xy 44.358551 -41.817655)
			(xy 44.391109 -41.770292) (xy 44.410376 -41.748964) (xy 44.41698 -41.742106) (xy 44.424092 -41.724072)
			(xy 44.424092 -41.635172) (xy 44.41698 -41.617138) (xy 44.410376 -41.61028) (xy 44.391122 -41.588938)
			(xy 44.358552 -41.541581) (xy 44.333456 -41.489873) (xy 44.316401 -41.434985) (xy 44.307775 -41.37816)
			(xy 44.307252 -41.349422) (xy 44.307738 -41.322171) (xy 44.315494 -41.268223) (xy 44.330849 -41.215928)
			(xy 44.353491 -41.166351) (xy 44.382957 -41.120501) (xy 44.418648 -41.07931) (xy 44.459839 -41.043619)
			(xy 44.505689 -41.014153) (xy 44.555266 -40.991511) (xy 44.607561 -40.976156) (xy 44.661509 -40.9684)
			(xy 44.716011 -40.9684) (xy 44.739132 -40.971724) (xy 52.594 -40.971724) (xy 52.598071 -40.916102)
			(xy 52.610197 -40.861665) (xy 52.63012 -40.809574) (xy 52.657416 -40.760939) (xy 52.691502 -40.716796)
			(xy 52.731651 -40.678087) (xy 52.777009 -40.645636) (xy 52.826609 -40.620135) (xy 52.879393 -40.602128)
			(xy 52.934236 -40.591998) (xy 52.98997 -40.589961) (xy 53.045407 -40.596061) (xy 53.099364 -40.610167)
			(xy 53.150693 -40.631979) (xy 53.198299 -40.661033) (xy 53.241167 -40.696708) (xy 53.278384 -40.738245)
			(xy 53.309157 -40.784758) (xy 53.332829 -40.835255) (xy 53.348897 -40.888662) (xy 53.357017 -40.943838)
			(xy 53.357526 -40.971724) (xy 53.357017 -40.99961) (xy 53.348897 -41.054786) (xy 53.332829 -41.108193)
			(xy 53.309157 -41.15869) (xy 53.278384 -41.205203) (xy 53.241167 -41.24674) (xy 53.198299 -41.282415)
			(xy 53.150693 -41.311469) (xy 53.099364 -41.333281) (xy 53.045407 -41.347387) (xy 52.98997 -41.353487)
			(xy 52.934236 -41.35145) (xy 52.879393 -41.34132) (xy 52.826609 -41.323313) (xy 52.777009 -41.297812)
			(xy 52.731651 -41.265361) (xy 52.691502 -41.226652) (xy 52.657416 -41.182509) (xy 52.63012 -41.133874)
			(xy 52.610197 -41.081783) (xy 52.598071 -41.027346) (xy 52.594 -40.971724) (xy 44.739132 -40.971724)
			(xy 44.769959 -40.976156) (xy 44.822254 -40.991511) (xy 44.871831 -41.014153) (xy 44.917681 -41.043619)
			(xy 44.958872 -41.07931) (xy 44.994563 -41.120501) (xy 45.024029 -41.166351) (xy 45.046671 -41.215928)
			(xy 45.062026 -41.268223) (xy 45.069782 -41.322171) (xy 45.070268 -41.349422) (xy 45.069739 -41.37816)
			(xy 45.061115 -41.434987) (xy 45.044065 -41.489877) (xy 45.018975 -41.541589) (xy 44.986413 -41.588952)
			(xy 44.967144 -41.61028) (xy 44.96054 -41.617138) (xy 44.953428 -41.635172) (xy 44.953428 -41.724072)
			(xy 44.96054 -41.742106) (xy 44.967144 -41.748964) (xy 44.986438 -41.770271) (xy 45.019005 -41.817636)
			(xy 45.044098 -41.869351) (xy 45.061148 -41.924245) (xy 45.069769 -41.981076) (xy 45.069767 -42.038556)
			(xy 45.06114 -42.095386) (xy 45.044086 -42.150279) (xy 45.018989 -42.201992) (xy 44.986418 -42.249354)
			(xy 44.967144 -42.27068) (xy 44.96054 -42.277538) (xy 44.953428 -42.295572) (xy 44.953428 -42.384472)
			(xy 44.96054 -42.402506) (xy 44.967144 -42.409364) (xy 44.986422 -42.430685) (xy 45.018988 -42.478048)
			(xy 45.044079 -42.529761) (xy 45.061128 -42.584654) (xy 45.069749 -42.641482) (xy 45.070268 -42.670222)
			(xy 45.069823 -42.697593) (xy 45.062001 -42.751773) (xy 45.046508 -42.804277) (xy 45.025951 -42.849038)
			(xy 46.891954 -42.849038) (xy 46.896025 -42.793416) (xy 46.908151 -42.738979) (xy 46.928074 -42.686888)
			(xy 46.95537 -42.638253) (xy 46.989456 -42.59411) (xy 47.029605 -42.555401) (xy 47.074963 -42.52295)
			(xy 47.124563 -42.497449) (xy 47.177347 -42.479442) (xy 47.23219 -42.469312) (xy 47.287924 -42.467275)
			(xy 47.343361 -42.473375) (xy 47.397318 -42.487481) (xy 47.448647 -42.509293) (xy 47.496253 -42.538347)
			(xy 47.539121 -42.574022) (xy 47.576338 -42.615559) (xy 47.607111 -42.662072) (xy 47.630783 -42.712569)
			(xy 47.646851 -42.765976) (xy 47.654971 -42.821152) (xy 47.655332 -42.84091) (xy 52.93309 -42.84091)
			(xy 52.937161 -42.785288) (xy 52.949287 -42.730851) (xy 52.96921 -42.67876) (xy 52.996506 -42.630125)
			(xy 53.030592 -42.585982) (xy 53.070741 -42.547273) (xy 53.116099 -42.514822) (xy 53.165699 -42.489321)
			(xy 53.218483 -42.471314) (xy 53.273326 -42.461184) (xy 53.32906 -42.459147) (xy 53.384497 -42.465247)
			(xy 53.438454 -42.479353) (xy 53.489783 -42.501165) (xy 53.537389 -42.530219) (xy 53.580257 -42.565894)
			(xy 53.617474 -42.607431) (xy 53.648247 -42.653944) (xy 53.671919 -42.704441) (xy 53.687987 -42.757848)
			(xy 53.696107 -42.813024) (xy 53.696616 -42.84091) (xy 53.696107 -42.868796) (xy 53.687987 -42.923972)
			(xy 53.671919 -42.977379) (xy 53.648247 -43.027876) (xy 53.617474 -43.074389) (xy 53.580257 -43.115926)
			(xy 53.537389 -43.151601) (xy 53.489783 -43.180655) (xy 53.438454 -43.202467) (xy 53.384497 -43.216573)
			(xy 53.32906 -43.222673) (xy 53.273326 -43.220636) (xy 53.218483 -43.210506) (xy 53.165699 -43.192499)
			(xy 53.116099 -43.166998) (xy 53.070741 -43.134547) (xy 53.030592 -43.095838) (xy 52.996506 -43.051695)
			(xy 52.96921 -43.00306) (xy 52.949287 -42.950969) (xy 52.937161 -42.896532) (xy 52.93309 -42.84091)
			(xy 47.655332 -42.84091) (xy 47.65548 -42.849038) (xy 47.654971 -42.876924) (xy 47.646851 -42.9321)
			(xy 47.630783 -42.985507) (xy 47.607111 -43.036004) (xy 47.576338 -43.082517) (xy 47.539121 -43.124054)
			(xy 47.496253 -43.159729) (xy 47.448647 -43.188783) (xy 47.397318 -43.210595) (xy 47.343361 -43.224701)
			(xy 47.287924 -43.230801) (xy 47.23219 -43.228764) (xy 47.177347 -43.218634) (xy 47.124563 -43.200627)
			(xy 47.074963 -43.175126) (xy 47.029605 -43.142675) (xy 46.989456 -43.103966) (xy 46.95537 -43.059823)
			(xy 46.928074 -43.011188) (xy 46.908151 -42.959097) (xy 46.896025 -42.90466) (xy 46.891954 -42.849038)
			(xy 45.025951 -42.849038) (xy 45.023661 -42.854024) (xy 44.993932 -42.899989) (xy 44.976288 -42.92092)
			(xy 44.976034 -42.921174) (xy 44.970444 -42.928258) (xy 44.964201 -42.945177) (xy 44.963842 -42.954194)
			(xy 44.963842 -43.02125) (xy 44.964214 -43.030266) (xy 44.97045 -43.047183) (xy 44.976034 -43.05427)
			(xy 44.976288 -43.05427) (xy 44.976288 -43.054524) (xy 44.993903 -43.075475) (xy 45.023619 -43.121443)
			(xy 45.04646 -43.171185) (xy 45.061956 -43.223682) (xy 45.069791 -43.277854) (xy 45.070268 -43.305222)
			(xy 45.069782 -43.332473) (xy 45.062026 -43.386421) (xy 45.046671 -43.438716) (xy 45.024029 -43.488293)
			(xy 44.994563 -43.534143) (xy 44.958872 -43.575334) (xy 44.917681 -43.611025) (xy 44.871831 -43.640491)
			(xy 44.822254 -43.663133) (xy 44.769959 -43.678488) (xy 44.716011 -43.686244) (xy 44.661509 -43.686244)
			(xy 44.607561 -43.678488) (xy 44.555266 -43.663133) (xy 44.505689 -43.640491) (xy 44.459839 -43.611025)
			(xy 44.418648 -43.575334) (xy 44.382957 -43.534143) (xy 44.353491 -43.488293) (xy 44.330849 -43.438716)
			(xy 44.315494 -43.386421) (xy 44.307738 -43.332473) (xy 44.307252 -43.305222) (xy 35.225482 -43.305222)
			(xy 35.65652 -43.73626) (xy 46.213012 -43.73626) (xy 46.217083 -43.680638) (xy 46.229209 -43.626201)
			(xy 46.249132 -43.57411) (xy 46.276428 -43.525475) (xy 46.310514 -43.481332) (xy 46.350663 -43.442623)
			(xy 46.396021 -43.410172) (xy 46.445621 -43.384671) (xy 46.498405 -43.366664) (xy 46.553248 -43.356534)
			(xy 46.608982 -43.354497) (xy 46.664419 -43.360597) (xy 46.718376 -43.374703) (xy 46.769705 -43.396515)
			(xy 46.817311 -43.425569) (xy 46.860179 -43.461244) (xy 46.897396 -43.502781) (xy 46.928169 -43.549294)
			(xy 46.951841 -43.599791) (xy 46.967909 -43.653198) (xy 46.976029 -43.708374) (xy 46.976538 -43.73626)
			(xy 46.976029 -43.764146) (xy 46.967909 -43.819322) (xy 46.9566 -43.85691) (xy 50.719734 -43.85691)
			(xy 50.723805 -43.801288) (xy 50.735931 -43.746851) (xy 50.755854 -43.69476) (xy 50.78315 -43.646125)
			(xy 50.817236 -43.601982) (xy 50.857385 -43.563273) (xy 50.902743 -43.530822) (xy 50.952343 -43.505321)
			(xy 51.005127 -43.487314) (xy 51.05997 -43.477184) (xy 51.115704 -43.475147) (xy 51.171141 -43.481247)
			(xy 51.225098 -43.495353) (xy 51.276427 -43.517165) (xy 51.324033 -43.546219) (xy 51.366901 -43.581894)
			(xy 51.404118 -43.623431) (xy 51.434891 -43.669944) (xy 51.458563 -43.720441) (xy 51.474631 -43.773848)
			(xy 51.482751 -43.829024) (xy 51.48326 -43.85691) (xy 51.482751 -43.884796) (xy 51.474631 -43.939972)
			(xy 51.458563 -43.993379) (xy 51.434891 -44.043876) (xy 51.404118 -44.090389) (xy 51.366901 -44.131926)
			(xy 51.324033 -44.167601) (xy 51.276427 -44.196655) (xy 51.225098 -44.218467) (xy 51.171141 -44.232573)
			(xy 51.115704 -44.238673) (xy 51.05997 -44.236636) (xy 51.005127 -44.226506) (xy 50.952343 -44.208499)
			(xy 50.902743 -44.182998) (xy 50.857385 -44.150547) (xy 50.817236 -44.111838) (xy 50.78315 -44.067695)
			(xy 50.755854 -44.01906) (xy 50.735931 -43.966969) (xy 50.723805 -43.912532) (xy 50.719734 -43.85691)
			(xy 46.9566 -43.85691) (xy 46.951841 -43.872729) (xy 46.928169 -43.923226) (xy 46.897396 -43.969739)
			(xy 46.860179 -44.011276) (xy 46.817311 -44.046951) (xy 46.769705 -44.076005) (xy 46.718376 -44.097817)
			(xy 46.664419 -44.111923) (xy 46.608982 -44.118023) (xy 46.553248 -44.115986) (xy 46.498405 -44.105856)
			(xy 46.445621 -44.087849) (xy 46.396021 -44.062348) (xy 46.350663 -44.029897) (xy 46.310514 -43.991188)
			(xy 46.276428 -43.947045) (xy 46.249132 -43.89841) (xy 46.229209 -43.846319) (xy 46.217083 -43.791882)
			(xy 46.213012 -43.73626) (xy 35.65652 -43.73626) (xy 37.034724 -45.114464) (xy 46.065438 -45.114464)
			(xy 46.069509 -45.058842) (xy 46.081635 -45.004405) (xy 46.101558 -44.952314) (xy 46.128854 -44.903679)
			(xy 46.16294 -44.859536) (xy 46.203089 -44.820827) (xy 46.248447 -44.788376) (xy 46.298047 -44.762875)
			(xy 46.350831 -44.744868) (xy 46.405674 -44.734738) (xy 46.461408 -44.732701) (xy 46.516845 -44.738801)
			(xy 46.570802 -44.752907) (xy 46.622131 -44.774719) (xy 46.669737 -44.803773) (xy 46.712605 -44.839448)
			(xy 46.742587 -44.87291) (xy 52.93309 -44.87291) (xy 52.937161 -44.817288) (xy 52.949287 -44.762851)
			(xy 52.96921 -44.71076) (xy 52.996506 -44.662125) (xy 53.030592 -44.617982) (xy 53.070741 -44.579273)
			(xy 53.116099 -44.546822) (xy 53.165699 -44.521321) (xy 53.218483 -44.503314) (xy 53.273326 -44.493184)
			(xy 53.32906 -44.491147) (xy 53.384497 -44.497247) (xy 53.438454 -44.511353) (xy 53.489783 -44.533165)
			(xy 53.537389 -44.562219) (xy 53.580257 -44.597894) (xy 53.617474 -44.639431) (xy 53.648247 -44.685944)
			(xy 53.671919 -44.736441) (xy 53.687987 -44.789848) (xy 53.696107 -44.845024) (xy 53.696616 -44.87291)
			(xy 53.696107 -44.900796) (xy 53.687987 -44.955972) (xy 53.671919 -45.009379) (xy 53.648247 -45.059876)
			(xy 53.617474 -45.106389) (xy 53.580257 -45.147926) (xy 53.537389 -45.183601) (xy 53.489783 -45.212655)
			(xy 53.438454 -45.234467) (xy 53.384497 -45.248573) (xy 53.32906 -45.254673) (xy 53.273326 -45.252636)
			(xy 53.218483 -45.242506) (xy 53.165699 -45.224499) (xy 53.116099 -45.198998) (xy 53.070741 -45.166547)
			(xy 53.030592 -45.127838) (xy 52.996506 -45.083695) (xy 52.96921 -45.03506) (xy 52.949287 -44.982969)
			(xy 52.937161 -44.928532) (xy 52.93309 -44.87291) (xy 46.742587 -44.87291) (xy 46.749822 -44.880985)
			(xy 46.780595 -44.927498) (xy 46.804267 -44.977995) (xy 46.820335 -45.031402) (xy 46.828455 -45.086578)
			(xy 46.828964 -45.114464) (xy 46.828455 -45.14235) (xy 46.820335 -45.197526) (xy 46.804267 -45.250933)
			(xy 46.780595 -45.30143) (xy 46.749822 -45.347943) (xy 46.74418 -45.35424) (xy 50.703732 -45.35424)
			(xy 50.707803 -45.298618) (xy 50.719929 -45.244181) (xy 50.739852 -45.19209) (xy 50.767148 -45.143455)
			(xy 50.801234 -45.099312) (xy 50.841383 -45.060603) (xy 50.886741 -45.028152) (xy 50.936341 -45.002651)
			(xy 50.989125 -44.984644) (xy 51.043968 -44.974514) (xy 51.099702 -44.972477) (xy 51.155139 -44.978577)
			(xy 51.209096 -44.992683) (xy 51.260425 -45.014495) (xy 51.308031 -45.043549) (xy 51.350899 -45.079224)
			(xy 51.388116 -45.120761) (xy 51.418889 -45.167274) (xy 51.442561 -45.217771) (xy 51.458629 -45.271178)
			(xy 51.466749 -45.326354) (xy 51.467258 -45.35424) (xy 51.466749 -45.382126) (xy 51.458629 -45.437302)
			(xy 51.442561 -45.490709) (xy 51.418889 -45.541206) (xy 51.388116 -45.587719) (xy 51.350899 -45.629256)
			(xy 51.308031 -45.664931) (xy 51.260425 -45.693985) (xy 51.209096 -45.715797) (xy 51.155139 -45.729903)
			(xy 51.099702 -45.736003) (xy 51.043968 -45.733966) (xy 50.989125 -45.723836) (xy 50.936341 -45.705829)
			(xy 50.886741 -45.680328) (xy 50.841383 -45.647877) (xy 50.801234 -45.609168) (xy 50.767148 -45.565025)
			(xy 50.739852 -45.51639) (xy 50.719929 -45.464299) (xy 50.707803 -45.409862) (xy 50.703732 -45.35424)
			(xy 46.74418 -45.35424) (xy 46.712605 -45.38948) (xy 46.669737 -45.425155) (xy 46.622131 -45.454209)
			(xy 46.570802 -45.476021) (xy 46.516845 -45.490127) (xy 46.461408 -45.496227) (xy 46.405674 -45.49419)
			(xy 46.350831 -45.48406) (xy 46.298047 -45.466053) (xy 46.248447 -45.440552) (xy 46.203089 -45.408101)
			(xy 46.16294 -45.369392) (xy 46.128854 -45.325249) (xy 46.101558 -45.276614) (xy 46.081635 -45.224523)
			(xy 46.069509 -45.170086) (xy 46.065438 -45.114464) (xy 37.034724 -45.114464) (xy 37.59327 -45.67301)
			(xy 37.61605 -45.696412) (xy 37.656772 -45.747473) (xy 37.691521 -45.802773) (xy 37.719859 -45.861616)
			(xy 37.741431 -45.923261) (xy 37.755966 -45.986934) (xy 37.763279 -46.051835) (xy 37.763674 -46.082204)
			(xy 44.05249 -46.082204) (xy 44.052959 -46.054951) (xy 44.060715 -46.001001) (xy 44.076071 -45.948703)
			(xy 44.098713 -45.899123) (xy 44.12818 -45.85327) (xy 44.163873 -45.812077) (xy 44.205065 -45.776384)
			(xy 44.250918 -45.746916) (xy 44.300497 -45.724273) (xy 44.352795 -45.708917) (xy 44.406745 -45.701159)
			(xy 44.433998 -45.700696) (xy 44.460901 -45.70116) (xy 44.51417 -45.708731) (xy 44.565849 -45.72371)
			(xy 44.61491 -45.7458) (xy 44.660383 -45.774562) (xy 44.701364 -45.809427) (xy 44.737042 -45.849702)
			(xy 44.75226 -45.871892) (xy 44.759372 -45.882814) (xy 44.782232 -45.894752) (xy 44.8945 -45.89272)
			(xy 44.916852 -45.879766) (xy 44.92371 -45.86859) (xy 44.938638 -45.844993) (xy 44.974316 -45.802041)
			(xy 45.015873 -45.764748) (xy 45.062422 -45.73391) (xy 45.112969 -45.710186) (xy 45.166433 -45.694082)
			(xy 45.221674 -45.685943) (xy 45.249592 -45.685456) (xy 45.276585 -45.685922) (xy 45.330033 -45.693527)
			(xy 45.381876 -45.708586) (xy 45.431081 -45.730799) (xy 45.476665 -45.759722) (xy 45.497496 -45.776896)
			(xy 45.505624 -45.784008) (xy 45.526198 -45.790104) (xy 45.611542 -45.779182) (xy 45.622082 -45.777389)
			(xy 45.640367 -45.766348) (xy 45.646848 -45.757846) (xy 45.662178 -45.736598) (xy 45.697769 -45.698145)
			(xy 45.73829 -45.664928) (xy 45.782977 -45.637572) (xy 45.830989 -45.616591) (xy 45.881421 -45.602382)
			(xy 45.933324 -45.595211) (xy 45.959522 -45.594778) (xy 45.986771 -45.595294) (xy 46.040714 -45.603053)
			(xy 46.093005 -45.618409) (xy 46.142577 -45.64105) (xy 46.188423 -45.670516) (xy 46.229609 -45.706206)
			(xy 46.265297 -45.747395) (xy 46.29476 -45.793242) (xy 46.317399 -45.842816) (xy 46.332752 -45.895107)
			(xy 46.340508 -45.949051) (xy 46.340508 -46.003549) (xy 46.332752 -46.057493) (xy 46.317399 -46.109784)
			(xy 46.29476 -46.159358) (xy 46.265297 -46.205205) (xy 46.229609 -46.246394) (xy 46.188423 -46.282084)
			(xy 46.142577 -46.31155) (xy 46.093005 -46.334191) (xy 46.040714 -46.349547) (xy 45.986771 -46.357306)
			(xy 45.959522 -46.357794) (xy 45.93253 -46.357308) (xy 45.879083 -46.349706) (xy 45.82724 -46.334651)
			(xy 45.778035 -46.312443) (xy 45.73245 -46.283525) (xy 45.711618 -46.266354) (xy 45.70349 -46.259242)
			(xy 45.682916 -46.253146) (xy 45.597572 -46.264068) (xy 45.587026 -46.265836) (xy 45.568745 -46.276896)
			(xy 45.562266 -46.285404) (xy 45.544654 -46.309705) (xy 45.503058 -46.352964) (xy 45.479462 -46.37151)
			(xy 45.471588 -46.377352) (xy 45.461174 -46.394878) (xy 45.447966 -46.485302) (xy 45.452792 -46.504606)
			(xy 45.458634 -46.51248) (xy 45.458634 -46.512734) (xy 45.476132 -46.537482) (xy 45.503937 -46.591333)
			(xy 45.522875 -46.648904) (xy 45.530078 -46.693836) (xy 50.676302 -46.693836) (xy 50.676788 -46.666585)
			(xy 50.684544 -46.612637) (xy 50.699899 -46.560342) (xy 50.722541 -46.510765) (xy 50.752007 -46.464915)
			(xy 50.787698 -46.423724) (xy 50.828889 -46.388033) (xy 50.874739 -46.358567) (xy 50.924316 -46.335925)
			(xy 50.976611 -46.32057) (xy 51.030559 -46.312814) (xy 51.085061 -46.312814) (xy 51.139009 -46.32057)
			(xy 51.191304 -46.335925) (xy 51.240881 -46.358567) (xy 51.286731 -46.388033) (xy 51.327922 -46.423724)
			(xy 51.363613 -46.464915) (xy 51.393079 -46.510765) (xy 51.415721 -46.560342) (xy 51.431076 -46.612637)
			(xy 51.438832 -46.666585) (xy 51.439318 -46.693836) (xy 51.438843 -46.720263) (xy 51.431534 -46.772611)
			(xy 51.417061 -46.823446) (xy 51.395702 -46.871793) (xy 51.382168 -46.894496) (xy 51.381914 -46.89475)
			(xy 51.376577 -46.904768) (xy 51.374321 -46.927318) (xy 51.377596 -46.938184) (xy 51.403758 -47.01286)
			(xy 51.408139 -47.023377) (xy 51.42423 -47.039465) (xy 51.434746 -47.043848) (xy 51.435 -47.043848)
			(xy 51.459499 -47.052944) (xy 51.505952 -47.076881) (xy 51.548706 -47.106932) (xy 51.586959 -47.142535)
			(xy 51.619998 -47.183025) (xy 51.647203 -47.227643) (xy 51.668066 -47.275556) (xy 51.682197 -47.325868)
			(xy 51.689331 -47.377637) (xy 51.689762 -47.403766) (xy 51.689276 -47.431017) (xy 51.687753 -47.441612)
			(xy 52.961792 -47.441612) (xy 52.965863 -47.38599) (xy 52.977989 -47.331553) (xy 52.997912 -47.279462)
			(xy 53.025208 -47.230827) (xy 53.059294 -47.186684) (xy 53.099443 -47.147975) (xy 53.144801 -47.115524)
			(xy 53.194401 -47.090023) (xy 53.247185 -47.072016) (xy 53.302028 -47.061886) (xy 53.357762 -47.059849)
			(xy 53.413199 -47.065949) (xy 53.467156 -47.080055) (xy 53.518485 -47.101867) (xy 53.566091 -47.130921)
			(xy 53.608959 -47.166596) (xy 53.646176 -47.208133) (xy 53.676949 -47.254646) (xy 53.700621 -47.305143)
			(xy 53.716689 -47.35855) (xy 53.724809 -47.413726) (xy 53.725318 -47.441612) (xy 53.724809 -47.469498)
			(xy 53.716689 -47.524674) (xy 53.700621 -47.578081) (xy 53.676949 -47.628578) (xy 53.646176 -47.675091)
			(xy 53.608959 -47.716628) (xy 53.566091 -47.752303) (xy 53.518485 -47.781357) (xy 53.467156 -47.803169)
			(xy 53.413199 -47.817275) (xy 53.357762 -47.823375) (xy 53.302028 -47.821338) (xy 53.247185 -47.811208)
			(xy 53.194401 -47.793201) (xy 53.144801 -47.7677) (xy 53.099443 -47.735249) (xy 53.059294 -47.69654)
			(xy 53.025208 -47.652397) (xy 52.997912 -47.603762) (xy 52.977989 -47.551671) (xy 52.965863 -47.497234)
			(xy 52.961792 -47.441612) (xy 51.687753 -47.441612) (xy 51.68152 -47.484965) (xy 51.666165 -47.53726)
			(xy 51.643523 -47.586837) (xy 51.614057 -47.632687) (xy 51.578366 -47.673878) (xy 51.537175 -47.709569)
			(xy 51.491325 -47.739035) (xy 51.441748 -47.761677) (xy 51.389453 -47.777032) (xy 51.335505 -47.784788)
			(xy 51.281003 -47.784788) (xy 51.227055 -47.777032) (xy 51.17476 -47.761677) (xy 51.125183 -47.739035)
			(xy 51.079333 -47.709569) (xy 51.038142 -47.673878) (xy 51.002451 -47.632687) (xy 50.972985 -47.586837)
			(xy 50.950343 -47.53726) (xy 50.934988 -47.484965) (xy 50.927232 -47.431017) (xy 50.926746 -47.403766)
			(xy 50.927213 -47.377338) (xy 50.934523 -47.32499) (xy 50.948998 -47.274155) (xy 50.97036 -47.225809)
			(xy 50.983896 -47.203106) (xy 50.98415 -47.202852) (xy 50.989485 -47.192834) (xy 50.991744 -47.170284)
			(xy 50.988468 -47.159418) (xy 50.962306 -47.084742) (xy 50.95794 -47.074217) (xy 50.941839 -47.058132)
			(xy 50.931318 -47.053754) (xy 50.931064 -47.053754) (xy 50.906558 -47.044677) (xy 50.860105 -47.020736)
			(xy 50.817353 -46.990681) (xy 50.779101 -46.955075) (xy 50.746064 -46.914583) (xy 50.71886 -46.869963)
			(xy 50.697998 -46.822048) (xy 50.683867 -46.771736) (xy 50.676733 -46.719966) (xy 50.676302 -46.693836)
			(xy 45.530078 -46.693836) (xy 45.532468 -46.708745) (xy 45.533056 -46.739048) (xy 45.532567 -46.766298)
			(xy 45.524805 -46.820243) (xy 45.509446 -46.872535) (xy 45.486803 -46.922109) (xy 45.457336 -46.967957)
			(xy 45.421646 -47.009146) (xy 45.380457 -47.044836) (xy 45.334609 -47.074303) (xy 45.285035 -47.096946)
			(xy 45.232743 -47.112305) (xy 45.178798 -47.120067) (xy 45.151548 -47.120556) (xy 45.125514 -47.120131)
			(xy 45.07393 -47.113038) (xy 45.023788 -47.099003) (xy 44.976018 -47.078287) (xy 44.931504 -47.051274)
			(xy 44.91101 -47.035212) (xy 44.903257 -47.029464) (xy 44.884843 -47.023727) (xy 44.875196 -47.024036)
			(xy 44.79544 -47.030386) (xy 44.77766 -47.039022) (xy 44.77131 -47.046388) (xy 44.753147 -47.066051)
			(xy 44.712235 -47.100572) (xy 44.666903 -47.129039) (xy 44.618038 -47.150893) (xy 44.566599 -47.165707)
			(xy 44.513595 -47.173189) (xy 44.48683 -47.173642) (xy 44.459581 -47.173094) (xy 44.405637 -47.165342)
			(xy 44.353346 -47.149993) (xy 44.303771 -47.127358) (xy 44.257922 -47.097898) (xy 44.216733 -47.062213)
			(xy 44.181041 -47.021029) (xy 44.151573 -46.975185) (xy 44.12893 -46.925614) (xy 44.113571 -46.873325)
			(xy 44.105811 -46.819383) (xy 44.105322 -46.792134) (xy 44.105841 -46.76336) (xy 44.114492 -46.706465)
			(xy 44.13159 -46.651514) (xy 44.156745 -46.599754) (xy 44.189387 -46.552358) (xy 44.2087 -46.531022)
			(xy 44.216066 -46.523148) (xy 44.223178 -46.503336) (xy 44.215812 -46.40707) (xy 44.205906 -46.388274)
			(xy 44.197524 -46.38167) (xy 44.17534 -46.363444) (xy 44.13613 -46.321509) (xy 44.103644 -46.274174)
			(xy 44.078615 -46.222506) (xy 44.061609 -46.167672) (xy 44.053008 -46.110909) (xy 44.05249 -46.082204)
			(xy 37.763674 -46.082204) (xy 37.763704 -46.08449) (xy 37.763704 -48.30699) (xy 50.553872 -48.30699)
			(xy 50.557943 -48.251368) (xy 50.570069 -48.196931) (xy 50.589992 -48.14484) (xy 50.617288 -48.096205)
			(xy 50.651374 -48.052062) (xy 50.691523 -48.013353) (xy 50.736881 -47.980902) (xy 50.786481 -47.955401)
			(xy 50.839265 -47.937394) (xy 50.894108 -47.927264) (xy 50.949842 -47.925227) (xy 51.005279 -47.931327)
			(xy 51.059236 -47.945433) (xy 51.110565 -47.967245) (xy 51.158171 -47.996299) (xy 51.201039 -48.031974)
			(xy 51.238256 -48.073511) (xy 51.269029 -48.120024) (xy 51.292701 -48.170521) (xy 51.308769 -48.223928)
			(xy 51.316889 -48.279104) (xy 51.317398 -48.30699) (xy 51.316889 -48.334876) (xy 51.308769 -48.390052)
			(xy 51.292701 -48.443459) (xy 51.269029 -48.493956) (xy 51.238256 -48.540469) (xy 51.201039 -48.582006)
			(xy 51.158171 -48.617681) (xy 51.110565 -48.646735) (xy 51.059236 -48.668547) (xy 51.005279 -48.682653)
			(xy 50.949842 -48.688753) (xy 50.894108 -48.686716) (xy 50.839265 -48.676586) (xy 50.786481 -48.658579)
			(xy 50.736881 -48.633078) (xy 50.691523 -48.600627) (xy 50.651374 -48.561918) (xy 50.617288 -48.517775)
			(xy 50.589992 -48.46914) (xy 50.570069 -48.417049) (xy 50.557943 -48.362612) (xy 50.553872 -48.30699)
			(xy 37.763704 -48.30699) (xy 37.763704 -48.3743) (xy 37.763958 -48.37938) (xy 37.800734 -48.753014)
			(xy 47.168306 -48.753014) (xy 47.172377 -48.697392) (xy 47.184503 -48.642955) (xy 47.204426 -48.590864)
			(xy 47.231722 -48.542229) (xy 47.265808 -48.498086) (xy 47.305957 -48.459377) (xy 47.351315 -48.426926)
			(xy 47.400915 -48.401425) (xy 47.453699 -48.383418) (xy 47.508542 -48.373288) (xy 47.564276 -48.371251)
			(xy 47.619713 -48.377351) (xy 47.67367 -48.391457) (xy 47.724999 -48.413269) (xy 47.772605 -48.442323)
			(xy 47.815473 -48.477998) (xy 47.85269 -48.519535) (xy 47.883463 -48.566048) (xy 47.907135 -48.616545)
			(xy 47.923203 -48.669952) (xy 47.931323 -48.725128) (xy 47.931832 -48.753014) (xy 47.931323 -48.7809)
			(xy 47.923203 -48.836076) (xy 47.907135 -48.889483) (xy 47.905739 -48.89246) (xy 49.214022 -48.89246)
			(xy 49.218093 -48.836838) (xy 49.230219 -48.782401) (xy 49.250142 -48.73031) (xy 49.277438 -48.681675)
			(xy 49.311524 -48.637532) (xy 49.351673 -48.598823) (xy 49.397031 -48.566372) (xy 49.446631 -48.540871)
			(xy 49.499415 -48.522864) (xy 49.554258 -48.512734) (xy 49.609992 -48.510697) (xy 49.665429 -48.516797)
			(xy 49.719386 -48.530903) (xy 49.770715 -48.552715) (xy 49.818321 -48.581769) (xy 49.861189 -48.617444)
			(xy 49.898406 -48.658981) (xy 49.929179 -48.705494) (xy 49.952851 -48.755991) (xy 49.968919 -48.809398)
			(xy 49.977039 -48.864574) (xy 49.977548 -48.89246) (xy 49.977039 -48.920346) (xy 49.974601 -48.93691)
			(xy 52.93309 -48.93691) (xy 52.937161 -48.881288) (xy 52.949287 -48.826851) (xy 52.96921 -48.77476)
			(xy 52.996506 -48.726125) (xy 53.030592 -48.681982) (xy 53.070741 -48.643273) (xy 53.116099 -48.610822)
			(xy 53.165699 -48.585321) (xy 53.218483 -48.567314) (xy 53.273326 -48.557184) (xy 53.32906 -48.555147)
			(xy 53.384497 -48.561247) (xy 53.438454 -48.575353) (xy 53.489783 -48.597165) (xy 53.537389 -48.626219)
			(xy 53.580257 -48.661894) (xy 53.617474 -48.703431) (xy 53.648247 -48.749944) (xy 53.671919 -48.800441)
			(xy 53.687987 -48.853848) (xy 53.696107 -48.909024) (xy 53.696616 -48.93691) (xy 53.696107 -48.964796)
			(xy 53.687987 -49.019972) (xy 53.671919 -49.073379) (xy 53.648247 -49.123876) (xy 53.617474 -49.170389)
			(xy 53.580257 -49.211926) (xy 53.537389 -49.247601) (xy 53.489783 -49.276655) (xy 53.438454 -49.298467)
			(xy 53.384497 -49.312573) (xy 53.32906 -49.318673) (xy 53.273326 -49.316636) (xy 53.218483 -49.306506)
			(xy 53.165699 -49.288499) (xy 53.116099 -49.262998) (xy 53.070741 -49.230547) (xy 53.030592 -49.191838)
			(xy 52.996506 -49.147695) (xy 52.96921 -49.09906) (xy 52.949287 -49.046969) (xy 52.937161 -48.992532)
			(xy 52.93309 -48.93691) (xy 49.974601 -48.93691) (xy 49.968919 -48.975522) (xy 49.952851 -49.028929)
			(xy 49.929179 -49.079426) (xy 49.898406 -49.125939) (xy 49.861189 -49.167476) (xy 49.818321 -49.203151)
			(xy 49.770715 -49.232205) (xy 49.719386 -49.254017) (xy 49.665429 -49.268123) (xy 49.609992 -49.274223)
			(xy 49.554258 -49.272186) (xy 49.499415 -49.262056) (xy 49.446631 -49.244049) (xy 49.397031 -49.218548)
			(xy 49.351673 -49.186097) (xy 49.311524 -49.147388) (xy 49.277438 -49.103245) (xy 49.250142 -49.05461)
			(xy 49.230219 -49.002519) (xy 49.218093 -48.948082) (xy 49.214022 -48.89246) (xy 47.905739 -48.89246)
			(xy 47.883463 -48.93998) (xy 47.85269 -48.986493) (xy 47.815473 -49.02803) (xy 47.772605 -49.063705)
			(xy 47.724999 -49.092759) (xy 47.67367 -49.114571) (xy 47.619713 -49.128677) (xy 47.564276 -49.134777)
			(xy 47.508542 -49.13274) (xy 47.453699 -49.12261) (xy 47.400915 -49.104603) (xy 47.351315 -49.079102)
			(xy 47.305957 -49.046651) (xy 47.265808 -49.007942) (xy 47.231722 -48.963799) (xy 47.204426 -48.915164)
			(xy 47.184503 -48.863073) (xy 47.172377 -48.808636) (xy 47.168306 -48.753014) (xy 37.800734 -48.753014)
			(xy 37.902388 -49.785778) (xy 37.904166 -49.795176) (xy 37.951072 -49.95291) (xy 52.93309 -49.95291)
			(xy 52.937161 -49.897288) (xy 52.949287 -49.842851) (xy 52.96921 -49.79076) (xy 52.996506 -49.742125)
			(xy 53.030592 -49.697982) (xy 53.070741 -49.659273) (xy 53.116099 -49.626822) (xy 53.165699 -49.601321)
			(xy 53.218483 -49.583314) (xy 53.273326 -49.573184) (xy 53.32906 -49.571147) (xy 53.384497 -49.577247)
			(xy 53.438454 -49.591353) (xy 53.463398 -49.601953) (xy 58.112859 -49.601953) (xy 58.112859 -49.547447)
			(xy 58.120617 -49.493495) (xy 58.135973 -49.441197) (xy 58.158616 -49.391616) (xy 58.188085 -49.345763)
			(xy 58.22378 -49.30457) (xy 58.264974 -49.268877) (xy 58.310829 -49.23941) (xy 58.36041 -49.216768)
			(xy 58.412709 -49.201414) (xy 58.466661 -49.193658) (xy 58.493914 -49.193196) (xy 58.521284 -49.193655)
			(xy 58.575464 -49.201475) (xy 58.627967 -49.216965) (xy 58.677714 -49.239809) (xy 58.72368 -49.269534)
			(xy 58.744612 -49.287176) (xy 58.744866 -49.28743) (xy 58.751956 -49.293012) (xy 58.76887 -49.29926)
			(xy 58.777886 -49.299622) (xy 58.844942 -49.299622) (xy 58.853956 -49.299233) (xy 58.870873 -49.293007)
			(xy 58.877962 -49.28743) (xy 58.877962 -49.287176) (xy 58.878216 -49.287176) (xy 58.899149 -49.269535)
			(xy 58.945117 -49.239811) (xy 58.994863 -49.216965) (xy 59.047365 -49.201469) (xy 59.101543 -49.19364)
			(xy 59.156285 -49.19364) (xy 59.210463 -49.201469) (xy 59.262965 -49.216965) (xy 59.312711 -49.239811)
			(xy 59.358679 -49.269535) (xy 59.379612 -49.287176) (xy 59.379866 -49.28743) (xy 59.386956 -49.293012)
			(xy 59.40387 -49.29926) (xy 59.412886 -49.299622) (xy 59.479942 -49.299622) (xy 59.488956 -49.299233)
			(xy 59.505873 -49.293007) (xy 59.512962 -49.28743) (xy 59.512962 -49.287176) (xy 59.513216 -49.287176)
			(xy 59.534149 -49.269535) (xy 59.580117 -49.239811) (xy 59.629863 -49.216965) (xy 59.682365 -49.201469)
			(xy 59.736543 -49.19364) (xy 59.791285 -49.19364) (xy 59.845463 -49.201469) (xy 59.897965 -49.216965)
			(xy 59.947711 -49.239811) (xy 59.993679 -49.269535) (xy 60.014612 -49.287176) (xy 60.014866 -49.28743)
			(xy 60.021956 -49.293012) (xy 60.03887 -49.29926) (xy 60.047886 -49.299622) (xy 60.114942 -49.299622)
			(xy 60.123956 -49.299233) (xy 60.140873 -49.293007) (xy 60.147962 -49.28743) (xy 60.147962 -49.287176)
			(xy 60.148216 -49.287176) (xy 60.169166 -49.269559) (xy 60.215134 -49.239845) (xy 60.264877 -49.217005)
			(xy 60.317374 -49.201509) (xy 60.371546 -49.193674) (xy 60.398914 -49.193196) (xy 60.426165 -49.193675)
			(xy 60.480112 -49.201433) (xy 60.532405 -49.216789) (xy 60.581981 -49.239432) (xy 60.62783 -49.268899)
			(xy 60.669019 -49.304591) (xy 60.70471 -49.345781) (xy 60.734175 -49.391631) (xy 60.756815 -49.441208)
			(xy 60.77217 -49.493502) (xy 60.779926 -49.547449) (xy 60.779926 -49.601951) (xy 60.77217 -49.655898)
			(xy 60.756815 -49.708192) (xy 60.734175 -49.757769) (xy 60.70471 -49.803619) (xy 60.669019 -49.844809)
			(xy 60.62783 -49.880501) (xy 60.581981 -49.909968) (xy 60.532405 -49.932611) (xy 60.480112 -49.947967)
			(xy 60.426165 -49.955725) (xy 60.398914 -49.956212) (xy 60.371544 -49.955735) (xy 60.317366 -49.947919)
			(xy 60.264863 -49.932433) (xy 60.215116 -49.909593) (xy 60.169148 -49.879872) (xy 60.148216 -49.862232)
			(xy 60.147962 -49.861978) (xy 60.140864 -49.856409) (xy 60.123956 -49.850152) (xy 60.114942 -49.849786)
			(xy 60.047886 -49.849786) (xy 60.038869 -49.85014) (xy 60.021952 -49.85639) (xy 60.014866 -49.861978)
			(xy 60.014612 -49.862232) (xy 59.993679 -49.879873) (xy 59.947711 -49.909597) (xy 59.897965 -49.932443)
			(xy 59.845463 -49.947939) (xy 59.791285 -49.955768) (xy 59.736543 -49.955768) (xy 59.682365 -49.947939)
			(xy 59.629863 -49.932443) (xy 59.580117 -49.909597) (xy 59.534149 -49.879873) (xy 59.513216 -49.862232)
			(xy 59.512962 -49.861978) (xy 59.505864 -49.856409) (xy 59.488956 -49.850152) (xy 59.479942 -49.849786)
			(xy 59.412886 -49.849786) (xy 59.403869 -49.85014) (xy 59.386952 -49.85639) (xy 59.379866 -49.861978)
			(xy 59.379866 -49.862232) (xy 59.379612 -49.862232) (xy 59.358679 -49.879873) (xy 59.312711 -49.909597)
			(xy 59.262965 -49.932443) (xy 59.210463 -49.947939) (xy 59.156285 -49.955768) (xy 59.101543 -49.955768)
			(xy 59.047365 -49.947939) (xy 58.994863 -49.932443) (xy 58.945117 -49.909597) (xy 58.899149 -49.879873)
			(xy 58.878216 -49.862232) (xy 58.877962 -49.861978) (xy 58.870864 -49.856409) (xy 58.853956 -49.850152)
			(xy 58.844942 -49.849786) (xy 58.777886 -49.849786) (xy 58.768869 -49.85014) (xy 58.751952 -49.85639)
			(xy 58.744866 -49.861978) (xy 58.744866 -49.862232) (xy 58.744612 -49.862232) (xy 58.72369 -49.879884)
			(xy 58.677714 -49.909593) (xy 58.627964 -49.932426) (xy 58.575461 -49.947914) (xy 58.521284 -49.955739)
			(xy 58.493914 -49.956212) (xy 58.466661 -49.955742) (xy 58.412709 -49.947986) (xy 58.36041 -49.932632)
			(xy 58.310829 -49.90999) (xy 58.264974 -49.880523) (xy 58.22378 -49.84483) (xy 58.188085 -49.803637)
			(xy 58.158616 -49.757784) (xy 58.135973 -49.708203) (xy 58.120617 -49.655905) (xy 58.112859 -49.601953)
			(xy 53.463398 -49.601953) (xy 53.489783 -49.613165) (xy 53.537389 -49.642219) (xy 53.580257 -49.677894)
			(xy 53.617474 -49.719431) (xy 53.648247 -49.765944) (xy 53.671919 -49.816441) (xy 53.687987 -49.869848)
			(xy 53.696107 -49.925024) (xy 53.696616 -49.95291) (xy 53.696107 -49.980796) (xy 53.687987 -50.035972)
			(xy 53.671919 -50.089379) (xy 53.648247 -50.139876) (xy 53.617474 -50.186389) (xy 53.580257 -50.227926)
			(xy 53.537389 -50.263601) (xy 53.489783 -50.292655) (xy 53.438454 -50.314467) (xy 53.384497 -50.328573)
			(xy 53.32906 -50.334673) (xy 53.273326 -50.332636) (xy 53.218483 -50.322506) (xy 53.165699 -50.304499)
			(xy 53.116099 -50.278998) (xy 53.070741 -50.246547) (xy 53.030592 -50.207838) (xy 52.996506 -50.163695)
			(xy 52.96921 -50.11506) (xy 52.949287 -50.062969) (xy 52.937161 -50.008532) (xy 52.93309 -49.95291)
			(xy 37.951072 -49.95291) (xy 38.168834 -50.685192) (xy 38.26817 -51.019456) (xy 50.749452 -51.019456)
			(xy 50.753523 -50.963834) (xy 50.765649 -50.909397) (xy 50.785572 -50.857306) (xy 50.812868 -50.808671)
			(xy 50.846954 -50.764528) (xy 50.887103 -50.725819) (xy 50.932461 -50.693368) (xy 50.982061 -50.667867)
			(xy 51.034845 -50.64986) (xy 51.089688 -50.63973) (xy 51.145422 -50.637693) (xy 51.200859 -50.643793)
			(xy 51.254816 -50.657899) (xy 51.306145 -50.679711) (xy 51.353751 -50.708765) (xy 51.396619 -50.74444)
			(xy 51.433836 -50.785977) (xy 51.464609 -50.83249) (xy 51.488281 -50.882987) (xy 51.504349 -50.936394)
			(xy 51.512469 -50.99157) (xy 51.512978 -51.019456) (xy 51.512469 -51.047342) (xy 51.504349 -51.102518)
			(xy 51.488281 -51.155925) (xy 51.464609 -51.206422) (xy 51.439753 -51.243992) (xy 59.132978 -51.243992)
			(xy 59.13342 -51.216621) (xy 59.141241 -51.16244) (xy 59.156735 -51.109936) (xy 59.179582 -51.060189)
			(xy 59.209313 -51.014224) (xy 59.226958 -50.993294) (xy 59.227212 -50.99304) (xy 59.232789 -50.985947)
			(xy 59.239041 -50.969035) (xy 59.239404 -50.96002) (xy 59.239404 -50.892964) (xy 59.239063 -50.883946)
			(xy 59.232804 -50.867029) (xy 59.227212 -50.859944) (xy 59.226958 -50.859944) (xy 59.226958 -50.85969)
			(xy 59.209294 -50.838778) (xy 59.179587 -50.792799) (xy 59.156757 -50.743046) (xy 59.141271 -50.690542)
			(xy 59.133449 -50.636362) (xy 59.132978 -50.608992) (xy 59.13347 -50.581741) (xy 59.141228 -50.527794)
			(xy 59.156583 -50.475501) (xy 59.179224 -50.425924) (xy 59.20869 -50.380075) (xy 59.244381 -50.338885)
			(xy 59.28557 -50.303193) (xy 59.331419 -50.273727) (xy 59.380995 -50.251085) (xy 59.433289 -50.235729)
			(xy 59.487235 -50.227971) (xy 59.514486 -50.227484) (xy 59.543404 -50.22798) (xy 59.600578 -50.236709)
			(xy 59.655778 -50.25397) (xy 59.707741 -50.279365) (xy 59.755274 -50.312314) (xy 59.797288 -50.352061)
			(xy 59.815476 -50.37455) (xy 59.823095 -50.383345) (xy 59.843987 -50.393533) (xy 59.855608 -50.394108)
			(xy 59.935364 -50.394108) (xy 59.946998 -50.393588) (xy 59.967907 -50.383385) (xy 59.975496 -50.37455)
			(xy 59.993677 -50.352058) (xy 60.0357 -50.312326) (xy 60.083238 -50.279389) (xy 60.135201 -50.254003)
			(xy 60.190399 -50.236748) (xy 60.24757 -50.228019) (xy 60.276486 -50.227484) (xy 60.303738 -50.227968)
			(xy 60.357688 -50.235723) (xy 60.409985 -50.251077) (xy 60.459564 -50.273717) (xy 60.505417 -50.303183)
			(xy 60.54661 -50.338875) (xy 60.582304 -50.380065) (xy 60.611772 -50.425916) (xy 60.634415 -50.475495)
			(xy 60.649772 -50.527791) (xy 60.65753 -50.58174) (xy 60.657994 -50.608992) (xy 60.657523 -50.635306)
			(xy 60.650289 -50.687434) (xy 60.635971 -50.738077) (xy 60.614839 -50.786276) (xy 60.587294 -50.83112)
			(xy 60.553855 -50.871759) (xy 60.534804 -50.889916) (xy 60.527394 -50.89743) (xy 60.518874 -50.916716)
			(xy 60.518294 -50.927254) (xy 60.518294 -51.00193) (xy 60.518849 -51.012477) (xy 60.527366 -51.031772)
			(xy 60.534804 -51.039268) (xy 60.553886 -51.057397) (xy 60.587341 -51.098032) (xy 60.614896 -51.142878)
			(xy 60.63603 -51.191084) (xy 60.650342 -51.241736) (xy 60.657559 -51.293874) (xy 60.657994 -51.320192)
			(xy 60.657537 -51.347445) (xy 60.649781 -51.401397) (xy 60.634425 -51.453696) (xy 60.611783 -51.503277)
			(xy 60.582314 -51.549131) (xy 60.54662 -51.590324) (xy 60.505426 -51.626018) (xy 60.459572 -51.655486)
			(xy 60.40999 -51.678127) (xy 60.357691 -51.693482) (xy 60.303739 -51.701238) (xy 60.276486 -51.7017)
			(xy 60.248821 -51.701199) (xy 60.194071 -51.693198) (xy 60.141049 -51.677379) (xy 60.090865 -51.654074)
			(xy 60.044569 -51.623771) (xy 60.003131 -51.587105) (xy 59.967419 -51.544842) (xy 59.952382 -51.521614)
			(xy 59.945763 -51.511923) (xy 59.925889 -51.499487) (xy 59.914282 -51.497738) (xy 59.834272 -51.489864)
			(xy 59.822633 -51.489219) (xy 59.800795 -51.497308) (xy 59.792362 -51.505358) (xy 59.792108 -51.505612)
			(xy 59.774008 -51.524174) (xy 59.73368 -51.556754) (xy 59.68931 -51.583569) (xy 59.641715 -51.604125)
			(xy 59.591774 -51.618043) (xy 59.540408 -51.625065) (xy 59.514486 -51.6255) (xy 59.487234 -51.625035)
			(xy 59.433285 -51.617277) (xy 59.38099 -51.601919) (xy 59.331412 -51.579276) (xy 59.285561 -51.549807)
			(xy 59.244371 -51.514114) (xy 59.208679 -51.472921) (xy 59.179214 -51.427069) (xy 59.156573 -51.37749)
			(xy 59.141219 -51.325193) (xy 59.133463 -51.271244) (xy 59.132978 -51.243992) (xy 51.439753 -51.243992)
			(xy 51.433836 -51.252935) (xy 51.396619 -51.294472) (xy 51.353751 -51.330147) (xy 51.306145 -51.359201)
			(xy 51.254816 -51.381013) (xy 51.200859 -51.395119) (xy 51.145422 -51.401219) (xy 51.089688 -51.399182)
			(xy 51.034845 -51.389052) (xy 50.982061 -51.371045) (xy 50.932461 -51.345544) (xy 50.887103 -51.313093)
			(xy 50.846954 -51.274384) (xy 50.812868 -51.230241) (xy 50.785572 -51.181606) (xy 50.765649 -51.129515)
			(xy 50.753523 -51.075078) (xy 50.749452 -51.019456) (xy 38.26817 -51.019456) (xy 38.28923 -51.090322)
			(xy 38.298228 -51.122432) (xy 38.309686 -51.188126) (xy 38.31209 -51.221386) (xy 38.360931 -52.035456)
			(xy 52.941218 -52.035456) (xy 52.945289 -51.979834) (xy 52.957415 -51.925397) (xy 52.977338 -51.873306)
			(xy 53.004634 -51.824671) (xy 53.03872 -51.780528) (xy 53.078869 -51.741819) (xy 53.124227 -51.709368)
			(xy 53.173827 -51.683867) (xy 53.226611 -51.66586) (xy 53.281454 -51.65573) (xy 53.337188 -51.653693)
			(xy 53.392625 -51.659793) (xy 53.446582 -51.673899) (xy 53.497911 -51.695711) (xy 53.545517 -51.724765)
			(xy 53.588385 -51.76044) (xy 53.625602 -51.801977) (xy 53.656375 -51.84849) (xy 53.680047 -51.898987)
			(xy 53.696115 -51.952394) (xy 53.704235 -52.00757) (xy 53.704744 -52.035456) (xy 53.704235 -52.063342)
			(xy 53.696115 -52.118518) (xy 53.680047 -52.171925) (xy 53.656375 -52.222422) (xy 53.625602 -52.268935)
			(xy 53.588385 -52.310472) (xy 53.545517 -52.346147) (xy 53.497911 -52.375201) (xy 53.446582 -52.397013)
			(xy 53.392625 -52.411119) (xy 53.337188 -52.417219) (xy 53.281454 -52.415182) (xy 53.226611 -52.405052)
			(xy 53.173827 -52.387045) (xy 53.124227 -52.361544) (xy 53.078869 -52.329093) (xy 53.03872 -52.290384)
			(xy 53.004634 -52.246241) (xy 52.977338 -52.197606) (xy 52.957415 -52.145515) (xy 52.945289 -52.091078)
			(xy 52.941218 -52.035456) (xy 38.360931 -52.035456) (xy 38.522679 -54.731412) (xy 39.520622 -54.731412)
			(xy 39.52109 -54.704042) (xy 39.528906 -54.649863) (xy 39.544395 -54.597359) (xy 39.567236 -54.547612)
			(xy 39.596961 -54.501646) (xy 39.614602 -54.480714) (xy 39.614856 -54.48046) (xy 39.62043 -54.473365)
			(xy 39.626683 -54.456455) (xy 39.627048 -54.44744) (xy 39.627048 -54.380384) (xy 39.62671 -54.371365)
			(xy 39.62045 -54.354448) (xy 39.614856 -54.347364) (xy 39.614602 -54.347364) (xy 39.614602 -54.34711)
			(xy 39.596974 -54.326167) (xy 39.567251 -54.280201) (xy 39.544406 -54.230456) (xy 39.52891 -54.177956)
			(xy 39.521081 -54.123779) (xy 39.52108 -54.069039) (xy 39.528906 -54.014862) (xy 39.5444 -53.962361)
			(xy 39.567242 -53.912615) (xy 39.596963 -53.866647) (xy 39.614602 -53.845714) (xy 39.614856 -53.84546)
			(xy 39.62043 -53.838365) (xy 39.626683 -53.821455) (xy 39.627048 -53.81244) (xy 39.627048 -53.745384)
			(xy 39.62671 -53.736365) (xy 39.62045 -53.719448) (xy 39.614856 -53.712364) (xy 39.614602 -53.712364)
			(xy 39.614602 -53.71211) (xy 39.596974 -53.691167) (xy 39.567251 -53.645201) (xy 39.544406 -53.595456)
			(xy 39.52891 -53.542956) (xy 39.521081 -53.488779) (xy 39.52108 -53.434039) (xy 39.528906 -53.379862)
			(xy 39.5444 -53.327361) (xy 39.567242 -53.277615) (xy 39.596963 -53.231647) (xy 39.614602 -53.210714)
			(xy 39.614856 -53.21046) (xy 39.62043 -53.203365) (xy 39.626683 -53.186455) (xy 39.627048 -53.17744)
			(xy 39.627048 -53.110384) (xy 39.62671 -53.101365) (xy 39.62045 -53.084448) (xy 39.614856 -53.077364)
			(xy 39.614602 -53.077364) (xy 39.614602 -53.07711) (xy 39.596954 -53.056185) (xy 39.567244 -53.01021)
			(xy 39.544409 -52.960461) (xy 39.52892 -52.907959) (xy 39.521095 -52.853782) (xy 39.520622 -52.826412)
			(xy 39.521108 -52.799161) (xy 39.528864 -52.745213) (xy 39.544219 -52.692918) (xy 39.566861 -52.643341)
			(xy 39.596327 -52.597491) (xy 39.632018 -52.5563) (xy 39.673209 -52.520609) (xy 39.719059 -52.491143)
			(xy 39.768636 -52.468501) (xy 39.820931 -52.453146) (xy 39.874879 -52.44539) (xy 39.929381 -52.44539)
			(xy 39.983329 -52.453146) (xy 40.035624 -52.468501) (xy 40.085201 -52.491143) (xy 40.131051 -52.520609)
			(xy 40.172242 -52.5563) (xy 40.207933 -52.597491) (xy 40.237399 -52.643341) (xy 40.260041 -52.692918)
			(xy 40.275396 -52.745213) (xy 40.283152 -52.799161) (xy 40.283638 -52.826412) (xy 40.283194 -52.853783)
			(xy 40.275373 -52.907964) (xy 40.25988 -52.960468) (xy 40.237033 -53.010214) (xy 40.207302 -53.05618)
			(xy 40.189658 -53.07711) (xy 40.189404 -53.077364) (xy 40.183827 -53.084457) (xy 40.177574 -53.101369)
			(xy 40.177212 -53.110384) (xy 40.177212 -53.17744) (xy 40.177547 -53.186459) (xy 40.18381 -53.203376)
			(xy 40.189404 -53.21046) (xy 40.189658 -53.21046) (xy 40.189658 -53.210714) (xy 40.207311 -53.231637)
			(xy 40.237037 -53.277606) (xy 40.259882 -53.327354) (xy 40.275378 -53.379858) (xy 40.283206 -53.434038)
			(xy 40.283205 -53.48878) (xy 40.275374 -53.54296) (xy 40.259876 -53.595463) (xy 40.237028 -53.64521)
			(xy 40.2073 -53.691178) (xy 40.189658 -53.71211) (xy 40.189404 -53.712364) (xy 40.183827 -53.719457)
			(xy 40.177574 -53.736369) (xy 40.177212 -53.745384) (xy 40.177212 -53.81244) (xy 40.177547 -53.821459)
			(xy 40.18381 -53.838376) (xy 40.189404 -53.84546) (xy 40.189658 -53.84546) (xy 40.189658 -53.845714)
			(xy 40.207311 -53.866637) (xy 40.237037 -53.912606) (xy 40.259882 -53.962354) (xy 40.275378 -54.014858)
			(xy 40.283206 -54.069038) (xy 40.283205 -54.12378) (xy 40.275374 -54.17796) (xy 40.259876 -54.230463)
			(xy 40.237028 -54.28021) (xy 40.2073 -54.326178) (xy 40.189658 -54.34711) (xy 40.189404 -54.347364)
			(xy 40.183827 -54.354457) (xy 40.177574 -54.371369) (xy 40.177212 -54.380384) (xy 40.177212 -54.44744)
			(xy 40.177547 -54.456459) (xy 40.18381 -54.473376) (xy 40.189404 -54.48046) (xy 40.189658 -54.48046)
			(xy 40.189658 -54.480714) (xy 40.207264 -54.501673) (xy 40.236982 -54.547638) (xy 40.259825 -54.597378)
			(xy 40.275324 -54.649873) (xy 40.28316 -54.704045) (xy 40.283638 -54.731412) (xy 40.283152 -54.758663)
			(xy 40.278488 -54.791102) (xy 42.176446 -54.791102) (xy 42.176902 -54.763731) (xy 42.184721 -54.709551)
			(xy 42.200211 -54.657048) (xy 42.223056 -54.607301) (xy 42.252783 -54.561335) (xy 42.270426 -54.540404)
			(xy 42.27068 -54.54015) (xy 42.276261 -54.53306) (xy 42.282509 -54.516146) (xy 42.282872 -54.50713)
			(xy 42.282872 -54.440074) (xy 42.282534 -54.431055) (xy 42.276274 -54.414138) (xy 42.27068 -54.407054)
			(xy 42.270426 -54.407054) (xy 42.270426 -54.4068) (xy 42.252787 -54.385866) (xy 42.223063 -54.339898)
			(xy 42.200217 -54.290152) (xy 42.184721 -54.23765) (xy 42.176892 -54.183472) (xy 42.176892 -54.128731)
			(xy 42.18472 -54.074553) (xy 42.200216 -54.022051) (xy 42.223061 -53.972305) (xy 42.252785 -53.926337)
			(xy 42.270426 -53.905404) (xy 42.27068 -53.90515) (xy 42.276261 -53.89806) (xy 42.282509 -53.881146)
			(xy 42.282872 -53.87213) (xy 42.282872 -53.805074) (xy 42.282534 -53.796055) (xy 42.276274 -53.779138)
			(xy 42.27068 -53.772054) (xy 42.270426 -53.772054) (xy 42.270426 -53.7718) (xy 42.252787 -53.750866)
			(xy 42.223063 -53.704898) (xy 42.200217 -53.655152) (xy 42.184721 -53.60265) (xy 42.176892 -53.548472)
			(xy 42.176892 -53.493731) (xy 42.18472 -53.439553) (xy 42.200216 -53.387051) (xy 42.223061 -53.337305)
			(xy 42.252785 -53.291337) (xy 42.270426 -53.270404) (xy 42.27068 -53.27015) (xy 42.276261 -53.26306)
			(xy 42.282509 -53.246146) (xy 42.282872 -53.23713) (xy 42.282872 -53.170074) (xy 42.282534 -53.161055)
			(xy 42.276274 -53.144138) (xy 42.27068 -53.137054) (xy 42.270426 -53.137054) (xy 42.270426 -53.1368)
			(xy 42.252777 -53.115875) (xy 42.223066 -53.069901) (xy 42.200232 -53.020152) (xy 42.184743 -52.967649)
			(xy 42.176918 -52.913472) (xy 42.176446 -52.886102) (xy 42.176932 -52.858851) (xy 42.184688 -52.804903)
			(xy 42.200043 -52.752608) (xy 42.222685 -52.703031) (xy 42.252151 -52.657181) (xy 42.287842 -52.61599)
			(xy 42.329033 -52.580299) (xy 42.374883 -52.550833) (xy 42.42446 -52.528191) (xy 42.476755 -52.512836)
			(xy 42.530703 -52.50508) (xy 42.585205 -52.50508) (xy 42.639153 -52.512836) (xy 42.691448 -52.528191)
			(xy 42.730557 -52.546052) (xy 47.679573 -52.546052) (xy 47.679573 -52.491548) (xy 47.68733 -52.437599)
			(xy 47.702686 -52.385303) (xy 47.725328 -52.335724) (xy 47.754796 -52.289873) (xy 47.790489 -52.248682)
			(xy 47.831681 -52.21299) (xy 47.877533 -52.183523) (xy 47.927112 -52.160883) (xy 47.979409 -52.145528)
			(xy 48.033358 -52.137773) (xy 48.06061 -52.13731) (xy 48.087981 -52.137768) (xy 48.14216 -52.145587)
			(xy 48.194663 -52.161078) (xy 48.24441 -52.183922) (xy 48.290377 -52.213648) (xy 48.311308 -52.23129)
			(xy 48.311562 -52.231544) (xy 48.318651 -52.237126) (xy 48.335566 -52.243374) (xy 48.344582 -52.243736)
			(xy 48.411638 -52.243736) (xy 48.420656 -52.243389) (xy 48.437572 -52.237134) (xy 48.444658 -52.231544)
			(xy 48.444658 -52.23129) (xy 48.444912 -52.23129) (xy 48.465845 -52.213649) (xy 48.511813 -52.183925)
			(xy 48.561559 -52.161079) (xy 48.614061 -52.145583) (xy 48.668239 -52.137754) (xy 48.722981 -52.137754)
			(xy 48.777159 -52.145583) (xy 48.829661 -52.161079) (xy 48.879407 -52.183925) (xy 48.925375 -52.213649)
			(xy 48.946308 -52.23129) (xy 48.946562 -52.231544) (xy 48.953651 -52.237126) (xy 48.970566 -52.243374)
			(xy 48.979582 -52.243736) (xy 49.046638 -52.243736) (xy 49.055656 -52.243389) (xy 49.072572 -52.237134)
			(xy 49.079658 -52.231544) (xy 49.079658 -52.23129) (xy 49.079912 -52.23129) (xy 49.100865 -52.213677)
			(xy 49.146832 -52.183962) (xy 49.196574 -52.161121) (xy 49.24907 -52.145624) (xy 49.303242 -52.137788)
			(xy 49.33061 -52.13731) (xy 49.357862 -52.137761) (xy 49.411811 -52.145519) (xy 49.464107 -52.160875)
			(xy 49.513686 -52.183518) (xy 49.559537 -52.212986) (xy 49.600728 -52.248679) (xy 49.63642 -52.289871)
			(xy 49.665887 -52.335723) (xy 49.688528 -52.385302) (xy 49.703884 -52.437599) (xy 49.71164 -52.491548)
			(xy 49.71164 -52.546052) (xy 49.705696 -52.587398) (xy 50.755294 -52.587398) (xy 50.759365 -52.531776)
			(xy 50.771491 -52.477339) (xy 50.791414 -52.425248) (xy 50.81871 -52.376613) (xy 50.852796 -52.33247)
			(xy 50.892945 -52.293761) (xy 50.938303 -52.26131) (xy 50.987903 -52.235809) (xy 51.040687 -52.217802)
			(xy 51.09553 -52.207672) (xy 51.151264 -52.205635) (xy 51.206701 -52.211735) (xy 51.260658 -52.225841)
			(xy 51.311987 -52.247653) (xy 51.359593 -52.276707) (xy 51.402461 -52.312382) (xy 51.439678 -52.353919)
			(xy 51.470451 -52.400432) (xy 51.494123 -52.450929) (xy 51.510191 -52.504336) (xy 51.517787 -52.555953)
			(xy 58.583779 -52.555953) (xy 58.583779 -52.501447) (xy 58.591537 -52.447497) (xy 58.606893 -52.3952)
			(xy 58.629536 -52.345621) (xy 58.659005 -52.29977) (xy 58.6947 -52.258579) (xy 58.735894 -52.222887)
			(xy 58.781748 -52.193422) (xy 58.831329 -52.170783) (xy 58.883627 -52.15543) (xy 58.937577 -52.147677)
			(xy 58.96483 -52.147216) (xy 58.992201 -52.147661) (xy 59.046381 -52.155483) (xy 59.098885 -52.170977)
			(xy 59.148631 -52.193823) (xy 59.194597 -52.223553) (xy 59.215528 -52.241196) (xy 59.215782 -52.24145)
			(xy 59.222865 -52.247041) (xy 59.239785 -52.253284) (xy 59.248802 -52.253642) (xy 59.315858 -52.253642)
			(xy 59.324874 -52.253278) (xy 59.341792 -52.247037) (xy 59.348878 -52.24145) (xy 59.348878 -52.241196)
			(xy 59.349132 -52.241196) (xy 59.370078 -52.223575) (xy 59.416047 -52.19386) (xy 59.465791 -52.171021)
			(xy 59.518289 -52.155526) (xy 59.572462 -52.147693) (xy 59.59983 -52.147216) (xy 59.627082 -52.147656)
			(xy 59.681029 -52.155416) (xy 59.733324 -52.170775) (xy 59.7829 -52.193419) (xy 59.82875 -52.222888)
			(xy 59.869939 -52.258582) (xy 59.90563 -52.299774) (xy 59.935095 -52.345626) (xy 59.957735 -52.395204)
			(xy 59.97309 -52.4475) (xy 59.980846 -52.501448) (xy 59.980846 -52.555952) (xy 59.97309 -52.6099)
			(xy 59.957735 -52.662196) (xy 59.935095 -52.711774) (xy 59.90563 -52.757626) (xy 59.869939 -52.798818)
			(xy 59.82875 -52.834512) (xy 59.7829 -52.863981) (xy 59.733324 -52.886625) (xy 59.681029 -52.901984)
			(xy 59.627082 -52.909744) (xy 59.59983 -52.910232) (xy 59.57246 -52.909765) (xy 59.51828 -52.90195)
			(xy 59.465776 -52.886462) (xy 59.416029 -52.86362) (xy 59.370063 -52.833894) (xy 59.349132 -52.816252)
			(xy 59.348878 -52.815998) (xy 59.341802 -52.810396) (xy 59.324877 -52.804159) (xy 59.315858 -52.803806)
			(xy 59.248802 -52.803806) (xy 59.239785 -52.804163) (xy 59.222868 -52.81041) (xy 59.215782 -52.815998)
			(xy 59.215782 -52.816252) (xy 59.215528 -52.816252) (xy 59.19459 -52.833884) (xy 59.14862 -52.863599)
			(xy 59.098874 -52.886437) (xy 59.046374 -52.901929) (xy 58.992199 -52.909758) (xy 58.96483 -52.910232)
			(xy 58.937577 -52.909723) (xy 58.883627 -52.90197) (xy 58.831329 -52.886617) (xy 58.781748 -52.863978)
			(xy 58.735894 -52.834513) (xy 58.6947 -52.798821) (xy 58.659005 -52.75763) (xy 58.629536 -52.711779)
			(xy 58.606893 -52.6622) (xy 58.591537 -52.609903) (xy 58.583779 -52.555953) (xy 51.517787 -52.555953)
			(xy 51.518311 -52.559512) (xy 51.51882 -52.587398) (xy 51.518311 -52.615284) (xy 51.510191 -52.67046)
			(xy 51.494123 -52.723867) (xy 51.470451 -52.774364) (xy 51.439678 -52.820877) (xy 51.402461 -52.862414)
			(xy 51.359593 -52.898089) (xy 51.311987 -52.927143) (xy 51.260658 -52.948955) (xy 51.206701 -52.963061)
			(xy 51.151264 -52.969161) (xy 51.09553 -52.967124) (xy 51.040687 -52.956994) (xy 50.987903 -52.938987)
			(xy 50.938303 -52.913486) (xy 50.892945 -52.881035) (xy 50.852796 -52.842326) (xy 50.81871 -52.798183)
			(xy 50.791414 -52.749548) (xy 50.771491 -52.697457) (xy 50.759365 -52.64302) (xy 50.755294 -52.587398)
			(xy 49.705696 -52.587398) (xy 49.703884 -52.600001) (xy 49.688528 -52.652298) (xy 49.665887 -52.701877)
			(xy 49.63642 -52.747729) (xy 49.600728 -52.788921) (xy 49.559537 -52.824614) (xy 49.513686 -52.854082)
			(xy 49.464107 -52.876725) (xy 49.411811 -52.892081) (xy 49.357862 -52.899839) (xy 49.33061 -52.900326)
			(xy 49.303239 -52.899872) (xy 49.249059 -52.892054) (xy 49.196555 -52.876563) (xy 49.146808 -52.853718)
			(xy 49.100843 -52.82399) (xy 49.079912 -52.806346) (xy 49.079658 -52.806092) (xy 49.07256 -52.800523)
			(xy 49.055652 -52.794266) (xy 49.046638 -52.7939) (xy 48.979582 -52.7939) (xy 48.970564 -52.794249)
			(xy 48.953647 -52.800502) (xy 48.946562 -52.806092) (xy 48.946308 -52.806346) (xy 48.925375 -52.823987)
			(xy 48.879407 -52.853711) (xy 48.829661 -52.876557) (xy 48.777159 -52.892053) (xy 48.722981 -52.899882)
			(xy 48.668239 -52.899882) (xy 48.614061 -52.892053) (xy 48.561559 -52.876557) (xy 48.511813 -52.853711)
			(xy 48.465845 -52.823987) (xy 48.444912 -52.806346) (xy 48.444658 -52.806092) (xy 48.43756 -52.800523)
			(xy 48.420652 -52.794266) (xy 48.411638 -52.7939) (xy 48.344582 -52.7939) (xy 48.335564 -52.794249)
			(xy 48.318647 -52.800502) (xy 48.311562 -52.806092) (xy 48.311562 -52.806346) (xy 48.311308 -52.806346)
			(xy 48.290377 -52.823986) (xy 48.244405 -52.8537) (xy 48.194657 -52.876536) (xy 48.142156 -52.892027)
			(xy 48.087979 -52.899853) (xy 48.06061 -52.900326) (xy 48.033358 -52.899827) (xy 47.979409 -52.892072)
			(xy 47.927112 -52.876717) (xy 47.877533 -52.854077) (xy 47.831681 -52.82461) (xy 47.790489 -52.788918)
			(xy 47.754796 -52.747727) (xy 47.725328 -52.701876) (xy 47.702686 -52.652297) (xy 47.68733 -52.600001)
			(xy 47.679573 -52.546052) (xy 42.730557 -52.546052) (xy 42.741025 -52.550833) (xy 42.786875 -52.580299)
			(xy 42.828066 -52.61599) (xy 42.863757 -52.657181) (xy 42.893223 -52.703031) (xy 42.915865 -52.752608)
			(xy 42.93122 -52.804903) (xy 42.938976 -52.858851) (xy 42.939462 -52.886102) (xy 42.939006 -52.913473)
			(xy 42.931187 -52.967653) (xy 42.915696 -53.020156) (xy 42.892852 -53.069903) (xy 42.863125 -53.115869)
			(xy 42.845482 -53.1368) (xy 42.845228 -53.137054) (xy 42.839646 -53.144143) (xy 42.833399 -53.161058)
			(xy 42.833036 -53.170074) (xy 42.833036 -53.23713) (xy 42.833371 -53.246149) (xy 42.839633 -53.263067)
			(xy 42.845228 -53.27015) (xy 42.845482 -53.27015) (xy 42.845482 -53.270404) (xy 42.863124 -53.291335)
			(xy 42.892848 -53.337304) (xy 42.915693 -53.38705) (xy 42.931189 -53.439552) (xy 42.939017 -53.493731)
			(xy 42.939017 -53.548472) (xy 42.931188 -53.602651) (xy 42.915692 -53.655153) (xy 42.892847 -53.704899)
			(xy 42.863122 -53.750867) (xy 42.846552 -53.77053) (xy 43.210734 -53.77053) (xy 43.211261 -53.741613)
			(xy 43.219986 -53.684442) (xy 43.237242 -53.629243) (xy 43.262632 -53.577281) (xy 43.295574 -53.529747)
			(xy 43.335315 -53.48773) (xy 43.3578 -53.46954) (xy 43.366579 -53.461906) (xy 43.376778 -53.441026)
			(xy 43.377358 -53.429408) (xy 43.377358 -53.349652) (xy 43.376847 -53.338016) (xy 43.36664 -53.317106)
			(xy 43.3578 -53.30952) (xy 43.335326 -53.291318) (xy 43.29559 -53.2493) (xy 43.26265 -53.201768)
			(xy 43.23726 -53.149809) (xy 43.220002 -53.094613) (xy 43.21127 -53.037445) (xy 43.210734 -53.00853)
			(xy 43.211183 -52.981276) (xy 43.218937 -52.927322) (xy 43.234292 -52.875022) (xy 43.256934 -52.825439)
			(xy 43.286403 -52.779584) (xy 43.322098 -52.738389) (xy 43.363293 -52.702695) (xy 43.409149 -52.673228)
			(xy 43.458733 -52.650587) (xy 43.511034 -52.635235) (xy 43.564988 -52.627482) (xy 43.592242 -52.627022)
			(xy 43.618557 -52.627454) (xy 43.670688 -52.634695) (xy 43.721331 -52.649021) (xy 43.76953 -52.67016)
			(xy 43.814373 -52.697712) (xy 43.855011 -52.731157) (xy 43.873166 -52.750212) (xy 43.880697 -52.757603)
			(xy 43.89997 -52.766133) (xy 43.910504 -52.766722) (xy 43.98518 -52.766722) (xy 43.995729 -52.766189)
			(xy 44.015024 -52.757656) (xy 44.022518 -52.750212) (xy 44.040674 -52.731157) (xy 44.081303 -52.697699)
			(xy 44.126144 -52.67014) (xy 44.174344 -52.649001) (xy 44.224992 -52.634684) (xy 44.277126 -52.62746)
			(xy 44.303442 -52.627022) (xy 44.330696 -52.627439) (xy 44.384647 -52.635202) (xy 44.436945 -52.650564)
			(xy 44.486525 -52.673212) (xy 44.532376 -52.702685) (xy 44.573567 -52.738384) (xy 44.609258 -52.779581)
			(xy 44.638723 -52.825439) (xy 44.661361 -52.875022) (xy 44.676713 -52.927323) (xy 44.684466 -52.981276)
			(xy 44.68495 -53.00853) (xy 44.684484 -53.036197) (xy 44.682253 -53.051456) (xy 52.941218 -53.051456)
			(xy 52.945289 -52.995834) (xy 52.957415 -52.941397) (xy 52.977338 -52.889306) (xy 53.004634 -52.840671)
			(xy 53.03872 -52.796528) (xy 53.078869 -52.757819) (xy 53.124227 -52.725368) (xy 53.173827 -52.699867)
			(xy 53.226611 -52.68186) (xy 53.281454 -52.67173) (xy 53.337188 -52.669693) (xy 53.392625 -52.675793)
			(xy 53.446582 -52.689899) (xy 53.497911 -52.711711) (xy 53.545517 -52.740765) (xy 53.588385 -52.77644)
			(xy 53.625602 -52.817977) (xy 53.656375 -52.86449) (xy 53.680047 -52.914987) (xy 53.696115 -52.968394)
			(xy 53.704235 -53.02357) (xy 53.704744 -53.051456) (xy 53.704235 -53.079342) (xy 53.696115 -53.134518)
			(xy 53.680047 -53.187925) (xy 53.656375 -53.238422) (xy 53.625602 -53.284935) (xy 53.588385 -53.326472)
			(xy 53.545517 -53.362147) (xy 53.497911 -53.391201) (xy 53.446582 -53.413013) (xy 53.392625 -53.427119)
			(xy 53.337188 -53.433219) (xy 53.281454 -53.431182) (xy 53.226611 -53.421052) (xy 53.173827 -53.403045)
			(xy 53.124227 -53.377544) (xy 53.078869 -53.345093) (xy 53.03872 -53.306384) (xy 53.004634 -53.262241)
			(xy 52.977338 -53.213606) (xy 52.957415 -53.161515) (xy 52.945289 -53.107078) (xy 52.941218 -53.051456)
			(xy 44.682253 -53.051456) (xy 44.676479 -53.090949) (xy 44.660656 -53.143973) (xy 44.637346 -53.194158)
			(xy 44.607037 -53.240453) (xy 44.570364 -53.281889) (xy 44.528095 -53.317599) (xy 44.504864 -53.332634)
			(xy 44.495176 -53.339257) (xy 44.482737 -53.359128) (xy 44.480988 -53.370734) (xy 44.473114 -53.450744)
			(xy 44.472473 -53.462382) (xy 44.480561 -53.484219) (xy 44.488608 -53.492654) (xy 44.488862 -53.492908)
			(xy 44.507422 -53.51101) (xy 44.540004 -53.551336) (xy 44.566821 -53.595706) (xy 44.587377 -53.643301)
			(xy 44.601295 -53.693242) (xy 44.608316 -53.744608) (xy 44.60875 -53.77053) (xy 44.60825 -53.79778)
			(xy 44.600491 -53.851725) (xy 44.585134 -53.904017) (xy 44.562492 -53.953592) (xy 44.533027 -53.99944)
			(xy 44.497337 -54.040629) (xy 44.456149 -54.07632) (xy 44.410302 -54.105787) (xy 44.360728 -54.12843)
			(xy 44.308437 -54.143788) (xy 44.254492 -54.151549) (xy 44.227242 -54.152038) (xy 44.199872 -54.151562)
			(xy 44.145693 -54.143749) (xy 44.093189 -54.128263) (xy 44.043442 -54.105423) (xy 43.997475 -54.075699)
			(xy 43.976544 -54.058058) (xy 43.97629 -54.057804) (xy 43.96921 -54.052208) (xy 43.952288 -54.045967)
			(xy 43.94327 -54.045612) (xy 43.876214 -54.045612) (xy 43.867197 -54.045973) (xy 43.85028 -54.052217)
			(xy 43.843194 -54.057804) (xy 43.843194 -54.058058) (xy 43.84294 -54.058058) (xy 43.821998 -54.075685)
			(xy 43.776029 -54.1054) (xy 43.726284 -54.128239) (xy 43.673785 -54.143733) (xy 43.619611 -54.151563)
			(xy 43.592242 -54.152038) (xy 43.564992 -54.151506) (xy 43.511045 -54.143755) (xy 43.45875 -54.128406)
			(xy 43.409172 -54.105771) (xy 43.36332 -54.07631) (xy 43.322128 -54.040623) (xy 43.286433 -53.999438)
			(xy 43.256964 -53.953591) (xy 43.234319 -53.904018) (xy 43.21896 -53.851726) (xy 43.211199 -53.79778)
			(xy 43.210734 -53.77053) (xy 42.846552 -53.77053) (xy 42.845482 -53.7718) (xy 42.845228 -53.772054)
			(xy 42.839646 -53.779143) (xy 42.833399 -53.796058) (xy 42.833036 -53.805074) (xy 42.833036 -53.87213)
			(xy 42.833371 -53.881149) (xy 42.839633 -53.898067) (xy 42.845228 -53.90515) (xy 42.845482 -53.90515)
			(xy 42.845482 -53.905404) (xy 42.863124 -53.926335) (xy 42.892848 -53.972304) (xy 42.915693 -54.02205)
			(xy 42.931189 -54.074552) (xy 42.939017 -54.128731) (xy 42.939017 -54.183472) (xy 42.931188 -54.237651)
			(xy 42.915692 -54.290153) (xy 42.9019 -54.320186) (xy 45.130466 -54.320186) (xy 45.130908 -54.292815)
			(xy 45.138729 -54.238634) (xy 45.154223 -54.18613) (xy 45.17707 -54.136383) (xy 45.206801 -54.090418)
			(xy 45.224446 -54.069488) (xy 45.2247 -54.069234) (xy 45.230278 -54.062142) (xy 45.23653 -54.045229)
			(xy 45.236892 -54.036214) (xy 45.236892 -53.969158) (xy 45.236509 -53.960144) (xy 45.23028 -53.943227)
			(xy 45.2247 -53.936138) (xy 45.224446 -53.936138) (xy 45.224446 -53.935884) (xy 45.20684 -53.914925)
			(xy 45.177122 -53.86896) (xy 45.154279 -53.81922) (xy 45.13878 -53.766725) (xy 45.130944 -53.712553)
			(xy 45.130466 -53.685186) (xy 45.130952 -53.657935) (xy 45.138708 -53.603987) (xy 45.154063 -53.551692)
			(xy 45.176705 -53.502115) (xy 45.206171 -53.456265) (xy 45.241862 -53.415074) (xy 45.283053 -53.379383)
			(xy 45.328903 -53.349917) (xy 45.37848 -53.327275) (xy 45.430775 -53.31192) (xy 45.484723 -53.304164)
			(xy 45.539225 -53.304164) (xy 45.593173 -53.31192) (xy 45.645468 -53.327275) (xy 45.695045 -53.349917)
			(xy 45.740895 -53.379383) (xy 45.782086 -53.415074) (xy 45.817777 -53.456265) (xy 45.843668 -53.496552)
			(xy 58.133464 -53.496552) (xy 58.133464 -53.442048) (xy 58.14122 -53.3881) (xy 58.156575 -53.335804)
			(xy 58.179216 -53.286226) (xy 58.208683 -53.240374) (xy 58.244374 -53.199183) (xy 58.285565 -53.16349)
			(xy 58.331415 -53.134022) (xy 58.380993 -53.11138) (xy 58.433288 -53.096023) (xy 58.487236 -53.088265)
			(xy 58.514488 -53.087778) (xy 58.541859 -53.088232) (xy 58.596039 -53.09605) (xy 58.648543 -53.111541)
			(xy 58.69829 -53.134386) (xy 58.744256 -53.164114) (xy 58.765186 -53.181758) (xy 58.76544 -53.182012)
			(xy 58.772539 -53.187581) (xy 58.789446 -53.193838) (xy 58.79846 -53.194204) (xy 58.865516 -53.194204)
			(xy 58.874534 -53.193854) (xy 58.89145 -53.187601) (xy 58.898536 -53.182012) (xy 58.898536 -53.181758)
			(xy 58.89879 -53.181758) (xy 58.919709 -53.164103) (xy 58.965686 -53.134395) (xy 59.015437 -53.111563)
			(xy 59.06794 -53.096075) (xy 59.122118 -53.08825) (xy 59.149488 -53.087778) (xy 59.17674 -53.088268)
			(xy 59.230691 -53.096024) (xy 59.282988 -53.111378) (xy 59.332568 -53.134019) (xy 59.378421 -53.163486)
			(xy 59.419613 -53.199178) (xy 59.455307 -53.24037) (xy 59.484775 -53.286222) (xy 59.507418 -53.335801)
			(xy 59.522774 -53.388098) (xy 59.530531 -53.442048) (xy 59.530531 -53.496552) (xy 59.522774 -53.550502)
			(xy 59.507418 -53.602799) (xy 59.484775 -53.652378) (xy 59.455307 -53.69823) (xy 59.419613 -53.739422)
			(xy 59.378421 -53.775114) (xy 59.332568 -53.804581) (xy 59.282988 -53.827222) (xy 59.230691 -53.842576)
			(xy 59.17674 -53.850332) (xy 59.149488 -53.850794) (xy 59.122117 -53.850336) (xy 59.067938 -53.842517)
			(xy 59.015435 -53.827026) (xy 58.965688 -53.804182) (xy 58.919721 -53.774456) (xy 58.89879 -53.756814)
			(xy 58.898536 -53.75656) (xy 58.891447 -53.750977) (xy 58.874532 -53.744729) (xy 58.865516 -53.744368)
			(xy 58.79846 -53.744368) (xy 58.789442 -53.744713) (xy 58.772525 -53.75097) (xy 58.76544 -53.75656)
			(xy 58.76544 -53.756814) (xy 58.765186 -53.756814) (xy 58.744234 -53.774428) (xy 58.698267 -53.804143)
			(xy 58.648524 -53.826984) (xy 58.596028 -53.842481) (xy 58.541856 -53.850316) (xy 58.514488 -53.850794)
			(xy 58.487236 -53.850335) (xy 58.433288 -53.842577) (xy 58.380993 -53.82722) (xy 58.331415 -53.804578)
			(xy 58.285565 -53.77511) (xy 58.244374 -53.739417) (xy 58.208683 -53.698226) (xy 58.179216 -53.652374)
			(xy 58.156575 -53.602796) (xy 58.14122 -53.5505) (xy 58.133464 -53.496552) (xy 45.843668 -53.496552)
			(xy 45.847243 -53.502115) (xy 45.869885 -53.551692) (xy 45.88524 -53.603987) (xy 45.892996 -53.657935)
			(xy 45.893482 -53.685186) (xy 45.893012 -53.712556) (xy 45.885196 -53.766735) (xy 45.869708 -53.819238)
			(xy 45.846867 -53.868985) (xy 45.817143 -53.914952) (xy 45.799502 -53.935884) (xy 45.799248 -53.936138)
			(xy 45.793675 -53.943234) (xy 45.787421 -53.960144) (xy 45.787056 -53.969158) (xy 45.787056 -54.036214)
			(xy 45.787394 -54.045233) (xy 45.793654 -54.06215) (xy 45.799248 -54.069234) (xy 45.799502 -54.069234)
			(xy 45.799502 -54.069488) (xy 45.817149 -54.090414) (xy 45.84686 -54.136388) (xy 45.869694 -54.186137)
			(xy 45.885183 -54.238639) (xy 45.893009 -54.292816) (xy 45.893482 -54.320186) (xy 45.892996 -54.347437)
			(xy 45.88524 -54.401385) (xy 45.869885 -54.45368) (xy 45.847243 -54.503257) (xy 45.817777 -54.549107)
			(xy 45.782086 -54.590298) (xy 45.740895 -54.625989) (xy 45.695045 -54.655455) (xy 45.645468 -54.678097)
			(xy 45.593173 -54.693452) (xy 45.539225 -54.701208) (xy 45.484723 -54.701208) (xy 45.430775 -54.693452)
			(xy 45.37848 -54.678097) (xy 45.328903 -54.655455) (xy 45.283053 -54.625989) (xy 45.241862 -54.590298)
			(xy 45.206171 -54.549107) (xy 45.176705 -54.503257) (xy 45.154063 -54.45368) (xy 45.138708 -54.401385)
			(xy 45.130952 -54.347437) (xy 45.130466 -54.320186) (xy 42.9019 -54.320186) (xy 42.892847 -54.339899)
			(xy 42.863122 -54.385867) (xy 42.845482 -54.4068) (xy 42.845228 -54.407054) (xy 42.839646 -54.414143)
			(xy 42.833399 -54.431058) (xy 42.833036 -54.440074) (xy 42.833036 -54.50713) (xy 42.833371 -54.516149)
			(xy 42.839633 -54.533067) (xy 42.845228 -54.54015) (xy 42.845482 -54.54015) (xy 42.845482 -54.540404)
			(xy 42.863134 -54.561326) (xy 42.892844 -54.607301) (xy 42.915678 -54.657051) (xy 42.931166 -54.709554)
			(xy 42.93899 -54.763732) (xy 42.939107 -54.770528) (xy 46.071028 -54.770528) (xy 46.071504 -54.743158)
			(xy 46.079318 -54.688979) (xy 46.094805 -54.636476) (xy 46.117644 -54.586729) (xy 46.147367 -54.540762)
			(xy 46.165008 -54.51983) (xy 46.165262 -54.519576) (xy 46.170872 -54.512506) (xy 46.177103 -54.495576)
			(xy 46.177454 -54.486556) (xy 46.177454 -54.4195) (xy 46.177107 -54.410482) (xy 46.170853 -54.393565)
			(xy 46.165262 -54.38648) (xy 46.165008 -54.38648) (xy 46.165008 -54.386226) (xy 46.147369 -54.365294)
			(xy 46.117657 -54.319321) (xy 46.094821 -54.269574) (xy 46.07933 -54.217073) (xy 46.071502 -54.162897)
			(xy 46.071028 -54.135528) (xy 46.071514 -54.108277) (xy 46.07927 -54.054329) (xy 46.094625 -54.002034)
			(xy 46.117267 -53.952457) (xy 46.146733 -53.906607) (xy 46.182424 -53.865416) (xy 46.223615 -53.829725)
			(xy 46.269465 -53.800259) (xy 46.319042 -53.777617) (xy 46.371337 -53.762262) (xy 46.425285 -53.754506)
			(xy 46.479787 -53.754506) (xy 46.533735 -53.762262) (xy 46.58603 -53.777617) (xy 46.635607 -53.800259)
			(xy 46.681457 -53.829725) (xy 46.722648 -53.865416) (xy 46.758339 -53.906607) (xy 46.787805 -53.952457)
			(xy 46.79288 -53.96357) (xy 50.772058 -53.96357) (xy 50.776129 -53.907948) (xy 50.788255 -53.853511)
			(xy 50.808178 -53.80142) (xy 50.835474 -53.752785) (xy 50.86956 -53.708642) (xy 50.909709 -53.669933)
			(xy 50.955067 -53.637482) (xy 51.004667 -53.611981) (xy 51.057451 -53.593974) (xy 51.112294 -53.583844)
			(xy 51.168028 -53.581807) (xy 51.223465 -53.587907) (xy 51.277422 -53.602013) (xy 51.328751 -53.623825)
			(xy 51.376357 -53.652879) (xy 51.419225 -53.688554) (xy 51.456442 -53.730091) (xy 51.487215 -53.776604)
			(xy 51.510887 -53.827101) (xy 51.526955 -53.880508) (xy 51.535075 -53.935684) (xy 51.535584 -53.96357)
			(xy 51.535075 -53.991456) (xy 51.526955 -54.046632) (xy 51.510887 -54.100039) (xy 51.487215 -54.150536)
			(xy 51.456442 -54.197049) (xy 51.419225 -54.238586) (xy 51.376357 -54.274261) (xy 51.328751 -54.303315)
			(xy 51.277422 -54.325127) (xy 51.223465 -54.339233) (xy 51.168028 -54.345333) (xy 51.112294 -54.343296)
			(xy 51.057451 -54.333166) (xy 51.004667 -54.315159) (xy 50.955067 -54.289658) (xy 50.909709 -54.257207)
			(xy 50.86956 -54.218498) (xy 50.835474 -54.174355) (xy 50.808178 -54.12572) (xy 50.788255 -54.073629)
			(xy 50.776129 -54.019192) (xy 50.772058 -53.96357) (xy 46.79288 -53.96357) (xy 46.810447 -54.002034)
			(xy 46.825802 -54.054329) (xy 46.833558 -54.108277) (xy 46.834044 -54.135528) (xy 46.833608 -54.162899)
			(xy 46.825785 -54.21708) (xy 46.81029 -54.269584) (xy 46.787441 -54.319331) (xy 46.757709 -54.365296)
			(xy 46.740064 -54.386226) (xy 46.73981 -54.38648) (xy 46.734227 -54.393569) (xy 46.727978 -54.410484)
			(xy 46.727618 -54.4195) (xy 46.727618 -54.486556) (xy 46.727992 -54.495571) (xy 46.734228 -54.512488)
			(xy 46.73981 -54.519576) (xy 46.740064 -54.519576) (xy 46.740064 -54.51983) (xy 46.757678 -54.540782)
			(xy 46.787395 -54.586749) (xy 46.810236 -54.636491) (xy 46.825733 -54.688988) (xy 46.833567 -54.74316)
			(xy 46.834044 -54.770528) (xy 46.833558 -54.797779) (xy 46.825802 -54.851727) (xy 46.810447 -54.904022)
			(xy 46.787805 -54.953599) (xy 46.765021 -54.989051) (xy 55.901068 -54.989051) (xy 55.901068 -54.934549)
			(xy 55.908824 -54.880601) (xy 55.924179 -54.828307) (xy 55.946819 -54.778729) (xy 55.976284 -54.732879)
			(xy 56.011975 -54.691688) (xy 56.053164 -54.655995) (xy 56.099013 -54.626528) (xy 56.14859 -54.603885)
			(xy 56.200884 -54.588528) (xy 56.254831 -54.580769) (xy 56.282082 -54.580282) (xy 56.310173 -54.580791)
			(xy 56.36575 -54.589016) (xy 56.419518 -54.605304) (xy 56.470316 -54.629305) (xy 56.517043 -54.660497)
			(xy 56.558688 -54.698207) (xy 56.594351 -54.741619) (xy 56.609234 -54.765448) (xy 56.614568 -54.774338)
			(xy 56.631586 -54.78653) (xy 56.724804 -54.80685) (xy 56.745378 -54.802532) (xy 56.754014 -54.79669)
			(xy 56.778072 -54.780681) (xy 56.830006 -54.75534) (xy 56.885165 -54.738117) (xy 56.942291 -54.729405)
			(xy 56.971184 -54.728872) (xy 56.998434 -54.729393) (xy 57.052379 -54.737147) (xy 57.104672 -54.752499)
			(xy 57.154248 -54.775137) (xy 57.200097 -54.804599) (xy 57.241287 -54.840287) (xy 57.276979 -54.881474)
			(xy 57.306446 -54.92732) (xy 57.329088 -54.976894) (xy 57.344445 -55.029185) (xy 57.352204 -55.08313)
			(xy 57.352692 -55.11038) (xy 57.352216 -55.13775) (xy 57.344401 -55.191929) (xy 57.328914 -55.244432)
			(xy 57.306075 -55.294179) (xy 57.276352 -55.340146) (xy 57.258712 -55.361078) (xy 57.258458 -55.361332)
			(xy 57.252889 -55.36843) (xy 57.246633 -55.385338) (xy 57.246266 -55.394352) (xy 57.246266 -55.461408)
			(xy 57.246626 -55.470424) (xy 57.252872 -55.487341) (xy 57.258458 -55.494428) (xy 57.258712 -55.494428)
			(xy 57.258712 -55.494682) (xy 57.276331 -55.515631) (xy 57.306054 -55.561597) (xy 57.328898 -55.611341)
			(xy 57.344394 -55.66384) (xy 57.352224 -55.718016) (xy 57.352226 -55.772754) (xy 57.344401 -55.82693)
			(xy 57.328909 -55.879431) (xy 57.306069 -55.929176) (xy 57.27635 -55.975145) (xy 57.258712 -55.996078)
			(xy 57.258458 -55.996332) (xy 57.252889 -56.00343) (xy 57.246633 -56.020338) (xy 57.246266 -56.029352)
			(xy 57.246266 -56.096408) (xy 57.246626 -56.105424) (xy 57.252872 -56.122341) (xy 57.258458 -56.129428)
			(xy 57.258712 -56.129428) (xy 57.258712 -56.129682) (xy 57.276358 -56.150608) (xy 57.306068 -56.196583)
			(xy 57.328903 -56.246332) (xy 57.344392 -56.298834) (xy 57.352219 -56.35301) (xy 57.352692 -56.38038)
			(xy 57.352206 -56.407631) (xy 57.34445 -56.461579) (xy 57.329095 -56.513874) (xy 57.306453 -56.563451)
			(xy 57.276987 -56.609301) (xy 57.241296 -56.650492) (xy 57.200105 -56.686183) (xy 57.154255 -56.715649)
			(xy 57.104678 -56.738291) (xy 57.052383 -56.753646) (xy 56.998435 -56.761402) (xy 56.943933 -56.761402)
			(xy 56.889985 -56.753646) (xy 56.83769 -56.738291) (xy 56.788113 -56.715649) (xy 56.742263 -56.686183)
			(xy 56.701072 -56.650492) (xy 56.665381 -56.609301) (xy 56.635915 -56.563451) (xy 56.613273 -56.513874)
			(xy 56.597918 -56.461579) (xy 56.590162 -56.407631) (xy 56.589676 -56.38038) (xy 56.590112 -56.353008)
			(xy 56.597934 -56.298827) (xy 56.613429 -56.246323) (xy 56.636278 -56.196577) (xy 56.666011 -56.150612)
			(xy 56.683656 -56.129682) (xy 56.68391 -56.129428) (xy 56.689492 -56.122338) (xy 56.695741 -56.105424)
			(xy 56.696102 -56.096408) (xy 56.696102 -56.029352) (xy 56.695719 -56.020338) (xy 56.689489 -56.003421)
			(xy 56.68391 -55.996332) (xy 56.683656 -55.996332) (xy 56.683656 -55.996078) (xy 56.665995 -55.975162)
			(xy 56.636268 -55.929192) (xy 56.613422 -55.879443) (xy 56.597926 -55.826938) (xy 56.590099 -55.772757)
			(xy 56.590101 -55.718013) (xy 56.597933 -55.663832) (xy 56.613433 -55.611329) (xy 56.636283 -55.561582)
			(xy 56.666013 -55.515614) (xy 56.683656 -55.494682) (xy 56.68391 -55.494428) (xy 56.689492 -55.487338)
			(xy 56.695741 -55.470424) (xy 56.696102 -55.461408) (xy 56.696102 -55.394352) (xy 56.695719 -55.385338)
			(xy 56.689489 -55.368421) (xy 56.68391 -55.361332) (xy 56.683656 -55.360824) (xy 56.67271 -55.348091)
			(xy 56.65287 -55.320999) (xy 56.644032 -55.306722) (xy 56.638698 -55.297832) (xy 56.62168 -55.28564)
			(xy 56.528462 -55.26532) (xy 56.507888 -55.269638) (xy 56.499252 -55.27548) (xy 56.475174 -55.291458)
			(xy 56.423248 -55.316806) (xy 56.368094 -55.334038) (xy 56.310973 -55.34276) (xy 56.282082 -55.343298)
			(xy 56.254831 -55.342831) (xy 56.200884 -55.335072) (xy 56.14859 -55.319715) (xy 56.099013 -55.297072)
			(xy 56.053164 -55.267605) (xy 56.011975 -55.231912) (xy 55.976284 -55.190721) (xy 55.946819 -55.144871)
			(xy 55.924179 -55.095293) (xy 55.908824 -55.042999) (xy 55.901068 -54.989051) (xy 46.765021 -54.989051)
			(xy 46.758339 -54.999449) (xy 46.722648 -55.04064) (xy 46.681457 -55.076331) (xy 46.635607 -55.105797)
			(xy 46.58603 -55.128439) (xy 46.533735 -55.143794) (xy 46.479787 -55.15155) (xy 46.425285 -55.15155)
			(xy 46.371337 -55.143794) (xy 46.319042 -55.128439) (xy 46.269465 -55.105797) (xy 46.223615 -55.076331)
			(xy 46.182424 -55.04064) (xy 46.146733 -54.999449) (xy 46.117267 -54.953599) (xy 46.094625 -54.904022)
			(xy 46.07927 -54.851727) (xy 46.071514 -54.797779) (xy 46.071028 -54.770528) (xy 42.939107 -54.770528)
			(xy 42.939462 -54.791102) (xy 42.938976 -54.818353) (xy 42.93122 -54.872301) (xy 42.915865 -54.924596)
			(xy 42.893223 -54.974173) (xy 42.863757 -55.020023) (xy 42.828066 -55.061214) (xy 42.786875 -55.096905)
			(xy 42.741025 -55.126371) (xy 42.691448 -55.149013) (xy 42.639153 -55.164368) (xy 42.585205 -55.172124)
			(xy 42.530703 -55.172124) (xy 42.476755 -55.164368) (xy 42.42446 -55.149013) (xy 42.374883 -55.126371)
			(xy 42.329033 -55.096905) (xy 42.287842 -55.061214) (xy 42.252151 -55.020023) (xy 42.222685 -54.974173)
			(xy 42.200043 -54.924596) (xy 42.184688 -54.872301) (xy 42.176932 -54.818353) (xy 42.176446 -54.791102)
			(xy 40.278488 -54.791102) (xy 40.275396 -54.812611) (xy 40.260041 -54.864906) (xy 40.237399 -54.914483)
			(xy 40.207933 -54.960333) (xy 40.172242 -55.001524) (xy 40.131051 -55.037215) (xy 40.085201 -55.066681)
			(xy 40.035624 -55.089323) (xy 39.983329 -55.104678) (xy 39.929381 -55.112434) (xy 39.874879 -55.112434)
			(xy 39.820931 -55.104678) (xy 39.768636 -55.089323) (xy 39.719059 -55.066681) (xy 39.673209 -55.037215)
			(xy 39.632018 -55.001524) (xy 39.596327 -54.960333) (xy 39.566861 -54.914483) (xy 39.544219 -54.864906)
			(xy 39.528864 -54.812611) (xy 39.521108 -54.758663) (xy 39.520622 -54.731412) (xy 38.522679 -54.731412)
			(xy 38.582127 -55.722266) (xy 51.834032 -55.722266) (xy 51.838103 -55.666644) (xy 51.850229 -55.612207)
			(xy 51.870152 -55.560116) (xy 51.897448 -55.511481) (xy 51.931534 -55.467338) (xy 51.971683 -55.428629)
			(xy 52.017041 -55.396178) (xy 52.066641 -55.370677) (xy 52.119425 -55.35267) (xy 52.174268 -55.34254)
			(xy 52.230002 -55.340503) (xy 52.285439 -55.346603) (xy 52.339396 -55.360709) (xy 52.390725 -55.382521)
			(xy 52.438331 -55.411575) (xy 52.449477 -55.420851) (xy 54.224668 -55.420851) (xy 54.224668 -55.366349)
			(xy 54.232424 -55.312401) (xy 54.247779 -55.260107) (xy 54.270419 -55.210529) (xy 54.299884 -55.164679)
			(xy 54.335575 -55.123488) (xy 54.376764 -55.087795) (xy 54.422613 -55.058328) (xy 54.47219 -55.035685)
			(xy 54.524484 -55.020328) (xy 54.578431 -55.012569) (xy 54.605682 -55.012082) (xy 54.631995 -55.012567)
			(xy 54.684123 -55.019799) (xy 54.734765 -55.034115) (xy 54.782964 -55.055244) (xy 54.827808 -55.082787)
			(xy 54.868449 -55.116222) (xy 54.886606 -55.135272) (xy 54.894127 -55.142674) (xy 54.913407 -55.151199)
			(xy 54.923944 -55.151782) (xy 54.99862 -55.151782) (xy 55.009167 -55.151228) (xy 55.028463 -55.142711)
			(xy 55.035958 -55.135272) (xy 55.054087 -55.11619) (xy 55.094723 -55.082736) (xy 55.139569 -55.055181)
			(xy 55.187775 -55.034048) (xy 55.238427 -55.019736) (xy 55.290564 -55.012517) (xy 55.316882 -55.012082)
			(xy 55.344135 -55.012564) (xy 55.398086 -55.020319) (xy 55.450385 -55.035673) (xy 55.499966 -55.058314)
			(xy 55.54582 -55.08778) (xy 55.587014 -55.123473) (xy 55.622709 -55.164665) (xy 55.652178 -55.210518)
			(xy 55.674821 -55.260098) (xy 55.690177 -55.312396) (xy 55.697935 -55.366347) (xy 55.697935 -55.420853)
			(xy 55.690177 -55.474804) (xy 55.674821 -55.527102) (xy 55.652178 -55.576682) (xy 55.622709 -55.622535)
			(xy 55.587014 -55.663727) (xy 55.54582 -55.69942) (xy 55.499966 -55.728886) (xy 55.450385 -55.751527)
			(xy 55.398086 -55.766881) (xy 55.344135 -55.774636) (xy 55.316882 -55.775098) (xy 55.290568 -55.774643)
			(xy 55.238439 -55.767406) (xy 55.187796 -55.753084) (xy 55.139597 -55.73195) (xy 55.094753 -55.704401)
			(xy 55.054114 -55.670961) (xy 55.035958 -55.651908) (xy 55.028453 -55.644487) (xy 55.00916 -55.635974)
			(xy 54.99862 -55.635398) (xy 54.923944 -55.635398) (xy 54.913396 -55.635938) (xy 54.8941 -55.644466)
			(xy 54.886606 -55.651908) (xy 54.868442 -55.670955) (xy 54.827814 -55.704413) (xy 54.782975 -55.731973)
			(xy 54.734776 -55.753113) (xy 54.68413 -55.767432) (xy 54.631998 -55.774658) (xy 54.605682 -55.775098)
			(xy 54.578431 -55.774631) (xy 54.524484 -55.766872) (xy 54.47219 -55.751515) (xy 54.422613 -55.728872)
			(xy 54.376764 -55.699405) (xy 54.335575 -55.663712) (xy 54.299884 -55.622521) (xy 54.270419 -55.576671)
			(xy 54.247779 -55.527093) (xy 54.232424 -55.474799) (xy 54.224668 -55.420851) (xy 52.449477 -55.420851)
			(xy 52.481199 -55.44725) (xy 52.518416 -55.488787) (xy 52.549189 -55.5353) (xy 52.572861 -55.585797)
			(xy 52.588929 -55.639204) (xy 52.597049 -55.69438) (xy 52.597558 -55.722266) (xy 52.597049 -55.750152)
			(xy 52.588929 -55.805328) (xy 52.572861 -55.858735) (xy 52.549189 -55.909232) (xy 52.518416 -55.955745)
			(xy 52.481199 -55.997282) (xy 52.438331 -56.032957) (xy 52.390725 -56.062011) (xy 52.339396 -56.083823)
			(xy 52.285439 -56.097929) (xy 52.230002 -56.104029) (xy 52.174268 -56.101992) (xy 52.119425 -56.091862)
			(xy 52.066641 -56.073855) (xy 52.017041 -56.048354) (xy 51.971683 -56.015903) (xy 51.931534 -55.977194)
			(xy 51.897448 -55.933051) (xy 51.870152 -55.884416) (xy 51.850229 -55.832325) (xy 51.838103 -55.777888)
			(xy 51.834032 -55.722266) (xy 38.582127 -55.722266) (xy 38.658962 -57.002934) (xy 47.563532 -57.002934)
			(xy 47.56403 -56.974842) (xy 47.572253 -56.919264) (xy 47.588542 -56.865494) (xy 47.612544 -56.814696)
			(xy 47.643739 -56.767969) (xy 47.681452 -56.726324) (xy 47.724867 -56.690663) (xy 47.748698 -56.675782)
			(xy 47.757588 -56.670448) (xy 47.76978 -56.65343) (xy 47.7901 -56.560212) (xy 47.785782 -56.539638)
			(xy 47.77994 -56.531002) (xy 47.763931 -56.506944) (xy 47.738592 -56.45501) (xy 47.721369 -56.39985)
			(xy 47.712656 -56.342725) (xy 47.712122 -56.313832) (xy 47.712585 -56.286579) (xy 47.720339 -56.232626)
			(xy 47.735692 -56.180326) (xy 47.758333 -56.130744) (xy 47.7878 -56.08489) (xy 47.823494 -56.043696)
			(xy 47.864688 -56.008002) (xy 47.910543 -55.978534) (xy 47.960125 -55.955893) (xy 48.012424 -55.940539)
			(xy 48.066377 -55.932785) (xy 48.09363 -55.932324) (xy 48.121001 -55.932767) (xy 48.175181 -55.940589)
			(xy 48.227685 -55.956083) (xy 48.277432 -55.978931) (xy 48.323397 -56.00866) (xy 48.344328 -56.026304)
			(xy 48.344582 -56.026558) (xy 48.351665 -56.03215) (xy 48.368585 -56.038392) (xy 48.377602 -56.03875)
			(xy 48.444658 -56.03875) (xy 48.453674 -56.038384) (xy 48.470592 -56.032144) (xy 48.477678 -56.026558)
			(xy 48.477678 -56.026304) (xy 48.477932 -56.026304) (xy 48.498865 -56.008663) (xy 48.544833 -55.978939)
			(xy 48.594579 -55.956093) (xy 48.647081 -55.940597) (xy 48.701259 -55.932768) (xy 48.756001 -55.932768)
			(xy 48.810179 -55.940597) (xy 48.862681 -55.956093) (xy 48.912427 -55.978939) (xy 48.958395 -56.008663)
			(xy 48.979328 -56.026304) (xy 48.979582 -56.026558) (xy 48.986665 -56.03215) (xy 49.003585 -56.038392)
			(xy 49.012602 -56.03875) (xy 49.079658 -56.03875) (xy 49.088674 -56.038384) (xy 49.105592 -56.032144)
			(xy 49.112678 -56.026558) (xy 49.112678 -56.026304) (xy 49.112932 -56.026304) (xy 49.133879 -56.008684)
			(xy 49.179848 -55.978969) (xy 49.229592 -55.956129) (xy 49.282089 -55.940634) (xy 49.336262 -55.932801)
			(xy 49.36363 -55.932324) (xy 49.390882 -55.932748) (xy 49.444831 -55.940509) (xy 49.497127 -55.955868)
			(xy 49.546704 -55.978512) (xy 49.592555 -56.007982) (xy 49.633745 -56.043676) (xy 49.669436 -56.084869)
			(xy 49.698902 -56.130722) (xy 49.721543 -56.180301) (xy 49.736898 -56.232598) (xy 49.744654 -56.286548)
			(xy 49.744654 -56.297068) (xy 50.086512 -56.297068) (xy 50.090583 -56.241446) (xy 50.102709 -56.187009)
			(xy 50.122632 -56.134918) (xy 50.149928 -56.086283) (xy 50.184014 -56.04214) (xy 50.224163 -56.003431)
			(xy 50.269521 -55.97098) (xy 50.319121 -55.945479) (xy 50.371905 -55.927472) (xy 50.426748 -55.917342)
			(xy 50.482482 -55.915305) (xy 50.537919 -55.921405) (xy 50.591876 -55.935511) (xy 50.643205 -55.957323)
			(xy 50.690811 -55.986377) (xy 50.733679 -56.022052) (xy 50.770896 -56.063589) (xy 50.801669 -56.110102)
			(xy 50.825341 -56.160599) (xy 50.841409 -56.214006) (xy 50.849529 -56.269182) (xy 50.850038 -56.297068)
			(xy 50.849529 -56.324954) (xy 50.841409 -56.38013) (xy 50.825341 -56.433537) (xy 50.801669 -56.484034)
			(xy 50.770896 -56.530547) (xy 50.733679 -56.572084) (xy 50.690811 -56.607759) (xy 50.643205 -56.636813)
			(xy 50.591876 -56.658625) (xy 50.537919 -56.672731) (xy 50.482482 -56.678831) (xy 50.426748 -56.676794)
			(xy 50.371905 -56.666664) (xy 50.319121 -56.648657) (xy 50.269521 -56.623156) (xy 50.224163 -56.590705)
			(xy 50.184014 -56.551996) (xy 50.149928 -56.507853) (xy 50.122632 -56.459218) (xy 50.102709 -56.407127)
			(xy 50.090583 -56.35269) (xy 50.086512 -56.297068) (xy 49.744654 -56.297068) (xy 49.744654 -56.341052)
			(xy 49.736898 -56.395002) (xy 49.721543 -56.447299) (xy 49.698902 -56.496878) (xy 49.669436 -56.542731)
			(xy 49.633745 -56.583924) (xy 49.592555 -56.619618) (xy 49.546704 -56.649088) (xy 49.497127 -56.671732)
			(xy 49.444831 -56.687091) (xy 49.390882 -56.694852) (xy 49.36363 -56.69534) (xy 49.33626 -56.694871)
			(xy 49.28208 -56.687056) (xy 49.229577 -56.671569) (xy 49.17983 -56.648727) (xy 49.133863 -56.619002)
			(xy 49.112932 -56.60136) (xy 49.112678 -56.601106) (xy 49.105601 -56.595505) (xy 49.088677 -56.589267)
			(xy 49.079658 -56.588914) (xy 49.012602 -56.588914) (xy 49.003585 -56.589269) (xy 48.986668 -56.595518)
			(xy 48.979582 -56.601106) (xy 48.979582 -56.60136) (xy 48.979328 -56.60136) (xy 48.958395 -56.619001)
			(xy 48.912427 -56.648725) (xy 48.862681 -56.671571) (xy 48.810179 -56.687067) (xy 48.756001 -56.694896)
			(xy 48.701259 -56.694896) (xy 48.647081 -56.687067) (xy 48.594579 -56.671571) (xy 48.544833 -56.648725)
			(xy 48.498865 -56.619001) (xy 48.477932 -56.60136) (xy 48.477678 -56.601106) (xy 48.470601 -56.595505)
			(xy 48.453677 -56.589267) (xy 48.444658 -56.588914) (xy 48.377602 -56.588914) (xy 48.368585 -56.589269)
			(xy 48.351668 -56.595518) (xy 48.344582 -56.601106) (xy 48.344074 -56.60136) (xy 48.331339 -56.612303)
			(xy 48.304248 -56.632145) (xy 48.289972 -56.640984) (xy 48.281082 -56.646318) (xy 48.26889 -56.663336)
			(xy 48.24857 -56.756554) (xy 48.252888 -56.777128) (xy 48.25873 -56.785764) (xy 48.27472 -56.809834)
			(xy 48.300064 -56.861763) (xy 48.317293 -56.91692) (xy 48.326011 -56.974042) (xy 48.326548 -57.002934)
			(xy 48.326062 -57.030185) (xy 48.318306 -57.084133) (xy 48.302951 -57.136428) (xy 48.280309 -57.186005)
			(xy 48.250843 -57.231855) (xy 48.215152 -57.273046) (xy 48.173961 -57.308737) (xy 48.128111 -57.338203)
			(xy 48.078534 -57.360845) (xy 48.026239 -57.3762) (xy 47.972291 -57.383956) (xy 47.917789 -57.383956)
			(xy 47.863841 -57.3762) (xy 47.811546 -57.360845) (xy 47.761969 -57.338203) (xy 47.716119 -57.308737)
			(xy 47.674928 -57.273046) (xy 47.639237 -57.231855) (xy 47.609771 -57.186005) (xy 47.587129 -57.136428)
			(xy 47.571774 -57.084133) (xy 47.564018 -57.030185) (xy 47.563532 -57.002934) (xy 38.658962 -57.002934)
			(xy 38.687901 -57.48528) (xy 56.60593 -57.48528) (xy 56.610001 -57.429658) (xy 56.622127 -57.375221)
			(xy 56.64205 -57.32313) (xy 56.669346 -57.274495) (xy 56.703432 -57.230352) (xy 56.743581 -57.191643)
			(xy 56.788939 -57.159192) (xy 56.838539 -57.133691) (xy 56.891323 -57.115684) (xy 56.946166 -57.105554)
			(xy 57.0019 -57.103517) (xy 57.057337 -57.109617) (xy 57.111294 -57.123723) (xy 57.162623 -57.145535)
			(xy 57.210229 -57.174589) (xy 57.253097 -57.210264) (xy 57.290314 -57.251801) (xy 57.321087 -57.298314)
			(xy 57.344759 -57.348811) (xy 57.360827 -57.402218) (xy 57.368947 -57.457394) (xy 57.369456 -57.48528)
			(xy 57.368947 -57.513166) (xy 57.360827 -57.568342) (xy 57.344759 -57.621749) (xy 57.321087 -57.672246)
			(xy 57.290314 -57.718759) (xy 57.253097 -57.760296) (xy 57.210229 -57.795971) (xy 57.162623 -57.825025)
			(xy 57.111294 -57.846837) (xy 57.057337 -57.860943) (xy 57.0019 -57.867043) (xy 56.946166 -57.865006)
			(xy 56.891323 -57.854876) (xy 56.838539 -57.836869) (xy 56.788939 -57.811368) (xy 56.743581 -57.778917)
			(xy 56.703432 -57.740208) (xy 56.669346 -57.696065) (xy 56.64205 -57.64743) (xy 56.622127 -57.595339)
			(xy 56.610001 -57.540902) (xy 56.60593 -57.48528) (xy 38.687901 -57.48528) (xy 38.730174 -58.189876)
			(xy 38.730174 -58.191908) (xy 38.778205 -58.679334) (xy 47.995332 -58.679334) (xy 47.995745 -58.653018)
			(xy 48.00299 -58.600887) (xy 48.017319 -58.550243) (xy 48.038461 -58.502044) (xy 48.066017 -58.457202)
			(xy 48.099466 -58.416565) (xy 48.118522 -58.39841) (xy 48.125925 -58.39089) (xy 48.134448 -58.371608)
			(xy 48.135032 -58.361072) (xy 48.135032 -58.286396) (xy 48.134509 -58.275846) (xy 48.125968 -58.256551)
			(xy 48.118522 -58.249058) (xy 48.099457 -58.230912) (xy 48.066 -58.19028) (xy 48.038442 -58.145438)
			(xy 48.017305 -58.097236) (xy 48.00299 -58.046586) (xy 47.995768 -57.994451) (xy 47.995332 -57.968134)
			(xy 47.995818 -57.940883) (xy 48.003574 -57.886935) (xy 48.018929 -57.83464) (xy 48.041571 -57.785063)
			(xy 48.071037 -57.739213) (xy 48.106728 -57.698022) (xy 48.147919 -57.662331) (xy 48.193769 -57.632865)
			(xy 48.243346 -57.610223) (xy 48.295641 -57.594868) (xy 48.349589 -57.587112) (xy 48.404091 -57.587112)
			(xy 48.458039 -57.594868) (xy 48.510334 -57.610223) (xy 48.559911 -57.632865) (xy 48.605761 -57.662331)
			(xy 48.646952 -57.698022) (xy 48.682643 -57.739213) (xy 48.712109 -57.785063) (xy 48.734751 -57.83464)
			(xy 48.750106 -57.886935) (xy 48.757862 -57.940883) (xy 48.758348 -57.968134) (xy 48.75792 -57.994449)
			(xy 48.750679 -58.04658) (xy 48.743411 -58.072274) (xy 51.993544 -58.072274) (xy 51.997615 -58.016652)
			(xy 52.009741 -57.962215) (xy 52.029664 -57.910124) (xy 52.05696 -57.861489) (xy 52.091046 -57.817346)
			(xy 52.131195 -57.778637) (xy 52.176553 -57.746186) (xy 52.226153 -57.720685) (xy 52.278937 -57.702678)
			(xy 52.33378 -57.692548) (xy 52.389514 -57.690511) (xy 52.444951 -57.696611) (xy 52.498908 -57.710717)
			(xy 52.550237 -57.732529) (xy 52.597843 -57.761583) (xy 52.640711 -57.797258) (xy 52.677928 -57.838795)
			(xy 52.708701 -57.885308) (xy 52.732373 -57.935805) (xy 52.748441 -57.989212) (xy 52.756561 -58.044388)
			(xy 52.75707 -58.072274) (xy 52.757 -58.076084) (xy 57.358024 -58.076084) (xy 57.362095 -58.020462)
			(xy 57.374221 -57.966025) (xy 57.394144 -57.913934) (xy 57.42144 -57.865299) (xy 57.455526 -57.821156)
			(xy 57.495675 -57.782447) (xy 57.541033 -57.749996) (xy 57.590633 -57.724495) (xy 57.643417 -57.706488)
			(xy 57.69826 -57.696358) (xy 57.753994 -57.694321) (xy 57.809431 -57.700421) (xy 57.863388 -57.714527)
			(xy 57.914717 -57.736339) (xy 57.962323 -57.765393) (xy 58.005191 -57.801068) (xy 58.042408 -57.842605)
			(xy 58.058744 -57.867296) (xy 59.643008 -57.867296) (xy 59.647079 -57.811674) (xy 59.659205 -57.757237)
			(xy 59.679128 -57.705146) (xy 59.706424 -57.656511) (xy 59.74051 -57.612368) (xy 59.780659 -57.573659)
			(xy 59.826017 -57.541208) (xy 59.875617 -57.515707) (xy 59.928401 -57.4977) (xy 59.983244 -57.48757)
			(xy 60.038978 -57.485533) (xy 60.094415 -57.491633) (xy 60.148372 -57.505739) (xy 60.199701 -57.527551)
			(xy 60.247307 -57.556605) (xy 60.290175 -57.59228) (xy 60.327392 -57.633817) (xy 60.358165 -57.68033)
			(xy 60.381837 -57.730827) (xy 60.397905 -57.784234) (xy 60.406025 -57.83941) (xy 60.406534 -57.867296)
			(xy 60.406025 -57.895182) (xy 60.397905 -57.950358) (xy 60.381837 -58.003765) (xy 60.358165 -58.054262)
			(xy 60.327392 -58.100775) (xy 60.290175 -58.142312) (xy 60.247307 -58.177987) (xy 60.199701 -58.207041)
			(xy 60.148372 -58.228853) (xy 60.094415 -58.242959) (xy 60.038978 -58.249059) (xy 59.983244 -58.247022)
			(xy 59.928401 -58.236892) (xy 59.875617 -58.218885) (xy 59.826017 -58.193384) (xy 59.780659 -58.160933)
			(xy 59.74051 -58.122224) (xy 59.706424 -58.078081) (xy 59.679128 -58.029446) (xy 59.659205 -57.977355)
			(xy 59.647079 -57.922918) (xy 59.643008 -57.867296) (xy 58.058744 -57.867296) (xy 58.073181 -57.889118)
			(xy 58.096853 -57.939615) (xy 58.112921 -57.993022) (xy 58.121041 -58.048198) (xy 58.12155 -58.076084)
			(xy 58.121041 -58.10397) (xy 58.112921 -58.159146) (xy 58.096853 -58.212553) (xy 58.073181 -58.26305)
			(xy 58.042408 -58.309563) (xy 58.005191 -58.3511) (xy 57.962323 -58.386775) (xy 57.914717 -58.415829)
			(xy 57.863388 -58.437641) (xy 57.809431 -58.451747) (xy 57.753994 -58.457847) (xy 57.69826 -58.45581)
			(xy 57.643417 -58.44568) (xy 57.590633 -58.427673) (xy 57.541033 -58.402172) (xy 57.495675 -58.369721)
			(xy 57.455526 -58.331012) (xy 57.42144 -58.286869) (xy 57.394144 -58.238234) (xy 57.374221 -58.186143)
			(xy 57.362095 -58.131706) (xy 57.358024 -58.076084) (xy 52.757 -58.076084) (xy 52.756561 -58.10016)
			(xy 52.748441 -58.155336) (xy 52.732373 -58.208743) (xy 52.708701 -58.25924) (xy 52.677928 -58.305753)
			(xy 52.640711 -58.34729) (xy 52.597843 -58.382965) (xy 52.550237 -58.412019) (xy 52.498908 -58.433831)
			(xy 52.444951 -58.447937) (xy 52.389514 -58.454037) (xy 52.33378 -58.452) (xy 52.278937 -58.44187)
			(xy 52.226153 -58.423863) (xy 52.176553 -58.398362) (xy 52.131195 -58.365911) (xy 52.091046 -58.327202)
			(xy 52.05696 -58.283059) (xy 52.029664 -58.234424) (xy 52.009741 -58.182333) (xy 51.997615 -58.127896)
			(xy 51.993544 -58.072274) (xy 48.743411 -58.072274) (xy 48.736354 -58.097225) (xy 48.715214 -58.145424)
			(xy 48.68766 -58.190266) (xy 48.654213 -58.230903) (xy 48.635158 -58.249058) (xy 48.627781 -58.256601)
			(xy 48.619241 -58.275864) (xy 48.618648 -58.286396) (xy 48.618648 -58.361072) (xy 48.619165 -58.371623)
			(xy 48.627707 -58.39092) (xy 48.635158 -58.39841) (xy 48.654222 -58.416556) (xy 48.687677 -58.457189)
			(xy 48.715233 -58.502032) (xy 48.736369 -58.550234) (xy 48.739475 -58.561224) (xy 58.562238 -58.561224)
			(xy 58.566309 -58.505602) (xy 58.578435 -58.451165) (xy 58.598358 -58.399074) (xy 58.625654 -58.350439)
			(xy 58.65974 -58.306296) (xy 58.699889 -58.267587) (xy 58.745247 -58.235136) (xy 58.794847 -58.209635)
			(xy 58.847631 -58.191628) (xy 58.902474 -58.181498) (xy 58.958208 -58.179461) (xy 59.013645 -58.185561)
			(xy 59.067602 -58.199667) (xy 59.118931 -58.221479) (xy 59.166537 -58.250533) (xy 59.209405 -58.286208)
			(xy 59.246622 -58.327745) (xy 59.277395 -58.374258) (xy 59.301067 -58.424755) (xy 59.308577 -58.449718)
			(xy 60.808868 -58.449718) (xy 60.812939 -58.394096) (xy 60.825065 -58.339659) (xy 60.844988 -58.287568)
			(xy 60.872284 -58.238933) (xy 60.90637 -58.19479) (xy 60.946519 -58.156081) (xy 60.991877 -58.12363)
			(xy 61.041477 -58.098129) (xy 61.094261 -58.080122) (xy 61.149104 -58.069992) (xy 61.204838 -58.067955)
			(xy 61.260275 -58.074055) (xy 61.314232 -58.088161) (xy 61.365561 -58.109973) (xy 61.413167 -58.139027)
			(xy 61.456035 -58.174702) (xy 61.493252 -58.216239) (xy 61.524025 -58.262752) (xy 61.547697 -58.313249)
			(xy 61.563765 -58.366656) (xy 61.571885 -58.421832) (xy 61.572394 -58.449718) (xy 61.571885 -58.477604)
			(xy 61.563765 -58.53278) (xy 61.547697 -58.586187) (xy 61.524025 -58.636684) (xy 61.493252 -58.683197)
			(xy 61.456035 -58.724734) (xy 61.413167 -58.760409) (xy 61.365561 -58.789463) (xy 61.314232 -58.811275)
			(xy 61.260275 -58.825381) (xy 61.204838 -58.831481) (xy 61.149104 -58.829444) (xy 61.094261 -58.819314)
			(xy 61.041477 -58.801307) (xy 60.991877 -58.775806) (xy 60.946519 -58.743355) (xy 60.90637 -58.704646)
			(xy 60.872284 -58.660503) (xy 60.844988 -58.611868) (xy 60.825065 -58.559777) (xy 60.812939 -58.50534)
			(xy 60.808868 -58.449718) (xy 59.308577 -58.449718) (xy 59.317135 -58.478162) (xy 59.325255 -58.533338)
			(xy 59.325764 -58.561224) (xy 59.325255 -58.58911) (xy 59.317135 -58.644286) (xy 59.301067 -58.697693)
			(xy 59.277395 -58.74819) (xy 59.246622 -58.794703) (xy 59.209405 -58.83624) (xy 59.166537 -58.871915)
			(xy 59.118931 -58.900969) (xy 59.067602 -58.922781) (xy 59.013645 -58.936887) (xy 58.958208 -58.942987)
			(xy 58.902474 -58.94095) (xy 58.847631 -58.93082) (xy 58.794847 -58.912813) (xy 58.745247 -58.887312)
			(xy 58.699889 -58.854861) (xy 58.65974 -58.816152) (xy 58.625654 -58.772009) (xy 58.598358 -58.723374)
			(xy 58.578435 -58.671283) (xy 58.566309 -58.616846) (xy 58.562238 -58.561224) (xy 48.739475 -58.561224)
			(xy 48.750685 -58.600883) (xy 48.75791 -58.653018) (xy 48.758348 -58.679334) (xy 48.757862 -58.706585)
			(xy 48.750106 -58.760533) (xy 48.734751 -58.812828) (xy 48.712109 -58.862405) (xy 48.682643 -58.908255)
			(xy 48.646952 -58.949446) (xy 48.605761 -58.985137) (xy 48.559911 -59.014603) (xy 48.510334 -59.037245)
			(xy 48.458039 -59.0526) (xy 48.404091 -59.060356) (xy 48.349589 -59.060356) (xy 48.295641 -59.0526)
			(xy 48.243346 -59.037245) (xy 48.193769 -59.014603) (xy 48.147919 -58.985137) (xy 48.106728 -58.949446)
			(xy 48.071037 -58.908255) (xy 48.041571 -58.862405) (xy 48.018929 -58.812828) (xy 48.003574 -58.760533)
			(xy 47.995818 -58.706585) (xy 47.995332 -58.679334) (xy 38.778205 -58.679334) (xy 38.81755 -59.078622)
			(xy 38.81885 -59.09281) (xy 38.820249 -59.121271) (xy 38.820344 -59.135518) (xy 38.820344 -59.174634)
			(xy 57.093102 -59.174634) (xy 57.097173 -59.119012) (xy 57.109299 -59.064575) (xy 57.129222 -59.012484)
			(xy 57.156518 -58.963849) (xy 57.190604 -58.919706) (xy 57.230753 -58.880997) (xy 57.276111 -58.848546)
			(xy 57.325711 -58.823045) (xy 57.378495 -58.805038) (xy 57.433338 -58.794908) (xy 57.489072 -58.792871)
			(xy 57.544509 -58.798971) (xy 57.598466 -58.813077) (xy 57.649795 -58.834889) (xy 57.697401 -58.863943)
			(xy 57.740269 -58.899618) (xy 57.777486 -58.941155) (xy 57.808259 -58.987668) (xy 57.831931 -59.038165)
			(xy 57.847999 -59.091572) (xy 57.856119 -59.146748) (xy 57.856628 -59.174634) (xy 57.856119 -59.20252)
			(xy 57.847999 -59.257696) (xy 57.831931 -59.311103) (xy 57.808259 -59.3616) (xy 57.777486 -59.408113)
			(xy 57.740269 -59.44965) (xy 57.697401 -59.485325) (xy 57.649795 -59.514379) (xy 57.598466 -59.536191)
			(xy 57.544509 -59.550297) (xy 57.489072 -59.556397) (xy 57.433338 -59.55436) (xy 57.378495 -59.54423)
			(xy 57.325711 -59.526223) (xy 57.276111 -59.500722) (xy 57.230753 -59.468271) (xy 57.190604 -59.429562)
			(xy 57.156518 -59.385419) (xy 57.129222 -59.336784) (xy 57.109299 -59.284693) (xy 57.097173 -59.230256)
			(xy 57.093102 -59.174634) (xy 38.820344 -59.174634) (xy 38.820344 -59.696604) (xy 38.839781 -60.019251)
			(xy 48.135784 -60.019251) (xy 48.135784 -59.964749) (xy 48.14354 -59.910803) (xy 48.158895 -59.85851)
			(xy 48.181535 -59.808934) (xy 48.211 -59.763084) (xy 48.246691 -59.721895) (xy 48.287879 -59.686204)
			(xy 48.333728 -59.656738) (xy 48.383304 -59.634097) (xy 48.435597 -59.618741) (xy 48.489543 -59.610984)
			(xy 48.516794 -59.610498) (xy 48.544164 -59.610968) (xy 48.598343 -59.618785) (xy 48.650846 -59.634273)
			(xy 48.700593 -59.657114) (xy 48.74656 -59.686837) (xy 48.767492 -59.704478) (xy 48.767746 -59.704732)
			(xy 48.774841 -59.710306) (xy 48.791751 -59.716559) (xy 48.800766 -59.716924) (xy 48.867822 -59.716924)
			(xy 48.876839 -59.716573) (xy 48.893756 -59.710321) (xy 48.900842 -59.704732) (xy 48.900842 -59.704478)
			(xy 48.901096 -59.704478) (xy 48.922029 -59.686837) (xy 48.967997 -59.657113) (xy 49.017743 -59.634267)
			(xy 49.070245 -59.618771) (xy 49.124423 -59.610942) (xy 49.179165 -59.610942) (xy 49.233343 -59.618771)
			(xy 49.285845 -59.634267) (xy 49.335591 -59.657113) (xy 49.381559 -59.686837) (xy 49.402492 -59.704478)
			(xy 49.402746 -59.704732) (xy 49.409841 -59.710306) (xy 49.426751 -59.716559) (xy 49.435766 -59.716924)
			(xy 49.502822 -59.716924) (xy 49.511839 -59.716573) (xy 49.528756 -59.710321) (xy 49.535842 -59.704732)
			(xy 49.535842 -59.704478) (xy 49.536096 -59.704478) (xy 49.557016 -59.686824) (xy 49.602992 -59.657115)
			(xy 49.652743 -59.634282) (xy 49.705246 -59.618795) (xy 49.759424 -59.61097) (xy 49.786794 -59.610498)
			(xy 49.814048 -59.610949) (xy 49.868 -59.618705) (xy 49.920299 -59.634061) (xy 49.969881 -59.656704)
			(xy 50.015736 -59.686172) (xy 50.05693 -59.721866) (xy 50.092624 -59.76306) (xy 50.122094 -59.808914)
			(xy 50.144737 -59.858495) (xy 50.160093 -59.910794) (xy 50.167851 -59.964746) (xy 50.167851 -60.019254)
			(xy 50.160093 -60.073206) (xy 50.144737 -60.125505) (xy 50.122094 -60.175086) (xy 50.092624 -60.22094)
			(xy 50.05693 -60.262134) (xy 50.015736 -60.297828) (xy 49.969881 -60.327296) (xy 49.920299 -60.349939)
			(xy 49.868 -60.365295) (xy 49.814048 -60.373051) (xy 49.786794 -60.373514) (xy 49.759424 -60.373048)
			(xy 49.705245 -60.36523) (xy 49.652742 -60.34974) (xy 49.602995 -60.326899) (xy 49.557028 -60.297175)
			(xy 49.536096 -60.279534) (xy 49.535842 -60.27928) (xy 49.528749 -60.273703) (xy 49.511837 -60.267451)
			(xy 49.502822 -60.267088) (xy 49.435766 -60.267088) (xy 49.426748 -60.267431) (xy 49.409831 -60.273688)
			(xy 49.402746 -60.27928) (xy 49.402492 -60.279534) (xy 49.381559 -60.297175) (xy 49.335591 -60.326899)
			(xy 49.285845 -60.349745) (xy 49.233343 -60.365241) (xy 49.179165 -60.37307) (xy 49.124423 -60.37307)
			(xy 49.070245 -60.365241) (xy 49.017743 -60.349745) (xy 48.967997 -60.326899) (xy 48.922029 -60.297175)
			(xy 48.901096 -60.279534) (xy 48.900842 -60.27928) (xy 48.893749 -60.273703) (xy 48.876837 -60.267451)
			(xy 48.867822 -60.267088) (xy 48.800766 -60.267088) (xy 48.791748 -60.267431) (xy 48.774831 -60.273688)
			(xy 48.767746 -60.27928) (xy 48.767746 -60.279534) (xy 48.767492 -60.279534) (xy 48.746578 -60.297196)
			(xy 48.7006 -60.326903) (xy 48.650848 -60.349734) (xy 48.598343 -60.36522) (xy 48.544164 -60.373043)
			(xy 48.516794 -60.373514) (xy 48.489543 -60.373016) (xy 48.435597 -60.365259) (xy 48.383304 -60.349903)
			(xy 48.333728 -60.327262) (xy 48.287879 -60.297796) (xy 48.246691 -60.262105) (xy 48.211 -60.220916)
			(xy 48.181535 -60.175066) (xy 48.158895 -60.12549) (xy 48.14354 -60.073197) (xy 48.135784 -60.019251)
			(xy 38.839781 -60.019251) (xy 38.840664 -60.033916) (xy 38.84168 -60.069984) (xy 38.840645 -60.633356)
			(xy 59.796932 -60.633356) (xy 59.801003 -60.577734) (xy 59.813129 -60.523297) (xy 59.833052 -60.471206)
			(xy 59.860348 -60.422571) (xy 59.894434 -60.378428) (xy 59.934583 -60.339719) (xy 59.979941 -60.307268)
			(xy 60.029541 -60.281767) (xy 60.082325 -60.26376) (xy 60.137168 -60.25363) (xy 60.192902 -60.251593)
			(xy 60.248339 -60.257693) (xy 60.302296 -60.271799) (xy 60.353625 -60.293611) (xy 60.401231 -60.322665)
			(xy 60.444099 -60.35834) (xy 60.481316 -60.399877) (xy 60.512089 -60.44639) (xy 60.535761 -60.496887)
			(xy 60.551829 -60.550294) (xy 60.559949 -60.60547) (xy 60.560458 -60.633356) (xy 60.559949 -60.661242)
			(xy 60.551829 -60.716418) (xy 60.535761 -60.769825) (xy 60.512089 -60.820322) (xy 60.481316 -60.866835)
			(xy 60.444099 -60.908372) (xy 60.401231 -60.944047) (xy 60.353625 -60.973101) (xy 60.302296 -60.994913)
			(xy 60.248339 -61.009019) (xy 60.192902 -61.015119) (xy 60.137168 -61.013082) (xy 60.082325 -61.002952)
			(xy 60.029541 -60.984945) (xy 59.979941 -60.959444) (xy 59.934583 -60.926993) (xy 59.894434 -60.888284)
			(xy 59.860348 -60.844141) (xy 59.833052 -60.795506) (xy 59.813129 -60.743415) (xy 59.801003 -60.688978)
			(xy 59.796932 -60.633356) (xy 38.840645 -60.633356) (xy 38.83914 -61.451998) (xy 38.83914 -61.487812)
			(xy 58.304428 -61.487812) (xy 58.308499 -61.43219) (xy 58.320625 -61.377753) (xy 58.340548 -61.325662)
			(xy 58.367844 -61.277027) (xy 58.40193 -61.232884) (xy 58.442079 -61.194175) (xy 58.487437 -61.161724)
			(xy 58.537037 -61.136223) (xy 58.589821 -61.118216) (xy 58.644664 -61.108086) (xy 58.700398 -61.106049)
			(xy 58.755835 -61.112149) (xy 58.809792 -61.126255) (xy 58.861121 -61.148067) (xy 58.908727 -61.177121)
			(xy 58.951595 -61.212796) (xy 58.988812 -61.254333) (xy 59.019585 -61.300846) (xy 59.043257 -61.351343)
			(xy 59.059325 -61.40475) (xy 59.067445 -61.459926) (xy 59.067954 -61.487812) (xy 59.067445 -61.515698)
			(xy 59.059325 -61.570874) (xy 59.043257 -61.624281) (xy 59.019585 -61.674778) (xy 58.988812 -61.721291)
			(xy 58.951595 -61.762828) (xy 58.908727 -61.798503) (xy 58.861121 -61.827557) (xy 58.809792 -61.849369)
			(xy 58.755835 -61.863475) (xy 58.700398 -61.869575) (xy 58.644664 -61.867538) (xy 58.589821 -61.857408)
			(xy 58.537037 -61.839401) (xy 58.487437 -61.8139) (xy 58.442079 -61.781449) (xy 58.40193 -61.74274)
			(xy 58.367844 -61.698597) (xy 58.340548 -61.649962) (xy 58.320625 -61.597871) (xy 58.308499 -61.543434)
			(xy 58.304428 -61.487812) (xy 38.83914 -61.487812) (xy 38.83914 -62.121034) (xy 56.242202 -62.121034)
			(xy 56.246273 -62.065412) (xy 56.258399 -62.010975) (xy 56.278322 -61.958884) (xy 56.305618 -61.910249)
			(xy 56.339704 -61.866106) (xy 56.379853 -61.827397) (xy 56.425211 -61.794946) (xy 56.474811 -61.769445)
			(xy 56.527595 -61.751438) (xy 56.582438 -61.741308) (xy 56.638172 -61.739271) (xy 56.693609 -61.745371)
			(xy 56.747566 -61.759477) (xy 56.798895 -61.781289) (xy 56.846501 -61.810343) (xy 56.889369 -61.846018)
			(xy 56.926586 -61.887555) (xy 56.957359 -61.934068) (xy 56.981031 -61.984565) (xy 56.997099 -62.037972)
			(xy 57.005219 -62.093148) (xy 57.005728 -62.121034) (xy 57.005219 -62.14892) (xy 56.997099 -62.204096)
			(xy 56.981031 -62.257503) (xy 56.957359 -62.308) (xy 56.926586 -62.354513) (xy 56.889369 -62.39605)
			(xy 56.846501 -62.431725) (xy 56.798895 -62.460779) (xy 56.747566 -62.482591) (xy 56.693609 -62.496697)
			(xy 56.638172 -62.502797) (xy 56.582438 -62.50076) (xy 56.527595 -62.49063) (xy 56.474811 -62.472623)
			(xy 56.425211 -62.447122) (xy 56.379853 -62.414671) (xy 56.339704 -62.375962) (xy 56.305618 -62.331819)
			(xy 56.278322 -62.283184) (xy 56.258399 -62.231093) (xy 56.246273 -62.176656) (xy 56.242202 -62.121034)
			(xy 38.83914 -62.121034) (xy 38.83914 -63.213553) (xy 48.120765 -63.213553) (xy 48.120765 -63.159047)
			(xy 48.128522 -63.105097) (xy 48.143878 -63.0528) (xy 48.166521 -63.003221) (xy 48.195989 -62.957369)
			(xy 48.231682 -62.916177) (xy 48.272875 -62.880484) (xy 48.318728 -62.851017) (xy 48.368308 -62.828376)
			(xy 48.420605 -62.813021) (xy 48.474555 -62.805265) (xy 48.501808 -62.804802) (xy 48.529178 -62.805263)
			(xy 48.583358 -62.813082) (xy 48.635861 -62.828572) (xy 48.685608 -62.851415) (xy 48.731574 -62.88114)
			(xy 48.752506 -62.898782) (xy 48.75276 -62.899036) (xy 48.759851 -62.904616) (xy 48.776765 -62.910866)
			(xy 48.78578 -62.911228) (xy 48.852836 -62.911228) (xy 48.861854 -62.910882) (xy 48.87877 -62.904626)
			(xy 48.885856 -62.899036) (xy 48.885856 -62.898782) (xy 48.88611 -62.898782) (xy 48.907043 -62.881141)
			(xy 48.953011 -62.851417) (xy 49.002757 -62.828571) (xy 49.055259 -62.813075) (xy 49.109437 -62.805246)
			(xy 49.164179 -62.805246) (xy 49.218357 -62.813075) (xy 49.270859 -62.828571) (xy 49.320605 -62.851417)
			(xy 49.366573 -62.881141) (xy 49.387506 -62.898782) (xy 49.38776 -62.899036) (xy 49.394851 -62.904616)
			(xy 49.411765 -62.910866) (xy 49.42078 -62.911228) (xy 49.487836 -62.911228) (xy 49.496854 -62.910882)
			(xy 49.51377 -62.904626) (xy 49.520856 -62.899036) (xy 49.520856 -62.898782) (xy 49.52111 -62.898782)
			(xy 49.542025 -62.881122) (xy 49.588003 -62.851414) (xy 49.637755 -62.828582) (xy 49.690259 -62.813096)
			(xy 49.744438 -62.805273) (xy 49.771808 -62.804802) (xy 49.79906 -62.805268) (xy 49.853008 -62.813026)
			(xy 49.905303 -62.828382) (xy 49.954881 -62.851024) (xy 50.000731 -62.880492) (xy 50.041922 -62.916184)
			(xy 50.077613 -62.957375) (xy 50.107079 -63.003226) (xy 50.129721 -63.052804) (xy 50.139537 -63.086234)
			(xy 53.387496 -63.086234) (xy 53.391567 -63.030612) (xy 53.403693 -62.976175) (xy 53.423616 -62.924084)
			(xy 53.450912 -62.875449) (xy 53.484998 -62.831306) (xy 53.525147 -62.792597) (xy 53.570505 -62.760146)
			(xy 53.620105 -62.734645) (xy 53.672889 -62.716638) (xy 53.727732 -62.706508) (xy 53.783466 -62.704471)
			(xy 53.838903 -62.710571) (xy 53.89286 -62.724677) (xy 53.913008 -62.733239) (xy 59.66605 -62.733239)
			(xy 59.666052 -62.678732) (xy 59.673812 -62.62478) (xy 59.68917 -62.572481) (xy 59.711816 -62.522901)
			(xy 59.741287 -62.477048) (xy 59.776983 -62.435856) (xy 59.818179 -62.400164) (xy 59.864035 -62.370697)
			(xy 59.913618 -62.348057) (xy 59.965918 -62.332704) (xy 60.01987 -62.32495) (xy 60.047124 -62.324488)
			(xy 60.070679 -62.324864) (xy 60.117423 -62.330724) (xy 60.140342 -62.336172) (xy 60.154099 -62.339206)
			(xy 60.182248 -62.338351) (xy 60.209096 -62.329845) (xy 60.232603 -62.314335) (xy 60.250983 -62.292997)
			(xy 60.262842 -62.267453) (xy 60.26728 -62.239643) (xy 60.263957 -62.211676) (xy 60.25896 -62.198504)
			(xy 60.249649 -62.175114) (xy 60.236524 -62.126514) (xy 60.229901 -62.076609) (xy 60.229496 -62.051438)
			(xy 60.229914 -62.024182) (xy 60.237667 -61.970224) (xy 60.25302 -61.917918) (xy 60.275661 -61.86833)
			(xy 60.305128 -61.822469) (xy 60.340822 -61.781268) (xy 60.382017 -61.745567) (xy 60.427873 -61.716092)
			(xy 60.477458 -61.693443) (xy 60.52976 -61.678081) (xy 60.583717 -61.670319) (xy 60.638229 -61.670315)
			(xy 60.692187 -61.678069) (xy 60.744492 -61.693424) (xy 60.79408 -61.716066) (xy 60.83994 -61.745535)
			(xy 60.88114 -61.78123) (xy 60.91684 -61.822426) (xy 60.946314 -61.868283) (xy 60.968961 -61.917868)
			(xy 60.984322 -61.970172) (xy 60.992082 -62.024129) (xy 60.992084 -62.078641) (xy 60.984328 -62.132598)
			(xy 60.968972 -62.184903) (xy 60.946329 -62.23449) (xy 60.916858 -62.280349) (xy 60.881162 -62.321548)
			(xy 60.839965 -62.357247) (xy 60.794107 -62.386719) (xy 60.744521 -62.409365) (xy 60.692217 -62.424724)
			(xy 60.63826 -62.432483) (xy 60.611004 -62.432946) (xy 60.58745 -62.432564) (xy 60.540705 -62.426708)
			(xy 60.517786 -62.421262) (xy 60.504031 -62.41821) (xy 60.475875 -62.419059) (xy 60.44902 -62.427562)
			(xy 60.425507 -62.443074) (xy 60.407123 -62.464417) (xy 60.395265 -62.489968) (xy 60.390833 -62.517785)
			(xy 60.394165 -62.545756) (xy 60.399168 -62.55893) (xy 60.40849 -62.582315) (xy 60.421611 -62.630918)
			(xy 60.428229 -62.680824) (xy 60.428632 -62.705996) (xy 60.428149 -62.73325) (xy 60.420392 -62.787202)
			(xy 60.405036 -62.839501) (xy 60.382393 -62.889083) (xy 60.352924 -62.934937) (xy 60.31723 -62.976131)
			(xy 60.276036 -63.011825) (xy 60.230182 -63.041294) (xy 60.1806 -63.063937) (xy 60.128301 -63.079292)
			(xy 60.074348 -63.087049) (xy 60.019841 -63.087048) (xy 59.965889 -63.07929) (xy 59.91359 -63.063933)
			(xy 59.864009 -63.041289) (xy 59.818155 -63.011819) (xy 59.776963 -62.976123) (xy 59.741269 -62.934929)
			(xy 59.711802 -62.889073) (xy 59.68916 -62.839491) (xy 59.673806 -62.787192) (xy 59.66605 -62.733239)
			(xy 53.913008 -62.733239) (xy 53.944189 -62.746489) (xy 53.991795 -62.775543) (xy 54.034663 -62.811218)
			(xy 54.07188 -62.852755) (xy 54.102653 -62.899268) (xy 54.126325 -62.949765) (xy 54.142393 -63.003172)
			(xy 54.150513 -63.058348) (xy 54.151022 -63.086234) (xy 54.150513 -63.11412) (xy 54.142393 -63.169296)
			(xy 54.126325 -63.222703) (xy 54.102653 -63.2732) (xy 54.1025 -63.273432) (xy 55.576722 -63.273432)
			(xy 55.580793 -63.21781) (xy 55.592919 -63.163373) (xy 55.612842 -63.111282) (xy 55.640138 -63.062647)
			(xy 55.674224 -63.018504) (xy 55.714373 -62.979795) (xy 55.759731 -62.947344) (xy 55.809331 -62.921843)
			(xy 55.862115 -62.903836) (xy 55.916958 -62.893706) (xy 55.972692 -62.891669) (xy 56.028129 -62.897769)
			(xy 56.082086 -62.911875) (xy 56.133415 -62.933687) (xy 56.181021 -62.962741) (xy 56.223889 -62.998416)
			(xy 56.261106 -63.039953) (xy 56.291879 -63.086466) (xy 56.315551 -63.136963) (xy 56.331619 -63.19037)
			(xy 56.339739 -63.245546) (xy 56.340248 -63.273432) (xy 56.339739 -63.301318) (xy 56.331619 -63.356494)
			(xy 56.315551 -63.409901) (xy 56.291879 -63.460398) (xy 56.261106 -63.506911) (xy 56.223889 -63.548448)
			(xy 56.181021 -63.584123) (xy 56.133415 -63.613177) (xy 56.082086 -63.634989) (xy 56.028129 -63.649095)
			(xy 55.972692 -63.655195) (xy 55.916958 -63.653158) (xy 55.862115 -63.643028) (xy 55.809331 -63.625021)
			(xy 55.759731 -63.59952) (xy 55.714373 -63.567069) (xy 55.674224 -63.52836) (xy 55.640138 -63.484217)
			(xy 55.612842 -63.435582) (xy 55.592919 -63.383491) (xy 55.580793 -63.329054) (xy 55.576722 -63.273432)
			(xy 54.1025 -63.273432) (xy 54.07188 -63.319713) (xy 54.034663 -63.36125) (xy 53.991795 -63.396925)
			(xy 53.944189 -63.425979) (xy 53.89286 -63.447791) (xy 53.838903 -63.461897) (xy 53.783466 -63.467997)
			(xy 53.727732 -63.46596) (xy 53.672889 -63.45583) (xy 53.620105 -63.437823) (xy 53.570505 -63.412322)
			(xy 53.525147 -63.379871) (xy 53.484998 -63.341162) (xy 53.450912 -63.297019) (xy 53.423616 -63.248384)
			(xy 53.403693 -63.196293) (xy 53.391567 -63.141856) (xy 53.387496 -63.086234) (xy 50.139537 -63.086234)
			(xy 50.145076 -63.1051) (xy 50.152832 -63.159048) (xy 50.152832 -63.213552) (xy 50.145076 -63.2675)
			(xy 50.129721 -63.319796) (xy 50.107079 -63.369374) (xy 50.077613 -63.415225) (xy 50.041922 -63.456416)
			(xy 50.000731 -63.492108) (xy 49.954881 -63.521576) (xy 49.905303 -63.544218) (xy 49.853008 -63.559574)
			(xy 49.79906 -63.567332) (xy 49.771808 -63.567818) (xy 49.744437 -63.567367) (xy 49.690256 -63.559549)
			(xy 49.637752 -63.544057) (xy 49.588006 -63.521212) (xy 49.54204 -63.491482) (xy 49.52111 -63.473838)
			(xy 49.520856 -63.473584) (xy 49.513759 -63.468013) (xy 49.49685 -63.461757) (xy 49.487836 -63.461392)
			(xy 49.42078 -63.461392) (xy 49.411762 -63.461741) (xy 49.394846 -63.467995) (xy 49.38776 -63.473584)
			(xy 49.387506 -63.473838) (xy 49.366573 -63.491479) (xy 49.320605 -63.521203) (xy 49.270859 -63.544049)
			(xy 49.218357 -63.559545) (xy 49.164179 -63.567374) (xy 49.109437 -63.567374) (xy 49.055259 -63.559545)
			(xy 49.002757 -63.544049) (xy 48.953011 -63.521203) (xy 48.907043 -63.491479) (xy 48.88611 -63.473838)
			(xy 48.885856 -63.473584) (xy 48.878759 -63.468013) (xy 48.86185 -63.461757) (xy 48.852836 -63.461392)
			(xy 48.78578 -63.461392) (xy 48.776762 -63.461741) (xy 48.759846 -63.467995) (xy 48.75276 -63.473584)
			(xy 48.75276 -63.473838) (xy 48.752506 -63.473838) (xy 48.731588 -63.491494) (xy 48.685611 -63.521202)
			(xy 48.635859 -63.544034) (xy 48.583356 -63.559522) (xy 48.529178 -63.567346) (xy 48.501808 -63.567818)
			(xy 48.474555 -63.567335) (xy 48.420605 -63.559579) (xy 48.368308 -63.544224) (xy 48.318728 -63.521583)
			(xy 48.272875 -63.492116) (xy 48.231682 -63.456423) (xy 48.195989 -63.415231) (xy 48.166521 -63.369379)
			(xy 48.143878 -63.3198) (xy 48.128522 -63.267503) (xy 48.120765 -63.213553) (xy 38.83914 -63.213553)
			(xy 38.83914 -64.312292) (xy 58.9059 -64.312292) (xy 58.909971 -64.25667) (xy 58.922097 -64.202233)
			(xy 58.94202 -64.150142) (xy 58.969316 -64.101507) (xy 59.003402 -64.057364) (xy 59.043551 -64.018655)
			(xy 59.088909 -63.986204) (xy 59.138509 -63.960703) (xy 59.191293 -63.942696) (xy 59.246136 -63.932566)
			(xy 59.30187 -63.930529) (xy 59.357307 -63.936629) (xy 59.411264 -63.950735) (xy 59.462593 -63.972547)
			(xy 59.510199 -64.001601) (xy 59.553067 -64.037276) (xy 59.590284 -64.078813) (xy 59.621057 -64.125326)
			(xy 59.644729 -64.175823) (xy 59.660797 -64.22923) (xy 59.668917 -64.284406) (xy 59.669426 -64.312292)
			(xy 59.668917 -64.340178) (xy 59.660797 -64.395354) (xy 59.644729 -64.448761) (xy 59.621057 -64.499258)
			(xy 59.590284 -64.545771) (xy 59.553067 -64.587308) (xy 59.510199 -64.622983) (xy 59.462593 -64.652037)
			(xy 59.411264 -64.673849) (xy 59.357307 -64.687955) (xy 59.30187 -64.694055) (xy 59.246136 -64.692018)
			(xy 59.191293 -64.681888) (xy 59.138509 -64.663881) (xy 59.088909 -64.63838) (xy 59.043551 -64.605929)
			(xy 59.003402 -64.56722) (xy 58.969316 -64.523077) (xy 58.94202 -64.474442) (xy 58.922097 -64.422351)
			(xy 58.909971 -64.367914) (xy 58.9059 -64.312292) (xy 38.83914 -64.312292) (xy 38.83914 -65.100962)
			(xy 46.132494 -65.100962) (xy 46.136565 -65.04534) (xy 46.148691 -64.990903) (xy 46.168614 -64.938812)
			(xy 46.19591 -64.890177) (xy 46.229996 -64.846034) (xy 46.270145 -64.807325) (xy 46.315503 -64.774874)
			(xy 46.365103 -64.749373) (xy 46.417887 -64.731366) (xy 46.47273 -64.721236) (xy 46.528464 -64.719199)
			(xy 46.583901 -64.725299) (xy 46.637858 -64.739405) (xy 46.689187 -64.761217) (xy 46.736793 -64.790271)
			(xy 46.779661 -64.825946) (xy 46.816878 -64.867483) (xy 46.847651 -64.913996) (xy 46.871323 -64.964493)
			(xy 46.887391 -65.0179) (xy 46.895511 -65.073076) (xy 46.89602 -65.100962) (xy 46.895511 -65.128848)
			(xy 46.887391 -65.184024) (xy 46.871323 -65.237431) (xy 46.847651 -65.287928) (xy 46.816878 -65.334441)
			(xy 46.779661 -65.375978) (xy 46.736793 -65.411653) (xy 46.689187 -65.440707) (xy 46.637858 -65.462519)
			(xy 46.583901 -65.476625) (xy 46.528464 -65.482725) (xy 46.47273 -65.480688) (xy 46.417887 -65.470558)
			(xy 46.365103 -65.452551) (xy 46.315503 -65.42705) (xy 46.270145 -65.394599) (xy 46.229996 -65.35589)
			(xy 46.19591 -65.311747) (xy 46.168614 -65.263112) (xy 46.148691 -65.211021) (xy 46.136565 -65.156584)
			(xy 46.132494 -65.100962) (xy 38.83914 -65.100962) (xy 38.83914 -65.75552) (xy 40.346628 -65.75552)
			(xy 40.350699 -65.699898) (xy 40.362825 -65.645461) (xy 40.382748 -65.59337) (xy 40.410044 -65.544735)
			(xy 40.44413 -65.500592) (xy 40.484279 -65.461883) (xy 40.529637 -65.429432) (xy 40.579237 -65.403931)
			(xy 40.632021 -65.385924) (xy 40.686864 -65.375794) (xy 40.742598 -65.373757) (xy 40.798035 -65.379857)
			(xy 40.851992 -65.393963) (xy 40.903321 -65.415775) (xy 40.950927 -65.444829) (xy 40.993795 -65.480504)
			(xy 41.031012 -65.522041) (xy 41.061785 -65.568554) (xy 41.085457 -65.619051) (xy 41.101525 -65.672458)
			(xy 41.109645 -65.727634) (xy 41.110154 -65.75552) (xy 41.109645 -65.783406) (xy 41.101525 -65.838582)
			(xy 41.085457 -65.891989) (xy 41.061785 -65.942486) (xy 41.031012 -65.988999) (xy 40.993795 -66.030536)
			(xy 40.950927 -66.066211) (xy 40.903321 -66.095265) (xy 40.851992 -66.117077) (xy 40.798035 -66.131183)
			(xy 40.742598 -66.137283) (xy 40.686864 -66.135246) (xy 40.632021 -66.125116) (xy 40.579237 -66.107109)
			(xy 40.529637 -66.081608) (xy 40.484279 -66.049157) (xy 40.44413 -66.010448) (xy 40.410044 -65.966305)
			(xy 40.382748 -65.91767) (xy 40.362825 -65.865579) (xy 40.350699 -65.811142) (xy 40.346628 -65.75552)
			(xy 38.83914 -65.75552) (xy 38.83914 -67.12895) (xy 40.366698 -67.12895) (xy 40.366698 -67.07445)
			(xy 40.374454 -67.020506) (xy 40.389808 -66.968214) (xy 40.412448 -66.91864) (xy 40.441912 -66.872792)
			(xy 40.477601 -66.831604) (xy 40.518789 -66.795915) (xy 40.564636 -66.76645) (xy 40.614211 -66.74381)
			(xy 40.666502 -66.728455) (xy 40.720446 -66.720699) (xy 40.747696 -66.720212) (xy 40.775066 -66.720677)
			(xy 40.829246 -66.728495) (xy 40.881749 -66.743984) (xy 40.931496 -66.766826) (xy 40.977462 -66.796551)
			(xy 40.998394 -66.814192) (xy 40.998648 -66.814446) (xy 41.005741 -66.820023) (xy 41.022653 -66.826274)
			(xy 41.031668 -66.826638) (xy 41.098724 -66.826638) (xy 41.107741 -66.826284) (xy 41.124658 -66.820034)
			(xy 41.131744 -66.814446) (xy 41.131744 -66.814192) (xy 41.131998 -66.814192) (xy 41.152919 -66.796539)
			(xy 41.198895 -66.76683) (xy 41.248645 -66.743996) (xy 41.301148 -66.728509) (xy 41.355326 -66.720684)
			(xy 41.382696 -66.720212) (xy 41.409951 -66.720635) (xy 41.463905 -66.728392) (xy 41.516206 -66.743748)
			(xy 41.565789 -66.766392) (xy 41.611645 -66.795861) (xy 41.652841 -66.831557) (xy 41.688537 -66.872752)
			(xy 41.718007 -66.918607) (xy 41.740651 -66.96819) (xy 41.756008 -67.020491) (xy 41.763765 -67.074446)
			(xy 41.763765 -67.128954) (xy 41.756008 -67.182909) (xy 41.740651 -67.23521) (xy 41.718007 -67.284793)
			(xy 41.688537 -67.330648) (xy 41.652841 -67.371843) (xy 41.611645 -67.407539) (xy 41.565789 -67.437008)
			(xy 41.516206 -67.459652) (xy 41.463905 -67.475008) (xy 41.409951 -67.482765) (xy 41.382696 -67.483228)
			(xy 41.355325 -67.482782) (xy 41.301144 -67.474962) (xy 41.24864 -67.459469) (xy 41.198894 -67.436623)
			(xy 41.152928 -67.406892) (xy 41.131998 -67.389248) (xy 41.131744 -67.388994) (xy 41.124649 -67.383419)
			(xy 41.107739 -67.377166) (xy 41.098724 -67.376802) (xy 41.031668 -67.376802) (xy 41.02265 -67.377143)
			(xy 41.005733 -67.383402) (xy 40.998648 -67.388994) (xy 40.998648 -67.389248) (xy 40.998394 -67.389248)
			(xy 40.977468 -67.406895) (xy 40.931495 -67.436608) (xy 40.881746 -67.459443) (xy 40.829243 -67.474932)
			(xy 40.775066 -67.482756) (xy 40.747696 -67.483228) (xy 40.720446 -67.482701) (xy 40.666502 -67.474945)
			(xy 40.614211 -67.45959) (xy 40.564636 -67.43695) (xy 40.518789 -67.407485) (xy 40.477601 -67.371796)
			(xy 40.441912 -67.330608) (xy 40.412448 -67.28476) (xy 40.389808 -67.235186) (xy 40.374454 -67.182894)
			(xy 40.366698 -67.12895) (xy 38.83914 -67.12895) (xy 38.83914 -67.488054) (xy 44.779182 -67.488054)
			(xy 44.783253 -67.432432) (xy 44.795379 -67.377995) (xy 44.815302 -67.325904) (xy 44.842598 -67.277269)
			(xy 44.876684 -67.233126) (xy 44.916833 -67.194417) (xy 44.962191 -67.161966) (xy 45.011791 -67.136465)
			(xy 45.064575 -67.118458) (xy 45.119418 -67.108328) (xy 45.175152 -67.106291) (xy 45.230589 -67.112391)
			(xy 45.284546 -67.126497) (xy 45.335875 -67.148309) (xy 45.383481 -67.177363) (xy 45.426349 -67.213038)
			(xy 45.463566 -67.254575) (xy 45.494339 -67.301088) (xy 45.518011 -67.351585) (xy 45.534079 -67.404992)
			(xy 45.542199 -67.460168) (xy 45.542708 -67.488054) (xy 45.542199 -67.51594) (xy 45.539014 -67.537584)
			(xy 46.07128 -67.537584) (xy 46.075351 -67.481962) (xy 46.087477 -67.427525) (xy 46.1074 -67.375434)
			(xy 46.134696 -67.326799) (xy 46.168782 -67.282656) (xy 46.208931 -67.243947) (xy 46.254289 -67.211496)
			(xy 46.303889 -67.185995) (xy 46.356673 -67.167988) (xy 46.411516 -67.157858) (xy 46.46725 -67.155821)
			(xy 46.522687 -67.161921) (xy 46.576644 -67.176027) (xy 46.627973 -67.197839) (xy 46.675579 -67.226893)
			(xy 46.718447 -67.262568) (xy 46.755664 -67.304105) (xy 46.786437 -67.350618) (xy 46.810109 -67.401115)
			(xy 46.826177 -67.454522) (xy 46.834297 -67.509698) (xy 46.834806 -67.537584) (xy 46.834297 -67.56547)
			(xy 46.830252 -67.592956) (xy 47.345344 -67.592956) (xy 47.349415 -67.537334) (xy 47.361541 -67.482897)
			(xy 47.381464 -67.430806) (xy 47.40876 -67.382171) (xy 47.442846 -67.338028) (xy 47.482995 -67.299319)
			(xy 47.528353 -67.266868) (xy 47.577953 -67.241367) (xy 47.630737 -67.22336) (xy 47.68558 -67.21323)
			(xy 47.741314 -67.211193) (xy 47.796751 -67.217293) (xy 47.850708 -67.231399) (xy 47.902037 -67.253211)
			(xy 47.949643 -67.282265) (xy 47.992511 -67.31794) (xy 48.029728 -67.359477) (xy 48.060501 -67.40599)
			(xy 48.084173 -67.456487) (xy 48.100241 -67.509894) (xy 48.108358 -67.565048) (xy 50.446716 -67.565048)
			(xy 50.446716 -67.510552) (xy 50.454472 -67.456611) (xy 50.469824 -67.404323) (xy 50.492462 -67.354751)
			(xy 50.521924 -67.308906) (xy 50.557611 -67.267721) (xy 50.598795 -67.232033) (xy 50.644639 -67.202569)
			(xy 50.69421 -67.179929) (xy 50.746497 -67.164574) (xy 50.800438 -67.156817) (xy 50.827686 -67.15633)
			(xy 50.855056 -67.156797) (xy 50.909236 -67.164613) (xy 50.961739 -67.180102) (xy 51.011486 -67.202944)
			(xy 51.057453 -67.232668) (xy 51.078384 -67.25031) (xy 51.078638 -67.250564) (xy 51.085733 -67.256138)
			(xy 51.102643 -67.262391) (xy 51.111658 -67.262756) (xy 51.178714 -67.262756) (xy 51.187733 -67.262415)
			(xy 51.20465 -67.256158) (xy 51.211734 -67.250564) (xy 51.211734 -67.25031) (xy 51.211988 -67.25031)
			(xy 51.232915 -67.232665) (xy 51.278889 -67.202953) (xy 51.328638 -67.180118) (xy 51.38114 -67.164629)
			(xy 51.435316 -67.156803) (xy 51.462686 -67.15633) (xy 51.489942 -67.156716) (xy 51.5439 -67.164472)
			(xy 51.596205 -67.179828) (xy 51.645792 -67.202472) (xy 51.691651 -67.231943) (xy 51.73285 -67.26764)
			(xy 51.768549 -67.308837) (xy 51.798021 -67.354696) (xy 51.820667 -67.404282) (xy 51.836025 -67.456586)
			(xy 51.843783 -67.510544) (xy 51.843783 -67.565056) (xy 51.836025 -67.619014) (xy 51.820667 -67.671318)
			(xy 51.798021 -67.720904) (xy 51.768549 -67.766763) (xy 51.73285 -67.80796) (xy 51.691651 -67.843657)
			(xy 51.645792 -67.873128) (xy 51.596205 -67.895772) (xy 51.5439 -67.911128) (xy 51.489942 -67.918884)
			(xy 51.462686 -67.919346) (xy 51.435315 -67.918901) (xy 51.381134 -67.91108) (xy 51.32863 -67.895587)
			(xy 51.278884 -67.87274) (xy 51.232918 -67.84301) (xy 51.211988 -67.825366) (xy 51.211734 -67.825112)
			(xy 51.204641 -67.819535) (xy 51.187729 -67.813282) (xy 51.178714 -67.81292) (xy 51.111658 -67.81292)
			(xy 51.102643 -67.813301) (xy 51.085726 -67.819531) (xy 51.078638 -67.825112) (xy 51.078638 -67.825366)
			(xy 51.078384 -67.825366) (xy 51.057427 -67.842974) (xy 51.011461 -67.872692) (xy 50.96172 -67.895534)
			(xy 50.909225 -67.911032) (xy 50.855054 -67.918868) (xy 50.827686 -67.919346) (xy 50.800438 -67.918783)
			(xy 50.746497 -67.911026) (xy 50.69421 -67.895671) (xy 50.644639 -67.873031) (xy 50.598795 -67.843567)
			(xy 50.557611 -67.807879) (xy 50.521924 -67.766694) (xy 50.492462 -67.720849) (xy 50.469824 -67.671277)
			(xy 50.454472 -67.618989) (xy 50.446716 -67.565048) (xy 48.108358 -67.565048) (xy 48.108361 -67.56507)
			(xy 48.10887 -67.592956) (xy 48.108361 -67.620842) (xy 48.100241 -67.676018) (xy 48.084173 -67.729425)
			(xy 48.060501 -67.779922) (xy 48.029728 -67.826435) (xy 47.992511 -67.867972) (xy 47.949643 -67.903647)
			(xy 47.902037 -67.932701) (xy 47.850708 -67.954513) (xy 47.796751 -67.968619) (xy 47.741314 -67.974719)
			(xy 47.68558 -67.972682) (xy 47.630737 -67.962552) (xy 47.577953 -67.944545) (xy 47.528353 -67.919044)
			(xy 47.482995 -67.886593) (xy 47.442846 -67.847884) (xy 47.40876 -67.803741) (xy 47.381464 -67.755106)
			(xy 47.361541 -67.703015) (xy 47.349415 -67.648578) (xy 47.345344 -67.592956) (xy 46.830252 -67.592956)
			(xy 46.826177 -67.620646) (xy 46.810109 -67.674053) (xy 46.786437 -67.72455) (xy 46.755664 -67.771063)
			(xy 46.718447 -67.8126) (xy 46.675579 -67.848275) (xy 46.627973 -67.877329) (xy 46.576644 -67.899141)
			(xy 46.522687 -67.913247) (xy 46.46725 -67.919347) (xy 46.411516 -67.91731) (xy 46.356673 -67.90718)
			(xy 46.303889 -67.889173) (xy 46.254289 -67.863672) (xy 46.208931 -67.831221) (xy 46.168782 -67.792512)
			(xy 46.134696 -67.748369) (xy 46.1074 -67.699734) (xy 46.087477 -67.647643) (xy 46.075351 -67.593206)
			(xy 46.07128 -67.537584) (xy 45.539014 -67.537584) (xy 45.534079 -67.571116) (xy 45.518011 -67.624523)
			(xy 45.494339 -67.67502) (xy 45.463566 -67.721533) (xy 45.426349 -67.76307) (xy 45.383481 -67.798745)
			(xy 45.335875 -67.827799) (xy 45.284546 -67.849611) (xy 45.230589 -67.863717) (xy 45.175152 -67.869817)
			(xy 45.119418 -67.86778) (xy 45.064575 -67.85765) (xy 45.011791 -67.839643) (xy 44.962191 -67.814142)
			(xy 44.916833 -67.781691) (xy 44.876684 -67.742982) (xy 44.842598 -67.698839) (xy 44.815302 -67.650204)
			(xy 44.795379 -67.598113) (xy 44.783253 -67.543676) (xy 44.779182 -67.488054) (xy 38.83914 -67.488054)
			(xy 38.83914 -68.586604) (xy 42.625264 -68.586604) (xy 42.625717 -68.559233) (xy 42.633535 -68.505053)
			(xy 42.649027 -68.452549) (xy 42.671872 -68.402802) (xy 42.701601 -68.356837) (xy 42.719244 -68.335906)
			(xy 42.719498 -68.335652) (xy 42.725069 -68.328555) (xy 42.731325 -68.311646) (xy 42.73169 -68.302632)
			(xy 42.73169 -68.235576) (xy 42.731347 -68.226558) (xy 42.72509 -68.209641) (xy 42.719498 -68.202556)
			(xy 42.719244 -68.202556) (xy 42.719244 -68.202302) (xy 42.701599 -68.181374) (xy 42.671887 -68.135401)
			(xy 42.649051 -68.085652) (xy 42.633562 -68.033151) (xy 42.625736 -67.978974) (xy 42.625264 -67.951604)
			(xy 42.625781 -67.924354) (xy 42.633537 -67.870409) (xy 42.64889 -67.818117) (xy 42.671529 -67.768541)
			(xy 42.700992 -67.722692) (xy 42.73668 -67.681503) (xy 42.777866 -67.645811) (xy 42.823713 -67.616344)
			(xy 42.873287 -67.593701) (xy 42.925578 -67.578343) (xy 42.979522 -67.570584) (xy 43.006772 -67.570096)
			(xy 43.033088 -67.570517) (xy 43.085218 -67.577761) (xy 43.135862 -67.59209) (xy 43.18406 -67.613231)
			(xy 43.228903 -67.640785) (xy 43.269541 -67.674231) (xy 43.287696 -67.693286) (xy 43.295219 -67.700686)
			(xy 43.314498 -67.709212) (xy 43.325034 -67.709796) (xy 43.39971 -67.709796) (xy 43.410262 -67.709287)
			(xy 43.429557 -67.700738) (xy 43.437048 -67.693286) (xy 43.455184 -67.674212) (xy 43.495819 -67.640757)
			(xy 43.540663 -67.6132) (xy 43.588867 -67.592065) (xy 43.639518 -67.577752) (xy 43.691655 -67.570532)
			(xy 43.717972 -67.570096) (xy 43.745342 -67.570579) (xy 43.79952 -67.578393) (xy 43.852023 -67.593878)
			(xy 43.90177 -67.616716) (xy 43.947738 -67.646437) (xy 43.96867 -67.664076) (xy 43.968924 -67.66433)
			(xy 43.975997 -67.669936) (xy 43.992924 -67.67617) (xy 44.001944 -67.676522) (xy 44.069 -67.676522)
			(xy 44.078016 -67.67616) (xy 44.094933 -67.669915) (xy 44.10202 -67.66433) (xy 44.10202 -67.664076)
			(xy 44.102274 -67.664076) (xy 44.123202 -67.646432) (xy 44.169176 -67.616722) (xy 44.218925 -67.593887)
			(xy 44.271426 -67.578397) (xy 44.325603 -67.57057) (xy 44.352972 -67.570096) (xy 44.380224 -67.570581)
			(xy 44.434175 -67.578335) (xy 44.486472 -67.593687) (xy 44.536053 -67.616327) (xy 44.581906 -67.645792)
			(xy 44.623099 -67.681484) (xy 44.658793 -67.722675) (xy 44.688262 -67.768526) (xy 44.710904 -67.818105)
			(xy 44.72626 -67.870402) (xy 44.734017 -67.924352) (xy 44.73448 -67.951604) (xy 44.734021 -67.978975)
			(xy 44.726202 -68.033154) (xy 44.710712 -68.085658) (xy 44.687868 -68.135404) (xy 44.658142 -68.181371)
			(xy 44.6405 -68.202302) (xy 44.640246 -68.202556) (xy 44.634665 -68.209646) (xy 44.628416 -68.22656)
			(xy 44.628054 -68.235576) (xy 44.628054 -68.302632) (xy 44.628384 -68.311652) (xy 44.634649 -68.328569)
			(xy 44.640246 -68.335652) (xy 44.6405 -68.335652) (xy 44.6405 -68.335906) (xy 44.658155 -68.356825)
			(xy 44.687865 -68.402801) (xy 44.710698 -68.452552) (xy 44.726185 -68.505056) (xy 44.734008 -68.559234)
			(xy 44.73448 -68.586604) (xy 44.734048 -68.613858) (xy 44.72629 -68.667812) (xy 44.710932 -68.720112)
			(xy 44.694299 -68.75653) (xy 48.170338 -68.75653) (xy 48.170812 -68.72916) (xy 48.178627 -68.674981)
			(xy 48.194113 -68.622477) (xy 48.216954 -68.57273) (xy 48.246677 -68.526764) (xy 48.264318 -68.505832)
			(xy 48.264572 -68.505578) (xy 48.270182 -68.498508) (xy 48.276413 -68.481578) (xy 48.276764 -68.472558)
			(xy 48.276764 -68.405502) (xy 48.276414 -68.396484) (xy 48.270162 -68.379567) (xy 48.264572 -68.372482)
			(xy 48.264318 -68.372482) (xy 48.264318 -68.372228) (xy 48.246681 -68.351294) (xy 48.216969 -68.305322)
			(xy 48.194132 -68.255575) (xy 48.17864 -68.203075) (xy 48.170812 -68.148899) (xy 48.170338 -68.12153)
			(xy 48.170783 -68.094276) (xy 48.178537 -68.040322) (xy 48.193892 -67.988021) (xy 48.216534 -67.938438)
			(xy 48.246004 -67.892582) (xy 48.281699 -67.851388) (xy 48.322895 -67.815694) (xy 48.368752 -67.786227)
			(xy 48.418336 -67.763586) (xy 48.470637 -67.748234) (xy 48.524592 -67.740482) (xy 48.551846 -67.740022)
			(xy 48.579215 -67.740514) (xy 48.633394 -67.748325) (xy 48.685897 -67.763808) (xy 48.735644 -67.786644)
			(xy 48.781612 -67.816363) (xy 48.802544 -67.834002) (xy 48.802798 -67.834256) (xy 48.809876 -67.839855)
			(xy 48.8268 -67.846093) (xy 48.835818 -67.846448) (xy 48.902874 -67.846448) (xy 48.911891 -67.84609)
			(xy 48.928809 -67.839844) (xy 48.935894 -67.834256) (xy 48.935894 -67.834002) (xy 48.936148 -67.834002)
			(xy 48.957089 -67.816374) (xy 49.003059 -67.786661) (xy 49.052805 -67.763822) (xy 49.105303 -67.748329)
			(xy 49.159477 -67.740498) (xy 49.186846 -67.740022) (xy 49.213161 -67.740452) (xy 49.265292 -67.747693)
			(xy 49.315935 -67.762019) (xy 49.364134 -67.783159) (xy 49.408977 -67.810712) (xy 49.449615 -67.844157)
			(xy 49.46777 -67.863212) (xy 49.475299 -67.870604) (xy 49.494574 -67.879134) (xy 49.505108 -67.879722)
			(xy 49.579784 -67.879722) (xy 49.590333 -67.879191) (xy 49.609628 -67.870657) (xy 49.617122 -67.863212)
			(xy 49.635276 -67.844155) (xy 49.675906 -67.810698) (xy 49.720746 -67.783138) (xy 49.768948 -67.762)
			(xy 49.819595 -67.747683) (xy 49.87173 -67.74046) (xy 49.898046 -67.740022) (xy 49.9253 -67.740435)
			(xy 49.979252 -67.748199) (xy 50.03155 -67.763561) (xy 50.081129 -67.78621) (xy 50.126981 -67.815684)
			(xy 50.168171 -67.851383) (xy 50.203862 -67.89258) (xy 50.233327 -67.938438) (xy 50.255965 -67.988022)
			(xy 50.271318 -68.040323) (xy 50.27907 -68.094276) (xy 50.279554 -68.12153) (xy 50.279117 -68.148901)
			(xy 50.271294 -68.203082) (xy 50.255798 -68.255586) (xy 50.23295 -68.305332) (xy 50.203219 -68.351298)
			(xy 50.185574 -68.372228) (xy 50.18532 -68.372482) (xy 50.179725 -68.379563) (xy 50.173486 -68.396484)
			(xy 50.173128 -68.405502) (xy 50.173128 -68.472558) (xy 50.173499 -68.481574) (xy 50.179736 -68.498491)
			(xy 50.18532 -68.505578) (xy 50.185574 -68.505578) (xy 50.185574 -68.505832) (xy 50.203191 -68.526782)
			(xy 50.232907 -68.57275) (xy 50.255747 -68.622492) (xy 50.271244 -68.674989) (xy 50.279077 -68.729162)
			(xy 50.279554 -68.75653) (xy 50.27905 -68.78378) (xy 50.271291 -68.837725) (xy 50.255934 -68.890016)
			(xy 50.233293 -68.93959) (xy 50.203828 -68.985438) (xy 50.168138 -69.026627) (xy 50.126951 -69.062318)
			(xy 50.081105 -69.091785) (xy 50.031531 -69.114429) (xy 49.97924 -69.129787) (xy 49.925296 -69.137549)
			(xy 49.898046 -69.138038) (xy 49.87173 -69.137626) (xy 49.819598 -69.130383) (xy 49.768954 -69.116054)
			(xy 49.720754 -69.094911) (xy 49.675912 -69.067355) (xy 49.635276 -69.033905) (xy 49.617122 -69.014848)
			(xy 49.609588 -69.007461) (xy 49.590318 -68.998927) (xy 49.579784 -68.998338) (xy 49.505108 -68.998338)
			(xy 49.494556 -68.998847) (xy 49.47526 -69.007395) (xy 49.46777 -69.014848) (xy 49.449631 -69.03392)
			(xy 49.408997 -69.067374) (xy 49.364153 -69.09493) (xy 49.315949 -69.116065) (xy 49.265299 -69.130379)
			(xy 49.213163 -69.137601) (xy 49.186846 -69.138038) (xy 49.159476 -69.13756) (xy 49.105297 -69.129747)
			(xy 49.052793 -69.114262) (xy 49.003046 -69.091422) (xy 48.957079 -69.061699) (xy 48.936148 -69.044058)
			(xy 48.935894 -69.043804) (xy 48.928813 -69.038209) (xy 48.911892 -69.031967) (xy 48.902874 -69.031612)
			(xy 48.835818 -69.031612) (xy 48.826802 -69.031975) (xy 48.809884 -69.038218) (xy 48.802798 -69.043804)
			(xy 48.802798 -69.044058) (xy 48.802544 -69.044058) (xy 48.781601 -69.061683) (xy 48.735632 -69.091399)
			(xy 48.685887 -69.114238) (xy 48.633389 -69.129732) (xy 48.579215 -69.137563) (xy 48.551846 -69.138038)
			(xy 48.524596 -69.137502) (xy 48.470649 -69.129752) (xy 48.418354 -69.114403) (xy 48.368776 -69.091768)
			(xy 48.322924 -69.062308) (xy 48.281732 -69.026622) (xy 48.246038 -68.985437) (xy 48.216568 -68.939591)
			(xy 48.193923 -68.890017) (xy 48.178564 -68.837725) (xy 48.170803 -68.78378) (xy 48.170338 -68.75653)
			(xy 44.694299 -68.75653) (xy 44.688287 -68.769694) (xy 44.658816 -68.815548) (xy 44.623119 -68.856742)
			(xy 44.581923 -68.892435) (xy 44.536066 -68.921902) (xy 44.486482 -68.944543) (xy 44.43418 -68.959897)
			(xy 44.380226 -68.967651) (xy 44.352972 -68.968112) (xy 44.325601 -68.967659) (xy 44.271422 -68.959838)
			(xy 44.218919 -68.944345) (xy 44.169172 -68.921501) (xy 44.123206 -68.891774) (xy 44.102274 -68.874132)
			(xy 44.10202 -68.873878) (xy 44.094934 -68.868291) (xy 44.078017 -68.862045) (xy 44.069 -68.861686)
			(xy 44.001944 -68.861686) (xy 43.99293 -68.862067) (xy 43.976013 -68.868298) (xy 43.968924 -68.873878)
			(xy 43.968924 -68.874132) (xy 43.96867 -68.874132) (xy 43.947726 -68.891757) (xy 43.901756 -68.92147)
			(xy 43.852012 -68.944308) (xy 43.799514 -68.959802) (xy 43.74534 -68.967635) (xy 43.717972 -68.968112)
			(xy 43.691658 -68.967659) (xy 43.639529 -68.960421) (xy 43.588886 -68.946099) (xy 43.540687 -68.924963)
			(xy 43.495844 -68.897415) (xy 43.455204 -68.863974) (xy 43.437048 -68.844922) (xy 43.429545 -68.837499)
			(xy 43.410251 -68.828986) (xy 43.39971 -68.828412) (xy 43.325034 -68.828412) (xy 43.314484 -68.828942)
			(xy 43.295189 -68.837476) (xy 43.287696 -68.844922) (xy 43.26954 -68.863977) (xy 43.22891 -68.897433)
			(xy 43.184069 -68.924992) (xy 43.135869 -68.94613) (xy 43.085222 -68.960448) (xy 43.033088 -68.967673)
			(xy 43.006772 -68.968112) (xy 42.97952 -68.967648) (xy 42.925572 -68.959888) (xy 42.873277 -68.94453)
			(xy 42.8237 -68.921885) (xy 42.77785 -68.892417) (xy 42.73666 -68.856723) (xy 42.700969 -68.815531)
			(xy 42.671503 -68.769679) (xy 42.648862 -68.7201) (xy 42.633507 -68.667805) (xy 42.62575 -68.613856)
			(xy 42.625264 -68.586604) (xy 38.83914 -68.586604) (xy 38.83914 -71.555864) (xy 45.194472 -71.555864)
			(xy 45.198543 -71.500242) (xy 45.210669 -71.445805) (xy 45.230592 -71.393714) (xy 45.257888 -71.345079)
			(xy 45.291974 -71.300936) (xy 45.332123 -71.262227) (xy 45.377481 -71.229776) (xy 45.427081 -71.204275)
			(xy 45.479865 -71.186268) (xy 45.534708 -71.176138) (xy 45.590442 -71.174101) (xy 45.645879 -71.180201)
			(xy 45.699836 -71.194307) (xy 45.751165 -71.216119) (xy 45.798771 -71.245173) (xy 45.841639 -71.280848)
			(xy 45.878856 -71.322385) (xy 45.909629 -71.368898) (xy 45.933301 -71.419395) (xy 45.949369 -71.472802)
			(xy 45.957489 -71.527978) (xy 45.957998 -71.555864) (xy 45.957489 -71.58375) (xy 45.95165 -71.623428)
			(xy 46.703486 -71.623428) (xy 46.707557 -71.567806) (xy 46.719683 -71.513369) (xy 46.739606 -71.461278)
			(xy 46.766902 -71.412643) (xy 46.800988 -71.3685) (xy 46.841137 -71.329791) (xy 46.886495 -71.29734)
			(xy 46.936095 -71.271839) (xy 46.988879 -71.253832) (xy 47.043722 -71.243702) (xy 47.099456 -71.241665)
			(xy 47.154893 -71.247765) (xy 47.20885 -71.261871) (xy 47.260179 -71.283683) (xy 47.307785 -71.312737)
			(xy 47.350653 -71.348412) (xy 47.38787 -71.389949) (xy 47.418643 -71.436462) (xy 47.442315 -71.486959)
			(xy 47.458383 -71.540366) (xy 47.466503 -71.595542) (xy 47.467012 -71.623428) (xy 47.466503 -71.651314)
			(xy 47.458383 -71.70649) (xy 47.442315 -71.759897) (xy 47.418643 -71.810394) (xy 47.38787 -71.856907)
			(xy 47.350653 -71.898444) (xy 47.307785 -71.934119) (xy 47.260179 -71.963173) (xy 47.20885 -71.984985)
			(xy 47.154893 -71.999091) (xy 47.099456 -72.005191) (xy 47.043722 -72.003154) (xy 46.988879 -71.993024)
			(xy 46.936095 -71.975017) (xy 46.886495 -71.949516) (xy 46.841137 -71.917065) (xy 46.800988 -71.878356)
			(xy 46.766902 -71.834213) (xy 46.739606 -71.785578) (xy 46.719683 -71.733487) (xy 46.707557 -71.67905)
			(xy 46.703486 -71.623428) (xy 45.95165 -71.623428) (xy 45.949369 -71.638926) (xy 45.933301 -71.692333)
			(xy 45.909629 -71.74283) (xy 45.878856 -71.789343) (xy 45.841639 -71.83088) (xy 45.798771 -71.866555)
			(xy 45.751165 -71.895609) (xy 45.699836 -71.917421) (xy 45.645879 -71.931527) (xy 45.590442 -71.937627)
			(xy 45.534708 -71.93559) (xy 45.479865 -71.92546) (xy 45.427081 -71.907453) (xy 45.377481 -71.881952)
			(xy 45.332123 -71.849501) (xy 45.291974 -71.810792) (xy 45.257888 -71.766649) (xy 45.230592 -71.718014)
			(xy 45.210669 -71.665923) (xy 45.198543 -71.611486) (xy 45.194472 -71.555864) (xy 38.83914 -71.555864)
			(xy 38.83914 -72.881998) (xy 38.839564 -72.892067) (xy 38.847282 -72.910669) (xy 38.854126 -72.918066)
			(xy 41.42613 -75.49007) (xy 41.433529 -75.496915) (xy 41.452127 -75.504643) (xy 41.462198 -75.505056)
			(xy 61.283342 -75.505056) (xy 61.288233 -75.50492) (xy 61.297825 -75.503002) (xy 61.302392 -75.501246)
			(xy 61.305186 -75.50023) (xy 61.312552 -75.497182) (xy 61.319156 -75.491086) (xy 61.319664 -75.490578)
			(xy 61.348112 -75.465432) (xy 61.374229 -75.444511) (xy 61.430405 -75.408144) (xy 61.490377 -75.378451)
			(xy 61.553354 -75.355821) (xy 61.618509 -75.340553) (xy 61.684984 -75.332848) (xy 61.718444 -75.332336)
			(xy 65.255394 -75.332336) (xy 65.265442 -75.331914) (xy 65.284003 -75.324211) (xy 65.298193 -75.309981)
			(xy 65.302384 -75.30084) (xy 65.30848 -75.286616) (xy 65.302384 -75.256644) (xy 63.23457 -73.18883)
			(xy 63.21146 -73.165052) (xy 63.170128 -73.113199) (xy 63.134861 -73.057044) (xy 63.106102 -72.997294)
			(xy 63.084214 -72.934701) (xy 63.069471 -72.87005) (xy 63.062058 -72.804155) (xy 63.061596 -72.771)
			(xy 63.061596 -56.815482) (xy 62.566042 -46.732698) (xy 62.565194 -46.723297) (xy 62.557489 -46.706079)
			(xy 62.551056 -46.69917) (xy 53.521102 -37.668962) (xy 53.507386 -37.661596) (xy 53.499766 -37.660326)
			(xy 53.464587 -37.653427) (xy 53.396101 -37.632226) (xy 53.330681 -37.602903) (xy 53.269284 -37.565888)
			(xy 53.212812 -37.521724) (xy 53.187092 -37.49675) (xy 52.836572 -37.14623) (xy 52.811612 -37.120529)
			(xy 52.76745 -37.064112) (xy 52.730435 -37.002769) (xy 52.70111 -36.9374) (xy 52.679906 -36.868964)
			(xy 52.672996 -36.83381) (xy 52.659026 -36.806886) (xy 52.652676 -36.800536) (xy 52.615808 -36.794273)
			(xy 52.543924 -36.773655) (xy 52.475211 -36.744141) (xy 52.410767 -36.706202) (xy 52.351618 -36.660443)
			(xy 52.324762 -36.63442) (xy 51.974242 -36.2839) (xy 51.949281 -36.258199) (xy 51.905117 -36.201784)
			(xy 51.8681 -36.140441) (xy 51.838775 -36.075072) (xy 51.817572 -36.006635) (xy 51.810666 -35.97148)
			(xy 51.796696 -35.944556) (xy 51.790346 -35.938206) (xy 51.753479 -35.931941) (xy 51.681598 -35.911319)
			(xy 51.612888 -35.881801) (xy 51.548448 -35.843859) (xy 51.489303 -35.798097) (xy 51.462432 -35.77209)
			(xy 51.111912 -35.42157) (xy 51.086949 -35.39587) (xy 51.04278 -35.339457) (xy 51.005758 -35.278115)
			(xy 50.976427 -35.212747) (xy 50.955217 -35.14431) (xy 50.948336 -35.10915) (xy 50.934366 -35.082226)
			(xy 50.928016 -35.075876) (xy 50.89115 -35.06961) (xy 50.819268 -35.048987) (xy 50.750559 -35.019469)
			(xy 50.686118 -34.981528) (xy 50.626972 -34.935768) (xy 50.600102 -34.90976) (xy 50.249582 -34.55924)
			(xy 50.224603 -34.533523) (xy 50.180413 -34.477066) (xy 50.143386 -34.415672) (xy 50.114068 -34.350246)
			(xy 50.09289 -34.28175) (xy 50.086006 -34.246566) (xy 50.084736 -34.238946) (xy 50.07737 -34.22523)
			(xy 49.89957 -34.04743) (xy 49.872832 -34.019821) (xy 49.82599 -33.958886) (xy 49.787444 -33.892392)
			(xy 49.757844 -33.821462) (xy 49.74717 -33.78454) (xy 49.745392 -33.777936) (xy 49.739042 -33.767014)
			(xy 49.71796 -33.745932) (xy 49.691893 -33.719105) (xy 49.646151 -33.659918) (xy 49.608373 -33.595356)
			(xy 49.57918 -33.526485) (xy 49.559056 -33.454441) (xy 49.553114 -33.41751) (xy 49.552352 -33.411922)
			(xy 49.544478 -33.391602) (xy 49.54016 -33.38576) (xy 49.539906 -33.385506) (xy 49.521078 -33.360105)
			(xy 49.488434 -33.305952) (xy 49.461846 -33.248582) (xy 49.441629 -33.18867) (xy 49.428019 -33.126921)
			(xy 49.421177 -33.064062) (xy 49.42078 -33.032446) (xy 49.42078 -32.590232) (xy 49.421273 -32.5564)
			(xy 49.429122 -32.489192) (xy 49.444707 -32.423346) (xy 49.467817 -32.35975) (xy 49.498141 -32.299261)
			(xy 49.516284 -32.2707) (xy 49.516538 -32.270446) (xy 49.519965 -32.264767) (xy 49.524078 -32.252161)
			(xy 49.524666 -32.245554) (xy 49.525428 -32.232346) (xy 49.516792 -32.215328) (xy 49.515268 -32.212788)
			(xy 49.51476 -32.212026) (xy 49.50698 -32.199903) (xy 49.492494 -32.174999) (xy 49.485804 -32.162242)
			(xy 49.470056 -32.129222) (xy 49.458259 -32.101486) (xy 49.439806 -32.044105) (xy 49.427392 -31.985123)
			(xy 49.421149 -31.925172) (xy 49.42078 -31.895034) (xy 49.42078 -31.45282) (xy 49.421266 -31.419044)
			(xy 49.429087 -31.351948) (xy 49.444625 -31.286208) (xy 49.467673 -31.22271) (xy 49.497918 -31.162309)
			(xy 49.51603 -31.133796) (xy 49.516284 -31.133542) (xy 49.520348 -31.127192) (xy 49.522634 -31.119826)
			(xy 49.524928 -31.110532) (xy 49.523244 -31.091477) (xy 49.519332 -31.082742) (xy 49.516792 -31.077916)
			(xy 49.515268 -31.075376) (xy 49.51476 -31.074614) (xy 49.50698 -31.062491) (xy 49.492495 -31.037587)
			(xy 49.485804 -31.02483) (xy 49.470056 -30.99181) (xy 49.45826 -30.964074) (xy 49.439808 -30.906693)
			(xy 49.427395 -30.84771) (xy 49.421153 -30.787759) (xy 49.42078 -30.757622) (xy 49.42078 -30.330902)
			(xy 49.4204 -30.292658) (xy 49.428468 -30.216602) (xy 49.446439 -30.142261) (xy 49.459642 -30.106366)
			(xy 49.459896 -30.105858) (xy 49.460658 -30.103826) (xy 49.461674 -30.10154) (xy 49.461674 -30.101032)
			(xy 49.464214 -30.09519) (xy 49.468024 -30.085792) (xy 49.468024 -30.055566) (xy 49.467875 -30.049698)
			(xy 49.465181 -30.038275) (xy 49.46269 -30.03296) (xy 49.458118 -30.023562) (xy 49.457864 -30.023308)
			(xy 49.44872 -30.00248) (xy 49.448212 -30.000956) (xy 49.445164 -29.994352) (xy 49.445926 -29.991558)
			(xy 49.436528 -29.974286) (xy 49.431612 -29.9661) (xy 49.416994 -29.953834) (xy 49.40808 -29.95041)
			(xy 49.405794 -29.949648) (xy 49.377762 -29.938925) (xy 49.323872 -29.912498) (xy 49.272985 -29.880668)
			(xy 49.249076 -29.862526) (xy 49.238371 -29.854124) (xy 49.217662 -29.836464) (xy 49.207674 -29.82722)
			(xy 49.202594 -29.822394) (xy 48.8823 -29.501846) (xy 48.856353 -29.475143) (xy 48.810747 -29.41629)
			(xy 48.791368 -29.384498) (xy 48.774237 -29.354283) (xy 48.746471 -29.290614) (xy 48.735996 -29.257498)
			(xy 48.726598 -29.222446) (xy 48.72482 -29.21508) (xy 48.32096 -28.81122) (xy 48.315471 -28.806037)
			(xy 48.302157 -28.798938) (xy 48.294798 -28.79725) (xy 48.07839 -28.754324) (xy 48.068484 -28.753308)
			(xy 46.932088 -28.753308) (xy 46.899426 -28.752854) (xy 46.834516 -28.745512) (xy 46.770837 -28.730945)
			(xy 46.709191 -28.709335) (xy 46.650353 -28.680956) (xy 46.595066 -28.646163) (xy 46.544024 -28.605396)
			(xy 46.520608 -28.58262) (xy 46.270672 -28.332684) (xy 46.263276 -28.325833) (xy 46.244677 -28.318095)
			(xy 46.234604 -28.317698) (xy 46.20006 -28.331414) (xy 46.178732 -28.350683) (xy 46.131369 -28.383246)
			(xy 46.079657 -28.408335) (xy 46.024767 -28.425383) (xy 45.96794 -28.434005) (xy 45.939202 -28.434538)
			(xy 45.938694 -28.434538) (xy 45.910789 -28.434008) (xy 45.855577 -28.425847) (xy 45.828712 -28.418282)
			(xy 45.81398 -28.415996) (xy 45.803975 -28.416488) (xy 45.785489 -28.424151) (xy 45.771342 -28.438303)
			(xy 45.763684 -28.456791) (xy 45.76318 -28.466796) (xy 45.76318 -29.114242) (xy 45.76269 -29.144226)
			(xy 45.754862 -29.203682) (xy 45.739341 -29.261607) (xy 45.716392 -29.317011) (xy 45.686408 -29.368945)
			(xy 45.649902 -29.416521) (xy 45.607497 -29.458926) (xy 45.559921 -29.495432) (xy 45.507987 -29.525416)
			(xy 45.452583 -29.548365) (xy 45.394658 -29.563886) (xy 45.335202 -29.571714) (xy 45.275234 -29.571714)
			(xy 45.215778 -29.563886) (xy 45.157853 -29.548365) (xy 45.102449 -29.525416) (xy 45.050515 -29.495432)
			(xy 45.002939 -29.458926) (xy 44.960534 -29.416521) (xy 44.924028 -29.368945) (xy 44.894044 -29.317011)
			(xy 44.871095 -29.261607) (xy 44.855574 -29.203682) (xy 44.847746 -29.144226) (xy 44.847256 -29.114242)
			(xy 44.847256 -28.24988) (xy 44.847824 -28.216964) (xy 44.857256 -28.15181) (xy 44.866052 -28.120086)
			(xy 44.867068 -28.116784) (xy 44.868084 -28.110942) (xy 44.869185 -28.100322) (xy 44.863667 -28.079721)
			(xy 44.857416 -28.071064) (xy 44.857416 -28.07081) (xy 44.849783 -28.0623) (xy 44.829206 -28.05241)
			(xy 44.817792 -28.05176) (xy 44.803568 -28.05176) (xy 44.770915 -28.051301) (xy 44.706019 -28.043986)
			(xy 44.642349 -28.029451) (xy 44.580708 -28.00788) (xy 44.521869 -27.979544) (xy 44.466572 -27.944798)
			(xy 44.415513 -27.90408) (xy 44.392088 -27.881326) (xy 44.256706 -27.745944) (xy 44.251246 -27.740824)
			(xy 44.238074 -27.733733) (xy 44.230798 -27.731974) (xy 43.782488 -27.64282) (xy 43.772582 -27.641804)
			(xy 43.539156 -27.641804) (xy 43.529089 -27.642235) (xy 43.510497 -27.649961) (xy 43.503088 -27.65679)
			(xy 43.399202 -27.760676) (xy 43.375444 -27.783819) (xy 43.323602 -27.825193) (xy 43.267453 -27.860502)
			(xy 43.207704 -27.889302) (xy 43.145105 -27.911229) (xy 43.080445 -27.926009) (xy 43.014536 -27.933456)
			(xy 42.981372 -27.933904) (xy 42.94821 -27.933454) (xy 42.882304 -27.926023) (xy 42.817645 -27.911258)
			(xy 42.755046 -27.889345) (xy 42.695295 -27.860559) (xy 42.639144 -27.825262) (xy 42.587299 -27.783899)
			(xy 42.540412 -27.73699) (xy 42.499074 -27.685126) (xy 42.463804 -27.628958) (xy 42.435047 -27.569193)
			(xy 42.413163 -27.506584) (xy 42.398429 -27.441917) (xy 42.39103 -27.376008) (xy 42.390568 -27.342846)
			(xy 42.390993 -27.310542) (xy 42.398021 -27.246317) (xy 42.41201 -27.183242) (xy 42.432793 -27.122068)
			(xy 42.460122 -27.063525) (xy 42.493671 -27.00831) (xy 42.512996 -26.98242) (xy 42.518076 -26.975816)
			(xy 42.523664 -26.960068) (xy 42.523664 -26.862024) (xy 42.517822 -26.845768) (xy 42.512996 -26.839672)
			(xy 42.493668 -26.813834) (xy 42.460139 -26.758702) (xy 42.432822 -26.700242) (xy 42.412042 -26.639152)
			(xy 42.398048 -26.57616) (xy 42.391005 -26.512018) (xy 42.390568 -26.479754) (xy 42.390568 -26.479246)
			(xy 42.391104 -26.443535) (xy 42.399706 -26.372632) (xy 42.41679 -26.303283) (xy 42.442107 -26.236498)
			(xy 42.475287 -26.173251) (xy 42.515848 -26.114463) (xy 42.563198 -26.060992) (xy 42.616647 -26.013618)
			(xy 42.675416 -25.973029) (xy 42.738648 -25.939819) (xy 42.805421 -25.914471) (xy 42.874762 -25.897355)
			(xy 42.945661 -25.888721) (xy 42.981372 -25.888188) (xy 43.014534 -25.888667) (xy 43.080438 -25.896121)
			(xy 43.145094 -25.910903) (xy 43.20769 -25.932829) (xy 43.267438 -25.961623) (xy 43.323588 -25.996922)
			(xy 43.375435 -26.038285) (xy 43.399202 -26.061416) (xy 43.501056 -26.16327) (xy 43.508456 -26.170111)
			(xy 43.527055 -26.177829) (xy 43.537124 -26.178256) (xy 43.863768 -26.178256) (xy 43.892786 -26.178548)
			(xy 43.950551 -26.184143) (xy 43.979084 -26.189432) (xy 43.99153 -26.191972) (xy 44.49572 -26.191972)
			(xy 44.528322 -26.192428) (xy 44.593118 -26.199719) (xy 44.656692 -26.214208) (xy 44.718249 -26.235712)
			(xy 44.777015 -26.263963) (xy 44.832256 -26.298606) (xy 44.883277 -26.339207) (xy 44.906692 -26.361898)
			(xy 44.9072 -26.362406) (xy 44.912534 -26.367486) (xy 44.91482 -26.369772) (xy 44.92244 -26.377138)
			(xy 44.959524 -26.384504) (xy 44.966143 -26.385607) (xy 44.979526 -26.384698) (xy 44.98594 -26.382726)
			(xy 45.028358 -26.367994) (xy 45.058838 -26.35758) (xy 45.062943 -26.356071) (xy 45.070604 -26.351855)
			(xy 45.074078 -26.349198) (xy 45.082206 -26.34107) (xy 45.084473 -26.338023) (xy 45.088179 -26.331395)
			(xy 45.089572 -26.327862) (xy 45.09262 -26.316178) (xy 45.092874 -26.313892) (xy 45.096759 -26.286534)
			(xy 45.111395 -26.233253) (xy 45.133567 -26.182641) (xy 45.16281 -26.135759) (xy 45.198511 -26.093586)
			(xy 45.239925 -26.057006) (xy 45.286183 -26.026785) (xy 45.336317 -26.003555) (xy 45.389279 -25.987802)
			(xy 45.44396 -25.979856) (xy 45.471588 -25.979374) (xy 45.498794 -25.979856) (xy 45.552655 -25.987585)
			(xy 45.604871 -26.002887) (xy 45.654383 -26.025453) (xy 45.700187 -26.054825) (xy 45.741354 -26.090406)
			(xy 45.777048 -26.131474) (xy 45.806544 -26.177198) (xy 45.829246 -26.226648) (xy 45.844692 -26.278822)
			(xy 45.850677 -26.319734) (xy 50.841908 -26.319734) (xy 50.845979 -26.264112) (xy 50.858105 -26.209675)
			(xy 50.878028 -26.157584) (xy 50.905324 -26.108949) (xy 50.93941 -26.064806) (xy 50.979559 -26.026097)
			(xy 51.024917 -25.993646) (xy 51.074517 -25.968145) (xy 51.127301 -25.950138) (xy 51.182144 -25.940008)
			(xy 51.237878 -25.937971) (xy 51.293315 -25.944071) (xy 51.347272 -25.958177) (xy 51.398601 -25.979989)
			(xy 51.446207 -26.009043) (xy 51.475872 -26.03373) (xy 57.267854 -26.03373) (xy 57.271925 -25.978108)
			(xy 57.284051 -25.923671) (xy 57.303974 -25.87158) (xy 57.33127 -25.822945) (xy 57.365356 -25.778802)
			(xy 57.405505 -25.740093) (xy 57.450863 -25.707642) (xy 57.500463 -25.682141) (xy 57.553247 -25.664134)
			(xy 57.60809 -25.654004) (xy 57.663824 -25.651967) (xy 57.719261 -25.658067) (xy 57.773218 -25.672173)
			(xy 57.824547 -25.693985) (xy 57.872153 -25.723039) (xy 57.915021 -25.758714) (xy 57.952238 -25.800251)
			(xy 57.983011 -25.846764) (xy 58.006683 -25.897261) (xy 58.022751 -25.950668) (xy 58.030871 -26.005844)
			(xy 58.03138 -26.03373) (xy 58.030871 -26.061616) (xy 58.022751 -26.116792) (xy 58.006683 -26.170199)
			(xy 57.983011 -26.220696) (xy 57.952777 -26.266394) (xy 60.52058 -26.266394) (xy 60.521066 -26.239143)
			(xy 60.528822 -26.185195) (xy 60.544177 -26.1329) (xy 60.566819 -26.083323) (xy 60.596285 -26.037473)
			(xy 60.631976 -25.996282) (xy 60.673167 -25.960591) (xy 60.719017 -25.931125) (xy 60.768594 -25.908483)
			(xy 60.820889 -25.893128) (xy 60.874837 -25.885372) (xy 60.929339 -25.885372) (xy 60.983287 -25.893128)
			(xy 61.035582 -25.908483) (xy 61.085159 -25.931125) (xy 61.131009 -25.960591) (xy 61.1722 -25.996282)
			(xy 61.207891 -26.037473) (xy 61.237357 -26.083323) (xy 61.259999 -26.1329) (xy 61.275354 -26.185195)
			(xy 61.28311 -26.239143) (xy 61.283596 -26.266394) (xy 61.283046 -26.295882) (xy 61.273951 -26.354152)
			(xy 61.255992 -26.410328) (xy 61.229599 -26.463068) (xy 61.1954 -26.511116) (xy 61.15421 -26.553325)
			(xy 61.130942 -26.571448) (xy 61.119794 -26.580313) (xy 61.102617 -26.603024) (xy 61.092375 -26.629593)
			(xy 61.089863 -26.657958) (xy 61.095277 -26.685913) (xy 61.108195 -26.71129) (xy 61.127615 -26.732115)
			(xy 61.139578 -26.73985) (xy 61.16331 -26.754763) (xy 61.206546 -26.790426) (xy 61.244099 -26.832032)
			(xy 61.27516 -26.878685) (xy 61.29906 -26.92938) (xy 61.315286 -26.983027) (xy 61.323487 -27.038471)
			(xy 61.323982 -27.066494) (xy 61.323496 -27.093745) (xy 61.31574 -27.147693) (xy 61.300385 -27.199988)
			(xy 61.277743 -27.249565) (xy 61.248277 -27.295415) (xy 61.212586 -27.336606) (xy 61.171395 -27.372297)
			(xy 61.125545 -27.401763) (xy 61.075968 -27.424405) (xy 61.023673 -27.43976) (xy 60.969725 -27.447516)
			(xy 60.915223 -27.447516) (xy 60.861275 -27.43976) (xy 60.80898 -27.424405) (xy 60.759403 -27.401763)
			(xy 60.713553 -27.372297) (xy 60.672362 -27.336606) (xy 60.636671 -27.295415) (xy 60.607205 -27.249565)
			(xy 60.584563 -27.199988) (xy 60.569208 -27.147693) (xy 60.561452 -27.093745) (xy 60.560966 -27.066494)
			(xy 60.561523 -27.037007) (xy 60.570618 -26.978737) (xy 60.588577 -26.922562) (xy 60.614969 -26.869822)
			(xy 60.649166 -26.821774) (xy 60.690353 -26.779564) (xy 60.71362 -26.76144) (xy 60.724683 -26.752475)
			(xy 60.741866 -26.729789) (xy 60.752119 -26.703242) (xy 60.754644 -26.674895) (xy 60.749245 -26.646954)
			(xy 60.736342 -26.621588) (xy 60.716938 -26.600771) (xy 60.704984 -26.593038) (xy 60.681238 -26.578147)
			(xy 60.638004 -26.542478) (xy 60.600453 -26.500868) (xy 60.569395 -26.454212) (xy 60.545497 -26.403513)
			(xy 60.529273 -26.349864) (xy 60.521074 -26.294418) (xy 60.52058 -26.266394) (xy 57.952777 -26.266394)
			(xy 57.952238 -26.267209) (xy 57.915021 -26.308746) (xy 57.872153 -26.344421) (xy 57.824547 -26.373475)
			(xy 57.773218 -26.395287) (xy 57.719261 -26.409393) (xy 57.663824 -26.415493) (xy 57.60809 -26.413456)
			(xy 57.553247 -26.403326) (xy 57.500463 -26.385319) (xy 57.450863 -26.359818) (xy 57.405505 -26.327367)
			(xy 57.365356 -26.288658) (xy 57.33127 -26.244515) (xy 57.303974 -26.19588) (xy 57.284051 -26.143789)
			(xy 57.271925 -26.089352) (xy 57.267854 -26.03373) (xy 51.475872 -26.03373) (xy 51.489075 -26.044718)
			(xy 51.526292 -26.086255) (xy 51.557065 -26.132768) (xy 51.580737 -26.183265) (xy 51.596805 -26.236672)
			(xy 51.604925 -26.291848) (xy 51.605434 -26.319734) (xy 51.604925 -26.34762) (xy 51.596805 -26.402796)
			(xy 51.580737 -26.456203) (xy 51.557065 -26.5067) (xy 51.526292 -26.553213) (xy 51.489075 -26.59475)
			(xy 51.446207 -26.630425) (xy 51.398601 -26.659479) (xy 51.347272 -26.681291) (xy 51.293315 -26.695397)
			(xy 51.237878 -26.701497) (xy 51.182144 -26.69946) (xy 51.127301 -26.68933) (xy 51.074517 -26.671323)
			(xy 51.024917 -26.645822) (xy 50.979559 -26.613371) (xy 50.93941 -26.574662) (xy 50.905324 -26.530519)
			(xy 50.878028 -26.481884) (xy 50.858105 -26.429793) (xy 50.845979 -26.375356) (xy 50.841908 -26.319734)
			(xy 45.850677 -26.319734) (xy 45.852568 -26.332661) (xy 45.853096 -26.359866) (xy 45.853096 -26.361644)
			(xy 45.852452 -26.391554) (xy 45.843011 -26.450626) (xy 45.8343 -26.479246) (xy 45.832268 -26.485596)
			(xy 45.83176 -26.4922) (xy 45.831526 -26.496687) (xy 45.832419 -26.505628) (xy 45.833538 -26.50998)
			(xy 45.835824 -26.518616) (xy 45.841412 -26.526236) (xy 45.858176 -26.54935) (xy 45.863851 -26.556535)
			(xy 45.879081 -26.566676) (xy 45.887894 -26.569162) (xy 45.888148 -26.569162) (xy 45.912621 -26.574993)
			(xy 45.960565 -26.590253) (xy 45.983906 -26.599642) (xy 46.00829 -26.609802) (xy 46.012977 -26.611601)
			(xy 46.022829 -26.613521) (xy 46.027848 -26.613612) (xy 46.34484 -26.613612) (xy 46.377493 -26.614072)
			(xy 46.442389 -26.621387) (xy 46.506058 -26.635922) (xy 46.5677 -26.657493) (xy 46.626539 -26.685829)
			(xy 46.681837 -26.720573) (xy 46.732897 -26.76129) (xy 46.75632 -26.784046) (xy 46.787562 -26.815034)
			(xy 46.802802 -26.830274) (xy 46.810214 -26.836958) (xy 46.828647 -26.844555) (xy 46.848585 -26.844555)
			(xy 46.867018 -26.836958) (xy 46.87443 -26.830274) (xy 46.881034 -26.82367) (xy 46.885098 -26.815034)
			(xy 46.896756 -26.790229) (xy 46.926127 -26.743958) (xy 46.961815 -26.702363) (xy 47.003086 -26.6663)
			(xy 47.049089 -26.63651) (xy 47.098881 -26.613606) (xy 47.151436 -26.598059) (xy 47.205675 -26.590189)
			(xy 47.233078 -26.589736) (xy 47.259961 -26.590201) (xy 47.313192 -26.597757) (xy 47.364837 -26.61271)
			(xy 47.413872 -26.634762) (xy 47.459327 -26.663478) (xy 47.500301 -26.698289) (xy 47.535985 -26.738505)
			(xy 47.565671 -26.783332) (xy 47.588773 -26.831882) (xy 47.604832 -26.883193) (xy 47.613532 -26.93625)
			(xy 47.614586 -26.963116) (xy 47.614586 -26.969974) (xy 47.614318 -26.992663) (xy 47.609092 -27.037739)
			(xy 47.604172 -27.05989) (xy 47.60222 -27.070012) (xy 47.605641 -27.09032) (xy 47.610776 -27.09926)
			(xy 47.650146 -27.160728) (xy 47.656069 -27.16921) (xy 47.673112 -27.180904) (xy 47.683166 -27.183334)
			(xy 48.339502 -27.313636) (xy 48.349408 -27.314652) (xy 48.667924 -27.314652) (xy 48.700588 -27.315101)
			(xy 48.765503 -27.322433) (xy 48.829189 -27.336992) (xy 48.890842 -27.358594) (xy 48.949688 -27.386966)
			(xy 49.004984 -27.421752) (xy 49.056035 -27.462514) (xy 49.079404 -27.48534) (xy 49.778412 -28.184348)
			(xy 49.781941 -28.187663) (xy 49.789997 -28.193033) (xy 49.794414 -28.195016) (xy 49.803812 -28.19908)
			(xy 49.845214 -28.19908) (xy 49.855374 -28.194762) (xy 49.878488 -28.185872) (xy 49.88433 -28.181046)
			(xy 49.885346 -28.18003) (xy 49.90804 -28.161212) (xy 49.958098 -28.130075) (xy 50.012351 -28.107013)
			(xy 50.040794 -28.099258) (xy 50.063776 -28.0938) (xy 50.110648 -28.087945) (xy 50.134266 -28.087574)
			(xy 50.13452 -28.087574) (xy 50.161771 -28.088061) (xy 50.215717 -28.09582) (xy 50.268011 -28.111177)
			(xy 50.317587 -28.133819) (xy 50.32586 -28.139136) (xy 54.397908 -28.139136) (xy 54.401979 -28.083514)
			(xy 54.414105 -28.029077) (xy 54.434028 -27.976986) (xy 54.461324 -27.928351) (xy 54.49541 -27.884208)
			(xy 54.535559 -27.845499) (xy 54.580917 -27.813048) (xy 54.630517 -27.787547) (xy 54.683301 -27.76954)
			(xy 54.738144 -27.75941) (xy 54.793878 -27.757373) (xy 54.849315 -27.763473) (xy 54.903272 -27.777579)
			(xy 54.954601 -27.799391) (xy 55.002207 -27.828445) (xy 55.045075 -27.86412) (xy 55.082292 -27.905657)
			(xy 55.113065 -27.95217) (xy 55.136737 -28.002667) (xy 55.152805 -28.056074) (xy 55.160925 -28.11125)
			(xy 55.161434 -28.139136) (xy 55.667908 -28.139136) (xy 55.671979 -28.083514) (xy 55.684105 -28.029077)
			(xy 55.704028 -27.976986) (xy 55.731324 -27.928351) (xy 55.76541 -27.884208) (xy 55.805559 -27.845499)
			(xy 55.850917 -27.813048) (xy 55.900517 -27.787547) (xy 55.953301 -27.76954) (xy 56.008144 -27.75941)
			(xy 56.063878 -27.757373) (xy 56.119315 -27.763473) (xy 56.173272 -27.777579) (xy 56.224601 -27.799391)
			(xy 56.272207 -27.828445) (xy 56.315075 -27.86412) (xy 56.352292 -27.905657) (xy 56.383065 -27.95217)
			(xy 56.406737 -28.002667) (xy 56.422805 -28.056074) (xy 56.430925 -28.11125) (xy 56.431434 -28.139136)
			(xy 56.430925 -28.167022) (xy 56.422805 -28.222198) (xy 56.406737 -28.275605) (xy 56.383065 -28.326102)
			(xy 56.352292 -28.372615) (xy 56.315075 -28.414152) (xy 56.272207 -28.449827) (xy 56.224601 -28.478881)
			(xy 56.173272 -28.500693) (xy 56.119315 -28.514799) (xy 56.063878 -28.520899) (xy 56.008144 -28.518862)
			(xy 55.953301 -28.508732) (xy 55.900517 -28.490725) (xy 55.850917 -28.465224) (xy 55.805559 -28.432773)
			(xy 55.76541 -28.394064) (xy 55.731324 -28.349921) (xy 55.704028 -28.301286) (xy 55.684105 -28.249195)
			(xy 55.671979 -28.194758) (xy 55.667908 -28.139136) (xy 55.161434 -28.139136) (xy 55.160925 -28.167022)
			(xy 55.152805 -28.222198) (xy 55.136737 -28.275605) (xy 55.113065 -28.326102) (xy 55.082292 -28.372615)
			(xy 55.045075 -28.414152) (xy 55.002207 -28.449827) (xy 54.954601 -28.478881) (xy 54.903272 -28.500693)
			(xy 54.849315 -28.514799) (xy 54.793878 -28.520899) (xy 54.738144 -28.518862) (xy 54.683301 -28.508732)
			(xy 54.630517 -28.490725) (xy 54.580917 -28.465224) (xy 54.535559 -28.432773) (xy 54.49541 -28.394064)
			(xy 54.461324 -28.349921) (xy 54.434028 -28.301286) (xy 54.414105 -28.249195) (xy 54.401979 -28.194758)
			(xy 54.397908 -28.139136) (xy 50.32586 -28.139136) (xy 50.363436 -28.163285) (xy 50.404625 -28.198976)
			(xy 50.440316 -28.240166) (xy 50.469782 -28.286015) (xy 50.492424 -28.335591) (xy 50.507781 -28.387885)
			(xy 50.515539 -28.441831) (xy 50.516028 -28.469082) (xy 50.515443 -28.499024) (xy 50.506085 -28.558173)
			(xy 50.487596 -28.615132) (xy 50.460431 -28.6685) (xy 50.425257 -28.716966) (xy 50.404522 -28.738576)
			(xy 50.404268 -28.73883) (xy 50.404268 -28.789376) (xy 50.404773 -28.799427) (xy 50.412493 -28.817989)
			(xy 50.419254 -28.825444) (xy 50.71618 -29.12237) (xy 60.60694 -29.12237) (xy 60.60694 -28.25877)
			(xy 60.60743 -28.228802) (xy 60.615253 -28.16938) (xy 60.630766 -28.111487) (xy 60.653702 -28.056114)
			(xy 60.683669 -28.004208) (xy 60.720156 -27.956658) (xy 60.762536 -27.914278) (xy 60.810086 -27.877791)
			(xy 60.861992 -27.847824) (xy 60.917365 -27.824888) (xy 60.975258 -27.809375) (xy 61.03468 -27.801552)
			(xy 61.094616 -27.801552) (xy 61.154038 -27.809375) (xy 61.211931 -27.824888) (xy 61.267304 -27.847824)
			(xy 61.31921 -27.877791) (xy 61.36676 -27.914278) (xy 61.40914 -27.956658) (xy 61.445627 -28.004208)
			(xy 61.475594 -28.056114) (xy 61.49853 -28.111487) (xy 61.514043 -28.16938) (xy 61.521866 -28.228802)
			(xy 61.522356 -28.25877) (xy 61.522356 -29.12237) (xy 61.521866 -29.152338) (xy 61.514043 -29.21176)
			(xy 61.49853 -29.269653) (xy 61.475594 -29.325026) (xy 61.445627 -29.376932) (xy 61.40914 -29.424482)
			(xy 61.36676 -29.466862) (xy 61.31921 -29.503349) (xy 61.267304 -29.533316) (xy 61.211931 -29.556252)
			(xy 61.154038 -29.571765) (xy 61.094616 -29.579588) (xy 61.03468 -29.579588) (xy 60.975258 -29.571765)
			(xy 60.917365 -29.556252) (xy 60.861992 -29.533316) (xy 60.810086 -29.503349) (xy 60.762536 -29.466862)
			(xy 60.720156 -29.424482) (xy 60.683669 -29.376932) (xy 60.653702 -29.325026) (xy 60.630766 -29.269653)
			(xy 60.615253 -29.21176) (xy 60.60743 -29.152338) (xy 60.60694 -29.12237) (xy 50.71618 -29.12237)
			(xy 50.815494 -29.221684) (xy 50.833819 -29.240393) (xy 50.867397 -29.280588) (xy 50.88255 -29.301948)
			(xy 50.884074 -29.30398) (xy 51.01717 -29.43733) (xy 51.04028 -29.461109) (xy 51.081613 -29.512962)
			(xy 51.116882 -29.569116) (xy 51.145642 -29.628865) (xy 51.167533 -29.691459) (xy 51.18228 -29.756109)
			(xy 51.189696 -29.822004) (xy 51.190144 -29.85516) (xy 51.190144 -30.376876) (xy 52.888896 -30.376876)
			(xy 52.889433 -30.347959) (xy 52.898153 -30.290787) (xy 52.915405 -30.235587) (xy 52.940793 -30.183625)
			(xy 52.973735 -30.136091) (xy 53.013476 -30.094075) (xy 53.035962 -30.075886) (xy 53.044776 -30.068286)
			(xy 53.054953 -30.047379) (xy 53.05552 -30.035754) (xy 53.05552 -29.955998) (xy 53.054961 -29.944369)
			(xy 53.044785 -29.92346) (xy 53.035962 -29.915866) (xy 53.013454 -29.897704) (xy 52.973722 -29.855677)
			(xy 52.940787 -29.808136) (xy 52.915403 -29.756169) (xy 52.898152 -29.700967) (xy 52.889428 -29.643794)
			(xy 52.888896 -29.614876) (xy 52.889382 -29.587625) (xy 52.897138 -29.533677) (xy 52.912493 -29.481382)
			(xy 52.935135 -29.431805) (xy 52.964601 -29.385955) (xy 53.000292 -29.344764) (xy 53.041483 -29.309073)
			(xy 53.087333 -29.279607) (xy 53.13691 -29.256965) (xy 53.189205 -29.24161) (xy 53.243153 -29.233854)
			(xy 53.297655 -29.233854) (xy 53.351603 -29.24161) (xy 53.403898 -29.256965) (xy 53.453475 -29.279607)
			(xy 53.499325 -29.309073) (xy 53.540516 -29.344764) (xy 53.576207 -29.385955) (xy 53.605673 -29.431805)
			(xy 53.628315 -29.481382) (xy 53.64367 -29.533677) (xy 53.651426 -29.587625) (xy 53.651912 -29.614876)
			(xy 53.65141 -29.643794) (xy 53.642682 -29.700967) (xy 53.625423 -29.756168) (xy 53.600029 -29.80813)
			(xy 53.567081 -29.855664) (xy 53.527334 -29.897678) (xy 53.504846 -29.915866) (xy 53.496055 -29.923488)
			(xy 53.485865 -29.944378) (xy 53.485288 -29.955998) (xy 53.485288 -30.035754) (xy 53.485815 -30.047387)
			(xy 53.496013 -30.068296) (xy 53.504846 -30.075886) (xy 53.527332 -30.094073) (xy 53.567065 -30.136095)
			(xy 53.600003 -30.183631) (xy 53.62539 -30.235593) (xy 53.642646 -30.290791) (xy 53.651376 -30.34796)
			(xy 53.651912 -30.376876) (xy 55.929022 -30.376876) (xy 55.929586 -30.347961) (xy 55.938305 -30.290791)
			(xy 55.955553 -30.235593) (xy 55.980936 -30.183631) (xy 56.013872 -30.136096) (xy 56.053606 -30.094077)
			(xy 56.076088 -30.075886) (xy 56.08489 -30.068273) (xy 56.095077 -30.047377) (xy 56.095646 -30.035754)
			(xy 56.095646 -29.955998) (xy 56.095113 -29.944365) (xy 56.084922 -29.923454) (xy 56.076088 -29.915866)
			(xy 56.053586 -29.897697) (xy 56.013852 -29.855672) (xy 55.980916 -29.808133) (xy 55.955531 -29.756167)
			(xy 55.938279 -29.700966) (xy 55.929554 -29.643793) (xy 55.929022 -29.614876) (xy 55.929508 -29.587625)
			(xy 55.937264 -29.533677) (xy 55.952619 -29.481382) (xy 55.975261 -29.431805) (xy 56.004727 -29.385955)
			(xy 56.040418 -29.344764) (xy 56.081609 -29.309073) (xy 56.127459 -29.279607) (xy 56.177036 -29.256965)
			(xy 56.229331 -29.24161) (xy 56.283279 -29.233854) (xy 56.337781 -29.233854) (xy 56.391729 -29.24161)
			(xy 56.444024 -29.256965) (xy 56.493601 -29.279607) (xy 56.539451 -29.309073) (xy 56.580642 -29.344764)
			(xy 56.616333 -29.385955) (xy 56.645799 -29.431805) (xy 56.668441 -29.481382) (xy 56.683796 -29.533677)
			(xy 56.691552 -29.587625) (xy 56.692038 -29.614876) (xy 56.691526 -29.643793) (xy 56.682799 -29.700966)
			(xy 56.665541 -29.756166) (xy 56.640149 -29.808128) (xy 56.607203 -29.855662) (xy 56.567459 -29.897677)
			(xy 56.544972 -29.915866) (xy 56.536185 -29.923493) (xy 56.525992 -29.944379) (xy 56.525414 -29.955998)
			(xy 56.525414 -30.035754) (xy 56.525931 -30.047389) (xy 56.536135 -30.068298) (xy 56.544972 -30.075886)
			(xy 56.567443 -30.094092) (xy 56.60718 -30.136108) (xy 56.640122 -30.183639) (xy 56.665512 -30.235598)
			(xy 56.682771 -30.290793) (xy 56.691502 -30.347961) (xy 56.692038 -30.376876) (xy 56.691552 -30.404127)
			(xy 56.683796 -30.458075) (xy 56.668441 -30.51037) (xy 56.645799 -30.559947) (xy 56.616333 -30.605797)
			(xy 56.580642 -30.646988) (xy 56.539451 -30.682679) (xy 56.493601 -30.712145) (xy 56.444024 -30.734787)
			(xy 56.391729 -30.750142) (xy 56.337781 -30.757898) (xy 56.283279 -30.757898) (xy 56.229331 -30.750142)
			(xy 56.177036 -30.734787) (xy 56.127459 -30.712145) (xy 56.081609 -30.682679) (xy 56.040418 -30.646988)
			(xy 56.004727 -30.605797) (xy 55.975261 -30.559947) (xy 55.952619 -30.51037) (xy 55.937264 -30.458075)
			(xy 55.929508 -30.404127) (xy 55.929022 -30.376876) (xy 53.651912 -30.376876) (xy 53.651426 -30.404127)
			(xy 53.64367 -30.458075) (xy 53.628315 -30.51037) (xy 53.605673 -30.559947) (xy 53.576207 -30.605797)
			(xy 53.540516 -30.646988) (xy 53.499325 -30.682679) (xy 53.453475 -30.712145) (xy 53.403898 -30.734787)
			(xy 53.351603 -30.750142) (xy 53.297655 -30.757898) (xy 53.243153 -30.757898) (xy 53.189205 -30.750142)
			(xy 53.13691 -30.734787) (xy 53.087333 -30.712145) (xy 53.041483 -30.682679) (xy 53.000292 -30.646988)
			(xy 52.964601 -30.605797) (xy 52.935135 -30.559947) (xy 52.912493 -30.51037) (xy 52.897138 -30.458075)
			(xy 52.889382 -30.404127) (xy 52.888896 -30.376876) (xy 51.190144 -30.376876) (xy 51.190144 -30.922468)
			(xy 58.75274 -30.922468) (xy 58.75274 -30.058868) (xy 58.75323 -30.0289) (xy 58.761053 -29.969478)
			(xy 58.776566 -29.911585) (xy 58.799502 -29.856212) (xy 58.829469 -29.804306) (xy 58.865956 -29.756756)
			(xy 58.908336 -29.714376) (xy 58.955886 -29.677889) (xy 59.007792 -29.647922) (xy 59.063165 -29.624986)
			(xy 59.121058 -29.609473) (xy 59.18048 -29.60165) (xy 59.240416 -29.60165) (xy 59.299838 -29.609473)
			(xy 59.357731 -29.624986) (xy 59.413104 -29.647922) (xy 59.46501 -29.677889) (xy 59.51256 -29.714376)
			(xy 59.55494 -29.756756) (xy 59.591427 -29.804306) (xy 59.621394 -29.856212) (xy 59.64433 -29.911585)
			(xy 59.659843 -29.969478) (xy 59.667666 -30.0289) (xy 59.668156 -30.058868) (xy 59.668156 -30.92069)
			(xy 73.489312 -30.92069) (xy 73.489312 -30.05709) (xy 73.489802 -30.027106) (xy 73.49763 -29.96765)
			(xy 73.513151 -29.909725) (xy 73.5361 -29.854321) (xy 73.566084 -29.802387) (xy 73.60259 -29.754811)
			(xy 73.644995 -29.712406) (xy 73.692571 -29.6759) (xy 73.744505 -29.645916) (xy 73.799909 -29.622967)
			(xy 73.857834 -29.607446) (xy 73.91729 -29.599618) (xy 73.977258 -29.599618) (xy 74.036714 -29.607446)
			(xy 74.094639 -29.622967) (xy 74.150043 -29.645916) (xy 74.201977 -29.6759) (xy 74.249553 -29.712406)
			(xy 74.291958 -29.754811) (xy 74.328464 -29.802387) (xy 74.358448 -29.854321) (xy 74.381397 -29.909725)
			(xy 74.396918 -29.96765) (xy 74.404746 -30.027106) (xy 74.405236 -30.05709) (xy 74.405236 -30.92069)
			(xy 74.404746 -30.950674) (xy 74.396918 -31.01013) (xy 74.381397 -31.068055) (xy 74.358448 -31.123459)
			(xy 74.328464 -31.175393) (xy 74.291958 -31.222969) (xy 74.249553 -31.265374) (xy 74.201977 -31.30188)
			(xy 74.150043 -31.331864) (xy 74.094639 -31.354813) (xy 74.036714 -31.370334) (xy 73.977258 -31.378162)
			(xy 73.91729 -31.378162) (xy 73.857834 -31.370334) (xy 73.799909 -31.354813) (xy 73.744505 -31.331864)
			(xy 73.692571 -31.30188) (xy 73.644995 -31.265374) (xy 73.60259 -31.222969) (xy 73.566084 -31.175393)
			(xy 73.5361 -31.123459) (xy 73.513151 -31.068055) (xy 73.49763 -31.01013) (xy 73.489802 -30.950674)
			(xy 73.489312 -30.92069) (xy 59.668156 -30.92069) (xy 59.668156 -30.922468) (xy 59.667666 -30.952436)
			(xy 59.659843 -31.011858) (xy 59.64433 -31.069751) (xy 59.621394 -31.125124) (xy 59.591427 -31.17703)
			(xy 59.55494 -31.22458) (xy 59.51256 -31.26696) (xy 59.46501 -31.303447) (xy 59.413104 -31.333414)
			(xy 59.357731 -31.35635) (xy 59.299838 -31.371863) (xy 59.240416 -31.379686) (xy 59.18048 -31.379686)
			(xy 59.121058 -31.371863) (xy 59.063165 -31.35635) (xy 59.007792 -31.333414) (xy 58.955886 -31.303447)
			(xy 58.908336 -31.26696) (xy 58.865956 -31.22458) (xy 58.829469 -31.17703) (xy 58.799502 -31.125124)
			(xy 58.776566 -31.069751) (xy 58.761053 -31.011858) (xy 58.75323 -30.952436) (xy 58.75274 -30.922468)
			(xy 51.190144 -30.922468) (xy 51.190144 -31.567882) (xy 52.998622 -31.567882) (xy 53.002693 -31.51226)
			(xy 53.014819 -31.457823) (xy 53.034742 -31.405732) (xy 53.062038 -31.357097) (xy 53.096124 -31.312954)
			(xy 53.136273 -31.274245) (xy 53.181631 -31.241794) (xy 53.231231 -31.216293) (xy 53.284015 -31.198286)
			(xy 53.338858 -31.188156) (xy 53.394592 -31.186119) (xy 53.450029 -31.192219) (xy 53.503986 -31.206325)
			(xy 53.555315 -31.228137) (xy 53.602921 -31.257191) (xy 53.645789 -31.292866) (xy 53.683006 -31.334403)
			(xy 53.713779 -31.380916) (xy 53.737451 -31.431413) (xy 53.753519 -31.48482) (xy 53.761639 -31.539996)
			(xy 53.762148 -31.567882) (xy 53.761639 -31.595768) (xy 53.753519 -31.650944) (xy 53.737451 -31.704351)
			(xy 53.730459 -31.719266) (xy 54.285386 -31.719266) (xy 54.289457 -31.663644) (xy 54.301583 -31.609207)
			(xy 54.321506 -31.557116) (xy 54.348802 -31.508481) (xy 54.382888 -31.464338) (xy 54.423037 -31.425629)
			(xy 54.468395 -31.393178) (xy 54.517995 -31.367677) (xy 54.570779 -31.34967) (xy 54.625622 -31.33954)
			(xy 54.681356 -31.337503) (xy 54.736793 -31.343603) (xy 54.79075 -31.357709) (xy 54.842079 -31.379521)
			(xy 54.889685 -31.408575) (xy 54.932553 -31.44425) (xy 54.96977 -31.485787) (xy 55.000543 -31.5323)
			(xy 55.024215 -31.582797) (xy 55.040283 -31.636204) (xy 55.044433 -31.664402) (xy 55.560974 -31.664402)
			(xy 55.565045 -31.60878) (xy 55.577171 -31.554343) (xy 55.597094 -31.502252) (xy 55.62439 -31.453617)
			(xy 55.658476 -31.409474) (xy 55.698625 -31.370765) (xy 55.743983 -31.338314) (xy 55.793583 -31.312813)
			(xy 55.846367 -31.294806) (xy 55.90121 -31.284676) (xy 55.956944 -31.282639) (xy 56.012381 -31.288739)
			(xy 56.066338 -31.302845) (xy 56.117667 -31.324657) (xy 56.165273 -31.353711) (xy 56.208141 -31.389386)
			(xy 56.245358 -31.430923) (xy 56.276131 -31.477436) (xy 56.299803 -31.527933) (xy 56.315871 -31.58134)
			(xy 56.323991 -31.636516) (xy 56.3245 -31.664402) (xy 56.323991 -31.692288) (xy 56.315871 -31.747464)
			(xy 56.306931 -31.777178) (xy 56.826148 -31.777178) (xy 56.830219 -31.721556) (xy 56.842345 -31.667119)
			(xy 56.862268 -31.615028) (xy 56.889564 -31.566393) (xy 56.92365 -31.52225) (xy 56.963799 -31.483541)
			(xy 57.009157 -31.45109) (xy 57.058757 -31.425589) (xy 57.111541 -31.407582) (xy 57.166384 -31.397452)
			(xy 57.222118 -31.395415) (xy 57.277555 -31.401515) (xy 57.331512 -31.415621) (xy 57.382841 -31.437433)
			(xy 57.430447 -31.466487) (xy 57.473315 -31.502162) (xy 57.510532 -31.543699) (xy 57.541305 -31.590212)
			(xy 57.564977 -31.640709) (xy 57.581045 -31.694116) (xy 57.589165 -31.749292) (xy 57.589674 -31.777178)
			(xy 57.589165 -31.805064) (xy 57.581045 -31.86024) (xy 57.564977 -31.913647) (xy 57.541305 -31.964144)
			(xy 57.510532 -32.010657) (xy 57.473315 -32.052194) (xy 57.430447 -32.087869) (xy 57.382841 -32.116923)
			(xy 57.331512 -32.138735) (xy 57.277555 -32.152841) (xy 57.222118 -32.158941) (xy 57.166384 -32.156904)
			(xy 57.111541 -32.146774) (xy 57.058757 -32.128767) (xy 57.009157 -32.103266) (xy 56.963799 -32.070815)
			(xy 56.92365 -32.032106) (xy 56.889564 -31.987963) (xy 56.862268 -31.939328) (xy 56.842345 -31.887237)
			(xy 56.830219 -31.8328) (xy 56.826148 -31.777178) (xy 56.306931 -31.777178) (xy 56.299803 -31.800871)
			(xy 56.276131 -31.851368) (xy 56.245358 -31.897881) (xy 56.208141 -31.939418) (xy 56.165273 -31.975093)
			(xy 56.117667 -32.004147) (xy 56.066338 -32.025959) (xy 56.012381 -32.040065) (xy 55.956944 -32.046165)
			(xy 55.90121 -32.044128) (xy 55.846367 -32.033998) (xy 55.793583 -32.015991) (xy 55.743983 -31.99049)
			(xy 55.698625 -31.958039) (xy 55.658476 -31.91933) (xy 55.62439 -31.875187) (xy 55.597094 -31.826552)
			(xy 55.577171 -31.774461) (xy 55.565045 -31.720024) (xy 55.560974 -31.664402) (xy 55.044433 -31.664402)
			(xy 55.048403 -31.69138) (xy 55.048912 -31.719266) (xy 55.048403 -31.747152) (xy 55.040283 -31.802328)
			(xy 55.024215 -31.855735) (xy 55.000543 -31.906232) (xy 54.96977 -31.952745) (xy 54.932553 -31.994282)
			(xy 54.889685 -32.029957) (xy 54.842079 -32.059011) (xy 54.79075 -32.080823) (xy 54.736793 -32.094929)
			(xy 54.681356 -32.101029) (xy 54.625622 -32.098992) (xy 54.570779 -32.088862) (xy 54.517995 -32.070855)
			(xy 54.468395 -32.045354) (xy 54.423037 -32.012903) (xy 54.382888 -31.974194) (xy 54.348802 -31.930051)
			(xy 54.321506 -31.881416) (xy 54.301583 -31.829325) (xy 54.289457 -31.774888) (xy 54.285386 -31.719266)
			(xy 53.730459 -31.719266) (xy 53.713779 -31.754848) (xy 53.683006 -31.801361) (xy 53.645789 -31.842898)
			(xy 53.602921 -31.878573) (xy 53.555315 -31.907627) (xy 53.503986 -31.929439) (xy 53.450029 -31.943545)
			(xy 53.394592 -31.949645) (xy 53.338858 -31.947608) (xy 53.284015 -31.937478) (xy 53.231231 -31.919471)
			(xy 53.181631 -31.89397) (xy 53.136273 -31.861519) (xy 53.096124 -31.82281) (xy 53.062038 -31.778667)
			(xy 53.034742 -31.730032) (xy 53.014819 -31.677941) (xy 53.002693 -31.623504) (xy 52.998622 -31.567882)
			(xy 51.190144 -31.567882) (xy 51.190144 -32.722312) (xy 60.60694 -32.722312) (xy 60.60694 -31.858712)
			(xy 60.60743 -31.828744) (xy 60.615253 -31.769322) (xy 60.630766 -31.711429) (xy 60.653702 -31.656056)
			(xy 60.683669 -31.60415) (xy 60.720156 -31.5566) (xy 60.762536 -31.51422) (xy 60.810086 -31.477733)
			(xy 60.861992 -31.447766) (xy 60.917365 -31.42483) (xy 60.975258 -31.409317) (xy 61.03468 -31.401494)
			(xy 61.094616 -31.401494) (xy 61.154038 -31.409317) (xy 61.211931 -31.42483) (xy 61.267304 -31.447766)
			(xy 61.31921 -31.477733) (xy 61.36676 -31.51422) (xy 61.40914 -31.5566) (xy 61.445627 -31.60415)
			(xy 61.475594 -31.656056) (xy 61.49853 -31.711429) (xy 61.514043 -31.769322) (xy 61.521866 -31.828744)
			(xy 61.522356 -31.858712) (xy 61.522356 -32.714184) (xy 70.847204 -32.714184) (xy 70.847204 -31.850584)
			(xy 70.847694 -31.8206) (xy 70.855522 -31.761144) (xy 70.871043 -31.703219) (xy 70.893992 -31.647815)
			(xy 70.923976 -31.595881) (xy 70.960482 -31.548305) (xy 71.002887 -31.5059) (xy 71.050463 -31.469394)
			(xy 71.102397 -31.43941) (xy 71.157801 -31.416461) (xy 71.215726 -31.40094) (xy 71.275182 -31.393112)
			(xy 71.33515 -31.393112) (xy 71.394606 -31.40094) (xy 71.452531 -31.416461) (xy 71.507935 -31.43941)
			(xy 71.559869 -31.469394) (xy 71.607445 -31.5059) (xy 71.64985 -31.548305) (xy 71.686356 -31.595881)
			(xy 71.71634 -31.647815) (xy 71.739289 -31.703219) (xy 71.75481 -31.761144) (xy 71.762638 -31.8206)
			(xy 71.763128 -31.850584) (xy 71.763128 -32.714184) (xy 71.762638 -32.744168) (xy 71.75481 -32.803624)
			(xy 71.739289 -32.861549) (xy 71.71634 -32.916953) (xy 71.686356 -32.968887) (xy 71.64985 -33.016463)
			(xy 71.607445 -33.058868) (xy 71.559869 -33.095374) (xy 71.507935 -33.125358) (xy 71.452531 -33.148307)
			(xy 71.394606 -33.163828) (xy 71.33515 -33.171656) (xy 71.275182 -33.171656) (xy 71.215726 -33.163828)
			(xy 71.157801 -33.148307) (xy 71.102397 -33.125358) (xy 71.050463 -33.095374) (xy 71.002887 -33.058868)
			(xy 70.960482 -33.016463) (xy 70.923976 -32.968887) (xy 70.893992 -32.916953) (xy 70.871043 -32.861549)
			(xy 70.855522 -32.803624) (xy 70.847694 -32.744168) (xy 70.847204 -32.714184) (xy 61.522356 -32.714184)
			(xy 61.522356 -32.722312) (xy 61.521866 -32.75228) (xy 61.514043 -32.811702) (xy 61.49853 -32.869595)
			(xy 61.475594 -32.924968) (xy 61.445627 -32.976874) (xy 61.40914 -33.024424) (xy 61.36676 -33.066804)
			(xy 61.31921 -33.103291) (xy 61.267304 -33.133258) (xy 61.211931 -33.156194) (xy 61.154038 -33.171707)
			(xy 61.094616 -33.17953) (xy 61.03468 -33.17953) (xy 60.975258 -33.171707) (xy 60.917365 -33.156194)
			(xy 60.861992 -33.133258) (xy 60.810086 -33.103291) (xy 60.762536 -33.066804) (xy 60.720156 -33.024424)
			(xy 60.683669 -32.976874) (xy 60.653702 -32.924968) (xy 60.630766 -32.869595) (xy 60.615253 -32.811702)
			(xy 60.60743 -32.75228) (xy 60.60694 -32.722312) (xy 51.190144 -32.722312) (xy 51.190144 -33.162494)
			(xy 51.190567 -33.172564) (xy 51.198285 -33.191166) (xy 51.20513 -33.198562) (xy 52.528978 -34.52241)
			(xy 58.75274 -34.52241) (xy 58.75274 -33.65881) (xy 58.75323 -33.628842) (xy 58.761053 -33.56942)
			(xy 58.776566 -33.511527) (xy 58.799502 -33.456154) (xy 58.829469 -33.404248) (xy 58.865956 -33.356698)
			(xy 58.908336 -33.314318) (xy 58.955886 -33.277831) (xy 59.007792 -33.247864) (xy 59.063165 -33.224928)
			(xy 59.121058 -33.209415) (xy 59.18048 -33.201592) (xy 59.240416 -33.201592) (xy 59.299838 -33.209415)
			(xy 59.357731 -33.224928) (xy 59.413104 -33.247864) (xy 59.46501 -33.277831) (xy 59.51256 -33.314318)
			(xy 59.55494 -33.356698) (xy 59.591427 -33.404248) (xy 59.621394 -33.456154) (xy 59.64433 -33.511527)
			(xy 59.659843 -33.56942) (xy 59.667666 -33.628842) (xy 59.668156 -33.65881) (xy 59.668156 -34.520886)
			(xy 73.489312 -34.520886) (xy 73.489312 -33.657286) (xy 73.489802 -33.627302) (xy 73.49763 -33.567846)
			(xy 73.513151 -33.509921) (xy 73.5361 -33.454517) (xy 73.566084 -33.402583) (xy 73.60259 -33.355007)
			(xy 73.644995 -33.312602) (xy 73.692571 -33.276096) (xy 73.744505 -33.246112) (xy 73.799909 -33.223163)
			(xy 73.857834 -33.207642) (xy 73.91729 -33.199814) (xy 73.977258 -33.199814) (xy 74.036714 -33.207642)
			(xy 74.094639 -33.223163) (xy 74.150043 -33.246112) (xy 74.201977 -33.276096) (xy 74.249553 -33.312602)
			(xy 74.291958 -33.355007) (xy 74.328464 -33.402583) (xy 74.358448 -33.454517) (xy 74.381397 -33.509921)
			(xy 74.396918 -33.567846) (xy 74.404746 -33.627302) (xy 74.405236 -33.657286) (xy 74.405236 -34.520886)
			(xy 74.404746 -34.55087) (xy 74.396918 -34.610326) (xy 74.381397 -34.668251) (xy 74.358448 -34.723655)
			(xy 74.328464 -34.775589) (xy 74.291958 -34.823165) (xy 74.249553 -34.86557) (xy 74.201977 -34.902076)
			(xy 74.150043 -34.93206) (xy 74.094639 -34.955009) (xy 74.036714 -34.97053) (xy 73.977258 -34.978358)
			(xy 73.91729 -34.978358) (xy 73.857834 -34.97053) (xy 73.799909 -34.955009) (xy 73.744505 -34.93206)
			(xy 73.692571 -34.902076) (xy 73.644995 -34.86557) (xy 73.60259 -34.823165) (xy 73.566084 -34.775589)
			(xy 73.5361 -34.723655) (xy 73.513151 -34.668251) (xy 73.49763 -34.610326) (xy 73.489802 -34.55087)
			(xy 73.489312 -34.520886) (xy 59.668156 -34.520886) (xy 59.668156 -34.52241) (xy 59.667666 -34.552378)
			(xy 59.659843 -34.6118) (xy 59.64433 -34.669693) (xy 59.621394 -34.725066) (xy 59.591427 -34.776972)
			(xy 59.55494 -34.824522) (xy 59.51256 -34.866902) (xy 59.46501 -34.903389) (xy 59.413104 -34.933356)
			(xy 59.357731 -34.956292) (xy 59.299838 -34.971805) (xy 59.240416 -34.979628) (xy 59.18048 -34.979628)
			(xy 59.121058 -34.971805) (xy 59.063165 -34.956292) (xy 59.007792 -34.933356) (xy 58.955886 -34.903389)
			(xy 58.908336 -34.866902) (xy 58.865956 -34.824522) (xy 58.829469 -34.776972) (xy 58.799502 -34.725066)
			(xy 58.776566 -34.669693) (xy 58.761053 -34.6118) (xy 58.75323 -34.552378) (xy 58.75274 -34.52241)
			(xy 52.528978 -34.52241) (xy 53.27142 -35.264852) (xy 55.90235 -35.264852) (xy 55.906421 -35.20923)
			(xy 55.918547 -35.154793) (xy 55.93847 -35.102702) (xy 55.965766 -35.054067) (xy 55.999852 -35.009924)
			(xy 56.040001 -34.971215) (xy 56.085359 -34.938764) (xy 56.134959 -34.913263) (xy 56.187743 -34.895256)
			(xy 56.242586 -34.885126) (xy 56.29832 -34.883089) (xy 56.353757 -34.889189) (xy 56.407714 -34.903295)
			(xy 56.459043 -34.925107) (xy 56.506649 -34.954161) (xy 56.549517 -34.989836) (xy 56.586734 -35.031373)
			(xy 56.617507 -35.077886) (xy 56.641179 -35.128383) (xy 56.657247 -35.18179) (xy 56.665367 -35.236966)
			(xy 56.665876 -35.264852) (xy 56.665367 -35.292738) (xy 56.657247 -35.347914) (xy 56.641179 -35.401321)
			(xy 56.617507 -35.451818) (xy 56.586734 -35.498331) (xy 56.549517 -35.539868) (xy 56.506649 -35.575543)
			(xy 56.459043 -35.604597) (xy 56.407714 -35.626409) (xy 56.353757 -35.640515) (xy 56.29832 -35.646615)
			(xy 56.242586 -35.644578) (xy 56.187743 -35.634448) (xy 56.134959 -35.616441) (xy 56.085359 -35.59094)
			(xy 56.040001 -35.558489) (xy 55.999852 -35.51978) (xy 55.965766 -35.475637) (xy 55.93847 -35.427002)
			(xy 55.918547 -35.374911) (xy 55.906421 -35.320474) (xy 55.90235 -35.264852) (xy 53.27142 -35.264852)
			(xy 54.293516 -36.286948) (xy 57.20029 -36.286948) (xy 57.204361 -36.231326) (xy 57.216487 -36.176889)
			(xy 57.23641 -36.124798) (xy 57.263706 -36.076163) (xy 57.297792 -36.03202) (xy 57.337941 -35.993311)
			(xy 57.383299 -35.96086) (xy 57.432899 -35.935359) (xy 57.485683 -35.917352) (xy 57.540526 -35.907222)
			(xy 57.59626 -35.905185) (xy 57.651697 -35.911285) (xy 57.705654 -35.925391) (xy 57.756983 -35.947203)
			(xy 57.804589 -35.976257) (xy 57.847457 -36.011932) (xy 57.884674 -36.053469) (xy 57.915447 -36.099982)
			(xy 57.939119 -36.150479) (xy 57.955187 -36.203886) (xy 57.963307 -36.259062) (xy 57.963816 -36.286948)
			(xy 57.963307 -36.314834) (xy 57.955187 -36.37001) (xy 57.939119 -36.423417) (xy 57.915447 -36.473914)
			(xy 57.887902 -36.515548) (xy 59.014104 -36.515548) (xy 59.018175 -36.459926) (xy 59.030301 -36.405489)
			(xy 59.050224 -36.353398) (xy 59.07752 -36.304763) (xy 59.111606 -36.26062) (xy 59.151755 -36.221911)
			(xy 59.197113 -36.18946) (xy 59.246713 -36.163959) (xy 59.299497 -36.145952) (xy 59.35434 -36.135822)
			(xy 59.410074 -36.133785) (xy 59.465511 -36.139885) (xy 59.519468 -36.153991) (xy 59.570797 -36.175803)
			(xy 59.618403 -36.204857) (xy 59.661271 -36.240532) (xy 59.698488 -36.282069) (xy 59.729261 -36.328582)
			(xy 59.752933 -36.379079) (xy 59.769001 -36.432486) (xy 59.777121 -36.487662) (xy 59.77763 -36.515548)
			(xy 59.777121 -36.543434) (xy 59.769001 -36.59861) (xy 59.768544 -36.60013) (xy 63.998101 -36.60013)
			(xy 64.002106 -36.512222) (xy 64.014089 -36.425042) (xy 64.033949 -36.339313) (xy 64.061524 -36.255745)
			(xy 64.096583 -36.175031) (xy 64.138836 -36.097839) (xy 64.187934 -36.02481) (xy 64.24347 -35.956548)
			(xy 64.304982 -35.893618) (xy 64.371963 -35.836544) (xy 64.443856 -35.785796) (xy 64.520065 -35.741796)
			(xy 64.59996 -35.704909) (xy 64.682879 -35.67544) (xy 64.768134 -35.653633) (xy 64.855018 -35.639669)
			(xy 64.942812 -35.633663) (xy 65.030789 -35.635667) (xy 65.118219 -35.645662) (xy 65.204378 -35.663566)
			(xy 65.288552 -35.68923) (xy 65.370043 -35.722443) (xy 65.448177 -35.762929) (xy 65.522305 -35.810351)
			(xy 65.591813 -35.864318) (xy 65.605112 -35.876738) (xy 70.717154 -35.876738) (xy 70.721225 -35.821116)
			(xy 70.733351 -35.766679) (xy 70.753274 -35.714588) (xy 70.78057 -35.665953) (xy 70.814656 -35.62181)
			(xy 70.854805 -35.583101) (xy 70.900163 -35.55065) (xy 70.949763 -35.525149) (xy 71.002547 -35.507142)
			(xy 71.05739 -35.497012) (xy 71.113124 -35.494975) (xy 71.168561 -35.501075) (xy 71.222518 -35.515181)
			(xy 71.273847 -35.536993) (xy 71.321453 -35.566047) (xy 71.364321 -35.601722) (xy 71.401538 -35.643259)
			(xy 71.432311 -35.689772) (xy 71.455983 -35.740269) (xy 71.472051 -35.793676) (xy 71.480171 -35.848852)
			(xy 71.48068 -35.876738) (xy 74.788774 -35.876738) (xy 74.792845 -35.821116) (xy 74.804971 -35.766679)
			(xy 74.824894 -35.714588) (xy 74.85219 -35.665953) (xy 74.886276 -35.62181) (xy 74.926425 -35.583101)
			(xy 74.971783 -35.55065) (xy 75.021383 -35.525149) (xy 75.074167 -35.507142) (xy 75.12901 -35.497012)
			(xy 75.184744 -35.494975) (xy 75.240181 -35.501075) (xy 75.294138 -35.515181) (xy 75.345467 -35.536993)
			(xy 75.393073 -35.566047) (xy 75.435941 -35.601722) (xy 75.473158 -35.643259) (xy 75.503931 -35.689772)
			(xy 75.527603 -35.740269) (xy 75.543671 -35.793676) (xy 75.551791 -35.848852) (xy 75.5523 -35.876738)
			(xy 75.551791 -35.904624) (xy 75.543671 -35.9598) (xy 75.527603 -36.013207) (xy 75.503931 -36.063704)
			(xy 75.473158 -36.110217) (xy 75.435941 -36.151754) (xy 75.393073 -36.187429) (xy 75.345467 -36.216483)
			(xy 75.294138 -36.238295) (xy 75.240181 -36.252401) (xy 75.184744 -36.258501) (xy 75.12901 -36.256464)
			(xy 75.074167 -36.246334) (xy 75.021383 -36.228327) (xy 74.971783 -36.202826) (xy 74.926425 -36.170375)
			(xy 74.886276 -36.131666) (xy 74.85219 -36.087523) (xy 74.824894 -36.038888) (xy 74.804971 -35.986797)
			(xy 74.792845 -35.93236) (xy 74.788774 -35.876738) (xy 71.48068 -35.876738) (xy 71.480171 -35.904624)
			(xy 71.472051 -35.9598) (xy 71.455983 -36.013207) (xy 71.432311 -36.063704) (xy 71.401538 -36.110217)
			(xy 71.364321 -36.151754) (xy 71.321453 -36.187429) (xy 71.273847 -36.216483) (xy 71.222518 -36.238295)
			(xy 71.168561 -36.252401) (xy 71.113124 -36.258501) (xy 71.05739 -36.256464) (xy 71.002547 -36.246334)
			(xy 70.949763 -36.228327) (xy 70.900163 -36.202826) (xy 70.854805 -36.170375) (xy 70.814656 -36.131666)
			(xy 70.78057 -36.087523) (xy 70.753274 -36.038888) (xy 70.733351 -35.986797) (xy 70.721225 -35.93236)
			(xy 70.717154 -35.876738) (xy 65.605112 -35.876738) (xy 65.656127 -35.924383) (xy 65.714711 -35.990047)
			(xy 65.767082 -36.060766) (xy 65.812805 -36.135954) (xy 65.851502 -36.214989) (xy 65.882851 -36.297215)
			(xy 65.906593 -36.381951) (xy 65.922531 -36.468495) (xy 65.926317 -36.50996) (xy 72.613772 -36.50996)
			(xy 72.617843 -36.454338) (xy 72.629969 -36.399901) (xy 72.649892 -36.34781) (xy 72.677188 -36.299175)
			(xy 72.711274 -36.255032) (xy 72.751423 -36.216323) (xy 72.796781 -36.183872) (xy 72.846381 -36.158371)
			(xy 72.899165 -36.140364) (xy 72.954008 -36.130234) (xy 73.009742 -36.128197) (xy 73.065179 -36.134297)
			(xy 73.119136 -36.148403) (xy 73.170465 -36.170215) (xy 73.218071 -36.199269) (xy 73.260939 -36.234944)
			(xy 73.298156 -36.276481) (xy 73.328929 -36.322994) (xy 73.352601 -36.373491) (xy 73.368669 -36.426898)
			(xy 73.372594 -36.453572) (xy 75.928472 -36.453572) (xy 75.932543 -36.39795) (xy 75.944669 -36.343513)
			(xy 75.964592 -36.291422) (xy 75.991888 -36.242787) (xy 76.025974 -36.198644) (xy 76.066123 -36.159935)
			(xy 76.111481 -36.127484) (xy 76.161081 -36.101983) (xy 76.213865 -36.083976) (xy 76.268708 -36.073846)
			(xy 76.324442 -36.071809) (xy 76.379879 -36.077909) (xy 76.433836 -36.092015) (xy 76.485165 -36.113827)
			(xy 76.532771 -36.142881) (xy 76.575639 -36.178556) (xy 76.612856 -36.220093) (xy 76.643629 -36.266606)
			(xy 76.667301 -36.317103) (xy 76.683369 -36.37051) (xy 76.691489 -36.425686) (xy 76.691998 -36.453572)
			(xy 76.691489 -36.481458) (xy 76.683369 -36.536634) (xy 76.667301 -36.590041) (xy 76.643629 -36.640538)
			(xy 76.612856 -36.687051) (xy 76.575639 -36.728588) (xy 76.532771 -36.764263) (xy 76.485165 -36.793317)
			(xy 76.433836 -36.815129) (xy 76.379879 -36.829235) (xy 76.324442 -36.835335) (xy 76.268708 -36.833298)
			(xy 76.213865 -36.823168) (xy 76.161081 -36.805161) (xy 76.111481 -36.77966) (xy 76.066123 -36.747209)
			(xy 76.025974 -36.7085) (xy 75.991888 -36.664357) (xy 75.964592 -36.615722) (xy 75.944669 -36.563631)
			(xy 75.932543 -36.509194) (xy 75.928472 -36.453572) (xy 73.372594 -36.453572) (xy 73.376789 -36.482074)
			(xy 73.377298 -36.50996) (xy 73.376789 -36.537846) (xy 73.368669 -36.593022) (xy 73.352601 -36.646429)
			(xy 73.328929 -36.696926) (xy 73.298156 -36.743439) (xy 73.260939 -36.784976) (xy 73.218071 -36.820651)
			(xy 73.170465 -36.849705) (xy 73.119136 -36.871517) (xy 73.065179 -36.885623) (xy 73.009742 -36.891723)
			(xy 72.954008 -36.889686) (xy 72.899165 -36.879556) (xy 72.846381 -36.861549) (xy 72.796781 -36.836048)
			(xy 72.751423 -36.803597) (xy 72.711274 -36.764888) (xy 72.677188 -36.720745) (xy 72.649892 -36.67211)
			(xy 72.629969 -36.620019) (xy 72.617843 -36.565582) (xy 72.613772 -36.50996) (xy 65.926317 -36.50996)
			(xy 65.930533 -36.55613) (xy 65.931034 -36.60013) (xy 65.930533 -36.64413) (xy 65.922531 -36.731765)
			(xy 65.906593 -36.818309) (xy 65.882851 -36.903045) (xy 65.851502 -36.985271) (xy 65.812805 -37.064306)
			(xy 65.767082 -37.139494) (xy 65.714711 -37.210213) (xy 65.656127 -37.275877) (xy 65.591813 -37.335942)
			(xy 65.522305 -37.389909) (xy 65.448177 -37.437331) (xy 65.375171 -37.47516) (xy 69.759066 -37.47516)
			(xy 69.763137 -37.419538) (xy 69.775263 -37.365101) (xy 69.795186 -37.31301) (xy 69.822482 -37.264375)
			(xy 69.856568 -37.220232) (xy 69.896717 -37.181523) (xy 69.942075 -37.149072) (xy 69.991675 -37.123571)
			(xy 70.044459 -37.105564) (xy 70.099302 -37.095434) (xy 70.155036 -37.093397) (xy 70.210473 -37.099497)
			(xy 70.26443 -37.113603) (xy 70.315759 -37.135415) (xy 70.363365 -37.164469) (xy 70.406233 -37.200144)
			(xy 70.44345 -37.241681) (xy 70.474223 -37.288194) (xy 70.497895 -37.338691) (xy 70.513963 -37.392098)
			(xy 70.522083 -37.447274) (xy 70.522592 -37.47516) (xy 70.522083 -37.503046) (xy 70.513963 -37.558222)
			(xy 70.497895 -37.611629) (xy 70.474223 -37.662126) (xy 70.47407 -37.662358) (xy 71.948292 -37.662358)
			(xy 71.952363 -37.606736) (xy 71.964489 -37.552299) (xy 71.984412 -37.500208) (xy 72.011708 -37.451573)
			(xy 72.045794 -37.40743) (xy 72.085943 -37.368721) (xy 72.131301 -37.33627) (xy 72.180901 -37.310769)
			(xy 72.233685 -37.292762) (xy 72.288528 -37.282632) (xy 72.344262 -37.280595) (xy 72.399699 -37.286695)
			(xy 72.453656 -37.300801) (xy 72.504985 -37.322613) (xy 72.552591 -37.351667) (xy 72.595459 -37.387342)
			(xy 72.632676 -37.428879) (xy 72.663449 -37.475392) (xy 72.687121 -37.525889) (xy 72.703189 -37.579296)
			(xy 72.711309 -37.634472) (xy 72.711818 -37.662358) (xy 72.711309 -37.690244) (xy 72.703189 -37.74542)
			(xy 72.687121 -37.798827) (xy 72.663449 -37.849324) (xy 72.632676 -37.895837) (xy 72.595459 -37.937374)
			(xy 72.552591 -37.973049) (xy 72.504985 -38.002103) (xy 72.453656 -38.023915) (xy 72.399699 -38.038021)
			(xy 72.344262 -38.044121) (xy 72.288528 -38.042084) (xy 72.233685 -38.031954) (xy 72.180901 -38.013947)
			(xy 72.131301 -37.988446) (xy 72.085943 -37.955995) (xy 72.045794 -37.917286) (xy 72.011708 -37.873143)
			(xy 71.984412 -37.824508) (xy 71.964489 -37.772417) (xy 71.952363 -37.71798) (xy 71.948292 -37.662358)
			(xy 70.47407 -37.662358) (xy 70.44345 -37.708639) (xy 70.406233 -37.750176) (xy 70.363365 -37.785851)
			(xy 70.315759 -37.814905) (xy 70.26443 -37.836717) (xy 70.210473 -37.850823) (xy 70.155036 -37.856923)
			(xy 70.099302 -37.854886) (xy 70.044459 -37.844756) (xy 69.991675 -37.826749) (xy 69.942075 -37.801248)
			(xy 69.896717 -37.768797) (xy 69.856568 -37.730088) (xy 69.822482 -37.685945) (xy 69.795186 -37.63731)
			(xy 69.775263 -37.585219) (xy 69.763137 -37.530782) (xy 69.759066 -37.47516) (xy 65.375171 -37.47516)
			(xy 65.370043 -37.477817) (xy 65.288552 -37.51103) (xy 65.204378 -37.536694) (xy 65.118219 -37.554598)
			(xy 65.030789 -37.564593) (xy 64.942812 -37.566597) (xy 64.855018 -37.560591) (xy 64.768134 -37.546627)
			(xy 64.682879 -37.52482) (xy 64.59996 -37.495351) (xy 64.520065 -37.458464) (xy 64.443856 -37.414464)
			(xy 64.371963 -37.363716) (xy 64.304982 -37.306642) (xy 64.24347 -37.243712) (xy 64.187934 -37.17545)
			(xy 64.138836 -37.102421) (xy 64.096583 -37.025229) (xy 64.061524 -36.944515) (xy 64.033949 -36.860947)
			(xy 64.014089 -36.775218) (xy 64.002106 -36.688038) (xy 63.998101 -36.60013) (xy 59.768544 -36.60013)
			(xy 59.752933 -36.652017) (xy 59.729261 -36.702514) (xy 59.698488 -36.749027) (xy 59.661271 -36.790564)
			(xy 59.618403 -36.826239) (xy 59.570797 -36.855293) (xy 59.519468 -36.877105) (xy 59.465511 -36.891211)
			(xy 59.410074 -36.897311) (xy 59.35434 -36.895274) (xy 59.299497 -36.885144) (xy 59.246713 -36.867137)
			(xy 59.197113 -36.841636) (xy 59.151755 -36.809185) (xy 59.111606 -36.770476) (xy 59.07752 -36.726333)
			(xy 59.050224 -36.677698) (xy 59.030301 -36.625607) (xy 59.018175 -36.57117) (xy 59.014104 -36.515548)
			(xy 57.887902 -36.515548) (xy 57.884674 -36.520427) (xy 57.847457 -36.561964) (xy 57.804589 -36.597639)
			(xy 57.756983 -36.626693) (xy 57.705654 -36.648505) (xy 57.651697 -36.662611) (xy 57.59626 -36.668711)
			(xy 57.540526 -36.666674) (xy 57.485683 -36.656544) (xy 57.432899 -36.638537) (xy 57.383299 -36.613036)
			(xy 57.337941 -36.580585) (xy 57.297792 -36.541876) (xy 57.263706 -36.497733) (xy 57.23641 -36.449098)
			(xy 57.216487 -36.397007) (xy 57.204361 -36.34257) (xy 57.20029 -36.286948) (xy 54.293516 -36.286948)
			(xy 55.780686 -37.774118) (xy 57.464704 -37.774118) (xy 57.468775 -37.718496) (xy 57.480901 -37.664059)
			(xy 57.500824 -37.611968) (xy 57.52812 -37.563333) (xy 57.562206 -37.51919) (xy 57.602355 -37.480481)
			(xy 57.647713 -37.44803) (xy 57.697313 -37.422529) (xy 57.750097 -37.404522) (xy 57.80494 -37.394392)
			(xy 57.860674 -37.392355) (xy 57.916111 -37.398455) (xy 57.970068 -37.412561) (xy 58.021397 -37.434373)
			(xy 58.069003 -37.463427) (xy 58.111871 -37.499102) (xy 58.149088 -37.540639) (xy 58.179861 -37.587152)
			(xy 58.203533 -37.637649) (xy 58.219601 -37.691056) (xy 58.227721 -37.746232) (xy 58.22823 -37.774118)
			(xy 58.227721 -37.802004) (xy 58.219601 -37.85718) (xy 58.203533 -37.910587) (xy 58.179861 -37.961084)
			(xy 58.149088 -38.007597) (xy 58.111871 -38.049134) (xy 58.069003 -38.084809) (xy 58.021397 -38.113863)
			(xy 57.970068 -38.135675) (xy 57.916111 -38.149781) (xy 57.860674 -38.155881) (xy 57.80494 -38.153844)
			(xy 57.750097 -38.143714) (xy 57.697313 -38.125707) (xy 57.647713 -38.100206) (xy 57.602355 -38.067755)
			(xy 57.562206 -38.029046) (xy 57.52812 -37.984903) (xy 57.500824 -37.936268) (xy 57.480901 -37.884177)
			(xy 57.468775 -37.82974) (xy 57.464704 -37.774118) (xy 55.780686 -37.774118) (xy 56.736516 -38.729948)
			(xy 75.70092 -38.729948) (xy 75.70092 -38.675452) (xy 75.708676 -38.621511) (xy 75.724028 -38.569223)
			(xy 75.746666 -38.519652) (xy 75.776128 -38.473807) (xy 75.811815 -38.432622) (xy 75.852999 -38.396934)
			(xy 75.898843 -38.367471) (xy 75.948414 -38.344832) (xy 76.000702 -38.329478) (xy 76.054642 -38.321721)
			(xy 76.08189 -38.321234) (xy 76.110195 -38.321716) (xy 76.166184 -38.330067) (xy 76.220324 -38.346603)
			(xy 76.271425 -38.370959) (xy 76.318365 -38.402601) (xy 76.360112 -38.440834) (xy 76.395749 -38.484818)
			(xy 76.410566 -38.50894) (xy 76.418111 -38.521011) (xy 76.438741 -38.540615) (xy 76.463984 -38.553756)
			(xy 76.491876 -38.559412) (xy 76.520244 -38.557141) (xy 76.54688 -38.54712) (xy 76.569711 -38.53013)
			(xy 76.578714 -38.5191) (xy 76.596897 -38.496221) (xy 76.639061 -38.455758) (xy 76.686897 -38.42219)
			(xy 76.73929 -38.396304) (xy 76.795015 -38.378702) (xy 76.852771 -38.369797) (xy 76.88199 -38.36924)
			(xy 76.909247 -38.369606) (xy 76.963206 -38.377363) (xy 77.015511 -38.39272) (xy 77.065099 -38.415365)
			(xy 77.110959 -38.444836) (xy 77.152158 -38.480535) (xy 77.187858 -38.521733) (xy 77.21733 -38.567592)
			(xy 77.239976 -38.617179) (xy 77.255335 -38.669485) (xy 77.263093 -38.723443) (xy 77.263093 -38.777957)
			(xy 77.255335 -38.831915) (xy 77.239976 -38.884221) (xy 77.21733 -38.933808) (xy 77.187858 -38.979667)
			(xy 77.152158 -39.020865) (xy 77.110959 -39.056564) (xy 77.065099 -39.086035) (xy 77.015511 -39.10868)
			(xy 76.963206 -39.124037) (xy 76.909247 -39.131794) (xy 76.88199 -39.132256) (xy 76.853685 -39.131795)
			(xy 76.797694 -39.12344) (xy 76.743553 -39.106902) (xy 76.692452 -39.082542) (xy 76.645512 -39.050896)
			(xy 76.603766 -39.01266) (xy 76.56813 -38.968674) (xy 76.553314 -38.94455) (xy 76.545665 -38.932552)
			(xy 76.525056 -38.912954) (xy 76.499835 -38.899812) (xy 76.471965 -38.894149) (xy 76.443615 -38.896405)
			(xy 76.416992 -38.906406) (xy 76.394168 -38.923372) (xy 76.385166 -38.93439) (xy 76.366991 -38.957276)
			(xy 76.324827 -38.99774) (xy 76.276988 -39.031306) (xy 76.224594 -39.057192) (xy 76.168868 -39.074792)
			(xy 76.11111 -39.083695) (xy 76.08189 -39.08425) (xy 76.054642 -39.083679) (xy 76.000702 -39.075922)
			(xy 75.948414 -39.060568) (xy 75.898843 -39.037929) (xy 75.852999 -39.008466) (xy 75.811815 -38.972778)
			(xy 75.776128 -38.931593) (xy 75.746666 -38.885748) (xy 75.724028 -38.836177) (xy 75.708676 -38.783889)
			(xy 75.70092 -38.729948) (xy 56.736516 -38.729948) (xy 57.978548 -39.97198) (xy 77.895702 -39.97198)
			(xy 77.899773 -39.916358) (xy 77.911899 -39.861921) (xy 77.931822 -39.80983) (xy 77.959118 -39.761195)
			(xy 77.993204 -39.717052) (xy 78.033353 -39.678343) (xy 78.078711 -39.645892) (xy 78.128311 -39.620391)
			(xy 78.181095 -39.602384) (xy 78.235938 -39.592254) (xy 78.291672 -39.590217) (xy 78.347109 -39.596317)
			(xy 78.401066 -39.610423) (xy 78.452395 -39.632235) (xy 78.500001 -39.661289) (xy 78.542869 -39.696964)
			(xy 78.580086 -39.738501) (xy 78.610859 -39.785014) (xy 78.634531 -39.835511) (xy 78.650599 -39.888918)
			(xy 78.658719 -39.944094) (xy 78.659228 -39.97198) (xy 78.658719 -39.999866) (xy 78.650599 -40.055042)
			(xy 78.634531 -40.108449) (xy 78.610859 -40.158946) (xy 78.580086 -40.205459) (xy 78.542869 -40.246996)
			(xy 78.500001 -40.282671) (xy 78.452395 -40.311725) (xy 78.401066 -40.333537) (xy 78.347109 -40.347643)
			(xy 78.291672 -40.353743) (xy 78.235938 -40.351706) (xy 78.181095 -40.341576) (xy 78.128311 -40.323569)
			(xy 78.078711 -40.298068) (xy 78.033353 -40.265617) (xy 77.993204 -40.226908) (xy 77.959118 -40.182765)
			(xy 77.931822 -40.13413) (xy 77.911899 -40.082039) (xy 77.899773 -40.027602) (xy 77.895702 -39.97198)
			(xy 57.978548 -39.97198) (xy 59.275323 -41.268755) (xy 67.843827 -41.268755) (xy 67.843827 -41.214245)
			(xy 67.851585 -41.160289) (xy 67.866942 -41.107987) (xy 67.889587 -41.058402) (xy 67.919058 -41.012545)
			(xy 67.954755 -40.971349) (xy 67.995952 -40.935653) (xy 68.041809 -40.906183) (xy 68.091394 -40.883539)
			(xy 68.143697 -40.868183) (xy 68.197653 -40.860426) (xy 68.224908 -40.859964) (xy 68.253647 -40.860492)
			(xy 68.310473 -40.869115) (xy 68.365364 -40.886165) (xy 68.417075 -40.911255) (xy 68.464439 -40.943818)
			(xy 68.485766 -40.963088) (xy 68.492624 -40.969692) (xy 68.510658 -40.976804) (xy 68.599558 -40.976804)
			(xy 68.617592 -40.969692) (xy 68.62445 -40.963088) (xy 68.645781 -40.943822) (xy 68.693141 -40.911253)
			(xy 68.744852 -40.886159) (xy 68.799742 -40.869107) (xy 68.856569 -40.860484) (xy 68.885308 -40.859964)
			(xy 68.912557 -40.860507) (xy 68.9665 -40.868264) (xy 69.01879 -40.883618) (xy 69.068362 -40.906258)
			(xy 69.114208 -40.935722) (xy 69.155394 -40.971411) (xy 69.191082 -41.012598) (xy 69.220546 -41.058445)
			(xy 69.243185 -41.108018) (xy 69.258538 -41.160308) (xy 69.266294 -41.214251) (xy 69.266294 -41.268749)
			(xy 69.258538 -41.322692) (xy 69.243185 -41.374982) (xy 69.220546 -41.424555) (xy 69.191082 -41.470402)
			(xy 69.155394 -41.511589) (xy 69.114208 -41.547277) (xy 69.068362 -41.576742) (xy 69.01879 -41.599382)
			(xy 68.9665 -41.614736) (xy 68.912557 -41.622493) (xy 68.885308 -41.62298) (xy 68.85657 -41.62243)
			(xy 68.799745 -41.613811) (xy 68.744855 -41.596765) (xy 68.693143 -41.57168) (xy 68.645779 -41.539123)
			(xy 68.62445 -41.519856) (xy 68.617592 -41.513252) (xy 68.599558 -41.50614) (xy 68.510658 -41.50614)
			(xy 68.492624 -41.513252) (xy 68.485766 -41.519856) (xy 68.464435 -41.539122) (xy 68.417074 -41.571689)
			(xy 68.365363 -41.596783) (xy 68.310474 -41.613834) (xy 68.253647 -41.622458) (xy 68.224908 -41.62298)
			(xy 68.197653 -41.622574) (xy 68.143697 -41.614817) (xy 68.091394 -41.599461) (xy 68.041809 -41.576817)
			(xy 67.995952 -41.547347) (xy 67.954755 -41.511651) (xy 67.919058 -41.470455) (xy 67.889587 -41.424598)
			(xy 67.866942 -41.375013) (xy 67.851585 -41.322711) (xy 67.843827 -41.268755) (xy 59.275323 -41.268755)
			(xy 61.31179 -43.305222) (xy 70.3072 -43.305222) (xy 70.307679 -43.277852) (xy 70.315494 -43.223674)
			(xy 70.33098 -43.171171) (xy 70.353819 -43.121424) (xy 70.38354 -43.075456) (xy 70.40118 -43.054524)
			(xy 70.401434 -43.05427) (xy 70.407001 -43.04717) (xy 70.413258 -43.030263) (xy 70.413626 -43.02125)
			(xy 70.413626 -42.954194) (xy 70.413266 -42.945178) (xy 70.40702 -42.928261) (xy 70.401434 -42.921174)
			(xy 70.40118 -42.921174) (xy 70.40118 -42.92092) (xy 70.383534 -42.899994) (xy 70.353824 -42.854019)
			(xy 70.330989 -42.80427) (xy 70.3155 -42.751768) (xy 70.307673 -42.697592) (xy 70.3072 -42.670222)
			(xy 70.307737 -42.641484) (xy 70.316356 -42.584657) (xy 70.333403 -42.529766) (xy 70.358492 -42.478054)
			(xy 70.391054 -42.430691) (xy 70.410324 -42.409364) (xy 70.416928 -42.402506) (xy 70.42404 -42.384472)
			(xy 70.42404 -42.295572) (xy 70.416928 -42.277538) (xy 70.410324 -42.27068) (xy 70.391075 -42.249334)
			(xy 70.358509 -42.201975) (xy 70.333416 -42.150266) (xy 70.316365 -42.095379) (xy 70.30774 -42.038554)
			(xy 70.307738 -41.981078) (xy 70.316357 -41.924253) (xy 70.333404 -41.869364) (xy 70.358493 -41.817653)
			(xy 70.391055 -41.770291) (xy 70.410324 -41.748964) (xy 70.416928 -41.742106) (xy 70.42404 -41.724072)
			(xy 70.42404 -41.635172) (xy 70.416928 -41.617138) (xy 70.410324 -41.61028) (xy 70.391061 -41.588946)
			(xy 70.358494 -41.541586) (xy 70.333401 -41.489876) (xy 70.316348 -41.434987) (xy 70.307723 -41.37816)
			(xy 70.3072 -41.349422) (xy 70.307686 -41.322171) (xy 70.315442 -41.268223) (xy 70.330797 -41.215928)
			(xy 70.353439 -41.166351) (xy 70.382905 -41.120501) (xy 70.418596 -41.07931) (xy 70.459787 -41.043619)
			(xy 70.505637 -41.014153) (xy 70.555214 -40.991511) (xy 70.607509 -40.976156) (xy 70.661457 -40.9684)
			(xy 70.715959 -40.9684) (xy 70.73908 -40.971724) (xy 78.593948 -40.971724) (xy 78.598019 -40.916102)
			(xy 78.610145 -40.861665) (xy 78.630068 -40.809574) (xy 78.657364 -40.760939) (xy 78.69145 -40.716796)
			(xy 78.731599 -40.678087) (xy 78.776957 -40.645636) (xy 78.826557 -40.620135) (xy 78.879341 -40.602128)
			(xy 78.934184 -40.591998) (xy 78.989918 -40.589961) (xy 79.045355 -40.596061) (xy 79.099312 -40.610167)
			(xy 79.150641 -40.631979) (xy 79.198247 -40.661033) (xy 79.241115 -40.696708) (xy 79.278332 -40.738245)
			(xy 79.309105 -40.784758) (xy 79.332777 -40.835255) (xy 79.348845 -40.888662) (xy 79.356965 -40.943838)
			(xy 79.357474 -40.971724) (xy 79.356965 -40.99961) (xy 79.348845 -41.054786) (xy 79.332777 -41.108193)
			(xy 79.309105 -41.15869) (xy 79.278332 -41.205203) (xy 79.241115 -41.24674) (xy 79.198247 -41.282415)
			(xy 79.150641 -41.311469) (xy 79.099312 -41.333281) (xy 79.045355 -41.347387) (xy 78.989918 -41.353487)
			(xy 78.934184 -41.35145) (xy 78.879341 -41.34132) (xy 78.826557 -41.323313) (xy 78.776957 -41.297812)
			(xy 78.731599 -41.265361) (xy 78.69145 -41.226652) (xy 78.657364 -41.182509) (xy 78.630068 -41.133874)
			(xy 78.610145 -41.081783) (xy 78.598019 -41.027346) (xy 78.593948 -40.971724) (xy 70.73908 -40.971724)
			(xy 70.769907 -40.976156) (xy 70.822202 -40.991511) (xy 70.871779 -41.014153) (xy 70.917629 -41.043619)
			(xy 70.95882 -41.07931) (xy 70.994511 -41.120501) (xy 71.023977 -41.166351) (xy 71.046619 -41.215928)
			(xy 71.061974 -41.268223) (xy 71.06973 -41.322171) (xy 71.070216 -41.349422) (xy 71.069701 -41.378161)
			(xy 71.061076 -41.434989) (xy 71.044023 -41.489879) (xy 71.01893 -41.541591) (xy 70.986363 -41.588953)
			(xy 70.967092 -41.61028) (xy 70.960488 -41.617138) (xy 70.953376 -41.635172) (xy 70.953376 -41.724072)
			(xy 70.960488 -41.742106) (xy 70.967092 -41.748964) (xy 70.986384 -41.770272) (xy 71.018947 -41.817638)
			(xy 71.044036 -41.869353) (xy 71.061084 -41.924247) (xy 71.069704 -41.981076) (xy 71.069702 -42.038556)
			(xy 71.061077 -42.095385) (xy 71.044025 -42.150277) (xy 71.018931 -42.201989) (xy 70.986364 -42.249353)
			(xy 70.967092 -42.27068) (xy 70.960488 -42.277538) (xy 70.953376 -42.295572) (xy 70.953376 -42.384472)
			(xy 70.960488 -42.402506) (xy 70.967092 -42.409364) (xy 70.986378 -42.430678) (xy 71.018941 -42.478044)
			(xy 71.04403 -42.529759) (xy 71.061077 -42.584652) (xy 71.069697 -42.641482) (xy 71.070216 -42.670222)
			(xy 71.069783 -42.697594) (xy 71.061961 -42.751775) (xy 71.046465 -42.804279) (xy 71.025906 -42.849038)
			(xy 72.891902 -42.849038) (xy 72.895973 -42.793416) (xy 72.908099 -42.738979) (xy 72.928022 -42.686888)
			(xy 72.955318 -42.638253) (xy 72.989404 -42.59411) (xy 73.029553 -42.555401) (xy 73.074911 -42.52295)
			(xy 73.124511 -42.497449) (xy 73.177295 -42.479442) (xy 73.232138 -42.469312) (xy 73.287872 -42.467275)
			(xy 73.343309 -42.473375) (xy 73.397266 -42.487481) (xy 73.448595 -42.509293) (xy 73.496201 -42.538347)
			(xy 73.539069 -42.574022) (xy 73.576286 -42.615559) (xy 73.607059 -42.662072) (xy 73.630731 -42.712569)
			(xy 73.646799 -42.765976) (xy 73.654919 -42.821152) (xy 73.65528 -42.84091) (xy 78.933038 -42.84091)
			(xy 78.937109 -42.785288) (xy 78.949235 -42.730851) (xy 78.969158 -42.67876) (xy 78.996454 -42.630125)
			(xy 79.03054 -42.585982) (xy 79.070689 -42.547273) (xy 79.116047 -42.514822) (xy 79.165647 -42.489321)
			(xy 79.218431 -42.471314) (xy 79.273274 -42.461184) (xy 79.329008 -42.459147) (xy 79.384445 -42.465247)
			(xy 79.438402 -42.479353) (xy 79.489731 -42.501165) (xy 79.537337 -42.530219) (xy 79.580205 -42.565894)
			(xy 79.617422 -42.607431) (xy 79.648195 -42.653944) (xy 79.671867 -42.704441) (xy 79.687935 -42.757848)
			(xy 79.696055 -42.813024) (xy 79.696564 -42.84091) (xy 79.696055 -42.868796) (xy 79.687935 -42.923972)
			(xy 79.671867 -42.977379) (xy 79.648195 -43.027876) (xy 79.617422 -43.074389) (xy 79.580205 -43.115926)
			(xy 79.537337 -43.151601) (xy 79.489731 -43.180655) (xy 79.438402 -43.202467) (xy 79.384445 -43.216573)
			(xy 79.329008 -43.222673) (xy 79.273274 -43.220636) (xy 79.218431 -43.210506) (xy 79.165647 -43.192499)
			(xy 79.116047 -43.166998) (xy 79.070689 -43.134547) (xy 79.03054 -43.095838) (xy 78.996454 -43.051695)
			(xy 78.969158 -43.00306) (xy 78.949235 -42.950969) (xy 78.937109 -42.896532) (xy 78.933038 -42.84091)
			(xy 73.65528 -42.84091) (xy 73.655428 -42.849038) (xy 73.654919 -42.876924) (xy 73.646799 -42.9321)
			(xy 73.630731 -42.985507) (xy 73.607059 -43.036004) (xy 73.576286 -43.082517) (xy 73.539069 -43.124054)
			(xy 73.496201 -43.159729) (xy 73.448595 -43.188783) (xy 73.397266 -43.210595) (xy 73.343309 -43.224701)
			(xy 73.287872 -43.230801) (xy 73.232138 -43.228764) (xy 73.177295 -43.218634) (xy 73.124511 -43.200627)
			(xy 73.074911 -43.175126) (xy 73.029553 -43.142675) (xy 72.989404 -43.103966) (xy 72.955318 -43.059823)
			(xy 72.928022 -43.011188) (xy 72.908099 -42.959097) (xy 72.895973 -42.90466) (xy 72.891902 -42.849038)
			(xy 71.025906 -42.849038) (xy 71.023615 -42.854026) (xy 70.993882 -42.89999) (xy 70.976236 -42.92092)
			(xy 70.975982 -42.921174) (xy 70.970398 -42.928262) (xy 70.96415 -42.945178) (xy 70.96379 -42.954194)
			(xy 70.96379 -43.02125) (xy 70.964173 -43.030264) (xy 70.970403 -43.047181) (xy 70.975982 -43.05427)
			(xy 70.976236 -43.05427) (xy 70.976236 -43.054524) (xy 70.993859 -43.075469) (xy 71.023572 -43.121439)
			(xy 71.04641 -43.171183) (xy 71.061905 -43.223681) (xy 71.069739 -43.277854) (xy 71.070216 -43.305222)
			(xy 71.06973 -43.332473) (xy 71.061974 -43.386421) (xy 71.046619 -43.438716) (xy 71.023977 -43.488293)
			(xy 70.994511 -43.534143) (xy 70.95882 -43.575334) (xy 70.917629 -43.611025) (xy 70.871779 -43.640491)
			(xy 70.822202 -43.663133) (xy 70.769907 -43.678488) (xy 70.715959 -43.686244) (xy 70.661457 -43.686244)
			(xy 70.607509 -43.678488) (xy 70.555214 -43.663133) (xy 70.505637 -43.640491) (xy 70.459787 -43.611025)
			(xy 70.418596 -43.575334) (xy 70.382905 -43.534143) (xy 70.353439 -43.488293) (xy 70.330797 -43.438716)
			(xy 70.315442 -43.386421) (xy 70.307686 -43.332473) (xy 70.3072 -43.305222) (xy 61.31179 -43.305222)
			(xy 61.742828 -43.73626) (xy 72.21296 -43.73626) (xy 72.217031 -43.680638) (xy 72.229157 -43.626201)
			(xy 72.24908 -43.57411) (xy 72.276376 -43.525475) (xy 72.310462 -43.481332) (xy 72.350611 -43.442623)
			(xy 72.395969 -43.410172) (xy 72.445569 -43.384671) (xy 72.498353 -43.366664) (xy 72.553196 -43.356534)
			(xy 72.60893 -43.354497) (xy 72.664367 -43.360597) (xy 72.718324 -43.374703) (xy 72.769653 -43.396515)
			(xy 72.817259 -43.425569) (xy 72.860127 -43.461244) (xy 72.897344 -43.502781) (xy 72.928117 -43.549294)
			(xy 72.951789 -43.599791) (xy 72.967857 -43.653198) (xy 72.975977 -43.708374) (xy 72.976486 -43.73626)
			(xy 72.975977 -43.764146) (xy 72.967857 -43.819322) (xy 72.956548 -43.85691) (xy 76.719682 -43.85691)
			(xy 76.723753 -43.801288) (xy 76.735879 -43.746851) (xy 76.755802 -43.69476) (xy 76.783098 -43.646125)
			(xy 76.817184 -43.601982) (xy 76.857333 -43.563273) (xy 76.902691 -43.530822) (xy 76.952291 -43.505321)
			(xy 77.005075 -43.487314) (xy 77.059918 -43.477184) (xy 77.115652 -43.475147) (xy 77.171089 -43.481247)
			(xy 77.225046 -43.495353) (xy 77.276375 -43.517165) (xy 77.323981 -43.546219) (xy 77.366849 -43.581894)
			(xy 77.404066 -43.623431) (xy 77.434839 -43.669944) (xy 77.458511 -43.720441) (xy 77.474579 -43.773848)
			(xy 77.482699 -43.829024) (xy 77.483208 -43.85691) (xy 77.482699 -43.884796) (xy 77.474579 -43.939972)
			(xy 77.458511 -43.993379) (xy 77.434839 -44.043876) (xy 77.404066 -44.090389) (xy 77.366849 -44.131926)
			(xy 77.323981 -44.167601) (xy 77.276375 -44.196655) (xy 77.225046 -44.218467) (xy 77.171089 -44.232573)
			(xy 77.115652 -44.238673) (xy 77.059918 -44.236636) (xy 77.005075 -44.226506) (xy 76.952291 -44.208499)
			(xy 76.902691 -44.182998) (xy 76.857333 -44.150547) (xy 76.817184 -44.111838) (xy 76.783098 -44.067695)
			(xy 76.755802 -44.01906) (xy 76.735879 -43.966969) (xy 76.723753 -43.912532) (xy 76.719682 -43.85691)
			(xy 72.956548 -43.85691) (xy 72.951789 -43.872729) (xy 72.928117 -43.923226) (xy 72.897344 -43.969739)
			(xy 72.860127 -44.011276) (xy 72.817259 -44.046951) (xy 72.769653 -44.076005) (xy 72.718324 -44.097817)
			(xy 72.664367 -44.111923) (xy 72.60893 -44.118023) (xy 72.553196 -44.115986) (xy 72.498353 -44.105856)
			(xy 72.445569 -44.087849) (xy 72.395969 -44.062348) (xy 72.350611 -44.029897) (xy 72.310462 -43.991188)
			(xy 72.276376 -43.947045) (xy 72.24908 -43.89841) (xy 72.229157 -43.846319) (xy 72.217031 -43.791882)
			(xy 72.21296 -43.73626) (xy 61.742828 -43.73626) (xy 63.121032 -45.114464) (xy 72.065386 -45.114464)
			(xy 72.069457 -45.058842) (xy 72.081583 -45.004405) (xy 72.101506 -44.952314) (xy 72.128802 -44.903679)
			(xy 72.162888 -44.859536) (xy 72.203037 -44.820827) (xy 72.248395 -44.788376) (xy 72.297995 -44.762875)
			(xy 72.350779 -44.744868) (xy 72.405622 -44.734738) (xy 72.461356 -44.732701) (xy 72.516793 -44.738801)
			(xy 72.57075 -44.752907) (xy 72.622079 -44.774719) (xy 72.669685 -44.803773) (xy 72.712553 -44.839448)
			(xy 72.742535 -44.87291) (xy 78.933038 -44.87291) (xy 78.937109 -44.817288) (xy 78.949235 -44.762851)
			(xy 78.969158 -44.71076) (xy 78.996454 -44.662125) (xy 79.03054 -44.617982) (xy 79.070689 -44.579273)
			(xy 79.116047 -44.546822) (xy 79.165647 -44.521321) (xy 79.218431 -44.503314) (xy 79.273274 -44.493184)
			(xy 79.329008 -44.491147) (xy 79.384445 -44.497247) (xy 79.438402 -44.511353) (xy 79.489731 -44.533165)
			(xy 79.537337 -44.562219) (xy 79.580205 -44.597894) (xy 79.617422 -44.639431) (xy 79.648195 -44.685944)
			(xy 79.671867 -44.736441) (xy 79.687935 -44.789848) (xy 79.696055 -44.845024) (xy 79.696564 -44.87291)
			(xy 79.696055 -44.900796) (xy 79.687935 -44.955972) (xy 79.671867 -45.009379) (xy 79.648195 -45.059876)
			(xy 79.617422 -45.106389) (xy 79.580205 -45.147926) (xy 79.537337 -45.183601) (xy 79.489731 -45.212655)
			(xy 79.438402 -45.234467) (xy 79.384445 -45.248573) (xy 79.329008 -45.254673) (xy 79.273274 -45.252636)
			(xy 79.218431 -45.242506) (xy 79.165647 -45.224499) (xy 79.116047 -45.198998) (xy 79.070689 -45.166547)
			(xy 79.03054 -45.127838) (xy 78.996454 -45.083695) (xy 78.969158 -45.03506) (xy 78.949235 -44.982969)
			(xy 78.937109 -44.928532) (xy 78.933038 -44.87291) (xy 72.742535 -44.87291) (xy 72.74977 -44.880985)
			(xy 72.780543 -44.927498) (xy 72.804215 -44.977995) (xy 72.820283 -45.031402) (xy 72.828403 -45.086578)
			(xy 72.828912 -45.114464) (xy 72.828403 -45.14235) (xy 72.820283 -45.197526) (xy 72.804215 -45.250933)
			(xy 72.780543 -45.30143) (xy 72.74977 -45.347943) (xy 72.744128 -45.35424) (xy 76.70368 -45.35424)
			(xy 76.707751 -45.298618) (xy 76.719877 -45.244181) (xy 76.7398 -45.19209) (xy 76.767096 -45.143455)
			(xy 76.801182 -45.099312) (xy 76.841331 -45.060603) (xy 76.886689 -45.028152) (xy 76.936289 -45.002651)
			(xy 76.989073 -44.984644) (xy 77.043916 -44.974514) (xy 77.09965 -44.972477) (xy 77.155087 -44.978577)
			(xy 77.209044 -44.992683) (xy 77.260373 -45.014495) (xy 77.307979 -45.043549) (xy 77.350847 -45.079224)
			(xy 77.388064 -45.120761) (xy 77.418837 -45.167274) (xy 77.442509 -45.217771) (xy 77.458577 -45.271178)
			(xy 77.466697 -45.326354) (xy 77.467206 -45.35424) (xy 77.466697 -45.382126) (xy 77.458577 -45.437302)
			(xy 77.442509 -45.490709) (xy 77.418837 -45.541206) (xy 77.388064 -45.587719) (xy 77.350847 -45.629256)
			(xy 77.307979 -45.664931) (xy 77.260373 -45.693985) (xy 77.209044 -45.715797) (xy 77.155087 -45.729903)
			(xy 77.09965 -45.736003) (xy 77.043916 -45.733966) (xy 76.989073 -45.723836) (xy 76.936289 -45.705829)
			(xy 76.886689 -45.680328) (xy 76.841331 -45.647877) (xy 76.801182 -45.609168) (xy 76.767096 -45.565025)
			(xy 76.7398 -45.51639) (xy 76.719877 -45.464299) (xy 76.707751 -45.409862) (xy 76.70368 -45.35424)
			(xy 72.744128 -45.35424) (xy 72.712553 -45.38948) (xy 72.669685 -45.425155) (xy 72.622079 -45.454209)
			(xy 72.57075 -45.476021) (xy 72.516793 -45.490127) (xy 72.461356 -45.496227) (xy 72.405622 -45.49419)
			(xy 72.350779 -45.48406) (xy 72.297995 -45.466053) (xy 72.248395 -45.440552) (xy 72.203037 -45.408101)
			(xy 72.162888 -45.369392) (xy 72.128802 -45.325249) (xy 72.101506 -45.276614) (xy 72.081583 -45.224523)
			(xy 72.069457 -45.170086) (xy 72.065386 -45.114464) (xy 63.121032 -45.114464) (xy 63.841884 -45.835316)
			(xy 63.866411 -45.860566) (xy 63.909822 -45.915984) (xy 63.946232 -45.976232) (xy 63.97511 -46.040432)
			(xy 63.988114 -46.082204) (xy 70.052438 -46.082204) (xy 70.052859 -46.054949) (xy 70.060617 -46.000994)
			(xy 70.075975 -45.948693) (xy 70.09862 -45.89911) (xy 70.128092 -45.853254) (xy 70.16379 -45.81206)
			(xy 70.204988 -45.776367) (xy 70.250847 -45.7469) (xy 70.300432 -45.72426) (xy 70.352735 -45.708908)
			(xy 70.406691 -45.701156) (xy 70.433946 -45.700696) (xy 70.46085 -45.701123) (xy 70.514121 -45.708701)
			(xy 70.5658 -45.723687) (xy 70.614862 -45.745783) (xy 70.660334 -45.77455) (xy 70.701315 -45.80942)
			(xy 70.736991 -45.8497) (xy 70.752208 -45.871892) (xy 70.75932 -45.882814) (xy 70.78218 -45.894752)
			(xy 70.894448 -45.89272) (xy 70.9168 -45.879766) (xy 70.923658 -45.86859) (xy 70.938554 -45.844971)
			(xy 70.974237 -45.80202) (xy 71.0158 -45.764728) (xy 71.062354 -45.733892) (xy 71.112906 -45.710172)
			(xy 71.166375 -45.694073) (xy 71.22162 -45.68594) (xy 71.24954 -45.685456) (xy 71.276534 -45.685894)
			(xy 71.329983 -45.693506) (xy 71.381827 -45.708571) (xy 71.431031 -45.73079) (xy 71.476614 -45.75972)
			(xy 71.497444 -45.776896) (xy 71.505572 -45.784008) (xy 71.526146 -45.790104) (xy 71.61149 -45.779182)
			(xy 71.622036 -45.777413) (xy 71.640318 -45.766355) (xy 71.646796 -45.757846) (xy 71.662158 -45.736622)
			(xy 71.697744 -45.698169) (xy 71.738259 -45.66495) (xy 71.782941 -45.637591) (xy 71.830948 -45.616606)
			(xy 71.881375 -45.602391) (xy 71.933274 -45.595214) (xy 71.95947 -45.594778) (xy 71.986723 -45.595267)
			(xy 72.040675 -45.60302) (xy 72.092975 -45.618373) (xy 72.142557 -45.641013) (xy 72.188412 -45.670479)
			(xy 72.229607 -45.706172) (xy 72.265303 -45.747364) (xy 72.294772 -45.793217) (xy 72.317416 -45.842797)
			(xy 72.332773 -45.895095) (xy 72.340531 -45.949047) (xy 72.340531 -46.003553) (xy 72.332773 -46.057505)
			(xy 72.317416 -46.109803) (xy 72.294772 -46.159383) (xy 72.265303 -46.205236) (xy 72.229607 -46.246428)
			(xy 72.188412 -46.282121) (xy 72.142557 -46.311587) (xy 72.092975 -46.334227) (xy 72.040675 -46.34958)
			(xy 71.986723 -46.357333) (xy 71.95947 -46.357794) (xy 71.932477 -46.357338) (xy 71.879029 -46.349729)
			(xy 71.827186 -46.334667) (xy 71.777981 -46.312452) (xy 71.732397 -46.283528) (xy 71.711566 -46.266354)
			(xy 71.703438 -46.259242) (xy 71.682864 -46.253146) (xy 71.59752 -46.264068) (xy 71.58698 -46.26586)
			(xy 71.568696 -46.276903) (xy 71.562214 -46.285404) (xy 71.544596 -46.3097) (xy 71.503004 -46.352962)
			(xy 71.47941 -46.37151) (xy 71.471536 -46.377352) (xy 71.461122 -46.394878) (xy 71.447914 -46.485302)
			(xy 71.45274 -46.504606) (xy 71.458582 -46.51248) (xy 71.458582 -46.512734) (xy 71.476086 -46.537478)
			(xy 71.503888 -46.591331) (xy 71.522824 -46.648903) (xy 71.530027 -46.693836) (xy 76.67625 -46.693836)
			(xy 76.676736 -46.666585) (xy 76.684492 -46.612637) (xy 76.699847 -46.560342) (xy 76.722489 -46.510765)
			(xy 76.751955 -46.464915) (xy 76.787646 -46.423724) (xy 76.828837 -46.388033) (xy 76.874687 -46.358567)
			(xy 76.924264 -46.335925) (xy 76.976559 -46.32057) (xy 77.030507 -46.312814) (xy 77.085009 -46.312814)
			(xy 77.138957 -46.32057) (xy 77.191252 -46.335925) (xy 77.240829 -46.358567) (xy 77.286679 -46.388033)
			(xy 77.32787 -46.423724) (xy 77.363561 -46.464915) (xy 77.393027 -46.510765) (xy 77.415669 -46.560342)
			(xy 77.431024 -46.612637) (xy 77.43878 -46.666585) (xy 77.439266 -46.693836) (xy 77.438798 -46.720264)
			(xy 77.431488 -46.772611) (xy 77.417013 -46.823446) (xy 77.395652 -46.871793) (xy 77.382116 -46.894496)
			(xy 77.381862 -46.89475) (xy 77.376525 -46.904768) (xy 77.374267 -46.927318) (xy 77.377544 -46.938184)
			(xy 77.403706 -47.01286) (xy 77.408066 -47.023388) (xy 77.424171 -47.039472) (xy 77.434694 -47.043848)
			(xy 77.434948 -47.043848) (xy 77.459457 -47.052916) (xy 77.50591 -47.076859) (xy 77.548661 -47.106915)
			(xy 77.586913 -47.142523) (xy 77.61995 -47.183016) (xy 77.647153 -47.227637) (xy 77.668015 -47.275552)
			(xy 77.682145 -47.325866) (xy 77.689279 -47.377636) (xy 77.68971 -47.403766) (xy 77.689224 -47.431017)
			(xy 77.687701 -47.441612) (xy 78.96174 -47.441612) (xy 78.965811 -47.38599) (xy 78.977937 -47.331553)
			(xy 78.99786 -47.279462) (xy 79.025156 -47.230827) (xy 79.059242 -47.186684) (xy 79.099391 -47.147975)
			(xy 79.144749 -47.115524) (xy 79.194349 -47.090023) (xy 79.247133 -47.072016) (xy 79.301976 -47.061886)
			(xy 79.35771 -47.059849) (xy 79.413147 -47.065949) (xy 79.467104 -47.080055) (xy 79.518433 -47.101867)
			(xy 79.566039 -47.130921) (xy 79.608907 -47.166596) (xy 79.646124 -47.208133) (xy 79.676897 -47.254646)
			(xy 79.700569 -47.305143) (xy 79.716637 -47.35855) (xy 79.724757 -47.413726) (xy 79.725266 -47.441612)
			(xy 79.724757 -47.469498) (xy 79.716637 -47.524674) (xy 79.700569 -47.578081) (xy 79.676897 -47.628578)
			(xy 79.646124 -47.675091) (xy 79.608907 -47.716628) (xy 79.566039 -47.752303) (xy 79.518433 -47.781357)
			(xy 79.467104 -47.803169) (xy 79.413147 -47.817275) (xy 79.35771 -47.823375) (xy 79.301976 -47.821338)
			(xy 79.247133 -47.811208) (xy 79.194349 -47.793201) (xy 79.144749 -47.7677) (xy 79.099391 -47.735249)
			(xy 79.059242 -47.69654) (xy 79.025156 -47.652397) (xy 78.99786 -47.603762) (xy 78.977937 -47.551671)
			(xy 78.965811 -47.497234) (xy 78.96174 -47.441612) (xy 77.687701 -47.441612) (xy 77.681468 -47.484965)
			(xy 77.666113 -47.53726) (xy 77.643471 -47.586837) (xy 77.614005 -47.632687) (xy 77.578314 -47.673878)
			(xy 77.537123 -47.709569) (xy 77.491273 -47.739035) (xy 77.441696 -47.761677) (xy 77.389401 -47.777032)
			(xy 77.335453 -47.784788) (xy 77.280951 -47.784788) (xy 77.227003 -47.777032) (xy 77.174708 -47.761677)
			(xy 77.125131 -47.739035) (xy 77.079281 -47.709569) (xy 77.03809 -47.673878) (xy 77.002399 -47.632687)
			(xy 76.972933 -47.586837) (xy 76.950291 -47.53726) (xy 76.934936 -47.484965) (xy 76.92718 -47.431017)
			(xy 76.926694 -47.403766) (xy 76.927168 -47.377339) (xy 76.934477 -47.324991) (xy 76.94895 -47.274156)
			(xy 76.970309 -47.225809) (xy 76.983844 -47.203106) (xy 76.984098 -47.202852) (xy 76.989433 -47.192833)
			(xy 76.991694 -47.170283) (xy 76.988416 -47.159418) (xy 76.962254 -47.084742) (xy 76.957866 -47.074228)
			(xy 76.94178 -47.058139) (xy 76.931266 -47.053754) (xy 76.931012 -47.053754) (xy 76.906495 -47.044706)
			(xy 76.860044 -47.020759) (xy 76.817293 -46.990699) (xy 76.779042 -46.955089) (xy 76.746007 -46.914593)
			(xy 76.718805 -46.86997) (xy 76.697944 -46.822053) (xy 76.683815 -46.771738) (xy 76.676681 -46.719966)
			(xy 76.67625 -46.693836) (xy 71.530027 -46.693836) (xy 71.532417 -46.708745) (xy 71.533004 -46.739048)
			(xy 71.532567 -46.766301) (xy 71.524804 -46.82025) (xy 71.509442 -46.872546) (xy 71.486795 -46.922124)
			(xy 71.457324 -46.967974) (xy 71.421627 -47.009164) (xy 71.380433 -47.044855) (xy 71.334578 -47.07432)
			(xy 71.284997 -47.09696) (xy 71.232699 -47.112315) (xy 71.178749 -47.120071) (xy 71.151496 -47.120556)
			(xy 71.125463 -47.120104) (xy 71.07388 -47.113017) (xy 71.023739 -47.098988) (xy 70.975968 -47.078278)
			(xy 70.931453 -47.051271) (xy 70.910958 -47.035212) (xy 70.903191 -47.029486) (xy 70.884788 -47.023736)
			(xy 70.875144 -47.024036) (xy 70.795388 -47.030386) (xy 70.777608 -47.039022) (xy 70.771258 -47.046388)
			(xy 70.753071 -47.066028) (xy 70.712165 -47.10055) (xy 70.666837 -47.12902) (xy 70.617977 -47.150879)
			(xy 70.566542 -47.165698) (xy 70.513541 -47.173186) (xy 70.486778 -47.173642) (xy 70.459528 -47.173143)
			(xy 70.405582 -47.165384) (xy 70.35329 -47.150028) (xy 70.303715 -47.127387) (xy 70.257866 -47.097921)
			(xy 70.216677 -47.062231) (xy 70.180986 -47.021043) (xy 70.151519 -46.975196) (xy 70.128876 -46.925621)
			(xy 70.113518 -46.873329) (xy 70.105758 -46.819384) (xy 70.10527 -46.792134) (xy 70.105803 -46.76336)
			(xy 70.114453 -46.706467) (xy 70.131548 -46.651517) (xy 70.156699 -46.599757) (xy 70.189337 -46.55236)
			(xy 70.208648 -46.531022) (xy 70.216014 -46.523148) (xy 70.223126 -46.503336) (xy 70.21576 -46.40707)
			(xy 70.205854 -46.388274) (xy 70.197472 -46.38167) (xy 70.175277 -46.363457) (xy 70.13607 -46.321518)
			(xy 70.103587 -46.274179) (xy 70.078561 -46.222509) (xy 70.061556 -46.167674) (xy 70.052956 -46.11091)
			(xy 70.052438 -46.082204) (xy 63.988114 -46.082204) (xy 63.996034 -46.107646) (xy 64.008699 -46.176893)
			(xy 64.011302 -46.211998) (xy 64.163792 -48.753014) (xy 73.168254 -48.753014) (xy 73.172325 -48.697392)
			(xy 73.184451 -48.642955) (xy 73.204374 -48.590864) (xy 73.23167 -48.542229) (xy 73.265756 -48.498086)
			(xy 73.305905 -48.459377) (xy 73.351263 -48.426926) (xy 73.400863 -48.401425) (xy 73.453647 -48.383418)
			(xy 73.50849 -48.373288) (xy 73.564224 -48.371251) (xy 73.619661 -48.377351) (xy 73.673618 -48.391457)
			(xy 73.724947 -48.413269) (xy 73.772553 -48.442323) (xy 73.815421 -48.477998) (xy 73.852638 -48.519535)
			(xy 73.883411 -48.566048) (xy 73.907083 -48.616545) (xy 73.923151 -48.669952) (xy 73.931271 -48.725128)
			(xy 73.93178 -48.753014) (xy 73.931271 -48.7809) (xy 73.923151 -48.836076) (xy 73.907083 -48.889483)
			(xy 73.892893 -48.919754) (xy 75.214938 -48.919754) (xy 75.214938 -48.865246) (xy 75.222695 -48.811294)
			(xy 75.238051 -48.758995) (xy 75.260694 -48.709413) (xy 75.290162 -48.663559) (xy 75.325856 -48.622364)
			(xy 75.367049 -48.586669) (xy 75.412903 -48.557199) (xy 75.462484 -48.534555) (xy 75.514782 -48.519197)
			(xy 75.568734 -48.511439) (xy 75.595988 -48.510952) (xy 75.622735 -48.511351) (xy 75.675703 -48.518842)
			(xy 75.727107 -48.533652) (xy 75.775942 -48.55549) (xy 75.821251 -48.58393) (xy 75.862148 -48.618414)
			(xy 75.897832 -48.658268) (xy 75.927606 -48.702711) (xy 75.93965 -48.726598) (xy 75.943618 -48.734179)
			(xy 75.955675 -48.746307) (xy 75.971069 -48.753753) (xy 75.979528 -48.755046) (xy 76.077826 -48.766222)
			(xy 76.101956 -48.75657) (xy 76.110084 -48.74641) (xy 76.128305 -48.724697) (xy 76.170056 -48.686361)
			(xy 76.21702 -48.654627) (xy 76.268163 -48.630191) (xy 76.32236 -48.613594) (xy 76.378416 -48.605199)
			(xy 76.406756 -48.604678) (xy 76.407518 -48.604678) (xy 76.425537 -48.604901) (xy 76.461412 -48.608334)
			(xy 76.479146 -48.611536) (xy 76.49337 -48.61433) (xy 76.519786 -48.604424) (xy 76.593192 -48.51019)
			(xy 76.596494 -48.481742) (xy 76.590398 -48.468788) (xy 76.579001 -48.443355) (xy 76.562925 -48.389993)
			(xy 76.554809 -48.334856) (xy 76.55433 -48.30699) (xy 76.554789 -48.27974) (xy 76.562546 -48.225796)
			(xy 76.577901 -48.173504) (xy 76.600542 -48.12393) (xy 76.630007 -48.078082) (xy 76.665697 -48.036894)
			(xy 76.706885 -48.001205) (xy 76.752733 -47.97174) (xy 76.802308 -47.9491) (xy 76.8546 -47.933745)
			(xy 76.908544 -47.925989) (xy 76.963044 -47.925988) (xy 77.016989 -47.933743) (xy 77.069281 -47.949096)
			(xy 77.118856 -47.971734) (xy 77.164705 -48.001198) (xy 77.205894 -48.036886) (xy 77.241585 -48.078073)
			(xy 77.271052 -48.123919) (xy 77.293694 -48.173493) (xy 77.309051 -48.225784) (xy 77.31681 -48.279728)
			(xy 77.316813 -48.334228) (xy 77.309061 -48.388173) (xy 77.29371 -48.440466) (xy 77.271073 -48.490042)
			(xy 77.241612 -48.535892) (xy 77.205925 -48.577083) (xy 77.16474 -48.612776) (xy 77.118895 -48.642244)
			(xy 77.069322 -48.664889) (xy 77.017032 -48.680248) (xy 76.963088 -48.688009) (xy 76.935838 -48.688498)
			(xy 76.935076 -48.688498) (xy 76.917057 -48.688277) (xy 76.881182 -48.684843) (xy 76.863448 -48.68164)
			(xy 76.849224 -48.678846) (xy 76.822808 -48.688752) (xy 76.749402 -48.782986) (xy 76.7461 -48.811434)
			(xy 76.752196 -48.824388) (xy 76.763585 -48.849824) (xy 76.779663 -48.903185) (xy 76.78463 -48.93691)
			(xy 78.933038 -48.93691) (xy 78.937109 -48.881288) (xy 78.949235 -48.826851) (xy 78.969158 -48.77476)
			(xy 78.996454 -48.726125) (xy 79.03054 -48.681982) (xy 79.070689 -48.643273) (xy 79.116047 -48.610822)
			(xy 79.165647 -48.585321) (xy 79.218431 -48.567314) (xy 79.273274 -48.557184) (xy 79.329008 -48.555147)
			(xy 79.384445 -48.561247) (xy 79.438402 -48.575353) (xy 79.489731 -48.597165) (xy 79.537337 -48.626219)
			(xy 79.580205 -48.661894) (xy 79.617422 -48.703431) (xy 79.648195 -48.749944) (xy 79.671867 -48.800441)
			(xy 79.687935 -48.853848) (xy 79.696055 -48.909024) (xy 79.696564 -48.93691) (xy 79.696055 -48.964796)
			(xy 79.687935 -49.019972) (xy 79.671867 -49.073379) (xy 79.648195 -49.123876) (xy 79.617422 -49.170389)
			(xy 79.580205 -49.211926) (xy 79.537337 -49.247601) (xy 79.489731 -49.276655) (xy 79.438402 -49.298467)
			(xy 79.384445 -49.312573) (xy 79.329008 -49.318673) (xy 79.273274 -49.316636) (xy 79.218431 -49.306506)
			(xy 79.165647 -49.288499) (xy 79.116047 -49.262998) (xy 79.070689 -49.230547) (xy 79.03054 -49.191838)
			(xy 78.996454 -49.147695) (xy 78.969158 -49.09906) (xy 78.949235 -49.046969) (xy 78.937109 -48.992532)
			(xy 78.933038 -48.93691) (xy 76.78463 -48.93691) (xy 76.787783 -48.958321) (xy 76.788264 -48.986186)
			(xy 76.787832 -49.013441) (xy 76.780075 -49.067395) (xy 76.764719 -49.119696) (xy 76.742075 -49.169279)
			(xy 76.712604 -49.215134) (xy 76.676907 -49.256328) (xy 76.63571 -49.292022) (xy 76.589853 -49.321489)
			(xy 76.540268 -49.344129) (xy 76.487965 -49.359482) (xy 76.434011 -49.367234) (xy 76.406756 -49.367694)
			(xy 76.380011 -49.367232) (xy 76.327047 -49.359748) (xy 76.275646 -49.344946) (xy 76.226813 -49.323116)
			(xy 76.181504 -49.294686) (xy 76.140606 -49.26021) (xy 76.104919 -49.220365) (xy 76.075141 -49.17593)
			(xy 76.063094 -49.152048) (xy 76.059082 -49.144493) (xy 76.047046 -49.132359) (xy 76.031668 -49.124901)
			(xy 76.023216 -49.1236) (xy 75.924918 -49.112424) (xy 75.900788 -49.122076) (xy 75.89266 -49.132236)
			(xy 75.874426 -49.153937) (xy 75.832677 -49.192272) (xy 75.785715 -49.224007) (xy 75.734574 -49.248443)
			(xy 75.680381 -49.265044) (xy 75.624327 -49.273444) (xy 75.595988 -49.273968) (xy 75.568734 -49.273561)
			(xy 75.514782 -49.265803) (xy 75.462484 -49.250445) (xy 75.412903 -49.227801) (xy 75.367049 -49.198331)
			(xy 75.325856 -49.162636) (xy 75.290162 -49.121441) (xy 75.260694 -49.075587) (xy 75.238051 -49.026005)
			(xy 75.222695 -48.973706) (xy 75.214938 -48.919754) (xy 73.892893 -48.919754) (xy 73.883411 -48.93998)
			(xy 73.852638 -48.986493) (xy 73.815421 -49.02803) (xy 73.772553 -49.063705) (xy 73.724947 -49.092759)
			(xy 73.673618 -49.114571) (xy 73.619661 -49.128677) (xy 73.564224 -49.134777) (xy 73.50849 -49.13274)
			(xy 73.453647 -49.12261) (xy 73.400863 -49.104603) (xy 73.351263 -49.079102) (xy 73.305905 -49.046651)
			(xy 73.265756 -49.007942) (xy 73.23167 -48.963799) (xy 73.204374 -48.915164) (xy 73.184451 -48.863073)
			(xy 73.172325 -48.808636) (xy 73.168254 -48.753014) (xy 64.163792 -48.753014) (xy 64.235799 -49.95291)
			(xy 78.933038 -49.95291) (xy 78.937109 -49.897288) (xy 78.949235 -49.842851) (xy 78.969158 -49.79076)
			(xy 78.996454 -49.742125) (xy 79.03054 -49.697982) (xy 79.070689 -49.659273) (xy 79.116047 -49.626822)
			(xy 79.165647 -49.601321) (xy 79.218431 -49.583314) (xy 79.273274 -49.573184) (xy 79.329008 -49.571147)
			(xy 79.384445 -49.577247) (xy 79.438402 -49.591353) (xy 79.463337 -49.601949) (xy 84.112882 -49.601949)
			(xy 84.112882 -49.547451) (xy 84.120637 -49.493507) (xy 84.13599 -49.441216) (xy 84.158628 -49.391642)
			(xy 84.188091 -49.345793) (xy 84.223778 -49.304605) (xy 84.264963 -49.268914) (xy 84.310808 -49.239447)
			(xy 84.36038 -49.216803) (xy 84.41267 -49.201445) (xy 84.466613 -49.193684) (xy 84.493862 -49.193196)
			(xy 84.521231 -49.193685) (xy 84.575409 -49.201498) (xy 84.627912 -49.216981) (xy 84.677659 -49.239818)
			(xy 84.723627 -49.269537) (xy 84.74456 -49.287176) (xy 84.744814 -49.28743) (xy 84.75189 -49.293032)
			(xy 84.768815 -49.299268) (xy 84.777834 -49.299622) (xy 84.84489 -49.299622) (xy 84.853906 -49.299255)
			(xy 84.870823 -49.293014) (xy 84.87791 -49.28743) (xy 84.87791 -49.287176) (xy 84.878164 -49.287176)
			(xy 84.899097 -49.269535) (xy 84.945065 -49.239811) (xy 84.994811 -49.216965) (xy 85.047313 -49.201469)
			(xy 85.101491 -49.19364) (xy 85.156233 -49.19364) (xy 85.210411 -49.201469) (xy 85.262913 -49.216965)
			(xy 85.312659 -49.239811) (xy 85.358627 -49.269535) (xy 85.37956 -49.287176) (xy 85.379814 -49.28743)
			(xy 85.38689 -49.293032) (xy 85.403815 -49.299268) (xy 85.412834 -49.299622) (xy 85.47989 -49.299622)
			(xy 85.488906 -49.299255) (xy 85.505823 -49.293014) (xy 85.51291 -49.28743) (xy 85.51291 -49.287176)
			(xy 85.513164 -49.287176) (xy 85.534097 -49.269535) (xy 85.580065 -49.239811) (xy 85.629811 -49.216965)
			(xy 85.682313 -49.201469) (xy 85.736491 -49.19364) (xy 85.791233 -49.19364) (xy 85.845411 -49.201469)
			(xy 85.897913 -49.216965) (xy 85.947659 -49.239811) (xy 85.993627 -49.269535) (xy 86.01456 -49.287176)
			(xy 86.014814 -49.28743) (xy 86.02189 -49.293032) (xy 86.038815 -49.299268) (xy 86.047834 -49.299622)
			(xy 86.11489 -49.299622) (xy 86.123906 -49.299255) (xy 86.140823 -49.293014) (xy 86.14791 -49.28743)
			(xy 86.14791 -49.287176) (xy 86.148164 -49.287176) (xy 86.169096 -49.269537) (xy 86.215069 -49.239826)
			(xy 86.264817 -49.21699) (xy 86.317317 -49.201499) (xy 86.371493 -49.19367) (xy 86.398862 -49.193196)
			(xy 86.426117 -49.193649) (xy 86.480073 -49.201401) (xy 86.532375 -49.216754) (xy 86.581961 -49.239395)
			(xy 86.627819 -49.268862) (xy 86.669017 -49.304556) (xy 86.704715 -49.34575) (xy 86.734187 -49.391606)
			(xy 86.756832 -49.441189) (xy 86.77219 -49.49349) (xy 86.779949 -49.547445) (xy 86.779949 -49.601955)
			(xy 86.77219 -49.65591) (xy 86.756832 -49.708211) (xy 86.734187 -49.757794) (xy 86.704715 -49.80365)
			(xy 86.669017 -49.844844) (xy 86.627819 -49.880538) (xy 86.581961 -49.910005) (xy 86.532375 -49.932646)
			(xy 86.480073 -49.947999) (xy 86.426117 -49.955751) (xy 86.398862 -49.956212) (xy 86.371493 -49.955707)
			(xy 86.317316 -49.947898) (xy 86.264813 -49.932418) (xy 86.215066 -49.909585) (xy 86.169097 -49.879869)
			(xy 86.148164 -49.862232) (xy 86.14791 -49.861978) (xy 86.140827 -49.856387) (xy 86.123907 -49.850144)
			(xy 86.11489 -49.849786) (xy 86.047834 -49.849786) (xy 86.038819 -49.850162) (xy 86.021902 -49.856397)
			(xy 86.014814 -49.861978) (xy 86.01456 -49.862232) (xy 85.993627 -49.879873) (xy 85.947659 -49.909597)
			(xy 85.897913 -49.932443) (xy 85.845411 -49.947939) (xy 85.791233 -49.955768) (xy 85.736491 -49.955768)
			(xy 85.682313 -49.947939) (xy 85.629811 -49.932443) (xy 85.580065 -49.909597) (xy 85.534097 -49.879873)
			(xy 85.513164 -49.862232) (xy 85.51291 -49.861978) (xy 85.505827 -49.856387) (xy 85.488907 -49.850144)
			(xy 85.47989 -49.849786) (xy 85.412834 -49.849786) (xy 85.403819 -49.850162) (xy 85.386902 -49.856397)
			(xy 85.379814 -49.861978) (xy 85.379814 -49.862232) (xy 85.37956 -49.862232) (xy 85.358627 -49.879873)
			(xy 85.312659 -49.909597) (xy 85.262913 -49.932443) (xy 85.210411 -49.947939) (xy 85.156233 -49.955768)
			(xy 85.101491 -49.955768) (xy 85.047313 -49.947939) (xy 84.994811 -49.932443) (xy 84.945065 -49.909597)
			(xy 84.899097 -49.879873) (xy 84.878164 -49.862232) (xy 84.87791 -49.861978) (xy 84.870827 -49.856387)
			(xy 84.853907 -49.850144) (xy 84.84489 -49.849786) (xy 84.777834 -49.849786) (xy 84.768819 -49.850162)
			(xy 84.751902 -49.856397) (xy 84.744814 -49.861978) (xy 84.744814 -49.862232) (xy 84.74456 -49.862232)
			(xy 84.72362 -49.879861) (xy 84.677649 -49.909574) (xy 84.627903 -49.932411) (xy 84.575405 -49.947904)
			(xy 84.521231 -49.955736) (xy 84.493862 -49.956212) (xy 84.466613 -49.955716) (xy 84.41267 -49.947955)
			(xy 84.36038 -49.932597) (xy 84.310808 -49.909953) (xy 84.264963 -49.880486) (xy 84.223778 -49.844795)
			(xy 84.188091 -49.803607) (xy 84.158628 -49.757758) (xy 84.13599 -49.708184) (xy 84.120637 -49.655893)
			(xy 84.112882 -49.601949) (xy 79.463337 -49.601949) (xy 79.489731 -49.613165) (xy 79.537337 -49.642219)
			(xy 79.580205 -49.677894) (xy 79.617422 -49.719431) (xy 79.648195 -49.765944) (xy 79.671867 -49.816441)
			(xy 79.687935 -49.869848) (xy 79.696055 -49.925024) (xy 79.696564 -49.95291) (xy 79.696055 -49.980796)
			(xy 79.687935 -50.035972) (xy 79.671867 -50.089379) (xy 79.648195 -50.139876) (xy 79.617422 -50.186389)
			(xy 79.580205 -50.227926) (xy 79.537337 -50.263601) (xy 79.489731 -50.292655) (xy 79.438402 -50.314467)
			(xy 79.384445 -50.328573) (xy 79.329008 -50.334673) (xy 79.273274 -50.332636) (xy 79.218431 -50.322506)
			(xy 79.165647 -50.304499) (xy 79.116047 -50.278998) (xy 79.070689 -50.246547) (xy 79.03054 -50.207838)
			(xy 78.996454 -50.163695) (xy 78.969158 -50.11506) (xy 78.949235 -50.062969) (xy 78.937109 -50.008532)
			(xy 78.933038 -49.95291) (xy 64.235799 -49.95291) (xy 64.299804 -51.019456) (xy 76.7494 -51.019456)
			(xy 76.753471 -50.963834) (xy 76.765597 -50.909397) (xy 76.78552 -50.857306) (xy 76.812816 -50.808671)
			(xy 76.846902 -50.764528) (xy 76.887051 -50.725819) (xy 76.932409 -50.693368) (xy 76.982009 -50.667867)
			(xy 77.034793 -50.64986) (xy 77.089636 -50.63973) (xy 77.14537 -50.637693) (xy 77.200807 -50.643793)
			(xy 77.254764 -50.657899) (xy 77.306093 -50.679711) (xy 77.353699 -50.708765) (xy 77.396567 -50.74444)
			(xy 77.433784 -50.785977) (xy 77.464557 -50.83249) (xy 77.488229 -50.882987) (xy 77.504297 -50.936394)
			(xy 77.512417 -50.99157) (xy 77.512926 -51.019456) (xy 77.512417 -51.047342) (xy 77.504297 -51.102518)
			(xy 77.488229 -51.155925) (xy 77.464557 -51.206422) (xy 77.439701 -51.243992) (xy 85.132926 -51.243992)
			(xy 85.133381 -51.216621) (xy 85.141201 -51.162441) (xy 85.156692 -51.109938) (xy 85.179536 -51.060191)
			(xy 85.209263 -51.014225) (xy 85.226906 -50.993294) (xy 85.22716 -50.99304) (xy 85.232743 -50.985951)
			(xy 85.23899 -50.969036) (xy 85.239352 -50.96002) (xy 85.239352 -50.892964) (xy 85.239023 -50.883944)
			(xy 85.232757 -50.867027) (xy 85.22716 -50.859944) (xy 85.226906 -50.859944) (xy 85.226906 -50.85969)
			(xy 85.20925 -50.838772) (xy 85.17954 -50.792795) (xy 85.156708 -50.743044) (xy 85.141221 -50.69054)
			(xy 85.133397 -50.636362) (xy 85.132926 -50.608992) (xy 85.133348 -50.581737) (xy 85.141107 -50.527783)
			(xy 85.156466 -50.475483) (xy 85.179112 -50.4259) (xy 85.208584 -50.380045) (xy 85.244282 -50.338852)
			(xy 85.285479 -50.303158) (xy 85.331337 -50.273691) (xy 85.380922 -50.251051) (xy 85.433224 -50.235698)
			(xy 85.487179 -50.227945) (xy 85.514434 -50.227484) (xy 85.543351 -50.228018) (xy 85.600523 -50.236739)
			(xy 85.655722 -50.253992) (xy 85.707685 -50.279381) (xy 85.755219 -50.312323) (xy 85.797235 -50.352064)
			(xy 85.815424 -50.37455) (xy 85.823022 -50.383367) (xy 85.84393 -50.393543) (xy 85.855556 -50.394108)
			(xy 85.935312 -50.394108) (xy 85.946942 -50.393559) (xy 85.967852 -50.383377) (xy 85.975444 -50.37455)
			(xy 85.993598 -50.352035) (xy 86.035627 -50.312304) (xy 86.08317 -50.27937) (xy 86.135138 -50.253988)
			(xy 86.190342 -50.236738) (xy 86.247516 -50.228016) (xy 86.276434 -50.227484) (xy 86.303686 -50.227946)
			(xy 86.357634 -50.235707) (xy 86.409929 -50.251066) (xy 86.459505 -50.273711) (xy 86.505355 -50.30318)
			(xy 86.546545 -50.338874) (xy 86.582236 -50.380066) (xy 86.611702 -50.425917) (xy 86.634343 -50.475496)
			(xy 86.649698 -50.527792) (xy 86.657456 -50.58174) (xy 86.657942 -50.608992) (xy 86.657488 -50.635307)
			(xy 86.650253 -50.687436) (xy 86.635932 -50.73808) (xy 86.614798 -50.78628) (xy 86.587248 -50.831123)
			(xy 86.553806 -50.871761) (xy 86.534752 -50.889916) (xy 86.527349 -50.897437) (xy 86.518824 -50.916717)
			(xy 86.518242 -50.927254) (xy 86.518242 -51.00193) (xy 86.518783 -51.012479) (xy 86.527308 -51.031775)
			(xy 86.534752 -51.039268) (xy 86.553843 -51.057387) (xy 86.587295 -51.098026) (xy 86.614848 -51.142874)
			(xy 86.63598 -51.191082) (xy 86.65029 -51.241735) (xy 86.657507 -51.293874) (xy 86.657942 -51.320192)
			(xy 86.657415 -51.347442) (xy 86.64966 -51.401386) (xy 86.634308 -51.453678) (xy 86.61167 -51.503253)
			(xy 86.582208 -51.549102) (xy 86.546521 -51.590291) (xy 86.505335 -51.625983) (xy 86.45949 -51.65545)
			(xy 86.409917 -51.678093) (xy 86.357627 -51.693451) (xy 86.303683 -51.701212) (xy 86.276434 -51.7017)
			(xy 86.24877 -51.701161) (xy 86.194022 -51.693167) (xy 86.141001 -51.677355) (xy 86.090817 -51.654056)
			(xy 86.044521 -51.623759) (xy 86.003082 -51.587097) (xy 85.967368 -51.544839) (xy 85.95233 -51.521614)
			(xy 85.945689 -51.511941) (xy 85.925831 -51.499496) (xy 85.91423 -51.497738) (xy 85.83422 -51.489864)
			(xy 85.822582 -51.489248) (xy 85.800745 -51.497317) (xy 85.79231 -51.505358) (xy 85.792056 -51.505612)
			(xy 85.773981 -51.524199) (xy 85.733647 -51.556776) (xy 85.689272 -51.583588) (xy 85.641672 -51.60414)
			(xy 85.591727 -51.618052) (xy 85.540357 -51.625069) (xy 85.514434 -51.6255) (xy 85.487182 -51.625013)
			(xy 85.433231 -51.61726) (xy 85.380933 -51.601908) (xy 85.331353 -51.579269) (xy 85.285499 -51.549804)
			(xy 85.244306 -51.514113) (xy 85.208612 -51.472922) (xy 85.179143 -51.42707) (xy 85.156501 -51.377491)
			(xy 85.141145 -51.325194) (xy 85.133389 -51.271244) (xy 85.132926 -51.243992) (xy 77.439701 -51.243992)
			(xy 77.433784 -51.252935) (xy 77.396567 -51.294472) (xy 77.353699 -51.330147) (xy 77.306093 -51.359201)
			(xy 77.254764 -51.381013) (xy 77.200807 -51.395119) (xy 77.14537 -51.401219) (xy 77.089636 -51.399182)
			(xy 77.034793 -51.389052) (xy 76.982009 -51.371045) (xy 76.932409 -51.345544) (xy 76.887051 -51.313093)
			(xy 76.846902 -51.274384) (xy 76.812816 -51.230241) (xy 76.78552 -51.181606) (xy 76.765597 -51.129515)
			(xy 76.753471 -51.075078) (xy 76.7494 -51.019456) (xy 64.299804 -51.019456) (xy 64.360776 -52.035456)
			(xy 78.941166 -52.035456) (xy 78.945237 -51.979834) (xy 78.957363 -51.925397) (xy 78.977286 -51.873306)
			(xy 79.004582 -51.824671) (xy 79.038668 -51.780528) (xy 79.078817 -51.741819) (xy 79.124175 -51.709368)
			(xy 79.173775 -51.683867) (xy 79.226559 -51.66586) (xy 79.281402 -51.65573) (xy 79.337136 -51.653693)
			(xy 79.392573 -51.659793) (xy 79.44653 -51.673899) (xy 79.497859 -51.695711) (xy 79.545465 -51.724765)
			(xy 79.588333 -51.76044) (xy 79.62555 -51.801977) (xy 79.656323 -51.84849) (xy 79.679995 -51.898987)
			(xy 79.696063 -51.952394) (xy 79.704183 -52.00757) (xy 79.704692 -52.035456) (xy 79.704183 -52.063342)
			(xy 79.696063 -52.118518) (xy 79.679995 -52.171925) (xy 79.656323 -52.222422) (xy 79.62555 -52.268935)
			(xy 79.588333 -52.310472) (xy 79.545465 -52.346147) (xy 79.497859 -52.375201) (xy 79.44653 -52.397013)
			(xy 79.392573 -52.411119) (xy 79.337136 -52.417219) (xy 79.281402 -52.415182) (xy 79.226559 -52.405052)
			(xy 79.173775 -52.387045) (xy 79.124175 -52.361544) (xy 79.078817 -52.329093) (xy 79.038668 -52.290384)
			(xy 79.004582 -52.246241) (xy 78.977286 -52.197606) (xy 78.957363 -52.145515) (xy 78.945237 -52.091078)
			(xy 78.941166 -52.035456) (xy 64.360776 -52.035456) (xy 64.522564 -54.731412) (xy 65.52057 -54.731412)
			(xy 65.521026 -54.704041) (xy 65.528844 -54.649861) (xy 65.544334 -54.597357) (xy 65.567179 -54.54761)
			(xy 65.596907 -54.501645) (xy 65.61455 -54.480714) (xy 65.614804 -54.48046) (xy 65.620372 -54.473361)
			(xy 65.62663 -54.456454) (xy 65.626996 -54.44744) (xy 65.626996 -54.380384) (xy 65.626647 -54.371366)
			(xy 65.620394 -54.354449) (xy 65.614804 -54.347364) (xy 65.61455 -54.347364) (xy 65.61455 -54.34711)
			(xy 65.59692 -54.326168) (xy 65.567193 -54.280203) (xy 65.544346 -54.230458) (xy 65.528847 -54.177957)
			(xy 65.521017 -54.123779) (xy 65.521016 -54.069039) (xy 65.528844 -54.014861) (xy 65.544339 -53.962359)
			(xy 65.567184 -53.912613) (xy 65.596909 -53.866646) (xy 65.61455 -53.845714) (xy 65.614804 -53.84546)
			(xy 65.620372 -53.838361) (xy 65.62663 -53.821454) (xy 65.626996 -53.81244) (xy 65.626996 -53.745384)
			(xy 65.626647 -53.736366) (xy 65.620394 -53.719449) (xy 65.614804 -53.712364) (xy 65.61455 -53.712364)
			(xy 65.61455 -53.71211) (xy 65.59692 -53.691168) (xy 65.567193 -53.645203) (xy 65.544346 -53.595458)
			(xy 65.528847 -53.542957) (xy 65.521017 -53.488779) (xy 65.521016 -53.434039) (xy 65.528844 -53.379861)
			(xy 65.544339 -53.327359) (xy 65.567184 -53.277613) (xy 65.596909 -53.231646) (xy 65.61455 -53.210714)
			(xy 65.614804 -53.21046) (xy 65.620372 -53.203361) (xy 65.62663 -53.186454) (xy 65.626996 -53.17744)
			(xy 65.626996 -53.110384) (xy 65.626647 -53.101366) (xy 65.620394 -53.084449) (xy 65.614804 -53.077364)
			(xy 65.61455 -53.077364) (xy 65.61455 -53.07711) (xy 65.59691 -53.056179) (xy 65.567197 -53.010206)
			(xy 65.54436 -52.960459) (xy 65.528869 -52.907958) (xy 65.521043 -52.853781) (xy 65.52057 -52.826412)
			(xy 65.521056 -52.799161) (xy 65.528812 -52.745213) (xy 65.544167 -52.692918) (xy 65.566809 -52.643341)
			(xy 65.596275 -52.597491) (xy 65.631966 -52.5563) (xy 65.673157 -52.520609) (xy 65.719007 -52.491143)
			(xy 65.768584 -52.468501) (xy 65.820879 -52.453146) (xy 65.874827 -52.44539) (xy 65.929329 -52.44539)
			(xy 65.983277 -52.453146) (xy 66.035572 -52.468501) (xy 66.085149 -52.491143) (xy 66.130999 -52.520609)
			(xy 66.17219 -52.5563) (xy 66.207881 -52.597491) (xy 66.237347 -52.643341) (xy 66.259989 -52.692918)
			(xy 66.275344 -52.745213) (xy 66.2831 -52.799161) (xy 66.283586 -52.826412) (xy 66.28313 -52.853783)
			(xy 66.275311 -52.907962) (xy 66.259819 -52.960466) (xy 66.236975 -53.010212) (xy 66.207248 -53.056179)
			(xy 66.189606 -53.07711) (xy 66.189352 -53.077364) (xy 66.183769 -53.084453) (xy 66.177521 -53.101368)
			(xy 66.17716 -53.110384) (xy 66.17716 -53.17744) (xy 66.177485 -53.18646) (xy 66.183753 -53.203378)
			(xy 66.189352 -53.21046) (xy 66.189606 -53.21046) (xy 66.189606 -53.210714) (xy 66.207257 -53.231638)
			(xy 66.236979 -53.277608) (xy 66.259822 -53.327356) (xy 66.275315 -53.379859) (xy 66.283142 -53.434038)
			(xy 66.283141 -53.48878) (xy 66.275312 -53.542959) (xy 66.259815 -53.595461) (xy 66.23697 -53.645208)
			(xy 66.207246 -53.691177) (xy 66.189606 -53.71211) (xy 66.189352 -53.712364) (xy 66.183769 -53.719453)
			(xy 66.177521 -53.736368) (xy 66.17716 -53.745384) (xy 66.17716 -53.81244) (xy 66.177485 -53.82146)
			(xy 66.183753 -53.838378) (xy 66.189352 -53.84546) (xy 66.189606 -53.84546) (xy 66.189606 -53.845714)
			(xy 66.207257 -53.866638) (xy 66.236979 -53.912608) (xy 66.259822 -53.962356) (xy 66.275315 -54.014859)
			(xy 66.283142 -54.069038) (xy 66.283141 -54.12378) (xy 66.275312 -54.177959) (xy 66.259815 -54.230461)
			(xy 66.23697 -54.280208) (xy 66.207246 -54.326177) (xy 66.189606 -54.34711) (xy 66.189352 -54.347364)
			(xy 66.183769 -54.354453) (xy 66.177521 -54.371368) (xy 66.17716 -54.380384) (xy 66.17716 -54.44744)
			(xy 66.177485 -54.45646) (xy 66.183753 -54.473378) (xy 66.189352 -54.48046) (xy 66.189606 -54.48046)
			(xy 66.189606 -54.480714) (xy 66.207219 -54.501667) (xy 66.236935 -54.547634) (xy 66.259776 -54.597376)
			(xy 66.275273 -54.649872) (xy 66.283108 -54.704044) (xy 66.283586 -54.731412) (xy 66.2831 -54.758663)
			(xy 66.278436 -54.791102) (xy 68.176394 -54.791102) (xy 68.176863 -54.763732) (xy 68.18468 -54.709553)
			(xy 68.200169 -54.65705) (xy 68.22301 -54.607303) (xy 68.252733 -54.561336) (xy 68.270374 -54.540404)
			(xy 68.270628 -54.54015) (xy 68.276203 -54.533056) (xy 68.282456 -54.516145) (xy 68.28282 -54.50713)
			(xy 68.28282 -54.440074) (xy 68.282471 -54.431056) (xy 68.276218 -54.41414) (xy 68.270628 -54.407054)
			(xy 68.270374 -54.407054) (xy 68.270374 -54.4068) (xy 68.252733 -54.385867) (xy 68.223005 -54.3399)
			(xy 68.200157 -54.290154) (xy 68.184658 -54.237652) (xy 68.176828 -54.183473) (xy 68.176828 -54.12873)
			(xy 68.184657 -54.074551) (xy 68.200155 -54.022049) (xy 68.223003 -53.972303) (xy 68.252731 -53.926336)
			(xy 68.270374 -53.905404) (xy 68.270628 -53.90515) (xy 68.276203 -53.898056) (xy 68.282456 -53.881145)
			(xy 68.28282 -53.87213) (xy 68.28282 -53.805074) (xy 68.282471 -53.796056) (xy 68.276218 -53.77914)
			(xy 68.270628 -53.772054) (xy 68.270374 -53.772054) (xy 68.270374 -53.7718) (xy 68.252733 -53.750867)
			(xy 68.223005 -53.7049) (xy 68.200157 -53.655154) (xy 68.184658 -53.602652) (xy 68.176828 -53.548473)
			(xy 68.176828 -53.49373) (xy 68.184657 -53.439551) (xy 68.200155 -53.387049) (xy 68.223003 -53.337303)
			(xy 68.252731 -53.291336) (xy 68.270374 -53.270404) (xy 68.270628 -53.27015) (xy 68.276203 -53.263056)
			(xy 68.282456 -53.246145) (xy 68.28282 -53.23713) (xy 68.28282 -53.170074) (xy 68.282471 -53.161056)
			(xy 68.276218 -53.14414) (xy 68.270628 -53.137054) (xy 68.270374 -53.137054) (xy 68.270374 -53.1368)
			(xy 68.252717 -53.115882) (xy 68.223009 -53.069905) (xy 68.200177 -53.020154) (xy 68.18469 -52.96765)
			(xy 68.176866 -52.913472) (xy 68.176394 -52.886102) (xy 68.17688 -52.858851) (xy 68.184636 -52.804903)
			(xy 68.199991 -52.752608) (xy 68.222633 -52.703031) (xy 68.252099 -52.657181) (xy 68.28779 -52.61599)
			(xy 68.328981 -52.580299) (xy 68.374831 -52.550833) (xy 68.424408 -52.528191) (xy 68.476703 -52.512836)
			(xy 68.530651 -52.50508) (xy 68.585153 -52.50508) (xy 68.639101 -52.512836) (xy 68.691396 -52.528191)
			(xy 68.730496 -52.546048) (xy 73.679596 -52.546048) (xy 73.679596 -52.491552) (xy 73.687351 -52.437611)
			(xy 73.702703 -52.385322) (xy 73.72534 -52.33575) (xy 73.754801 -52.289903) (xy 73.790487 -52.248716)
			(xy 73.83167 -52.213027) (xy 73.877513 -52.183561) (xy 73.927082 -52.160918) (xy 73.979369 -52.14556)
			(xy 74.03331 -52.137799) (xy 74.060558 -52.13731) (xy 74.087927 -52.137798) (xy 74.142106 -52.14561)
			(xy 74.194609 -52.161094) (xy 74.244356 -52.183931) (xy 74.290324 -52.213651) (xy 74.311256 -52.23129)
			(xy 74.31151 -52.231544) (xy 74.318586 -52.237146) (xy 74.335511 -52.243382) (xy 74.34453 -52.243736)
			(xy 74.411586 -52.243736) (xy 74.420601 -52.243364) (xy 74.437518 -52.237126) (xy 74.444606 -52.231544)
			(xy 74.444606 -52.23129) (xy 74.44486 -52.23129) (xy 74.465793 -52.213649) (xy 74.511761 -52.183925)
			(xy 74.561507 -52.161079) (xy 74.614009 -52.145583) (xy 74.668187 -52.137754) (xy 74.722929 -52.137754)
			(xy 74.777107 -52.145583) (xy 74.829609 -52.161079) (xy 74.879355 -52.183925) (xy 74.925323 -52.213649)
			(xy 74.946256 -52.23129) (xy 74.94651 -52.231544) (xy 74.953586 -52.237146) (xy 74.970511 -52.243382)
			(xy 74.97953 -52.243736) (xy 75.046586 -52.243736) (xy 75.055601 -52.243364) (xy 75.072518 -52.237126)
			(xy 75.079606 -52.231544) (xy 75.079606 -52.23129) (xy 75.07986 -52.23129) (xy 75.100795 -52.213655)
			(xy 75.146767 -52.183943) (xy 75.196514 -52.161106) (xy 75.249014 -52.145614) (xy 75.303189 -52.137785)
			(xy 75.330558 -52.13731) (xy 75.357814 -52.137734) (xy 75.411772 -52.145487) (xy 75.464078 -52.16084)
			(xy 75.513665 -52.183481) (xy 75.559526 -52.212949) (xy 75.600726 -52.248645) (xy 75.636426 -52.28984)
			(xy 75.665899 -52.335698) (xy 75.688546 -52.385283) (xy 75.703905 -52.437587) (xy 75.711663 -52.491544)
			(xy 75.711663 -52.546056) (xy 75.705719 -52.587398) (xy 76.755242 -52.587398) (xy 76.759313 -52.531776)
			(xy 76.771439 -52.477339) (xy 76.791362 -52.425248) (xy 76.818658 -52.376613) (xy 76.852744 -52.33247)
			(xy 76.892893 -52.293761) (xy 76.938251 -52.26131) (xy 76.987851 -52.235809) (xy 77.040635 -52.217802)
			(xy 77.095478 -52.207672) (xy 77.151212 -52.205635) (xy 77.206649 -52.211735) (xy 77.260606 -52.225841)
			(xy 77.311935 -52.247653) (xy 77.359541 -52.276707) (xy 77.402409 -52.312382) (xy 77.439626 -52.353919)
			(xy 77.470399 -52.400432) (xy 77.494071 -52.450929) (xy 77.510139 -52.504336) (xy 77.517735 -52.555949)
			(xy 84.583802 -52.555949) (xy 84.583802 -52.501452) (xy 84.591558 -52.447509) (xy 84.606911 -52.39522)
			(xy 84.629549 -52.345647) (xy 84.659011 -52.299801) (xy 84.694698 -52.258614) (xy 84.735883 -52.222924)
			(xy 84.781728 -52.193459) (xy 84.831299 -52.170818) (xy 84.883588 -52.155462) (xy 84.93753 -52.147704)
			(xy 84.964778 -52.147216) (xy 84.992148 -52.147691) (xy 85.046327 -52.155506) (xy 85.09883 -52.170993)
			(xy 85.148577 -52.193833) (xy 85.194544 -52.223556) (xy 85.215476 -52.241196) (xy 85.21573 -52.24145)
			(xy 85.222828 -52.247019) (xy 85.239736 -52.253275) (xy 85.24875 -52.253642) (xy 85.315806 -52.253642)
			(xy 85.324825 -52.2533) (xy 85.341742 -52.247043) (xy 85.348826 -52.24145) (xy 85.348826 -52.241196)
			(xy 85.34908 -52.241196) (xy 85.370008 -52.223552) (xy 85.415982 -52.193841) (xy 85.465731 -52.171006)
			(xy 85.518232 -52.155516) (xy 85.572409 -52.147689) (xy 85.599778 -52.147216) (xy 85.627034 -52.147629)
			(xy 85.68099 -52.155384) (xy 85.733294 -52.170739) (xy 85.78288 -52.193382) (xy 85.828739 -52.222851)
			(xy 85.869937 -52.258547) (xy 85.905635 -52.299743) (xy 85.935107 -52.3456) (xy 85.957753 -52.395185)
			(xy 85.973111 -52.447488) (xy 85.980869 -52.501444) (xy 85.980869 -52.555956) (xy 85.973111 -52.609912)
			(xy 85.957753 -52.662215) (xy 85.935107 -52.7118) (xy 85.905635 -52.757657) (xy 85.869937 -52.798853)
			(xy 85.828739 -52.834549) (xy 85.78288 -52.864018) (xy 85.733294 -52.886661) (xy 85.68099 -52.902016)
			(xy 85.627034 -52.909771) (xy 85.599778 -52.910232) (xy 85.572407 -52.909795) (xy 85.518225 -52.901973)
			(xy 85.465721 -52.886478) (xy 85.415975 -52.863629) (xy 85.37001 -52.833897) (xy 85.34908 -52.816252)
			(xy 85.348826 -52.815998) (xy 85.341736 -52.810416) (xy 85.324822 -52.804167) (xy 85.315806 -52.803806)
			(xy 85.24875 -52.803806) (xy 85.239735 -52.804186) (xy 85.222818 -52.810418) (xy 85.21573 -52.815998)
			(xy 85.21573 -52.816252) (xy 85.215476 -52.816252) (xy 85.19452 -52.833861) (xy 85.148554 -52.863579)
			(xy 85.098813 -52.886422) (xy 85.046318 -52.90192) (xy 84.992146 -52.909755) (xy 84.964778 -52.910232)
			(xy 84.93753 -52.909696) (xy 84.883588 -52.901938) (xy 84.831299 -52.886582) (xy 84.781728 -52.863941)
			(xy 84.735883 -52.834476) (xy 84.694698 -52.798786) (xy 84.659011 -52.757599) (xy 84.629549 -52.711753)
			(xy 84.606911 -52.66218) (xy 84.591558 -52.609891) (xy 84.583802 -52.555949) (xy 77.517735 -52.555949)
			(xy 77.518259 -52.559512) (xy 77.518768 -52.587398) (xy 77.518259 -52.615284) (xy 77.510139 -52.67046)
			(xy 77.494071 -52.723867) (xy 77.470399 -52.774364) (xy 77.439626 -52.820877) (xy 77.402409 -52.862414)
			(xy 77.359541 -52.898089) (xy 77.311935 -52.927143) (xy 77.260606 -52.948955) (xy 77.206649 -52.963061)
			(xy 77.151212 -52.969161) (xy 77.095478 -52.967124) (xy 77.040635 -52.956994) (xy 76.987851 -52.938987)
			(xy 76.938251 -52.913486) (xy 76.892893 -52.881035) (xy 76.852744 -52.842326) (xy 76.818658 -52.798183)
			(xy 76.791362 -52.749548) (xy 76.771439 -52.697457) (xy 76.759313 -52.64302) (xy 76.755242 -52.587398)
			(xy 75.705719 -52.587398) (xy 75.703905 -52.600013) (xy 75.688546 -52.652317) (xy 75.665899 -52.701902)
			(xy 75.636426 -52.74776) (xy 75.600726 -52.788955) (xy 75.559526 -52.824651) (xy 75.513665 -52.854119)
			(xy 75.464078 -52.87676) (xy 75.411772 -52.892113) (xy 75.357814 -52.899866) (xy 75.330558 -52.900326)
			(xy 75.303188 -52.899844) (xy 75.249009 -52.892033) (xy 75.196505 -52.876548) (xy 75.146758 -52.85371)
			(xy 75.100791 -52.823987) (xy 75.07986 -52.806346) (xy 75.079606 -52.806092) (xy 75.072523 -52.800501)
			(xy 75.055603 -52.794257) (xy 75.046586 -52.7939) (xy 74.97953 -52.7939) (xy 74.970515 -52.794271)
			(xy 74.953597 -52.800509) (xy 74.94651 -52.806092) (xy 74.946256 -52.806346) (xy 74.925323 -52.823987)
			(xy 74.879355 -52.853711) (xy 74.829609 -52.876557) (xy 74.777107 -52.892053) (xy 74.722929 -52.899882)
			(xy 74.668187 -52.899882) (xy 74.614009 -52.892053) (xy 74.561507 -52.876557) (xy 74.511761 -52.853711)
			(xy 74.465793 -52.823987) (xy 74.44486 -52.806346) (xy 74.444606 -52.806092) (xy 74.437523 -52.800501)
			(xy 74.420603 -52.794257) (xy 74.411586 -52.7939) (xy 74.34453 -52.7939) (xy 74.335515 -52.794271)
			(xy 74.318597 -52.800509) (xy 74.31151 -52.806092) (xy 74.31151 -52.806346) (xy 74.311256 -52.806346)
			(xy 74.290307 -52.823964) (xy 74.244339 -52.853681) (xy 74.194596 -52.876522) (xy 74.142099 -52.892018)
			(xy 74.087926 -52.89985) (xy 74.060558 -52.900326) (xy 74.03331 -52.899801) (xy 73.979369 -52.89204)
			(xy 73.927082 -52.876682) (xy 73.877513 -52.854039) (xy 73.83167 -52.824573) (xy 73.790487 -52.788884)
			(xy 73.754801 -52.747697) (xy 73.72534 -52.70185) (xy 73.702703 -52.652278) (xy 73.687351 -52.599989)
			(xy 73.679596 -52.546048) (xy 68.730496 -52.546048) (xy 68.740973 -52.550833) (xy 68.786823 -52.580299)
			(xy 68.828014 -52.61599) (xy 68.863705 -52.657181) (xy 68.893171 -52.703031) (xy 68.915813 -52.752608)
			(xy 68.931168 -52.804903) (xy 68.938924 -52.858851) (xy 68.93941 -52.886102) (xy 68.938943 -52.913472)
			(xy 68.931125 -52.967651) (xy 68.915636 -53.020154) (xy 68.892794 -53.069901) (xy 68.863071 -53.115868)
			(xy 68.84543 -53.1368) (xy 68.845176 -53.137054) (xy 68.8396 -53.144148) (xy 68.833348 -53.161059)
			(xy 68.832984 -53.170074) (xy 68.832984 -53.23713) (xy 68.83333 -53.246148) (xy 68.839585 -53.263065)
			(xy 68.845176 -53.27015) (xy 68.84543 -53.27015) (xy 68.84543 -53.270404) (xy 68.863074 -53.291334)
			(xy 68.892802 -53.337301) (xy 68.91565 -53.387048) (xy 68.931148 -53.439551) (xy 68.938978 -53.49373)
			(xy 68.938977 -53.548473) (xy 68.931148 -53.602652) (xy 68.915649 -53.655155) (xy 68.892801 -53.704901)
			(xy 68.863073 -53.750868) (xy 68.8465 -53.77053) (xy 69.210682 -53.77053) (xy 69.211191 -53.741612)
			(xy 69.219917 -53.684439) (xy 69.237175 -53.629239) (xy 69.262568 -53.577276) (xy 69.295515 -53.529743)
			(xy 69.33526 -53.487728) (xy 69.357748 -53.46954) (xy 69.366535 -53.461914) (xy 69.376728 -53.441027)
			(xy 69.377306 -53.429408) (xy 69.377306 -53.349652) (xy 69.376778 -53.338019) (xy 69.366581 -53.31711)
			(xy 69.357748 -53.30952) (xy 69.335263 -53.291331) (xy 69.295531 -53.249309) (xy 69.262593 -53.201773)
			(xy 69.237206 -53.149812) (xy 69.219949 -53.094615) (xy 69.211218 -53.037446) (xy 69.210682 -53.00853)
			(xy 69.211183 -52.981278) (xy 69.218936 -52.927329) (xy 69.234288 -52.875033) (xy 69.256926 -52.825453)
			(xy 69.28639 -52.779601) (xy 69.32208 -52.738408) (xy 69.363269 -52.702714) (xy 69.409118 -52.673245)
			(xy 69.458695 -52.650602) (xy 69.51099 -52.635244) (xy 69.564938 -52.627486) (xy 69.59219 -52.627022)
			(xy 69.618504 -52.627489) (xy 69.670633 -52.634723) (xy 69.721276 -52.649042) (xy 69.769475 -52.670174)
			(xy 69.814318 -52.697721) (xy 69.854958 -52.73116) (xy 69.873114 -52.750212) (xy 69.880627 -52.757624)
			(xy 69.899914 -52.766142) (xy 69.910452 -52.766722) (xy 69.985128 -52.766722) (xy 69.995674 -52.766161)
			(xy 70.014969 -52.757648) (xy 70.022466 -52.750212) (xy 70.040599 -52.731134) (xy 70.081233 -52.697678)
			(xy 70.126078 -52.670122) (xy 70.174283 -52.648987) (xy 70.224935 -52.634675) (xy 70.277072 -52.627457)
			(xy 70.30339 -52.627022) (xy 70.330644 -52.627465) (xy 70.384597 -52.635221) (xy 70.436897 -52.650577)
			(xy 70.486479 -52.673221) (xy 70.532334 -52.702691) (xy 70.573528 -52.738387) (xy 70.609221 -52.779582)
			(xy 70.638689 -52.825438) (xy 70.66133 -52.875022) (xy 70.676683 -52.927322) (xy 70.684437 -52.981276)
			(xy 70.684898 -53.00853) (xy 70.68441 -53.036196) (xy 70.682179 -53.051456) (xy 78.941166 -53.051456)
			(xy 78.945237 -52.995834) (xy 78.957363 -52.941397) (xy 78.977286 -52.889306) (xy 79.004582 -52.840671)
			(xy 79.038668 -52.796528) (xy 79.078817 -52.757819) (xy 79.124175 -52.725368) (xy 79.173775 -52.699867)
			(xy 79.226559 -52.68186) (xy 79.281402 -52.67173) (xy 79.337136 -52.669693) (xy 79.392573 -52.675793)
			(xy 79.44653 -52.689899) (xy 79.497859 -52.711711) (xy 79.545465 -52.740765) (xy 79.588333 -52.77644)
			(xy 79.62555 -52.817977) (xy 79.656323 -52.86449) (xy 79.679995 -52.914987) (xy 79.696063 -52.968394)
			(xy 79.704183 -53.02357) (xy 79.704692 -53.051456) (xy 79.704183 -53.079342) (xy 79.696063 -53.134518)
			(xy 79.679995 -53.187925) (xy 79.656323 -53.238422) (xy 79.62555 -53.284935) (xy 79.588333 -53.326472)
			(xy 79.545465 -53.362147) (xy 79.497859 -53.391201) (xy 79.44653 -53.413013) (xy 79.392573 -53.427119)
			(xy 79.337136 -53.433219) (xy 79.281402 -53.431182) (xy 79.226559 -53.421052) (xy 79.173775 -53.403045)
			(xy 79.124175 -53.377544) (xy 79.078817 -53.345093) (xy 79.038668 -53.306384) (xy 79.004582 -53.262241)
			(xy 78.977286 -53.213606) (xy 78.957363 -53.161515) (xy 78.945237 -53.107078) (xy 78.941166 -53.051456)
			(xy 70.682179 -53.051456) (xy 70.676407 -53.090946) (xy 70.660586 -53.143969) (xy 70.637279 -53.194153)
			(xy 70.606974 -53.240448) (xy 70.570305 -53.281885) (xy 70.52804 -53.317598) (xy 70.504812 -53.332634)
			(xy 70.495114 -53.339245) (xy 70.482682 -53.359125) (xy 70.480936 -53.370734) (xy 70.473062 -53.450744)
			(xy 70.472407 -53.462383) (xy 70.480503 -53.484222) (xy 70.488556 -53.492654) (xy 70.48881 -53.492908)
			(xy 70.507379 -53.511001) (xy 70.539958 -53.55133) (xy 70.566773 -53.595702) (xy 70.587328 -53.643298)
			(xy 70.601244 -53.69324) (xy 70.608264 -53.744608) (xy 70.608698 -53.77053) (xy 70.60825 -53.797782)
			(xy 70.600489 -53.851732) (xy 70.58513 -53.904028) (xy 70.562484 -53.953606) (xy 70.533014 -53.999457)
			(xy 70.497319 -54.040647) (xy 70.456125 -54.076338) (xy 70.410271 -54.105804) (xy 70.360691 -54.128444)
			(xy 70.308393 -54.143798) (xy 70.254442 -54.151553) (xy 70.22719 -54.152038) (xy 70.199819 -54.151593)
			(xy 70.145638 -54.143772) (xy 70.093134 -54.128279) (xy 70.043388 -54.105432) (xy 69.997422 -54.075702)
			(xy 69.976492 -54.058058) (xy 69.976238 -54.057804) (xy 69.969144 -54.052228) (xy 69.952233 -54.045975)
			(xy 69.943218 -54.045612) (xy 69.876162 -54.045612) (xy 69.867143 -54.045948) (xy 69.850226 -54.05221)
			(xy 69.843142 -54.057804) (xy 69.843142 -54.058058) (xy 69.842888 -54.058058) (xy 69.821928 -54.075663)
			(xy 69.775964 -54.105381) (xy 69.726223 -54.128224) (xy 69.673728 -54.143723) (xy 69.619557 -54.15156)
			(xy 69.59219 -54.152038) (xy 69.56494 -54.151532) (xy 69.510994 -54.143775) (xy 69.458702 -54.12842)
			(xy 69.409127 -54.10578) (xy 69.363278 -54.076315) (xy 69.322088 -54.040626) (xy 69.286397 -53.999438)
			(xy 69.25693 -53.953591) (xy 69.234287 -53.904017) (xy 69.21893 -53.851725) (xy 69.21117 -53.79778)
			(xy 69.210682 -53.77053) (xy 68.8465 -53.77053) (xy 68.84543 -53.7718) (xy 68.845176 -53.772054)
			(xy 68.8396 -53.779148) (xy 68.833348 -53.796059) (xy 68.832984 -53.805074) (xy 68.832984 -53.87213)
			(xy 68.83333 -53.881148) (xy 68.839585 -53.898065) (xy 68.845176 -53.90515) (xy 68.84543 -53.90515)
			(xy 68.84543 -53.905404) (xy 68.863074 -53.926334) (xy 68.892802 -53.972301) (xy 68.91565 -54.022048)
			(xy 68.931148 -54.074551) (xy 68.938978 -54.12873) (xy 68.938977 -54.183473) (xy 68.931148 -54.237652)
			(xy 68.915649 -54.290155) (xy 68.901856 -54.320186) (xy 71.130414 -54.320186) (xy 71.130868 -54.292815)
			(xy 71.138689 -54.238636) (xy 71.15418 -54.186132) (xy 71.177025 -54.136386) (xy 71.206752 -54.090419)
			(xy 71.224394 -54.069488) (xy 71.224648 -54.069234) (xy 71.230232 -54.062146) (xy 71.236479 -54.04523)
			(xy 71.23684 -54.036214) (xy 71.23684 -53.969158) (xy 71.236468 -53.960142) (xy 71.230232 -53.943225)
			(xy 71.224648 -53.936138) (xy 71.224394 -53.936138) (xy 71.224394 -53.935884) (xy 71.20678 -53.914932)
			(xy 71.177065 -53.868964) (xy 71.154224 -53.819222) (xy 71.138727 -53.766726) (xy 71.130892 -53.712554)
			(xy 71.130414 -53.685186) (xy 71.1309 -53.657935) (xy 71.138656 -53.603987) (xy 71.154011 -53.551692)
			(xy 71.176653 -53.502115) (xy 71.206119 -53.456265) (xy 71.24181 -53.415074) (xy 71.283001 -53.379383)
			(xy 71.328851 -53.349917) (xy 71.378428 -53.327275) (xy 71.430723 -53.31192) (xy 71.484671 -53.304164)
			(xy 71.539173 -53.304164) (xy 71.593121 -53.31192) (xy 71.645416 -53.327275) (xy 71.694993 -53.349917)
			(xy 71.740843 -53.379383) (xy 71.782034 -53.415074) (xy 71.817725 -53.456265) (xy 71.843618 -53.496556)
			(xy 84.133341 -53.496556) (xy 84.133341 -53.442044) (xy 84.141099 -53.388088) (xy 84.156458 -53.335786)
			(xy 84.179104 -53.286201) (xy 84.208576 -53.240345) (xy 84.244275 -53.199149) (xy 84.285474 -53.163454)
			(xy 84.331333 -53.133986) (xy 84.380919 -53.111345) (xy 84.433224 -53.095992) (xy 84.48718 -53.088238)
			(xy 84.514436 -53.087778) (xy 84.541808 -53.088204) (xy 84.595989 -53.096029) (xy 84.648494 -53.111526)
			(xy 84.69824 -53.134377) (xy 84.744204 -53.164112) (xy 84.765134 -53.181758) (xy 84.765388 -53.182012)
			(xy 84.772473 -53.187601) (xy 84.789391 -53.193846) (xy 84.798408 -53.194204) (xy 84.865464 -53.194204)
			(xy 84.874479 -53.193829) (xy 84.891396 -53.187594) (xy 84.898484 -53.182012) (xy 84.898484 -53.181758)
			(xy 84.898738 -53.181758) (xy 84.919677 -53.164128) (xy 84.965648 -53.134416) (xy 85.015394 -53.111579)
			(xy 85.067893 -53.096085) (xy 85.122067 -53.088254) (xy 85.149436 -53.087778) (xy 85.176685 -53.088295)
			(xy 85.230626 -53.096055) (xy 85.282915 -53.111413) (xy 85.332486 -53.134055) (xy 85.37833 -53.163521)
			(xy 85.419514 -53.199211) (xy 85.4552 -53.240399) (xy 85.484662 -53.286246) (xy 85.5073 -53.335819)
			(xy 85.522653 -53.388109) (xy 85.530408 -53.442051) (xy 85.530408 -53.496549) (xy 85.522653 -53.550491)
			(xy 85.5073 -53.602781) (xy 85.484662 -53.652354) (xy 85.4552 -53.698201) (xy 85.419514 -53.739389)
			(xy 85.37833 -53.775079) (xy 85.332486 -53.804545) (xy 85.282915 -53.827187) (xy 85.230626 -53.842545)
			(xy 85.176685 -53.850305) (xy 85.149436 -53.850794) (xy 85.122066 -53.850308) (xy 85.067888 -53.842495)
			(xy 85.015385 -53.827011) (xy 84.965638 -53.804174) (xy 84.91967 -53.774453) (xy 84.898738 -53.756814)
			(xy 84.898484 -53.75656) (xy 84.89141 -53.750956) (xy 84.874483 -53.744721) (xy 84.865464 -53.744368)
			(xy 84.798408 -53.744368) (xy 84.789392 -53.744736) (xy 84.772476 -53.750977) (xy 84.765388 -53.75656)
			(xy 84.765388 -53.756814) (xy 84.765134 -53.756814) (xy 84.744202 -53.774453) (xy 84.698229 -53.804164)
			(xy 84.648481 -53.827) (xy 84.595981 -53.842491) (xy 84.541805 -53.85032) (xy 84.514436 -53.850794)
			(xy 84.48718 -53.850362) (xy 84.433224 -53.842608) (xy 84.380919 -53.827255) (xy 84.331333 -53.804614)
			(xy 84.285474 -53.775146) (xy 84.244275 -53.739451) (xy 84.208576 -53.698255) (xy 84.179104 -53.652399)
			(xy 84.156458 -53.602814) (xy 84.141099 -53.550512) (xy 84.133341 -53.496556) (xy 71.843618 -53.496556)
			(xy 71.847191 -53.502115) (xy 71.869833 -53.551692) (xy 71.885188 -53.603987) (xy 71.892944 -53.657935)
			(xy 71.89343 -53.685186) (xy 71.892973 -53.712557) (xy 71.885155 -53.766737) (xy 71.869665 -53.819241)
			(xy 71.846821 -53.868988) (xy 71.817093 -53.914953) (xy 71.79945 -53.935884) (xy 71.799196 -53.936138)
			(xy 71.793629 -53.943238) (xy 71.787371 -53.960144) (xy 71.787004 -53.969158) (xy 71.787004 -54.036214)
			(xy 71.787354 -54.045232) (xy 71.793606 -54.062149) (xy 71.799196 -54.069234) (xy 71.79945 -54.069234)
			(xy 71.79945 -54.069488) (xy 71.817089 -54.09042) (xy 71.846803 -54.136392) (xy 71.869639 -54.18614)
			(xy 71.88513 -54.238641) (xy 71.892957 -54.292817) (xy 71.89343 -54.320186) (xy 71.892944 -54.347437)
			(xy 71.885188 -54.401385) (xy 71.869833 -54.45368) (xy 71.847191 -54.503257) (xy 71.817725 -54.549107)
			(xy 71.782034 -54.590298) (xy 71.740843 -54.625989) (xy 71.694993 -54.655455) (xy 71.645416 -54.678097)
			(xy 71.593121 -54.693452) (xy 71.539173 -54.701208) (xy 71.484671 -54.701208) (xy 71.430723 -54.693452)
			(xy 71.378428 -54.678097) (xy 71.328851 -54.655455) (xy 71.283001 -54.625989) (xy 71.24181 -54.590298)
			(xy 71.206119 -54.549107) (xy 71.176653 -54.503257) (xy 71.154011 -54.45368) (xy 71.138656 -54.401385)
			(xy 71.1309 -54.347437) (xy 71.130414 -54.320186) (xy 68.901856 -54.320186) (xy 68.892801 -54.339901)
			(xy 68.863073 -54.385868) (xy 68.84543 -54.4068) (xy 68.845176 -54.407054) (xy 68.8396 -54.414148)
			(xy 68.833348 -54.431059) (xy 68.832984 -54.440074) (xy 68.832984 -54.50713) (xy 68.83333 -54.516148)
			(xy 68.839585 -54.533065) (xy 68.845176 -54.54015) (xy 68.84543 -54.54015) (xy 68.84543 -54.540404)
			(xy 68.863089 -54.56132) (xy 68.892797 -54.607298) (xy 68.915629 -54.657049) (xy 68.931115 -54.709553)
			(xy 68.938938 -54.763732) (xy 68.939055 -54.770528) (xy 72.070976 -54.770528) (xy 72.07144 -54.743157)
			(xy 72.079255 -54.688978) (xy 72.094744 -54.636474) (xy 72.117587 -54.586727) (xy 72.147313 -54.540761)
			(xy 72.164956 -54.51983) (xy 72.16521 -54.519576) (xy 72.170814 -54.512501) (xy 72.17705 -54.495575)
			(xy 72.177402 -54.486556) (xy 72.177402 -54.4195) (xy 72.177045 -54.410483) (xy 72.170797 -54.393566)
			(xy 72.16521 -54.38648) (xy 72.164956 -54.38648) (xy 72.164956 -54.386226) (xy 72.147308 -54.365301)
			(xy 72.117599 -54.319326) (xy 72.094766 -54.269576) (xy 72.079276 -54.217074) (xy 72.071449 -54.162898)
			(xy 72.070976 -54.135528) (xy 72.071462 -54.108277) (xy 72.079218 -54.054329) (xy 72.094573 -54.002034)
			(xy 72.117215 -53.952457) (xy 72.146681 -53.906607) (xy 72.182372 -53.865416) (xy 72.223563 -53.829725)
			(xy 72.269413 -53.800259) (xy 72.31899 -53.777617) (xy 72.371285 -53.762262) (xy 72.425233 -53.754506)
			(xy 72.479735 -53.754506) (xy 72.533683 -53.762262) (xy 72.585978 -53.777617) (xy 72.635555 -53.800259)
			(xy 72.681405 -53.829725) (xy 72.722596 -53.865416) (xy 72.758287 -53.906607) (xy 72.787753 -53.952457)
			(xy 72.792828 -53.96357) (xy 76.772006 -53.96357) (xy 76.776077 -53.907948) (xy 76.788203 -53.853511)
			(xy 76.808126 -53.80142) (xy 76.835422 -53.752785) (xy 76.869508 -53.708642) (xy 76.909657 -53.669933)
			(xy 76.955015 -53.637482) (xy 77.004615 -53.611981) (xy 77.057399 -53.593974) (xy 77.112242 -53.583844)
			(xy 77.167976 -53.581807) (xy 77.223413 -53.587907) (xy 77.27737 -53.602013) (xy 77.328699 -53.623825)
			(xy 77.376305 -53.652879) (xy 77.419173 -53.688554) (xy 77.45639 -53.730091) (xy 77.487163 -53.776604)
			(xy 77.510835 -53.827101) (xy 77.526903 -53.880508) (xy 77.535023 -53.935684) (xy 77.535532 -53.96357)
			(xy 77.535023 -53.991456) (xy 77.526903 -54.046632) (xy 77.510835 -54.100039) (xy 77.487163 -54.150536)
			(xy 77.45639 -54.197049) (xy 77.419173 -54.238586) (xy 77.376305 -54.274261) (xy 77.328699 -54.303315)
			(xy 77.27737 -54.325127) (xy 77.223413 -54.339233) (xy 77.167976 -54.345333) (xy 77.112242 -54.343296)
			(xy 77.057399 -54.333166) (xy 77.004615 -54.315159) (xy 76.955015 -54.289658) (xy 76.909657 -54.257207)
			(xy 76.869508 -54.218498) (xy 76.835422 -54.174355) (xy 76.808126 -54.12572) (xy 76.788203 -54.073629)
			(xy 76.776077 -54.019192) (xy 76.772006 -53.96357) (xy 72.792828 -53.96357) (xy 72.810395 -54.002034)
			(xy 72.82575 -54.054329) (xy 72.833506 -54.108277) (xy 72.833992 -54.135528) (xy 72.833544 -54.162899)
			(xy 72.825722 -54.217079) (xy 72.810229 -54.269582) (xy 72.787383 -54.319329) (xy 72.757655 -54.365295)
			(xy 72.740012 -54.386226) (xy 72.739758 -54.38648) (xy 72.734169 -54.393564) (xy 72.727925 -54.410483)
			(xy 72.727566 -54.4195) (xy 72.727566 -54.486556) (xy 72.727951 -54.49557) (xy 72.73418 -54.512487)
			(xy 72.739758 -54.519576) (xy 72.740012 -54.519576) (xy 72.740012 -54.51983) (xy 72.757634 -54.540776)
			(xy 72.787348 -54.586745) (xy 72.810187 -54.636489) (xy 72.825682 -54.688987) (xy 72.833515 -54.74316)
			(xy 72.833992 -54.770528) (xy 72.833506 -54.797779) (xy 72.82575 -54.851727) (xy 72.810395 -54.904022)
			(xy 72.787753 -54.953599) (xy 72.764967 -54.989055) (xy 81.900945 -54.989055) (xy 81.900945 -54.934545)
			(xy 81.908703 -54.88059) (xy 81.924061 -54.828288) (xy 81.946706 -54.778705) (xy 81.976178 -54.732849)
			(xy 82.011876 -54.691654) (xy 82.053073 -54.65596) (xy 82.098931 -54.626492) (xy 82.148516 -54.60385)
			(xy 82.200819 -54.588497) (xy 82.254775 -54.580743) (xy 82.28203 -54.580282) (xy 82.310122 -54.580753)
			(xy 82.365701 -54.588985) (xy 82.41947 -54.60528) (xy 82.470268 -54.629286) (xy 82.516994 -54.660485)
			(xy 82.558639 -54.6982) (xy 82.5943 -54.741616) (xy 82.609182 -54.765448) (xy 82.614516 -54.774338)
			(xy 82.631534 -54.78653) (xy 82.724752 -54.80685) (xy 82.745326 -54.802532) (xy 82.753962 -54.79669)
			(xy 82.778034 -54.780703) (xy 82.829963 -54.755357) (xy 82.885118 -54.738128) (xy 82.94224 -54.729409)
			(xy 82.971132 -54.728872) (xy 82.998383 -54.729348) (xy 83.05233 -54.737108) (xy 83.104624 -54.752467)
			(xy 83.1542 -54.77511) (xy 83.200049 -54.804578) (xy 83.241238 -54.84027) (xy 83.27693 -54.88146)
			(xy 83.306396 -54.927311) (xy 83.329038 -54.976887) (xy 83.344394 -55.029182) (xy 83.352153 -55.083129)
			(xy 83.35264 -55.11038) (xy 83.352177 -55.137751) (xy 83.344361 -55.19193) (xy 83.328872 -55.244434)
			(xy 83.306029 -55.294181) (xy 83.276302 -55.340147) (xy 83.25866 -55.361078) (xy 83.258406 -55.361332)
			(xy 83.252842 -55.368434) (xy 83.246582 -55.385339) (xy 83.246214 -55.394352) (xy 83.246214 -55.461408)
			(xy 83.246564 -55.470426) (xy 83.252816 -55.487343) (xy 83.258406 -55.494428) (xy 83.25866 -55.494428)
			(xy 83.25866 -55.494682) (xy 83.276282 -55.51563) (xy 83.306008 -55.561595) (xy 83.328856 -55.611339)
			(xy 83.344354 -55.663839) (xy 83.352185 -55.718015) (xy 83.352187 -55.772755) (xy 83.34436 -55.826932)
			(xy 83.328866 -55.879433) (xy 83.306023 -55.929178) (xy 83.2763 -55.975146) (xy 83.25866 -55.996078)
			(xy 83.258406 -55.996332) (xy 83.252842 -56.003434) (xy 83.246582 -56.020339) (xy 83.246214 -56.029352)
			(xy 83.246214 -56.096408) (xy 83.246564 -56.105426) (xy 83.252816 -56.122343) (xy 83.258406 -56.129428)
			(xy 83.25866 -56.129428) (xy 83.25866 -56.129682) (xy 83.276298 -56.150615) (xy 83.306011 -56.196587)
			(xy 83.328848 -56.246334) (xy 83.344339 -56.298835) (xy 83.352167 -56.353011) (xy 83.35264 -56.38038)
			(xy 83.352154 -56.407631) (xy 83.344398 -56.461579) (xy 83.329043 -56.513874) (xy 83.306401 -56.563451)
			(xy 83.276935 -56.609301) (xy 83.241244 -56.650492) (xy 83.200053 -56.686183) (xy 83.154203 -56.715649)
			(xy 83.104626 -56.738291) (xy 83.052331 -56.753646) (xy 82.998383 -56.761402) (xy 82.943881 -56.761402)
			(xy 82.889933 -56.753646) (xy 82.837638 -56.738291) (xy 82.788061 -56.715649) (xy 82.742211 -56.686183)
			(xy 82.70102 -56.650492) (xy 82.665329 -56.609301) (xy 82.635863 -56.563451) (xy 82.613221 -56.513874)
			(xy 82.597866 -56.461579) (xy 82.59011 -56.407631) (xy 82.589624 -56.38038) (xy 82.590072 -56.353009)
			(xy 82.597894 -56.298829) (xy 82.613387 -56.246325) (xy 82.636232 -56.196579) (xy 82.665961 -56.150613)
			(xy 82.683604 -56.129682) (xy 82.683858 -56.129428) (xy 82.689446 -56.122343) (xy 82.69569 -56.105425)
			(xy 82.69605 -56.096408) (xy 82.69605 -56.029352) (xy 82.695679 -56.020336) (xy 82.689442 -56.003419)
			(xy 82.683858 -55.996332) (xy 82.683604 -55.996332) (xy 82.683604 -55.996078) (xy 82.665945 -55.975161)
			(xy 82.636222 -55.92919) (xy 82.61338 -55.879441) (xy 82.597886 -55.826936) (xy 82.59006 -55.772756)
			(xy 82.590062 -55.718014) (xy 82.597892 -55.663834) (xy 82.61339 -55.611331) (xy 82.636237 -55.561584)
			(xy 82.665963 -55.515615) (xy 82.683604 -55.494682) (xy 82.683858 -55.494428) (xy 82.689446 -55.487343)
			(xy 82.69569 -55.470425) (xy 82.69605 -55.461408) (xy 82.69605 -55.394352) (xy 82.695679 -55.385336)
			(xy 82.689442 -55.368419) (xy 82.683858 -55.361332) (xy 82.683604 -55.360824) (xy 82.672661 -55.348089)
			(xy 82.652819 -55.320998) (xy 82.64398 -55.306722) (xy 82.638646 -55.297832) (xy 82.621628 -55.28564)
			(xy 82.52841 -55.26532) (xy 82.507836 -55.269638) (xy 82.4992 -55.27548) (xy 82.475136 -55.29148)
			(xy 82.423205 -55.316823) (xy 82.368047 -55.334049) (xy 82.310923 -55.342764) (xy 82.28203 -55.343298)
			(xy 82.254775 -55.342857) (xy 82.200819 -55.335103) (xy 82.148516 -55.31975) (xy 82.098931 -55.297108)
			(xy 82.053073 -55.26764) (xy 82.011876 -55.231946) (xy 81.976178 -55.190751) (xy 81.946706 -55.144895)
			(xy 81.924061 -55.095312) (xy 81.908703 -55.04301) (xy 81.900945 -54.989055) (xy 72.764967 -54.989055)
			(xy 72.758287 -54.999449) (xy 72.722596 -55.04064) (xy 72.681405 -55.076331) (xy 72.635555 -55.105797)
			(xy 72.585978 -55.128439) (xy 72.533683 -55.143794) (xy 72.479735 -55.15155) (xy 72.425233 -55.15155)
			(xy 72.371285 -55.143794) (xy 72.31899 -55.128439) (xy 72.269413 -55.105797) (xy 72.223563 -55.076331)
			(xy 72.182372 -55.04064) (xy 72.146681 -54.999449) (xy 72.117215 -54.953599) (xy 72.094573 -54.904022)
			(xy 72.079218 -54.851727) (xy 72.071462 -54.797779) (xy 72.070976 -54.770528) (xy 68.939055 -54.770528)
			(xy 68.93941 -54.791102) (xy 68.938924 -54.818353) (xy 68.931168 -54.872301) (xy 68.915813 -54.924596)
			(xy 68.893171 -54.974173) (xy 68.863705 -55.020023) (xy 68.828014 -55.061214) (xy 68.786823 -55.096905)
			(xy 68.740973 -55.126371) (xy 68.691396 -55.149013) (xy 68.639101 -55.164368) (xy 68.585153 -55.172124)
			(xy 68.530651 -55.172124) (xy 68.476703 -55.164368) (xy 68.424408 -55.149013) (xy 68.374831 -55.126371)
			(xy 68.328981 -55.096905) (xy 68.28779 -55.061214) (xy 68.252099 -55.020023) (xy 68.222633 -54.974173)
			(xy 68.199991 -54.924596) (xy 68.184636 -54.872301) (xy 68.17688 -54.818353) (xy 68.176394 -54.791102)
			(xy 66.278436 -54.791102) (xy 66.275344 -54.812611) (xy 66.259989 -54.864906) (xy 66.237347 -54.914483)
			(xy 66.207881 -54.960333) (xy 66.17219 -55.001524) (xy 66.130999 -55.037215) (xy 66.085149 -55.066681)
			(xy 66.035572 -55.089323) (xy 65.983277 -55.104678) (xy 65.929329 -55.112434) (xy 65.874827 -55.112434)
			(xy 65.820879 -55.104678) (xy 65.768584 -55.089323) (xy 65.719007 -55.066681) (xy 65.673157 -55.037215)
			(xy 65.631966 -55.001524) (xy 65.596275 -54.960333) (xy 65.566809 -54.914483) (xy 65.544167 -54.864906)
			(xy 65.528812 -54.812611) (xy 65.521056 -54.758663) (xy 65.52057 -54.731412) (xy 64.522564 -54.731412)
			(xy 64.582027 -55.722266) (xy 77.83398 -55.722266) (xy 77.838051 -55.666644) (xy 77.850177 -55.612207)
			(xy 77.8701 -55.560116) (xy 77.897396 -55.511481) (xy 77.931482 -55.467338) (xy 77.971631 -55.428629)
			(xy 78.016989 -55.396178) (xy 78.066589 -55.370677) (xy 78.119373 -55.35267) (xy 78.174216 -55.34254)
			(xy 78.22995 -55.340503) (xy 78.285387 -55.346603) (xy 78.339344 -55.360709) (xy 78.390673 -55.382521)
			(xy 78.438279 -55.411575) (xy 78.44943 -55.420855) (xy 80.224545 -55.420855) (xy 80.224545 -55.366345)
			(xy 80.232303 -55.31239) (xy 80.247661 -55.260088) (xy 80.270306 -55.210505) (xy 80.299778 -55.164649)
			(xy 80.335476 -55.123454) (xy 80.376673 -55.08776) (xy 80.422531 -55.058292) (xy 80.472116 -55.03565)
			(xy 80.524419 -55.020297) (xy 80.578375 -55.012543) (xy 80.60563 -55.012082) (xy 80.631944 -55.012535)
			(xy 80.684073 -55.019774) (xy 80.734716 -55.034096) (xy 80.782915 -55.055231) (xy 80.827758 -55.082779)
			(xy 80.868397 -55.11622) (xy 80.886554 -55.135272) (xy 80.894057 -55.142695) (xy 80.913351 -55.151208)
			(xy 80.923892 -55.151782) (xy 80.998568 -55.151782) (xy 81.009118 -55.151255) (xy 81.028414 -55.142719)
			(xy 81.035906 -55.135272) (xy 81.05406 -55.116215) (xy 81.094691 -55.082759) (xy 81.139532 -55.055201)
			(xy 81.187733 -55.034063) (xy 81.23838 -55.019746) (xy 81.290514 -55.012521) (xy 81.31683 -55.012082)
			(xy 81.344079 -55.01259) (xy 81.398022 -55.02035) (xy 81.450312 -55.035707) (xy 81.499884 -55.05835)
			(xy 81.545729 -55.087816) (xy 81.586915 -55.123506) (xy 81.622602 -55.164695) (xy 81.652065 -55.210542)
			(xy 81.674703 -55.260116) (xy 81.690056 -55.312407) (xy 81.697812 -55.366351) (xy 81.697812 -55.420849)
			(xy 81.690056 -55.474793) (xy 81.674703 -55.527084) (xy 81.652065 -55.576658) (xy 81.622602 -55.622505)
			(xy 81.586915 -55.663694) (xy 81.545729 -55.699384) (xy 81.499884 -55.72885) (xy 81.450312 -55.751493)
			(xy 81.398022 -55.76685) (xy 81.344079 -55.77461) (xy 81.31683 -55.775098) (xy 81.290514 -55.774678)
			(xy 81.238384 -55.767433) (xy 81.18774 -55.753105) (xy 81.139541 -55.731964) (xy 81.094699 -55.704409)
			(xy 81.054061 -55.670963) (xy 81.035906 -55.651908) (xy 81.028383 -55.644508) (xy 81.009104 -55.635983)
			(xy 80.998568 -55.635398) (xy 80.923892 -55.635398) (xy 80.91334 -55.63591) (xy 80.894045 -55.644457)
			(xy 80.886554 -55.651908) (xy 80.868415 -55.67098) (xy 80.827782 -55.704436) (xy 80.782938 -55.731992)
			(xy 80.734734 -55.753128) (xy 80.684084 -55.767441) (xy 80.631947 -55.774662) (xy 80.60563 -55.775098)
			(xy 80.578375 -55.774657) (xy 80.524419 -55.766903) (xy 80.472116 -55.75155) (xy 80.422531 -55.728908)
			(xy 80.376673 -55.69944) (xy 80.335476 -55.663746) (xy 80.299778 -55.622551) (xy 80.270306 -55.576695)
			(xy 80.247661 -55.527112) (xy 80.232303 -55.47481) (xy 80.224545 -55.420855) (xy 78.44943 -55.420855)
			(xy 78.481147 -55.44725) (xy 78.518364 -55.488787) (xy 78.549137 -55.5353) (xy 78.572809 -55.585797)
			(xy 78.588877 -55.639204) (xy 78.596997 -55.69438) (xy 78.597506 -55.722266) (xy 78.596997 -55.750152)
			(xy 78.588877 -55.805328) (xy 78.572809 -55.858735) (xy 78.549137 -55.909232) (xy 78.518364 -55.955745)
			(xy 78.481147 -55.997282) (xy 78.438279 -56.032957) (xy 78.390673 -56.062011) (xy 78.339344 -56.083823)
			(xy 78.285387 -56.097929) (xy 78.22995 -56.104029) (xy 78.174216 -56.101992) (xy 78.119373 -56.091862)
			(xy 78.066589 -56.073855) (xy 78.016989 -56.048354) (xy 77.971631 -56.015903) (xy 77.931482 -55.977194)
			(xy 77.897396 -55.933051) (xy 77.8701 -55.884416) (xy 77.850177 -55.832325) (xy 77.838051 -55.777888)
			(xy 77.83398 -55.722266) (xy 64.582027 -55.722266) (xy 64.658882 -57.002934) (xy 73.56348 -57.002934)
			(xy 73.564003 -56.974843) (xy 73.572225 -56.919268) (xy 73.588511 -56.865499) (xy 73.612509 -56.814702)
			(xy 73.6437 -56.767975) (xy 73.681408 -56.726329) (xy 73.724817 -56.690665) (xy 73.748646 -56.675782)
			(xy 73.757536 -56.670448) (xy 73.769728 -56.65343) (xy 73.790048 -56.560212) (xy 73.78573 -56.539638)
			(xy 73.779888 -56.531002) (xy 73.763885 -56.50694) (xy 73.738544 -56.455008) (xy 73.721319 -56.399849)
			(xy 73.712604 -56.342725) (xy 73.71207 -56.313832) (xy 73.712585 -56.286581) (xy 73.720337 -56.232633)
			(xy 73.735688 -56.180337) (xy 73.758325 -56.130759) (xy 73.787788 -56.084907) (xy 73.823476 -56.043714)
			(xy 73.864663 -56.00802) (xy 73.910511 -55.978551) (xy 73.960087 -55.955907) (xy 74.01238 -55.940549)
			(xy 74.066327 -55.932789) (xy 74.093578 -55.932324) (xy 74.120948 -55.932797) (xy 74.175127 -55.940612)
			(xy 74.22763 -55.956099) (xy 74.277377 -55.97894) (xy 74.323344 -56.008663) (xy 74.344276 -56.026304)
			(xy 74.34453 -56.026558) (xy 74.351627 -56.032128) (xy 74.368536 -56.038383) (xy 74.37755 -56.03875)
			(xy 74.444606 -56.03875) (xy 74.453624 -56.038406) (xy 74.470542 -56.032151) (xy 74.477626 -56.026558)
			(xy 74.477626 -56.026304) (xy 74.47788 -56.026304) (xy 74.498813 -56.008663) (xy 74.544781 -55.978939)
			(xy 74.594527 -55.956093) (xy 74.647029 -55.940597) (xy 74.701207 -55.932768) (xy 74.755949 -55.932768)
			(xy 74.810127 -55.940597) (xy 74.862629 -55.956093) (xy 74.912375 -55.978939) (xy 74.958343 -56.008663)
			(xy 74.979276 -56.026304) (xy 74.97953 -56.026558) (xy 74.986627 -56.032128) (xy 75.003536 -56.038383)
			(xy 75.01255 -56.03875) (xy 75.079606 -56.03875) (xy 75.088624 -56.038406) (xy 75.105542 -56.032151)
			(xy 75.112626 -56.026558) (xy 75.112626 -56.026304) (xy 75.11288 -56.026304) (xy 75.133809 -56.008661)
			(xy 75.179783 -55.97895) (xy 75.229531 -55.956115) (xy 75.282032 -55.940624) (xy 75.336209 -55.932797)
			(xy 75.363578 -55.932324) (xy 75.390834 -55.932721) (xy 75.444792 -55.940477) (xy 75.497097 -55.955832)
			(xy 75.546684 -55.978475) (xy 75.592544 -56.007945) (xy 75.633743 -56.043642) (xy 75.669442 -56.084838)
			(xy 75.698914 -56.130697) (xy 75.72156 -56.180282) (xy 75.736919 -56.232586) (xy 75.744677 -56.286544)
			(xy 75.744677 -56.297068) (xy 76.08646 -56.297068) (xy 76.090531 -56.241446) (xy 76.102657 -56.187009)
			(xy 76.12258 -56.134918) (xy 76.149876 -56.086283) (xy 76.183962 -56.04214) (xy 76.224111 -56.003431)
			(xy 76.269469 -55.97098) (xy 76.319069 -55.945479) (xy 76.371853 -55.927472) (xy 76.426696 -55.917342)
			(xy 76.48243 -55.915305) (xy 76.537867 -55.921405) (xy 76.591824 -55.935511) (xy 76.643153 -55.957323)
			(xy 76.690759 -55.986377) (xy 76.733627 -56.022052) (xy 76.770844 -56.063589) (xy 76.801617 -56.110102)
			(xy 76.825289 -56.160599) (xy 76.841357 -56.214006) (xy 76.849477 -56.269182) (xy 76.849986 -56.297068)
			(xy 76.849477 -56.324954) (xy 76.841357 -56.38013) (xy 76.825289 -56.433537) (xy 76.801617 -56.484034)
			(xy 76.770844 -56.530547) (xy 76.733627 -56.572084) (xy 76.690759 -56.607759) (xy 76.643153 -56.636813)
			(xy 76.591824 -56.658625) (xy 76.537867 -56.672731) (xy 76.48243 -56.678831) (xy 76.426696 -56.676794)
			(xy 76.371853 -56.666664) (xy 76.319069 -56.648657) (xy 76.269469 -56.623156) (xy 76.224111 -56.590705)
			(xy 76.183962 -56.551996) (xy 76.149876 -56.507853) (xy 76.12258 -56.459218) (xy 76.102657 -56.407127)
			(xy 76.090531 -56.35269) (xy 76.08646 -56.297068) (xy 75.744677 -56.297068) (xy 75.744677 -56.341056)
			(xy 75.736919 -56.395014) (xy 75.72156 -56.447318) (xy 75.698914 -56.496903) (xy 75.669442 -56.542762)
			(xy 75.633743 -56.583958) (xy 75.592544 -56.619655) (xy 75.546684 -56.649125) (xy 75.497097 -56.671768)
			(xy 75.444792 -56.687123) (xy 75.390834 -56.694879) (xy 75.363578 -56.69534) (xy 75.336207 -56.694901)
			(xy 75.282026 -56.687079) (xy 75.229522 -56.671585) (xy 75.179775 -56.648736) (xy 75.13381 -56.619005)
			(xy 75.11288 -56.60136) (xy 75.112626 -56.601106) (xy 75.105536 -56.595525) (xy 75.088622 -56.589275)
			(xy 75.079606 -56.588914) (xy 75.01255 -56.588914) (xy 75.003535 -56.589292) (xy 74.986618 -56.595525)
			(xy 74.97953 -56.601106) (xy 74.97953 -56.60136) (xy 74.979276 -56.60136) (xy 74.958343 -56.619001)
			(xy 74.912375 -56.648725) (xy 74.862629 -56.671571) (xy 74.810127 -56.687067) (xy 74.755949 -56.694896)
			(xy 74.701207 -56.694896) (xy 74.647029 -56.687067) (xy 74.594527 -56.671571) (xy 74.544781 -56.648725)
			(xy 74.498813 -56.619001) (xy 74.47788 -56.60136) (xy 74.477626 -56.601106) (xy 74.470536 -56.595525)
			(xy 74.453622 -56.589275) (xy 74.444606 -56.588914) (xy 74.37755 -56.588914) (xy 74.368535 -56.589292)
			(xy 74.351618 -56.595525) (xy 74.34453 -56.601106) (xy 74.344022 -56.60136) (xy 74.33129 -56.612307)
			(xy 74.304197 -56.632146) (xy 74.28992 -56.640984) (xy 74.28103 -56.646318) (xy 74.268838 -56.663336)
			(xy 74.248518 -56.756554) (xy 74.252836 -56.777128) (xy 74.258678 -56.785764) (xy 74.274662 -56.809838)
			(xy 74.300009 -56.861765) (xy 74.317239 -56.91692) (xy 74.325959 -56.974042) (xy 74.326496 -57.002934)
			(xy 74.32601 -57.030185) (xy 74.318254 -57.084133) (xy 74.302899 -57.136428) (xy 74.280257 -57.186005)
			(xy 74.250791 -57.231855) (xy 74.2151 -57.273046) (xy 74.173909 -57.308737) (xy 74.128059 -57.338203)
			(xy 74.078482 -57.360845) (xy 74.026187 -57.3762) (xy 73.972239 -57.383956) (xy 73.917737 -57.383956)
			(xy 73.863789 -57.3762) (xy 73.811494 -57.360845) (xy 73.761917 -57.338203) (xy 73.716067 -57.308737)
			(xy 73.674876 -57.273046) (xy 73.639185 -57.231855) (xy 73.609719 -57.186005) (xy 73.587077 -57.136428)
			(xy 73.571722 -57.084133) (xy 73.563966 -57.030185) (xy 73.56348 -57.002934) (xy 64.658882 -57.002934)
			(xy 64.687828 -57.48528) (xy 82.605878 -57.48528) (xy 82.609949 -57.429658) (xy 82.622075 -57.375221)
			(xy 82.641998 -57.32313) (xy 82.669294 -57.274495) (xy 82.70338 -57.230352) (xy 82.743529 -57.191643)
			(xy 82.788887 -57.159192) (xy 82.838487 -57.133691) (xy 82.891271 -57.115684) (xy 82.946114 -57.105554)
			(xy 83.001848 -57.103517) (xy 83.057285 -57.109617) (xy 83.111242 -57.123723) (xy 83.162571 -57.145535)
			(xy 83.210177 -57.174589) (xy 83.253045 -57.210264) (xy 83.290262 -57.251801) (xy 83.321035 -57.298314)
			(xy 83.344707 -57.348811) (xy 83.360775 -57.402218) (xy 83.368895 -57.457394) (xy 83.369404 -57.48528)
			(xy 83.368895 -57.513166) (xy 83.360775 -57.568342) (xy 83.344707 -57.621749) (xy 83.321035 -57.672246)
			(xy 83.290262 -57.718759) (xy 83.253045 -57.760296) (xy 83.210177 -57.795971) (xy 83.162571 -57.825025)
			(xy 83.111242 -57.846837) (xy 83.057285 -57.860943) (xy 83.001848 -57.867043) (xy 82.946114 -57.865006)
			(xy 82.891271 -57.854876) (xy 82.838487 -57.836869) (xy 82.788887 -57.811368) (xy 82.743529 -57.778917)
			(xy 82.70338 -57.740208) (xy 82.669294 -57.696065) (xy 82.641998 -57.64743) (xy 82.622075 -57.595339)
			(xy 82.609949 -57.540902) (xy 82.605878 -57.48528) (xy 64.687828 -57.48528) (xy 64.759485 -58.679334)
			(xy 73.99528 -58.679334) (xy 73.99571 -58.653019) (xy 74.002953 -58.600889) (xy 74.01728 -58.550246)
			(xy 74.03842 -58.502047) (xy 74.065972 -58.457204) (xy 74.099416 -58.416566) (xy 74.11847 -58.39841)
			(xy 74.125865 -58.390883) (xy 74.134394 -58.371607) (xy 74.13498 -58.361072) (xy 74.13498 -58.286396)
			(xy 74.134472 -58.275844) (xy 74.125923 -58.256548) (xy 74.11847 -58.249058) (xy 74.099395 -58.230922)
			(xy 74.065941 -58.190287) (xy 74.038385 -58.145443) (xy 74.01725 -58.097238) (xy 74.002937 -58.046588)
			(xy 73.995716 -57.994451) (xy 73.99528 -57.968134) (xy 73.995766 -57.940883) (xy 74.003522 -57.886935)
			(xy 74.018877 -57.83464) (xy 74.041519 -57.785063) (xy 74.070985 -57.739213) (xy 74.106676 -57.698022)
			(xy 74.147867 -57.662331) (xy 74.193717 -57.632865) (xy 74.243294 -57.610223) (xy 74.295589 -57.594868)
			(xy 74.349537 -57.587112) (xy 74.404039 -57.587112) (xy 74.457987 -57.594868) (xy 74.510282 -57.610223)
			(xy 74.559859 -57.632865) (xy 74.605709 -57.662331) (xy 74.6469 -57.698022) (xy 74.682591 -57.739213)
			(xy 74.712057 -57.785063) (xy 74.734699 -57.83464) (xy 74.750054 -57.886935) (xy 74.75781 -57.940883)
			(xy 74.758296 -57.968134) (xy 74.757853 -57.994449) (xy 74.750613 -58.046578) (xy 74.743345 -58.072274)
			(xy 77.993492 -58.072274) (xy 77.997563 -58.016652) (xy 78.009689 -57.962215) (xy 78.029612 -57.910124)
			(xy 78.056908 -57.861489) (xy 78.090994 -57.817346) (xy 78.131143 -57.778637) (xy 78.176501 -57.746186)
			(xy 78.226101 -57.720685) (xy 78.278885 -57.702678) (xy 78.333728 -57.692548) (xy 78.389462 -57.690511)
			(xy 78.444899 -57.696611) (xy 78.498856 -57.710717) (xy 78.550185 -57.732529) (xy 78.597791 -57.761583)
			(xy 78.640659 -57.797258) (xy 78.677876 -57.838795) (xy 78.708649 -57.885308) (xy 78.732321 -57.935805)
			(xy 78.748389 -57.989212) (xy 78.756509 -58.044388) (xy 78.757018 -58.072274) (xy 78.756948 -58.076084)
			(xy 83.357972 -58.076084) (xy 83.362043 -58.020462) (xy 83.374169 -57.966025) (xy 83.394092 -57.913934)
			(xy 83.421388 -57.865299) (xy 83.455474 -57.821156) (xy 83.495623 -57.782447) (xy 83.540981 -57.749996)
			(xy 83.590581 -57.724495) (xy 83.643365 -57.706488) (xy 83.698208 -57.696358) (xy 83.753942 -57.694321)
			(xy 83.809379 -57.700421) (xy 83.863336 -57.714527) (xy 83.914665 -57.736339) (xy 83.962271 -57.765393)
			(xy 84.005139 -57.801068) (xy 84.042356 -57.842605) (xy 84.058692 -57.867296) (xy 85.642956 -57.867296)
			(xy 85.647027 -57.811674) (xy 85.659153 -57.757237) (xy 85.679076 -57.705146) (xy 85.706372 -57.656511)
			(xy 85.740458 -57.612368) (xy 85.780607 -57.573659) (xy 85.825965 -57.541208) (xy 85.875565 -57.515707)
			(xy 85.928349 -57.4977) (xy 85.983192 -57.48757) (xy 86.038926 -57.485533) (xy 86.094363 -57.491633)
			(xy 86.14832 -57.505739) (xy 86.199649 -57.527551) (xy 86.247255 -57.556605) (xy 86.290123 -57.59228)
			(xy 86.32734 -57.633817) (xy 86.358113 -57.68033) (xy 86.381785 -57.730827) (xy 86.397853 -57.784234)
			(xy 86.405973 -57.83941) (xy 86.406482 -57.867296) (xy 86.405973 -57.895182) (xy 86.397853 -57.950358)
			(xy 86.381785 -58.003765) (xy 86.358113 -58.054262) (xy 86.32734 -58.100775) (xy 86.290123 -58.142312)
			(xy 86.247255 -58.177987) (xy 86.199649 -58.207041) (xy 86.14832 -58.228853) (xy 86.094363 -58.242959)
			(xy 86.038926 -58.249059) (xy 85.983192 -58.247022) (xy 85.928349 -58.236892) (xy 85.875565 -58.218885)
			(xy 85.825965 -58.193384) (xy 85.780607 -58.160933) (xy 85.740458 -58.122224) (xy 85.706372 -58.078081)
			(xy 85.679076 -58.029446) (xy 85.659153 -57.977355) (xy 85.647027 -57.922918) (xy 85.642956 -57.867296)
			(xy 84.058692 -57.867296) (xy 84.073129 -57.889118) (xy 84.096801 -57.939615) (xy 84.112869 -57.993022)
			(xy 84.120989 -58.048198) (xy 84.121498 -58.076084) (xy 84.120989 -58.10397) (xy 84.112869 -58.159146)
			(xy 84.096801 -58.212553) (xy 84.073129 -58.26305) (xy 84.042356 -58.309563) (xy 84.005139 -58.3511)
			(xy 83.962271 -58.386775) (xy 83.914665 -58.415829) (xy 83.863336 -58.437641) (xy 83.809379 -58.451747)
			(xy 83.753942 -58.457847) (xy 83.698208 -58.45581) (xy 83.643365 -58.44568) (xy 83.590581 -58.427673)
			(xy 83.540981 -58.402172) (xy 83.495623 -58.369721) (xy 83.455474 -58.331012) (xy 83.421388 -58.286869)
			(xy 83.394092 -58.238234) (xy 83.374169 -58.186143) (xy 83.362043 -58.131706) (xy 83.357972 -58.076084)
			(xy 78.756948 -58.076084) (xy 78.756509 -58.10016) (xy 78.748389 -58.155336) (xy 78.732321 -58.208743)
			(xy 78.708649 -58.25924) (xy 78.677876 -58.305753) (xy 78.640659 -58.34729) (xy 78.597791 -58.382965)
			(xy 78.550185 -58.412019) (xy 78.498856 -58.433831) (xy 78.444899 -58.447937) (xy 78.389462 -58.454037)
			(xy 78.333728 -58.452) (xy 78.278885 -58.44187) (xy 78.226101 -58.423863) (xy 78.176501 -58.398362)
			(xy 78.131143 -58.365911) (xy 78.090994 -58.327202) (xy 78.056908 -58.283059) (xy 78.029612 -58.234424)
			(xy 78.009689 -58.182333) (xy 77.997563 -58.127896) (xy 77.993492 -58.072274) (xy 74.743345 -58.072274)
			(xy 74.736289 -58.097222) (xy 74.715152 -58.145421) (xy 74.687602 -58.190263) (xy 74.654159 -58.230902)
			(xy 74.635106 -58.249058) (xy 74.627722 -58.256594) (xy 74.619187 -58.275863) (xy 74.618596 -58.286396)
			(xy 74.618596 -58.361072) (xy 74.619128 -58.371621) (xy 74.627661 -58.390917) (xy 74.635106 -58.39841)
			(xy 74.654161 -58.416567) (xy 74.687618 -58.457196) (xy 74.715177 -58.502036) (xy 74.736315 -58.550237)
			(xy 74.739421 -58.561224) (xy 84.562186 -58.561224) (xy 84.566257 -58.505602) (xy 84.578383 -58.451165)
			(xy 84.598306 -58.399074) (xy 84.625602 -58.350439) (xy 84.659688 -58.306296) (xy 84.699837 -58.267587)
			(xy 84.745195 -58.235136) (xy 84.794795 -58.209635) (xy 84.847579 -58.191628) (xy 84.902422 -58.181498)
			(xy 84.958156 -58.179461) (xy 85.013593 -58.185561) (xy 85.06755 -58.199667) (xy 85.118879 -58.221479)
			(xy 85.166485 -58.250533) (xy 85.209353 -58.286208) (xy 85.24657 -58.327745) (xy 85.277343 -58.374258)
			(xy 85.301015 -58.424755) (xy 85.308525 -58.449718) (xy 86.808816 -58.449718) (xy 86.812887 -58.394096)
			(xy 86.825013 -58.339659) (xy 86.844936 -58.287568) (xy 86.872232 -58.238933) (xy 86.906318 -58.19479)
			(xy 86.946467 -58.156081) (xy 86.991825 -58.12363) (xy 87.041425 -58.098129) (xy 87.094209 -58.080122)
			(xy 87.149052 -58.069992) (xy 87.204786 -58.067955) (xy 87.260223 -58.074055) (xy 87.31418 -58.088161)
			(xy 87.365509 -58.109973) (xy 87.413115 -58.139027) (xy 87.455983 -58.174702) (xy 87.4932 -58.216239)
			(xy 87.523973 -58.262752) (xy 87.547645 -58.313249) (xy 87.563713 -58.366656) (xy 87.571833 -58.421832)
			(xy 87.572342 -58.449718) (xy 87.571833 -58.477604) (xy 87.563713 -58.53278) (xy 87.547645 -58.586187)
			(xy 87.523973 -58.636684) (xy 87.4932 -58.683197) (xy 87.455983 -58.724734) (xy 87.413115 -58.760409)
			(xy 87.365509 -58.789463) (xy 87.31418 -58.811275) (xy 87.260223 -58.825381) (xy 87.204786 -58.831481)
			(xy 87.149052 -58.829444) (xy 87.094209 -58.819314) (xy 87.041425 -58.801307) (xy 86.991825 -58.775806)
			(xy 86.946467 -58.743355) (xy 86.906318 -58.704646) (xy 86.872232 -58.660503) (xy 86.844936 -58.611868)
			(xy 86.825013 -58.559777) (xy 86.812887 -58.50534) (xy 86.808816 -58.449718) (xy 85.308525 -58.449718)
			(xy 85.317083 -58.478162) (xy 85.325203 -58.533338) (xy 85.325712 -58.561224) (xy 85.325203 -58.58911)
			(xy 85.317083 -58.644286) (xy 85.301015 -58.697693) (xy 85.277343 -58.74819) (xy 85.24657 -58.794703)
			(xy 85.209353 -58.83624) (xy 85.166485 -58.871915) (xy 85.118879 -58.900969) (xy 85.06755 -58.922781)
			(xy 85.013593 -58.936887) (xy 84.958156 -58.942987) (xy 84.902422 -58.94095) (xy 84.847579 -58.93082)
			(xy 84.794795 -58.912813) (xy 84.745195 -58.887312) (xy 84.699837 -58.854861) (xy 84.659688 -58.816152)
			(xy 84.625602 -58.772009) (xy 84.598306 -58.723374) (xy 84.578383 -58.671283) (xy 84.566257 -58.616846)
			(xy 84.562186 -58.561224) (xy 74.739421 -58.561224) (xy 74.750633 -58.600884) (xy 74.757857 -58.653018)
			(xy 74.758296 -58.679334) (xy 74.75781 -58.706585) (xy 74.750054 -58.760533) (xy 74.734699 -58.812828)
			(xy 74.712057 -58.862405) (xy 74.682591 -58.908255) (xy 74.6469 -58.949446) (xy 74.605709 -58.985137)
			(xy 74.559859 -59.014603) (xy 74.510282 -59.037245) (xy 74.457987 -59.0526) (xy 74.404039 -59.060356)
			(xy 74.349537 -59.060356) (xy 74.295589 -59.0526) (xy 74.243294 -59.037245) (xy 74.193717 -59.014603)
			(xy 74.147867 -58.985137) (xy 74.106676 -58.949446) (xy 74.070985 -58.908255) (xy 74.041519 -58.862405)
			(xy 74.018877 -58.812828) (xy 74.003522 -58.760533) (xy 73.995766 -58.706585) (xy 73.99528 -58.679334)
			(xy 64.759485 -58.679334) (xy 64.789209 -59.174634) (xy 83.09305 -59.174634) (xy 83.097121 -59.119012)
			(xy 83.109247 -59.064575) (xy 83.12917 -59.012484) (xy 83.156466 -58.963849) (xy 83.190552 -58.919706)
			(xy 83.230701 -58.880997) (xy 83.276059 -58.848546) (xy 83.325659 -58.823045) (xy 83.378443 -58.805038)
			(xy 83.433286 -58.794908) (xy 83.48902 -58.792871) (xy 83.544457 -58.798971) (xy 83.598414 -58.813077)
			(xy 83.649743 -58.834889) (xy 83.697349 -58.863943) (xy 83.740217 -58.899618) (xy 83.777434 -58.941155)
			(xy 83.808207 -58.987668) (xy 83.831879 -59.038165) (xy 83.847947 -59.091572) (xy 83.856067 -59.146748)
			(xy 83.856576 -59.174634) (xy 83.856067 -59.20252) (xy 83.847947 -59.257696) (xy 83.831879 -59.311103)
			(xy 83.808207 -59.3616) (xy 83.777434 -59.408113) (xy 83.740217 -59.44965) (xy 83.697349 -59.485325)
			(xy 83.649743 -59.514379) (xy 83.598414 -59.536191) (xy 83.544457 -59.550297) (xy 83.48902 -59.556397)
			(xy 83.433286 -59.55436) (xy 83.378443 -59.54423) (xy 83.325659 -59.526223) (xy 83.276059 -59.500722)
			(xy 83.230701 -59.468271) (xy 83.190552 -59.429562) (xy 83.156466 -59.385419) (xy 83.12917 -59.336784)
			(xy 83.109247 -59.284693) (xy 83.097121 -59.230256) (xy 83.09305 -59.174634) (xy 64.789209 -59.174634)
			(xy 64.836294 -59.95924) (xy 64.836548 -59.959748) (xy 64.836548 -59.962796) (xy 64.836802 -59.965336)
			(xy 64.836802 -59.968384) (xy 64.837056 -59.971432) (xy 64.837056 -59.97448) (xy 64.83731 -59.979814)
			(xy 64.83731 -59.983624) (xy 64.837564 -59.994546) (xy 64.837564 -59.99607) (xy 64.8371 -60.019254)
			(xy 74.135661 -60.019254) (xy 74.135661 -59.964746) (xy 74.143419 -59.910792) (xy 74.158777 -59.858492)
			(xy 74.181423 -59.808909) (xy 74.210894 -59.763055) (xy 74.246592 -59.721862) (xy 74.287789 -59.686169)
			(xy 74.333646 -59.656702) (xy 74.383231 -59.634063) (xy 74.435533 -59.61871) (xy 74.489488 -59.610958)
			(xy 74.516742 -59.610498) (xy 74.544111 -59.610999) (xy 74.598289 -59.618808) (xy 74.650791 -59.634289)
			(xy 74.700539 -59.657123) (xy 74.746507 -59.68684) (xy 74.76744 -59.704478) (xy 74.767694 -59.704732)
			(xy 74.774775 -59.710326) (xy 74.791696 -59.716567) (xy 74.800714 -59.716924) (xy 74.86777 -59.716924)
			(xy 74.876785 -59.716547) (xy 74.893702 -59.710313) (xy 74.90079 -59.704732) (xy 74.90079 -59.704478)
			(xy 74.901044 -59.704478) (xy 74.921977 -59.686837) (xy 74.967945 -59.657113) (xy 75.017691 -59.634267)
			(xy 75.070193 -59.618771) (xy 75.124371 -59.610942) (xy 75.179113 -59.610942) (xy 75.233291 -59.618771)
			(xy 75.285793 -59.634267) (xy 75.335539 -59.657113) (xy 75.381507 -59.686837) (xy 75.40244 -59.704478)
			(xy 75.402694 -59.704732) (xy 75.409775 -59.710326) (xy 75.426696 -59.716567) (xy 75.435714 -59.716924)
			(xy 75.50277 -59.716924) (xy 75.511785 -59.716547) (xy 75.528702 -59.710313) (xy 75.53579 -59.704732)
			(xy 75.53579 -59.704478) (xy 75.536044 -59.704478) (xy 75.556984 -59.686848) (xy 75.602955 -59.657136)
			(xy 75.6527 -59.634298) (xy 75.705199 -59.618805) (xy 75.759373 -59.610974) (xy 75.786742 -59.610498)
			(xy 75.813992 -59.610975) (xy 75.867936 -59.618736) (xy 75.920226 -59.634095) (xy 75.969799 -59.656739)
			(xy 76.015645 -59.686207) (xy 76.056831 -59.721899) (xy 76.092518 -59.763089) (xy 76.121981 -59.808938)
			(xy 76.14462 -59.858513) (xy 76.159973 -59.910805) (xy 76.167728 -59.96475) (xy 76.167728 -60.01925)
			(xy 76.159973 -60.073195) (xy 76.14462 -60.125487) (xy 76.121981 -60.175062) (xy 76.092518 -60.220911)
			(xy 76.056831 -60.262101) (xy 76.015645 -60.297793) (xy 75.969799 -60.327261) (xy 75.920226 -60.349905)
			(xy 75.867936 -60.365264) (xy 75.813992 -60.373025) (xy 75.786742 -60.373514) (xy 75.759373 -60.37302)
			(xy 75.705195 -60.365208) (xy 75.652692 -60.349726) (xy 75.602945 -60.32689) (xy 75.556977 -60.297172)
			(xy 75.536044 -60.279534) (xy 75.53579 -60.27928) (xy 75.528712 -60.273681) (xy 75.511789 -60.267442)
			(xy 75.50277 -60.267088) (xy 75.435714 -60.267088) (xy 75.426698 -60.267454) (xy 75.409781 -60.273696)
			(xy 75.402694 -60.27928) (xy 75.40244 -60.279534) (xy 75.381507 -60.297175) (xy 75.335539 -60.326899)
			(xy 75.285793 -60.349745) (xy 75.233291 -60.365241) (xy 75.179113 -60.37307) (xy 75.124371 -60.37307)
			(xy 75.070193 -60.365241) (xy 75.017691 -60.349745) (xy 74.967945 -60.326899) (xy 74.921977 -60.297175)
			(xy 74.901044 -60.279534) (xy 74.90079 -60.27928) (xy 74.893712 -60.273681) (xy 74.876789 -60.267442)
			(xy 74.86777 -60.267088) (xy 74.800714 -60.267088) (xy 74.791698 -60.267454) (xy 74.774781 -60.273696)
			(xy 74.767694 -60.27928) (xy 74.767694 -60.279534) (xy 74.76744 -60.279534) (xy 74.746508 -60.297173)
			(xy 74.700535 -60.326884) (xy 74.650787 -60.349719) (xy 74.598287 -60.36521) (xy 74.544111 -60.373039)
			(xy 74.516742 -60.373514) (xy 74.489488 -60.373042) (xy 74.435533 -60.36529) (xy 74.383231 -60.349937)
			(xy 74.333646 -60.327298) (xy 74.287789 -60.297831) (xy 74.246592 -60.262138) (xy 74.210894 -60.220945)
			(xy 74.181423 -60.175091) (xy 74.158777 -60.125508) (xy 74.143419 -60.073208) (xy 74.135661 -60.019254)
			(xy 64.8371 -60.019254) (xy 64.836732 -60.037616) (xy 64.824747 -60.119844) (xy 64.813688 -60.1599)
			(xy 64.703198 -60.53328) (xy 64.673671 -60.633356) (xy 85.79688 -60.633356) (xy 85.800951 -60.577734)
			(xy 85.813077 -60.523297) (xy 85.833 -60.471206) (xy 85.860296 -60.422571) (xy 85.894382 -60.378428)
			(xy 85.934531 -60.339719) (xy 85.979889 -60.307268) (xy 86.029489 -60.281767) (xy 86.082273 -60.26376)
			(xy 86.137116 -60.25363) (xy 86.19285 -60.251593) (xy 86.248287 -60.257693) (xy 86.302244 -60.271799)
			(xy 86.353573 -60.293611) (xy 86.401179 -60.322665) (xy 86.444047 -60.35834) (xy 86.481264 -60.399877)
			(xy 86.512037 -60.44639) (xy 86.535709 -60.496887) (xy 86.551777 -60.550294) (xy 86.559897 -60.60547)
			(xy 86.560406 -60.633356) (xy 86.559897 -60.661242) (xy 86.551777 -60.716418) (xy 86.535709 -60.769825)
			(xy 86.512037 -60.820322) (xy 86.481264 -60.866835) (xy 86.444047 -60.908372) (xy 86.401179 -60.944047)
			(xy 86.353573 -60.973101) (xy 86.302244 -60.994913) (xy 86.248287 -61.009019) (xy 86.19285 -61.015119)
			(xy 86.137116 -61.013082) (xy 86.082273 -61.002952) (xy 86.029489 -60.984945) (xy 85.979889 -60.959444)
			(xy 85.934531 -60.926993) (xy 85.894382 -60.888284) (xy 85.860296 -60.844141) (xy 85.833 -60.795506)
			(xy 85.813077 -60.743415) (xy 85.800951 -60.688978) (xy 85.79688 -60.633356) (xy 64.673671 -60.633356)
			(xy 64.669924 -60.646056) (xy 64.60744 -60.857384) (xy 64.586358 -60.928758) (xy 64.544956 -61.068712)
			(xy 64.541908 -61.078618) (xy 64.541908 -61.487812) (xy 84.304376 -61.487812) (xy 84.308447 -61.43219)
			(xy 84.320573 -61.377753) (xy 84.340496 -61.325662) (xy 84.367792 -61.277027) (xy 84.401878 -61.232884)
			(xy 84.442027 -61.194175) (xy 84.487385 -61.161724) (xy 84.536985 -61.136223) (xy 84.589769 -61.118216)
			(xy 84.644612 -61.108086) (xy 84.700346 -61.106049) (xy 84.755783 -61.112149) (xy 84.80974 -61.126255)
			(xy 84.861069 -61.148067) (xy 84.908675 -61.177121) (xy 84.951543 -61.212796) (xy 84.98876 -61.254333)
			(xy 85.019533 -61.300846) (xy 85.043205 -61.351343) (xy 85.059273 -61.40475) (xy 85.067393 -61.459926)
			(xy 85.067902 -61.487812) (xy 85.067393 -61.515698) (xy 85.059273 -61.570874) (xy 85.043205 -61.624281)
			(xy 85.019533 -61.674778) (xy 84.98876 -61.721291) (xy 84.951543 -61.762828) (xy 84.908675 -61.798503)
			(xy 84.861069 -61.827557) (xy 84.80974 -61.849369) (xy 84.755783 -61.863475) (xy 84.700346 -61.869575)
			(xy 84.644612 -61.867538) (xy 84.589769 -61.857408) (xy 84.536985 -61.839401) (xy 84.487385 -61.8139)
			(xy 84.442027 -61.781449) (xy 84.401878 -61.74274) (xy 84.367792 -61.698597) (xy 84.340496 -61.649962)
			(xy 84.320573 -61.597871) (xy 84.308447 -61.543434) (xy 84.304376 -61.487812) (xy 64.541908 -61.487812)
			(xy 64.541908 -62.121034) (xy 82.24215 -62.121034) (xy 82.246221 -62.065412) (xy 82.258347 -62.010975)
			(xy 82.27827 -61.958884) (xy 82.305566 -61.910249) (xy 82.339652 -61.866106) (xy 82.379801 -61.827397)
			(xy 82.425159 -61.794946) (xy 82.474759 -61.769445) (xy 82.527543 -61.751438) (xy 82.582386 -61.741308)
			(xy 82.63812 -61.739271) (xy 82.693557 -61.745371) (xy 82.747514 -61.759477) (xy 82.798843 -61.781289)
			(xy 82.846449 -61.810343) (xy 82.889317 -61.846018) (xy 82.926534 -61.887555) (xy 82.957307 -61.934068)
			(xy 82.980979 -61.984565) (xy 82.997047 -62.037972) (xy 83.005167 -62.093148) (xy 83.005676 -62.121034)
			(xy 83.005167 -62.14892) (xy 82.997047 -62.204096) (xy 82.980979 -62.257503) (xy 82.957307 -62.308)
			(xy 82.926534 -62.354513) (xy 82.889317 -62.39605) (xy 82.846449 -62.431725) (xy 82.798843 -62.460779)
			(xy 82.747514 -62.482591) (xy 82.693557 -62.496697) (xy 82.63812 -62.502797) (xy 82.582386 -62.50076)
			(xy 82.527543 -62.49063) (xy 82.474759 -62.472623) (xy 82.425159 -62.447122) (xy 82.379801 -62.414671)
			(xy 82.339652 -62.375962) (xy 82.305566 -62.331819) (xy 82.27827 -62.283184) (xy 82.258347 -62.231093)
			(xy 82.246221 -62.176656) (xy 82.24215 -62.121034) (xy 64.541908 -62.121034) (xy 64.541908 -62.678769)
			(xy 85.666072 -62.678769) (xy 85.673826 -62.624821) (xy 85.689178 -62.572525) (xy 85.711816 -62.522947)
			(xy 85.74128 -62.477095) (xy 85.776969 -62.435903) (xy 85.818156 -62.400208) (xy 85.864005 -62.370739)
			(xy 85.91358 -62.348095) (xy 85.965874 -62.332736) (xy 86.019821 -62.324976) (xy 86.047072 -62.324488)
			(xy 86.070626 -62.324873) (xy 86.117371 -62.330727) (xy 86.14029 -62.336172) (xy 86.154058 -62.339153)
			(xy 86.182203 -62.338309) (xy 86.209049 -62.329814) (xy 86.232556 -62.314311) (xy 86.250937 -62.29298)
			(xy 86.262796 -62.267441) (xy 86.267231 -62.239635) (xy 86.263907 -62.211674) (xy 86.258908 -62.198504)
			(xy 86.249595 -62.175115) (xy 86.236471 -62.126514) (xy 86.229849 -62.076609) (xy 86.229444 -62.051438)
			(xy 86.229914 -62.024181) (xy 86.237667 -61.970221) (xy 86.253021 -61.917914) (xy 86.275663 -61.868325)
			(xy 86.305132 -61.822463) (xy 86.340828 -61.781262) (xy 86.382025 -61.745561) (xy 86.427884 -61.716086)
			(xy 86.47747 -61.693438) (xy 86.529775 -61.678078) (xy 86.583734 -61.670318) (xy 86.638248 -61.670316)
			(xy 86.692207 -61.678074) (xy 86.744512 -61.693431) (xy 86.7941 -61.716077) (xy 86.83996 -61.745549)
			(xy 86.881158 -61.781249) (xy 86.916857 -61.822448) (xy 86.946328 -61.868309) (xy 86.968972 -61.917897)
			(xy 86.984329 -61.970203) (xy 86.992084 -62.024162) (xy 86.992082 -62.078676) (xy 86.98432 -62.132635)
			(xy 86.968959 -62.184939) (xy 86.946309 -62.234525) (xy 86.916833 -62.280383) (xy 86.881131 -62.321579)
			(xy 86.839929 -62.357274) (xy 86.794066 -62.386742) (xy 86.744476 -62.409382) (xy 86.692169 -62.424735)
			(xy 86.638209 -62.432486) (xy 86.610952 -62.432946) (xy 86.587397 -62.432574) (xy 86.540653 -62.426711)
			(xy 86.517734 -62.421262) (xy 86.503968 -62.418259) (xy 86.475816 -62.419096) (xy 86.448963 -62.427591)
			(xy 86.42545 -62.443095) (xy 86.407066 -62.464432) (xy 86.395208 -62.489979) (xy 86.390777 -62.517793)
			(xy 86.394111 -62.545759) (xy 86.399116 -62.55893) (xy 86.408441 -62.582314) (xy 86.42156 -62.630918)
			(xy 86.428177 -62.680824) (xy 86.42858 -62.705996) (xy 86.428127 -62.733247) (xy 86.420371 -62.787195)
			(xy 86.405016 -62.83949) (xy 86.382376 -62.889067) (xy 86.352911 -62.934918) (xy 86.31722 -62.976109)
			(xy 86.276031 -63.011801) (xy 86.230181 -63.041268) (xy 86.180605 -63.063911) (xy 86.128311 -63.079267)
			(xy 86.074363 -63.087025) (xy 86.019861 -63.087027) (xy 85.965913 -63.079272) (xy 85.913618 -63.063919)
			(xy 85.86404 -63.04128) (xy 85.818188 -63.011816) (xy 85.776997 -62.976126) (xy 85.741304 -62.934937)
			(xy 85.711835 -62.889088) (xy 85.689192 -62.839512) (xy 85.673834 -62.787218) (xy 85.666075 -62.733271)
			(xy 85.666072 -62.678769) (xy 64.541908 -62.678769) (xy 64.541908 -63.213549) (xy 74.120788 -63.213549)
			(xy 74.120788 -63.159052) (xy 74.128543 -63.105109) (xy 74.143896 -63.052819) (xy 74.166533 -63.003246)
			(xy 74.195994 -62.957399) (xy 74.23168 -62.916211) (xy 74.272864 -62.880521) (xy 74.318708 -62.851054)
			(xy 74.368278 -62.828411) (xy 74.420566 -62.813053) (xy 74.474508 -62.805291) (xy 74.501756 -62.804802)
			(xy 74.529125 -62.805293) (xy 74.583303 -62.813105) (xy 74.635806 -62.828588) (xy 74.685553 -62.851424)
			(xy 74.731521 -62.881143) (xy 74.752454 -62.898782) (xy 74.752708 -62.899036) (xy 74.759785 -62.904636)
			(xy 74.776709 -62.910874) (xy 74.785728 -62.911228) (xy 74.852784 -62.911228) (xy 74.861799 -62.910857)
			(xy 74.878716 -62.904618) (xy 74.885804 -62.899036) (xy 74.885804 -62.898782) (xy 74.886058 -62.898782)
			(xy 74.906991 -62.881141) (xy 74.952959 -62.851417) (xy 75.002705 -62.828571) (xy 75.055207 -62.813075)
			(xy 75.109385 -62.805246) (xy 75.164127 -62.805246) (xy 75.218305 -62.813075) (xy 75.270807 -62.828571)
			(xy 75.320553 -62.851417) (xy 75.366521 -62.881141) (xy 75.387454 -62.898782) (xy 75.387708 -62.899036)
			(xy 75.394785 -62.904636) (xy 75.411709 -62.910874) (xy 75.420728 -62.911228) (xy 75.487784 -62.911228)
			(xy 75.496799 -62.910857) (xy 75.513716 -62.904618) (xy 75.520804 -62.899036) (xy 75.520804 -62.898782)
			(xy 75.521058 -62.898782) (xy 75.541993 -62.881146) (xy 75.587965 -62.851435) (xy 75.637712 -62.828598)
			(xy 75.690212 -62.813106) (xy 75.744387 -62.805277) (xy 75.771756 -62.804802) (xy 75.799012 -62.805242)
			(xy 75.852969 -62.812994) (xy 75.905273 -62.828347) (xy 75.95486 -62.850987) (xy 76.00072 -62.880455)
			(xy 76.041919 -62.916149) (xy 76.077619 -62.957344) (xy 76.107092 -63.003201) (xy 76.129738 -63.052785)
			(xy 76.13956 -63.086234) (xy 79.387444 -63.086234) (xy 79.391515 -63.030612) (xy 79.403641 -62.976175)
			(xy 79.423564 -62.924084) (xy 79.45086 -62.875449) (xy 79.484946 -62.831306) (xy 79.525095 -62.792597)
			(xy 79.570453 -62.760146) (xy 79.620053 -62.734645) (xy 79.672837 -62.716638) (xy 79.72768 -62.706508)
			(xy 79.783414 -62.704471) (xy 79.838851 -62.710571) (xy 79.892808 -62.724677) (xy 79.944137 -62.746489)
			(xy 79.991743 -62.775543) (xy 80.034611 -62.811218) (xy 80.071828 -62.852755) (xy 80.102601 -62.899268)
			(xy 80.126273 -62.949765) (xy 80.142341 -63.003172) (xy 80.150461 -63.058348) (xy 80.15097 -63.086234)
			(xy 80.150461 -63.11412) (xy 80.142341 -63.169296) (xy 80.126273 -63.222703) (xy 80.102601 -63.2732)
			(xy 80.102448 -63.273432) (xy 81.57667 -63.273432) (xy 81.580741 -63.21781) (xy 81.592867 -63.163373)
			(xy 81.61279 -63.111282) (xy 81.640086 -63.062647) (xy 81.674172 -63.018504) (xy 81.714321 -62.979795)
			(xy 81.759679 -62.947344) (xy 81.809279 -62.921843) (xy 81.862063 -62.903836) (xy 81.916906 -62.893706)
			(xy 81.97264 -62.891669) (xy 82.028077 -62.897769) (xy 82.082034 -62.911875) (xy 82.133363 -62.933687)
			(xy 82.180969 -62.962741) (xy 82.223837 -62.998416) (xy 82.261054 -63.039953) (xy 82.291827 -63.086466)
			(xy 82.315499 -63.136963) (xy 82.331567 -63.19037) (xy 82.339687 -63.245546) (xy 82.340196 -63.273432)
			(xy 82.339687 -63.301318) (xy 82.331567 -63.356494) (xy 82.315499 -63.409901) (xy 82.291827 -63.460398)
			(xy 82.261054 -63.506911) (xy 82.223837 -63.548448) (xy 82.180969 -63.584123) (xy 82.133363 -63.613177)
			(xy 82.082034 -63.634989) (xy 82.028077 -63.649095) (xy 81.97264 -63.655195) (xy 81.916906 -63.653158)
			(xy 81.862063 -63.643028) (xy 81.809279 -63.625021) (xy 81.759679 -63.59952) (xy 81.714321 -63.567069)
			(xy 81.674172 -63.52836) (xy 81.640086 -63.484217) (xy 81.61279 -63.435582) (xy 81.592867 -63.383491)
			(xy 81.580741 -63.329054) (xy 81.57667 -63.273432) (xy 80.102448 -63.273432) (xy 80.071828 -63.319713)
			(xy 80.034611 -63.36125) (xy 79.991743 -63.396925) (xy 79.944137 -63.425979) (xy 79.892808 -63.447791)
			(xy 79.838851 -63.461897) (xy 79.783414 -63.467997) (xy 79.72768 -63.46596) (xy 79.672837 -63.45583)
			(xy 79.620053 -63.437823) (xy 79.570453 -63.412322) (xy 79.525095 -63.379871) (xy 79.484946 -63.341162)
			(xy 79.45086 -63.297019) (xy 79.423564 -63.248384) (xy 79.403641 -63.196293) (xy 79.391515 -63.141856)
			(xy 79.387444 -63.086234) (xy 76.13956 -63.086234) (xy 76.145097 -63.105088) (xy 76.152855 -63.159044)
			(xy 76.152855 -63.213556) (xy 76.145097 -63.267512) (xy 76.129738 -63.319815) (xy 76.107092 -63.369399)
			(xy 76.077619 -63.415256) (xy 76.041919 -63.456451) (xy 76.00072 -63.492145) (xy 75.95486 -63.521613)
			(xy 75.905273 -63.544253) (xy 75.852969 -63.559606) (xy 75.799012 -63.567358) (xy 75.771756 -63.567818)
			(xy 75.744386 -63.567339) (xy 75.690207 -63.559527) (xy 75.637703 -63.544042) (xy 75.587956 -63.521203)
			(xy 75.541989 -63.491479) (xy 75.521058 -63.473838) (xy 75.520804 -63.473584) (xy 75.513722 -63.467991)
			(xy 75.496802 -63.461749) (xy 75.487784 -63.461392) (xy 75.420728 -63.461392) (xy 75.411713 -63.461764)
			(xy 75.394796 -63.468001) (xy 75.387708 -63.473584) (xy 75.387454 -63.473838) (xy 75.366521 -63.491479)
			(xy 75.320553 -63.521203) (xy 75.270807 -63.544049) (xy 75.218305 -63.559545) (xy 75.164127 -63.567374)
			(xy 75.109385 -63.567374) (xy 75.055207 -63.559545) (xy 75.002705 -63.544049) (xy 74.952959 -63.521203)
			(xy 74.906991 -63.491479) (xy 74.886058 -63.473838) (xy 74.885804 -63.473584) (xy 74.878722 -63.467991)
			(xy 74.861802 -63.461749) (xy 74.852784 -63.461392) (xy 74.785728 -63.461392) (xy 74.776713 -63.461764)
			(xy 74.759796 -63.468001) (xy 74.752708 -63.473584) (xy 74.752708 -63.473838) (xy 74.752454 -63.473838)
			(xy 74.731518 -63.491472) (xy 74.685545 -63.521183) (xy 74.635799 -63.54402) (xy 74.583299 -63.559512)
			(xy 74.529125 -63.567343) (xy 74.501756 -63.567818) (xy 74.474508 -63.567309) (xy 74.420566 -63.559547)
			(xy 74.368278 -63.544189) (xy 74.318708 -63.521546) (xy 74.272864 -63.492079) (xy 74.23168 -63.456389)
			(xy 74.195994 -63.415201) (xy 74.166533 -63.369354) (xy 74.143896 -63.319781) (xy 74.128543 -63.267491)
			(xy 74.120788 -63.213549) (xy 64.541908 -63.213549) (xy 64.541908 -65.100962) (xy 72.132442 -65.100962)
			(xy 72.136513 -65.04534) (xy 72.148639 -64.990903) (xy 72.168562 -64.938812) (xy 72.195858 -64.890177)
			(xy 72.229944 -64.846034) (xy 72.270093 -64.807325) (xy 72.315451 -64.774874) (xy 72.365051 -64.749373)
			(xy 72.417835 -64.731366) (xy 72.472678 -64.721236) (xy 72.528412 -64.719199) (xy 72.583849 -64.725299)
			(xy 72.637806 -64.739405) (xy 72.689135 -64.761217) (xy 72.736741 -64.790271) (xy 72.779609 -64.825946)
			(xy 72.816826 -64.867483) (xy 72.847599 -64.913996) (xy 72.871271 -64.964493) (xy 72.887339 -65.0179)
			(xy 72.895459 -65.073076) (xy 72.895968 -65.100962) (xy 72.895546 -65.124076) (xy 84.107272 -65.124076)
			(xy 84.111343 -65.068454) (xy 84.123469 -65.014017) (xy 84.143392 -64.961926) (xy 84.170688 -64.913291)
			(xy 84.204774 -64.869148) (xy 84.244923 -64.830439) (xy 84.290281 -64.797988) (xy 84.339881 -64.772487)
			(xy 84.392665 -64.75448) (xy 84.447508 -64.74435) (xy 84.503242 -64.742313) (xy 84.558679 -64.748413)
			(xy 84.612636 -64.762519) (xy 84.663965 -64.784331) (xy 84.711571 -64.813385) (xy 84.754439 -64.84906)
			(xy 84.791656 -64.890597) (xy 84.822429 -64.93711) (xy 84.846101 -64.987607) (xy 84.862169 -65.041014)
			(xy 84.870289 -65.09619) (xy 84.870798 -65.124076) (xy 84.870289 -65.151962) (xy 84.862169 -65.207138)
			(xy 84.846101 -65.260545) (xy 84.822429 -65.311042) (xy 84.791656 -65.357555) (xy 84.754439 -65.399092)
			(xy 84.711571 -65.434767) (xy 84.663965 -65.463821) (xy 84.612636 -65.485633) (xy 84.558679 -65.499739)
			(xy 84.503242 -65.505839) (xy 84.447508 -65.503802) (xy 84.392665 -65.493672) (xy 84.339881 -65.475665)
			(xy 84.290281 -65.450164) (xy 84.244923 -65.417713) (xy 84.204774 -65.379004) (xy 84.170688 -65.334861)
			(xy 84.143392 -65.286226) (xy 84.123469 -65.234135) (xy 84.111343 -65.179698) (xy 84.107272 -65.124076)
			(xy 72.895546 -65.124076) (xy 72.895459 -65.128848) (xy 72.887339 -65.184024) (xy 72.871271 -65.237431)
			(xy 72.847599 -65.287928) (xy 72.816826 -65.334441) (xy 72.779609 -65.375978) (xy 72.736741 -65.411653)
			(xy 72.689135 -65.440707) (xy 72.637806 -65.462519) (xy 72.583849 -65.476625) (xy 72.528412 -65.482725)
			(xy 72.472678 -65.480688) (xy 72.417835 -65.470558) (xy 72.365051 -65.452551) (xy 72.315451 -65.42705)
			(xy 72.270093 -65.394599) (xy 72.229944 -65.35589) (xy 72.195858 -65.311747) (xy 72.168562 -65.263112)
			(xy 72.148639 -65.211021) (xy 72.136513 -65.156584) (xy 72.132442 -65.100962) (xy 64.541908 -65.100962)
			(xy 64.541908 -65.75552) (xy 66.346576 -65.75552) (xy 66.350647 -65.699898) (xy 66.362773 -65.645461)
			(xy 66.382696 -65.59337) (xy 66.409992 -65.544735) (xy 66.444078 -65.500592) (xy 66.484227 -65.461883)
			(xy 66.529585 -65.429432) (xy 66.579185 -65.403931) (xy 66.631969 -65.385924) (xy 66.686812 -65.375794)
			(xy 66.742546 -65.373757) (xy 66.797983 -65.379857) (xy 66.85194 -65.393963) (xy 66.903269 -65.415775)
			(xy 66.950875 -65.444829) (xy 66.993743 -65.480504) (xy 67.03096 -65.522041) (xy 67.061733 -65.568554)
			(xy 67.085405 -65.619051) (xy 67.101473 -65.672458) (xy 67.109593 -65.727634) (xy 67.110102 -65.75552)
			(xy 67.109593 -65.783406) (xy 67.101473 -65.838582) (xy 67.085405 -65.891989) (xy 67.061733 -65.942486)
			(xy 67.03096 -65.988999) (xy 66.993743 -66.030536) (xy 66.950875 -66.066211) (xy 66.903269 -66.095265)
			(xy 66.85194 -66.117077) (xy 66.797983 -66.131183) (xy 66.742546 -66.137283) (xy 66.686812 -66.135246)
			(xy 66.631969 -66.125116) (xy 66.579185 -66.107109) (xy 66.529585 -66.081608) (xy 66.484227 -66.049157)
			(xy 66.444078 -66.010448) (xy 66.409992 -65.966305) (xy 66.382696 -65.91767) (xy 66.362773 -65.865579)
			(xy 66.350647 -65.811142) (xy 66.346576 -65.75552) (xy 64.541908 -65.75552) (xy 64.541908 -67.128953)
			(xy 66.366575 -67.128953) (xy 66.366575 -67.074447) (xy 66.374333 -67.020495) (xy 66.389691 -66.968196)
			(xy 66.412335 -66.918616) (xy 66.441806 -66.872763) (xy 66.477502 -66.831571) (xy 66.518698 -66.795879)
			(xy 66.564554 -66.766414) (xy 66.614137 -66.743775) (xy 66.666438 -66.728424) (xy 66.720391 -66.720672)
			(xy 66.747644 -66.720212) (xy 66.775013 -66.720708) (xy 66.829191 -66.728518) (xy 66.881694 -66.744)
			(xy 66.931441 -66.766835) (xy 66.977409 -66.796554) (xy 66.998342 -66.814192) (xy 66.998596 -66.814446)
			(xy 67.005676 -66.820043) (xy 67.022598 -66.826282) (xy 67.031616 -66.826638) (xy 67.098672 -66.826638)
			(xy 67.107686 -66.826259) (xy 67.124603 -66.820026) (xy 67.131692 -66.814446) (xy 67.131692 -66.814192)
			(xy 67.131946 -66.814192) (xy 67.152887 -66.796564) (xy 67.198857 -66.76685) (xy 67.248603 -66.744013)
			(xy 67.301101 -66.728519) (xy 67.355275 -66.720688) (xy 67.382644 -66.720212) (xy 67.409895 -66.720661)
			(xy 67.46384 -66.728423) (xy 67.516133 -66.743783) (xy 67.565707 -66.766427) (xy 67.611554 -66.795896)
			(xy 67.652741 -66.83159) (xy 67.68843 -66.872781) (xy 67.717894 -66.918632) (xy 67.740533 -66.968209)
			(xy 67.755887 -67.020503) (xy 67.763642 -67.074449) (xy 67.763642 -67.128951) (xy 67.755887 -67.182897)
			(xy 67.740533 -67.235191) (xy 67.717894 -67.284768) (xy 67.68843 -67.330619) (xy 67.652741 -67.37181)
			(xy 67.611554 -67.407504) (xy 67.565707 -67.436973) (xy 67.516133 -67.459617) (xy 67.46384 -67.474977)
			(xy 67.409895 -67.482739) (xy 67.382644 -67.483228) (xy 67.355274 -67.482754) (xy 67.301094 -67.474941)
			(xy 67.248591 -67.459454) (xy 67.198844 -67.436614) (xy 67.152877 -67.40689) (xy 67.131946 -67.389248)
			(xy 67.131692 -67.388994) (xy 67.124612 -67.383397) (xy 67.10769 -67.377157) (xy 67.098672 -67.376802)
			(xy 67.031616 -67.376802) (xy 67.0226 -67.377166) (xy 67.005683 -67.383409) (xy 66.998596 -67.388994)
			(xy 66.998596 -67.389248) (xy 66.998342 -67.389248) (xy 66.977398 -67.406873) (xy 66.931429 -67.436589)
			(xy 66.881685 -67.459428) (xy 66.829187 -67.474922) (xy 66.775013 -67.482753) (xy 66.747644 -67.483228)
			(xy 66.720391 -67.482728) (xy 66.666438 -67.474976) (xy 66.614137 -67.459625) (xy 66.564554 -67.436986)
			(xy 66.518698 -67.407521) (xy 66.477502 -67.371829) (xy 66.441806 -67.330637) (xy 66.412335 -67.284784)
			(xy 66.389691 -67.235204) (xy 66.374333 -67.182905) (xy 66.366575 -67.128953) (xy 64.541908 -67.128953)
			(xy 64.541908 -67.488054) (xy 70.77913 -67.488054) (xy 70.783201 -67.432432) (xy 70.795327 -67.377995)
			(xy 70.81525 -67.325904) (xy 70.842546 -67.277269) (xy 70.876632 -67.233126) (xy 70.916781 -67.194417)
			(xy 70.962139 -67.161966) (xy 71.011739 -67.136465) (xy 71.064523 -67.118458) (xy 71.119366 -67.108328)
			(xy 71.1751 -67.106291) (xy 71.230537 -67.112391) (xy 71.284494 -67.126497) (xy 71.335823 -67.148309)
			(xy 71.383429 -67.177363) (xy 71.426297 -67.213038) (xy 71.463514 -67.254575) (xy 71.494287 -67.301088)
			(xy 71.517959 -67.351585) (xy 71.534027 -67.404992) (xy 71.542147 -67.460168) (xy 71.542656 -67.488054)
			(xy 71.542147 -67.51594) (xy 71.538962 -67.537584) (xy 72.071228 -67.537584) (xy 72.075299 -67.481962)
			(xy 72.087425 -67.427525) (xy 72.107348 -67.375434) (xy 72.134644 -67.326799) (xy 72.16873 -67.282656)
			(xy 72.208879 -67.243947) (xy 72.254237 -67.211496) (xy 72.303837 -67.185995) (xy 72.356621 -67.167988)
			(xy 72.411464 -67.157858) (xy 72.467198 -67.155821) (xy 72.522635 -67.161921) (xy 72.576592 -67.176027)
			(xy 72.627921 -67.197839) (xy 72.675527 -67.226893) (xy 72.718395 -67.262568) (xy 72.755612 -67.304105)
			(xy 72.786385 -67.350618) (xy 72.810057 -67.401115) (xy 72.826125 -67.454522) (xy 72.834245 -67.509698)
			(xy 72.834754 -67.537584) (xy 72.834245 -67.56547) (xy 72.8302 -67.592956) (xy 73.345292 -67.592956)
			(xy 73.349363 -67.537334) (xy 73.361489 -67.482897) (xy 73.381412 -67.430806) (xy 73.408708 -67.382171)
			(xy 73.442794 -67.338028) (xy 73.482943 -67.299319) (xy 73.528301 -67.266868) (xy 73.577901 -67.241367)
			(xy 73.630685 -67.22336) (xy 73.685528 -67.21323) (xy 73.741262 -67.211193) (xy 73.796699 -67.217293)
			(xy 73.850656 -67.231399) (xy 73.901985 -67.253211) (xy 73.949591 -67.282265) (xy 73.992459 -67.31794)
			(xy 74.029676 -67.359477) (xy 74.060449 -67.40599) (xy 74.084121 -67.456487) (xy 74.100189 -67.509894)
			(xy 74.108306 -67.565052) (xy 76.446593 -67.565052) (xy 76.446593 -67.510548) (xy 76.45435 -67.4566)
			(xy 76.469707 -67.404304) (xy 76.492349 -67.354727) (xy 76.521818 -67.308877) (xy 76.557511 -67.267687)
			(xy 76.598704 -67.231997) (xy 76.644557 -67.202533) (xy 76.694136 -67.179895) (xy 76.746433 -67.164543)
			(xy 76.800382 -67.156791) (xy 76.827634 -67.15633) (xy 76.855005 -67.156769) (xy 76.909186 -67.164592)
			(xy 76.96169 -67.180087) (xy 77.011436 -67.202935) (xy 77.057401 -67.232666) (xy 77.078332 -67.25031)
			(xy 77.078586 -67.250564) (xy 77.085667 -67.256158) (xy 77.102588 -67.262399) (xy 77.111606 -67.262756)
			(xy 77.178662 -67.262756) (xy 77.187678 -67.26239) (xy 77.204596 -67.25615) (xy 77.211682 -67.250564)
			(xy 77.211682 -67.25031) (xy 77.211936 -67.25031) (xy 77.232883 -67.232689) (xy 77.278851 -67.202974)
			(xy 77.328595 -67.180135) (xy 77.381093 -67.164639) (xy 77.435266 -67.156806) (xy 77.462634 -67.15633)
			(xy 77.489886 -67.156742) (xy 77.543836 -67.164503) (xy 77.596132 -67.179863) (xy 77.64571 -67.202508)
			(xy 77.69156 -67.231978) (xy 77.732751 -67.267674) (xy 77.768442 -67.308867) (xy 77.797908 -67.35472)
			(xy 77.820549 -67.4043) (xy 77.835904 -67.456597) (xy 77.84366 -67.510548) (xy 77.84366 -67.565052)
			(xy 77.835904 -67.619003) (xy 77.820549 -67.6713) (xy 77.797908 -67.72088) (xy 77.768442 -67.766733)
			(xy 77.732751 -67.807926) (xy 77.69156 -67.843622) (xy 77.64571 -67.873092) (xy 77.596132 -67.895737)
			(xy 77.543836 -67.911097) (xy 77.489886 -67.918858) (xy 77.462634 -67.919346) (xy 77.435264 -67.918873)
			(xy 77.381085 -67.911059) (xy 77.328581 -67.895572) (xy 77.278834 -67.872732) (xy 77.232867 -67.843007)
			(xy 77.211936 -67.825366) (xy 77.211682 -67.825112) (xy 77.204604 -67.819513) (xy 77.187681 -67.813273)
			(xy 77.178662 -67.81292) (xy 77.111606 -67.81292) (xy 77.102589 -67.813275) (xy 77.085672 -67.819524)
			(xy 77.078586 -67.825112) (xy 77.078586 -67.825366) (xy 77.078332 -67.825366) (xy 77.057394 -67.842998)
			(xy 77.011424 -67.872712) (xy 76.961678 -67.89555) (xy 76.909178 -67.911043) (xy 76.855003 -67.918872)
			(xy 76.827634 -67.919346) (xy 76.800382 -67.918809) (xy 76.746433 -67.911057) (xy 76.694136 -67.895705)
			(xy 76.644557 -67.873067) (xy 76.598704 -67.843603) (xy 76.557511 -67.807913) (xy 76.521818 -67.766723)
			(xy 76.492349 -67.720873) (xy 76.469707 -67.671296) (xy 76.45435 -67.619) (xy 76.446593 -67.565052)
			(xy 74.108306 -67.565052) (xy 74.108309 -67.56507) (xy 74.108818 -67.592956) (xy 74.108309 -67.620842)
			(xy 74.100189 -67.676018) (xy 74.084121 -67.729425) (xy 74.060449 -67.779922) (xy 74.029676 -67.826435)
			(xy 73.992459 -67.867972) (xy 73.949591 -67.903647) (xy 73.901985 -67.932701) (xy 73.850656 -67.954513)
			(xy 73.796699 -67.968619) (xy 73.741262 -67.974719) (xy 73.685528 -67.972682) (xy 73.630685 -67.962552)
			(xy 73.577901 -67.944545) (xy 73.528301 -67.919044) (xy 73.482943 -67.886593) (xy 73.442794 -67.847884)
			(xy 73.408708 -67.803741) (xy 73.381412 -67.755106) (xy 73.361489 -67.703015) (xy 73.349363 -67.648578)
			(xy 73.345292 -67.592956) (xy 72.8302 -67.592956) (xy 72.826125 -67.620646) (xy 72.810057 -67.674053)
			(xy 72.786385 -67.72455) (xy 72.755612 -67.771063) (xy 72.718395 -67.8126) (xy 72.675527 -67.848275)
			(xy 72.627921 -67.877329) (xy 72.576592 -67.899141) (xy 72.522635 -67.913247) (xy 72.467198 -67.919347)
			(xy 72.411464 -67.91731) (xy 72.356621 -67.90718) (xy 72.303837 -67.889173) (xy 72.254237 -67.863672)
			(xy 72.208879 -67.831221) (xy 72.16873 -67.792512) (xy 72.134644 -67.748369) (xy 72.107348 -67.699734)
			(xy 72.087425 -67.647643) (xy 72.075299 -67.593206) (xy 72.071228 -67.537584) (xy 71.538962 -67.537584)
			(xy 71.534027 -67.571116) (xy 71.517959 -67.624523) (xy 71.494287 -67.67502) (xy 71.463514 -67.721533)
			(xy 71.426297 -67.76307) (xy 71.383429 -67.798745) (xy 71.335823 -67.827799) (xy 71.284494 -67.849611)
			(xy 71.230537 -67.863717) (xy 71.1751 -67.869817) (xy 71.119366 -67.86778) (xy 71.064523 -67.85765)
			(xy 71.011739 -67.839643) (xy 70.962139 -67.814142) (xy 70.916781 -67.781691) (xy 70.876632 -67.742982)
			(xy 70.842546 -67.698839) (xy 70.81525 -67.650204) (xy 70.795327 -67.598113) (xy 70.783201 -67.543676)
			(xy 70.77913 -67.488054) (xy 64.541908 -67.488054) (xy 64.541908 -68.586604) (xy 68.625212 -68.586604)
			(xy 68.625677 -68.559234) (xy 68.633495 -68.505054) (xy 68.648984 -68.452551) (xy 68.671826 -68.402804)
			(xy 68.701551 -68.356838) (xy 68.719192 -68.335906) (xy 68.719446 -68.335652) (xy 68.725023 -68.328559)
			(xy 68.731274 -68.311647) (xy 68.731638 -68.302632) (xy 68.731638 -68.235576) (xy 68.731284 -68.226559)
			(xy 68.725034 -68.209642) (xy 68.719446 -68.202556) (xy 68.719192 -68.202556) (xy 68.719192 -68.202302)
			(xy 68.701539 -68.181381) (xy 68.67183 -68.135405) (xy 68.648996 -68.085655) (xy 68.633509 -68.033152)
			(xy 68.625684 -67.978974) (xy 68.625212 -67.951604) (xy 68.625659 -67.92435) (xy 68.633416 -67.870398)
			(xy 68.648773 -67.818098) (xy 68.671416 -67.768517) (xy 68.700886 -67.722663) (xy 68.736581 -67.68147)
			(xy 68.777776 -67.645776) (xy 68.823631 -67.616308) (xy 68.873213 -67.593667) (xy 68.925513 -67.578313)
			(xy 68.979466 -67.570558) (xy 69.00672 -67.570096) (xy 69.033034 -67.570551) (xy 69.085163 -67.577789)
			(xy 69.135806 -67.59211) (xy 69.184005 -67.613245) (xy 69.228848 -67.640793) (xy 69.269488 -67.674234)
			(xy 69.287644 -67.693286) (xy 69.295149 -67.700707) (xy 69.314442 -67.709221) (xy 69.324982 -67.709796)
			(xy 69.399658 -67.709796) (xy 69.410207 -67.709259) (xy 69.429502 -67.70073) (xy 69.436996 -67.693286)
			(xy 69.455158 -67.674237) (xy 69.495786 -67.64078) (xy 69.540626 -67.61322) (xy 69.588825 -67.592081)
			(xy 69.639471 -67.577762) (xy 69.691604 -67.570535) (xy 69.71792 -67.570096) (xy 69.745291 -67.570551)
			(xy 69.79947 -67.578372) (xy 69.851973 -67.593864) (xy 69.90172 -67.616708) (xy 69.947686 -67.646434)
			(xy 69.968618 -67.664076) (xy 69.968872 -67.66433) (xy 69.97596 -67.669914) (xy 69.992876 -67.676161)
			(xy 70.001892 -67.676522) (xy 70.068948 -67.676522) (xy 70.077962 -67.676135) (xy 70.094879 -67.669908)
			(xy 70.101968 -67.66433) (xy 70.101968 -67.664076) (xy 70.102222 -67.664076) (xy 70.12317 -67.646456)
			(xy 70.169139 -67.616742) (xy 70.218882 -67.593903) (xy 70.271379 -67.578407) (xy 70.325552 -67.570573)
			(xy 70.35292 -67.570096) (xy 70.380172 -67.570559) (xy 70.434121 -67.578319) (xy 70.486416 -67.593676)
			(xy 70.535994 -67.61632) (xy 70.581844 -67.645789) (xy 70.623034 -67.681483) (xy 70.658725 -67.722675)
			(xy 70.688191 -67.768527) (xy 70.710832 -67.818106) (xy 70.726187 -67.870403) (xy 70.733943 -67.924352)
			(xy 70.734428 -67.951604) (xy 70.733982 -67.978975) (xy 70.726162 -68.033156) (xy 70.710669 -68.08566)
			(xy 70.687823 -68.135406) (xy 70.658092 -68.181372) (xy 70.640448 -68.202302) (xy 70.640194 -68.202556)
			(xy 70.634619 -68.209651) (xy 70.628366 -68.226561) (xy 70.628002 -68.235576) (xy 70.628002 -68.302632)
			(xy 70.628343 -68.31165) (xy 70.634602 -68.328567) (xy 70.640194 -68.335652) (xy 70.640448 -68.335652)
			(xy 70.640448 -68.335906) (xy 70.658095 -68.356832) (xy 70.687808 -68.402805) (xy 70.710643 -68.452554)
			(xy 70.726132 -68.505057) (xy 70.733956 -68.559234) (xy 70.734428 -68.586604) (xy 70.733926 -68.613854)
			(xy 70.726169 -68.667801) (xy 70.710815 -68.720094) (xy 70.694176 -68.75653) (xy 74.170286 -68.75653)
			(xy 74.170773 -68.729161) (xy 74.178586 -68.674983) (xy 74.194071 -68.62248) (xy 74.216908 -68.572733)
			(xy 74.246627 -68.526765) (xy 74.264266 -68.505832) (xy 74.26452 -68.505578) (xy 74.270124 -68.498504)
			(xy 74.27636 -68.481577) (xy 74.276712 -68.472558) (xy 74.276712 -68.405502) (xy 74.276351 -68.396486)
			(xy 74.270106 -68.379569) (xy 74.26452 -68.372482) (xy 74.264266 -68.372482) (xy 74.264266 -68.372228)
			(xy 74.246621 -68.351301) (xy 74.216911 -68.305326) (xy 74.194077 -68.255577) (xy 74.178587 -68.203076)
			(xy 74.17076 -68.148899) (xy 74.170286 -68.12153) (xy 74.170783 -68.094278) (xy 74.178536 -68.040329)
			(xy 74.193888 -67.988032) (xy 74.216526 -67.938452) (xy 74.245991 -67.892599) (xy 74.281681 -67.851406)
			(xy 74.32287 -67.815712) (xy 74.368721 -67.786244) (xy 74.418298 -67.7636) (xy 74.470594 -67.748244)
			(xy 74.524542 -67.740486) (xy 74.551794 -67.740022) (xy 74.579164 -67.740486) (xy 74.633344 -67.748304)
			(xy 74.685847 -67.763793) (xy 74.735594 -67.786635) (xy 74.781561 -67.81636) (xy 74.802492 -67.834002)
			(xy 74.802746 -67.834256) (xy 74.809839 -67.839833) (xy 74.826751 -67.846084) (xy 74.835766 -67.846448)
			(xy 74.902822 -67.846448) (xy 74.911841 -67.846113) (xy 74.928759 -67.839852) (xy 74.935842 -67.834256)
			(xy 74.935842 -67.834002) (xy 74.936096 -67.834002) (xy 74.957019 -67.816352) (xy 75.002994 -67.786641)
			(xy 75.052744 -67.763808) (xy 75.105247 -67.748319) (xy 75.159424 -67.740494) (xy 75.186794 -67.740022)
			(xy 75.213108 -67.740486) (xy 75.265237 -67.747721) (xy 75.31588 -67.76204) (xy 75.364079 -67.783173)
			(xy 75.408923 -67.81072) (xy 75.449562 -67.84416) (xy 75.467718 -67.863212) (xy 75.475229 -67.870625)
			(xy 75.494517 -67.879143) (xy 75.505056 -67.879722) (xy 75.579732 -67.879722) (xy 75.590278 -67.879163)
			(xy 75.609573 -67.870648) (xy 75.61707 -67.863212) (xy 75.63525 -67.84418) (xy 75.675874 -67.810721)
			(xy 75.720709 -67.783158) (xy 75.768905 -67.762015) (xy 75.819549 -67.747693) (xy 75.871679 -67.740463)
			(xy 75.897994 -67.740022) (xy 75.925248 -67.740461) (xy 75.979201 -67.748218) (xy 76.031502 -67.763575)
			(xy 76.081084 -67.786219) (xy 76.126938 -67.815689) (xy 76.168132 -67.851385) (xy 76.203826 -67.892581)
			(xy 76.233293 -67.938437) (xy 76.255934 -67.988021) (xy 76.271287 -68.040322) (xy 76.279041 -68.094276)
			(xy 76.279502 -68.12153) (xy 76.279053 -68.148901) (xy 76.271231 -68.203081) (xy 76.255738 -68.255584)
			(xy 76.232892 -68.30533) (xy 76.203165 -68.351297) (xy 76.185522 -68.372228) (xy 76.185268 -68.372482)
			(xy 76.179679 -68.379567) (xy 76.173435 -68.396485) (xy 76.173076 -68.405502) (xy 76.173076 -68.472558)
			(xy 76.173458 -68.481572) (xy 76.179689 -68.498489) (xy 76.185268 -68.505578) (xy 76.185522 -68.505578)
			(xy 76.185522 -68.505832) (xy 76.203146 -68.526776) (xy 76.232859 -68.572746) (xy 76.255698 -68.62249)
			(xy 76.271193 -68.674988) (xy 76.279025 -68.729162) (xy 76.279502 -68.75653) (xy 76.27905 -68.783782)
			(xy 76.271289 -68.837732) (xy 76.25593 -68.890027) (xy 76.233285 -68.939605) (xy 76.203815 -68.985456)
			(xy 76.16812 -69.026646) (xy 76.126927 -69.062337) (xy 76.081073 -69.091802) (xy 76.031493 -69.114443)
			(xy 75.979196 -69.129797) (xy 75.925246 -69.137553) (xy 75.897994 -69.138038) (xy 75.871679 -69.137594)
			(xy 75.819549 -69.130357) (xy 75.768905 -69.116035) (xy 75.720705 -69.094898) (xy 75.675863 -69.067347)
			(xy 75.635225 -69.033903) (xy 75.61707 -69.014848) (xy 75.609555 -69.007438) (xy 75.59027 -68.998917)
			(xy 75.579732 -68.998338) (xy 75.505056 -68.998338) (xy 75.494507 -68.998873) (xy 75.475211 -69.007403)
			(xy 75.467718 -69.014848) (xy 75.449556 -69.033897) (xy 75.408927 -69.067353) (xy 75.364087 -69.094912)
			(xy 75.315888 -69.116051) (xy 75.265242 -69.13037) (xy 75.21311 -69.137598) (xy 75.186794 -69.138038)
			(xy 75.159423 -69.137591) (xy 75.105242 -69.129771) (xy 75.052739 -69.114278) (xy 75.002992 -69.091432)
			(xy 74.957026 -69.061702) (xy 74.936096 -69.044058) (xy 74.935842 -69.043804) (xy 74.928747 -69.038229)
			(xy 74.911837 -69.031975) (xy 74.902822 -69.031612) (xy 74.835766 -69.031612) (xy 74.826747 -69.03195)
			(xy 74.80983 -69.038211) (xy 74.802746 -69.043804) (xy 74.802746 -69.044058) (xy 74.802492 -69.044058)
			(xy 74.781568 -69.061708) (xy 74.735594 -69.091419) (xy 74.685844 -69.114254) (xy 74.633342 -69.129742)
			(xy 74.579164 -69.137567) (xy 74.551794 -69.138038) (xy 74.524544 -69.137528) (xy 74.470599 -69.129771)
			(xy 74.418306 -69.114417) (xy 74.368731 -69.091777) (xy 74.322882 -69.062313) (xy 74.281693 -69.026624)
			(xy 74.246001 -68.985437) (xy 74.216534 -68.93959) (xy 74.193891 -68.890016) (xy 74.178534 -68.837725)
			(xy 74.170774 -68.78378) (xy 74.170286 -68.75653) (xy 70.694176 -68.75653) (xy 70.688175 -68.76967)
			(xy 70.65871 -68.815519) (xy 70.62302 -68.856709) (xy 70.581832 -68.8924) (xy 70.535984 -68.921867)
			(xy 70.486409 -68.944509) (xy 70.434116 -68.959866) (xy 70.38017 -68.967625) (xy 70.35292 -68.968112)
			(xy 70.32555 -68.967631) (xy 70.271372 -68.959817) (xy 70.218869 -68.944331) (xy 70.169122 -68.921492)
			(xy 70.123154 -68.891771) (xy 70.102222 -68.874132) (xy 70.101968 -68.873878) (xy 70.094868 -68.868311)
			(xy 70.077961 -68.862053) (xy 70.068948 -68.861686) (xy 70.001892 -68.861686) (xy 69.992875 -68.862042)
			(xy 69.975958 -68.868291) (xy 69.968872 -68.873878) (xy 69.968872 -68.874132) (xy 69.968618 -68.874132)
			(xy 69.947694 -68.891781) (xy 69.901719 -68.92149) (xy 69.851969 -68.944324) (xy 69.799467 -68.959813)
			(xy 69.74529 -68.967639) (xy 69.71792 -68.968112) (xy 69.691607 -68.967627) (xy 69.639479 -68.960396)
			(xy 69.588837 -68.94608) (xy 69.540638 -68.92495) (xy 69.495794 -68.897407) (xy 69.455153 -68.863972)
			(xy 69.436996 -68.844922) (xy 69.429475 -68.83752) (xy 69.410195 -68.828995) (xy 69.399658 -68.828412)
			(xy 69.324982 -68.828412) (xy 69.314435 -68.828968) (xy 69.295139 -68.837484) (xy 69.287644 -68.844922)
			(xy 69.269513 -68.864002) (xy 69.228878 -68.897456) (xy 69.184032 -68.925011) (xy 69.135826 -68.946145)
			(xy 69.085175 -68.960458) (xy 69.033037 -68.967677) (xy 69.00672 -68.968112) (xy 68.979468 -68.967626)
			(xy 68.925518 -68.959872) (xy 68.873221 -68.944519) (xy 68.823641 -68.921879) (xy 68.777788 -68.892413)
			(xy 68.736595 -68.856722) (xy 68.700901 -68.815531) (xy 68.671433 -68.76968) (xy 68.64879 -68.720102)
			(xy 68.633433 -68.667806) (xy 68.625676 -68.613856) (xy 68.625212 -68.586604) (xy 64.541908 -68.586604)
			(xy 64.541908 -71.555864) (xy 71.19442 -71.555864) (xy 71.198491 -71.500242) (xy 71.210617 -71.445805)
			(xy 71.23054 -71.393714) (xy 71.257836 -71.345079) (xy 71.291922 -71.300936) (xy 71.332071 -71.262227)
			(xy 71.377429 -71.229776) (xy 71.427029 -71.204275) (xy 71.479813 -71.186268) (xy 71.534656 -71.176138)
			(xy 71.59039 -71.174101) (xy 71.645827 -71.180201) (xy 71.699784 -71.194307) (xy 71.751113 -71.216119)
			(xy 71.798719 -71.245173) (xy 71.841587 -71.280848) (xy 71.878804 -71.322385) (xy 71.909577 -71.368898)
			(xy 71.933249 -71.419395) (xy 71.949317 -71.472802) (xy 71.957437 -71.527978) (xy 71.957946 -71.555864)
			(xy 71.957437 -71.58375) (xy 71.951598 -71.623428) (xy 72.703434 -71.623428) (xy 72.707505 -71.567806)
			(xy 72.719631 -71.513369) (xy 72.739554 -71.461278) (xy 72.76685 -71.412643) (xy 72.800936 -71.3685)
			(xy 72.841085 -71.329791) (xy 72.886443 -71.29734) (xy 72.936043 -71.271839) (xy 72.988827 -71.253832)
			(xy 73.04367 -71.243702) (xy 73.099404 -71.241665) (xy 73.154841 -71.247765) (xy 73.208798 -71.261871)
			(xy 73.260127 -71.283683) (xy 73.307733 -71.312737) (xy 73.350601 -71.348412) (xy 73.387818 -71.389949)
			(xy 73.418591 -71.436462) (xy 73.442263 -71.486959) (xy 73.458331 -71.540366) (xy 73.466451 -71.595542)
			(xy 73.46696 -71.623428) (xy 73.466451 -71.651314) (xy 73.458331 -71.70649) (xy 73.442263 -71.759897)
			(xy 73.418591 -71.810394) (xy 73.387818 -71.856907) (xy 73.350601 -71.898444) (xy 73.307733 -71.934119)
			(xy 73.260127 -71.963173) (xy 73.208798 -71.984985) (xy 73.154841 -71.999091) (xy 73.099404 -72.005191)
			(xy 73.04367 -72.003154) (xy 72.988827 -71.993024) (xy 72.936043 -71.975017) (xy 72.886443 -71.949516)
			(xy 72.841085 -71.917065) (xy 72.800936 -71.878356) (xy 72.76685 -71.834213) (xy 72.739554 -71.785578)
			(xy 72.719631 -71.733487) (xy 72.707505 -71.67905) (xy 72.703434 -71.623428) (xy 71.951598 -71.623428)
			(xy 71.949317 -71.638926) (xy 71.933249 -71.692333) (xy 71.909577 -71.74283) (xy 71.878804 -71.789343)
			(xy 71.841587 -71.83088) (xy 71.798719 -71.866555) (xy 71.751113 -71.895609) (xy 71.699784 -71.917421)
			(xy 71.645827 -71.931527) (xy 71.59039 -71.937627) (xy 71.534656 -71.93559) (xy 71.479813 -71.92546)
			(xy 71.427029 -71.907453) (xy 71.377429 -71.881952) (xy 71.332071 -71.849501) (xy 71.291922 -71.810792)
			(xy 71.257836 -71.766649) (xy 71.23054 -71.718014) (xy 71.210617 -71.665923) (xy 71.198491 -71.611486)
			(xy 71.19442 -71.555864) (xy 64.541908 -71.555864) (xy 64.541908 -72.365108) (xy 64.542924 -72.37476)
			(xy 64.544552 -72.382004) (xy 64.551395 -72.395172) (xy 64.556386 -72.400668) (xy 64.578484 -72.422766)
			(xy 66.4845 -74.328528) (xy 66.49119 -74.334731) (xy 66.507753 -74.342346) (xy 66.525935 -74.34367)
			(xy 66.534792 -74.341482) (xy 66.553842 -74.334878) (xy 66.560954 -74.329036) (xy 66.581501 -74.312777)
			(xy 66.626204 -74.285445) (xy 66.674224 -74.264482) (xy 66.72466 -74.250283) (xy 66.776564 -74.243113)
			(xy 66.802762 -74.242676) (xy 66.806572 -74.242676) (xy 66.814192 -74.242676) (xy 66.837306 -74.243946)
			(xy 66.840608 -74.244454) (xy 66.84264 -74.244708) (xy 66.849244 -74.24547) (xy 66.861949 -74.247135)
			(xy 66.887116 -74.251967) (xy 66.899536 -74.255122) (xy 66.900044 -74.255122) (xy 66.908426 -74.257662)
			(xy 66.908934 -74.257662) (xy 66.938705 -74.266837) (xy 66.994996 -74.293514) (xy 67.020948 -74.310748)
			(xy 67.040252 -74.32421) (xy 67.039744 -74.324718) (xy 67.054222 -74.336656) (xy 67.058286 -74.340212)
			(xy 67.064581 -74.344203) (xy 67.078782 -74.34871) (xy 67.086226 -74.349102) (xy 67.15379 -74.349102)
			(xy 67.158616 -74.348848) (xy 67.166027 -74.347878) (xy 67.17984 -74.342191) (xy 67.185794 -74.337672)
			(xy 67.18681 -74.336656) (xy 67.211745 -74.315762) (xy 67.267296 -74.281918) (xy 67.2973 -74.269346)
			(xy 67.322579 -74.259821) (xy 67.375101 -74.247197) (xy 67.401948 -74.2442) (xy 67.4116 -74.243438)
			(xy 67.437508 -74.242422) (xy 67.438016 -74.242422) (xy 67.465956 -74.242925) (xy 67.521234 -74.251102)
			(xy 67.57473 -74.267249) (xy 67.6253 -74.291022) (xy 67.671865 -74.321914) (xy 67.71343 -74.359263)
			(xy 67.749106 -74.402271) (xy 67.778131 -74.450022) (xy 67.799886 -74.501493) (xy 67.807332 -74.528426)
			(xy 67.80911 -74.535538) (xy 67.813174 -74.542142) (xy 67.815469 -74.545779) (xy 67.821093 -74.552286)
			(xy 67.82435 -74.555096) (xy 67.826128 -74.55662) (xy 67.846448 -74.57313) (xy 67.853411 -74.578331)
			(xy 67.869769 -74.584168) (xy 67.878452 -74.58456) (xy 74.910696 -74.58456) (xy 74.919838 -74.584177)
			(xy 74.936956 -74.577755) (xy 74.950726 -74.565726) (xy 74.959392 -74.549627) (xy 74.960988 -74.540618)
			(xy 74.960988 -74.539348) (xy 74.962766 -74.52868) (xy 74.967358 -74.501486) (xy 74.983351 -74.448708)
			(xy 75.006782 -74.398785) (xy 75.037163 -74.352759) (xy 75.073859 -74.311592) (xy 75.116105 -74.276143)
			(xy 75.139296 -74.261218) (xy 75.161488 -74.248021) (xy 75.208675 -74.227066) (xy 75.258254 -74.212656)
			(xy 75.309322 -74.205053) (xy 75.33513 -74.204322) (xy 75.340464 -74.204322) (xy 75.367809 -74.204804)
			(xy 75.421936 -74.212642) (xy 75.474388 -74.228133) (xy 75.524087 -74.250959) (xy 75.570016 -74.280653)
			(xy 75.590908 -74.298302) (xy 75.59802 -74.304398) (xy 75.606148 -74.307446) (xy 75.610496 -74.308986)
			(xy 75.61957 -74.310641) (xy 75.624182 -74.310748) (xy 75.69073 -74.310748) (xy 75.697588 -74.309478)
			(xy 75.708002 -74.307446) (xy 75.719686 -74.302112) (xy 75.72502 -74.297286) (xy 75.742828 -74.282374)
			(xy 75.781414 -74.256515) (xy 75.801982 -74.245724) (xy 75.818824 -74.237429) (xy 75.853814 -74.223818)
			(xy 75.871832 -74.218546) (xy 75.877928 -74.216768) (xy 75.8825 -74.214228) (xy 75.885548 -74.21245)
			(xy 75.892565 -74.208946) (xy 75.907956 -74.205971) (xy 75.915774 -74.206608) (xy 75.920346 -74.20737)
			(xy 75.937872 -74.2061) (xy 75.938126 -74.205846) (xy 75.968098 -74.204322) (xy 75.980798 -74.204322)
			(xy 76.00816 -74.205209) (xy 76.062217 -74.213856) (xy 76.114483 -74.230141) (xy 76.163884 -74.253728)
			(xy 76.209408 -74.284135) (xy 76.250118 -74.320735) (xy 76.285178 -74.362779) (xy 76.31387 -74.409402)
			(xy 76.335603 -74.459647) (xy 76.349931 -74.512483) (xy 76.35367 -74.539602) (xy 76.35367 -74.540364)
			(xy 76.355241 -74.54938) (xy 76.363828 -74.565527) (xy 76.370434 -74.57186) (xy 76.377646 -74.577669)
			(xy 76.394964 -74.58419) (xy 76.404216 -74.58456) (xy 89.148412 -74.58456) (xy 89.153238 -74.584306)
			(xy 89.153492 -74.584306) (xy 89.16022 -74.583351) (xy 89.172842 -74.578332) (xy 89.178384 -74.5744)
			(xy 89.183718 -74.569828) (xy 89.518236 -74.23531) (xy 89.524332 -74.206354) (xy 89.518744 -74.19213)
			(xy 89.506148 -74.158033) (xy 89.488488 -74.08752) (xy 89.479632 -74.01537) (xy 89.47912 -73.979024)
			(xy 89.47912 -73.966324) (xy 89.672922 -64.935354) (xy 89.672922 -64.93129) (xy 88.537034 -45.98924)
			(xy 88.536068 -45.979982) (xy 88.528374 -45.96305) (xy 88.522048 -45.95622) (xy 77.687424 -35.121596)
			(xy 77.663606 -35.097103) (xy 77.621265 -35.043483) (xy 77.585495 -34.985274) (xy 77.556788 -34.923276)
			(xy 77.535539 -34.858342) (xy 77.522042 -34.791367) (xy 77.518768 -34.75736) (xy 77.51826 -34.753804)
			(xy 77.515186 -34.73209) (xy 77.511878 -34.688357) (xy 77.511656 -34.666428) (xy 77.511656 -33.548574)
			(xy 77.502512 -33.519618) (xy 77.482554 -33.489903) (xy 77.449191 -33.426569) (xy 77.423733 -33.359665)
			(xy 77.406554 -33.290173) (xy 77.397905 -33.219114) (xy 77.397356 -33.183322) (xy 77.397356 -33.139634)
			(xy 77.396848 -33.135824) (xy 77.393528 -33.113365) (xy 77.389967 -33.068102) (xy 77.389736 -33.0454)
			(xy 77.389736 -32.60344) (xy 77.39027 -32.568423) (xy 77.398705 -32.4989) (xy 77.415435 -32.430894)
			(xy 77.427328 -32.397954) (xy 77.427836 -32.397192) (xy 77.428598 -32.394906) (xy 77.427836 -32.375602)
			(xy 77.39126 -32.292798) (xy 77.377036 -32.279082) (xy 77.367892 -32.275526) (xy 77.33178 -32.260093)
			(xy 77.263643 -32.221045) (xy 77.201283 -32.173309) (xy 77.173074 -32.145986) (xy 76.822554 -31.795466)
			(xy 76.794198 -31.766176) (xy 76.745003 -31.701169) (xy 76.72451 -31.665926) (xy 76.720954 -31.65983)
			(xy 76.697332 -31.635954) (xy 76.671733 -31.609648) (xy 76.62667 -31.551706) (xy 76.589244 -31.488561)
			(xy 76.574142 -31.455106) (xy 76.543408 -31.426912) (xy 76.510824 -31.415641) (xy 76.44831 -31.386554)
			(xy 76.389599 -31.3504) (xy 76.335488 -31.307667) (xy 76.310744 -31.283656) (xy 75.960224 -30.933136)
			(xy 75.939738 -30.912101) (xy 75.902583 -30.866632) (xy 75.870124 -30.8177) (xy 75.856084 -30.791912)
			(xy 75.85075 -30.783784) (xy 75.836579 -30.765832) (xy 75.810768 -30.728069) (xy 75.799188 -30.708346)
			(xy 75.785834 -30.68437) (xy 75.76319 -30.634375) (xy 75.753976 -30.608524) (xy 75.749233 -30.596796)
			(xy 75.730723 -30.579596) (xy 75.71867 -30.575758) (xy 75.688269 -30.567482) (xy 75.629285 -30.545316)
			(xy 75.572992 -30.517007) (xy 75.520028 -30.482874) (xy 75.470992 -30.443304) (xy 75.448414 -30.421326)
			(xy 75.097894 -30.070806) (xy 75.072935 -30.045105) (xy 75.028773 -29.988688) (xy 74.991758 -29.927345)
			(xy 74.962435 -29.861975) (xy 74.941233 -29.793539) (xy 74.934318 -29.758386) (xy 74.934318 -29.757878)
			(xy 74.933048 -29.750766) (xy 74.925936 -29.737558) (xy 74.879708 -29.69133) (xy 74.877676 -29.690822)
			(xy 74.846085 -29.683062) (xy 74.784729 -29.661442) (xy 74.726168 -29.633111) (xy 74.671134 -29.598424)
			(xy 74.620312 -29.557814) (xy 74.597006 -29.53512) (xy 74.284332 -29.222446) (xy 74.259641 -29.197038)
			(xy 74.215964 -29.141252) (xy 74.19721 -29.111194) (xy 74.192892 -29.104082) (xy 74.180954 -29.093668)
			(xy 73.99909 -29.018484) (xy 73.994403 -29.016687) (xy 73.984551 -29.014772) (xy 73.979532 -29.014674)
			(xy 73.969118 -29.01569) (xy 73.938134 -29.022002) (xy 73.87526 -29.028745) (xy 73.843642 -29.029152)
			(xy 73.804974 -29.028553) (xy 73.72829 -29.018537) (xy 73.653564 -28.998619) (xy 73.617582 -28.984448)
			(xy 73.426066 -28.904946) (xy 73.421379 -28.903149) (xy 73.411527 -28.901236) (xy 73.406508 -28.901136)
			(xy 73.178162 -28.901136) (xy 73.145509 -28.900676) (xy 73.080613 -28.89336) (xy 73.016945 -28.878825)
			(xy 72.955304 -28.857253) (xy 72.896467 -28.828915) (xy 72.841171 -28.794168) (xy 72.790114 -28.753449)
			(xy 72.766682 -28.730702) (xy 72.52335 -28.487624) (xy 72.403716 -28.36799) (xy 72.400629 -28.364985)
			(xy 72.393606 -28.359997) (xy 72.389746 -28.358084) (xy 72.34936 -28.341066) (xy 72.348852 -28.341066)
			(xy 72.26681 -28.30703) (xy 72.26017 -28.304893) (xy 72.246264 -28.303876) (xy 72.239378 -28.304998)
			(xy 72.239124 -28.304998) (xy 72.23125 -28.306522) (xy 72.218296 -28.31338) (xy 72.212962 -28.318968)
			(xy 72.212708 -28.319222) (xy 72.191335 -28.340358) (xy 72.143164 -28.376309) (xy 72.089953 -28.404265)
			(xy 72.033019 -28.423535) (xy 71.973767 -28.433644) (xy 71.943722 -28.434538) (xy 71.935086 -28.434538)
			(xy 71.908939 -28.433827) (xy 71.857195 -28.426184) (xy 71.831962 -28.419298) (xy 71.828406 -28.418282)
			(xy 71.82104 -28.417266) (xy 71.810755 -28.41629) (xy 71.790822 -28.421654) (xy 71.782432 -28.42768)
			(xy 71.778876 -28.430728) (xy 71.77218 -28.437672) (xy 71.764082 -28.455165) (xy 71.763128 -28.464764)
			(xy 71.763128 -29.114242) (xy 71.762638 -29.144226) (xy 71.75481 -29.203682) (xy 71.739289 -29.261607)
			(xy 71.71634 -29.317011) (xy 71.686356 -29.368945) (xy 71.64985 -29.416521) (xy 71.607445 -29.458926)
			(xy 71.559869 -29.495432) (xy 71.507935 -29.525416) (xy 71.452531 -29.548365) (xy 71.394606 -29.563886)
			(xy 71.33515 -29.571714) (xy 71.275182 -29.571714) (xy 71.215726 -29.563886) (xy 71.157801 -29.548365)
			(xy 71.102397 -29.525416) (xy 71.050463 -29.495432) (xy 71.002887 -29.458926) (xy 70.960482 -29.416521)
			(xy 70.923976 -29.368945) (xy 70.893992 -29.317011) (xy 70.871043 -29.261607) (xy 70.855522 -29.203682)
			(xy 70.847694 -29.144226) (xy 70.847204 -29.114242) (xy 70.847204 -28.250642) (xy 70.847678 -28.220626)
			(xy 70.855525 -28.16111) (xy 70.871077 -28.103128) (xy 70.894068 -28.047674) (xy 70.924104 -27.995697)
			(xy 70.96067 -27.948087) (xy 70.98157 -27.926538) (xy 70.987619 -27.920075) (xy 70.995169 -27.904075)
			(xy 70.996302 -27.895296) (xy 70.996556 -27.892756) (xy 70.995794 -27.882342) (xy 70.993 -27.867864)
			(xy 70.990662 -27.858087) (xy 70.979554 -27.841351) (xy 70.962881 -27.830149) (xy 70.953122 -27.827732)
			(xy 70.03796 -27.64536) (xy 70.028054 -27.644344) (xy 69.536564 -27.644344) (xy 69.526498 -27.644775)
			(xy 69.507907 -27.652504) (xy 69.500496 -27.65933) (xy 69.39915 -27.760676) (xy 69.375392 -27.783821)
			(xy 69.323552 -27.8252) (xy 69.267404 -27.860513) (xy 69.207654 -27.889317) (xy 69.145056 -27.91125)
			(xy 69.080395 -27.926035) (xy 69.014485 -27.933487) (xy 68.98132 -27.933904) (xy 68.948157 -27.933457)
			(xy 68.882247 -27.926031) (xy 68.817583 -27.911269) (xy 68.75498 -27.889359) (xy 68.695224 -27.860575)
			(xy 68.639068 -27.825279) (xy 68.587218 -27.783917) (xy 68.540327 -27.737007) (xy 68.498985 -27.685141)
			(xy 68.463712 -27.628971) (xy 68.434951 -27.569204) (xy 68.413066 -27.506592) (xy 68.39833 -27.441923)
			(xy 68.39093 -27.37601) (xy 68.390516 -27.342846) (xy 68.390941 -27.310542) (xy 68.39797 -27.246318)
			(xy 68.41196 -27.183243) (xy 68.432744 -27.12207) (xy 68.460075 -27.063528) (xy 68.493625 -27.008315)
			(xy 68.512944 -26.98242) (xy 68.518024 -26.975816) (xy 68.523612 -26.960068) (xy 68.523612 -26.862024)
			(xy 68.51777 -26.845768) (xy 68.512944 -26.839672) (xy 68.493618 -26.813834) (xy 68.460092 -26.7587)
			(xy 68.432777 -26.70024) (xy 68.411999 -26.63915) (xy 68.398006 -26.576159) (xy 68.390964 -26.512017)
			(xy 68.390516 -26.479754) (xy 68.390516 -26.479246) (xy 68.391052 -26.443534) (xy 68.399654 -26.372629)
			(xy 68.416737 -26.303277) (xy 68.442053 -26.236489) (xy 68.475234 -26.173239) (xy 68.515794 -26.114449)
			(xy 68.563143 -26.060974) (xy 68.616592 -26.013595) (xy 68.67536 -25.973002) (xy 68.738592 -25.939787)
			(xy 68.805365 -25.914434) (xy 68.874708 -25.897313) (xy 68.945608 -25.888672) (xy 68.98132 -25.888188)
			(xy 69.014481 -25.88867) (xy 69.080383 -25.896128) (xy 69.145036 -25.910915) (xy 69.207628 -25.932845)
			(xy 69.267372 -25.961641) (xy 69.323518 -25.996944) (xy 69.375361 -26.038308) (xy 69.39915 -26.061416)
			(xy 69.503544 -26.16581) (xy 69.51094 -26.172659) (xy 69.52954 -26.180392) (xy 69.539612 -26.180796)
			(xy 70.11924 -26.180796) (xy 70.147025 -26.181066) (xy 70.202361 -26.186155) (xy 70.22973 -26.190956)
			(xy 70.234302 -26.191972) (xy 70.784466 -26.191972) (xy 70.786498 -26.191718) (xy 70.788276 -26.191718)
			(xy 70.803516 -26.191464) (xy 70.804024 -26.191464) (xy 70.842097 -26.192134) (xy 70.917582 -26.202147)
			(xy 70.991124 -26.221896) (xy 71.026528 -26.235914) (xy 71.050912 -26.246074) (xy 71.061161 -26.249742)
			(xy 71.082894 -26.248948) (xy 71.10234 -26.239213) (xy 71.109586 -26.231088) (xy 71.115428 -26.223468)
			(xy 71.117714 -26.218134) (xy 71.117968 -26.217626) (xy 71.11873 -26.215848) (xy 71.129909 -26.189991)
			(xy 71.158758 -26.141607) (xy 71.194407 -26.09799) (xy 71.236079 -26.060087) (xy 71.282871 -26.028721)
			(xy 71.333764 -26.004574) (xy 71.387654 -25.98817) (xy 71.44337 -25.979866) (xy 71.471536 -25.979374)
			(xy 71.498705 -25.979856) (xy 71.552494 -25.987571) (xy 71.604643 -26.00284) (xy 71.654099 -26.025353)
			(xy 71.69986 -26.054655) (xy 71.741001 -26.090153) (xy 71.776688 -26.13113) (xy 71.806201 -26.176755)
			(xy 71.828942 -26.226107) (xy 71.844451 -26.278185) (xy 71.850606 -26.319734) (xy 76.841856 -26.319734)
			(xy 76.845927 -26.264112) (xy 76.858053 -26.209675) (xy 76.877976 -26.157584) (xy 76.905272 -26.108949)
			(xy 76.939358 -26.064806) (xy 76.979507 -26.026097) (xy 77.024865 -25.993646) (xy 77.074465 -25.968145)
			(xy 77.127249 -25.950138) (xy 77.182092 -25.940008) (xy 77.237826 -25.937971) (xy 77.293263 -25.944071)
			(xy 77.34722 -25.958177) (xy 77.398549 -25.979989) (xy 77.446155 -26.009043) (xy 77.47582 -26.03373)
			(xy 83.267802 -26.03373) (xy 83.271873 -25.978108) (xy 83.283999 -25.923671) (xy 83.303922 -25.87158)
			(xy 83.331218 -25.822945) (xy 83.365304 -25.778802) (xy 83.405453 -25.740093) (xy 83.450811 -25.707642)
			(xy 83.500411 -25.682141) (xy 83.553195 -25.664134) (xy 83.608038 -25.654004) (xy 83.663772 -25.651967)
			(xy 83.719209 -25.658067) (xy 83.773166 -25.672173) (xy 83.824495 -25.693985) (xy 83.872101 -25.723039)
			(xy 83.914969 -25.758714) (xy 83.952186 -25.800251) (xy 83.982959 -25.846764) (xy 84.006631 -25.897261)
			(xy 84.022699 -25.950668) (xy 84.030819 -26.005844) (xy 84.031328 -26.03373) (xy 84.030819 -26.061616)
			(xy 84.022699 -26.116792) (xy 84.006631 -26.170199) (xy 83.982959 -26.220696) (xy 83.952725 -26.266394)
			(xy 86.520528 -26.266394) (xy 86.521014 -26.239143) (xy 86.52877 -26.185195) (xy 86.544125 -26.1329)
			(xy 86.566767 -26.083323) (xy 86.596233 -26.037473) (xy 86.631924 -25.996282) (xy 86.673115 -25.960591)
			(xy 86.718965 -25.931125) (xy 86.768542 -25.908483) (xy 86.820837 -25.893128) (xy 86.874785 -25.885372)
			(xy 86.929287 -25.885372) (xy 86.983235 -25.893128) (xy 87.03553 -25.908483) (xy 87.085107 -25.931125)
			(xy 87.130957 -25.960591) (xy 87.172148 -25.996282) (xy 87.207839 -26.037473) (xy 87.237305 -26.083323)
			(xy 87.259947 -26.1329) (xy 87.275302 -26.185195) (xy 87.283058 -26.239143) (xy 87.283544 -26.266394)
			(xy 87.282975 -26.295881) (xy 87.273881 -26.35415) (xy 87.255925 -26.410324) (xy 87.229535 -26.463064)
			(xy 87.19534 -26.511112) (xy 87.154156 -26.553324) (xy 87.13089 -26.571448) (xy 87.119734 -26.580307)
			(xy 87.102549 -26.603017) (xy 87.092301 -26.629589) (xy 87.089788 -26.657958) (xy 87.095204 -26.685918)
			(xy 87.108129 -26.711295) (xy 87.127559 -26.732118) (xy 87.139526 -26.73985) (xy 87.163268 -26.754746)
			(xy 87.206502 -26.790414) (xy 87.244053 -26.832023) (xy 87.275111 -26.878679) (xy 87.29901 -26.929377)
			(xy 87.315235 -26.983025) (xy 87.323435 -27.03847) (xy 87.32393 -27.066494) (xy 87.323444 -27.093745)
			(xy 87.315688 -27.147693) (xy 87.300333 -27.199988) (xy 87.277691 -27.249565) (xy 87.248225 -27.295415)
			(xy 87.212534 -27.336606) (xy 87.171343 -27.372297) (xy 87.125493 -27.401763) (xy 87.075916 -27.424405)
			(xy 87.023621 -27.43976) (xy 86.969673 -27.447516) (xy 86.915171 -27.447516) (xy 86.861223 -27.43976)
			(xy 86.808928 -27.424405) (xy 86.759351 -27.401763) (xy 86.713501 -27.372297) (xy 86.67231 -27.336606)
			(xy 86.636619 -27.295415) (xy 86.607153 -27.249565) (xy 86.584511 -27.199988) (xy 86.569156 -27.147693)
			(xy 86.5614 -27.093745) (xy 86.560914 -27.066494) (xy 86.561452 -27.037006) (xy 86.570549 -26.978734)
			(xy 86.588509 -26.922558) (xy 86.614905 -26.869818) (xy 86.649107 -26.82177) (xy 86.690299 -26.779562)
			(xy 86.713568 -26.76144) (xy 86.724624 -26.75247) (xy 86.741799 -26.729783) (xy 86.752046 -26.703238)
			(xy 86.754569 -26.674896) (xy 86.749173 -26.646958) (xy 86.736277 -26.621594) (xy 86.716882 -26.600773)
			(xy 86.704932 -26.593038) (xy 86.681197 -26.57813) (xy 86.637961 -26.542466) (xy 86.600408 -26.50086)
			(xy 86.569347 -26.454206) (xy 86.545447 -26.40351) (xy 86.529222 -26.349862) (xy 86.521022 -26.294418)
			(xy 86.520528 -26.266394) (xy 83.952725 -26.266394) (xy 83.952186 -26.267209) (xy 83.914969 -26.308746)
			(xy 83.872101 -26.344421) (xy 83.824495 -26.373475) (xy 83.773166 -26.395287) (xy 83.719209 -26.409393)
			(xy 83.663772 -26.415493) (xy 83.608038 -26.413456) (xy 83.553195 -26.403326) (xy 83.500411 -26.385319)
			(xy 83.450811 -26.359818) (xy 83.405453 -26.327367) (xy 83.365304 -26.288658) (xy 83.331218 -26.244515)
			(xy 83.303922 -26.19588) (xy 83.283999 -26.143789) (xy 83.271873 -26.089352) (xy 83.267802 -26.03373)
			(xy 77.47582 -26.03373) (xy 77.489023 -26.044718) (xy 77.52624 -26.086255) (xy 77.557013 -26.132768)
			(xy 77.580685 -26.183265) (xy 77.596753 -26.236672) (xy 77.604873 -26.291848) (xy 77.605382 -26.319734)
			(xy 77.604873 -26.34762) (xy 77.596753 -26.402796) (xy 77.580685 -26.456203) (xy 77.557013 -26.5067)
			(xy 77.52624 -26.553213) (xy 77.489023 -26.59475) (xy 77.446155 -26.630425) (xy 77.398549 -26.659479)
			(xy 77.34722 -26.681291) (xy 77.293263 -26.695397) (xy 77.237826 -26.701497) (xy 77.182092 -26.69946)
			(xy 77.127249 -26.68933) (xy 77.074465 -26.671323) (xy 77.024865 -26.645822) (xy 76.979507 -26.613371)
			(xy 76.939358 -26.574662) (xy 76.905272 -26.530519) (xy 76.877976 -26.481884) (xy 76.858053 -26.429793)
			(xy 76.845927 -26.375356) (xy 76.841856 -26.319734) (xy 71.850606 -26.319734) (xy 71.852414 -26.331937)
			(xy 71.853044 -26.359104) (xy 71.853044 -26.36139) (xy 71.85235 -26.392973) (xy 71.84189 -26.455269)
			(xy 71.832216 -26.485342) (xy 71.819516 -26.522172) (xy 71.819008 -26.53157) (xy 72.774048 -26.926794)
			(xy 72.795638 -26.926032) (xy 72.799194 -26.924254) (xy 72.799702 -26.924254) (xy 72.837294 -26.905712)
			(xy 72.842628 -26.902918) (xy 72.849342 -26.898192) (xy 72.859579 -26.885368) (xy 72.862694 -26.877772)
			(xy 72.863964 -26.874216) (xy 72.864726 -26.871422) (xy 72.872444 -26.844811) (xy 72.894509 -26.793989)
			(xy 72.923694 -26.746893) (xy 72.959386 -26.704515) (xy 73.000834 -26.667748) (xy 73.047166 -26.637364)
			(xy 73.097406 -26.614003) (xy 73.150498 -26.598156) (xy 73.205323 -26.590158) (xy 73.233026 -26.589736)
			(xy 73.260276 -26.590201) (xy 73.314222 -26.597961) (xy 73.366514 -26.61332) (xy 73.416089 -26.635965)
			(xy 73.461935 -26.665434) (xy 73.503121 -26.701128) (xy 73.538808 -26.742321) (xy 73.568269 -26.788173)
			(xy 73.590904 -26.837751) (xy 73.606254 -26.890046) (xy 73.614004 -26.943993) (xy 73.614534 -26.971244)
			(xy 73.61396 -27.001138) (xy 73.604631 -27.060193) (xy 73.58618 -27.117062) (xy 73.573132 -27.143964)
			(xy 73.572624 -27.14498) (xy 73.56983 -27.150568) (xy 73.568814 -27.171142) (xy 73.598786 -27.250898)
			(xy 73.602891 -27.260457) (xy 73.61732 -27.275411) (xy 73.626726 -27.279854) (xy 74.059542 -27.459178)
			(xy 74.064229 -27.460973) (xy 74.074081 -27.462884) (xy 74.0791 -27.462988) (xy 74.497184 -27.462988)
			(xy 74.529839 -27.463428) (xy 74.594739 -27.470739) (xy 74.658412 -27.48527) (xy 74.720058 -27.506839)
			(xy 74.778901 -27.535175) (xy 74.834202 -27.569921) (xy 74.885264 -27.61064) (xy 74.908664 -27.633422)
			(xy 75.05319 -27.777694) (xy 75.62088 -28.345384) (xy 75.62723 -28.350718) (xy 75.634976 -28.355734)
			(xy 75.652814 -28.360408) (xy 75.662028 -28.359862) (xy 75.663806 -28.359608) (xy 75.708002 -28.351734)
			(xy 75.70851 -28.351734) (xy 75.74915 -28.343606) (xy 75.754852 -28.342273) (xy 75.765499 -28.337402)
			(xy 75.770232 -28.333954) (xy 75.775312 -28.32989) (xy 75.782932 -28.320238) (xy 75.785472 -28.314396)
			(xy 75.797097 -28.289444) (xy 75.826455 -28.242881) (xy 75.86219 -28.201012) (xy 75.903563 -28.164704)
			(xy 75.949718 -28.134709) (xy 75.999699 -28.111647) (xy 76.052472 -28.095995) (xy 76.106945 -28.088078)
			(xy 76.134468 -28.087574) (xy 76.161723 -28.088035) (xy 76.215678 -28.095788) (xy 76.267981 -28.111141)
			(xy 76.317566 -28.133781) (xy 76.3259 -28.139136) (xy 80.397856 -28.139136) (xy 80.401927 -28.083514)
			(xy 80.414053 -28.029077) (xy 80.433976 -27.976986) (xy 80.461272 -27.928351) (xy 80.495358 -27.884208)
			(xy 80.535507 -27.845499) (xy 80.580865 -27.813048) (xy 80.630465 -27.787547) (xy 80.683249 -27.76954)
			(xy 80.738092 -27.75941) (xy 80.793826 -27.757373) (xy 80.849263 -27.763473) (xy 80.90322 -27.777579)
			(xy 80.954549 -27.799391) (xy 81.002155 -27.828445) (xy 81.045023 -27.86412) (xy 81.08224 -27.905657)
			(xy 81.113013 -27.95217) (xy 81.136685 -28.002667) (xy 81.152753 -28.056074) (xy 81.160873 -28.11125)
			(xy 81.161382 -28.139136) (xy 81.667856 -28.139136) (xy 81.671927 -28.083514) (xy 81.684053 -28.029077)
			(xy 81.703976 -27.976986) (xy 81.731272 -27.928351) (xy 81.765358 -27.884208) (xy 81.805507 -27.845499)
			(xy 81.850865 -27.813048) (xy 81.900465 -27.787547) (xy 81.953249 -27.76954) (xy 82.008092 -27.75941)
			(xy 82.063826 -27.757373) (xy 82.119263 -27.763473) (xy 82.17322 -27.777579) (xy 82.224549 -27.799391)
			(xy 82.272155 -27.828445) (xy 82.315023 -27.86412) (xy 82.35224 -27.905657) (xy 82.383013 -27.95217)
			(xy 82.406685 -28.002667) (xy 82.422753 -28.056074) (xy 82.430873 -28.11125) (xy 82.431382 -28.139136)
			(xy 82.430873 -28.167022) (xy 82.422753 -28.222198) (xy 82.406685 -28.275605) (xy 82.383013 -28.326102)
			(xy 82.35224 -28.372615) (xy 82.315023 -28.414152) (xy 82.272155 -28.449827) (xy 82.224549 -28.478881)
			(xy 82.17322 -28.500693) (xy 82.119263 -28.514799) (xy 82.063826 -28.520899) (xy 82.008092 -28.518862)
			(xy 81.953249 -28.508732) (xy 81.900465 -28.490725) (xy 81.850865 -28.465224) (xy 81.805507 -28.432773)
			(xy 81.765358 -28.394064) (xy 81.731272 -28.349921) (xy 81.703976 -28.301286) (xy 81.684053 -28.249195)
			(xy 81.671927 -28.194758) (xy 81.667856 -28.139136) (xy 81.161382 -28.139136) (xy 81.160873 -28.167022)
			(xy 81.152753 -28.222198) (xy 81.136685 -28.275605) (xy 81.113013 -28.326102) (xy 81.08224 -28.372615)
			(xy 81.045023 -28.414152) (xy 81.002155 -28.449827) (xy 80.954549 -28.478881) (xy 80.90322 -28.500693)
			(xy 80.849263 -28.514799) (xy 80.793826 -28.520899) (xy 80.738092 -28.518862) (xy 80.683249 -28.508732)
			(xy 80.630465 -28.490725) (xy 80.580865 -28.465224) (xy 80.535507 -28.432773) (xy 80.495358 -28.394064)
			(xy 80.461272 -28.349921) (xy 80.433976 -28.301286) (xy 80.414053 -28.249195) (xy 80.401927 -28.194758)
			(xy 80.397856 -28.139136) (xy 76.3259 -28.139136) (xy 76.363425 -28.163248) (xy 76.404623 -28.198942)
			(xy 76.440322 -28.240135) (xy 76.469795 -28.28599) (xy 76.492442 -28.335572) (xy 76.507802 -28.387873)
			(xy 76.515562 -28.441827) (xy 76.515976 -28.469082) (xy 76.515496 -28.496606) (xy 76.507592 -28.551084)
			(xy 76.491946 -28.603861) (xy 76.468882 -28.653845) (xy 76.438879 -28.699998) (xy 76.402558 -28.741363)
			(xy 76.360672 -28.777082) (xy 76.314091 -28.806416) (xy 76.289154 -28.818078) (xy 76.281026 -28.821634)
			(xy 76.275184 -28.827222) (xy 76.272089 -28.830178) (xy 76.266856 -28.836947) (xy 76.26477 -28.840684)
			(xy 76.260452 -28.849066) (xy 76.258674 -28.858464) (xy 76.24318 -28.941268) (xy 76.24318 -28.946602)
			(xy 76.243434 -28.954952) (xy 76.248763 -28.970774) (xy 76.253594 -28.97759) (xy 76.256896 -28.9814)
			(xy 76.397866 -29.12237) (xy 86.606888 -29.12237) (xy 86.606888 -28.25877) (xy 86.607378 -28.228802)
			(xy 86.615201 -28.16938) (xy 86.630714 -28.111487) (xy 86.65365 -28.056114) (xy 86.683617 -28.004208)
			(xy 86.720104 -27.956658) (xy 86.762484 -27.914278) (xy 86.810034 -27.877791) (xy 86.86194 -27.847824)
			(xy 86.917313 -27.824888) (xy 86.975206 -27.809375) (xy 87.034628 -27.801552) (xy 87.094564 -27.801552)
			(xy 87.153986 -27.809375) (xy 87.211879 -27.824888) (xy 87.267252 -27.847824) (xy 87.319158 -27.877791)
			(xy 87.366708 -27.914278) (xy 87.409088 -27.956658) (xy 87.445575 -28.004208) (xy 87.475542 -28.056114)
			(xy 87.498478 -28.111487) (xy 87.513991 -28.16938) (xy 87.521814 -28.228802) (xy 87.522304 -28.25877)
			(xy 87.522304 -29.12237) (xy 87.521814 -29.152338) (xy 87.513991 -29.21176) (xy 87.498478 -29.269653)
			(xy 87.475542 -29.325026) (xy 87.445575 -29.376932) (xy 87.409088 -29.424482) (xy 87.366708 -29.466862)
			(xy 87.319158 -29.503349) (xy 87.267252 -29.533316) (xy 87.211879 -29.556252) (xy 87.153986 -29.571765)
			(xy 87.094564 -29.579588) (xy 87.034628 -29.579588) (xy 86.975206 -29.571765) (xy 86.917313 -29.556252)
			(xy 86.86194 -29.533316) (xy 86.810034 -29.503349) (xy 86.762484 -29.466862) (xy 86.720104 -29.424482)
			(xy 86.683617 -29.376932) (xy 86.65365 -29.325026) (xy 86.630714 -29.269653) (xy 86.615201 -29.21176)
			(xy 86.607378 -29.152338) (xy 86.606888 -29.12237) (xy 76.397866 -29.12237) (xy 77.652372 -30.376876)
			(xy 78.888844 -30.376876) (xy 78.8894 -30.34796) (xy 78.898119 -30.29079) (xy 78.915369 -30.235591)
			(xy 78.940753 -30.183629) (xy 78.973691 -30.136094) (xy 79.013427 -30.094077) (xy 79.03591 -30.075886)
			(xy 79.044715 -30.068277) (xy 79.054899 -30.047378) (xy 79.055468 -30.035754) (xy 79.055468 -29.955998)
			(xy 79.054927 -29.944366) (xy 79.044741 -29.923456) (xy 79.03591 -29.915866) (xy 79.013412 -29.897692)
			(xy 78.973678 -29.855669) (xy 78.94074 -29.80813) (xy 78.915354 -29.756166) (xy 78.898101 -29.700965)
			(xy 78.889376 -29.643793) (xy 78.888844 -29.614876) (xy 78.88933 -29.587625) (xy 78.897086 -29.533677)
			(xy 78.912441 -29.481382) (xy 78.935083 -29.431805) (xy 78.964549 -29.385955) (xy 79.00024 -29.344764)
			(xy 79.041431 -29.309073) (xy 79.087281 -29.279607) (xy 79.136858 -29.256965) (xy 79.189153 -29.24161)
			(xy 79.243101 -29.233854) (xy 79.297603 -29.233854) (xy 79.351551 -29.24161) (xy 79.403846 -29.256965)
			(xy 79.453423 -29.279607) (xy 79.499273 -29.309073) (xy 79.540464 -29.344764) (xy 79.576155 -29.385955)
			(xy 79.605621 -29.431805) (xy 79.628263 -29.481382) (xy 79.643618 -29.533677) (xy 79.651374 -29.587625)
			(xy 79.65186 -29.614876) (xy 79.65134 -29.643793) (xy 79.642613 -29.700965) (xy 79.625357 -29.756164)
			(xy 79.599965 -29.808126) (xy 79.567022 -29.85566) (xy 79.52728 -29.897676) (xy 79.504794 -29.915866)
			(xy 79.496011 -29.923497) (xy 79.485815 -29.94438) (xy 79.485236 -29.955998) (xy 79.485236 -30.035754)
			(xy 79.485746 -30.04739) (xy 79.495954 -30.0683) (xy 79.504794 -30.075886) (xy 79.52727 -30.094086)
			(xy 79.567005 -30.136104) (xy 79.599946 -30.183637) (xy 79.625335 -30.235596) (xy 79.642593 -30.290792)
			(xy 79.651324 -30.347961) (xy 79.65186 -30.376876) (xy 81.92897 -30.376876) (xy 81.929517 -30.34796)
			(xy 81.938236 -30.290789) (xy 81.955487 -30.235589) (xy 81.980873 -30.183627) (xy 82.013813 -30.136093)
			(xy 82.053552 -30.094076) (xy 82.076036 -30.075886) (xy 82.084846 -30.068281) (xy 82.095026 -30.047379)
			(xy 82.095594 -30.035754) (xy 82.095594 -29.955998) (xy 82.095044 -29.944367) (xy 82.084863 -29.923458)
			(xy 82.076036 -29.915866) (xy 82.053544 -29.897685) (xy 82.013807 -29.855664) (xy 81.980868 -29.808128)
			(xy 81.955481 -29.756164) (xy 81.938227 -29.700964) (xy 81.929502 -29.643793) (xy 81.92897 -29.614876)
			(xy 81.929456 -29.587625) (xy 81.937212 -29.533677) (xy 81.952567 -29.481382) (xy 81.975209 -29.431805)
			(xy 82.004675 -29.385955) (xy 82.040366 -29.344764) (xy 82.081557 -29.309073) (xy 82.127407 -29.279607)
			(xy 82.176984 -29.256965) (xy 82.229279 -29.24161) (xy 82.283227 -29.233854) (xy 82.337729 -29.233854)
			(xy 82.391677 -29.24161) (xy 82.443972 -29.256965) (xy 82.493549 -29.279607) (xy 82.539399 -29.309073)
			(xy 82.58059 -29.344764) (xy 82.616281 -29.385955) (xy 82.645747 -29.431805) (xy 82.668389 -29.481382)
			(xy 82.683744 -29.533677) (xy 82.6915 -29.587625) (xy 82.691986 -29.614876) (xy 82.691456 -29.643793)
			(xy 82.68273 -29.700963) (xy 82.665475 -29.756162) (xy 82.640085 -29.808124) (xy 82.607144 -29.855658)
			(xy 82.567405 -29.897676) (xy 82.54492 -29.915866) (xy 82.536125 -29.923484) (xy 82.525938 -29.944377)
			(xy 82.525362 -29.955998) (xy 82.525362 -30.035754) (xy 82.525863 -30.047391) (xy 82.536076 -30.068302)
			(xy 82.54492 -30.075886) (xy 82.567401 -30.09408) (xy 82.607135 -30.1361) (xy 82.640074 -30.183634)
			(xy 82.665463 -30.235595) (xy 82.68272 -30.290791) (xy 82.69145 -30.34796) (xy 82.691986 -30.376876)
			(xy 82.6915 -30.404127) (xy 82.683744 -30.458075) (xy 82.668389 -30.51037) (xy 82.645747 -30.559947)
			(xy 82.616281 -30.605797) (xy 82.58059 -30.646988) (xy 82.539399 -30.682679) (xy 82.493549 -30.712145)
			(xy 82.443972 -30.734787) (xy 82.391677 -30.750142) (xy 82.337729 -30.757898) (xy 82.283227 -30.757898)
			(xy 82.229279 -30.750142) (xy 82.176984 -30.734787) (xy 82.127407 -30.712145) (xy 82.081557 -30.682679)
			(xy 82.040366 -30.646988) (xy 82.004675 -30.605797) (xy 81.975209 -30.559947) (xy 81.952567 -30.51037)
			(xy 81.937212 -30.458075) (xy 81.929456 -30.404127) (xy 81.92897 -30.376876) (xy 79.65186 -30.376876)
			(xy 79.651374 -30.404127) (xy 79.643618 -30.458075) (xy 79.628263 -30.51037) (xy 79.605621 -30.559947)
			(xy 79.576155 -30.605797) (xy 79.540464 -30.646988) (xy 79.499273 -30.682679) (xy 79.453423 -30.712145)
			(xy 79.403846 -30.734787) (xy 79.351551 -30.750142) (xy 79.297603 -30.757898) (xy 79.243101 -30.757898)
			(xy 79.189153 -30.750142) (xy 79.136858 -30.734787) (xy 79.087281 -30.712145) (xy 79.041431 -30.682679)
			(xy 79.00024 -30.646988) (xy 78.964549 -30.605797) (xy 78.935083 -30.559947) (xy 78.912441 -30.51037)
			(xy 78.897086 -30.458075) (xy 78.88933 -30.404127) (xy 78.888844 -30.376876) (xy 77.652372 -30.376876)
			(xy 78.197964 -30.922468) (xy 84.752688 -30.922468) (xy 84.752688 -30.058868) (xy 84.753178 -30.0289)
			(xy 84.761001 -29.969478) (xy 84.776514 -29.911585) (xy 84.79945 -29.856212) (xy 84.829417 -29.804306)
			(xy 84.865904 -29.756756) (xy 84.908284 -29.714376) (xy 84.955834 -29.677889) (xy 85.00774 -29.647922)
			(xy 85.063113 -29.624986) (xy 85.121006 -29.609473) (xy 85.180428 -29.60165) (xy 85.240364 -29.60165)
			(xy 85.299786 -29.609473) (xy 85.357679 -29.624986) (xy 85.413052 -29.647922) (xy 85.464958 -29.677889)
			(xy 85.512508 -29.714376) (xy 85.554888 -29.756756) (xy 85.591375 -29.804306) (xy 85.621342 -29.856212)
			(xy 85.644278 -29.911585) (xy 85.659791 -29.969478) (xy 85.667614 -30.0289) (xy 85.668104 -30.058868)
			(xy 85.668104 -30.92069) (xy 99.48926 -30.92069) (xy 99.48926 -30.05709) (xy 99.48975 -30.027106)
			(xy 99.497578 -29.96765) (xy 99.513099 -29.909725) (xy 99.536048 -29.854321) (xy 99.566032 -29.802387)
			(xy 99.602538 -29.754811) (xy 99.644943 -29.712406) (xy 99.692519 -29.6759) (xy 99.744453 -29.645916)
			(xy 99.799857 -29.622967) (xy 99.857782 -29.607446) (xy 99.917238 -29.599618) (xy 99.977206 -29.599618)
			(xy 100.036662 -29.607446) (xy 100.094587 -29.622967) (xy 100.149991 -29.645916) (xy 100.201925 -29.6759)
			(xy 100.249501 -29.712406) (xy 100.291906 -29.754811) (xy 100.328412 -29.802387) (xy 100.358396 -29.854321)
			(xy 100.381345 -29.909725) (xy 100.396866 -29.96765) (xy 100.404694 -30.027106) (xy 100.405184 -30.05709)
			(xy 100.405184 -30.92069) (xy 100.404694 -30.950674) (xy 100.396866 -31.01013) (xy 100.381345 -31.068055)
			(xy 100.358396 -31.123459) (xy 100.328412 -31.175393) (xy 100.291906 -31.222969) (xy 100.249501 -31.265374)
			(xy 100.201925 -31.30188) (xy 100.149991 -31.331864) (xy 100.094587 -31.354813) (xy 100.036662 -31.370334)
			(xy 99.977206 -31.378162) (xy 99.917238 -31.378162) (xy 99.857782 -31.370334) (xy 99.799857 -31.354813)
			(xy 99.744453 -31.331864) (xy 99.692519 -31.30188) (xy 99.644943 -31.265374) (xy 99.602538 -31.222969)
			(xy 99.566032 -31.175393) (xy 99.536048 -31.123459) (xy 99.513099 -31.068055) (xy 99.497578 -31.01013)
			(xy 99.48975 -30.950674) (xy 99.48926 -30.92069) (xy 85.668104 -30.92069) (xy 85.668104 -30.922468)
			(xy 85.667614 -30.952436) (xy 85.659791 -31.011858) (xy 85.644278 -31.069751) (xy 85.621342 -31.125124)
			(xy 85.591375 -31.17703) (xy 85.554888 -31.22458) (xy 85.512508 -31.26696) (xy 85.464958 -31.303447)
			(xy 85.413052 -31.333414) (xy 85.357679 -31.35635) (xy 85.299786 -31.371863) (xy 85.240364 -31.379686)
			(xy 85.180428 -31.379686) (xy 85.121006 -31.371863) (xy 85.063113 -31.35635) (xy 85.00774 -31.333414)
			(xy 84.955834 -31.303447) (xy 84.908284 -31.26696) (xy 84.865904 -31.22458) (xy 84.829417 -31.17703)
			(xy 84.79945 -31.125124) (xy 84.776514 -31.069751) (xy 84.761001 -31.011858) (xy 84.753178 -30.952436)
			(xy 84.752688 -30.922468) (xy 78.197964 -30.922468) (xy 78.784704 -31.509208) (xy 78.807139 -31.532231)
			(xy 78.847326 -31.58241) (xy 78.881728 -31.636718) (xy 78.89621 -31.665418) (xy 78.897734 -31.667958)
			(xy 78.913228 -31.697422) (xy 78.916525 -31.703521) (xy 78.925798 -31.71382) (xy 78.931516 -31.717742)
			(xy 78.965298 -31.739078) (xy 78.975318 -31.738658) (xy 78.993832 -31.730988) (xy 79.007999 -31.716815)
			(xy 79.015662 -31.698298) (xy 79.016098 -31.688278) (xy 79.014574 -31.677356) (xy 79.013304 -31.671006)
			(xy 79.0067 -31.645865) (xy 78.999557 -31.594379) (xy 78.99908 -31.56839) (xy 78.99908 -31.567882)
			(xy 78.999567 -31.54063) (xy 79.007326 -31.486681) (xy 79.022684 -31.434386) (xy 79.045328 -31.384808)
			(xy 79.074798 -31.338958) (xy 79.110492 -31.297768) (xy 79.151685 -31.262077) (xy 79.197538 -31.232612)
			(xy 79.247117 -31.209972) (xy 79.299414 -31.194619) (xy 79.353364 -31.186865) (xy 79.407868 -31.186867)
			(xy 79.461817 -31.194626) (xy 79.514113 -31.209984) (xy 79.56369 -31.232627) (xy 79.609541 -31.262096)
			(xy 79.650731 -31.297791) (xy 79.686422 -31.338983) (xy 79.715887 -31.384836) (xy 79.738527 -31.434416)
			(xy 79.75388 -31.486712) (xy 79.761635 -31.540662) (xy 79.761633 -31.595166) (xy 79.753875 -31.649115)
			(xy 79.738517 -31.701411) (xy 79.730362 -31.719266) (xy 80.285334 -31.719266) (xy 80.289405 -31.663644)
			(xy 80.301531 -31.609207) (xy 80.321454 -31.557116) (xy 80.34875 -31.508481) (xy 80.382836 -31.464338)
			(xy 80.422985 -31.425629) (xy 80.468343 -31.393178) (xy 80.517943 -31.367677) (xy 80.570727 -31.34967)
			(xy 80.62557 -31.33954) (xy 80.681304 -31.337503) (xy 80.736741 -31.343603) (xy 80.790698 -31.357709)
			(xy 80.842027 -31.379521) (xy 80.889633 -31.408575) (xy 80.932501 -31.44425) (xy 80.969718 -31.485787)
			(xy 81.000491 -31.5323) (xy 81.024163 -31.582797) (xy 81.040231 -31.636204) (xy 81.044381 -31.664402)
			(xy 81.560922 -31.664402) (xy 81.564993 -31.60878) (xy 81.577119 -31.554343) (xy 81.597042 -31.502252)
			(xy 81.624338 -31.453617) (xy 81.658424 -31.409474) (xy 81.698573 -31.370765) (xy 81.743931 -31.338314)
			(xy 81.793531 -31.312813) (xy 81.846315 -31.294806) (xy 81.901158 -31.284676) (xy 81.956892 -31.282639)
			(xy 82.012329 -31.288739) (xy 82.066286 -31.302845) (xy 82.117615 -31.324657) (xy 82.165221 -31.353711)
			(xy 82.208089 -31.389386) (xy 82.245306 -31.430923) (xy 82.276079 -31.477436) (xy 82.299751 -31.527933)
			(xy 82.315819 -31.58134) (xy 82.323939 -31.636516) (xy 82.324448 -31.664402) (xy 82.323939 -31.692288)
			(xy 82.315819 -31.747464) (xy 82.306879 -31.777178) (xy 82.826096 -31.777178) (xy 82.830167 -31.721556)
			(xy 82.842293 -31.667119) (xy 82.862216 -31.615028) (xy 82.889512 -31.566393) (xy 82.923598 -31.52225)
			(xy 82.963747 -31.483541) (xy 83.009105 -31.45109) (xy 83.058705 -31.425589) (xy 83.111489 -31.407582)
			(xy 83.166332 -31.397452) (xy 83.222066 -31.395415) (xy 83.277503 -31.401515) (xy 83.33146 -31.415621)
			(xy 83.382789 -31.437433) (xy 83.430395 -31.466487) (xy 83.473263 -31.502162) (xy 83.51048 -31.543699)
			(xy 83.541253 -31.590212) (xy 83.564925 -31.640709) (xy 83.580993 -31.694116) (xy 83.589113 -31.749292)
			(xy 83.589622 -31.777178) (xy 83.589113 -31.805064) (xy 83.580993 -31.86024) (xy 83.564925 -31.913647)
			(xy 83.541253 -31.964144) (xy 83.51048 -32.010657) (xy 83.473263 -32.052194) (xy 83.430395 -32.087869)
			(xy 83.382789 -32.116923) (xy 83.33146 -32.138735) (xy 83.277503 -32.152841) (xy 83.222066 -32.158941)
			(xy 83.166332 -32.156904) (xy 83.111489 -32.146774) (xy 83.058705 -32.128767) (xy 83.009105 -32.103266)
			(xy 82.963747 -32.070815) (xy 82.923598 -32.032106) (xy 82.889512 -31.987963) (xy 82.862216 -31.939328)
			(xy 82.842293 -31.887237) (xy 82.830167 -31.8328) (xy 82.826096 -31.777178) (xy 82.306879 -31.777178)
			(xy 82.299751 -31.800871) (xy 82.276079 -31.851368) (xy 82.245306 -31.897881) (xy 82.208089 -31.939418)
			(xy 82.165221 -31.975093) (xy 82.117615 -32.004147) (xy 82.066286 -32.025959) (xy 82.012329 -32.040065)
			(xy 81.956892 -32.046165) (xy 81.901158 -32.044128) (xy 81.846315 -32.033998) (xy 81.793531 -32.015991)
			(xy 81.743931 -31.99049) (xy 81.698573 -31.958039) (xy 81.658424 -31.91933) (xy 81.624338 -31.875187)
			(xy 81.597042 -31.826552) (xy 81.577119 -31.774461) (xy 81.564993 -31.720024) (xy 81.560922 -31.664402)
			(xy 81.044381 -31.664402) (xy 81.048351 -31.69138) (xy 81.04886 -31.719266) (xy 81.048351 -31.747152)
			(xy 81.040231 -31.802328) (xy 81.024163 -31.855735) (xy 81.000491 -31.906232) (xy 80.969718 -31.952745)
			(xy 80.932501 -31.994282) (xy 80.889633 -32.029957) (xy 80.842027 -32.059011) (xy 80.790698 -32.080823)
			(xy 80.736741 -32.094929) (xy 80.681304 -32.101029) (xy 80.62557 -32.098992) (xy 80.570727 -32.088862)
			(xy 80.517943 -32.070855) (xy 80.468343 -32.045354) (xy 80.422985 -32.012903) (xy 80.382836 -31.974194)
			(xy 80.34875 -31.930051) (xy 80.321454 -31.881416) (xy 80.301531 -31.829325) (xy 80.289405 -31.774888)
			(xy 80.285334 -31.719266) (xy 79.730362 -31.719266) (xy 79.715874 -31.750988) (xy 79.686405 -31.796839)
			(xy 79.650711 -31.838029) (xy 79.609518 -31.87372) (xy 79.563666 -31.903186) (xy 79.514086 -31.925826)
			(xy 79.46179 -31.94118) (xy 79.40784 -31.948935) (xy 79.380588 -31.94939) (xy 79.354647 -31.948952)
			(xy 79.303244 -31.941915) (xy 79.25327 -31.927974) (xy 79.205647 -31.907384) (xy 79.161257 -31.880527)
			(xy 79.140812 -31.864554) (xy 79.140558 -31.8643) (xy 79.132792 -31.858622) (xy 79.114409 -31.853002)
			(xy 79.09525 -31.854558) (xy 79.086456 -31.858458) (xy 78.99019 -31.905956) (xy 78.97495 -31.931356)
			(xy 78.975458 -31.946342) (xy 78.975712 -31.961328) (xy 78.975712 -32.722312) (xy 86.606888 -32.722312)
			(xy 86.606888 -31.858712) (xy 86.607378 -31.828744) (xy 86.615201 -31.769322) (xy 86.630714 -31.711429)
			(xy 86.65365 -31.656056) (xy 86.683617 -31.60415) (xy 86.720104 -31.5566) (xy 86.762484 -31.51422)
			(xy 86.810034 -31.477733) (xy 86.86194 -31.447766) (xy 86.917313 -31.42483) (xy 86.975206 -31.409317)
			(xy 87.034628 -31.401494) (xy 87.094564 -31.401494) (xy 87.153986 -31.409317) (xy 87.211879 -31.42483)
			(xy 87.267252 -31.447766) (xy 87.319158 -31.477733) (xy 87.366708 -31.51422) (xy 87.409088 -31.5566)
			(xy 87.445575 -31.60415) (xy 87.475542 -31.656056) (xy 87.498478 -31.711429) (xy 87.513991 -31.769322)
			(xy 87.521814 -31.828744) (xy 87.522304 -31.858712) (xy 87.522304 -32.714184) (xy 96.847152 -32.714184)
			(xy 96.847152 -31.850584) (xy 96.847642 -31.8206) (xy 96.85547 -31.761144) (xy 96.870991 -31.703219)
			(xy 96.89394 -31.647815) (xy 96.923924 -31.595881) (xy 96.96043 -31.548305) (xy 97.002835 -31.5059)
			(xy 97.050411 -31.469394) (xy 97.102345 -31.43941) (xy 97.157749 -31.416461) (xy 97.215674 -31.40094)
			(xy 97.27513 -31.393112) (xy 97.335098 -31.393112) (xy 97.394554 -31.40094) (xy 97.452479 -31.416461)
			(xy 97.507883 -31.43941) (xy 97.559817 -31.469394) (xy 97.607393 -31.5059) (xy 97.649798 -31.548305)
			(xy 97.686304 -31.595881) (xy 97.716288 -31.647815) (xy 97.739237 -31.703219) (xy 97.754758 -31.761144)
			(xy 97.762586 -31.8206) (xy 97.763076 -31.850584) (xy 97.763076 -32.714184) (xy 97.762586 -32.744168)
			(xy 97.754758 -32.803624) (xy 97.739237 -32.861549) (xy 97.716288 -32.916953) (xy 97.686304 -32.968887)
			(xy 97.649798 -33.016463) (xy 97.607393 -33.058868) (xy 97.559817 -33.095374) (xy 97.507883 -33.125358)
			(xy 97.452479 -33.148307) (xy 97.394554 -33.163828) (xy 97.335098 -33.171656) (xy 97.27513 -33.171656)
			(xy 97.215674 -33.163828) (xy 97.157749 -33.148307) (xy 97.102345 -33.125358) (xy 97.050411 -33.095374)
			(xy 97.002835 -33.058868) (xy 96.96043 -33.016463) (xy 96.923924 -32.968887) (xy 96.89394 -32.916953)
			(xy 96.870991 -32.861549) (xy 96.85547 -32.803624) (xy 96.847642 -32.744168) (xy 96.847152 -32.714184)
			(xy 87.522304 -32.714184) (xy 87.522304 -32.722312) (xy 87.521814 -32.75228) (xy 87.513991 -32.811702)
			(xy 87.498478 -32.869595) (xy 87.475542 -32.924968) (xy 87.445575 -32.976874) (xy 87.409088 -33.024424)
			(xy 87.366708 -33.066804) (xy 87.319158 -33.103291) (xy 87.267252 -33.133258) (xy 87.211879 -33.156194)
			(xy 87.153986 -33.171707) (xy 87.094564 -33.17953) (xy 87.034628 -33.17953) (xy 86.975206 -33.171707)
			(xy 86.917313 -33.156194) (xy 86.86194 -33.133258) (xy 86.810034 -33.103291) (xy 86.762484 -33.066804)
			(xy 86.720104 -33.024424) (xy 86.683617 -32.976874) (xy 86.65365 -32.924968) (xy 86.630714 -32.869595)
			(xy 86.615201 -32.811702) (xy 86.607378 -32.75228) (xy 86.606888 -32.722312) (xy 78.975712 -32.722312)
			(xy 78.975712 -34.28365) (xy 78.976145 -34.293716) (xy 78.983873 -34.312306) (xy 78.990698 -34.319718)
			(xy 79.193385 -34.52241) (xy 84.752688 -34.52241) (xy 84.752688 -33.65881) (xy 84.753178 -33.628842)
			(xy 84.761001 -33.56942) (xy 84.776514 -33.511527) (xy 84.79945 -33.456154) (xy 84.829417 -33.404248)
			(xy 84.865904 -33.356698) (xy 84.908284 -33.314318) (xy 84.955834 -33.277831) (xy 85.00774 -33.247864)
			(xy 85.063113 -33.224928) (xy 85.121006 -33.209415) (xy 85.180428 -33.201592) (xy 85.240364 -33.201592)
			(xy 85.299786 -33.209415) (xy 85.357679 -33.224928) (xy 85.413052 -33.247864) (xy 85.464958 -33.277831)
			(xy 85.512508 -33.314318) (xy 85.554888 -33.356698) (xy 85.591375 -33.404248) (xy 85.621342 -33.456154)
			(xy 85.644278 -33.511527) (xy 85.659791 -33.56942) (xy 85.667614 -33.628842) (xy 85.668104 -33.65881)
			(xy 85.668104 -34.520886) (xy 99.48926 -34.520886) (xy 99.48926 -33.657286) (xy 99.48975 -33.627302)
			(xy 99.497578 -33.567846) (xy 99.513099 -33.509921) (xy 99.536048 -33.454517) (xy 99.566032 -33.402583)
			(xy 99.602538 -33.355007) (xy 99.644943 -33.312602) (xy 99.692519 -33.276096) (xy 99.744453 -33.246112)
			(xy 99.799857 -33.223163) (xy 99.857782 -33.207642) (xy 99.917238 -33.199814) (xy 99.977206 -33.199814)
			(xy 100.036662 -33.207642) (xy 100.094587 -33.223163) (xy 100.149991 -33.246112) (xy 100.201925 -33.276096)
			(xy 100.249501 -33.312602) (xy 100.291906 -33.355007) (xy 100.328412 -33.402583) (xy 100.358396 -33.454517)
			(xy 100.381345 -33.509921) (xy 100.396866 -33.567846) (xy 100.404694 -33.627302) (xy 100.405184 -33.657286)
			(xy 100.405184 -34.520886) (xy 100.404694 -34.55087) (xy 100.396866 -34.610326) (xy 100.381345 -34.668251)
			(xy 100.358396 -34.723655) (xy 100.328412 -34.775589) (xy 100.291906 -34.823165) (xy 100.249501 -34.86557)
			(xy 100.201925 -34.902076) (xy 100.149991 -34.93206) (xy 100.094587 -34.955009) (xy 100.036662 -34.97053)
			(xy 99.977206 -34.978358) (xy 99.917238 -34.978358) (xy 99.857782 -34.97053) (xy 99.799857 -34.955009)
			(xy 99.744453 -34.93206) (xy 99.692519 -34.902076) (xy 99.644943 -34.86557) (xy 99.602538 -34.823165)
			(xy 99.566032 -34.775589) (xy 99.536048 -34.723655) (xy 99.513099 -34.668251) (xy 99.497578 -34.610326)
			(xy 99.48975 -34.55087) (xy 99.48926 -34.520886) (xy 85.668104 -34.520886) (xy 85.668104 -34.52241)
			(xy 85.667614 -34.552378) (xy 85.659791 -34.6118) (xy 85.644278 -34.669693) (xy 85.621342 -34.725066)
			(xy 85.591375 -34.776972) (xy 85.554888 -34.824522) (xy 85.512508 -34.866902) (xy 85.464958 -34.903389)
			(xy 85.413052 -34.933356) (xy 85.357679 -34.956292) (xy 85.299786 -34.971805) (xy 85.240364 -34.979628)
			(xy 85.180428 -34.979628) (xy 85.121006 -34.971805) (xy 85.063113 -34.956292) (xy 85.00774 -34.933356)
			(xy 84.955834 -34.903389) (xy 84.908284 -34.866902) (xy 84.865904 -34.824522) (xy 84.829417 -34.776972)
			(xy 84.79945 -34.725066) (xy 84.776514 -34.669693) (xy 84.761001 -34.6118) (xy 84.753178 -34.552378)
			(xy 84.752688 -34.52241) (xy 79.193385 -34.52241) (xy 79.93581 -35.264852) (xy 81.902298 -35.264852)
			(xy 81.906369 -35.20923) (xy 81.918495 -35.154793) (xy 81.938418 -35.102702) (xy 81.965714 -35.054067)
			(xy 81.9998 -35.009924) (xy 82.039949 -34.971215) (xy 82.085307 -34.938764) (xy 82.134907 -34.913263)
			(xy 82.187691 -34.895256) (xy 82.242534 -34.885126) (xy 82.298268 -34.883089) (xy 82.353705 -34.889189)
			(xy 82.407662 -34.903295) (xy 82.458991 -34.925107) (xy 82.506597 -34.954161) (xy 82.549465 -34.989836)
			(xy 82.586682 -35.031373) (xy 82.617455 -35.077886) (xy 82.641127 -35.128383) (xy 82.657195 -35.18179)
			(xy 82.665315 -35.236966) (xy 82.665824 -35.264852) (xy 82.665315 -35.292738) (xy 82.657195 -35.347914)
			(xy 82.641127 -35.401321) (xy 82.617455 -35.451818) (xy 82.586682 -35.498331) (xy 82.549465 -35.539868)
			(xy 82.506597 -35.575543) (xy 82.458991 -35.604597) (xy 82.407662 -35.626409) (xy 82.353705 -35.640515)
			(xy 82.298268 -35.646615) (xy 82.242534 -35.644578) (xy 82.187691 -35.634448) (xy 82.134907 -35.616441)
			(xy 82.085307 -35.59094) (xy 82.039949 -35.558489) (xy 81.9998 -35.51978) (xy 81.965714 -35.475637)
			(xy 81.938418 -35.427002) (xy 81.918495 -35.374911) (xy 81.906369 -35.320474) (xy 81.902298 -35.264852)
			(xy 79.93581 -35.264852) (xy 80.957882 -36.286948) (xy 83.200238 -36.286948) (xy 83.204309 -36.231326)
			(xy 83.216435 -36.176889) (xy 83.236358 -36.124798) (xy 83.263654 -36.076163) (xy 83.29774 -36.03202)
			(xy 83.337889 -35.993311) (xy 83.383247 -35.96086) (xy 83.432847 -35.935359) (xy 83.485631 -35.917352)
			(xy 83.540474 -35.907222) (xy 83.596208 -35.905185) (xy 83.651645 -35.911285) (xy 83.705602 -35.925391)
			(xy 83.756931 -35.947203) (xy 83.804537 -35.976257) (xy 83.847405 -36.011932) (xy 83.884622 -36.053469)
			(xy 83.915395 -36.099982) (xy 83.939067 -36.150479) (xy 83.955135 -36.203886) (xy 83.963255 -36.259062)
			(xy 83.963764 -36.286948) (xy 83.963255 -36.314834) (xy 83.955135 -36.37001) (xy 83.939067 -36.423417)
			(xy 83.915395 -36.473914) (xy 83.88785 -36.515548) (xy 85.014052 -36.515548) (xy 85.018123 -36.459926)
			(xy 85.030249 -36.405489) (xy 85.050172 -36.353398) (xy 85.077468 -36.304763) (xy 85.111554 -36.26062)
			(xy 85.151703 -36.221911) (xy 85.197061 -36.18946) (xy 85.246661 -36.163959) (xy 85.299445 -36.145952)
			(xy 85.354288 -36.135822) (xy 85.410022 -36.133785) (xy 85.465459 -36.139885) (xy 85.519416 -36.153991)
			(xy 85.570745 -36.175803) (xy 85.618351 -36.204857) (xy 85.661219 -36.240532) (xy 85.698436 -36.282069)
			(xy 85.729209 -36.328582) (xy 85.752881 -36.379079) (xy 85.768949 -36.432486) (xy 85.777069 -36.487662)
			(xy 85.777578 -36.515548) (xy 85.777069 -36.543434) (xy 85.768949 -36.59861) (xy 85.768492 -36.60013)
			(xy 89.998049 -36.60013) (xy 90.002054 -36.512222) (xy 90.014037 -36.425042) (xy 90.033897 -36.339313)
			(xy 90.061472 -36.255745) (xy 90.096531 -36.175031) (xy 90.138784 -36.097839) (xy 90.187882 -36.02481)
			(xy 90.243418 -35.956548) (xy 90.30493 -35.893618) (xy 90.371911 -35.836544) (xy 90.443804 -35.785796)
			(xy 90.520013 -35.741796) (xy 90.599908 -35.704909) (xy 90.682827 -35.67544) (xy 90.768082 -35.653633)
			(xy 90.854966 -35.639669) (xy 90.94276 -35.633663) (xy 91.030737 -35.635667) (xy 91.118167 -35.645662)
			(xy 91.204326 -35.663566) (xy 91.2885 -35.68923) (xy 91.369991 -35.722443) (xy 91.448125 -35.762929)
			(xy 91.522253 -35.810351) (xy 91.591761 -35.864318) (xy 91.656075 -35.924383) (xy 91.714659 -35.990047)
			(xy 91.76703 -36.060766) (xy 91.812753 -36.135954) (xy 91.85145 -36.214989) (xy 91.882799 -36.297215)
			(xy 91.906541 -36.381951) (xy 91.922479 -36.468495) (xy 91.930481 -36.55613) (xy 91.930982 -36.60013)
			(xy 91.930481 -36.64413) (xy 91.922479 -36.731765) (xy 91.906541 -36.818309) (xy 91.882799 -36.903045)
			(xy 91.85145 -36.985271) (xy 91.812753 -37.064306) (xy 91.76703 -37.139494) (xy 91.714659 -37.210213)
			(xy 91.656075 -37.275877) (xy 91.591761 -37.335942) (xy 91.522253 -37.389909) (xy 91.448125 -37.437331)
			(xy 91.369991 -37.477817) (xy 91.2885 -37.51103) (xy 91.204326 -37.536694) (xy 91.118167 -37.554598)
			(xy 91.030737 -37.564593) (xy 90.94276 -37.566597) (xy 90.854966 -37.560591) (xy 90.768082 -37.546627)
			(xy 90.682827 -37.52482) (xy 90.599908 -37.495351) (xy 90.520013 -37.458464) (xy 90.443804 -37.414464)
			(xy 90.371911 -37.363716) (xy 90.30493 -37.306642) (xy 90.243418 -37.243712) (xy 90.187882 -37.17545)
			(xy 90.138784 -37.102421) (xy 90.096531 -37.025229) (xy 90.061472 -36.944515) (xy 90.033897 -36.860947)
			(xy 90.014037 -36.775218) (xy 90.002054 -36.688038) (xy 89.998049 -36.60013) (xy 85.768492 -36.60013)
			(xy 85.752881 -36.652017) (xy 85.729209 -36.702514) (xy 85.698436 -36.749027) (xy 85.661219 -36.790564)
			(xy 85.618351 -36.826239) (xy 85.570745 -36.855293) (xy 85.519416 -36.877105) (xy 85.465459 -36.891211)
			(xy 85.410022 -36.897311) (xy 85.354288 -36.895274) (xy 85.299445 -36.885144) (xy 85.246661 -36.867137)
			(xy 85.197061 -36.841636) (xy 85.151703 -36.809185) (xy 85.111554 -36.770476) (xy 85.077468 -36.726333)
			(xy 85.050172 -36.677698) (xy 85.030249 -36.625607) (xy 85.018123 -36.57117) (xy 85.014052 -36.515548)
			(xy 83.88785 -36.515548) (xy 83.884622 -36.520427) (xy 83.847405 -36.561964) (xy 83.804537 -36.597639)
			(xy 83.756931 -36.626693) (xy 83.705602 -36.648505) (xy 83.651645 -36.662611) (xy 83.596208 -36.668711)
			(xy 83.540474 -36.666674) (xy 83.485631 -36.656544) (xy 83.432847 -36.638537) (xy 83.383247 -36.613036)
			(xy 83.337889 -36.580585) (xy 83.29774 -36.541876) (xy 83.263654 -36.497733) (xy 83.236358 -36.449098)
			(xy 83.216435 -36.397007) (xy 83.204309 -36.34257) (xy 83.200238 -36.286948) (xy 80.957882 -36.286948)
			(xy 82.445017 -37.774118) (xy 83.464652 -37.774118) (xy 83.468723 -37.718496) (xy 83.480849 -37.664059)
			(xy 83.500772 -37.611968) (xy 83.528068 -37.563333) (xy 83.562154 -37.51919) (xy 83.602303 -37.480481)
			(xy 83.647661 -37.44803) (xy 83.697261 -37.422529) (xy 83.750045 -37.404522) (xy 83.804888 -37.394392)
			(xy 83.860622 -37.392355) (xy 83.916059 -37.398455) (xy 83.970016 -37.412561) (xy 84.021345 -37.434373)
			(xy 84.068951 -37.463427) (xy 84.111819 -37.499102) (xy 84.149036 -37.540639) (xy 84.179809 -37.587152)
			(xy 84.203481 -37.637649) (xy 84.219549 -37.691056) (xy 84.227669 -37.746232) (xy 84.228178 -37.774118)
			(xy 84.227669 -37.802004) (xy 84.219549 -37.85718) (xy 84.203481 -37.910587) (xy 84.179809 -37.961084)
			(xy 84.149036 -38.007597) (xy 84.111819 -38.049134) (xy 84.068951 -38.084809) (xy 84.021345 -38.113863)
			(xy 83.970016 -38.135675) (xy 83.916059 -38.149781) (xy 83.860622 -38.155881) (xy 83.804888 -38.153844)
			(xy 83.750045 -38.143714) (xy 83.697261 -38.125707) (xy 83.647661 -38.100206) (xy 83.602303 -38.067755)
			(xy 83.562154 -38.029046) (xy 83.528068 -37.984903) (xy 83.500772 -37.936268) (xy 83.480849 -37.884177)
			(xy 83.468723 -37.82974) (xy 83.464652 -37.774118) (xy 82.445017 -37.774118) (xy 85.939568 -41.268751)
			(xy 93.84385 -41.268751) (xy 93.84385 -41.214249) (xy 93.851606 -41.160301) (xy 93.86696 -41.108006)
			(xy 93.889599 -41.058428) (xy 93.919064 -41.012576) (xy 93.954753 -40.971384) (xy 93.995941 -40.93569)
			(xy 94.041789 -40.90622) (xy 94.091365 -40.883575) (xy 94.143658 -40.868215) (xy 94.197605 -40.860453)
			(xy 94.224856 -40.859964) (xy 94.253596 -40.860463) (xy 94.310424 -40.869093) (xy 94.365314 -40.88615)
			(xy 94.417026 -40.911246) (xy 94.464387 -40.943816) (xy 94.485714 -40.963088) (xy 94.492572 -40.969692)
			(xy 94.510606 -40.976804) (xy 94.599506 -40.976804) (xy 94.61754 -40.969692) (xy 94.624398 -40.963088)
			(xy 94.645709 -40.943799) (xy 94.693075 -40.911233) (xy 94.74479 -40.886143) (xy 94.799685 -40.869097)
			(xy 94.856516 -40.860481) (xy 94.885256 -40.859964) (xy 94.912509 -40.86048) (xy 94.966461 -40.868232)
			(xy 95.01876 -40.883583) (xy 95.068342 -40.906221) (xy 95.114197 -40.935686) (xy 95.155392 -40.971377)
			(xy 95.191088 -41.012567) (xy 95.220558 -41.058419) (xy 95.243202 -41.107999) (xy 95.258559 -41.160296)
			(xy 95.266317 -41.214247) (xy 95.266317 -41.268753) (xy 95.258559 -41.322704) (xy 95.243202 -41.375001)
			(xy 95.220558 -41.424581) (xy 95.191088 -41.470433) (xy 95.155392 -41.511623) (xy 95.114197 -41.547314)
			(xy 95.068342 -41.576779) (xy 95.01876 -41.599417) (xy 94.966461 -41.614768) (xy 94.912509 -41.62252)
			(xy 94.885256 -41.62298) (xy 94.856517 -41.622462) (xy 94.79969 -41.613834) (xy 94.744801 -41.596782)
			(xy 94.693089 -41.57169) (xy 94.645726 -41.539126) (xy 94.624398 -41.519856) (xy 94.61754 -41.513252)
			(xy 94.599506 -41.50614) (xy 94.510606 -41.50614) (xy 94.492572 -41.513252) (xy 94.485714 -41.519856)
			(xy 94.464404 -41.539147) (xy 94.417038 -41.57171) (xy 94.365322 -41.596799) (xy 94.310427 -41.613845)
			(xy 94.253596 -41.622462) (xy 94.224856 -41.62298) (xy 94.197605 -41.622547) (xy 94.143658 -41.614785)
			(xy 94.091365 -41.599425) (xy 94.041789 -41.57678) (xy 93.995941 -41.54731) (xy 93.954753 -41.511616)
			(xy 93.919064 -41.470424) (xy 93.889599 -41.424572) (xy 93.86696 -41.374994) (xy 93.851606 -41.322699)
			(xy 93.84385 -41.268751) (xy 85.939568 -41.268751) (xy 87.975991 -43.305222) (xy 96.307148 -43.305222)
			(xy 96.307615 -43.277852) (xy 96.315431 -43.223672) (xy 96.330919 -43.171169) (xy 96.353761 -43.121422)
			(xy 96.383486 -43.075455) (xy 96.401128 -43.054524) (xy 96.401382 -43.05427) (xy 96.406943 -43.047166)
			(xy 96.413205 -43.030263) (xy 96.413574 -43.02125) (xy 96.413574 -42.954194) (xy 96.413226 -42.945176)
			(xy 96.406973 -42.928259) (xy 96.401382 -42.921174) (xy 96.401128 -42.921174) (xy 96.401128 -42.92092)
			(xy 96.383489 -42.899988) (xy 96.353776 -42.854015) (xy 96.33094 -42.804268) (xy 96.315449 -42.751767)
			(xy 96.307621 -42.697591) (xy 96.307148 -42.670222) (xy 96.307699 -42.641484) (xy 96.316317 -42.584659)
			(xy 96.333362 -42.529769) (xy 96.358447 -42.478057) (xy 96.391005 -42.430692) (xy 96.410272 -42.409364)
			(xy 96.416876 -42.402506) (xy 96.423988 -42.384472) (xy 96.423988 -42.295572) (xy 96.416876 -42.277538)
			(xy 96.410272 -42.27068) (xy 96.391025 -42.249333) (xy 96.358464 -42.201973) (xy 96.333374 -42.150264)
			(xy 96.316325 -42.095377) (xy 96.307702 -42.038553) (xy 96.307699 -41.981079) (xy 96.316318 -41.924255)
			(xy 96.333363 -41.869366) (xy 96.358448 -41.817655) (xy 96.391005 -41.770292) (xy 96.410272 -41.748964)
			(xy 96.416876 -41.742106) (xy 96.423988 -41.724072) (xy 96.423988 -41.635172) (xy 96.416876 -41.617138)
			(xy 96.410272 -41.61028) (xy 96.391017 -41.588939) (xy 96.358448 -41.541581) (xy 96.333351 -41.489873)
			(xy 96.316297 -41.434985) (xy 96.307671 -41.37816) (xy 96.307148 -41.349422) (xy 96.307634 -41.322171)
			(xy 96.31539 -41.268223) (xy 96.330745 -41.215928) (xy 96.353387 -41.166351) (xy 96.382853 -41.120501)
			(xy 96.418544 -41.07931) (xy 96.459735 -41.043619) (xy 96.505585 -41.014153) (xy 96.555162 -40.991511)
			(xy 96.607457 -40.976156) (xy 96.661405 -40.9684) (xy 96.715907 -40.9684) (xy 96.769855 -40.976156)
			(xy 96.82215 -40.991511) (xy 96.871727 -41.014153) (xy 96.917577 -41.043619) (xy 96.958768 -41.07931)
			(xy 96.994459 -41.120501) (xy 97.023925 -41.166351) (xy 97.046567 -41.215928) (xy 97.061922 -41.268223)
			(xy 97.069678 -41.322171) (xy 97.070164 -41.349422) (xy 97.069637 -41.378161) (xy 97.061012 -41.434987)
			(xy 97.043962 -41.489877) (xy 97.018872 -41.541589) (xy 96.986309 -41.588952) (xy 96.96704 -41.61028)
			(xy 96.960436 -41.617138) (xy 96.953324 -41.635172) (xy 96.953324 -41.724072) (xy 96.960436 -41.742106)
			(xy 96.96704 -41.748964) (xy 96.986334 -41.770271) (xy 97.018902 -41.817636) (xy 97.043995 -41.869351)
			(xy 97.061045 -41.924245) (xy 97.069666 -41.981076) (xy 97.069664 -42.038557) (xy 97.061037 -42.095387)
			(xy 97.043983 -42.150279) (xy 97.018886 -42.201992) (xy 96.986314 -42.249354) (xy 96.96704 -42.27068)
			(xy 96.960436 -42.277538) (xy 96.953324 -42.295572) (xy 96.953324 -42.384472) (xy 96.960436 -42.402506)
			(xy 96.96704 -42.409364) (xy 96.986318 -42.430685) (xy 97.018884 -42.478048) (xy 97.043975 -42.529761)
			(xy 97.061024 -42.584654) (xy 97.069645 -42.641483) (xy 97.070164 -42.670222) (xy 97.06972 -42.697593)
			(xy 97.061898 -42.751773) (xy 97.046404 -42.804277) (xy 97.025847 -42.849038) (xy 98.89185 -42.849038)
			(xy 98.895921 -42.793416) (xy 98.908047 -42.738979) (xy 98.92797 -42.686888) (xy 98.955266 -42.638253)
			(xy 98.989352 -42.59411) (xy 99.029501 -42.555401) (xy 99.074859 -42.52295) (xy 99.124459 -42.497449)
			(xy 99.177243 -42.479442) (xy 99.232086 -42.469312) (xy 99.28782 -42.467275) (xy 99.343257 -42.473375)
			(xy 99.397214 -42.487481) (xy 99.448543 -42.509293) (xy 99.496149 -42.538347) (xy 99.539017 -42.574022)
			(xy 99.576234 -42.615559) (xy 99.607007 -42.662072) (xy 99.630679 -42.712569) (xy 99.646747 -42.765976)
			(xy 99.654867 -42.821152) (xy 99.655228 -42.84091) (xy 104.932986 -42.84091) (xy 104.937057 -42.785288)
			(xy 104.949183 -42.730851) (xy 104.969106 -42.67876) (xy 104.996402 -42.630125) (xy 105.030488 -42.585982)
			(xy 105.070637 -42.547273) (xy 105.115995 -42.514822) (xy 105.165595 -42.489321) (xy 105.218379 -42.471314)
			(xy 105.273222 -42.461184) (xy 105.328956 -42.459147) (xy 105.384393 -42.465247) (xy 105.43835 -42.479353)
			(xy 105.489679 -42.501165) (xy 105.537285 -42.530219) (xy 105.580153 -42.565894) (xy 105.61737 -42.607431)
			(xy 105.648143 -42.653944) (xy 105.671815 -42.704441) (xy 105.687883 -42.757848) (xy 105.696003 -42.813024)
			(xy 105.696512 -42.84091) (xy 105.696003 -42.868796) (xy 105.687883 -42.923972) (xy 105.671815 -42.977379)
			(xy 105.648143 -43.027876) (xy 105.61737 -43.074389) (xy 105.580153 -43.115926) (xy 105.537285 -43.151601)
			(xy 105.489679 -43.180655) (xy 105.43835 -43.202467) (xy 105.384393 -43.216573) (xy 105.328956 -43.222673)
			(xy 105.273222 -43.220636) (xy 105.218379 -43.210506) (xy 105.165595 -43.192499) (xy 105.115995 -43.166998)
			(xy 105.070637 -43.134547) (xy 105.030488 -43.095838) (xy 104.996402 -43.051695) (xy 104.969106 -43.00306)
			(xy 104.949183 -42.950969) (xy 104.937057 -42.896532) (xy 104.932986 -42.84091) (xy 99.655228 -42.84091)
			(xy 99.655376 -42.849038) (xy 99.654867 -42.876924) (xy 99.646747 -42.9321) (xy 99.630679 -42.985507)
			(xy 99.607007 -43.036004) (xy 99.576234 -43.082517) (xy 99.539017 -43.124054) (xy 99.496149 -43.159729)
			(xy 99.448543 -43.188783) (xy 99.397214 -43.210595) (xy 99.343257 -43.224701) (xy 99.28782 -43.230801)
			(xy 99.232086 -43.228764) (xy 99.177243 -43.218634) (xy 99.124459 -43.200627) (xy 99.074859 -43.175126)
			(xy 99.029501 -43.142675) (xy 98.989352 -43.103966) (xy 98.955266 -43.059823) (xy 98.92797 -43.011188)
			(xy 98.908047 -42.959097) (xy 98.895921 -42.90466) (xy 98.89185 -42.849038) (xy 97.025847 -42.849038)
			(xy 97.023557 -42.854024) (xy 96.993828 -42.899989) (xy 96.976184 -42.92092) (xy 96.97593 -42.921174)
			(xy 96.97034 -42.928258) (xy 96.964097 -42.945177) (xy 96.963738 -42.954194) (xy 96.963738 -43.02125)
			(xy 96.964111 -43.030265) (xy 96.970346 -43.047183) (xy 96.97593 -43.05427) (xy 96.976184 -43.05427)
			(xy 96.976184 -43.054524) (xy 96.993798 -43.075476) (xy 97.023515 -43.121443) (xy 97.046355 -43.171185)
			(xy 97.061852 -43.223682) (xy 97.069687 -43.277854) (xy 97.070164 -43.305222) (xy 97.069678 -43.332473)
			(xy 97.061922 -43.386421) (xy 97.046567 -43.438716) (xy 97.023925 -43.488293) (xy 96.994459 -43.534143)
			(xy 96.958768 -43.575334) (xy 96.917577 -43.611025) (xy 96.871727 -43.640491) (xy 96.82215 -43.663133)
			(xy 96.769855 -43.678488) (xy 96.715907 -43.686244) (xy 96.661405 -43.686244) (xy 96.607457 -43.678488)
			(xy 96.555162 -43.663133) (xy 96.505585 -43.640491) (xy 96.459735 -43.611025) (xy 96.418544 -43.575334)
			(xy 96.382853 -43.534143) (xy 96.353387 -43.488293) (xy 96.330745 -43.438716) (xy 96.31539 -43.386421)
			(xy 96.307634 -43.332473) (xy 96.307148 -43.305222) (xy 87.975991 -43.305222) (xy 88.407019 -43.73626)
			(xy 98.212908 -43.73626) (xy 98.216979 -43.680638) (xy 98.229105 -43.626201) (xy 98.249028 -43.57411)
			(xy 98.276324 -43.525475) (xy 98.31041 -43.481332) (xy 98.350559 -43.442623) (xy 98.395917 -43.410172)
			(xy 98.445517 -43.384671) (xy 98.498301 -43.366664) (xy 98.553144 -43.356534) (xy 98.608878 -43.354497)
			(xy 98.664315 -43.360597) (xy 98.718272 -43.374703) (xy 98.769601 -43.396515) (xy 98.817207 -43.425569)
			(xy 98.860075 -43.461244) (xy 98.897292 -43.502781) (xy 98.928065 -43.549294) (xy 98.951737 -43.599791)
			(xy 98.967805 -43.653198) (xy 98.975925 -43.708374) (xy 98.976434 -43.73626) (xy 98.975925 -43.764146)
			(xy 98.967805 -43.819322) (xy 98.956496 -43.85691) (xy 102.71963 -43.85691) (xy 102.723701 -43.801288)
			(xy 102.735827 -43.746851) (xy 102.75575 -43.69476) (xy 102.783046 -43.646125) (xy 102.817132 -43.601982)
			(xy 102.857281 -43.563273) (xy 102.902639 -43.530822) (xy 102.952239 -43.505321) (xy 103.005023 -43.487314)
			(xy 103.059866 -43.477184) (xy 103.1156 -43.475147) (xy 103.171037 -43.481247) (xy 103.224994 -43.495353)
			(xy 103.276323 -43.517165) (xy 103.323929 -43.546219) (xy 103.366797 -43.581894) (xy 103.404014 -43.623431)
			(xy 103.434787 -43.669944) (xy 103.458459 -43.720441) (xy 103.474527 -43.773848) (xy 103.482647 -43.829024)
			(xy 103.483156 -43.85691) (xy 103.482647 -43.884796) (xy 103.474527 -43.939972) (xy 103.458459 -43.993379)
			(xy 103.434787 -44.043876) (xy 103.404014 -44.090389) (xy 103.366797 -44.131926) (xy 103.323929 -44.167601)
			(xy 103.276323 -44.196655) (xy 103.224994 -44.218467) (xy 103.171037 -44.232573) (xy 103.1156 -44.238673)
			(xy 103.059866 -44.236636) (xy 103.005023 -44.226506) (xy 102.952239 -44.208499) (xy 102.902639 -44.182998)
			(xy 102.857281 -44.150547) (xy 102.817132 -44.111838) (xy 102.783046 -44.067695) (xy 102.75575 -44.01906)
			(xy 102.735827 -43.966969) (xy 102.723701 -43.912532) (xy 102.71963 -43.85691) (xy 98.956496 -43.85691)
			(xy 98.951737 -43.872729) (xy 98.928065 -43.923226) (xy 98.897292 -43.969739) (xy 98.860075 -44.011276)
			(xy 98.817207 -44.046951) (xy 98.769601 -44.076005) (xy 98.718272 -44.097817) (xy 98.664315 -44.111923)
			(xy 98.608878 -44.118023) (xy 98.553144 -44.115986) (xy 98.498301 -44.105856) (xy 98.445517 -44.087849)
			(xy 98.395917 -44.062348) (xy 98.350559 -44.029897) (xy 98.31041 -43.991188) (xy 98.276324 -43.947045)
			(xy 98.249028 -43.89841) (xy 98.229105 -43.846319) (xy 98.216979 -43.791882) (xy 98.212908 -43.73626)
			(xy 88.407019 -43.73626) (xy 89.78519 -45.114464) (xy 98.065334 -45.114464) (xy 98.069405 -45.058842)
			(xy 98.081531 -45.004405) (xy 98.101454 -44.952314) (xy 98.12875 -44.903679) (xy 98.162836 -44.859536)
			(xy 98.202985 -44.820827) (xy 98.248343 -44.788376) (xy 98.297943 -44.762875) (xy 98.350727 -44.744868)
			(xy 98.40557 -44.734738) (xy 98.461304 -44.732701) (xy 98.516741 -44.738801) (xy 98.570698 -44.752907)
			(xy 98.622027 -44.774719) (xy 98.669633 -44.803773) (xy 98.712501 -44.839448) (xy 98.742483 -44.87291)
			(xy 104.932986 -44.87291) (xy 104.937057 -44.817288) (xy 104.949183 -44.762851) (xy 104.969106 -44.71076)
			(xy 104.996402 -44.662125) (xy 105.030488 -44.617982) (xy 105.070637 -44.579273) (xy 105.115995 -44.546822)
			(xy 105.165595 -44.521321) (xy 105.218379 -44.503314) (xy 105.273222 -44.493184) (xy 105.328956 -44.491147)
			(xy 105.384393 -44.497247) (xy 105.43835 -44.511353) (xy 105.489679 -44.533165) (xy 105.537285 -44.562219)
			(xy 105.580153 -44.597894) (xy 105.61737 -44.639431) (xy 105.648143 -44.685944) (xy 105.671815 -44.736441)
			(xy 105.687883 -44.789848) (xy 105.696003 -44.845024) (xy 105.696512 -44.87291) (xy 105.696003 -44.900796)
			(xy 105.687883 -44.955972) (xy 105.671815 -45.009379) (xy 105.648143 -45.059876) (xy 105.61737 -45.106389)
			(xy 105.580153 -45.147926) (xy 105.537285 -45.183601) (xy 105.489679 -45.212655) (xy 105.43835 -45.234467)
			(xy 105.384393 -45.248573) (xy 105.328956 -45.254673) (xy 105.273222 -45.252636) (xy 105.218379 -45.242506)
			(xy 105.165595 -45.224499) (xy 105.115995 -45.198998) (xy 105.070637 -45.166547) (xy 105.030488 -45.127838)
			(xy 104.996402 -45.083695) (xy 104.969106 -45.03506) (xy 104.949183 -44.982969) (xy 104.937057 -44.928532)
			(xy 104.932986 -44.87291) (xy 98.742483 -44.87291) (xy 98.749718 -44.880985) (xy 98.780491 -44.927498)
			(xy 98.804163 -44.977995) (xy 98.820231 -45.031402) (xy 98.828351 -45.086578) (xy 98.82886 -45.114464)
			(xy 98.828351 -45.14235) (xy 98.820231 -45.197526) (xy 98.804163 -45.250933) (xy 98.780491 -45.30143)
			(xy 98.749718 -45.347943) (xy 98.744076 -45.35424) (xy 102.703628 -45.35424) (xy 102.707699 -45.298618)
			(xy 102.719825 -45.244181) (xy 102.739748 -45.19209) (xy 102.767044 -45.143455) (xy 102.80113 -45.099312)
			(xy 102.841279 -45.060603) (xy 102.886637 -45.028152) (xy 102.936237 -45.002651) (xy 102.989021 -44.984644)
			(xy 103.043864 -44.974514) (xy 103.099598 -44.972477) (xy 103.155035 -44.978577) (xy 103.208992 -44.992683)
			(xy 103.260321 -45.014495) (xy 103.307927 -45.043549) (xy 103.350795 -45.079224) (xy 103.388012 -45.120761)
			(xy 103.418785 -45.167274) (xy 103.442457 -45.217771) (xy 103.458525 -45.271178) (xy 103.466645 -45.326354)
			(xy 103.467154 -45.35424) (xy 103.466645 -45.382126) (xy 103.458525 -45.437302) (xy 103.442457 -45.490709)
			(xy 103.418785 -45.541206) (xy 103.388012 -45.587719) (xy 103.350795 -45.629256) (xy 103.307927 -45.664931)
			(xy 103.260321 -45.693985) (xy 103.208992 -45.715797) (xy 103.155035 -45.729903) (xy 103.099598 -45.736003)
			(xy 103.043864 -45.733966) (xy 102.989021 -45.723836) (xy 102.936237 -45.705829) (xy 102.886637 -45.680328)
			(xy 102.841279 -45.647877) (xy 102.80113 -45.609168) (xy 102.767044 -45.565025) (xy 102.739748 -45.51639)
			(xy 102.719825 -45.464299) (xy 102.707699 -45.409862) (xy 102.703628 -45.35424) (xy 98.744076 -45.35424)
			(xy 98.712501 -45.38948) (xy 98.669633 -45.425155) (xy 98.622027 -45.454209) (xy 98.570698 -45.476021)
			(xy 98.516741 -45.490127) (xy 98.461304 -45.496227) (xy 98.40557 -45.49419) (xy 98.350727 -45.48406)
			(xy 98.297943 -45.466053) (xy 98.248343 -45.440552) (xy 98.202985 -45.408101) (xy 98.162836 -45.369392)
			(xy 98.12875 -45.325249) (xy 98.101454 -45.276614) (xy 98.081531 -45.224523) (xy 98.069405 -45.170086)
			(xy 98.065334 -45.114464) (xy 89.78519 -45.114464) (xy 89.80297 -45.132244) (xy 89.827877 -45.157883)
			(xy 89.871957 -45.214156) (xy 89.90892 -45.27534) (xy 89.938227 -45.340539) (xy 89.959447 -45.408799)
			(xy 89.972272 -45.479122) (xy 89.974928 -45.514768) (xy 90.008954 -46.082204) (xy 96.052386 -46.082204)
			(xy 96.052881 -46.054953) (xy 96.060637 -46.001006) (xy 96.075992 -45.948712) (xy 96.098632 -45.899135)
			(xy 96.128097 -45.853285) (xy 96.163788 -45.812095) (xy 96.204977 -45.776403) (xy 96.250826 -45.746937)
			(xy 96.300402 -45.724295) (xy 96.352696 -45.708939) (xy 96.406643 -45.701182) (xy 96.433894 -45.700696)
			(xy 96.460796 -45.701163) (xy 96.514066 -45.708734) (xy 96.565744 -45.723712) (xy 96.614806 -45.745802)
			(xy 96.660279 -45.774563) (xy 96.70126 -45.809427) (xy 96.736938 -45.849702) (xy 96.752156 -45.871892)
			(xy 96.759268 -45.882814) (xy 96.782128 -45.894752) (xy 96.894396 -45.89272) (xy 96.916748 -45.879766)
			(xy 96.923606 -45.86859) (xy 96.938537 -45.844995) (xy 96.974214 -45.802043) (xy 97.015771 -45.76475)
			(xy 97.06232 -45.733912) (xy 97.112865 -45.710187) (xy 97.166329 -45.694083) (xy 97.22157 -45.685943)
			(xy 97.249488 -45.685456) (xy 97.276481 -45.685924) (xy 97.329929 -45.693528) (xy 97.381772 -45.708587)
			(xy 97.430977 -45.730799) (xy 97.476561 -45.759723) (xy 97.497392 -45.776896) (xy 97.50552 -45.784008)
			(xy 97.526094 -45.790104) (xy 97.611438 -45.779182) (xy 97.621978 -45.777387) (xy 97.640263 -45.766348)
			(xy 97.646744 -45.757846) (xy 97.662076 -45.7366) (xy 97.697667 -45.698147) (xy 97.738188 -45.66493)
			(xy 97.782874 -45.637573) (xy 97.830886 -45.616592) (xy 97.881318 -45.602382) (xy 97.93322 -45.595211)
			(xy 97.959418 -45.594778) (xy 97.986667 -45.595293) (xy 98.040611 -45.603052) (xy 98.092902 -45.618408)
			(xy 98.142475 -45.641049) (xy 98.188321 -45.670515) (xy 98.229508 -45.706205) (xy 98.265196 -45.747393)
			(xy 98.294659 -45.793241) (xy 98.317298 -45.842815) (xy 98.332652 -45.895106) (xy 98.340408 -45.949051)
			(xy 98.340408 -46.003549) (xy 98.332652 -46.057493) (xy 98.317298 -46.109785) (xy 98.294659 -46.159359)
			(xy 98.265196 -46.205207) (xy 98.229508 -46.246395) (xy 98.188321 -46.282085) (xy 98.142475 -46.311551)
			(xy 98.092902 -46.334192) (xy 98.040611 -46.349548) (xy 97.986667 -46.357307) (xy 97.959418 -46.357794)
			(xy 97.932426 -46.357311) (xy 97.878979 -46.349708) (xy 97.827136 -46.334653) (xy 97.777931 -46.312444)
			(xy 97.732346 -46.283525) (xy 97.711514 -46.266354) (xy 97.703386 -46.259242) (xy 97.682812 -46.253146)
			(xy 97.597468 -46.264068) (xy 97.586922 -46.265834) (xy 97.568641 -46.276896) (xy 97.562162 -46.285404)
			(xy 97.544551 -46.309706) (xy 97.502954 -46.352964) (xy 97.479358 -46.37151) (xy 97.471484 -46.377352)
			(xy 97.46107 -46.394878) (xy 97.447862 -46.485302) (xy 97.452688 -46.504606) (xy 97.45853 -46.51248)
			(xy 97.45853 -46.512734) (xy 97.476028 -46.537482) (xy 97.503833 -46.591333) (xy 97.522771 -46.648904)
			(xy 97.532364 -46.708745) (xy 97.532952 -46.739048) (xy 97.532467 -46.766298) (xy 97.524705 -46.820244)
			(xy 97.509346 -46.872536) (xy 97.486703 -46.92211) (xy 97.457235 -46.967958) (xy 97.421544 -47.009147)
			(xy 97.380355 -47.044838) (xy 97.334507 -47.074304) (xy 97.284932 -47.096947) (xy 97.23264 -47.112306)
			(xy 97.178694 -47.120067) (xy 97.151444 -47.120556) (xy 97.12541 -47.120133) (xy 97.073826 -47.113039)
			(xy 97.023684 -47.099004) (xy 96.975913 -47.078288) (xy 96.9314 -47.051275) (xy 96.910906 -47.035212)
			(xy 96.903154 -47.029462) (xy 96.884739 -47.023726) (xy 96.875092 -47.024036) (xy 96.795336 -47.030386)
			(xy 96.777556 -47.039022) (xy 96.771206 -47.046388) (xy 96.753045 -47.066053) (xy 96.712133 -47.100573)
			(xy 96.6668 -47.12904) (xy 96.617935 -47.150894) (xy 96.566495 -47.165708) (xy 96.513491 -47.173189)
			(xy 96.486726 -47.173642) (xy 96.459477 -47.173098) (xy 96.405533 -47.165346) (xy 96.353242 -47.149995)
			(xy 96.303667 -47.12736) (xy 96.257818 -47.0979) (xy 96.216628 -47.062214) (xy 96.180936 -47.02103)
			(xy 96.151469 -46.975186) (xy 96.128826 -46.925615) (xy 96.113467 -46.873326) (xy 96.105707 -46.819383)
			(xy 96.105218 -46.792134) (xy 96.105738 -46.76336) (xy 96.114389 -46.706465) (xy 96.131486 -46.651514)
			(xy 96.156641 -46.599754) (xy 96.189283 -46.552359) (xy 96.208596 -46.531022) (xy 96.215962 -46.523148)
			(xy 96.223074 -46.503336) (xy 96.215708 -46.40707) (xy 96.205802 -46.388274) (xy 96.19742 -46.38167)
			(xy 96.175235 -46.363445) (xy 96.136025 -46.32151) (xy 96.10354 -46.274174) (xy 96.078511 -46.222506)
			(xy 96.061505 -46.167672) (xy 96.052904 -46.110909) (xy 96.052386 -46.082204) (xy 90.008954 -46.082204)
			(xy 90.142361 -48.30699) (xy 102.554278 -48.30699) (xy 102.554823 -48.278329) (xy 102.563428 -48.221656)
			(xy 102.580413 -48.166908) (xy 102.605395 -48.115315) (xy 102.637813 -48.06804) (xy 102.676937 -48.026146)
			(xy 102.721888 -47.990574) (xy 102.771653 -47.962126) (xy 102.825113 -47.941441) (xy 102.881066 -47.928985)
			(xy 102.909624 -47.926498) (xy 102.909878 -47.926498) (xy 102.919502 -47.925384) (xy 102.936913 -47.916914)
			(xy 102.949985 -47.902631) (xy 102.95382 -47.893732) (xy 102.986332 -47.807118) (xy 102.989241 -47.797812)
			(xy 102.988695 -47.778341) (xy 102.980985 -47.760453) (xy 102.974394 -47.75327) (xy 102.96652 -47.745396)
			(xy 102.944538 -47.722658) (xy 102.906082 -47.672447) (xy 102.874505 -47.617648) (xy 102.850345 -47.559199)
			(xy 102.834016 -47.498098) (xy 102.825797 -47.435389) (xy 102.825296 -47.403766) (xy 102.825832 -47.371476)
			(xy 102.834415 -47.307468) (xy 102.851448 -47.245175) (xy 102.87663 -47.185706) (xy 102.892606 -47.15764)
			(xy 102.892606 -47.157386) (xy 102.897183 -47.148668) (xy 102.900059 -47.129208) (xy 102.898194 -47.11954)
			(xy 102.878636 -47.040546) (xy 102.866698 -47.02429) (xy 102.858316 -47.01921) (xy 102.834825 -47.004261)
			(xy 102.792099 -46.968557) (xy 102.755014 -46.927023) (xy 102.724357 -46.880542) (xy 102.700778 -46.8301)
			(xy 102.684779 -46.776768) (xy 102.676698 -46.721676) (xy 102.676198 -46.693836) (xy 102.676684 -46.666585)
			(xy 102.68444 -46.612637) (xy 102.699795 -46.560342) (xy 102.722437 -46.510765) (xy 102.751903 -46.464915)
			(xy 102.787594 -46.423724) (xy 102.828785 -46.388033) (xy 102.874635 -46.358567) (xy 102.924212 -46.335925)
			(xy 102.976507 -46.32057) (xy 103.030455 -46.312814) (xy 103.084957 -46.312814) (xy 103.138905 -46.32057)
			(xy 103.1912 -46.335925) (xy 103.240777 -46.358567) (xy 103.286627 -46.388033) (xy 103.327818 -46.423724)
			(xy 103.363509 -46.464915) (xy 103.392975 -46.510765) (xy 103.415617 -46.560342) (xy 103.430972 -46.612637)
			(xy 103.438728 -46.666585) (xy 103.439214 -46.693836) (xy 103.439214 -46.694344) (xy 103.438533 -46.726939)
			(xy 103.427427 -46.791177) (xy 103.417116 -46.822106) (xy 103.413814 -46.831504) (xy 103.414576 -46.85157)
			(xy 103.453184 -46.934374) (xy 103.467662 -46.947836) (xy 103.476806 -46.951392) (xy 103.477314 -46.951392)
			(xy 103.509363 -46.964005) (xy 103.569823 -46.996991) (xy 103.62498 -47.038236) (xy 103.64978 -47.062136)
			(xy 104.029256 -47.441612) (xy 104.961688 -47.441612) (xy 104.965759 -47.38599) (xy 104.977885 -47.331553)
			(xy 104.997808 -47.279462) (xy 105.025104 -47.230827) (xy 105.05919 -47.186684) (xy 105.099339 -47.147975)
			(xy 105.144697 -47.115524) (xy 105.194297 -47.090023) (xy 105.247081 -47.072016) (xy 105.301924 -47.061886)
			(xy 105.357658 -47.059849) (xy 105.413095 -47.065949) (xy 105.467052 -47.080055) (xy 105.518381 -47.101867)
			(xy 105.565987 -47.130921) (xy 105.608855 -47.166596) (xy 105.646072 -47.208133) (xy 105.676845 -47.254646)
			(xy 105.700517 -47.305143) (xy 105.716585 -47.35855) (xy 105.724705 -47.413726) (xy 105.725214 -47.441612)
			(xy 105.724705 -47.469498) (xy 105.716585 -47.524674) (xy 105.700517 -47.578081) (xy 105.676845 -47.628578)
			(xy 105.646072 -47.675091) (xy 105.608855 -47.716628) (xy 105.565987 -47.752303) (xy 105.518381 -47.781357)
			(xy 105.467052 -47.803169) (xy 105.413095 -47.817275) (xy 105.357658 -47.823375) (xy 105.301924 -47.821338)
			(xy 105.247081 -47.811208) (xy 105.194297 -47.793201) (xy 105.144697 -47.7677) (xy 105.099339 -47.735249)
			(xy 105.05919 -47.69654) (xy 105.025104 -47.652397) (xy 104.997808 -47.603762) (xy 104.977885 -47.551671)
			(xy 104.965759 -47.497234) (xy 104.961688 -47.441612) (xy 104.029256 -47.441612) (xy 104.777286 -48.189642)
			(xy 104.79928 -48.212381) (xy 104.837784 -48.262576) (xy 104.86941 -48.317365) (xy 104.893615 -48.375813)
			(xy 104.909987 -48.43692) (xy 104.918245 -48.499641) (xy 104.918764 -48.531272) (xy 104.918764 -48.554132)
			(xy 104.919167 -48.563629) (xy 104.926011 -48.581343) (xy 104.938853 -48.595332) (xy 104.947212 -48.599852)
			(xy 105.029 -48.639984) (xy 105.037648 -48.64382) (xy 105.056484 -48.645451) (xy 105.074623 -48.640123)
			(xy 105.08234 -48.63465) (xy 105.102418 -48.619688) (xy 105.145738 -48.594577) (xy 105.191973 -48.575356)
			(xy 105.240327 -48.562354) (xy 105.289968 -48.555798) (xy 105.315004 -48.555402) (xy 105.342256 -48.555868)
			(xy 105.396204 -48.563625) (xy 105.4485 -48.578981) (xy 105.498078 -48.601623) (xy 105.543929 -48.63109)
			(xy 105.58512 -48.666783) (xy 105.620812 -48.707974) (xy 105.650279 -48.753825) (xy 105.67292 -48.803404)
			(xy 105.688276 -48.855699) (xy 105.696032 -48.909648) (xy 105.696032 -48.964152) (xy 105.688276 -49.018101)
			(xy 105.67292 -49.070396) (xy 105.650279 -49.119975) (xy 105.620812 -49.165826) (xy 105.58512 -49.207017)
			(xy 105.543929 -49.24271) (xy 105.498078 -49.272177) (xy 105.4485 -49.294819) (xy 105.396204 -49.310175)
			(xy 105.342256 -49.317932) (xy 105.315004 -49.318418) (xy 105.289968 -49.318023) (xy 105.240329 -49.311458)
			(xy 105.191975 -49.298456) (xy 105.145739 -49.279238) (xy 105.102415 -49.254135) (xy 105.08234 -49.23917)
			(xy 105.074628 -49.233694) (xy 105.056485 -49.228383) (xy 105.037651 -49.230008) (xy 105.029 -49.233836)
			(xy 104.947212 -49.273968) (xy 104.938877 -49.278521) (xy 104.926059 -49.292517) (xy 104.919163 -49.310199)
			(xy 104.918764 -49.319688) (xy 104.918764 -49.570132) (xy 104.919167 -49.579629) (xy 104.926011 -49.597343)
			(xy 104.938853 -49.611332) (xy 104.947212 -49.615852) (xy 105.029 -49.655984) (xy 105.037648 -49.65982)
			(xy 105.056484 -49.661451) (xy 105.074623 -49.656123) (xy 105.08234 -49.65065) (xy 105.102418 -49.635688)
			(xy 105.145738 -49.610577) (xy 105.191973 -49.591356) (xy 105.240327 -49.578354) (xy 105.289968 -49.571798)
			(xy 105.315004 -49.571402) (xy 105.342256 -49.571868) (xy 105.396204 -49.579625) (xy 105.4485 -49.594981)
			(xy 105.498078 -49.617623) (xy 105.543929 -49.64709) (xy 105.58512 -49.682783) (xy 105.620812 -49.723974)
			(xy 105.650279 -49.769825) (xy 105.67292 -49.819404) (xy 105.688276 -49.871699) (xy 105.696032 -49.925648)
			(xy 105.696032 -49.980152) (xy 105.688276 -50.034101) (xy 105.67292 -50.086396) (xy 105.650279 -50.135975)
			(xy 105.620812 -50.181826) (xy 105.58512 -50.223017) (xy 105.543929 -50.25871) (xy 105.498078 -50.288177)
			(xy 105.4485 -50.310819) (xy 105.396204 -50.326175) (xy 105.342256 -50.333932) (xy 105.315004 -50.334418)
			(xy 105.289968 -50.334023) (xy 105.240329 -50.327458) (xy 105.191975 -50.314456) (xy 105.145739 -50.295238)
			(xy 105.102415 -50.270135) (xy 105.08234 -50.25517) (xy 105.074628 -50.249694) (xy 105.056485 -50.244383)
			(xy 105.037651 -50.246008) (xy 105.029 -50.249836) (xy 104.947212 -50.289968) (xy 104.938877 -50.294521)
			(xy 104.926059 -50.308517) (xy 104.919163 -50.326199) (xy 104.918764 -50.335688) (xy 104.918764 -51.375818)
			(xy 104.919163 -51.385891) (xy 104.9269 -51.404489) (xy 104.93375 -51.411886) (xy 105.059226 -51.537362)
			(xy 105.066627 -51.544201) (xy 105.085225 -51.551922) (xy 105.095294 -51.552348) (xy 105.323132 -51.552348)
			(xy 105.354758 -51.552955) (xy 105.41747 -51.561215) (xy 105.478566 -51.57759) (xy 105.537003 -51.601799)
			(xy 105.59178 -51.633427) (xy 105.641961 -51.671935) (xy 105.686686 -51.716663) (xy 105.72519 -51.766846)
			(xy 105.756816 -51.821626) (xy 105.781021 -51.880064) (xy 105.797391 -51.941162) (xy 105.805647 -52.003874)
			(xy 105.805647 -52.067126) (xy 105.797391 -52.129838) (xy 105.781021 -52.190936) (xy 105.756816 -52.249374)
			(xy 105.72519 -52.304154) (xy 105.686686 -52.354337) (xy 105.641961 -52.399065) (xy 105.59178 -52.437573)
			(xy 105.537003 -52.469201) (xy 105.478566 -52.49341) (xy 105.41747 -52.509785) (xy 105.354758 -52.518045)
			(xy 105.323132 -52.518564) (xy 104.87406 -52.518564) (xy 104.842427 -52.518038) (xy 104.779702 -52.509798)
			(xy 104.718589 -52.493438) (xy 104.660135 -52.469238) (xy 104.605343 -52.437612) (xy 104.555148 -52.399103)
			(xy 104.53243 -52.377086) (xy 104.094026 -51.938682) (xy 104.072046 -51.91593) (xy 104.03354 -51.865739)
			(xy 104.001912 -51.810952) (xy 103.977704 -51.752506) (xy 103.961329 -51.691401) (xy 103.953068 -51.628682)
			(xy 103.952548 -51.597052) (xy 103.952548 -48.752506) (xy 103.952133 -48.742435) (xy 103.944406 -48.723837)
			(xy 103.937562 -48.716438) (xy 103.489506 -48.268128) (xy 103.482327 -48.261534) (xy 103.464408 -48.253892)
			(xy 103.444934 -48.253442) (xy 103.435658 -48.256444) (xy 103.349044 -48.288956) (xy 103.340112 -48.292742)
			(xy 103.325786 -48.305799) (xy 103.317363 -48.323257) (xy 103.316278 -48.332898) (xy 103.316278 -48.333152)
			(xy 103.313847 -48.361722) (xy 103.301422 -48.417698) (xy 103.280756 -48.471183) (xy 103.252315 -48.52097)
			(xy 103.21674 -48.565938) (xy 103.174832 -48.605072) (xy 103.127538 -48.63749) (xy 103.075922 -48.662461)
			(xy 103.02115 -48.679421) (xy 102.964455 -48.68799) (xy 102.935786 -48.688498) (xy 102.908534 -48.688035)
			(xy 102.854585 -48.680277) (xy 102.802289 -48.664919) (xy 102.752711 -48.642276) (xy 102.70686 -48.612807)
			(xy 102.66567 -48.577113) (xy 102.629979 -48.53592) (xy 102.600513 -48.490068) (xy 102.577872 -48.440488)
			(xy 102.562518 -48.388192) (xy 102.554763 -48.334242) (xy 102.554278 -48.30699) (xy 90.142361 -48.30699)
			(xy 90.169106 -48.753014) (xy 99.168202 -48.753014) (xy 99.172273 -48.697392) (xy 99.184399 -48.642955)
			(xy 99.204322 -48.590864) (xy 99.231618 -48.542229) (xy 99.265704 -48.498086) (xy 99.305853 -48.459377)
			(xy 99.351211 -48.426926) (xy 99.400811 -48.401425) (xy 99.453595 -48.383418) (xy 99.508438 -48.373288)
			(xy 99.564172 -48.371251) (xy 99.619609 -48.377351) (xy 99.673566 -48.391457) (xy 99.724895 -48.413269)
			(xy 99.772501 -48.442323) (xy 99.815369 -48.477998) (xy 99.852586 -48.519535) (xy 99.883359 -48.566048)
			(xy 99.907031 -48.616545) (xy 99.923099 -48.669952) (xy 99.931219 -48.725128) (xy 99.931728 -48.753014)
			(xy 99.931219 -48.7809) (xy 99.923099 -48.836076) (xy 99.920655 -48.8442) (xy 100.18725 -48.8442)
			(xy 100.191321 -48.788578) (xy 100.203447 -48.734141) (xy 100.22337 -48.68205) (xy 100.250666 -48.633415)
			(xy 100.284752 -48.589272) (xy 100.324901 -48.550563) (xy 100.370259 -48.518112) (xy 100.419859 -48.492611)
			(xy 100.472643 -48.474604) (xy 100.527486 -48.464474) (xy 100.58322 -48.462437) (xy 100.638657 -48.468537)
			(xy 100.692614 -48.482643) (xy 100.743943 -48.504455) (xy 100.791549 -48.533509) (xy 100.834417 -48.569184)
			(xy 100.871634 -48.610721) (xy 100.902407 -48.657234) (xy 100.926079 -48.707731) (xy 100.942147 -48.761138)
			(xy 100.950267 -48.816314) (xy 100.950776 -48.8442) (xy 100.950267 -48.872086) (xy 100.947269 -48.89246)
			(xy 101.213918 -48.89246) (xy 101.217989 -48.836838) (xy 101.230115 -48.782401) (xy 101.250038 -48.73031)
			(xy 101.277334 -48.681675) (xy 101.31142 -48.637532) (xy 101.351569 -48.598823) (xy 101.396927 -48.566372)
			(xy 101.446527 -48.540871) (xy 101.499311 -48.522864) (xy 101.554154 -48.512734) (xy 101.609888 -48.510697)
			(xy 101.665325 -48.516797) (xy 101.719282 -48.530903) (xy 101.770611 -48.552715) (xy 101.818217 -48.581769)
			(xy 101.861085 -48.617444) (xy 101.898302 -48.658981) (xy 101.929075 -48.705494) (xy 101.952747 -48.755991)
			(xy 101.968815 -48.809398) (xy 101.976935 -48.864574) (xy 101.977444 -48.89246) (xy 101.976935 -48.920346)
			(xy 101.968815 -48.975522) (xy 101.952747 -49.028929) (xy 101.929075 -49.079426) (xy 101.898302 -49.125939)
			(xy 101.861085 -49.167476) (xy 101.818217 -49.203151) (xy 101.770611 -49.232205) (xy 101.719282 -49.254017)
			(xy 101.665325 -49.268123) (xy 101.609888 -49.274223) (xy 101.554154 -49.272186) (xy 101.499311 -49.262056)
			(xy 101.446527 -49.244049) (xy 101.396927 -49.218548) (xy 101.351569 -49.186097) (xy 101.31142 -49.147388)
			(xy 101.277334 -49.103245) (xy 101.250038 -49.05461) (xy 101.230115 -49.002519) (xy 101.217989 -48.948082)
			(xy 101.213918 -48.89246) (xy 100.947269 -48.89246) (xy 100.942147 -48.927262) (xy 100.926079 -48.980669)
			(xy 100.902407 -49.031166) (xy 100.871634 -49.077679) (xy 100.834417 -49.119216) (xy 100.791549 -49.154891)
			(xy 100.743943 -49.183945) (xy 100.692614 -49.205757) (xy 100.638657 -49.219863) (xy 100.58322 -49.225963)
			(xy 100.527486 -49.223926) (xy 100.472643 -49.213796) (xy 100.419859 -49.195789) (xy 100.370259 -49.170288)
			(xy 100.324901 -49.137837) (xy 100.284752 -49.099128) (xy 100.250666 -49.054985) (xy 100.22337 -49.00635)
			(xy 100.203447 -48.954259) (xy 100.191321 -48.899822) (xy 100.18725 -48.8442) (xy 99.920655 -48.8442)
			(xy 99.907031 -48.889483) (xy 99.883359 -48.93998) (xy 99.852586 -48.986493) (xy 99.815369 -49.02803)
			(xy 99.772501 -49.063705) (xy 99.724895 -49.092759) (xy 99.673566 -49.114571) (xy 99.619609 -49.128677)
			(xy 99.564172 -49.134777) (xy 99.508438 -49.13274) (xy 99.453595 -49.12261) (xy 99.400811 -49.104603)
			(xy 99.351211 -49.079102) (xy 99.305853 -49.046651) (xy 99.265704 -49.007942) (xy 99.231618 -48.963799)
			(xy 99.204322 -48.915164) (xy 99.184399 -48.863073) (xy 99.172273 -48.808636) (xy 99.168202 -48.753014)
			(xy 90.169106 -48.753014) (xy 90.30501 -51.019456) (xy 102.749348 -51.019456) (xy 102.753419 -50.963834)
			(xy 102.765545 -50.909397) (xy 102.785468 -50.857306) (xy 102.812764 -50.808671) (xy 102.84685 -50.764528)
			(xy 102.886999 -50.725819) (xy 102.932357 -50.693368) (xy 102.981957 -50.667867) (xy 103.034741 -50.64986)
			(xy 103.089584 -50.63973) (xy 103.145318 -50.637693) (xy 103.200755 -50.643793) (xy 103.254712 -50.657899)
			(xy 103.306041 -50.679711) (xy 103.353647 -50.708765) (xy 103.396515 -50.74444) (xy 103.433732 -50.785977)
			(xy 103.464505 -50.83249) (xy 103.488177 -50.882987) (xy 103.504245 -50.936394) (xy 103.512365 -50.99157)
			(xy 103.512874 -51.019456) (xy 103.512365 -51.047342) (xy 103.504245 -51.102518) (xy 103.488177 -51.155925)
			(xy 103.464505 -51.206422) (xy 103.433732 -51.252935) (xy 103.396515 -51.294472) (xy 103.353647 -51.330147)
			(xy 103.306041 -51.359201) (xy 103.254712 -51.381013) (xy 103.200755 -51.395119) (xy 103.145318 -51.401219)
			(xy 103.089584 -51.399182) (xy 103.034741 -51.389052) (xy 102.981957 -51.371045) (xy 102.932357 -51.345544)
			(xy 102.886999 -51.313093) (xy 102.84685 -51.274384) (xy 102.812764 -51.230241) (xy 102.785468 -51.181606)
			(xy 102.765545 -51.129515) (xy 102.753419 -51.075078) (xy 102.749348 -51.019456) (xy 90.30501 -51.019456)
			(xy 90.527593 -54.731412) (xy 91.520518 -54.731412) (xy 91.520987 -54.704042) (xy 91.528803 -54.649863)
			(xy 91.544291 -54.597359) (xy 91.567133 -54.547612) (xy 91.596857 -54.501646) (xy 91.614498 -54.480714)
			(xy 91.614752 -54.48046) (xy 91.620326 -54.473365) (xy 91.626579 -54.456454) (xy 91.626944 -54.44744)
			(xy 91.626944 -54.380384) (xy 91.626607 -54.371365) (xy 91.620347 -54.354448) (xy 91.614752 -54.347364)
			(xy 91.614498 -54.347364) (xy 91.614498 -54.34711) (xy 91.59687 -54.326167) (xy 91.567147 -54.2802)
			(xy 91.544303 -54.230456) (xy 91.528807 -54.177955) (xy 91.520978 -54.123779) (xy 91.520977 -54.069039)
			(xy 91.528803 -54.014862) (xy 91.544297 -53.962361) (xy 91.567138 -53.912615) (xy 91.596859 -53.866647)
			(xy 91.614498 -53.845714) (xy 91.614752 -53.84546) (xy 91.620326 -53.838365) (xy 91.626579 -53.821454)
			(xy 91.626944 -53.81244) (xy 91.626944 -53.745384) (xy 91.626607 -53.736365) (xy 91.620347 -53.719448)
			(xy 91.614752 -53.712364) (xy 91.614498 -53.712364) (xy 91.614498 -53.71211) (xy 91.59687 -53.691167)
			(xy 91.567147 -53.6452) (xy 91.544303 -53.595456) (xy 91.528807 -53.542955) (xy 91.520978 -53.488779)
			(xy 91.520977 -53.434039) (xy 91.528803 -53.379862) (xy 91.544297 -53.327361) (xy 91.567138 -53.277615)
			(xy 91.596859 -53.231647) (xy 91.614498 -53.210714) (xy 91.614752 -53.21046) (xy 91.620326 -53.203365)
			(xy 91.626579 -53.186454) (xy 91.626944 -53.17744) (xy 91.626944 -53.110384) (xy 91.626607 -53.101365)
			(xy 91.620347 -53.084448) (xy 91.614752 -53.077364) (xy 91.614498 -53.077364) (xy 91.614498 -53.07711)
			(xy 91.59685 -53.056185) (xy 91.567139 -53.01021) (xy 91.544305 -52.960461) (xy 91.528816 -52.907959)
			(xy 91.520991 -52.853782) (xy 91.520518 -52.826412) (xy 91.521004 -52.799161) (xy 91.52876 -52.745213)
			(xy 91.544115 -52.692918) (xy 91.566757 -52.643341) (xy 91.596223 -52.597491) (xy 91.631914 -52.5563)
			(xy 91.673105 -52.520609) (xy 91.718955 -52.491143) (xy 91.768532 -52.468501) (xy 91.820827 -52.453146)
			(xy 91.874775 -52.44539) (xy 91.929277 -52.44539) (xy 91.983225 -52.453146) (xy 92.03552 -52.468501)
			(xy 92.085097 -52.491143) (xy 92.130947 -52.520609) (xy 92.172138 -52.5563) (xy 92.207829 -52.597491)
			(xy 92.237295 -52.643341) (xy 92.259937 -52.692918) (xy 92.275292 -52.745213) (xy 92.283048 -52.799161)
			(xy 92.283534 -52.826412) (xy 92.283091 -52.853783) (xy 92.27527 -52.907964) (xy 92.259777 -52.960468)
			(xy 92.236929 -53.010215) (xy 92.207198 -53.05618) (xy 92.189554 -53.07711) (xy 92.1893 -53.077364)
			(xy 92.183722 -53.084457) (xy 92.17747 -53.101369) (xy 92.177108 -53.110384) (xy 92.177108 -53.17744)
			(xy 92.177444 -53.186459) (xy 92.183706 -53.203376) (xy 92.1893 -53.21046) (xy 92.189554 -53.21046)
			(xy 92.189554 -53.210714) (xy 92.207207 -53.231637) (xy 92.236933 -53.277606) (xy 92.259779 -53.327354)
			(xy 92.275275 -53.379857) (xy 92.283103 -53.434038) (xy 92.283102 -53.48878) (xy 92.275271 -53.54296)
			(xy 92.259772 -53.595463) (xy 92.236924 -53.64521) (xy 92.207196 -53.691178) (xy 92.189554 -53.71211)
			(xy 92.1893 -53.712364) (xy 92.183722 -53.719457) (xy 92.17747 -53.736369) (xy 92.177108 -53.745384)
			(xy 92.177108 -53.81244) (xy 92.177444 -53.821459) (xy 92.183706 -53.838376) (xy 92.1893 -53.84546)
			(xy 92.189554 -53.84546) (xy 92.189554 -53.845714) (xy 92.207207 -53.866637) (xy 92.236933 -53.912606)
			(xy 92.259779 -53.962354) (xy 92.275275 -54.014857) (xy 92.283103 -54.069038) (xy 92.283102 -54.12378)
			(xy 92.275271 -54.17796) (xy 92.259772 -54.230463) (xy 92.236924 -54.28021) (xy 92.207196 -54.326178)
			(xy 92.189554 -54.34711) (xy 92.1893 -54.347364) (xy 92.183722 -54.354457) (xy 92.17747 -54.371369)
			(xy 92.177108 -54.380384) (xy 92.177108 -54.44744) (xy 92.177444 -54.456459) (xy 92.183706 -54.473376)
			(xy 92.1893 -54.48046) (xy 92.189554 -54.48046) (xy 92.189554 -54.480714) (xy 92.207159 -54.501674)
			(xy 92.236878 -54.547638) (xy 92.259721 -54.597379) (xy 92.27522 -54.649873) (xy 92.283056 -54.704045)
			(xy 92.283534 -54.731412) (xy 92.283048 -54.758663) (xy 92.278384 -54.791102) (xy 94.176342 -54.791102)
			(xy 94.176799 -54.763731) (xy 94.184617 -54.709551) (xy 94.200108 -54.657048) (xy 94.222952 -54.607301)
			(xy 94.252679 -54.561335) (xy 94.270322 -54.540404) (xy 94.270576 -54.54015) (xy 94.276157 -54.53306)
			(xy 94.282405 -54.516146) (xy 94.282768 -54.50713) (xy 94.282768 -54.440074) (xy 94.28243 -54.431055)
			(xy 94.27617 -54.414138) (xy 94.270576 -54.407054) (xy 94.270322 -54.407054) (xy 94.270322 -54.4068)
			(xy 94.252683 -54.385866) (xy 94.222959 -54.339898) (xy 94.200114 -54.290152) (xy 94.184618 -54.23765)
			(xy 94.176789 -54.183472) (xy 94.176789 -54.128731) (xy 94.184617 -54.074553) (xy 94.200113 -54.022051)
			(xy 94.222958 -53.972305) (xy 94.252682 -53.926337) (xy 94.270322 -53.905404) (xy 94.270576 -53.90515)
			(xy 94.276157 -53.89806) (xy 94.282405 -53.881146) (xy 94.282768 -53.87213) (xy 94.282768 -53.805074)
			(xy 94.28243 -53.796055) (xy 94.27617 -53.779138) (xy 94.270576 -53.772054) (xy 94.270322 -53.772054)
			(xy 94.270322 -53.7718) (xy 94.252683 -53.750866) (xy 94.222959 -53.704898) (xy 94.200114 -53.655152)
			(xy 94.184618 -53.60265) (xy 94.176789 -53.548472) (xy 94.176789 -53.493731) (xy 94.184617 -53.439553)
			(xy 94.200113 -53.387051) (xy 94.222958 -53.337305) (xy 94.252682 -53.291337) (xy 94.270322 -53.270404)
			(xy 94.270576 -53.27015) (xy 94.276157 -53.26306) (xy 94.282405 -53.246146) (xy 94.282768 -53.23713)
			(xy 94.282768 -53.170074) (xy 94.28243 -53.161055) (xy 94.27617 -53.144138) (xy 94.270576 -53.137054)
			(xy 94.270322 -53.137054) (xy 94.270322 -53.1368) (xy 94.252673 -53.115876) (xy 94.222962 -53.069901)
			(xy 94.200127 -53.020152) (xy 94.184639 -52.967649) (xy 94.176814 -52.913472) (xy 94.176342 -52.886102)
			(xy 94.176828 -52.858851) (xy 94.184584 -52.804903) (xy 94.199939 -52.752608) (xy 94.222581 -52.703031)
			(xy 94.252047 -52.657181) (xy 94.287738 -52.61599) (xy 94.328929 -52.580299) (xy 94.374779 -52.550833)
			(xy 94.424356 -52.528191) (xy 94.476651 -52.512836) (xy 94.530599 -52.50508) (xy 94.585101 -52.50508)
			(xy 94.639049 -52.512836) (xy 94.691344 -52.528191) (xy 94.730453 -52.546052) (xy 99.679473 -52.546052)
			(xy 99.679473 -52.491548) (xy 99.68723 -52.437599) (xy 99.702586 -52.385303) (xy 99.725228 -52.335725)
			(xy 99.754695 -52.289874) (xy 99.790387 -52.248683) (xy 99.831579 -52.212991) (xy 99.87743 -52.183525)
			(xy 99.927009 -52.160884) (xy 99.979305 -52.145529) (xy 100.033254 -52.137773) (xy 100.060506 -52.13731)
			(xy 100.087876 -52.13777) (xy 100.142056 -52.145589) (xy 100.194559 -52.161079) (xy 100.244306 -52.183922)
			(xy 100.290273 -52.213648) (xy 100.311204 -52.23129) (xy 100.311458 -52.231544) (xy 100.318549 -52.237124)
			(xy 100.335462 -52.243374) (xy 100.344478 -52.243736) (xy 100.411534 -52.243736) (xy 100.420552 -52.243388)
			(xy 100.437468 -52.237133) (xy 100.444554 -52.231544) (xy 100.444554 -52.23129) (xy 100.444808 -52.23129)
			(xy 100.465741 -52.213649) (xy 100.511709 -52.183925) (xy 100.561455 -52.161079) (xy 100.613957 -52.145583)
			(xy 100.668135 -52.137754) (xy 100.722877 -52.137754) (xy 100.777055 -52.145583) (xy 100.829557 -52.161079)
			(xy 100.879303 -52.183925) (xy 100.925271 -52.213649) (xy 100.946204 -52.23129) (xy 100.946458 -52.231544)
			(xy 100.953549 -52.237124) (xy 100.970462 -52.243374) (xy 100.979478 -52.243736) (xy 101.046534 -52.243736)
			(xy 101.055552 -52.243388) (xy 101.072468 -52.237133) (xy 101.079554 -52.231544) (xy 101.079554 -52.23129)
			(xy 101.079808 -52.23129) (xy 101.100725 -52.213632) (xy 101.146702 -52.183923) (xy 101.196453 -52.161091)
			(xy 101.248957 -52.145605) (xy 101.303136 -52.137781) (xy 101.330506 -52.13731) (xy 101.357758 -52.13776)
			(xy 101.411708 -52.145518) (xy 101.464004 -52.160874) (xy 101.513583 -52.183517) (xy 101.559435 -52.212985)
			(xy 101.600626 -52.248678) (xy 101.636319 -52.28987) (xy 101.665786 -52.335722) (xy 101.688428 -52.385301)
			(xy 101.703783 -52.437598) (xy 101.71154 -52.491548) (xy 101.71154 -52.546052) (xy 101.705595 -52.587398)
			(xy 102.75519 -52.587398) (xy 102.759261 -52.531776) (xy 102.771387 -52.477339) (xy 102.79131 -52.425248)
			(xy 102.818606 -52.376613) (xy 102.852692 -52.33247) (xy 102.892841 -52.293761) (xy 102.938199 -52.26131)
			(xy 102.987799 -52.235809) (xy 103.040583 -52.217802) (xy 103.095426 -52.207672) (xy 103.15116 -52.205635)
			(xy 103.206597 -52.211735) (xy 103.260554 -52.225841) (xy 103.311883 -52.247653) (xy 103.359489 -52.276707)
			(xy 103.402357 -52.312382) (xy 103.439574 -52.353919) (xy 103.470347 -52.400432) (xy 103.494019 -52.450929)
			(xy 103.510087 -52.504336) (xy 103.518207 -52.559512) (xy 103.518716 -52.587398) (xy 103.518207 -52.615284)
			(xy 103.510087 -52.67046) (xy 103.494019 -52.723867) (xy 103.470347 -52.774364) (xy 103.439574 -52.820877)
			(xy 103.402357 -52.862414) (xy 103.359489 -52.898089) (xy 103.311883 -52.927143) (xy 103.260554 -52.948955)
			(xy 103.206597 -52.963061) (xy 103.15116 -52.969161) (xy 103.095426 -52.967124) (xy 103.040583 -52.956994)
			(xy 102.987799 -52.938987) (xy 102.938199 -52.913486) (xy 102.892841 -52.881035) (xy 102.852692 -52.842326)
			(xy 102.818606 -52.798183) (xy 102.79131 -52.749548) (xy 102.771387 -52.697457) (xy 102.759261 -52.64302)
			(xy 102.75519 -52.587398) (xy 101.705595 -52.587398) (xy 101.703783 -52.600002) (xy 101.688428 -52.652299)
			(xy 101.665786 -52.701878) (xy 101.636319 -52.74773) (xy 101.600626 -52.788922) (xy 101.559435 -52.824615)
			(xy 101.513583 -52.854083) (xy 101.464004 -52.876726) (xy 101.411708 -52.892082) (xy 101.357758 -52.89984)
			(xy 101.330506 -52.900326) (xy 101.303135 -52.899874) (xy 101.248955 -52.892056) (xy 101.196451 -52.876564)
			(xy 101.146704 -52.853719) (xy 101.100738 -52.82399) (xy 101.079808 -52.806346) (xy 101.079554 -52.806092)
			(xy 101.072457 -52.800521) (xy 101.055548 -52.794265) (xy 101.046534 -52.7939) (xy 100.979478 -52.7939)
			(xy 100.97046 -52.794247) (xy 100.953543 -52.800501) (xy 100.946458 -52.806092) (xy 100.946204 -52.806346)
			(xy 100.925271 -52.823987) (xy 100.879303 -52.853711) (xy 100.829557 -52.876557) (xy 100.777055 -52.892053)
			(xy 100.722877 -52.899882) (xy 100.668135 -52.899882) (xy 100.613957 -52.892053) (xy 100.561455 -52.876557)
			(xy 100.511709 -52.853711) (xy 100.465741 -52.823987) (xy 100.444808 -52.806346) (xy 100.444554 -52.806092)
			(xy 100.437457 -52.800521) (xy 100.420548 -52.794265) (xy 100.411534 -52.7939) (xy 100.344478 -52.7939)
			(xy 100.33546 -52.794247) (xy 100.318543 -52.800501) (xy 100.311458 -52.806092) (xy 100.311458 -52.806346)
			(xy 100.311204 -52.806346) (xy 100.290274 -52.823988) (xy 100.244302 -52.853701) (xy 100.194554 -52.876538)
			(xy 100.142052 -52.892028) (xy 100.087875 -52.899854) (xy 100.060506 -52.900326) (xy 100.033254 -52.899827)
			(xy 99.979305 -52.892071) (xy 99.927009 -52.876716) (xy 99.87743 -52.854075) (xy 99.831579 -52.824609)
			(xy 99.790387 -52.788917) (xy 99.754695 -52.747726) (xy 99.725228 -52.701875) (xy 99.702586 -52.652297)
			(xy 99.68723 -52.600001) (xy 99.679473 -52.546052) (xy 94.730453 -52.546052) (xy 94.740921 -52.550833)
			(xy 94.786771 -52.580299) (xy 94.827962 -52.61599) (xy 94.863653 -52.657181) (xy 94.893119 -52.703031)
			(xy 94.915761 -52.752608) (xy 94.931116 -52.804903) (xy 94.938872 -52.858851) (xy 94.939358 -52.886102)
			(xy 94.938903 -52.913473) (xy 94.931084 -52.967653) (xy 94.915593 -53.020156) (xy 94.892749 -53.069903)
			(xy 94.863021 -53.115869) (xy 94.845378 -53.1368) (xy 94.845124 -53.137054) (xy 94.839542 -53.144143)
			(xy 94.833294 -53.161058) (xy 94.832932 -53.170074) (xy 94.832932 -53.23713) (xy 94.833268 -53.246149)
			(xy 94.839529 -53.263066) (xy 94.845124 -53.27015) (xy 94.845378 -53.27015) (xy 94.845378 -53.270404)
			(xy 94.86302 -53.291335) (xy 94.892745 -53.337303) (xy 94.91559 -53.38705) (xy 94.931086 -53.439552)
			(xy 94.938914 -53.493731) (xy 94.938914 -53.548472) (xy 94.931085 -53.602651) (xy 94.915589 -53.655153)
			(xy 94.892743 -53.704899) (xy 94.863019 -53.750867) (xy 94.846448 -53.77053) (xy 95.21063 -53.77053)
			(xy 95.211158 -53.741613) (xy 95.219884 -53.684442) (xy 95.237139 -53.629243) (xy 95.262529 -53.577281)
			(xy 95.295471 -53.529747) (xy 95.335211 -53.48773) (xy 95.357696 -53.46954) (xy 95.366475 -53.461905)
			(xy 95.376674 -53.441026) (xy 95.377254 -53.429408) (xy 95.377254 -53.349652) (xy 95.376744 -53.338016)
			(xy 95.366536 -53.317106) (xy 95.357696 -53.30952) (xy 95.335221 -53.291319) (xy 95.295486 -53.249301)
			(xy 95.262546 -53.201768) (xy 95.237156 -53.149809) (xy 95.219898 -53.094613) (xy 95.211166 -53.037445)
			(xy 95.21063 -53.00853) (xy 95.211083 -52.981276) (xy 95.218837 -52.927323) (xy 95.234191 -52.875023)
			(xy 95.256833 -52.82544) (xy 95.286302 -52.779585) (xy 95.321997 -52.738391) (xy 95.363191 -52.702697)
			(xy 95.409047 -52.673229) (xy 95.45863 -52.650589) (xy 95.510931 -52.635236) (xy 95.564884 -52.627483)
			(xy 95.592138 -52.627022) (xy 95.618453 -52.627457) (xy 95.670583 -52.634698) (xy 95.721227 -52.649023)
			(xy 95.769426 -52.670161) (xy 95.814269 -52.697713) (xy 95.854907 -52.731158) (xy 95.873062 -52.750212)
			(xy 95.880594 -52.757601) (xy 95.899866 -52.766132) (xy 95.9104 -52.766722) (xy 95.985076 -52.766722)
			(xy 95.995625 -52.766187) (xy 96.01492 -52.757655) (xy 96.022414 -52.750212) (xy 96.040572 -52.731159)
			(xy 96.081201 -52.697701) (xy 96.126041 -52.670141) (xy 96.174241 -52.649002) (xy 96.224888 -52.634685)
			(xy 96.277022 -52.62746) (xy 96.303338 -52.627022) (xy 96.330592 -52.627443) (xy 96.384543 -52.635205)
			(xy 96.436841 -52.650566) (xy 96.48642 -52.673214) (xy 96.532272 -52.702687) (xy 96.573463 -52.738386)
			(xy 96.609154 -52.779583) (xy 96.638618 -52.825439) (xy 96.661257 -52.875023) (xy 96.676609 -52.927323)
			(xy 96.684362 -52.981276) (xy 96.684846 -53.00853) (xy 96.684382 -53.036197) (xy 96.682151 -53.051456)
			(xy 104.941114 -53.051456) (xy 104.945185 -52.995834) (xy 104.957311 -52.941397) (xy 104.977234 -52.889306)
			(xy 105.00453 -52.840671) (xy 105.038616 -52.796528) (xy 105.078765 -52.757819) (xy 105.124123 -52.725368)
			(xy 105.173723 -52.699867) (xy 105.226507 -52.68186) (xy 105.28135 -52.67173) (xy 105.337084 -52.669693)
			(xy 105.392521 -52.675793) (xy 105.446478 -52.689899) (xy 105.497807 -52.711711) (xy 105.545413 -52.740765)
			(xy 105.588281 -52.77644) (xy 105.625498 -52.817977) (xy 105.656271 -52.86449) (xy 105.679943 -52.914987)
			(xy 105.696011 -52.968394) (xy 105.704131 -53.02357) (xy 105.70464 -53.051456) (xy 105.704131 -53.079342)
			(xy 105.696011 -53.134518) (xy 105.679943 -53.187925) (xy 105.656271 -53.238422) (xy 105.625498 -53.284935)
			(xy 105.588281 -53.326472) (xy 105.545413 -53.362147) (xy 105.497807 -53.391201) (xy 105.446478 -53.413013)
			(xy 105.392521 -53.427119) (xy 105.337084 -53.433219) (xy 105.28135 -53.431182) (xy 105.226507 -53.421052)
			(xy 105.173723 -53.403045) (xy 105.124123 -53.377544) (xy 105.078765 -53.345093) (xy 105.038616 -53.306384)
			(xy 105.00453 -53.262241) (xy 104.977234 -53.213606) (xy 104.957311 -53.161515) (xy 104.945185 -53.107078)
			(xy 104.941114 -53.051456) (xy 96.682151 -53.051456) (xy 96.676377 -53.09095) (xy 96.660554 -53.143973)
			(xy 96.637244 -53.194158) (xy 96.606934 -53.240454) (xy 96.570261 -53.28189) (xy 96.527991 -53.317599)
			(xy 96.50476 -53.332634) (xy 96.495071 -53.339256) (xy 96.482633 -53.359128) (xy 96.480884 -53.370734)
			(xy 96.47301 -53.450744) (xy 96.47237 -53.462382) (xy 96.480457 -53.484219) (xy 96.488504 -53.492654)
			(xy 96.488758 -53.492908) (xy 96.507317 -53.511011) (xy 96.5399 -53.551337) (xy 96.566716 -53.595706)
			(xy 96.587273 -53.643301) (xy 96.601191 -53.693242) (xy 96.608212 -53.744608) (xy 96.608646 -53.77053)
			(xy 96.60815 -53.79778) (xy 96.600391 -53.851726) (xy 96.585034 -53.904018) (xy 96.562392 -53.953593)
			(xy 96.532926 -53.999441) (xy 96.497236 -54.04063) (xy 96.456048 -54.076321) (xy 96.4102 -54.105788)
			(xy 96.360625 -54.128431) (xy 96.308333 -54.143789) (xy 96.254388 -54.15155) (xy 96.227138 -54.152038)
			(xy 96.199768 -54.151565) (xy 96.145588 -54.143751) (xy 96.093085 -54.128264) (xy 96.043338 -54.105424)
			(xy 95.997371 -54.075699) (xy 95.97644 -54.058058) (xy 95.976186 -54.057804) (xy 95.969107 -54.052206)
			(xy 95.952185 -54.045966) (xy 95.943166 -54.045612) (xy 95.87611 -54.045612) (xy 95.867093 -54.045971)
			(xy 95.850176 -54.052217) (xy 95.84309 -54.057804) (xy 95.84309 -54.058058) (xy 95.842836 -54.058058)
			(xy 95.821896 -54.075687) (xy 95.775926 -54.105402) (xy 95.726181 -54.12824) (xy 95.673681 -54.143734)
			(xy 95.619507 -54.151563) (xy 95.592138 -54.152038) (xy 95.564887 -54.151509) (xy 95.51094 -54.143758)
			(xy 95.458646 -54.128409) (xy 95.409068 -54.105773) (xy 95.363216 -54.076312) (xy 95.322023 -54.040625)
			(xy 95.286329 -53.999439) (xy 95.25686 -53.953592) (xy 95.234215 -53.904018) (xy 95.218856 -53.851726)
			(xy 95.211095 -53.79778) (xy 95.21063 -53.77053) (xy 94.846448 -53.77053) (xy 94.845378 -53.7718)
			(xy 94.845124 -53.772054) (xy 94.839542 -53.779143) (xy 94.833294 -53.796058) (xy 94.832932 -53.805074)
			(xy 94.832932 -53.87213) (xy 94.833268 -53.881149) (xy 94.839529 -53.898066) (xy 94.845124 -53.90515)
			(xy 94.845378 -53.90515) (xy 94.845378 -53.905404) (xy 94.86302 -53.926335) (xy 94.892745 -53.972303)
			(xy 94.91559 -54.02205) (xy 94.931086 -54.074552) (xy 94.938914 -54.128731) (xy 94.938914 -54.183472)
			(xy 94.931085 -54.237651) (xy 94.915589 -54.290153) (xy 94.901796 -54.320186) (xy 97.130362 -54.320186)
			(xy 97.130805 -54.292815) (xy 97.138626 -54.238634) (xy 97.15412 -54.18613) (xy 97.176967 -54.136384)
			(xy 97.206698 -54.090418) (xy 97.224342 -54.069488) (xy 97.224596 -54.069234) (xy 97.230174 -54.062142)
			(xy 97.236426 -54.045229) (xy 97.236788 -54.036214) (xy 97.236788 -53.969158) (xy 97.236406 -53.960144)
			(xy 97.230176 -53.943226) (xy 97.224596 -53.936138) (xy 97.224342 -53.936138) (xy 97.224342 -53.935884)
			(xy 97.206735 -53.914926) (xy 97.177017 -53.868961) (xy 97.154174 -53.81922) (xy 97.138676 -53.766725)
			(xy 97.13084 -53.712553) (xy 97.130362 -53.685186) (xy 97.130848 -53.657935) (xy 97.138604 -53.603987)
			(xy 97.153959 -53.551692) (xy 97.176601 -53.502115) (xy 97.206067 -53.456265) (xy 97.241758 -53.415074)
			(xy 97.282949 -53.379383) (xy 97.328799 -53.349917) (xy 97.378376 -53.327275) (xy 97.430671 -53.31192)
			(xy 97.484619 -53.304164) (xy 97.539121 -53.304164) (xy 97.593069 -53.31192) (xy 97.645364 -53.327275)
			(xy 97.694941 -53.349917) (xy 97.740791 -53.379383) (xy 97.781982 -53.415074) (xy 97.817673 -53.456265)
			(xy 97.847139 -53.502115) (xy 97.869781 -53.551692) (xy 97.885136 -53.603987) (xy 97.892892 -53.657935)
			(xy 97.893378 -53.685186) (xy 97.892909 -53.712556) (xy 97.885093 -53.766735) (xy 97.869605 -53.819239)
			(xy 97.846763 -53.868986) (xy 97.817039 -53.914952) (xy 97.799398 -53.935884) (xy 97.799144 -53.936138)
			(xy 97.793571 -53.943233) (xy 97.787317 -53.960144) (xy 97.786952 -53.969158) (xy 97.786952 -54.036214)
			(xy 97.787291 -54.045233) (xy 97.79355 -54.06215) (xy 97.799144 -54.069234) (xy 97.799398 -54.069234)
			(xy 97.799398 -54.069488) (xy 97.817045 -54.090414) (xy 97.846755 -54.136388) (xy 97.86959 -54.186137)
			(xy 97.885079 -54.23864) (xy 97.892905 -54.292816) (xy 97.893378 -54.320186) (xy 97.892892 -54.347437)
			(xy 97.885136 -54.401385) (xy 97.869781 -54.45368) (xy 97.847139 -54.503257) (xy 97.817673 -54.549107)
			(xy 97.781982 -54.590298) (xy 97.740791 -54.625989) (xy 97.694941 -54.655455) (xy 97.645364 -54.678097)
			(xy 97.593069 -54.693452) (xy 97.539121 -54.701208) (xy 97.484619 -54.701208) (xy 97.430671 -54.693452)
			(xy 97.378376 -54.678097) (xy 97.328799 -54.655455) (xy 97.282949 -54.625989) (xy 97.241758 -54.590298)
			(xy 97.206067 -54.549107) (xy 97.176601 -54.503257) (xy 97.153959 -54.45368) (xy 97.138604 -54.401385)
			(xy 97.130848 -54.347437) (xy 97.130362 -54.320186) (xy 94.901796 -54.320186) (xy 94.892743 -54.339899)
			(xy 94.863019 -54.385867) (xy 94.845378 -54.4068) (xy 94.845124 -54.407054) (xy 94.839542 -54.414143)
			(xy 94.833294 -54.431058) (xy 94.832932 -54.440074) (xy 94.832932 -54.50713) (xy 94.833268 -54.516149)
			(xy 94.839529 -54.533066) (xy 94.845124 -54.54015) (xy 94.845378 -54.54015) (xy 94.845378 -54.540404)
			(xy 94.863029 -54.561327) (xy 94.89274 -54.607302) (xy 94.915574 -54.657052) (xy 94.931062 -54.709554)
			(xy 94.938886 -54.763732) (xy 94.939003 -54.770528) (xy 98.070924 -54.770528) (xy 98.071401 -54.743158)
			(xy 98.079215 -54.688979) (xy 98.094701 -54.636476) (xy 98.117541 -54.586729) (xy 98.147264 -54.540762)
			(xy 98.164904 -54.51983) (xy 98.165158 -54.519576) (xy 98.170768 -54.512505) (xy 98.176999 -54.495576)
			(xy 98.17735 -54.486556) (xy 98.17735 -54.4195) (xy 98.177004 -54.410482) (xy 98.17075 -54.393564)
			(xy 98.165158 -54.38648) (xy 98.164904 -54.38648) (xy 98.164904 -54.386226) (xy 98.147264 -54.365294)
			(xy 98.117552 -54.319322) (xy 98.094716 -54.269574) (xy 98.079226 -54.217073) (xy 98.071398 -54.162897)
			(xy 98.070924 -54.135528) (xy 98.07141 -54.108277) (xy 98.079166 -54.054329) (xy 98.094521 -54.002034)
			(xy 98.117163 -53.952457) (xy 98.146629 -53.906607) (xy 98.18232 -53.865416) (xy 98.223511 -53.829725)
			(xy 98.269361 -53.800259) (xy 98.318938 -53.777617) (xy 98.371233 -53.762262) (xy 98.425181 -53.754506)
			(xy 98.479683 -53.754506) (xy 98.533631 -53.762262) (xy 98.585926 -53.777617) (xy 98.635503 -53.800259)
			(xy 98.681353 -53.829725) (xy 98.722544 -53.865416) (xy 98.758235 -53.906607) (xy 98.787701 -53.952457)
			(xy 98.792776 -53.96357) (xy 102.771954 -53.96357) (xy 102.776025 -53.907948) (xy 102.788151 -53.853511)
			(xy 102.808074 -53.80142) (xy 102.83537 -53.752785) (xy 102.869456 -53.708642) (xy 102.909605 -53.669933)
			(xy 102.954963 -53.637482) (xy 103.004563 -53.611981) (xy 103.057347 -53.593974) (xy 103.11219 -53.583844)
			(xy 103.167924 -53.581807) (xy 103.223361 -53.587907) (xy 103.277318 -53.602013) (xy 103.328647 -53.623825)
			(xy 103.376253 -53.652879) (xy 103.419121 -53.688554) (xy 103.456338 -53.730091) (xy 103.487111 -53.776604)
			(xy 103.510783 -53.827101) (xy 103.526851 -53.880508) (xy 103.534971 -53.935684) (xy 103.53548 -53.96357)
			(xy 103.534971 -53.991456) (xy 103.526851 -54.046632) (xy 103.510783 -54.100039) (xy 103.487111 -54.150536)
			(xy 103.456338 -54.197049) (xy 103.419121 -54.238586) (xy 103.376253 -54.274261) (xy 103.328647 -54.303315)
			(xy 103.277318 -54.325127) (xy 103.223361 -54.339233) (xy 103.167924 -54.345333) (xy 103.11219 -54.343296)
			(xy 103.057347 -54.333166) (xy 103.004563 -54.315159) (xy 102.954963 -54.289658) (xy 102.909605 -54.257207)
			(xy 102.869456 -54.218498) (xy 102.83537 -54.174355) (xy 102.808074 -54.12572) (xy 102.788151 -54.073629)
			(xy 102.776025 -54.019192) (xy 102.771954 -53.96357) (xy 98.792776 -53.96357) (xy 98.810343 -54.002034)
			(xy 98.825698 -54.054329) (xy 98.833454 -54.108277) (xy 98.83394 -54.135528) (xy 98.833505 -54.1629)
			(xy 98.825682 -54.217081) (xy 98.810186 -54.269585) (xy 98.787337 -54.319331) (xy 98.757605 -54.365296)
			(xy 98.73996 -54.386226) (xy 98.739706 -54.38648) (xy 98.734122 -54.393569) (xy 98.727874 -54.410484)
			(xy 98.727514 -54.4195) (xy 98.727514 -54.486556) (xy 98.727889 -54.495571) (xy 98.734124 -54.512488)
			(xy 98.739706 -54.519576) (xy 98.73996 -54.519576) (xy 98.73996 -54.51983) (xy 98.757574 -54.540783)
			(xy 98.787291 -54.586749) (xy 98.810132 -54.636491) (xy 98.825629 -54.688988) (xy 98.833463 -54.74316)
			(xy 98.83394 -54.770528) (xy 98.833454 -54.797779) (xy 98.825698 -54.851727) (xy 98.810343 -54.904022)
			(xy 98.787701 -54.953599) (xy 98.758235 -54.999449) (xy 98.722544 -55.04064) (xy 98.681353 -55.076331)
			(xy 98.635503 -55.105797) (xy 98.585926 -55.128439) (xy 98.533631 -55.143794) (xy 98.479683 -55.15155)
			(xy 98.425181 -55.15155) (xy 98.371233 -55.143794) (xy 98.318938 -55.128439) (xy 98.269361 -55.105797)
			(xy 98.223511 -55.076331) (xy 98.18232 -55.04064) (xy 98.146629 -54.999449) (xy 98.117163 -54.953599)
			(xy 98.094521 -54.904022) (xy 98.079166 -54.851727) (xy 98.07141 -54.797779) (xy 98.070924 -54.770528)
			(xy 94.939003 -54.770528) (xy 94.939358 -54.791102) (xy 94.938872 -54.818353) (xy 94.931116 -54.872301)
			(xy 94.915761 -54.924596) (xy 94.893119 -54.974173) (xy 94.863653 -55.020023) (xy 94.827962 -55.061214)
			(xy 94.786771 -55.096905) (xy 94.740921 -55.126371) (xy 94.691344 -55.149013) (xy 94.639049 -55.164368)
			(xy 94.585101 -55.172124) (xy 94.530599 -55.172124) (xy 94.476651 -55.164368) (xy 94.424356 -55.149013)
			(xy 94.374779 -55.126371) (xy 94.328929 -55.096905) (xy 94.287738 -55.061214) (xy 94.252047 -55.020023)
			(xy 94.222581 -54.974173) (xy 94.199939 -54.924596) (xy 94.184584 -54.872301) (xy 94.176828 -54.818353)
			(xy 94.176342 -54.791102) (xy 92.278384 -54.791102) (xy 92.275292 -54.812611) (xy 92.259937 -54.864906)
			(xy 92.237295 -54.914483) (xy 92.207829 -54.960333) (xy 92.172138 -55.001524) (xy 92.130947 -55.037215)
			(xy 92.085097 -55.066681) (xy 92.03552 -55.089323) (xy 91.983225 -55.104678) (xy 91.929277 -55.112434)
			(xy 91.874775 -55.112434) (xy 91.820827 -55.104678) (xy 91.768532 -55.089323) (xy 91.718955 -55.066681)
			(xy 91.673105 -55.037215) (xy 91.631914 -55.001524) (xy 91.596223 -54.960333) (xy 91.566757 -54.914483)
			(xy 91.544115 -54.864906) (xy 91.52876 -54.812611) (xy 91.521004 -54.758663) (xy 91.520518 -54.731412)
			(xy 90.527593 -54.731412) (xy 90.587008 -55.722266) (xy 103.833928 -55.722266) (xy 103.837999 -55.666644)
			(xy 103.850125 -55.612207) (xy 103.870048 -55.560116) (xy 103.897344 -55.511481) (xy 103.93143 -55.467338)
			(xy 103.971579 -55.428629) (xy 104.016937 -55.396178) (xy 104.066537 -55.370677) (xy 104.119321 -55.35267)
			(xy 104.174164 -55.34254) (xy 104.229898 -55.340503) (xy 104.285335 -55.346603) (xy 104.339292 -55.360709)
			(xy 104.390621 -55.382521) (xy 104.438227 -55.411575) (xy 104.481095 -55.44725) (xy 104.518312 -55.488787)
			(xy 104.549085 -55.5353) (xy 104.572757 -55.585797) (xy 104.588825 -55.639204) (xy 104.596945 -55.69438)
			(xy 104.597454 -55.722266) (xy 104.596945 -55.750152) (xy 104.588825 -55.805328) (xy 104.572757 -55.858735)
			(xy 104.549085 -55.909232) (xy 104.518312 -55.955745) (xy 104.481095 -55.997282) (xy 104.438227 -56.032957)
			(xy 104.390621 -56.062011) (xy 104.339292 -56.083823) (xy 104.285335 -56.097929) (xy 104.229898 -56.104029)
			(xy 104.174164 -56.101992) (xy 104.119321 -56.091862) (xy 104.066537 -56.073855) (xy 104.016937 -56.048354)
			(xy 103.971579 -56.015903) (xy 103.93143 -55.977194) (xy 103.897344 -55.933051) (xy 103.870048 -55.884416)
			(xy 103.850125 -55.832325) (xy 103.837999 -55.777888) (xy 103.833928 -55.722266) (xy 90.587008 -55.722266)
			(xy 90.663802 -57.002934) (xy 99.563428 -57.002934) (xy 99.563927 -56.974842) (xy 99.572151 -56.919264)
			(xy 99.58844 -56.865494) (xy 99.612441 -56.814696) (xy 99.643636 -56.767969) (xy 99.681348 -56.726324)
			(xy 99.724763 -56.690664) (xy 99.748594 -56.675782) (xy 99.757484 -56.670448) (xy 99.769676 -56.65343)
			(xy 99.789996 -56.560212) (xy 99.785678 -56.539638) (xy 99.779836 -56.531002) (xy 99.763839 -56.506936)
			(xy 99.738494 -56.455006) (xy 99.721268 -56.399848) (xy 99.712552 -56.342724) (xy 99.712018 -56.313832)
			(xy 99.712485 -56.286579) (xy 99.720238 -56.232627) (xy 99.735592 -56.180327) (xy 99.758232 -56.130746)
			(xy 99.787699 -56.084891) (xy 99.823393 -56.043697) (xy 99.864586 -56.008003) (xy 99.91044 -55.978535)
			(xy 99.960022 -55.955894) (xy 100.012321 -55.94054) (xy 100.066273 -55.932786) (xy 100.093526 -55.932324)
			(xy 100.120897 -55.932769) (xy 100.175077 -55.940591) (xy 100.227581 -55.956085) (xy 100.277327 -55.978931)
			(xy 100.323293 -56.00866) (xy 100.344224 -56.026304) (xy 100.344478 -56.026558) (xy 100.351562 -56.032148)
			(xy 100.368481 -56.038391) (xy 100.377498 -56.03875) (xy 100.444554 -56.03875) (xy 100.45357 -56.038382)
			(xy 100.470488 -56.032143) (xy 100.477574 -56.026558) (xy 100.477574 -56.026304) (xy 100.477828 -56.026304)
			(xy 100.498761 -56.008663) (xy 100.544729 -55.978939) (xy 100.594475 -55.956093) (xy 100.646977 -55.940597)
			(xy 100.701155 -55.932768) (xy 100.755897 -55.932768) (xy 100.810075 -55.940597) (xy 100.862577 -55.956093)
			(xy 100.912323 -55.978939) (xy 100.958291 -56.008663) (xy 100.979224 -56.026304) (xy 100.979478 -56.026558)
			(xy 100.986562 -56.032148) (xy 101.003481 -56.038391) (xy 101.012498 -56.03875) (xy 101.079554 -56.03875)
			(xy 101.08857 -56.038382) (xy 101.105488 -56.032143) (xy 101.112574 -56.026558) (xy 101.112574 -56.026304)
			(xy 101.112828 -56.026304) (xy 101.133777 -56.008686) (xy 101.179745 -55.978971) (xy 101.229488 -55.956131)
			(xy 101.281985 -55.940635) (xy 101.336158 -55.932801) (xy 101.363526 -55.932324) (xy 101.390778 -55.932748)
			(xy 101.444728 -55.940508) (xy 101.497024 -55.955866) (xy 101.546602 -55.978511) (xy 101.592453 -56.00798)
			(xy 101.633643 -56.043675) (xy 101.669335 -56.084868) (xy 101.698801 -56.130721) (xy 101.721443 -56.180301)
			(xy 101.736798 -56.232598) (xy 101.744554 -56.286548) (xy 101.744554 -56.297068) (xy 102.086408 -56.297068)
			(xy 102.090479 -56.241446) (xy 102.102605 -56.187009) (xy 102.122528 -56.134918) (xy 102.149824 -56.086283)
			(xy 102.18391 -56.04214) (xy 102.224059 -56.003431) (xy 102.269417 -55.97098) (xy 102.319017 -55.945479)
			(xy 102.371801 -55.927472) (xy 102.426644 -55.917342) (xy 102.482378 -55.915305) (xy 102.537815 -55.921405)
			(xy 102.591772 -55.935511) (xy 102.643101 -55.957323) (xy 102.690707 -55.986377) (xy 102.733575 -56.022052)
			(xy 102.770792 -56.063589) (xy 102.801565 -56.110102) (xy 102.825237 -56.160599) (xy 102.841305 -56.214006)
			(xy 102.849425 -56.269182) (xy 102.849934 -56.297068) (xy 102.849425 -56.324954) (xy 102.841305 -56.38013)
			(xy 102.825237 -56.433537) (xy 102.801565 -56.484034) (xy 102.770792 -56.530547) (xy 102.733575 -56.572084)
			(xy 102.690707 -56.607759) (xy 102.643101 -56.636813) (xy 102.591772 -56.658625) (xy 102.537815 -56.672731)
			(xy 102.482378 -56.678831) (xy 102.426644 -56.676794) (xy 102.371801 -56.666664) (xy 102.319017 -56.648657)
			(xy 102.269417 -56.623156) (xy 102.224059 -56.590705) (xy 102.18391 -56.551996) (xy 102.149824 -56.507853)
			(xy 102.122528 -56.459218) (xy 102.102605 -56.407127) (xy 102.090479 -56.35269) (xy 102.086408 -56.297068)
			(xy 101.744554 -56.297068) (xy 101.744554 -56.341052) (xy 101.736798 -56.395002) (xy 101.721443 -56.447299)
			(xy 101.698801 -56.496879) (xy 101.669335 -56.542732) (xy 101.633643 -56.583925) (xy 101.592453 -56.61962)
			(xy 101.546602 -56.649089) (xy 101.497024 -56.671734) (xy 101.444728 -56.687092) (xy 101.390778 -56.694852)
			(xy 101.363526 -56.69534) (xy 101.336156 -56.694873) (xy 101.281976 -56.687058) (xy 101.229472 -56.67157)
			(xy 101.179725 -56.648728) (xy 101.133759 -56.619002) (xy 101.112828 -56.60136) (xy 101.112574 -56.601106)
			(xy 101.10547 -56.595545) (xy 101.088567 -56.589283) (xy 101.079554 -56.588914) (xy 101.012498 -56.588914)
			(xy 101.003481 -56.589267) (xy 100.986564 -56.595517) (xy 100.979478 -56.601106) (xy 100.979478 -56.60136)
			(xy 100.979224 -56.60136) (xy 100.958291 -56.619001) (xy 100.912323 -56.648725) (xy 100.862577 -56.671571)
			(xy 100.810075 -56.687067) (xy 100.755897 -56.694896) (xy 100.701155 -56.694896) (xy 100.646977 -56.687067)
			(xy 100.594475 -56.671571) (xy 100.544729 -56.648725) (xy 100.498761 -56.619001) (xy 100.477828 -56.60136)
			(xy 100.477574 -56.601106) (xy 100.47047 -56.595545) (xy 100.453567 -56.589283) (xy 100.444554 -56.588914)
			(xy 100.377498 -56.588914) (xy 100.368481 -56.589267) (xy 100.351564 -56.595517) (xy 100.344478 -56.601106)
			(xy 100.34397 -56.60136) (xy 100.331235 -56.612303) (xy 100.304144 -56.632145) (xy 100.289868 -56.640984)
			(xy 100.280978 -56.646318) (xy 100.268786 -56.663336) (xy 100.248466 -56.756554) (xy 100.252784 -56.777128)
			(xy 100.258626 -56.785764) (xy 100.274616 -56.809834) (xy 100.29996 -56.861764) (xy 100.317188 -56.91692)
			(xy 100.325907 -56.974042) (xy 100.326444 -57.002934) (xy 100.325958 -57.030185) (xy 100.318202 -57.084133)
			(xy 100.302847 -57.136428) (xy 100.280205 -57.186005) (xy 100.250739 -57.231855) (xy 100.215048 -57.273046)
			(xy 100.173857 -57.308737) (xy 100.128007 -57.338203) (xy 100.07843 -57.360845) (xy 100.026135 -57.3762)
			(xy 99.972187 -57.383956) (xy 99.917685 -57.383956) (xy 99.863737 -57.3762) (xy 99.811442 -57.360845)
			(xy 99.761865 -57.338203) (xy 99.716015 -57.308737) (xy 99.674824 -57.273046) (xy 99.639133 -57.231855)
			(xy 99.609667 -57.186005) (xy 99.587025 -57.136428) (xy 99.57167 -57.084133) (xy 99.563914 -57.030185)
			(xy 99.563428 -57.002934) (xy 90.663802 -57.002934) (xy 90.764325 -58.679334) (xy 99.995228 -58.679334)
			(xy 99.995642 -58.653018) (xy 100.002887 -58.600887) (xy 100.017216 -58.550243) (xy 100.038358 -58.502044)
			(xy 100.065914 -58.457202) (xy 100.099362 -58.416565) (xy 100.118418 -58.39841) (xy 100.12582 -58.390889)
			(xy 100.134344 -58.371608) (xy 100.134928 -58.361072) (xy 100.134928 -58.286396) (xy 100.134406 -58.275846)
			(xy 100.125865 -58.256551) (xy 100.118418 -58.249058) (xy 100.099353 -58.230912) (xy 100.065896 -58.190281)
			(xy 100.038337 -58.145439) (xy 100.017201 -58.097236) (xy 100.002886 -58.046586) (xy 99.995664 -57.994451)
			(xy 99.995228 -57.968134) (xy 99.995714 -57.940883) (xy 100.00347 -57.886935) (xy 100.018825 -57.83464)
			(xy 100.041467 -57.785063) (xy 100.070933 -57.739213) (xy 100.106624 -57.698022) (xy 100.147815 -57.662331)
			(xy 100.193665 -57.632865) (xy 100.243242 -57.610223) (xy 100.295537 -57.594868) (xy 100.349485 -57.587112)
			(xy 100.403987 -57.587112) (xy 100.457935 -57.594868) (xy 100.51023 -57.610223) (xy 100.559807 -57.632865)
			(xy 100.605657 -57.662331) (xy 100.646848 -57.698022) (xy 100.682539 -57.739213) (xy 100.712005 -57.785063)
			(xy 100.734647 -57.83464) (xy 100.750002 -57.886935) (xy 100.757758 -57.940883) (xy 100.758244 -57.968134)
			(xy 100.757817 -57.99445) (xy 100.750577 -58.046581) (xy 100.743309 -58.072274) (xy 103.99344 -58.072274)
			(xy 103.997511 -58.016652) (xy 104.009637 -57.962215) (xy 104.02956 -57.910124) (xy 104.056856 -57.861489)
			(xy 104.090942 -57.817346) (xy 104.131091 -57.778637) (xy 104.176449 -57.746186) (xy 104.226049 -57.720685)
			(xy 104.278833 -57.702678) (xy 104.333676 -57.692548) (xy 104.38941 -57.690511) (xy 104.444847 -57.696611)
			(xy 104.498804 -57.710717) (xy 104.550133 -57.732529) (xy 104.597739 -57.761583) (xy 104.640607 -57.797258)
			(xy 104.677824 -57.838795) (xy 104.708597 -57.885308) (xy 104.732269 -57.935805) (xy 104.748337 -57.989212)
			(xy 104.756457 -58.044388) (xy 104.756966 -58.072274) (xy 104.756457 -58.10016) (xy 104.748337 -58.155336)
			(xy 104.732269 -58.208743) (xy 104.708597 -58.25924) (xy 104.677824 -58.305753) (xy 104.640607 -58.34729)
			(xy 104.597739 -58.382965) (xy 104.550133 -58.412019) (xy 104.498804 -58.433831) (xy 104.444847 -58.447937)
			(xy 104.38941 -58.454037) (xy 104.333676 -58.452) (xy 104.278833 -58.44187) (xy 104.226049 -58.423863)
			(xy 104.176449 -58.398362) (xy 104.131091 -58.365911) (xy 104.090942 -58.327202) (xy 104.056856 -58.283059)
			(xy 104.02956 -58.234424) (xy 104.009637 -58.182333) (xy 103.997511 -58.127896) (xy 103.99344 -58.072274)
			(xy 100.743309 -58.072274) (xy 100.736251 -58.097225) (xy 100.715111 -58.145424) (xy 100.687557 -58.190266)
			(xy 100.65411 -58.230903) (xy 100.635054 -58.249058) (xy 100.627677 -58.256601) (xy 100.619137 -58.275864)
			(xy 100.618544 -58.286396) (xy 100.618544 -58.361072) (xy 100.619062 -58.371623) (xy 100.627604 -58.390919)
			(xy 100.635054 -58.39841) (xy 100.654118 -58.416557) (xy 100.687572 -58.45719) (xy 100.715129 -58.502032)
			(xy 100.736265 -58.550234) (xy 100.750581 -58.600883) (xy 100.757806 -58.653018) (xy 100.758244 -58.679334)
			(xy 100.757758 -58.706585) (xy 100.750002 -58.760533) (xy 100.734647 -58.812828) (xy 100.712005 -58.862405)
			(xy 100.682539 -58.908255) (xy 100.646848 -58.949446) (xy 100.605657 -58.985137) (xy 100.559807 -59.014603)
			(xy 100.51023 -59.037245) (xy 100.457935 -59.0526) (xy 100.403987 -59.060356) (xy 100.349485 -59.060356)
			(xy 100.295537 -59.0526) (xy 100.243242 -59.037245) (xy 100.193665 -59.014603) (xy 100.147815 -58.985137)
			(xy 100.106624 -58.949446) (xy 100.070933 -58.908255) (xy 100.041467 -58.862405) (xy 100.018825 -58.812828)
			(xy 100.00347 -58.760533) (xy 99.995714 -58.706585) (xy 99.995228 -58.679334) (xy 90.764325 -58.679334)
			(xy 90.844671 -60.01925) (xy 100.135684 -60.01925) (xy 100.135684 -59.96475) (xy 100.14344 -59.910804)
			(xy 100.158794 -59.85851) (xy 100.181434 -59.808935) (xy 100.210899 -59.763086) (xy 100.246589 -59.721896)
			(xy 100.287777 -59.686205) (xy 100.333626 -59.656739) (xy 100.383201 -59.634098) (xy 100.435494 -59.618742)
			(xy 100.48944 -59.610984) (xy 100.51669 -59.610498) (xy 100.54406 -59.61097) (xy 100.598239 -59.618787)
			(xy 100.650742 -59.634274) (xy 100.700489 -59.657115) (xy 100.746456 -59.686838) (xy 100.767388 -59.704478)
			(xy 100.767642 -59.704732) (xy 100.774738 -59.710304) (xy 100.791648 -59.716558) (xy 100.800662 -59.716924)
			(xy 100.867718 -59.716924) (xy 100.876735 -59.716571) (xy 100.893652 -59.71032) (xy 100.900738 -59.704732)
			(xy 100.900738 -59.704478) (xy 100.900992 -59.704478) (xy 100.921925 -59.686837) (xy 100.967893 -59.657113)
			(xy 101.017639 -59.634267) (xy 101.070141 -59.618771) (xy 101.124319 -59.610942) (xy 101.179061 -59.610942)
			(xy 101.233239 -59.618771) (xy 101.285741 -59.634267) (xy 101.335487 -59.657113) (xy 101.381455 -59.686837)
			(xy 101.402388 -59.704478) (xy 101.402642 -59.704732) (xy 101.409738 -59.710304) (xy 101.426648 -59.716558)
			(xy 101.435662 -59.716924) (xy 101.502718 -59.716924) (xy 101.511735 -59.716571) (xy 101.528652 -59.71032)
			(xy 101.535738 -59.704732) (xy 101.535738 -59.704478) (xy 101.535992 -59.704478) (xy 101.556913 -59.686826)
			(xy 101.60289 -59.657117) (xy 101.65264 -59.634284) (xy 101.705143 -59.618796) (xy 101.75932 -59.61097)
			(xy 101.78669 -59.610498) (xy 101.813944 -59.610949) (xy 101.867897 -59.618705) (xy 101.920196 -59.63406)
			(xy 101.969779 -59.656702) (xy 102.015634 -59.68617) (xy 102.056828 -59.721865) (xy 102.092524 -59.763058)
			(xy 102.121993 -59.808913) (xy 102.144636 -59.858494) (xy 102.159993 -59.910794) (xy 102.167751 -59.964746)
			(xy 102.167751 -60.019254) (xy 102.159993 -60.073206) (xy 102.144636 -60.125506) (xy 102.121993 -60.175087)
			(xy 102.092524 -60.220942) (xy 102.056828 -60.262135) (xy 102.015634 -60.29783) (xy 101.969779 -60.327298)
			(xy 101.920196 -60.34994) (xy 101.867897 -60.365295) (xy 101.813944 -60.373051) (xy 101.78669 -60.373514)
			(xy 101.75932 -60.37305) (xy 101.705141 -60.365231) (xy 101.652638 -60.349742) (xy 101.602891 -60.326899)
			(xy 101.556924 -60.297175) (xy 101.535992 -60.279534) (xy 101.535738 -60.27928) (xy 101.528646 -60.273701)
			(xy 101.511733 -60.26745) (xy 101.502718 -60.267088) (xy 101.435662 -60.267088) (xy 101.426644 -60.267429)
			(xy 101.409727 -60.273688) (xy 101.402642 -60.27928) (xy 101.402388 -60.279534) (xy 101.381455 -60.297175)
			(xy 101.335487 -60.326899) (xy 101.285741 -60.349745) (xy 101.233239 -60.365241) (xy 101.179061 -60.37307)
			(xy 101.124319 -60.37307) (xy 101.070141 -60.365241) (xy 101.017639 -60.349745) (xy 100.967893 -60.326899)
			(xy 100.921925 -60.297175) (xy 100.900992 -60.279534) (xy 100.900738 -60.27928) (xy 100.893646 -60.273701)
			(xy 100.876733 -60.26745) (xy 100.867718 -60.267088) (xy 100.800662 -60.267088) (xy 100.791644 -60.267429)
			(xy 100.774727 -60.273688) (xy 100.767642 -60.27928) (xy 100.767642 -60.279534) (xy 100.767388 -60.279534)
			(xy 100.746438 -60.297151) (xy 100.70047 -60.326865) (xy 100.650727 -60.349704) (xy 100.59823 -60.365201)
			(xy 100.544058 -60.373036) (xy 100.51669 -60.373514) (xy 100.48944 -60.373016) (xy 100.435494 -60.365258)
			(xy 100.383201 -60.349902) (xy 100.333626 -60.327261) (xy 100.287777 -60.297795) (xy 100.246589 -60.262104)
			(xy 100.210899 -60.220914) (xy 100.181434 -60.175065) (xy 100.158794 -60.12549) (xy 100.14344 -60.073196)
			(xy 100.135684 -60.01925) (xy 90.844671 -60.01925) (xy 91.036214 -63.213552) (xy 100.120665 -63.213552)
			(xy 100.120665 -63.159048) (xy 100.128422 -63.105098) (xy 100.143778 -63.052801) (xy 100.16642 -63.003222)
			(xy 100.195888 -62.95737) (xy 100.231581 -62.916178) (xy 100.272773 -62.880485) (xy 100.318625 -62.851018)
			(xy 100.368205 -62.828377) (xy 100.420502 -62.813021) (xy 100.474452 -62.805265) (xy 100.501704 -62.804802)
			(xy 100.529074 -62.805265) (xy 100.583254 -62.813084) (xy 100.635757 -62.828573) (xy 100.685504 -62.851416)
			(xy 100.73147 -62.881141) (xy 100.752402 -62.898782) (xy 100.752656 -62.899036) (xy 100.759748 -62.904614)
			(xy 100.776661 -62.910865) (xy 100.785676 -62.911228) (xy 100.852732 -62.911228) (xy 100.86175 -62.91088)
			(xy 100.878666 -62.904626) (xy 100.885752 -62.899036) (xy 100.885752 -62.898782) (xy 100.886006 -62.898782)
			(xy 100.906939 -62.881141) (xy 100.952907 -62.851417) (xy 101.002653 -62.828571) (xy 101.055155 -62.813075)
			(xy 101.109333 -62.805246) (xy 101.164075 -62.805246) (xy 101.218253 -62.813075) (xy 101.270755 -62.828571)
			(xy 101.320501 -62.851417) (xy 101.366469 -62.881141) (xy 101.387402 -62.898782) (xy 101.387656 -62.899036)
			(xy 101.394748 -62.904614) (xy 101.411661 -62.910865) (xy 101.420676 -62.911228) (xy 101.487732 -62.911228)
			(xy 101.49675 -62.91088) (xy 101.513666 -62.904626) (xy 101.520752 -62.899036) (xy 101.520752 -62.898782)
			(xy 101.521006 -62.898782) (xy 101.541923 -62.881124) (xy 101.5879 -62.851415) (xy 101.637651 -62.828583)
			(xy 101.690155 -62.813097) (xy 101.744334 -62.805273) (xy 101.771704 -62.804802) (xy 101.798956 -62.805268)
			(xy 101.852904 -62.813025) (xy 101.9052 -62.828381) (xy 101.954778 -62.851023) (xy 102.000629 -62.88049)
			(xy 102.04182 -62.916183) (xy 102.077512 -62.957374) (xy 102.106979 -63.003225) (xy 102.12962 -63.052804)
			(xy 102.144976 -63.105099) (xy 102.152732 -63.159048) (xy 102.152732 -63.213552) (xy 102.144976 -63.267501)
			(xy 102.12962 -63.319796) (xy 102.106979 -63.369375) (xy 102.077512 -63.415226) (xy 102.04182 -63.456417)
			(xy 102.000629 -63.49211) (xy 101.954778 -63.521577) (xy 101.9052 -63.544219) (xy 101.852904 -63.559575)
			(xy 101.798956 -63.567332) (xy 101.771704 -63.567818) (xy 101.744333 -63.56737) (xy 101.690152 -63.559551)
			(xy 101.637648 -63.544058) (xy 101.587902 -63.521212) (xy 101.541936 -63.491482) (xy 101.521006 -63.473838)
			(xy 101.520752 -63.473584) (xy 101.513656 -63.468011) (xy 101.496746 -63.461757) (xy 101.487732 -63.461392)
			(xy 101.420676 -63.461392) (xy 101.411658 -63.461739) (xy 101.394741 -63.467994) (xy 101.387656 -63.473584)
			(xy 101.387402 -63.473838) (xy 101.366469 -63.491479) (xy 101.320501 -63.521203) (xy 101.270755 -63.544049)
			(xy 101.218253 -63.559545) (xy 101.164075 -63.567374) (xy 101.109333 -63.567374) (xy 101.055155 -63.559545)
			(xy 101.002653 -63.544049) (xy 100.952907 -63.521203) (xy 100.906939 -63.491479) (xy 100.886006 -63.473838)
			(xy 100.885752 -63.473584) (xy 100.878656 -63.468011) (xy 100.861746 -63.461757) (xy 100.852732 -63.461392)
			(xy 100.785676 -63.461392) (xy 100.776658 -63.461739) (xy 100.759741 -63.467994) (xy 100.752656 -63.473584)
			(xy 100.752656 -63.473838) (xy 100.752402 -63.473838) (xy 100.731485 -63.491496) (xy 100.685508 -63.521204)
			(xy 100.635756 -63.544036) (xy 100.583252 -63.559522) (xy 100.529074 -63.567346) (xy 100.501704 -63.567818)
			(xy 100.474452 -63.567335) (xy 100.420502 -63.559579) (xy 100.368205 -63.544223) (xy 100.318625 -63.521582)
			(xy 100.272773 -63.492115) (xy 100.231581 -63.456422) (xy 100.195888 -63.41523) (xy 100.16642 -63.369378)
			(xy 100.143778 -63.319799) (xy 100.128422 -63.267502) (xy 100.120665 -63.213552) (xy 91.036214 -63.213552)
			(xy 91.136216 -64.881252) (xy 91.137232 -64.916558) (xy 91.137232 -64.929258) (xy 91.13647 -64.966596)
			(xy 91.13647 -64.97066) (xy 91.14282 -65.07607) (xy 91.143558 -65.100962) (xy 98.13239 -65.100962)
			(xy 98.136461 -65.04534) (xy 98.148587 -64.990903) (xy 98.16851 -64.938812) (xy 98.195806 -64.890177)
			(xy 98.229892 -64.846034) (xy 98.270041 -64.807325) (xy 98.315399 -64.774874) (xy 98.364999 -64.749373)
			(xy 98.417783 -64.731366) (xy 98.472626 -64.721236) (xy 98.52836 -64.719199) (xy 98.583797 -64.725299)
			(xy 98.637754 -64.739405) (xy 98.689083 -64.761217) (xy 98.736689 -64.790271) (xy 98.779557 -64.825946)
			(xy 98.816774 -64.867483) (xy 98.847547 -64.913996) (xy 98.871219 -64.964493) (xy 98.887287 -65.0179)
			(xy 98.895407 -65.073076) (xy 98.895916 -65.100962) (xy 98.895407 -65.128848) (xy 98.887287 -65.184024)
			(xy 98.871219 -65.237431) (xy 98.847547 -65.287928) (xy 98.816774 -65.334441) (xy 98.779557 -65.375978)
			(xy 98.736689 -65.411653) (xy 98.689083 -65.440707) (xy 98.637754 -65.462519) (xy 98.583797 -65.476625)
			(xy 98.52836 -65.482725) (xy 98.472626 -65.480688) (xy 98.417783 -65.470558) (xy 98.364999 -65.452551)
			(xy 98.315399 -65.42705) (xy 98.270041 -65.394599) (xy 98.229892 -65.35589) (xy 98.195806 -65.311747)
			(xy 98.16851 -65.263112) (xy 98.148587 -65.211021) (xy 98.136461 -65.156584) (xy 98.13239 -65.100962)
			(xy 91.143558 -65.100962) (xy 91.143836 -65.11036) (xy 91.143836 -65.123314) (xy 91.137994 -65.40119)
			(xy 91.130471 -65.75552) (xy 92.346524 -65.75552) (xy 92.350595 -65.699898) (xy 92.362721 -65.645461)
			(xy 92.382644 -65.59337) (xy 92.40994 -65.544735) (xy 92.444026 -65.500592) (xy 92.484175 -65.461883)
			(xy 92.529533 -65.429432) (xy 92.579133 -65.403931) (xy 92.631917 -65.385924) (xy 92.68676 -65.375794)
			(xy 92.742494 -65.373757) (xy 92.797931 -65.379857) (xy 92.851888 -65.393963) (xy 92.903217 -65.415775)
			(xy 92.950823 -65.444829) (xy 92.993691 -65.480504) (xy 93.030908 -65.522041) (xy 93.061681 -65.568554)
			(xy 93.085353 -65.619051) (xy 93.101421 -65.672458) (xy 93.109541 -65.727634) (xy 93.11005 -65.75552)
			(xy 93.109541 -65.783406) (xy 93.101421 -65.838582) (xy 93.085353 -65.891989) (xy 93.061681 -65.942486)
			(xy 93.030908 -65.988999) (xy 92.993691 -66.030536) (xy 92.950823 -66.066211) (xy 92.903217 -66.095265)
			(xy 92.851888 -66.117077) (xy 92.797931 -66.131183) (xy 92.742494 -66.137283) (xy 92.68676 -66.135246)
			(xy 92.631917 -66.125116) (xy 92.579133 -66.107109) (xy 92.529533 -66.081608) (xy 92.484175 -66.049157)
			(xy 92.444026 -66.010448) (xy 92.40994 -65.966305) (xy 92.382644 -65.91767) (xy 92.362721 -65.865579)
			(xy 92.350595 -65.811142) (xy 92.346524 -65.75552) (xy 91.130471 -65.75552) (xy 91.101312 -67.128949)
			(xy 92.366598 -67.128949) (xy 92.366598 -67.074451) (xy 92.374354 -67.020506) (xy 92.389708 -66.968215)
			(xy 92.412347 -66.918641) (xy 92.441811 -66.872794) (xy 92.4775 -66.831606) (xy 92.518687 -66.795916)
			(xy 92.564534 -66.766451) (xy 92.614108 -66.743811) (xy 92.666399 -66.728456) (xy 92.720343 -66.720699)
			(xy 92.747592 -66.720212) (xy 92.774962 -66.72068) (xy 92.829141 -66.728497) (xy 92.881645 -66.743985)
			(xy 92.931391 -66.766827) (xy 92.977358 -66.796551) (xy 92.99829 -66.814192) (xy 92.998544 -66.814446)
			(xy 93.005638 -66.820021) (xy 93.022549 -66.826273) (xy 93.031564 -66.826638) (xy 93.09862 -66.826638)
			(xy 93.107637 -66.826282) (xy 93.124553 -66.820033) (xy 93.13164 -66.814446) (xy 93.13164 -66.814192)
			(xy 93.131894 -66.814192) (xy 93.152816 -66.796541) (xy 93.198792 -66.766831) (xy 93.248542 -66.743998)
			(xy 93.301045 -66.728509) (xy 93.355222 -66.720684) (xy 93.382592 -66.720212) (xy 93.409847 -66.720634)
			(xy 93.463801 -66.728391) (xy 93.516103 -66.743747) (xy 93.565687 -66.76639) (xy 93.611543 -66.79586)
			(xy 93.652739 -66.831555) (xy 93.688436 -66.87275) (xy 93.717906 -66.918606) (xy 93.74055 -66.96819)
			(xy 93.755907 -67.020491) (xy 93.763665 -67.074445) (xy 93.763665 -67.128955) (xy 93.755907 -67.182909)
			(xy 93.74055 -67.23521) (xy 93.717906 -67.284794) (xy 93.688436 -67.33065) (xy 93.652739 -67.371845)
			(xy 93.611543 -67.40754) (xy 93.565687 -67.43701) (xy 93.516103 -67.459653) (xy 93.463801 -67.475009)
			(xy 93.409847 -67.482766) (xy 93.382592 -67.483228) (xy 93.355221 -67.482784) (xy 93.30104 -67.474964)
			(xy 93.248536 -67.45947) (xy 93.198789 -67.436623) (xy 93.152824 -67.406892) (xy 93.131894 -67.389248)
			(xy 93.13164 -67.388994) (xy 93.124547 -67.383417) (xy 93.107635 -67.377165) (xy 93.09862 -67.376802)
			(xy 93.031564 -67.376802) (xy 93.022545 -67.377142) (xy 93.005629 -67.383401) (xy 92.998544 -67.388994)
			(xy 92.998544 -67.389248) (xy 92.99829 -67.389248) (xy 92.977366 -67.406897) (xy 92.931392 -67.436609)
			(xy 92.881642 -67.459444) (xy 92.82914 -67.474933) (xy 92.774962 -67.482757) (xy 92.747592 -67.483228)
			(xy 92.720343 -67.482701) (xy 92.666399 -67.474944) (xy 92.614108 -67.459589) (xy 92.564534 -67.436949)
			(xy 92.518687 -67.407484) (xy 92.4775 -67.371794) (xy 92.441811 -67.330606) (xy 92.412347 -67.284759)
			(xy 92.389708 -67.235185) (xy 92.374354 -67.182894) (xy 92.366598 -67.128949) (xy 91.101312 -67.128949)
			(xy 91.093688 -67.488054) (xy 96.779078 -67.488054) (xy 96.783149 -67.432432) (xy 96.795275 -67.377995)
			(xy 96.815198 -67.325904) (xy 96.842494 -67.277269) (xy 96.87658 -67.233126) (xy 96.916729 -67.194417)
			(xy 96.962087 -67.161966) (xy 97.011687 -67.136465) (xy 97.064471 -67.118458) (xy 97.119314 -67.108328)
			(xy 97.175048 -67.106291) (xy 97.230485 -67.112391) (xy 97.284442 -67.126497) (xy 97.335771 -67.148309)
			(xy 97.383377 -67.177363) (xy 97.426245 -67.213038) (xy 97.463462 -67.254575) (xy 97.494235 -67.301088)
			(xy 97.517907 -67.351585) (xy 97.533975 -67.404992) (xy 97.542095 -67.460168) (xy 97.542604 -67.488054)
			(xy 97.542095 -67.51594) (xy 97.53891 -67.537584) (xy 98.071176 -67.537584) (xy 98.075247 -67.481962)
			(xy 98.087373 -67.427525) (xy 98.107296 -67.375434) (xy 98.134592 -67.326799) (xy 98.168678 -67.282656)
			(xy 98.208827 -67.243947) (xy 98.254185 -67.211496) (xy 98.303785 -67.185995) (xy 98.356569 -67.167988)
			(xy 98.411412 -67.157858) (xy 98.467146 -67.155821) (xy 98.522583 -67.161921) (xy 98.57654 -67.176027)
			(xy 98.627869 -67.197839) (xy 98.675475 -67.226893) (xy 98.718343 -67.262568) (xy 98.75556 -67.304105)
			(xy 98.786333 -67.350618) (xy 98.810005 -67.401115) (xy 98.826073 -67.454522) (xy 98.834193 -67.509698)
			(xy 98.834702 -67.537584) (xy 98.834193 -67.56547) (xy 98.830148 -67.592956) (xy 99.34524 -67.592956)
			(xy 99.349311 -67.537334) (xy 99.361437 -67.482897) (xy 99.38136 -67.430806) (xy 99.408656 -67.382171)
			(xy 99.442742 -67.338028) (xy 99.482891 -67.299319) (xy 99.528249 -67.266868) (xy 99.577849 -67.241367)
			(xy 99.630633 -67.22336) (xy 99.685476 -67.21323) (xy 99.74121 -67.211193) (xy 99.796647 -67.217293)
			(xy 99.850604 -67.231399) (xy 99.901933 -67.253211) (xy 99.949539 -67.282265) (xy 99.992407 -67.31794)
			(xy 100.029624 -67.359477) (xy 100.060397 -67.40599) (xy 100.084069 -67.456487) (xy 100.100137 -67.509894)
			(xy 100.108254 -67.565048) (xy 102.446616 -67.565048) (xy 102.446616 -67.510552) (xy 102.454371 -67.456612)
			(xy 102.469724 -67.404324) (xy 102.492362 -67.354753) (xy 102.521823 -67.308908) (xy 102.557509 -67.267722)
			(xy 102.598693 -67.232034) (xy 102.644537 -67.20257) (xy 102.694107 -67.17993) (xy 102.746394 -67.164575)
			(xy 102.800334 -67.156817) (xy 102.827582 -67.15633) (xy 102.854952 -67.156799) (xy 102.909131 -67.164615)
			(xy 102.961635 -67.180103) (xy 103.011382 -67.202944) (xy 103.057348 -67.232669) (xy 103.07828 -67.25031)
			(xy 103.078534 -67.250564) (xy 103.08563 -67.256137) (xy 103.10254 -67.26239) (xy 103.111554 -67.262756)
			(xy 103.17861 -67.262756) (xy 103.187629 -67.262414) (xy 103.204546 -67.256157) (xy 103.21163 -67.250564)
			(xy 103.21163 -67.25031) (xy 103.211884 -67.25031) (xy 103.232813 -67.232667) (xy 103.278786 -67.202955)
			(xy 103.328535 -67.18012) (xy 103.381036 -67.16463) (xy 103.435213 -67.156803) (xy 103.462582 -67.15633)
			(xy 103.489838 -67.156716) (xy 103.543797 -67.164471) (xy 103.596102 -67.179827) (xy 103.645689 -67.202471)
			(xy 103.691549 -67.231942) (xy 103.732748 -67.267639) (xy 103.768448 -67.308836) (xy 103.79792 -67.354695)
			(xy 103.820566 -67.404281) (xy 103.835925 -67.456586) (xy 103.843683 -67.510544) (xy 103.843683 -67.565056)
			(xy 103.835925 -67.619014) (xy 103.820566 -67.671319) (xy 103.79792 -67.720905) (xy 103.768448 -67.766764)
			(xy 103.732748 -67.807961) (xy 103.691549 -67.843658) (xy 103.645689 -67.873129) (xy 103.596102 -67.895773)
			(xy 103.543797 -67.911129) (xy 103.489838 -67.918884) (xy 103.462582 -67.919346) (xy 103.435211 -67.918904)
			(xy 103.38103 -67.911082) (xy 103.328526 -67.895588) (xy 103.27878 -67.872741) (xy 103.232814 -67.84301)
			(xy 103.211884 -67.825366) (xy 103.21163 -67.825112) (xy 103.204538 -67.819533) (xy 103.187625 -67.813281)
			(xy 103.17861 -67.81292) (xy 103.111554 -67.81292) (xy 103.102539 -67.813299) (xy 103.085622 -67.819531)
			(xy 103.078534 -67.825112) (xy 103.078534 -67.825366) (xy 103.07828 -67.825366) (xy 103.057324 -67.842976)
			(xy 103.011358 -67.872693) (xy 102.961617 -67.895535) (xy 102.909121 -67.911033) (xy 102.85495 -67.918868)
			(xy 102.827582 -67.919346) (xy 102.800334 -67.918783) (xy 102.746394 -67.911025) (xy 102.694107 -67.89567)
			(xy 102.644537 -67.87303) (xy 102.598693 -67.843566) (xy 102.557509 -67.807878) (xy 102.521823 -67.766692)
			(xy 102.492362 -67.720847) (xy 102.469724 -67.671276) (xy 102.454371 -67.618988) (xy 102.446616 -67.565048)
			(xy 100.108254 -67.565048) (xy 100.108257 -67.56507) (xy 100.108766 -67.592956) (xy 100.108257 -67.620842)
			(xy 100.100137 -67.676018) (xy 100.084069 -67.729425) (xy 100.060397 -67.779922) (xy 100.029624 -67.826435)
			(xy 99.992407 -67.867972) (xy 99.949539 -67.903647) (xy 99.901933 -67.932701) (xy 99.850604 -67.954513)
			(xy 99.796647 -67.968619) (xy 99.74121 -67.974719) (xy 99.685476 -67.972682) (xy 99.630633 -67.962552)
			(xy 99.577849 -67.944545) (xy 99.528249 -67.919044) (xy 99.482891 -67.886593) (xy 99.442742 -67.847884)
			(xy 99.408656 -67.803741) (xy 99.38136 -67.755106) (xy 99.361437 -67.703015) (xy 99.349311 -67.648578)
			(xy 99.34524 -67.592956) (xy 98.830148 -67.592956) (xy 98.826073 -67.620646) (xy 98.810005 -67.674053)
			(xy 98.786333 -67.72455) (xy 98.75556 -67.771063) (xy 98.718343 -67.8126) (xy 98.675475 -67.848275)
			(xy 98.627869 -67.877329) (xy 98.57654 -67.899141) (xy 98.522583 -67.913247) (xy 98.467146 -67.919347)
			(xy 98.411412 -67.91731) (xy 98.356569 -67.90718) (xy 98.303785 -67.889173) (xy 98.254185 -67.863672)
			(xy 98.208827 -67.831221) (xy 98.168678 -67.792512) (xy 98.134592 -67.748369) (xy 98.107296 -67.699734)
			(xy 98.087373 -67.647643) (xy 98.075247 -67.593206) (xy 98.071176 -67.537584) (xy 97.53891 -67.537584)
			(xy 97.533975 -67.571116) (xy 97.517907 -67.624523) (xy 97.494235 -67.67502) (xy 97.463462 -67.721533)
			(xy 97.426245 -67.76307) (xy 97.383377 -67.798745) (xy 97.335771 -67.827799) (xy 97.284442 -67.849611)
			(xy 97.230485 -67.863717) (xy 97.175048 -67.869817) (xy 97.119314 -67.86778) (xy 97.064471 -67.85765)
			(xy 97.011687 -67.839643) (xy 96.962087 -67.814142) (xy 96.916729 -67.781691) (xy 96.87658 -67.742982)
			(xy 96.842494 -67.698839) (xy 96.815198 -67.650204) (xy 96.795275 -67.598113) (xy 96.783149 -67.543676)
			(xy 96.779078 -67.488054) (xy 91.093688 -67.488054) (xy 91.07551 -68.344288) (xy 91.070376 -68.586604)
			(xy 94.62516 -68.586604) (xy 94.625614 -68.559233) (xy 94.633432 -68.505053) (xy 94.648923 -68.452549)
			(xy 94.671768 -68.402802) (xy 94.701497 -68.356837) (xy 94.71914 -68.335906) (xy 94.719394 -68.335652)
			(xy 94.724964 -68.328554) (xy 94.731221 -68.311646) (xy 94.731586 -68.302632) (xy 94.731586 -68.235576)
			(xy 94.731243 -68.226558) (xy 94.724986 -68.209641) (xy 94.719394 -68.202556) (xy 94.71914 -68.202556)
			(xy 94.71914 -68.202302) (xy 94.701495 -68.181375) (xy 94.671782 -68.135401) (xy 94.648947 -68.085653)
			(xy 94.633458 -68.033151) (xy 94.625632 -67.978974) (xy 94.62516 -67.951604) (xy 94.625681 -67.924354)
			(xy 94.633437 -67.87041) (xy 94.64879 -67.818117) (xy 94.671428 -67.768542) (xy 94.700891 -67.722693)
			(xy 94.736578 -67.681504) (xy 94.777765 -67.645812) (xy 94.823611 -67.616345) (xy 94.873184 -67.593702)
			(xy 94.925474 -67.578344) (xy 94.979418 -67.570584) (xy 95.006668 -67.570096) (xy 95.032983 -67.570519)
			(xy 95.085114 -67.577763) (xy 95.135757 -67.592091) (xy 95.183956 -67.613232) (xy 95.228799 -67.640786)
			(xy 95.269436 -67.674231) (xy 95.287592 -67.693286) (xy 95.295117 -67.700684) (xy 95.314394 -67.709211)
			(xy 95.32493 -67.709796) (xy 95.399606 -67.709796) (xy 95.410158 -67.709285) (xy 95.429453 -67.700737)
			(xy 95.436944 -67.693286) (xy 95.455082 -67.674213) (xy 95.495716 -67.640758) (xy 95.54056 -67.613202)
			(xy 95.588764 -67.592067) (xy 95.639415 -67.577753) (xy 95.691551 -67.570532) (xy 95.717868 -67.570096)
			(xy 95.745238 -67.570582) (xy 95.799416 -67.578395) (xy 95.851919 -67.59388) (xy 95.901666 -67.616717)
			(xy 95.947634 -67.646437) (xy 95.968566 -67.664076) (xy 95.96882 -67.66433) (xy 95.975894 -67.669934)
			(xy 95.992821 -67.676169) (xy 96.00184 -67.676522) (xy 96.068896 -67.676522) (xy 96.077912 -67.676158)
			(xy 96.094829 -67.669915) (xy 96.101916 -67.66433) (xy 96.101916 -67.664076) (xy 96.10217 -67.664076)
			(xy 96.123099 -67.646434) (xy 96.169073 -67.616723) (xy 96.218822 -67.593888) (xy 96.271323 -67.578398)
			(xy 96.325499 -67.57057) (xy 96.352868 -67.570096) (xy 96.38012 -67.570585) (xy 96.43407 -67.578338)
			(xy 96.486368 -67.59369) (xy 96.535948 -67.616329) (xy 96.581802 -67.645794) (xy 96.622995 -67.681485)
			(xy 96.658689 -67.722676) (xy 96.688158 -67.768527) (xy 96.7108 -67.818106) (xy 96.726156 -67.870402)
			(xy 96.733913 -67.924352) (xy 96.734376 -67.951604) (xy 96.733918 -67.978975) (xy 96.726099 -68.033154)
			(xy 96.710609 -68.085658) (xy 96.687765 -68.135404) (xy 96.658038 -68.181371) (xy 96.640396 -68.202302)
			(xy 96.640142 -68.202556) (xy 96.634561 -68.209646) (xy 96.628312 -68.22656) (xy 96.62795 -68.235576)
			(xy 96.62795 -68.302632) (xy 96.628281 -68.311652) (xy 96.634545 -68.328569) (xy 96.640142 -68.335652)
			(xy 96.640396 -68.335652) (xy 96.640396 -68.335906) (xy 96.658051 -68.356825) (xy 96.68776 -68.402802)
			(xy 96.710593 -68.452552) (xy 96.726081 -68.505056) (xy 96.733904 -68.559234) (xy 96.734376 -68.586604)
			(xy 96.733948 -68.613858) (xy 96.72619 -68.667812) (xy 96.710832 -68.720113) (xy 96.694199 -68.75653)
			(xy 100.170234 -68.75653) (xy 100.170709 -68.72916) (xy 100.178524 -68.674981) (xy 100.19401 -68.622478)
			(xy 100.21685 -68.572731) (xy 100.246573 -68.526764) (xy 100.264214 -68.505832) (xy 100.264468 -68.505578)
			(xy 100.270078 -68.498508) (xy 100.276309 -68.481578) (xy 100.27666 -68.472558) (xy 100.27666 -68.405502)
			(xy 100.27631 -68.396484) (xy 100.270059 -68.379567) (xy 100.264468 -68.372482) (xy 100.264214 -68.372482)
			(xy 100.264214 -68.372228) (xy 100.246577 -68.351294) (xy 100.216864 -68.305322) (xy 100.194028 -68.255575)
			(xy 100.178536 -68.203075) (xy 100.170708 -68.148899) (xy 100.170234 -68.12153) (xy 100.170683 -68.094276)
			(xy 100.178437 -68.040322) (xy 100.193792 -67.988022) (xy 100.216434 -67.938439) (xy 100.245903 -67.892584)
			(xy 100.281598 -67.851389) (xy 100.322793 -67.815695) (xy 100.368649 -67.786228) (xy 100.418233 -67.763587)
			(xy 100.470534 -67.748235) (xy 100.524488 -67.740482) (xy 100.551742 -67.740022) (xy 100.579111 -67.740517)
			(xy 100.633289 -67.748327) (xy 100.685792 -67.763809) (xy 100.73554 -67.786644) (xy 100.781508 -67.816363)
			(xy 100.80244 -67.834002) (xy 100.802694 -67.834256) (xy 100.809773 -67.839853) (xy 100.826696 -67.846092)
			(xy 100.835714 -67.846448) (xy 100.90277 -67.846448) (xy 100.911787 -67.846088) (xy 100.928704 -67.839844)
			(xy 100.93579 -67.834256) (xy 100.93579 -67.834002) (xy 100.936044 -67.834002) (xy 100.956987 -67.816376)
			(xy 101.002956 -67.786662) (xy 101.052701 -67.763824) (xy 101.1052 -67.74833) (xy 101.159374 -67.740498)
			(xy 101.186742 -67.740022) (xy 101.213057 -67.740454) (xy 101.265188 -67.747695) (xy 101.315831 -67.762021)
			(xy 101.36403 -67.78316) (xy 101.408873 -67.810712) (xy 101.449511 -67.844157) (xy 101.467666 -67.863212)
			(xy 101.475197 -67.870603) (xy 101.49447 -67.879133) (xy 101.505004 -67.879722) (xy 101.57968 -67.879722)
			(xy 101.590229 -67.879189) (xy 101.609524 -67.870656) (xy 101.617018 -67.863212) (xy 101.635174 -67.844157)
			(xy 101.675803 -67.810699) (xy 101.720644 -67.78314) (xy 101.768844 -67.762001) (xy 101.819492 -67.747684)
			(xy 101.871626 -67.74046) (xy 101.897942 -67.740022) (xy 101.925196 -67.740439) (xy 101.979147 -67.748202)
			(xy 102.031445 -67.763564) (xy 102.081025 -67.786212) (xy 102.126876 -67.815685) (xy 102.168067 -67.851384)
			(xy 102.203758 -67.892581) (xy 102.233223 -67.938439) (xy 102.255861 -67.988022) (xy 102.271213 -68.040323)
			(xy 102.278966 -68.094276) (xy 102.27945 -68.12153) (xy 102.279014 -68.148901) (xy 102.271191 -68.203082)
			(xy 102.255695 -68.255586) (xy 102.232847 -68.305333) (xy 102.203115 -68.351298) (xy 102.18547 -68.372228)
			(xy 102.185216 -68.372482) (xy 102.179633 -68.379571) (xy 102.173384 -68.396486) (xy 102.173024 -68.405502)
			(xy 102.173024 -68.472558) (xy 102.173396 -68.481573) (xy 102.179633 -68.498491) (xy 102.185216 -68.505578)
			(xy 102.18547 -68.505578) (xy 102.18547 -68.505832) (xy 102.203086 -68.526783) (xy 102.232802 -68.57275)
			(xy 102.255643 -68.622493) (xy 102.27114 -68.674989) (xy 102.278973 -68.729162) (xy 102.27945 -68.75653)
			(xy 102.27895 -68.78378) (xy 102.271191 -68.837725) (xy 102.255834 -68.890017) (xy 102.233192 -68.939592)
			(xy 102.203727 -68.98544) (xy 102.168037 -69.026629) (xy 102.126849 -69.06232) (xy 102.081002 -69.091787)
			(xy 102.031428 -69.11443) (xy 101.979137 -69.129788) (xy 101.925192 -69.137549) (xy 101.897942 -69.138038)
			(xy 101.871626 -69.137629) (xy 101.819494 -69.130385) (xy 101.768849 -69.116056) (xy 101.72065 -69.094913)
			(xy 101.675808 -69.067355) (xy 101.635172 -69.033905) (xy 101.617018 -69.014848) (xy 101.609485 -69.00746)
			(xy 101.590214 -68.998926) (xy 101.57968 -68.998338) (xy 101.505004 -68.998338) (xy 101.494451 -68.998844)
			(xy 101.475156 -69.007394) (xy 101.467666 -69.014848) (xy 101.449529 -69.033922) (xy 101.408895 -69.067376)
			(xy 101.36405 -69.094931) (xy 101.315846 -69.116066) (xy 101.265195 -69.13038) (xy 101.213059 -69.137601)
			(xy 101.186742 -69.138038) (xy 101.159372 -69.137562) (xy 101.105193 -69.129749) (xy 101.052689 -69.114263)
			(xy 101.002942 -69.091423) (xy 100.956975 -69.061699) (xy 100.936044 -69.044058) (xy 100.93579 -69.043804)
			(xy 100.92871 -69.038208) (xy 100.911788 -69.031967) (xy 100.90277 -69.031612) (xy 100.835714 -69.031612)
			(xy 100.826697 -69.031973) (xy 100.80978 -69.038217) (xy 100.802694 -69.043804) (xy 100.802694 -69.044058)
			(xy 100.80244 -69.044058) (xy 100.781498 -69.061685) (xy 100.735529 -69.0914) (xy 100.685784 -69.114239)
			(xy 100.633285 -69.129733) (xy 100.579111 -69.137563) (xy 100.551742 -69.138038) (xy 100.524492 -69.137506)
			(xy 100.470545 -69.129755) (xy 100.41825 -69.114406) (xy 100.368672 -69.091771) (xy 100.32282 -69.06231)
			(xy 100.281628 -69.026623) (xy 100.245933 -68.985438) (xy 100.216464 -68.939591) (xy 100.193819 -68.890018)
			(xy 100.17846 -68.837726) (xy 100.170699 -68.78378) (xy 100.170234 -68.75653) (xy 96.694199 -68.75653)
			(xy 96.688186 -68.769695) (xy 96.658715 -68.81555) (xy 96.623018 -68.856743) (xy 96.581821 -68.892437)
			(xy 96.535963 -68.921904) (xy 96.486379 -68.944544) (xy 96.434077 -68.959898) (xy 96.380122 -68.967651)
			(xy 96.352868 -68.968112) (xy 96.325497 -68.967662) (xy 96.271318 -68.95984) (xy 96.218814 -68.944347)
			(xy 96.169068 -68.921502) (xy 96.123101 -68.891774) (xy 96.10217 -68.874132) (xy 96.101916 -68.873878)
			(xy 96.094831 -68.86829) (xy 96.077913 -68.862045) (xy 96.068896 -68.861686) (xy 96.00184 -68.861686)
			(xy 95.992825 -68.862065) (xy 95.975908 -68.868298) (xy 95.96882 -68.873878) (xy 95.96882 -68.874132)
			(xy 95.968566 -68.874132) (xy 95.947624 -68.891759) (xy 95.901653 -68.921471) (xy 95.851908 -68.944309)
			(xy 95.79941 -68.959803) (xy 95.745236 -68.967636) (xy 95.717868 -68.968112) (xy 95.691553 -68.967662)
			(xy 95.639424 -68.960423) (xy 95.588781 -68.9461) (xy 95.540583 -68.924965) (xy 95.49574 -68.897416)
			(xy 95.4551 -68.863975) (xy 95.436944 -68.844922) (xy 95.429405 -68.837541) (xy 95.410138 -68.829004)
			(xy 95.399606 -68.828412) (xy 95.32493 -68.828412) (xy 95.31438 -68.82894) (xy 95.295085 -68.837476)
			(xy 95.287592 -68.844922) (xy 95.269438 -68.863979) (xy 95.228807 -68.897435) (xy 95.183966 -68.924993)
			(xy 95.135766 -68.946131) (xy 95.085118 -68.960448) (xy 95.032984 -68.967673) (xy 95.006668 -68.968112)
			(xy 94.979416 -68.967652) (xy 94.925468 -68.959891) (xy 94.873173 -68.944532) (xy 94.823596 -68.921888)
			(xy 94.777746 -68.892418) (xy 94.736556 -68.856724) (xy 94.700865 -68.815532) (xy 94.671399 -68.76968)
			(xy 94.648758 -68.720101) (xy 94.633403 -68.667805) (xy 94.625646 -68.613856) (xy 94.62516 -68.586604)
			(xy 91.070376 -68.586604) (xy 91.048586 -69.61505) (xy 91.02471 -70.738492) (xy 91.007287 -71.555864)
			(xy 97.194368 -71.555864) (xy 97.198439 -71.500242) (xy 97.210565 -71.445805) (xy 97.230488 -71.393714)
			(xy 97.257784 -71.345079) (xy 97.29187 -71.300936) (xy 97.332019 -71.262227) (xy 97.377377 -71.229776)
			(xy 97.426977 -71.204275) (xy 97.479761 -71.186268) (xy 97.534604 -71.176138) (xy 97.590338 -71.174101)
			(xy 97.645775 -71.180201) (xy 97.699732 -71.194307) (xy 97.751061 -71.216119) (xy 97.798667 -71.245173)
			(xy 97.841535 -71.280848) (xy 97.878752 -71.322385) (xy 97.909525 -71.368898) (xy 97.933197 -71.419395)
			(xy 97.949265 -71.472802) (xy 97.957385 -71.527978) (xy 97.957894 -71.555864) (xy 97.957385 -71.58375)
			(xy 97.951546 -71.623428) (xy 98.703382 -71.623428) (xy 98.707453 -71.567806) (xy 98.719579 -71.513369)
			(xy 98.739502 -71.461278) (xy 98.766798 -71.412643) (xy 98.800884 -71.3685) (xy 98.841033 -71.329791)
			(xy 98.886391 -71.29734) (xy 98.935991 -71.271839) (xy 98.988775 -71.253832) (xy 99.043618 -71.243702)
			(xy 99.099352 -71.241665) (xy 99.154789 -71.247765) (xy 99.208746 -71.261871) (xy 99.260075 -71.283683)
			(xy 99.307681 -71.312737) (xy 99.350549 -71.348412) (xy 99.387766 -71.389949) (xy 99.418539 -71.436462)
			(xy 99.442211 -71.486959) (xy 99.458279 -71.540366) (xy 99.466399 -71.595542) (xy 99.466908 -71.623428)
			(xy 99.466399 -71.651314) (xy 99.458279 -71.70649) (xy 99.442211 -71.759897) (xy 99.418539 -71.810394)
			(xy 99.387766 -71.856907) (xy 99.350549 -71.898444) (xy 99.307681 -71.934119) (xy 99.260075 -71.963173)
			(xy 99.208746 -71.984985) (xy 99.154789 -71.999091) (xy 99.099352 -72.005191) (xy 99.043618 -72.003154)
			(xy 98.988775 -71.993024) (xy 98.935991 -71.975017) (xy 98.886391 -71.949516) (xy 98.841033 -71.917065)
			(xy 98.800884 -71.878356) (xy 98.766798 -71.834213) (xy 98.739502 -71.785578) (xy 98.719579 -71.733487)
			(xy 98.707453 -71.67905) (xy 98.703382 -71.623428) (xy 97.951546 -71.623428) (xy 97.949265 -71.638926)
			(xy 97.933197 -71.692333) (xy 97.909525 -71.74283) (xy 97.878752 -71.789343) (xy 97.841535 -71.83088)
			(xy 97.798667 -71.866555) (xy 97.751061 -71.895609) (xy 97.699732 -71.917421) (xy 97.645775 -71.931527)
			(xy 97.590338 -71.937627) (xy 97.534604 -71.93559) (xy 97.479761 -71.92546) (xy 97.426977 -71.907453)
			(xy 97.377377 -71.881952) (xy 97.332019 -71.849501) (xy 97.29187 -71.810792) (xy 97.257784 -71.766649)
			(xy 97.230488 -71.718014) (xy 97.210565 -71.665923) (xy 97.198439 -71.611486) (xy 97.194368 -71.555864)
			(xy 91.007287 -71.555864) (xy 90.97772 -72.942958) (xy 90.968576 -73.37298) (xy 90.968708 -73.381681)
			(xy 90.974139 -73.3982) (xy 90.98482 -73.411922) (xy 90.991944 -73.416922) (xy 91.01201 -73.429876)
			(xy 91.065096 -73.463912) (xy 91.070334 -73.467063) (xy 91.081888 -73.471043) (xy 91.087956 -73.471786)
			(xy 91.095322 -73.472548) (xy 91.108784 -73.470008) (xy 91.115134 -73.46696) (xy 91.14116 -73.454944)
			(xy 91.195914 -73.437977) (xy 91.252589 -73.429378) (xy 91.28125 -73.42886) (xy 91.289632 -73.42886)
			(xy 91.316953 -73.429911) (xy 91.37089 -73.438865) (xy 91.422996 -73.455425) (xy 91.472206 -73.479251)
			(xy 91.517513 -73.509856) (xy 91.557987 -73.546613) (xy 91.592802 -73.588771) (xy 91.621245 -73.635465)
			(xy 91.642732 -73.68574) (xy 91.656825 -73.738567) (xy 91.660472 -73.765664) (xy 91.661996 -73.779888)
			(xy 91.663793 -73.80956) (xy 91.659259 -73.868829) (xy 91.645568 -73.926672) (xy 91.634818 -73.954386)
			(xy 91.625674 -73.97496) (xy 91.625674 -73.975468) (xy 91.614989 -73.996692) (xy 91.589136 -74.036561)
			(xy 91.574112 -74.05497) (xy 91.574112 -74.055224) (xy 91.573858 -74.055478) (xy 91.568254 -74.062956)
			(xy 91.562376 -74.080678) (xy 91.562428 -74.090022) (xy 91.56319 -74.106532) (xy 91.565222 -74.158094)
			(xy 91.56551 -74.162737) (xy 91.56755 -74.171812) (xy 91.569286 -74.176128) (xy 91.572588 -74.183494)
			(xy 91.578684 -74.190352) (xy 91.579446 -74.191368) (xy 92.136214 -74.748136) (xy 92.375482 -74.987658)
			(xy 92.378022 -74.989944) (xy 101.960934 -74.989944) (xy 101.971 -74.989513) (xy 101.98959 -74.981784)
			(xy 101.997002 -74.974958) (xy 102.849426 -74.12228) (xy 102.856277 -74.114884) (xy 102.864016 -74.096285)
			(xy 102.864412 -74.086212) (xy 102.864412 -69.891402) (xy 102.864893 -69.858241) (xy 102.872349 -69.792338)
			(xy 102.887134 -69.727684) (xy 102.909063 -69.665091) (xy 102.937859 -69.605346) (xy 102.973161 -69.549198)
			(xy 103.014526 -69.497355) (xy 103.03764 -69.473572) (xy 103.365046 -69.146166) (xy 103.388824 -69.123055)
			(xy 103.440677 -69.081721) (xy 103.496831 -69.046452) (xy 103.55658 -69.017692) (xy 103.619174 -68.995801)
			(xy 103.683825 -68.981055) (xy 103.74972 -68.97364) (xy 103.782876 -68.973192) (xy 108.03382 -68.973192)
			(xy 108.052666 -68.973283) (xy 108.090286 -68.97557) (xy 108.109004 -68.977764) (xy 108.112052 -68.978272)
			(xy 113.957354 -68.978272) (xy 113.967768 -68.977256) (xy 113.991136 -68.96735) (xy 114.000788 -68.962524)
			(xy 114.007392 -68.956428) (xy 114.0079 -68.95592) (xy 114.038888 -68.925694) (xy 114.099699 -68.86718)
			(xy 114.224564 -68.75362) (xy 114.28857 -68.698618) (xy 114.333528 -68.660772) (xy 114.343942 -68.652136)
			(xy 114.349784 -68.64731) (xy 114.401346 -68.6054) (xy 114.403378 -68.603622) (xy 116.408962 -66.598038)
			(xy 116.414866 -66.591701) (xy 116.422413 -66.576123) (xy 116.423694 -66.567558) (xy 116.423948 -66.564764)
			(xy 116.423948 -64.568324) (xy 116.42351 -64.558261) (xy 116.41577 -64.539682) (xy 116.408962 -64.532256)
			(xy 115.026186 -63.14948) (xy 115.018774 -63.142796) (xy 115.000341 -63.135199) (xy 114.980403 -63.135199)
			(xy 114.96197 -63.142796) (xy 114.954558 -63.14948) (xy 114.230404 -63.87338) (xy 114.206646 -63.896523)
			(xy 114.154804 -63.937897) (xy 114.098655 -63.973206) (xy 114.038905 -64.002005) (xy 113.976307 -64.023933)
			(xy 113.911647 -64.038713) (xy 113.845738 -64.04616) (xy 113.812574 -64.046608) (xy 113.37671 -64.046608)
			(xy 113.343548 -64.046128) (xy 113.277645 -64.038673) (xy 113.21299 -64.023888) (xy 113.150396 -64.001961)
			(xy 113.09065 -63.973166) (xy 113.034501 -63.937865) (xy 112.982656 -63.896502) (xy 112.95888 -63.87338)
			(xy 112.354106 -63.268606) (xy 112.330999 -63.244826) (xy 112.289674 -63.192971) (xy 112.254413 -63.136815)
			(xy 112.22566 -63.077065) (xy 112.203776 -63.014472) (xy 112.189038 -62.949823) (xy 112.181628 -62.88393)
			(xy 112.181132 -62.850776) (xy 112.181132 -62.415166) (xy 112.180703 -62.405098) (xy 112.172984 -62.386499)
			(xy 112.166146 -62.379098) (xy 112.162336 -62.375288) (xy 111.694976 -62.375288) (xy 111.661822 -62.374823)
			(xy 111.595929 -62.367401) (xy 111.531282 -62.352651) (xy 111.46869 -62.330761) (xy 111.408942 -62.302004)
			(xy 111.352786 -62.266743) (xy 111.300929 -62.225419) (xy 111.277146 -62.202314) (xy 110.67542 -61.600588)
			(xy 110.652278 -61.576829) (xy 110.610905 -61.524987) (xy 110.575598 -61.468838) (xy 110.5468 -61.409089)
			(xy 110.524874 -61.34649) (xy 110.510095 -61.28183) (xy 110.50265 -61.215922) (xy 110.502192 -61.182758)
			(xy 110.502192 -60.736226) (xy 110.501755 -60.726162) (xy 110.494021 -60.707578) (xy 110.487206 -60.700158)
			(xy 110.483904 -60.696856) (xy 110.01629 -60.696856) (xy 109.983129 -60.696375) (xy 109.917226 -60.688918)
			(xy 109.852571 -60.674133) (xy 109.789978 -60.652205) (xy 109.730231 -60.623411) (xy 109.674082 -60.588111)
			(xy 109.622237 -60.546749) (xy 109.59846 -60.523628) (xy 108.996734 -59.921902) (xy 108.973626 -59.898123)
			(xy 108.932299 -59.846268) (xy 108.897037 -59.790113) (xy 108.868283 -59.730363) (xy 108.846399 -59.66777)
			(xy 108.83166 -59.60312) (xy 108.824251 -59.537226) (xy 108.82376 -59.504072) (xy 108.82376 -59.057794)
			(xy 108.823335 -59.047725) (xy 108.815614 -59.029126) (xy 108.808774 -59.021726) (xy 108.803694 -59.016646)
			(xy 108.796074 -59.010296) (xy 108.340652 -59.010296) (xy 108.307498 -59.00983) (xy 108.241607 -59.002405)
			(xy 108.176961 -58.987654) (xy 108.114371 -58.965762) (xy 108.054624 -58.937004) (xy 107.99847 -58.901741)
			(xy 107.946614 -58.860416) (xy 107.922822 -58.837322) (xy 107.325668 -58.240168) (xy 107.302528 -58.216408)
			(xy 107.261161 -58.164564) (xy 107.225858 -58.108414) (xy 107.197065 -58.048664) (xy 107.175143 -57.986066)
			(xy 107.160369 -57.921407) (xy 107.152927 -57.855501) (xy 107.15244 -57.822338) (xy 107.15244 -57.375806)
			(xy 107.15292 -57.342644) (xy 107.160376 -57.276741) (xy 107.175159 -57.212085) (xy 107.197085 -57.14949)
			(xy 107.225879 -57.089742) (xy 107.261177 -57.033592) (xy 107.302538 -56.981745) (xy 107.325668 -56.957976)
			(xy 109.35335 -54.930294) (xy 109.352592 -54.920849) (xy 109.34503 -54.903488) (xy 109.338618 -54.896512)
			(xy 107.5436 -53.101494) (xy 107.520826 -53.07808) (xy 107.480089 -53.027021) (xy 107.445319 -52.971726)
			(xy 107.416952 -52.912888) (xy 107.395345 -52.851247) (xy 107.380768 -52.787575) (xy 107.373404 -52.722673)
			(xy 107.372912 -52.690014) (xy 107.372912 -52.680616) (xy 107.371642 -52.675028) (xy 107.364634 -52.642523)
			(xy 107.357121 -52.576451) (xy 107.356656 -52.543202) (xy 107.356656 -51.689254) (xy 107.347258 -51.660044)
			(xy 107.34548 -51.65725) (xy 107.340654 -51.650138) (xy 107.337098 -51.644296) (xy 107.336844 -51.643788)
			(xy 107.318326 -51.613744) (xy 107.287893 -51.550066) (xy 107.276138 -51.516788) (xy 107.275884 -51.515772)
			(xy 107.265144 -51.484239) (xy 107.250119 -51.419337) (xy 107.242618 -51.353143) (xy 107.24274 -51.286525)
			(xy 107.246166 -51.25339) (xy 107.24642 -51.250342) (xy 107.24642 -50.889916) (xy 107.246858 -50.856603)
			(xy 107.254374 -50.790402) (xy 107.261406 -50.757836) (xy 107.266475 -50.736866) (xy 107.279317 -50.695676)
			(xy 107.28706 -50.67554) (xy 107.290362 -50.667412) (xy 107.295641 -50.654927) (xy 107.307203 -50.630407)
			(xy 107.313476 -50.61839) (xy 107.323038 -50.600682) (xy 107.344265 -50.566488) (xy 107.355894 -50.550064)
			(xy 107.356656 -50.548794) (xy 107.356656 -50.336704) (xy 107.35564 -50.33518) (xy 107.344539 -50.319465)
			(xy 107.324201 -50.2868) (xy 107.315 -50.269902) (xy 107.309158 -50.258726) (xy 107.300059 -50.240311)
			(xy 107.28417 -50.202429) (xy 107.277408 -50.183034) (xy 107.276392 -50.180494) (xy 107.272836 -50.17135)
			(xy 107.263946 -50.139346) (xy 107.256298 -50.107098) (xy 107.247509 -50.041406) (xy 107.24642 -50.008282)
			(xy 107.24642 -49.553114) (xy 107.247182 -49.520602) (xy 107.247944 -49.507902) (xy 107.248198 -49.504854)
			(xy 107.249621 -49.489203) (xy 107.253943 -49.458071) (xy 107.256834 -49.442624) (xy 107.26166 -49.420018)
			(xy 107.263438 -49.412652) (xy 107.26674 -49.400206) (xy 107.272096 -49.381166) (xy 107.285061 -49.343796)
			(xy 107.292648 -49.32553) (xy 107.29849 -49.312576) (xy 107.299506 -49.310036) (xy 107.306364 -49.295558)
			(xy 107.315608 -49.277279) (xy 107.336328 -49.241939) (xy 107.347766 -49.224946) (xy 107.351874 -49.218493)
			(xy 107.356403 -49.203889) (xy 107.356656 -49.196244) (xy 107.356656 -44.511722) (xy 107.356441 -44.505492)
			(xy 107.35335 -44.49342) (xy 107.35056 -44.487846) (xy 106.496866 -42.891456) (xy 106.48823 -42.882058)
			(xy 106.482642 -42.878502) (xy 106.451061 -42.857664) (xy 106.392963 -42.809193) (xy 106.341525 -42.753705)
			(xy 106.297588 -42.692107) (xy 106.279188 -42.659046) (xy 106.045254 -42.221912) (xy 106.028617 -42.189628)
			(xy 106.002472 -42.12187) (xy 105.984828 -42.051417) (xy 105.975949 -41.979334) (xy 105.975404 -41.94302)
			(xy 105.975404 -41.93032) (xy 105.975658 -41.916858) (xy 105.92181 -41.816274) (xy 105.913174 -41.806876)
			(xy 105.907586 -41.80332) (xy 105.875935 -41.782499) (xy 105.817738 -41.733992) (xy 105.76623 -41.678434)
			(xy 105.722257 -41.616739) (xy 105.703878 -41.58361) (xy 105.470198 -41.146476) (xy 105.453598 -41.114246)
			(xy 105.427498 -41.046609) (xy 105.409858 -40.976289) (xy 105.400941 -40.904341) (xy 105.400348 -40.868092)
			(xy 105.400348 -40.867584) (xy 105.400602 -40.855392) (xy 105.400856 -40.842184) (xy 105.355898 -40.758618)
			(xy 105.355898 -40.75811) (xy 105.346754 -40.741092) (xy 105.338118 -40.731694) (xy 105.33253 -40.728138)
			(xy 105.300881 -40.707315) (xy 105.242687 -40.658806) (xy 105.191181 -40.603246) (xy 105.147211 -40.541551)
			(xy 105.128822 -40.508428) (xy 104.895142 -40.071294) (xy 104.87854 -40.039065) (xy 104.852436 -39.971428)
			(xy 104.834792 -39.901108) (xy 104.825872 -39.829159) (xy 104.825292 -39.79291) (xy 104.825292 -39.792402)
			(xy 104.825546 -39.78021) (xy 104.8258 -39.767002) (xy 104.771698 -39.66591) (xy 104.763062 -39.656512)
			(xy 104.757474 -39.652956) (xy 104.725822 -39.632135) (xy 104.667624 -39.583629) (xy 104.616113 -39.528072)
			(xy 104.572138 -39.466379) (xy 104.553766 -39.433246) (xy 104.320086 -38.996112) (xy 104.303484 -38.963883)
			(xy 104.277381 -38.896246) (xy 104.259736 -38.825926) (xy 104.250815 -38.753977) (xy 104.250236 -38.717728)
			(xy 104.250236 -38.71722) (xy 104.25049 -38.705028) (xy 104.250744 -38.69182) (xy 104.196642 -38.590728)
			(xy 104.188006 -38.58133) (xy 104.182418 -38.577774) (xy 104.150764 -38.556955) (xy 104.092561 -38.508453)
			(xy 104.041046 -38.452898) (xy 103.997065 -38.391206) (xy 103.97871 -38.358064) (xy 103.74503 -37.92093)
			(xy 103.728426 -37.888701) (xy 103.702319 -37.821065) (xy 103.684671 -37.750745) (xy 103.675747 -37.678796)
			(xy 103.67518 -37.642546) (xy 103.67518 -37.642038) (xy 103.675434 -37.629846) (xy 103.675688 -37.616384)
			(xy 103.624888 -37.521642) (xy 103.621653 -37.516051) (xy 103.612907 -37.506553) (xy 103.607616 -37.502846)
			(xy 103.607362 -37.502592) (xy 103.57571 -37.481772) (xy 103.51751 -37.433267) (xy 103.465997 -37.377711)
			(xy 103.42202 -37.316019) (xy 103.403654 -37.282882) (xy 103.169974 -36.845748) (xy 103.15337 -36.813519)
			(xy 103.127264 -36.745882) (xy 103.109615 -36.675563) (xy 103.10069 -36.603614) (xy 103.100124 -36.567364)
			(xy 103.100124 -36.566856) (xy 103.100378 -36.554664) (xy 103.100632 -36.541202) (xy 102.991158 -36.336478)
			(xy 102.975859 -36.306956) (xy 102.951346 -36.245145) (xy 102.934046 -36.180941) (xy 102.924183 -36.115182)
			(xy 102.922578 -36.08197) (xy 102.92207 -36.075366) (xy 102.918167 -36.050851) (xy 102.913971 -36.001383)
			(xy 102.913688 -35.97656) (xy 102.913688 -35.731704) (xy 102.904544 -35.702748) (xy 102.884583 -35.673033)
			(xy 102.851215 -35.609701) (xy 102.825753 -35.542797) (xy 102.808569 -35.473305) (xy 102.799916 -35.402245)
			(xy 102.799388 -35.366452) (xy 102.799388 -34.870644) (xy 102.79993 -34.834854) (xy 102.808613 -34.763802)
			(xy 102.825807 -34.694317) (xy 102.851263 -34.627416) (xy 102.884607 -34.564076) (xy 102.904544 -34.534348)
			(xy 102.913688 -34.505392) (xy 102.913688 -34.496248) (xy 102.892052 -34.465759) (xy 102.855812 -34.400366)
			(xy 102.82811 -34.330925) (xy 102.809388 -34.258544) (xy 102.799946 -34.184379) (xy 102.799388 -34.146998)
			(xy 102.799388 -33.650936) (xy 102.800051 -33.611196) (xy 102.810759 -33.53244) (xy 102.820724 -33.493964)
			(xy 102.822756 -33.486598) (xy 102.822248 -33.471612) (xy 102.818946 -33.461706) (xy 102.81539 -33.447482)
			(xy 102.813612 -33.440116) (xy 102.813358 -33.439608) (xy 102.809294 -33.423098) (xy 102.809294 -33.42259)
			(xy 102.808278 -33.418018) (xy 102.808278 -33.41751) (xy 102.807262 -33.41243) (xy 102.804722 -33.399984)
			(xy 102.80396 -33.395666) (xy 102.800077 -33.371151) (xy 102.796004 -33.32168) (xy 102.795832 -33.29686)
			(xy 102.795832 -32.854138) (xy 102.795903 -32.838998) (xy 102.797429 -32.808757) (xy 102.79888 -32.793686)
			(xy 102.799134 -32.792416) (xy 102.799388 -32.79013) (xy 102.799388 -32.431736) (xy 102.799764 -32.402065)
			(xy 102.80574 -32.343023) (xy 102.811326 -32.31388) (xy 102.812272 -32.308517) (xy 102.812139 -32.29763)
			(xy 102.811072 -32.29229) (xy 102.80394 -32.259737) (xy 102.796295 -32.193532) (xy 102.795832 -32.16021)
			(xy 102.795832 -31.71698) (xy 102.796284 -31.684647) (xy 102.803478 -31.620382) (xy 102.817754 -31.55731)
			(xy 102.838935 -31.496211) (xy 102.866759 -31.437836) (xy 102.883462 -31.410148) (xy 102.884224 -31.409132)
			(xy 102.884732 -31.407862) (xy 102.887018 -31.403544) (xy 102.890423 -31.396097) (xy 102.892751 -31.3799)
			(xy 102.89159 -31.371794) (xy 102.278942 -30.758892) (xy 102.266496 -30.757114) (xy 102.25913 -30.755844)
			(xy 102.258114 -30.75559) (xy 102.256082 -30.755336) (xy 102.254558 -30.755082) (xy 102.218961 -30.748067)
			(xy 102.14973 -30.72636) (xy 102.083733 -30.696221) (xy 102.02199 -30.658115) (xy 101.96546 -30.612635)
			(xy 101.939852 -30.586934) (xy 101.939344 -30.586426) (xy 101.634036 -30.281118) (xy 101.610993 -30.257402)
			(xy 101.569853 -30.205631) (xy 101.534839 -30.149535) (xy 101.506404 -30.089834) (xy 101.484912 -30.027297)
			(xy 101.477318 -29.995114) (xy 101.476011 -29.991735) (xy 101.472564 -29.985364) (xy 101.47046 -29.982414)
			(xy 101.467666 -29.979366) (xy 101.466142 -29.977334) (xy 101.447092 -29.958284) (xy 101.445822 -29.957268)
			(xy 101.444298 -29.955744) (xy 101.440337 -29.952436) (xy 101.431378 -29.947319) (xy 101.426518 -29.945584)
			(xy 101.394553 -29.937925) (xy 101.332459 -29.916359) (xy 101.273188 -29.887938) (xy 101.217495 -29.853023)
			(xy 101.166088 -29.812058) (xy 101.142546 -29.78912) (xy 100.829872 -29.476446) (xy 100.804252 -29.450061)
			(xy 100.759172 -29.391952) (xy 100.721758 -29.328634) (xy 100.706682 -29.29509) (xy 100.704396 -29.289756)
			(xy 100.6983 -29.281374) (xy 100.695506 -29.278834) (xy 100.692024 -29.27555) (xy 100.684096 -29.270189)
			(xy 100.679758 -29.268166) (xy 100.646992 -29.254704) (xy 100.646484 -29.254704) (xy 100.620322 -29.244036)
			(xy 100.616155 -29.242556) (xy 100.607469 -29.240896) (xy 100.60305 -29.240734) (xy 100.575872 -29.240734)
			(xy 100.567236 -29.244036) (xy 100.534313 -29.256022) (xy 100.466317 -29.272921) (xy 100.396781 -29.281521)
			(xy 100.36175 -29.282136) (xy 99.917758 -29.282136) (xy 99.88164 -29.281593) (xy 99.809959 -29.272657)
			(xy 99.739936 -29.254914) (xy 99.672649 -29.228639) (xy 99.609133 -29.194234) (xy 99.57943 -29.173678)
			(xy 99.572826 -29.169106) (xy 99.558094 -29.16428) (xy 99.464622 -29.16428) (xy 99.425545 -29.163629)
			(xy 99.348075 -29.153304) (xy 99.31019 -29.143706) (xy 99.307142 -29.142944) (xy 99.274235 -29.135556)
			(xy 99.210264 -29.114191) (xy 99.14919 -29.085575) (xy 99.091833 -29.050093) (xy 99.038961 -29.00822)
			(xy 99.014788 -28.984702) (xy 98.972624 -28.942792) (xy 98.881438 -28.851606) (xy 98.87851 -28.848718)
			(xy 98.87187 -28.843867) (xy 98.86823 -28.841954) (xy 98.860864 -28.838398) (xy 98.855784 -28.837636)
			(xy 98.85172 -28.837128) (xy 98.83521 -28.834588) (xy 98.834194 -28.834334) (xy 98.832162 -28.83408)
			(xy 98.830638 -28.833826) (xy 98.795041 -28.826811) (xy 98.725811 -28.805103) (xy 98.659813 -28.774963)
			(xy 98.59807 -28.736859) (xy 98.541539 -28.69138) (xy 98.515932 -28.665678) (xy 98.515424 -28.66517)
			(xy 98.210116 -28.359862) (xy 98.186902 -28.335975) (xy 98.14552 -28.283777) (xy 98.127566 -28.255722)
			(xy 98.127312 -28.255468) (xy 98.123756 -28.24988) (xy 98.122994 -28.24861) (xy 98.12274 -28.248102)
			(xy 98.120454 -28.244292) (xy 98.101603 -28.211153) (xy 98.071723 -28.14101) (xy 98.051243 -28.067571)
			(xy 98.04527 -28.029916) (xy 98.044 -28.021534) (xy 98.040698 -28.014676) (xy 98.03876 -28.010994)
			(xy 98.033905 -28.004238) (xy 98.031046 -28.001214) (xy 97.926144 -27.896312) (xy 97.918778 -27.890216)
			(xy 97.759012 -27.890216) (xy 97.752282 -27.895121) (xy 97.742182 -27.908347) (xy 97.7392 -27.916124)
			(xy 97.731072 -27.940254) (xy 97.7265 -27.95016) (xy 97.708212 -27.980894) (xy 97.704997 -27.986558)
			(xy 97.701264 -27.999032) (xy 97.700846 -28.005532) (xy 97.700592 -28.018486) (xy 97.706688 -28.030424)
			(xy 97.707196 -28.03144) (xy 97.70745 -28.031694) (xy 97.712784 -28.042108) (xy 97.724731 -28.066335)
			(xy 97.743504 -28.116987) (xy 97.7562 -28.169492) (xy 97.762643 -28.223125) (xy 97.763076 -28.250134)
			(xy 97.763076 -29.114242) (xy 97.762586 -29.144226) (xy 97.754758 -29.203682) (xy 97.739237 -29.261607)
			(xy 97.716288 -29.317011) (xy 97.686304 -29.368945) (xy 97.649798 -29.416521) (xy 97.607393 -29.458926)
			(xy 97.559817 -29.495432) (xy 97.507883 -29.525416) (xy 97.452479 -29.548365) (xy 97.394554 -29.563886)
			(xy 97.335098 -29.571714) (xy 97.27513 -29.571714) (xy 97.215674 -29.563886) (xy 97.157749 -29.548365)
			(xy 97.102345 -29.525416) (xy 97.050411 -29.495432) (xy 97.002835 -29.458926) (xy 96.96043 -29.416521)
			(xy 96.923924 -29.368945) (xy 96.89394 -29.317011) (xy 96.870991 -29.261607) (xy 96.85547 -29.203682)
			(xy 96.847642 -29.144226) (xy 96.847152 -29.114242) (xy 96.847152 -28.246324) (xy 96.847976 -28.21471)
			(xy 96.857265 -28.152156) (xy 96.875086 -28.091478) (xy 96.901101 -28.033837) (xy 96.91751 -28.006802)
			(xy 96.92132 -28.000706) (xy 96.925892 -27.984704) (xy 96.927659 -27.977488) (xy 96.927414 -27.96264)
			(xy 96.925384 -27.955494) (xy 96.923606 -27.949398) (xy 96.912176 -27.91587) (xy 96.872552 -27.882088)
			(xy 96.836663 -27.87543) (xy 96.766757 -27.85442) (xy 96.699969 -27.824967) (xy 96.637312 -27.787519)
			(xy 96.579739 -27.742646) (xy 96.553528 -27.717242) (xy 96.490282 -27.653996) (xy 96.482856 -27.647222)
			(xy 96.46426 -27.639635) (xy 96.454214 -27.639264) (xy 95.541846 -27.639264) (xy 95.531813 -27.639701)
			(xy 95.513235 -27.647272) (xy 95.505778 -27.653996) (xy 95.399098 -27.760676) (xy 95.37534 -27.783819)
			(xy 95.323498 -27.825193) (xy 95.267349 -27.860501) (xy 95.207599 -27.8893) (xy 95.145001 -27.911228)
			(xy 95.08034 -27.926007) (xy 95.014432 -27.933453) (xy 94.981268 -27.933904) (xy 94.948106 -27.933454)
			(xy 94.882201 -27.926023) (xy 94.817542 -27.911258) (xy 94.754944 -27.889344) (xy 94.695193 -27.860558)
			(xy 94.639042 -27.825261) (xy 94.587197 -27.783898) (xy 94.540311 -27.736989) (xy 94.498973 -27.685124)
			(xy 94.463704 -27.628956) (xy 94.434947 -27.569192) (xy 94.413063 -27.506583) (xy 94.398329 -27.441917)
			(xy 94.39093 -27.376008) (xy 94.390464 -27.342846) (xy 94.390889 -27.310542) (xy 94.397917 -27.246317)
			(xy 94.411906 -27.183242) (xy 94.432689 -27.122068) (xy 94.460017 -27.063524) (xy 94.493566 -27.008309)
			(xy 94.512892 -26.98242) (xy 94.517972 -26.975816) (xy 94.52356 -26.960068) (xy 94.52356 -26.864056)
			(xy 94.521782 -26.850848) (xy 94.512892 -26.839672) (xy 94.493564 -26.813834) (xy 94.460036 -26.758702)
			(xy 94.432718 -26.700242) (xy 94.411939 -26.639152) (xy 94.397944 -26.57616) (xy 94.390902 -26.512018)
			(xy 94.390464 -26.479754) (xy 94.390464 -26.479246) (xy 94.391 -26.443535) (xy 94.399602 -26.372632)
			(xy 94.416686 -26.303282) (xy 94.442002 -26.236497) (xy 94.475183 -26.17325) (xy 94.515744 -26.114462)
			(xy 94.563094 -26.060991) (xy 94.616543 -26.013616) (xy 94.675312 -25.973027) (xy 94.738544 -25.939817)
			(xy 94.805317 -25.914469) (xy 94.874658 -25.897352) (xy 94.945557 -25.888717) (xy 94.981268 -25.888188)
			(xy 95.01443 -25.888667) (xy 95.080335 -25.89612) (xy 95.144991 -25.910902) (xy 95.207587 -25.932828)
			(xy 95.267335 -25.961621) (xy 95.323486 -25.99692) (xy 95.375333 -26.038283) (xy 95.399098 -26.061416)
			(xy 95.498158 -26.160476) (xy 95.505579 -26.167263) (xy 95.524176 -26.174875) (xy 95.534226 -26.175208)
			(xy 96.837246 -26.175208) (xy 96.8756 -26.175813) (xy 96.951663 -26.185745) (xy 96.988884 -26.19502)
			(xy 96.995488 -26.196544) (xy 97.013244 -26.198889) (xy 97.048449 -26.205497) (xy 97.065846 -26.209752)
			(xy 97.075498 -26.212292) (xy 97.084642 -26.211022) (xy 97.089504 -26.210299) (xy 97.098844 -26.207234)
			(xy 97.103184 -26.204926) (xy 97.117154 -26.196798) (xy 97.120268 -26.195001) (xy 97.126006 -26.190668)
			(xy 97.128584 -26.188162) (xy 97.132648 -26.183844) (xy 97.136204 -26.17724) (xy 97.150684 -26.152022)
			(xy 97.186088 -26.105894) (xy 97.228073 -26.065663) (xy 97.275667 -26.032256) (xy 97.327774 -26.006446)
			(xy 97.383189 -25.988828) (xy 97.440634 -25.979809) (xy 97.469706 -25.97912) (xy 97.471484 -25.97912)
			(xy 97.498036 -25.979582) (xy 97.550626 -25.986952) (xy 97.601688 -26.001537) (xy 97.650237 -26.023056)
			(xy 97.695336 -26.051094) (xy 97.736115 -26.085111) (xy 97.771787 -26.124449) (xy 97.801665 -26.168351)
			(xy 97.825172 -26.215969) (xy 97.841855 -26.266385) (xy 97.851391 -26.318626) (xy 97.851458 -26.319734)
			(xy 102.841804 -26.319734) (xy 102.845875 -26.264112) (xy 102.858001 -26.209675) (xy 102.877924 -26.157584)
			(xy 102.90522 -26.108949) (xy 102.939306 -26.064806) (xy 102.979455 -26.026097) (xy 103.024813 -25.993646)
			(xy 103.074413 -25.968145) (xy 103.127197 -25.950138) (xy 103.18204 -25.940008) (xy 103.237774 -25.937971)
			(xy 103.293211 -25.944071) (xy 103.347168 -25.958177) (xy 103.398497 -25.979989) (xy 103.446103 -26.009043)
			(xy 103.475768 -26.03373) (xy 121.368056 -26.03373) (xy 121.372127 -25.978108) (xy 121.384253 -25.923671)
			(xy 121.404176 -25.87158) (xy 121.431472 -25.822945) (xy 121.465558 -25.778802) (xy 121.505707 -25.740093)
			(xy 121.551065 -25.707642) (xy 121.600665 -25.682141) (xy 121.653449 -25.664134) (xy 121.708292 -25.654004)
			(xy 121.764026 -25.651967) (xy 121.819463 -25.658067) (xy 121.87342 -25.672173) (xy 121.924749 -25.693985)
			(xy 121.972355 -25.723039) (xy 122.015223 -25.758714) (xy 122.05244 -25.800251) (xy 122.083213 -25.846764)
			(xy 122.106885 -25.897261) (xy 122.122953 -25.950668) (xy 122.131073 -26.005844) (xy 122.131582 -26.03373)
			(xy 122.131073 -26.061616) (xy 122.122953 -26.116792) (xy 122.106885 -26.170199) (xy 122.083213 -26.220696)
			(xy 122.052979 -26.266394) (xy 124.620782 -26.266394) (xy 124.621268 -26.239143) (xy 124.629024 -26.185195)
			(xy 124.644379 -26.1329) (xy 124.667021 -26.083323) (xy 124.696487 -26.037473) (xy 124.732178 -25.996282)
			(xy 124.773369 -25.960591) (xy 124.819219 -25.931125) (xy 124.868796 -25.908483) (xy 124.921091 -25.893128)
			(xy 124.975039 -25.885372) (xy 125.029541 -25.885372) (xy 125.083489 -25.893128) (xy 125.135784 -25.908483)
			(xy 125.185361 -25.931125) (xy 125.231211 -25.960591) (xy 125.272402 -25.996282) (xy 125.308093 -26.037473)
			(xy 125.337559 -26.083323) (xy 125.360201 -26.1329) (xy 125.375556 -26.185195) (xy 125.383312 -26.239143)
			(xy 125.383798 -26.266394) (xy 125.383247 -26.295882) (xy 125.374152 -26.354152) (xy 125.356194 -26.410328)
			(xy 125.3298 -26.463068) (xy 125.295601 -26.511116) (xy 125.254412 -26.553325) (xy 125.231144 -26.571448)
			(xy 125.219995 -26.580313) (xy 125.202818 -26.603024) (xy 125.192576 -26.629593) (xy 125.190064 -26.657958)
			(xy 125.195478 -26.685914) (xy 125.208397 -26.71129) (xy 125.227817 -26.732115) (xy 125.23978 -26.73985)
			(xy 125.263512 -26.754762) (xy 125.306748 -26.790426) (xy 125.344301 -26.832032) (xy 125.375362 -26.878684)
			(xy 125.399262 -26.92938) (xy 125.415488 -26.983027) (xy 125.423689 -27.038471) (xy 125.424184 -27.066494)
			(xy 125.423698 -27.093745) (xy 125.415942 -27.147693) (xy 125.400587 -27.199988) (xy 125.377945 -27.249565)
			(xy 125.348479 -27.295415) (xy 125.312788 -27.336606) (xy 125.271597 -27.372297) (xy 125.225747 -27.401763)
			(xy 125.17617 -27.424405) (xy 125.123875 -27.43976) (xy 125.069927 -27.447516) (xy 125.015425 -27.447516)
			(xy 124.961477 -27.43976) (xy 124.909182 -27.424405) (xy 124.859605 -27.401763) (xy 124.813755 -27.372297)
			(xy 124.772564 -27.336606) (xy 124.736873 -27.295415) (xy 124.707407 -27.249565) (xy 124.684765 -27.199988)
			(xy 124.66941 -27.147693) (xy 124.661654 -27.093745) (xy 124.661168 -27.066494) (xy 124.661724 -27.037007)
			(xy 124.67082 -26.978737) (xy 124.688778 -26.922562) (xy 124.71517 -26.869822) (xy 124.749368 -26.821774)
			(xy 124.790555 -26.779564) (xy 124.813822 -26.76144) (xy 124.824885 -26.752475) (xy 124.842068 -26.729789)
			(xy 124.85232 -26.703242) (xy 124.854845 -26.674895) (xy 124.849447 -26.646954) (xy 124.836544 -26.621588)
			(xy 124.81714 -26.600771) (xy 124.805186 -26.593038) (xy 124.781441 -26.578146) (xy 124.738206 -26.542478)
			(xy 124.700656 -26.500868) (xy 124.669597 -26.454212) (xy 124.645699 -26.403513) (xy 124.629475 -26.349864)
			(xy 124.621276 -26.294418) (xy 124.620782 -26.266394) (xy 122.052979 -26.266394) (xy 122.05244 -26.267209)
			(xy 122.015223 -26.308746) (xy 121.972355 -26.344421) (xy 121.924749 -26.373475) (xy 121.87342 -26.395287)
			(xy 121.819463 -26.409393) (xy 121.764026 -26.415493) (xy 121.708292 -26.413456) (xy 121.653449 -26.403326)
			(xy 121.600665 -26.385319) (xy 121.551065 -26.359818) (xy 121.505707 -26.327367) (xy 121.465558 -26.288658)
			(xy 121.431472 -26.244515) (xy 121.404176 -26.19588) (xy 121.384253 -26.143789) (xy 121.372127 -26.089352)
			(xy 121.368056 -26.03373) (xy 103.475768 -26.03373) (xy 103.488971 -26.044718) (xy 103.526188 -26.086255)
			(xy 103.556961 -26.132768) (xy 103.580633 -26.183265) (xy 103.596701 -26.236672) (xy 103.604821 -26.291848)
			(xy 103.60533 -26.319734) (xy 103.604821 -26.34762) (xy 103.596701 -26.402796) (xy 103.580633 -26.456203)
			(xy 103.556961 -26.5067) (xy 103.526188 -26.553213) (xy 103.488971 -26.59475) (xy 103.446103 -26.630425)
			(xy 103.398497 -26.659479) (xy 103.347168 -26.681291) (xy 103.293211 -26.695397) (xy 103.237774 -26.701497)
			(xy 103.18204 -26.69946) (xy 103.127197 -26.68933) (xy 103.074413 -26.671323) (xy 103.024813 -26.645822)
			(xy 102.979455 -26.613371) (xy 102.939306 -26.574662) (xy 102.90522 -26.530519) (xy 102.877924 -26.481884)
			(xy 102.858001 -26.429793) (xy 102.845875 -26.375356) (xy 102.841804 -26.319734) (xy 97.851458 -26.319734)
			(xy 97.852992 -26.345134) (xy 97.8535 -26.354786) (xy 97.858834 -26.366978) (xy 97.860631 -26.370373)
			(xy 97.865098 -26.37662) (xy 97.867724 -26.379424) (xy 97.884742 -26.39568) (xy 97.902268 -26.412444)
			(xy 97.909621 -26.418922) (xy 97.927784 -26.426229) (xy 97.937574 -26.426668) (xy 98.307906 -26.426668)
			(xy 98.341061 -26.427132) (xy 98.406955 -26.434552) (xy 98.471604 -26.449299) (xy 98.534198 -26.471186)
			(xy 98.593949 -26.49994) (xy 98.650108 -26.535199) (xy 98.701969 -26.576521) (xy 98.725736 -26.599642)
			(xy 98.853244 -26.726896) (xy 98.861019 -26.73399) (xy 98.880566 -26.741727) (xy 98.89109 -26.741882)
			(xy 98.90633 -26.741374) (xy 98.911596 -26.741014) (xy 98.921832 -26.738449) (xy 98.92665 -26.736294)
			(xy 98.935286 -26.731976) (xy 98.942398 -26.723848) (xy 98.942906 -26.72334) (xy 98.961127 -26.702775)
			(xy 99.002457 -26.666575) (xy 99.048549 -26.636672) (xy 99.09845 -26.613682) (xy 99.15113 -26.59808)
			(xy 99.205503 -26.590189) (xy 99.232974 -26.589736) (xy 99.260711 -26.590239) (xy 99.315598 -26.59828)
			(xy 99.368743 -26.614183) (xy 99.419026 -26.637612) (xy 99.465388 -26.668074) (xy 99.506851 -26.704926)
			(xy 99.542542 -26.747393) (xy 99.57171 -26.79458) (xy 99.593739 -26.845492) (xy 99.608165 -26.899057)
			(xy 99.611942 -26.92654) (xy 99.613466 -26.940256) (xy 99.614736 -26.971244) (xy 99.614736 -26.971498)
			(xy 99.614277 -26.998457) (xy 99.606694 -27.05184) (xy 99.591666 -27.103622) (xy 99.569491 -27.152769)
			(xy 99.540613 -27.198302) (xy 99.505608 -27.239312) (xy 99.485704 -27.257502) (xy 99.480624 -27.262074)
			(xy 99.473258 -27.271472) (xy 99.469023 -27.277437) (xy 99.463873 -27.291121) (xy 99.463098 -27.298396)
			(xy 99.46259 -27.311858) (xy 99.46259 -27.313128) (xy 99.462646 -27.323691) (xy 99.470262 -27.343369)
			(xy 99.477322 -27.351228) (xy 99.811586 -27.685238) (xy 99.818986 -27.692078) (xy 99.837585 -27.69979)
			(xy 99.847654 -27.700224) (xy 101.045772 -27.700224) (xy 101.078934 -27.700704) (xy 101.144838 -27.708158)
			(xy 101.209493 -27.722941) (xy 101.272088 -27.744867) (xy 101.331835 -27.773662) (xy 101.387983 -27.808964)
			(xy 101.439828 -27.850328) (xy 101.463602 -27.873452) (xy 101.768656 -28.178252) (xy 101.775669 -28.184757)
			(xy 101.793158 -28.192472) (xy 101.802692 -28.193238) (xy 101.810566 -28.193492) (xy 101.811074 -28.193492)
			(xy 101.848412 -28.194508) (xy 101.853207 -28.19455) (xy 101.862671 -28.193013) (xy 101.867208 -28.19146)
			(xy 101.874828 -28.188666) (xy 101.881432 -28.183078) (xy 101.882956 -28.181808) (xy 101.888544 -28.177236)
			(xy 101.888798 -28.176982) (xy 101.890068 -28.175966) (xy 101.890322 -28.175712) (xy 102.001574 -28.0797)
			(xy 102.010774 -28.072477) (xy 102.033368 -28.066534) (xy 102.056259 -28.071209) (xy 102.065836 -28.077922)
			(xy 102.072186 -28.082748) (xy 102.091236 -28.08986) (xy 102.10292 -28.088844) (xy 102.133654 -28.087574)
			(xy 102.1588 -28.087574) (xy 102.165912 -28.088082) (xy 102.188772 -28.091384) (xy 102.215508 -28.095707)
			(xy 102.267485 -28.110919) (xy 102.316788 -28.133331) (xy 102.325873 -28.139136) (xy 118.49811 -28.139136)
			(xy 118.502181 -28.083514) (xy 118.514307 -28.029077) (xy 118.53423 -27.976986) (xy 118.561526 -27.928351)
			(xy 118.595612 -27.884208) (xy 118.635761 -27.845499) (xy 118.681119 -27.813048) (xy 118.730719 -27.787547)
			(xy 118.783503 -27.76954) (xy 118.838346 -27.75941) (xy 118.89408 -27.757373) (xy 118.949517 -27.763473)
			(xy 119.003474 -27.777579) (xy 119.054803 -27.799391) (xy 119.102409 -27.828445) (xy 119.145277 -27.86412)
			(xy 119.182494 -27.905657) (xy 119.213267 -27.95217) (xy 119.236939 -28.002667) (xy 119.253007 -28.056074)
			(xy 119.261127 -28.11125) (xy 119.261636 -28.139136) (xy 119.76811 -28.139136) (xy 119.772181 -28.083514)
			(xy 119.784307 -28.029077) (xy 119.80423 -27.976986) (xy 119.831526 -27.928351) (xy 119.865612 -27.884208)
			(xy 119.905761 -27.845499) (xy 119.951119 -27.813048) (xy 120.000719 -27.787547) (xy 120.053503 -27.76954)
			(xy 120.108346 -27.75941) (xy 120.16408 -27.757373) (xy 120.219517 -27.763473) (xy 120.273474 -27.777579)
			(xy 120.324803 -27.799391) (xy 120.372409 -27.828445) (xy 120.415277 -27.86412) (xy 120.452494 -27.905657)
			(xy 120.483267 -27.95217) (xy 120.506939 -28.002667) (xy 120.523007 -28.056074) (xy 120.531127 -28.11125)
			(xy 120.531636 -28.139136) (xy 120.531127 -28.167022) (xy 120.523007 -28.222198) (xy 120.506939 -28.275605)
			(xy 120.483267 -28.326102) (xy 120.452494 -28.372615) (xy 120.415277 -28.414152) (xy 120.372409 -28.449827)
			(xy 120.324803 -28.478881) (xy 120.273474 -28.500693) (xy 120.219517 -28.514799) (xy 120.16408 -28.520899)
			(xy 120.108346 -28.518862) (xy 120.053503 -28.508732) (xy 120.000719 -28.490725) (xy 119.951119 -28.465224)
			(xy 119.905761 -28.432773) (xy 119.865612 -28.394064) (xy 119.831526 -28.349921) (xy 119.80423 -28.301286)
			(xy 119.784307 -28.249195) (xy 119.772181 -28.194758) (xy 119.76811 -28.139136) (xy 119.261636 -28.139136)
			(xy 119.261127 -28.167022) (xy 119.253007 -28.222198) (xy 119.236939 -28.275605) (xy 119.213267 -28.326102)
			(xy 119.182494 -28.372615) (xy 119.145277 -28.414152) (xy 119.102409 -28.449827) (xy 119.054803 -28.478881)
			(xy 119.003474 -28.500693) (xy 118.949517 -28.514799) (xy 118.89408 -28.520899) (xy 118.838346 -28.518862)
			(xy 118.783503 -28.508732) (xy 118.730719 -28.490725) (xy 118.681119 -28.465224) (xy 118.635761 -28.432773)
			(xy 118.595612 -28.394064) (xy 118.561526 -28.349921) (xy 118.53423 -28.301286) (xy 118.514307 -28.249195)
			(xy 118.502181 -28.194758) (xy 118.49811 -28.139136) (xy 102.325873 -28.139136) (xy 102.362424 -28.162492)
			(xy 102.403477 -28.197815) (xy 102.439119 -28.23859) (xy 102.468636 -28.283998) (xy 102.491432 -28.333124)
			(xy 102.507049 -28.384981) (xy 102.511606 -28.411678) (xy 102.511606 -28.412186) (xy 102.513892 -28.42641)
			(xy 102.514654 -28.438856) (xy 102.514654 -28.439364) (xy 102.515924 -28.464002) (xy 102.515924 -28.46959)
			(xy 102.514654 -28.500832) (xy 102.513638 -28.512008) (xy 102.517702 -28.522676) (xy 102.519714 -28.52777)
			(xy 102.525613 -28.536994) (xy 102.529386 -28.540964) (xy 102.535482 -28.54706) (xy 102.536244 -28.566618)
			(xy 102.536217 -28.57625) (xy 102.529813 -28.5944) (xy 102.523798 -28.601924) (xy 102.427786 -28.713176)
			(xy 102.427532 -28.71343) (xy 102.426516 -28.7147) (xy 102.426262 -28.714954) (xy 102.42169 -28.720542)
			(xy 102.42042 -28.722066) (xy 102.414832 -28.72867) (xy 102.412038 -28.73629) (xy 102.410519 -28.740835)
			(xy 102.408981 -28.750294) (xy 102.40899 -28.755086) (xy 102.410006 -28.792424) (xy 102.410006 -28.792932)
			(xy 102.41026 -28.800806) (xy 102.411014 -28.8104) (xy 102.418729 -28.828013) (xy 102.425246 -28.835096)
			(xy 102.71252 -29.12237) (xy 124.706888 -29.12237) (xy 124.706888 -28.25877) (xy 124.707378 -28.228786)
			(xy 124.715206 -28.16933) (xy 124.730727 -28.111405) (xy 124.753676 -28.056001) (xy 124.78366 -28.004067)
			(xy 124.820166 -27.956491) (xy 124.862571 -27.914086) (xy 124.910147 -27.87758) (xy 124.962081 -27.847596)
			(xy 125.017485 -27.824647) (xy 125.07541 -27.809126) (xy 125.134866 -27.801298) (xy 125.194834 -27.801298)
			(xy 125.25429 -27.809126) (xy 125.312215 -27.824647) (xy 125.367619 -27.847596) (xy 125.419553 -27.87758)
			(xy 125.467129 -27.914086) (xy 125.509534 -27.956491) (xy 125.54604 -28.004067) (xy 125.576024 -28.056001)
			(xy 125.598973 -28.111405) (xy 125.614494 -28.16933) (xy 125.622322 -28.228786) (xy 125.622812 -28.25877)
			(xy 125.622812 -29.12237) (xy 125.622322 -29.152354) (xy 125.614494 -29.21181) (xy 125.598973 -29.269735)
			(xy 125.576024 -29.325139) (xy 125.54604 -29.377073) (xy 125.509534 -29.424649) (xy 125.467129 -29.467054)
			(xy 125.419553 -29.50356) (xy 125.367619 -29.533544) (xy 125.312215 -29.556493) (xy 125.25429 -29.572014)
			(xy 125.194834 -29.579842) (xy 125.134866 -29.579842) (xy 125.07541 -29.572014) (xy 125.017485 -29.556493)
			(xy 124.962081 -29.533544) (xy 124.910147 -29.50356) (xy 124.862571 -29.467054) (xy 124.820166 -29.424649)
			(xy 124.78366 -29.377073) (xy 124.753676 -29.325139) (xy 124.730727 -29.269735) (xy 124.715206 -29.21181)
			(xy 124.707378 -29.152354) (xy 124.706888 -29.12237) (xy 102.71252 -29.12237) (xy 103.967026 -30.376876)
			(xy 116.989098 -30.376876) (xy 116.989672 -30.347961) (xy 116.998389 -30.290793) (xy 117.015636 -30.235595)
			(xy 117.041017 -30.183633) (xy 117.073951 -30.136098) (xy 117.113683 -30.094078) (xy 117.136164 -30.075886)
			(xy 117.144978 -30.068286) (xy 117.155155 -30.047379) (xy 117.155722 -30.035754) (xy 117.155722 -29.955998)
			(xy 117.155162 -29.944369) (xy 117.144987 -29.92346) (xy 117.136164 -29.915866) (xy 117.113657 -29.897703)
			(xy 117.073925 -29.855677) (xy 117.04099 -29.808135) (xy 117.015606 -29.756169) (xy 116.998354 -29.700967)
			(xy 116.98963 -29.643794) (xy 116.989098 -29.614876) (xy 116.989584 -29.587625) (xy 116.99734 -29.533677)
			(xy 117.012695 -29.481382) (xy 117.035337 -29.431805) (xy 117.064803 -29.385955) (xy 117.100494 -29.344764)
			(xy 117.141685 -29.309073) (xy 117.187535 -29.279607) (xy 117.237112 -29.256965) (xy 117.289407 -29.24161)
			(xy 117.343355 -29.233854) (xy 117.397857 -29.233854) (xy 117.451805 -29.24161) (xy 117.5041 -29.256965)
			(xy 117.553677 -29.279607) (xy 117.599527 -29.309073) (xy 117.640718 -29.344764) (xy 117.676409 -29.385955)
			(xy 117.705875 -29.431805) (xy 117.728517 -29.481382) (xy 117.743872 -29.533677) (xy 117.751628 -29.587625)
			(xy 117.752114 -29.614876) (xy 117.751611 -29.643794) (xy 117.742884 -29.700967) (xy 117.725625 -29.756168)
			(xy 117.70023 -29.80813) (xy 117.667282 -29.855663) (xy 117.627536 -29.897678) (xy 117.605048 -29.915866)
			(xy 117.596257 -29.923489) (xy 117.586067 -29.944378) (xy 117.58549 -29.955998) (xy 117.58549 -30.035754)
			(xy 117.586016 -30.047387) (xy 117.596215 -30.068296) (xy 117.605048 -30.075886) (xy 117.627535 -30.094073)
			(xy 117.667268 -30.136095) (xy 117.700205 -30.183631) (xy 117.725592 -30.235593) (xy 117.742848 -30.290791)
			(xy 117.751578 -30.34796) (xy 117.752114 -30.376876) (xy 120.029224 -30.376876) (xy 120.029788 -30.347961)
			(xy 120.038506 -30.290791) (xy 120.055754 -30.235593) (xy 120.081137 -30.183631) (xy 120.114073 -30.136096)
			(xy 120.153808 -30.094077) (xy 120.17629 -30.075886) (xy 120.185092 -30.068274) (xy 120.195279 -30.047377)
			(xy 120.195848 -30.035754) (xy 120.195848 -29.955998) (xy 120.195314 -29.944365) (xy 120.185123 -29.923454)
			(xy 120.17629 -29.915866) (xy 120.153788 -29.897697) (xy 120.114055 -29.855672) (xy 120.081118 -29.808133)
			(xy 120.055733 -29.756167) (xy 120.038481 -29.700966) (xy 120.029756 -29.643793) (xy 120.029224 -29.614876)
			(xy 120.02971 -29.587625) (xy 120.037466 -29.533677) (xy 120.052821 -29.481382) (xy 120.075463 -29.431805)
			(xy 120.104929 -29.385955) (xy 120.14062 -29.344764) (xy 120.181811 -29.309073) (xy 120.227661 -29.279607)
			(xy 120.277238 -29.256965) (xy 120.329533 -29.24161) (xy 120.383481 -29.233854) (xy 120.437983 -29.233854)
			(xy 120.491931 -29.24161) (xy 120.544226 -29.256965) (xy 120.593803 -29.279607) (xy 120.639653 -29.309073)
			(xy 120.680844 -29.344764) (xy 120.716535 -29.385955) (xy 120.746001 -29.431805) (xy 120.768643 -29.481382)
			(xy 120.783998 -29.533677) (xy 120.791754 -29.587625) (xy 120.79224 -29.614876) (xy 120.791727 -29.643793)
			(xy 120.783 -29.700966) (xy 120.765743 -29.756166) (xy 120.74035 -29.808128) (xy 120.707405 -29.855662)
			(xy 120.667661 -29.897677) (xy 120.645174 -29.915866) (xy 120.636388 -29.923493) (xy 120.626194 -29.944379)
			(xy 120.625616 -29.955998) (xy 120.625616 -30.035754) (xy 120.626133 -30.047389) (xy 120.636337 -30.068298)
			(xy 120.645174 -30.075886) (xy 120.667645 -30.094092) (xy 120.707382 -30.136107) (xy 120.740324 -30.183639)
			(xy 120.765714 -30.235598) (xy 120.782973 -30.290793) (xy 120.791704 -30.347961) (xy 120.79224 -30.376876)
			(xy 120.791754 -30.404127) (xy 120.783998 -30.458075) (xy 120.768643 -30.51037) (xy 120.746001 -30.559947)
			(xy 120.716535 -30.605797) (xy 120.680844 -30.646988) (xy 120.639653 -30.682679) (xy 120.593803 -30.712145)
			(xy 120.544226 -30.734787) (xy 120.491931 -30.750142) (xy 120.437983 -30.757898) (xy 120.383481 -30.757898)
			(xy 120.329533 -30.750142) (xy 120.277238 -30.734787) (xy 120.227661 -30.712145) (xy 120.181811 -30.682679)
			(xy 120.14062 -30.646988) (xy 120.104929 -30.605797) (xy 120.075463 -30.559947) (xy 120.052821 -30.51037)
			(xy 120.037466 -30.458075) (xy 120.02971 -30.404127) (xy 120.029224 -30.376876) (xy 117.752114 -30.376876)
			(xy 117.751628 -30.404127) (xy 117.743872 -30.458075) (xy 117.728517 -30.51037) (xy 117.705875 -30.559947)
			(xy 117.676409 -30.605797) (xy 117.640718 -30.646988) (xy 117.599527 -30.682679) (xy 117.553677 -30.712145)
			(xy 117.5041 -30.734787) (xy 117.451805 -30.750142) (xy 117.397857 -30.757898) (xy 117.343355 -30.757898)
			(xy 117.289407 -30.750142) (xy 117.237112 -30.734787) (xy 117.187535 -30.712145) (xy 117.141685 -30.682679)
			(xy 117.100494 -30.646988) (xy 117.064803 -30.605797) (xy 117.035337 -30.559947) (xy 117.012695 -30.51037)
			(xy 116.99734 -30.458075) (xy 116.989584 -30.404127) (xy 116.989098 -30.376876) (xy 103.967026 -30.376876)
			(xy 104.204262 -30.614112) (xy 104.227373 -30.63789) (xy 104.268708 -30.689743) (xy 104.303979 -30.745897)
			(xy 104.332742 -30.805646) (xy 104.354635 -30.868239) (xy 104.367006 -30.922468) (xy 122.852688 -30.922468)
			(xy 122.852688 -30.058868) (xy 122.853178 -30.028884) (xy 122.861006 -29.969428) (xy 122.876527 -29.911503)
			(xy 122.899476 -29.856099) (xy 122.92946 -29.804165) (xy 122.965966 -29.756589) (xy 123.008371 -29.714184)
			(xy 123.055947 -29.677678) (xy 123.107881 -29.647694) (xy 123.163285 -29.624745) (xy 123.22121 -29.609224)
			(xy 123.280666 -29.601396) (xy 123.340634 -29.601396) (xy 123.40009 -29.609224) (xy 123.458015 -29.624745)
			(xy 123.513419 -29.647694) (xy 123.565353 -29.677678) (xy 123.612929 -29.714184) (xy 123.655334 -29.756589)
			(xy 123.69184 -29.804165) (xy 123.721824 -29.856099) (xy 123.744773 -29.911503) (xy 123.760294 -29.969428)
			(xy 123.768122 -30.028884) (xy 123.768612 -30.058868) (xy 123.768612 -30.922468) (xy 123.768122 -30.952452)
			(xy 123.760294 -31.011908) (xy 123.744773 -31.069833) (xy 123.721824 -31.125237) (xy 123.69184 -31.177171)
			(xy 123.655334 -31.224747) (xy 123.612929 -31.267152) (xy 123.565353 -31.303658) (xy 123.513419 -31.333642)
			(xy 123.458015 -31.356591) (xy 123.40009 -31.372112) (xy 123.340634 -31.37994) (xy 123.280666 -31.37994)
			(xy 123.22121 -31.372112) (xy 123.163285 -31.356591) (xy 123.107881 -31.333642) (xy 123.055947 -31.303658)
			(xy 123.008371 -31.267152) (xy 122.965966 -31.224747) (xy 122.92946 -31.177171) (xy 122.899476 -31.125237)
			(xy 122.876527 -31.069833) (xy 122.861006 -31.011908) (xy 122.853178 -30.952452) (xy 122.852688 -30.922468)
			(xy 104.367006 -30.922468) (xy 104.369384 -30.93289) (xy 104.376802 -30.998786) (xy 104.377236 -31.031942)
			(xy 104.377236 -31.567882) (xy 117.098824 -31.567882) (xy 117.102895 -31.51226) (xy 117.115021 -31.457823)
			(xy 117.134944 -31.405732) (xy 117.16224 -31.357097) (xy 117.196326 -31.312954) (xy 117.236475 -31.274245)
			(xy 117.281833 -31.241794) (xy 117.331433 -31.216293) (xy 117.384217 -31.198286) (xy 117.43906 -31.188156)
			(xy 117.494794 -31.186119) (xy 117.550231 -31.192219) (xy 117.604188 -31.206325) (xy 117.655517 -31.228137)
			(xy 117.703123 -31.257191) (xy 117.745991 -31.292866) (xy 117.783208 -31.334403) (xy 117.813981 -31.380916)
			(xy 117.837653 -31.431413) (xy 117.853721 -31.48482) (xy 117.861841 -31.539996) (xy 117.86235 -31.567882)
			(xy 117.861841 -31.595768) (xy 117.853721 -31.650944) (xy 117.837653 -31.704351) (xy 117.830661 -31.719266)
			(xy 118.385588 -31.719266) (xy 118.389659 -31.663644) (xy 118.401785 -31.609207) (xy 118.421708 -31.557116)
			(xy 118.449004 -31.508481) (xy 118.48309 -31.464338) (xy 118.523239 -31.425629) (xy 118.568597 -31.393178)
			(xy 118.618197 -31.367677) (xy 118.670981 -31.34967) (xy 118.725824 -31.33954) (xy 118.781558 -31.337503)
			(xy 118.836995 -31.343603) (xy 118.890952 -31.357709) (xy 118.942281 -31.379521) (xy 118.989887 -31.408575)
			(xy 119.032755 -31.44425) (xy 119.069972 -31.485787) (xy 119.100745 -31.5323) (xy 119.124417 -31.582797)
			(xy 119.140485 -31.636204) (xy 119.144635 -31.664402) (xy 119.661176 -31.664402) (xy 119.665247 -31.60878)
			(xy 119.677373 -31.554343) (xy 119.697296 -31.502252) (xy 119.724592 -31.453617) (xy 119.758678 -31.409474)
			(xy 119.798827 -31.370765) (xy 119.844185 -31.338314) (xy 119.893785 -31.312813) (xy 119.946569 -31.294806)
			(xy 120.001412 -31.284676) (xy 120.057146 -31.282639) (xy 120.112583 -31.288739) (xy 120.16654 -31.302845)
			(xy 120.217869 -31.324657) (xy 120.265475 -31.353711) (xy 120.308343 -31.389386) (xy 120.34556 -31.430923)
			(xy 120.376333 -31.477436) (xy 120.400005 -31.527933) (xy 120.416073 -31.58134) (xy 120.424193 -31.636516)
			(xy 120.424702 -31.664402) (xy 120.424193 -31.692288) (xy 120.416073 -31.747464) (xy 120.407133 -31.777178)
			(xy 120.92635 -31.777178) (xy 120.930421 -31.721556) (xy 120.942547 -31.667119) (xy 120.96247 -31.615028)
			(xy 120.989766 -31.566393) (xy 121.023852 -31.52225) (xy 121.064001 -31.483541) (xy 121.109359 -31.45109)
			(xy 121.158959 -31.425589) (xy 121.211743 -31.407582) (xy 121.266586 -31.397452) (xy 121.32232 -31.395415)
			(xy 121.377757 -31.401515) (xy 121.431714 -31.415621) (xy 121.483043 -31.437433) (xy 121.530649 -31.466487)
			(xy 121.573517 -31.502162) (xy 121.610734 -31.543699) (xy 121.641507 -31.590212) (xy 121.665179 -31.640709)
			(xy 121.681247 -31.694116) (xy 121.689367 -31.749292) (xy 121.689876 -31.777178) (xy 121.689367 -31.805064)
			(xy 121.681247 -31.86024) (xy 121.665179 -31.913647) (xy 121.641507 -31.964144) (xy 121.610734 -32.010657)
			(xy 121.573517 -32.052194) (xy 121.530649 -32.087869) (xy 121.483043 -32.116923) (xy 121.431714 -32.138735)
			(xy 121.377757 -32.152841) (xy 121.32232 -32.158941) (xy 121.266586 -32.156904) (xy 121.211743 -32.146774)
			(xy 121.158959 -32.128767) (xy 121.109359 -32.103266) (xy 121.064001 -32.070815) (xy 121.023852 -32.032106)
			(xy 120.989766 -31.987963) (xy 120.96247 -31.939328) (xy 120.942547 -31.887237) (xy 120.930421 -31.8328)
			(xy 120.92635 -31.777178) (xy 120.407133 -31.777178) (xy 120.400005 -31.800871) (xy 120.376333 -31.851368)
			(xy 120.34556 -31.897881) (xy 120.308343 -31.939418) (xy 120.265475 -31.975093) (xy 120.217869 -32.004147)
			(xy 120.16654 -32.025959) (xy 120.112583 -32.040065) (xy 120.057146 -32.046165) (xy 120.001412 -32.044128)
			(xy 119.946569 -32.033998) (xy 119.893785 -32.015991) (xy 119.844185 -31.99049) (xy 119.798827 -31.958039)
			(xy 119.758678 -31.91933) (xy 119.724592 -31.875187) (xy 119.697296 -31.826552) (xy 119.677373 -31.774461)
			(xy 119.665247 -31.720024) (xy 119.661176 -31.664402) (xy 119.144635 -31.664402) (xy 119.148605 -31.69138)
			(xy 119.149114 -31.719266) (xy 119.148605 -31.747152) (xy 119.140485 -31.802328) (xy 119.124417 -31.855735)
			(xy 119.100745 -31.906232) (xy 119.069972 -31.952745) (xy 119.032755 -31.994282) (xy 118.989887 -32.029957)
			(xy 118.942281 -32.059011) (xy 118.890952 -32.080823) (xy 118.836995 -32.094929) (xy 118.781558 -32.101029)
			(xy 118.725824 -32.098992) (xy 118.670981 -32.088862) (xy 118.618197 -32.070855) (xy 118.568597 -32.045354)
			(xy 118.523239 -32.012903) (xy 118.48309 -31.974194) (xy 118.449004 -31.930051) (xy 118.421708 -31.881416)
			(xy 118.401785 -31.829325) (xy 118.389659 -31.774888) (xy 118.385588 -31.719266) (xy 117.830661 -31.719266)
			(xy 117.813981 -31.754848) (xy 117.783208 -31.801361) (xy 117.745991 -31.842898) (xy 117.703123 -31.878573)
			(xy 117.655517 -31.907627) (xy 117.604188 -31.929439) (xy 117.550231 -31.943545) (xy 117.494794 -31.949645)
			(xy 117.43906 -31.947608) (xy 117.384217 -31.937478) (xy 117.331433 -31.919471) (xy 117.281833 -31.89397)
			(xy 117.236475 -31.861519) (xy 117.196326 -31.82281) (xy 117.16224 -31.778667) (xy 117.134944 -31.730032)
			(xy 117.115021 -31.677941) (xy 117.102895 -31.623504) (xy 117.098824 -31.567882) (xy 104.377236 -31.567882)
			(xy 104.377236 -32.722312) (xy 124.706888 -32.722312) (xy 124.706888 -31.858712) (xy 124.707378 -31.828728)
			(xy 124.715206 -31.769272) (xy 124.730727 -31.711347) (xy 124.753676 -31.655943) (xy 124.78366 -31.604009)
			(xy 124.820166 -31.556433) (xy 124.862571 -31.514028) (xy 124.910147 -31.477522) (xy 124.962081 -31.447538)
			(xy 125.017485 -31.424589) (xy 125.07541 -31.409068) (xy 125.134866 -31.40124) (xy 125.194834 -31.40124)
			(xy 125.25429 -31.409068) (xy 125.312215 -31.424589) (xy 125.367619 -31.447538) (xy 125.419553 -31.477522)
			(xy 125.467129 -31.514028) (xy 125.509534 -31.556433) (xy 125.54604 -31.604009) (xy 125.576024 -31.655943)
			(xy 125.598973 -31.711347) (xy 125.614494 -31.769272) (xy 125.622322 -31.828728) (xy 125.622812 -31.858712)
			(xy 125.622812 -32.722312) (xy 125.622322 -32.752296) (xy 125.614494 -32.811752) (xy 125.598973 -32.869677)
			(xy 125.576024 -32.925081) (xy 125.54604 -32.977015) (xy 125.509534 -33.024591) (xy 125.467129 -33.066996)
			(xy 125.419553 -33.103502) (xy 125.367619 -33.133486) (xy 125.312215 -33.156435) (xy 125.25429 -33.171956)
			(xy 125.194834 -33.179784) (xy 125.134866 -33.179784) (xy 125.07541 -33.171956) (xy 125.017485 -33.156435)
			(xy 124.962081 -33.133486) (xy 124.910147 -33.103502) (xy 124.862571 -33.066996) (xy 124.820166 -33.024591)
			(xy 124.78366 -32.977015) (xy 124.753676 -32.925081) (xy 124.730727 -32.869677) (xy 124.715206 -32.811752)
			(xy 124.707378 -32.752296) (xy 124.706888 -32.722312) (xy 104.377236 -32.722312) (xy 104.377236 -34.52241)
			(xy 122.852688 -34.52241) (xy 122.852688 -33.65881) (xy 122.853178 -33.628826) (xy 122.861006 -33.56937)
			(xy 122.876527 -33.511445) (xy 122.899476 -33.456041) (xy 122.92946 -33.404107) (xy 122.965966 -33.356531)
			(xy 123.008371 -33.314126) (xy 123.055947 -33.27762) (xy 123.107881 -33.247636) (xy 123.163285 -33.224687)
			(xy 123.22121 -33.209166) (xy 123.280666 -33.201338) (xy 123.340634 -33.201338) (xy 123.40009 -33.209166)
			(xy 123.458015 -33.224687) (xy 123.513419 -33.247636) (xy 123.565353 -33.27762) (xy 123.612929 -33.314126)
			(xy 123.655334 -33.356531) (xy 123.69184 -33.404107) (xy 123.721824 -33.456041) (xy 123.744773 -33.511445)
			(xy 123.760294 -33.56937) (xy 123.768122 -33.628826) (xy 123.768612 -33.65881) (xy 123.768612 -34.52241)
			(xy 123.768122 -34.552394) (xy 123.760294 -34.61185) (xy 123.744773 -34.669775) (xy 123.721824 -34.725179)
			(xy 123.69184 -34.777113) (xy 123.655334 -34.824689) (xy 123.612929 -34.867094) (xy 123.565353 -34.9036)
			(xy 123.513419 -34.933584) (xy 123.458015 -34.956533) (xy 123.40009 -34.972054) (xy 123.340634 -34.979882)
			(xy 123.280666 -34.979882) (xy 123.22121 -34.972054) (xy 123.163285 -34.956533) (xy 123.107881 -34.933584)
			(xy 123.055947 -34.9036) (xy 123.008371 -34.867094) (xy 122.965966 -34.824689) (xy 122.92946 -34.777113)
			(xy 122.899476 -34.725179) (xy 122.876527 -34.669775) (xy 122.861006 -34.61185) (xy 122.853178 -34.552394)
			(xy 122.852688 -34.52241) (xy 104.377236 -34.52241) (xy 104.377236 -35.264852) (xy 120.002552 -35.264852)
			(xy 120.006623 -35.20923) (xy 120.018749 -35.154793) (xy 120.038672 -35.102702) (xy 120.065968 -35.054067)
			(xy 120.100054 -35.009924) (xy 120.140203 -34.971215) (xy 120.185561 -34.938764) (xy 120.235161 -34.913263)
			(xy 120.287945 -34.895256) (xy 120.342788 -34.885126) (xy 120.398522 -34.883089) (xy 120.453959 -34.889189)
			(xy 120.507916 -34.903295) (xy 120.559245 -34.925107) (xy 120.606851 -34.954161) (xy 120.649719 -34.989836)
			(xy 120.686936 -35.031373) (xy 120.717709 -35.077886) (xy 120.741381 -35.128383) (xy 120.757449 -35.18179)
			(xy 120.765569 -35.236966) (xy 120.766078 -35.264852) (xy 120.765569 -35.292738) (xy 120.757449 -35.347914)
			(xy 120.741381 -35.401321) (xy 120.717709 -35.451818) (xy 120.686936 -35.498331) (xy 120.649719 -35.539868)
			(xy 120.606851 -35.575543) (xy 120.559245 -35.604597) (xy 120.507916 -35.626409) (xy 120.453959 -35.640515)
			(xy 120.398522 -35.646615) (xy 120.342788 -35.644578) (xy 120.287945 -35.634448) (xy 120.235161 -35.616441)
			(xy 120.185561 -35.59094) (xy 120.140203 -35.558489) (xy 120.100054 -35.51978) (xy 120.065968 -35.475637)
			(xy 120.038672 -35.427002) (xy 120.018749 -35.374911) (xy 120.006623 -35.320474) (xy 120.002552 -35.264852)
			(xy 104.377236 -35.264852) (xy 104.377236 -35.74415) (xy 104.377448 -35.750381) (xy 104.380532 -35.762456)
			(xy 104.383332 -35.768026) (xy 104.441475 -35.876738) (xy 108.817408 -35.876738) (xy 108.821479 -35.821116)
			(xy 108.833605 -35.766679) (xy 108.853528 -35.714588) (xy 108.880824 -35.665953) (xy 108.91491 -35.62181)
			(xy 108.955059 -35.583101) (xy 109.000417 -35.55065) (xy 109.050017 -35.525149) (xy 109.102801 -35.507142)
			(xy 109.157644 -35.497012) (xy 109.213378 -35.494975) (xy 109.268815 -35.501075) (xy 109.322772 -35.515181)
			(xy 109.374101 -35.536993) (xy 109.421707 -35.566047) (xy 109.464575 -35.601722) (xy 109.501792 -35.643259)
			(xy 109.532565 -35.689772) (xy 109.556237 -35.740269) (xy 109.572305 -35.793676) (xy 109.580425 -35.848852)
			(xy 109.580934 -35.876738) (xy 112.889028 -35.876738) (xy 112.893099 -35.821116) (xy 112.905225 -35.766679)
			(xy 112.925148 -35.714588) (xy 112.952444 -35.665953) (xy 112.98653 -35.62181) (xy 113.026679 -35.583101)
			(xy 113.072037 -35.55065) (xy 113.121637 -35.525149) (xy 113.174421 -35.507142) (xy 113.229264 -35.497012)
			(xy 113.284998 -35.494975) (xy 113.340435 -35.501075) (xy 113.394392 -35.515181) (xy 113.445721 -35.536993)
			(xy 113.493327 -35.566047) (xy 113.536195 -35.601722) (xy 113.573412 -35.643259) (xy 113.604185 -35.689772)
			(xy 113.627857 -35.740269) (xy 113.643925 -35.793676) (xy 113.652045 -35.848852) (xy 113.652554 -35.876738)
			(xy 113.652045 -35.904624) (xy 113.643925 -35.9598) (xy 113.627857 -36.013207) (xy 113.604185 -36.063704)
			(xy 113.573412 -36.110217) (xy 113.536195 -36.151754) (xy 113.493327 -36.187429) (xy 113.445721 -36.216483)
			(xy 113.394392 -36.238295) (xy 113.340435 -36.252401) (xy 113.284998 -36.258501) (xy 113.229264 -36.256464)
			(xy 113.174421 -36.246334) (xy 113.121637 -36.228327) (xy 113.072037 -36.202826) (xy 113.026679 -36.170375)
			(xy 112.98653 -36.131666) (xy 112.952444 -36.087523) (xy 112.925148 -36.038888) (xy 112.905225 -35.986797)
			(xy 112.893099 -35.93236) (xy 112.889028 -35.876738) (xy 109.580934 -35.876738) (xy 109.580425 -35.904624)
			(xy 109.572305 -35.9598) (xy 109.556237 -36.013207) (xy 109.532565 -36.063704) (xy 109.501792 -36.110217)
			(xy 109.464575 -36.151754) (xy 109.421707 -36.187429) (xy 109.374101 -36.216483) (xy 109.322772 -36.238295)
			(xy 109.268815 -36.252401) (xy 109.213378 -36.258501) (xy 109.157644 -36.256464) (xy 109.102801 -36.246334)
			(xy 109.050017 -36.228327) (xy 109.000417 -36.202826) (xy 108.955059 -36.170375) (xy 108.91491 -36.131666)
			(xy 108.880824 -36.087523) (xy 108.853528 -36.038888) (xy 108.833605 -35.986797) (xy 108.821479 -35.93236)
			(xy 108.817408 -35.876738) (xy 104.441475 -35.876738) (xy 104.780147 -36.50996) (xy 110.714026 -36.50996)
			(xy 110.718097 -36.454338) (xy 110.730223 -36.399901) (xy 110.750146 -36.34781) (xy 110.777442 -36.299175)
			(xy 110.811528 -36.255032) (xy 110.851677 -36.216323) (xy 110.897035 -36.183872) (xy 110.946635 -36.158371)
			(xy 110.999419 -36.140364) (xy 111.054262 -36.130234) (xy 111.109996 -36.128197) (xy 111.165433 -36.134297)
			(xy 111.21939 -36.148403) (xy 111.270719 -36.170215) (xy 111.318325 -36.199269) (xy 111.361193 -36.234944)
			(xy 111.39841 -36.276481) (xy 111.429183 -36.322994) (xy 111.452855 -36.373491) (xy 111.468923 -36.426898)
			(xy 111.472848 -36.453572) (xy 114.028726 -36.453572) (xy 114.032797 -36.39795) (xy 114.044923 -36.343513)
			(xy 114.064846 -36.291422) (xy 114.092142 -36.242787) (xy 114.126228 -36.198644) (xy 114.166377 -36.159935)
			(xy 114.211735 -36.127484) (xy 114.261335 -36.101983) (xy 114.314119 -36.083976) (xy 114.368962 -36.073846)
			(xy 114.424696 -36.071809) (xy 114.480133 -36.077909) (xy 114.53409 -36.092015) (xy 114.585419 -36.113827)
			(xy 114.633025 -36.142881) (xy 114.675893 -36.178556) (xy 114.71311 -36.220093) (xy 114.743883 -36.266606)
			(xy 114.753419 -36.286948) (xy 121.300492 -36.286948) (xy 121.304563 -36.231326) (xy 121.316689 -36.176889)
			(xy 121.336612 -36.124798) (xy 121.363908 -36.076163) (xy 121.397994 -36.03202) (xy 121.438143 -35.993311)
			(xy 121.483501 -35.96086) (xy 121.533101 -35.935359) (xy 121.585885 -35.917352) (xy 121.640728 -35.907222)
			(xy 121.696462 -35.905185) (xy 121.751899 -35.911285) (xy 121.805856 -35.925391) (xy 121.857185 -35.947203)
			(xy 121.904791 -35.976257) (xy 121.947659 -36.011932) (xy 121.984876 -36.053469) (xy 122.015649 -36.099982)
			(xy 122.039321 -36.150479) (xy 122.055389 -36.203886) (xy 122.063509 -36.259062) (xy 122.064018 -36.286948)
			(xy 122.063509 -36.314834) (xy 122.055389 -36.37001) (xy 122.039321 -36.423417) (xy 122.015649 -36.473914)
			(xy 121.988104 -36.515548) (xy 123.114306 -36.515548) (xy 123.118377 -36.459926) (xy 123.130503 -36.405489)
			(xy 123.150426 -36.353398) (xy 123.177722 -36.304763) (xy 123.211808 -36.26062) (xy 123.251957 -36.221911)
			(xy 123.297315 -36.18946) (xy 123.346915 -36.163959) (xy 123.399699 -36.145952) (xy 123.454542 -36.135822)
			(xy 123.510276 -36.133785) (xy 123.565713 -36.139885) (xy 123.61967 -36.153991) (xy 123.670999 -36.175803)
			(xy 123.718605 -36.204857) (xy 123.761473 -36.240532) (xy 123.79869 -36.282069) (xy 123.829463 -36.328582)
			(xy 123.853135 -36.379079) (xy 123.869203 -36.432486) (xy 123.877323 -36.487662) (xy 123.877832 -36.515548)
			(xy 123.877323 -36.543434) (xy 123.869203 -36.59861) (xy 123.868746 -36.60013) (xy 128.098303 -36.60013)
			(xy 128.102308 -36.512222) (xy 128.114291 -36.425042) (xy 128.134151 -36.339313) (xy 128.161726 -36.255745)
			(xy 128.196785 -36.175031) (xy 128.239038 -36.097839) (xy 128.288136 -36.02481) (xy 128.343672 -35.956548)
			(xy 128.405184 -35.893618) (xy 128.472165 -35.836544) (xy 128.544058 -35.785796) (xy 128.620267 -35.741796)
			(xy 128.700162 -35.704909) (xy 128.783081 -35.67544) (xy 128.868336 -35.653633) (xy 128.95522 -35.639669)
			(xy 129.043014 -35.633663) (xy 129.130991 -35.635667) (xy 129.218421 -35.645662) (xy 129.30458 -35.663566)
			(xy 129.388754 -35.68923) (xy 129.470245 -35.722443) (xy 129.548379 -35.762929) (xy 129.622507 -35.810351)
			(xy 129.692015 -35.864318) (xy 129.756329 -35.924383) (xy 129.814913 -35.990047) (xy 129.867284 -36.060766)
			(xy 129.913007 -36.135954) (xy 129.951704 -36.214989) (xy 129.983053 -36.297215) (xy 130.006795 -36.381951)
			(xy 130.022733 -36.468495) (xy 130.030735 -36.55613) (xy 130.031236 -36.60013) (xy 130.030735 -36.64413)
			(xy 130.022733 -36.731765) (xy 130.006795 -36.818309) (xy 129.983053 -36.903045) (xy 129.951704 -36.985271)
			(xy 129.913007 -37.064306) (xy 129.867284 -37.139494) (xy 129.814913 -37.210213) (xy 129.756329 -37.275877)
			(xy 129.692015 -37.335942) (xy 129.622507 -37.389909) (xy 129.548379 -37.437331) (xy 129.470245 -37.477817)
			(xy 129.388754 -37.51103) (xy 129.30458 -37.536694) (xy 129.218421 -37.554598) (xy 129.130991 -37.564593)
			(xy 129.043014 -37.566597) (xy 128.95522 -37.560591) (xy 128.868336 -37.546627) (xy 128.783081 -37.52482)
			(xy 128.700162 -37.495351) (xy 128.620267 -37.458464) (xy 128.544058 -37.414464) (xy 128.472165 -37.363716)
			(xy 128.405184 -37.306642) (xy 128.343672 -37.243712) (xy 128.288136 -37.17545) (xy 128.239038 -37.102421)
			(xy 128.196785 -37.025229) (xy 128.161726 -36.944515) (xy 128.134151 -36.860947) (xy 128.114291 -36.775218)
			(xy 128.102308 -36.688038) (xy 128.098303 -36.60013) (xy 123.868746 -36.60013) (xy 123.853135 -36.652017)
			(xy 123.829463 -36.702514) (xy 123.79869 -36.749027) (xy 123.761473 -36.790564) (xy 123.718605 -36.826239)
			(xy 123.670999 -36.855293) (xy 123.61967 -36.877105) (xy 123.565713 -36.891211) (xy 123.510276 -36.897311)
			(xy 123.454542 -36.895274) (xy 123.399699 -36.885144) (xy 123.346915 -36.867137) (xy 123.297315 -36.841636)
			(xy 123.251957 -36.809185) (xy 123.211808 -36.770476) (xy 123.177722 -36.726333) (xy 123.150426 -36.677698)
			(xy 123.130503 -36.625607) (xy 123.118377 -36.57117) (xy 123.114306 -36.515548) (xy 121.988104 -36.515548)
			(xy 121.984876 -36.520427) (xy 121.947659 -36.561964) (xy 121.904791 -36.597639) (xy 121.857185 -36.626693)
			(xy 121.805856 -36.648505) (xy 121.751899 -36.662611) (xy 121.696462 -36.668711) (xy 121.640728 -36.666674)
			(xy 121.585885 -36.656544) (xy 121.533101 -36.638537) (xy 121.483501 -36.613036) (xy 121.438143 -36.580585)
			(xy 121.397994 -36.541876) (xy 121.363908 -36.497733) (xy 121.336612 -36.449098) (xy 121.316689 -36.397007)
			(xy 121.304563 -36.34257) (xy 121.300492 -36.286948) (xy 114.753419 -36.286948) (xy 114.767555 -36.317103)
			(xy 114.783623 -36.37051) (xy 114.791743 -36.425686) (xy 114.792252 -36.453572) (xy 114.791743 -36.481458)
			(xy 114.783623 -36.536634) (xy 114.767555 -36.590041) (xy 114.743883 -36.640538) (xy 114.71311 -36.687051)
			(xy 114.675893 -36.728588) (xy 114.633025 -36.764263) (xy 114.585419 -36.793317) (xy 114.53409 -36.815129)
			(xy 114.480133 -36.829235) (xy 114.424696 -36.835335) (xy 114.368962 -36.833298) (xy 114.314119 -36.823168)
			(xy 114.261335 -36.805161) (xy 114.211735 -36.77966) (xy 114.166377 -36.747209) (xy 114.126228 -36.7085)
			(xy 114.092142 -36.664357) (xy 114.064846 -36.615722) (xy 114.044923 -36.563631) (xy 114.032797 -36.509194)
			(xy 114.028726 -36.453572) (xy 111.472848 -36.453572) (xy 111.477043 -36.482074) (xy 111.477552 -36.50996)
			(xy 111.477043 -36.537846) (xy 111.468923 -36.593022) (xy 111.452855 -36.646429) (xy 111.429183 -36.696926)
			(xy 111.39841 -36.743439) (xy 111.361193 -36.784976) (xy 111.318325 -36.820651) (xy 111.270719 -36.849705)
			(xy 111.21939 -36.871517) (xy 111.165433 -36.885623) (xy 111.109996 -36.891723) (xy 111.054262 -36.889686)
			(xy 110.999419 -36.879556) (xy 110.946635 -36.861549) (xy 110.897035 -36.836048) (xy 110.851677 -36.803597)
			(xy 110.811528 -36.764888) (xy 110.777442 -36.720745) (xy 110.750146 -36.67211) (xy 110.730223 -36.620019)
			(xy 110.718097 -36.565582) (xy 110.714026 -36.50996) (xy 104.780147 -36.50996) (xy 105.296374 -37.47516)
			(xy 107.85932 -37.47516) (xy 107.863391 -37.419538) (xy 107.875517 -37.365101) (xy 107.89544 -37.31301)
			(xy 107.922736 -37.264375) (xy 107.956822 -37.220232) (xy 107.996971 -37.181523) (xy 108.042329 -37.149072)
			(xy 108.091929 -37.123571) (xy 108.144713 -37.105564) (xy 108.199556 -37.095434) (xy 108.25529 -37.093397)
			(xy 108.310727 -37.099497) (xy 108.364684 -37.113603) (xy 108.416013 -37.135415) (xy 108.463619 -37.164469)
			(xy 108.506487 -37.200144) (xy 108.543704 -37.241681) (xy 108.574477 -37.288194) (xy 108.598149 -37.338691)
			(xy 108.614217 -37.392098) (xy 108.622337 -37.447274) (xy 108.622846 -37.47516) (xy 108.622337 -37.503046)
			(xy 108.614217 -37.558222) (xy 108.598149 -37.611629) (xy 108.574477 -37.662126) (xy 108.574324 -37.662358)
			(xy 110.048546 -37.662358) (xy 110.052617 -37.606736) (xy 110.064743 -37.552299) (xy 110.084666 -37.500208)
			(xy 110.111962 -37.451573) (xy 110.146048 -37.40743) (xy 110.186197 -37.368721) (xy 110.231555 -37.33627)
			(xy 110.281155 -37.310769) (xy 110.333939 -37.292762) (xy 110.388782 -37.282632) (xy 110.444516 -37.280595)
			(xy 110.499953 -37.286695) (xy 110.55391 -37.300801) (xy 110.605239 -37.322613) (xy 110.652845 -37.351667)
			(xy 110.695713 -37.387342) (xy 110.73293 -37.428879) (xy 110.763703 -37.475392) (xy 110.787375 -37.525889)
			(xy 110.803443 -37.579296) (xy 110.811563 -37.634472) (xy 110.812072 -37.662358) (xy 110.811563 -37.690244)
			(xy 110.803443 -37.74542) (xy 110.794809 -37.774118) (xy 121.564906 -37.774118) (xy 121.568977 -37.718496)
			(xy 121.581103 -37.664059) (xy 121.601026 -37.611968) (xy 121.628322 -37.563333) (xy 121.662408 -37.51919)
			(xy 121.702557 -37.480481) (xy 121.747915 -37.44803) (xy 121.797515 -37.422529) (xy 121.850299 -37.404522)
			(xy 121.905142 -37.394392) (xy 121.960876 -37.392355) (xy 122.016313 -37.398455) (xy 122.07027 -37.412561)
			(xy 122.121599 -37.434373) (xy 122.169205 -37.463427) (xy 122.212073 -37.499102) (xy 122.24929 -37.540639)
			(xy 122.280063 -37.587152) (xy 122.303735 -37.637649) (xy 122.319803 -37.691056) (xy 122.327923 -37.746232)
			(xy 122.328432 -37.774118) (xy 122.327923 -37.802004) (xy 122.319803 -37.85718) (xy 122.303735 -37.910587)
			(xy 122.280063 -37.961084) (xy 122.24929 -38.007597) (xy 122.212073 -38.049134) (xy 122.169205 -38.084809)
			(xy 122.121599 -38.113863) (xy 122.07027 -38.135675) (xy 122.016313 -38.149781) (xy 121.960876 -38.155881)
			(xy 121.905142 -38.153844) (xy 121.850299 -38.143714) (xy 121.797515 -38.125707) (xy 121.747915 -38.100206)
			(xy 121.702557 -38.067755) (xy 121.662408 -38.029046) (xy 121.628322 -37.984903) (xy 121.601026 -37.936268)
			(xy 121.581103 -37.884177) (xy 121.568977 -37.82974) (xy 121.564906 -37.774118) (xy 110.794809 -37.774118)
			(xy 110.787375 -37.798827) (xy 110.763703 -37.849324) (xy 110.73293 -37.895837) (xy 110.695713 -37.937374)
			(xy 110.652845 -37.973049) (xy 110.605239 -38.002103) (xy 110.55391 -38.023915) (xy 110.499953 -38.038021)
			(xy 110.444516 -38.044121) (xy 110.388782 -38.042084) (xy 110.333939 -38.031954) (xy 110.281155 -38.013947)
			(xy 110.231555 -37.988446) (xy 110.186197 -37.955995) (xy 110.146048 -37.917286) (xy 110.111962 -37.873143)
			(xy 110.084666 -37.824508) (xy 110.064743 -37.772417) (xy 110.052617 -37.71798) (xy 110.048546 -37.662358)
			(xy 108.574324 -37.662358) (xy 108.543704 -37.708639) (xy 108.506487 -37.750176) (xy 108.463619 -37.785851)
			(xy 108.416013 -37.814905) (xy 108.364684 -37.836717) (xy 108.310727 -37.850823) (xy 108.25529 -37.856923)
			(xy 108.199556 -37.854886) (xy 108.144713 -37.844756) (xy 108.091929 -37.826749) (xy 108.042329 -37.801248)
			(xy 107.996971 -37.768797) (xy 107.956822 -37.730088) (xy 107.922736 -37.685945) (xy 107.89544 -37.63731)
			(xy 107.875517 -37.585219) (xy 107.863391 -37.530782) (xy 107.85932 -37.47516) (xy 105.296374 -37.47516)
			(xy 105.967485 -38.729952) (xy 113.801097 -38.729952) (xy 113.801097 -38.675448) (xy 113.808855 -38.621499)
			(xy 113.824211 -38.569204) (xy 113.846854 -38.519626) (xy 113.876323 -38.473776) (xy 113.912018 -38.432587)
			(xy 113.953211 -38.396897) (xy 113.999065 -38.367433) (xy 114.048645 -38.344796) (xy 114.100942 -38.329445)
			(xy 114.154892 -38.321694) (xy 114.182144 -38.321234) (xy 114.210447 -38.321752) (xy 114.266435 -38.330097)
			(xy 114.320575 -38.346626) (xy 114.371676 -38.370976) (xy 114.418616 -38.402613) (xy 114.460364 -38.440841)
			(xy 114.496003 -38.48482) (xy 114.51082 -38.50894) (xy 114.518425 -38.520969) (xy 114.539042 -38.540571)
			(xy 114.564273 -38.553713) (xy 114.592152 -38.559374) (xy 114.62051 -38.557111) (xy 114.647139 -38.547101)
			(xy 114.669966 -38.530123) (xy 114.678968 -38.5191) (xy 114.697178 -38.496243) (xy 114.739336 -38.455778)
			(xy 114.787167 -38.422209) (xy 114.839554 -38.396318) (xy 114.895274 -38.378712) (xy 114.953026 -38.3698)
			(xy 114.982244 -38.36924) (xy 115.009497 -38.369633) (xy 115.063446 -38.377395) (xy 115.115742 -38.392756)
			(xy 115.16532 -38.415403) (xy 115.211171 -38.444874) (xy 115.252361 -38.48057) (xy 115.288052 -38.521764)
			(xy 115.317518 -38.567618) (xy 115.340159 -38.617199) (xy 115.355514 -38.669497) (xy 115.36327 -38.723447)
			(xy 115.36327 -38.777953) (xy 115.355514 -38.831903) (xy 115.340159 -38.884201) (xy 115.317518 -38.933782)
			(xy 115.288052 -38.979636) (xy 115.252361 -39.02083) (xy 115.211171 -39.056526) (xy 115.16532 -39.085997)
			(xy 115.115742 -39.108644) (xy 115.063446 -39.124005) (xy 115.009497 -39.131767) (xy 114.982244 -39.132256)
			(xy 114.95394 -39.131752) (xy 114.897951 -39.123406) (xy 114.843811 -39.106874) (xy 114.79271 -39.082522)
			(xy 114.74577 -39.050883) (xy 114.704022 -39.012653) (xy 114.668385 -38.968671) (xy 114.653568 -38.94455)
			(xy 114.645978 -38.93251) (xy 114.625357 -38.91291) (xy 114.600124 -38.899769) (xy 114.572242 -38.89411)
			(xy 114.543882 -38.896375) (xy 114.517251 -38.906387) (xy 114.494423 -38.923366) (xy 114.48542 -38.93439)
			(xy 114.467215 -38.95725) (xy 114.425056 -38.997716) (xy 114.377224 -39.031285) (xy 114.324836 -39.057175)
			(xy 114.269115 -39.074781) (xy 114.211362 -39.083691) (xy 114.182144 -39.08425) (xy 114.154892 -39.083706)
			(xy 114.100942 -39.075955) (xy 114.048645 -39.060604) (xy 113.999065 -39.037967) (xy 113.953211 -39.008503)
			(xy 113.912018 -38.972813) (xy 113.876323 -38.931624) (xy 113.846854 -38.885774) (xy 113.824211 -38.836196)
			(xy 113.808855 -38.783901) (xy 113.801097 -38.729952) (xy 105.967485 -38.729952) (xy 106.63177 -39.97198)
			(xy 115.995956 -39.97198) (xy 116.000027 -39.916358) (xy 116.012153 -39.861921) (xy 116.032076 -39.80983)
			(xy 116.059372 -39.761195) (xy 116.093458 -39.717052) (xy 116.133607 -39.678343) (xy 116.178965 -39.645892)
			(xy 116.228565 -39.620391) (xy 116.281349 -39.602384) (xy 116.336192 -39.592254) (xy 116.391926 -39.590217)
			(xy 116.447363 -39.596317) (xy 116.50132 -39.610423) (xy 116.552649 -39.632235) (xy 116.600255 -39.661289)
			(xy 116.643123 -39.696964) (xy 116.68034 -39.738501) (xy 116.711113 -39.785014) (xy 116.734785 -39.835511)
			(xy 116.750853 -39.888918) (xy 116.758973 -39.944094) (xy 116.759482 -39.97198) (xy 116.758973 -39.999866)
			(xy 116.750853 -40.055042) (xy 116.734785 -40.108449) (xy 116.711113 -40.158946) (xy 116.68034 -40.205459)
			(xy 116.643123 -40.246996) (xy 116.600255 -40.282671) (xy 116.552649 -40.311725) (xy 116.50132 -40.333537)
			(xy 116.447363 -40.347643) (xy 116.391926 -40.353743) (xy 116.336192 -40.351706) (xy 116.281349 -40.341576)
			(xy 116.228565 -40.323569) (xy 116.178965 -40.298068) (xy 116.133607 -40.265617) (xy 116.093458 -40.226908)
			(xy 116.059372 -40.182765) (xy 116.032076 -40.13413) (xy 116.012153 -40.082039) (xy 116.000027 -40.027602)
			(xy 115.995956 -39.97198) (xy 106.63177 -39.97198) (xy 107.166472 -40.971724) (xy 116.694202 -40.971724)
			(xy 116.698273 -40.916102) (xy 116.710399 -40.861665) (xy 116.730322 -40.809574) (xy 116.757618 -40.760939)
			(xy 116.791704 -40.716796) (xy 116.831853 -40.678087) (xy 116.877211 -40.645636) (xy 116.926811 -40.620135)
			(xy 116.979595 -40.602128) (xy 117.034438 -40.591998) (xy 117.090172 -40.589961) (xy 117.145609 -40.596061)
			(xy 117.199566 -40.610167) (xy 117.250895 -40.631979) (xy 117.298501 -40.661033) (xy 117.341369 -40.696708)
			(xy 117.378586 -40.738245) (xy 117.409359 -40.784758) (xy 117.433031 -40.835255) (xy 117.449099 -40.888662)
			(xy 117.457219 -40.943838) (xy 117.457728 -40.971724) (xy 117.457219 -40.99961) (xy 117.449099 -41.054786)
			(xy 117.433031 -41.108193) (xy 117.409359 -41.15869) (xy 117.378586 -41.205203) (xy 117.341369 -41.24674)
			(xy 117.298501 -41.282415) (xy 117.250895 -41.311469) (xy 117.199566 -41.333281) (xy 117.145609 -41.347387)
			(xy 117.090172 -41.353487) (xy 117.034438 -41.35145) (xy 116.979595 -41.34132) (xy 116.926811 -41.323313)
			(xy 116.877211 -41.297812) (xy 116.831853 -41.265361) (xy 116.791704 -41.226652) (xy 116.757618 -41.182509)
			(xy 116.730322 -41.133874) (xy 116.710399 -41.081783) (xy 116.698273 -41.027346) (xy 116.694202 -40.971724)
			(xy 107.166472 -40.971724) (xy 108.750608 -43.933618) (xy 108.767154 -43.965796) (xy 108.793163 -44.033316)
			(xy 108.810738 -44.103506) (xy 108.819617 -44.175316) (xy 108.820204 -44.211494) (xy 108.820204 -49.601953)
			(xy 122.213059 -49.601953) (xy 122.213059 -49.547447) (xy 122.220817 -49.493495) (xy 122.236173 -49.441196)
			(xy 122.258817 -49.391616) (xy 122.288286 -49.345762) (xy 122.323981 -49.30457) (xy 122.365175 -49.268876)
			(xy 122.41103 -49.239409) (xy 122.460611 -49.216768) (xy 122.512911 -49.201413) (xy 122.566863 -49.193658)
			(xy 122.594116 -49.193196) (xy 122.621487 -49.193654) (xy 122.675666 -49.201474) (xy 122.728169 -49.216965)
			(xy 122.777916 -49.239808) (xy 122.823882 -49.269534) (xy 122.844814 -49.287176) (xy 122.845068 -49.28743)
			(xy 122.852157 -49.293013) (xy 122.869072 -49.299261) (xy 122.878088 -49.299622) (xy 122.945144 -49.299622)
			(xy 122.954158 -49.299234) (xy 122.971075 -49.293007) (xy 122.978164 -49.28743) (xy 122.978164 -49.287176)
			(xy 122.978418 -49.287176) (xy 122.999351 -49.269535) (xy 123.045319 -49.239811) (xy 123.095065 -49.216965)
			(xy 123.147567 -49.201469) (xy 123.201745 -49.19364) (xy 123.256487 -49.19364) (xy 123.310665 -49.201469)
			(xy 123.363167 -49.216965) (xy 123.412913 -49.239811) (xy 123.458881 -49.269535) (xy 123.479814 -49.287176)
			(xy 123.480068 -49.28743) (xy 123.487157 -49.293013) (xy 123.504072 -49.299261) (xy 123.513088 -49.299622)
			(xy 123.580144 -49.299622) (xy 123.589158 -49.299234) (xy 123.606075 -49.293007) (xy 123.613164 -49.28743)
			(xy 123.613164 -49.287176) (xy 123.613418 -49.287176) (xy 123.634351 -49.269535) (xy 123.680319 -49.239811)
			(xy 123.730065 -49.216965) (xy 123.782567 -49.201469) (xy 123.836745 -49.19364) (xy 123.891487 -49.19364)
			(xy 123.945665 -49.201469) (xy 123.998167 -49.216965) (xy 124.047913 -49.239811) (xy 124.093881 -49.269535)
			(xy 124.114814 -49.287176) (xy 124.115068 -49.28743) (xy 124.122157 -49.293013) (xy 124.139072 -49.299261)
			(xy 124.148088 -49.299622) (xy 124.215144 -49.299622) (xy 124.224158 -49.299234) (xy 124.241075 -49.293007)
			(xy 124.248164 -49.28743) (xy 124.248164 -49.287176) (xy 124.248418 -49.287176) (xy 124.269367 -49.269558)
			(xy 124.315336 -49.239844) (xy 124.365079 -49.217004) (xy 124.417576 -49.201508) (xy 124.471748 -49.193674)
			(xy 124.499116 -49.193196) (xy 124.526367 -49.193675) (xy 124.580313 -49.201433) (xy 124.632607 -49.21679)
			(xy 124.682182 -49.239432) (xy 124.728031 -49.268899) (xy 124.76922 -49.304591) (xy 124.80491 -49.345781)
			(xy 124.834375 -49.391632) (xy 124.857016 -49.441208) (xy 124.87237 -49.493502) (xy 124.880126 -49.547449)
			(xy 124.880126 -49.601951) (xy 124.87237 -49.655898) (xy 124.857016 -49.708192) (xy 124.834375 -49.757768)
			(xy 124.80491 -49.803619) (xy 124.76922 -49.844809) (xy 124.728031 -49.880501) (xy 124.682182 -49.909968)
			(xy 124.632607 -49.93261) (xy 124.580313 -49.947967) (xy 124.526367 -49.955725) (xy 124.499116 -49.956212)
			(xy 124.471746 -49.955734) (xy 124.417568 -49.947918) (xy 124.365065 -49.932432) (xy 124.315318 -49.909593)
			(xy 124.26935 -49.879872) (xy 124.248418 -49.862232) (xy 124.248164 -49.861978) (xy 124.241065 -49.85641)
			(xy 124.224158 -49.850153) (xy 124.215144 -49.849786) (xy 124.148088 -49.849786) (xy 124.139071 -49.85014)
			(xy 124.122154 -49.85639) (xy 124.115068 -49.861978) (xy 124.114814 -49.862232) (xy 124.093881 -49.879873)
			(xy 124.047913 -49.909597) (xy 123.998167 -49.932443) (xy 123.945665 -49.947939) (xy 123.891487 -49.955768)
			(xy 123.836745 -49.955768) (xy 123.782567 -49.947939) (xy 123.730065 -49.932443) (xy 123.680319 -49.909597)
			(xy 123.634351 -49.879873) (xy 123.613418 -49.862232) (xy 123.613164 -49.861978) (xy 123.606065 -49.85641)
			(xy 123.589158 -49.850153) (xy 123.580144 -49.849786) (xy 123.513088 -49.849786) (xy 123.504071 -49.85014)
			(xy 123.487154 -49.85639) (xy 123.480068 -49.861978) (xy 123.480068 -49.862232) (xy 123.479814 -49.862232)
			(xy 123.458881 -49.879873) (xy 123.412913 -49.909597) (xy 123.363167 -49.932443) (xy 123.310665 -49.947939)
			(xy 123.256487 -49.955768) (xy 123.201745 -49.955768) (xy 123.147567 -49.947939) (xy 123.095065 -49.932443)
			(xy 123.045319 -49.909597) (xy 122.999351 -49.879873) (xy 122.978418 -49.862232) (xy 122.978164 -49.861978)
			(xy 122.971065 -49.85641) (xy 122.954158 -49.850153) (xy 122.945144 -49.849786) (xy 122.878088 -49.849786)
			(xy 122.869071 -49.85014) (xy 122.852154 -49.85639) (xy 122.845068 -49.861978) (xy 122.845068 -49.862232)
			(xy 122.844814 -49.862232) (xy 122.823892 -49.879883) (xy 122.777916 -49.909592) (xy 122.728166 -49.932425)
			(xy 122.675663 -49.947913) (xy 122.621486 -49.955739) (xy 122.594116 -49.956212) (xy 122.566863 -49.955742)
			(xy 122.512911 -49.947987) (xy 122.460611 -49.932632) (xy 122.41103 -49.909991) (xy 122.365175 -49.880524)
			(xy 122.323981 -49.84483) (xy 122.288286 -49.803638) (xy 122.258817 -49.757784) (xy 122.236173 -49.708204)
			(xy 122.220817 -49.655905) (xy 122.213059 -49.601953) (xy 108.820204 -49.601953) (xy 108.820204 -51.243992)
			(xy 123.23318 -51.243992) (xy 123.233622 -51.216621) (xy 123.241443 -51.16244) (xy 123.256936 -51.109936)
			(xy 123.279784 -51.060189) (xy 123.309515 -51.014224) (xy 123.32716 -50.993294) (xy 123.327414 -50.99304)
			(xy 123.332992 -50.985947) (xy 123.339243 -50.969035) (xy 123.339606 -50.96002) (xy 123.339606 -50.892964)
			(xy 123.339265 -50.883946) (xy 123.333006 -50.867029) (xy 123.327414 -50.859944) (xy 123.32716 -50.859944)
			(xy 123.32716 -50.85969) (xy 123.309496 -50.838778) (xy 123.279789 -50.792799) (xy 123.256959 -50.743046)
			(xy 123.241473 -50.690542) (xy 123.233651 -50.636362) (xy 123.23318 -50.608992) (xy 123.23367 -50.581741)
			(xy 123.241428 -50.527794) (xy 123.256783 -50.4755) (xy 123.279424 -50.425924) (xy 123.30889 -50.380074)
			(xy 123.344581 -50.338884) (xy 123.385771 -50.303193) (xy 123.43162 -50.273726) (xy 123.481196 -50.251085)
			(xy 123.53349 -50.235728) (xy 123.587437 -50.227971) (xy 123.614688 -50.227484) (xy 123.643606 -50.227979)
			(xy 123.70078 -50.236708) (xy 123.755981 -50.253969) (xy 123.807943 -50.279365) (xy 123.855476 -50.312314)
			(xy 123.89749 -50.352061) (xy 123.915678 -50.37455) (xy 123.923296 -50.383346) (xy 123.944189 -50.393534)
			(xy 123.95581 -50.394108) (xy 124.035566 -50.394108) (xy 124.047193 -50.393532) (xy 124.068103 -50.383369)
			(xy 124.075698 -50.37455) (xy 124.093877 -50.352057) (xy 124.135901 -50.312325) (xy 124.183439 -50.279388)
			(xy 124.235402 -50.254002) (xy 124.290601 -50.236747) (xy 124.347772 -50.228019) (xy 124.376688 -50.227484)
			(xy 124.40394 -50.227966) (xy 124.45789 -50.235722) (xy 124.510187 -50.251076) (xy 124.559767 -50.273716)
			(xy 124.605619 -50.303182) (xy 124.646812 -50.338874) (xy 124.682506 -50.380065) (xy 124.711974 -50.425916)
			(xy 124.734617 -50.475494) (xy 124.749974 -50.52779) (xy 124.757732 -50.58174) (xy 124.758196 -50.608992)
			(xy 124.757725 -50.635306) (xy 124.750491 -50.687434) (xy 124.736172 -50.738077) (xy 124.715041 -50.786276)
			(xy 124.687495 -50.83112) (xy 124.654057 -50.871759) (xy 124.635006 -50.889916) (xy 124.627596 -50.897431)
			(xy 124.619076 -50.916716) (xy 124.618496 -50.927254) (xy 124.618496 -51.00193) (xy 124.619051 -51.012477)
			(xy 124.627568 -51.031772) (xy 124.635006 -51.039268) (xy 124.654089 -51.057396) (xy 124.687543 -51.098032)
			(xy 124.715098 -51.142878) (xy 124.736232 -51.191084) (xy 124.750544 -51.241736) (xy 124.757761 -51.293874)
			(xy 124.758196 -51.320192) (xy 124.757737 -51.347445) (xy 124.749981 -51.401397) (xy 124.734625 -51.453696)
			(xy 124.711983 -51.503276) (xy 124.682515 -51.54913) (xy 124.64682 -51.590323) (xy 124.605627 -51.626017)
			(xy 124.559773 -51.655485) (xy 124.510192 -51.678127) (xy 124.457893 -51.693482) (xy 124.403941 -51.701237)
			(xy 124.376688 -51.7017) (xy 124.349023 -51.701197) (xy 124.294273 -51.693196) (xy 124.241251 -51.677378)
			(xy 124.191067 -51.654073) (xy 124.144771 -51.623771) (xy 124.103334 -51.587104) (xy 124.067621 -51.544842)
			(xy 124.052584 -51.521614) (xy 124.045965 -51.511923) (xy 124.02609 -51.499487) (xy 124.014484 -51.497738)
			(xy 123.934474 -51.489864) (xy 123.922835 -51.48922) (xy 123.900997 -51.497308) (xy 123.892564 -51.505358)
			(xy 123.89231 -51.505612) (xy 123.874209 -51.524173) (xy 123.833881 -51.556753) (xy 123.789511 -51.583568)
			(xy 123.741917 -51.604124) (xy 123.691976 -51.618042) (xy 123.64061 -51.625065) (xy 123.614688 -51.6255)
			(xy 123.587436 -51.625033) (xy 123.533487 -51.617275) (xy 123.481192 -51.601918) (xy 123.431614 -51.579275)
			(xy 123.385763 -51.549807) (xy 123.344573 -51.514113) (xy 123.308881 -51.472921) (xy 123.279416 -51.427069)
			(xy 123.256775 -51.37749) (xy 123.241421 -51.325193) (xy 123.233665 -51.271244) (xy 123.23318 -51.243992)
			(xy 108.820204 -51.243992) (xy 108.820204 -52.159662) (xy 108.820639 -52.169727) (xy 108.828369 -52.188315)
			(xy 108.83519 -52.19573) (xy 109.195413 -52.555953) (xy 122.683979 -52.555953) (xy 122.683979 -52.501447)
			(xy 122.691737 -52.447497) (xy 122.707093 -52.3952) (xy 122.729737 -52.345621) (xy 122.759206 -52.299769)
			(xy 122.794901 -52.258578) (xy 122.836095 -52.222887) (xy 122.881949 -52.193421) (xy 122.93153 -52.170782)
			(xy 122.983828 -52.15543) (xy 123.037779 -52.147677) (xy 123.065032 -52.147216) (xy 123.092403 -52.147659)
			(xy 123.146583 -52.155482) (xy 123.199087 -52.170976) (xy 123.248833 -52.193823) (xy 123.294799 -52.223552)
			(xy 123.31573 -52.241196) (xy 123.315984 -52.24145) (xy 123.323067 -52.247042) (xy 123.339987 -52.253284)
			(xy 123.349004 -52.253642) (xy 123.41606 -52.253642) (xy 123.425076 -52.253278) (xy 123.441994 -52.247037)
			(xy 123.44908 -52.24145) (xy 123.44908 -52.241196) (xy 123.449334 -52.241196) (xy 123.47028 -52.223574)
			(xy 123.516249 -52.19386) (xy 123.565993 -52.17102) (xy 123.61849 -52.155525) (xy 123.672664 -52.147693)
			(xy 123.700032 -52.147216) (xy 123.727283 -52.147656) (xy 123.781231 -52.155417) (xy 123.833525 -52.170776)
			(xy 123.883102 -52.19342) (xy 123.928951 -52.222889) (xy 123.97014 -52.258583) (xy 124.00583 -52.299775)
			(xy 124.035295 -52.345626) (xy 124.057936 -52.395205) (xy 124.07329 -52.4475) (xy 124.081046 -52.501448)
			(xy 124.081046 -52.555952) (xy 124.07329 -52.6099) (xy 124.057936 -52.662195) (xy 124.035295 -52.711774)
			(xy 124.00583 -52.757625) (xy 123.97014 -52.798817) (xy 123.928951 -52.834511) (xy 123.883102 -52.86398)
			(xy 123.833525 -52.886624) (xy 123.781231 -52.901983) (xy 123.727283 -52.909744) (xy 123.700032 -52.910232)
			(xy 123.672662 -52.909764) (xy 123.618482 -52.901949) (xy 123.565978 -52.886461) (xy 123.516231 -52.86362)
			(xy 123.470265 -52.833894) (xy 123.449334 -52.816252) (xy 123.44908 -52.815998) (xy 123.442004 -52.810397)
			(xy 123.425079 -52.804159) (xy 123.41606 -52.803806) (xy 123.349004 -52.803806) (xy 123.339987 -52.804164)
			(xy 123.32307 -52.810411) (xy 123.315984 -52.815998) (xy 123.315984 -52.816252) (xy 123.31573 -52.816252)
			(xy 123.294791 -52.833883) (xy 123.248821 -52.863598) (xy 123.199075 -52.886436) (xy 123.146576 -52.901929)
			(xy 123.092401 -52.909758) (xy 123.065032 -52.910232) (xy 123.037779 -52.909723) (xy 122.983828 -52.90197)
			(xy 122.93153 -52.886618) (xy 122.881949 -52.863979) (xy 122.836095 -52.834513) (xy 122.794901 -52.798822)
			(xy 122.759206 -52.757631) (xy 122.729737 -52.711779) (xy 122.707093 -52.6622) (xy 122.691737 -52.609903)
			(xy 122.683979 -52.555953) (xy 109.195413 -52.555953) (xy 110.136012 -53.496552) (xy 122.233664 -53.496552)
			(xy 122.233664 -53.442048) (xy 122.24142 -53.388099) (xy 122.256776 -53.335803) (xy 122.279417 -53.286225)
			(xy 122.308883 -53.240374) (xy 122.344575 -53.199182) (xy 122.385766 -53.163489) (xy 122.431616 -53.134022)
			(xy 122.481194 -53.111379) (xy 122.53349 -53.096022) (xy 122.587438 -53.088264) (xy 122.61469 -53.087778)
			(xy 122.642061 -53.088231) (xy 122.696241 -53.096049) (xy 122.748745 -53.11154) (xy 122.798492 -53.134385)
			(xy 122.844458 -53.164114) (xy 122.865388 -53.181758) (xy 122.865642 -53.182012) (xy 122.87274 -53.187582)
			(xy 122.889648 -53.193838) (xy 122.898662 -53.194204) (xy 122.965718 -53.194204) (xy 122.974736 -53.193855)
			(xy 122.991652 -53.187602) (xy 122.998738 -53.182012) (xy 122.998738 -53.181758) (xy 122.998992 -53.181758)
			(xy 123.019911 -53.164102) (xy 123.065888 -53.134394) (xy 123.115639 -53.111562) (xy 123.168142 -53.096075)
			(xy 123.22232 -53.08825) (xy 123.24969 -53.087778) (xy 123.276942 -53.088269) (xy 123.330892 -53.096024)
			(xy 123.383189 -53.111379) (xy 123.432769 -53.13402) (xy 123.478622 -53.163486) (xy 123.519814 -53.199179)
			(xy 123.555508 -53.24037) (xy 123.584975 -53.286222) (xy 123.607618 -53.335801) (xy 123.622974 -53.388098)
			(xy 123.630731 -53.442048) (xy 123.630731 -53.496552) (xy 123.622974 -53.550502) (xy 123.607618 -53.602799)
			(xy 123.584975 -53.652378) (xy 123.555508 -53.69823) (xy 123.519814 -53.739421) (xy 123.478622 -53.775114)
			(xy 123.432769 -53.80458) (xy 123.383189 -53.827221) (xy 123.330892 -53.842576) (xy 123.276942 -53.850331)
			(xy 123.24969 -53.850794) (xy 123.222319 -53.850335) (xy 123.16814 -53.842516) (xy 123.115637 -53.827025)
			(xy 123.06589 -53.804182) (xy 123.019924 -53.774456) (xy 122.998992 -53.756814) (xy 122.998738 -53.75656)
			(xy 122.991648 -53.750978) (xy 122.974734 -53.74473) (xy 122.965718 -53.744368) (xy 122.898662 -53.744368)
			(xy 122.889644 -53.744714) (xy 122.872728 -53.75097) (xy 122.865642 -53.75656) (xy 122.865642 -53.756814)
			(xy 122.865388 -53.756814) (xy 122.844435 -53.774427) (xy 122.798468 -53.804143) (xy 122.748726 -53.826983)
			(xy 122.69623 -53.84248) (xy 122.642058 -53.850316) (xy 122.61469 -53.850794) (xy 122.587438 -53.850336)
			(xy 122.53349 -53.842578) (xy 122.481194 -53.827221) (xy 122.431616 -53.804578) (xy 122.385766 -53.775111)
			(xy 122.344575 -53.739418) (xy 122.308883 -53.698226) (xy 122.279417 -53.652375) (xy 122.256776 -53.602797)
			(xy 122.24142 -53.550501) (xy 122.233664 -53.496552) (xy 110.136012 -53.496552) (xy 110.67415 -54.03469)
			(xy 110.700431 -54.061781) (xy 110.746608 -54.121485) (xy 110.784801 -54.186587) (xy 110.81439 -54.256024)
			(xy 110.83489 -54.328664) (xy 110.841028 -54.365906) (xy 110.841961 -54.371597) (xy 110.846073 -54.382368)
			(xy 110.849156 -54.387242) (xy 110.868345 -54.416271) (xy 110.900422 -54.478025) (xy 110.924895 -54.543167)
			(xy 110.941413 -54.610766) (xy 110.949741 -54.679854) (xy 110.950248 -54.714648) (xy 110.950248 -54.989051)
			(xy 120.001268 -54.989051) (xy 120.001268 -54.934549) (xy 120.009024 -54.880601) (xy 120.024379 -54.828306)
			(xy 120.047019 -54.778729) (xy 120.076485 -54.732878) (xy 120.112176 -54.691687) (xy 120.153365 -54.655995)
			(xy 120.199215 -54.626527) (xy 120.248791 -54.603884) (xy 120.301085 -54.588527) (xy 120.355033 -54.580769)
			(xy 120.382284 -54.580282) (xy 120.410375 -54.58079) (xy 120.465952 -54.589014) (xy 120.51972 -54.605303)
			(xy 120.570518 -54.629304) (xy 120.617245 -54.660497) (xy 120.65889 -54.698207) (xy 120.694553 -54.741618)
			(xy 120.709436 -54.765448) (xy 120.71477 -54.774338) (xy 120.731788 -54.78653) (xy 120.825006 -54.80685)
			(xy 120.84558 -54.802532) (xy 120.854216 -54.79669) (xy 120.878273 -54.78068) (xy 120.930207 -54.75534)
			(xy 120.985367 -54.738117) (xy 121.042493 -54.729405) (xy 121.071386 -54.728872) (xy 121.098636 -54.729391)
			(xy 121.152581 -54.737145) (xy 121.204874 -54.752498) (xy 121.25445 -54.775136) (xy 121.300299 -54.804599)
			(xy 121.341489 -54.840287) (xy 121.377181 -54.881473) (xy 121.406648 -54.92732) (xy 121.42929 -54.976894)
			(xy 121.444647 -55.029185) (xy 121.452406 -55.08313) (xy 121.452894 -55.11038) (xy 121.452418 -55.13775)
			(xy 121.444603 -55.191929) (xy 121.429116 -55.244432) (xy 121.406276 -55.294179) (xy 121.376554 -55.340146)
			(xy 121.358914 -55.361078) (xy 121.35866 -55.361332) (xy 121.353091 -55.36843) (xy 121.346835 -55.385338)
			(xy 121.346468 -55.394352) (xy 121.346468 -55.461408) (xy 121.346828 -55.470424) (xy 121.353074 -55.487341)
			(xy 121.35866 -55.494428) (xy 121.358914 -55.494428) (xy 121.358914 -55.494682) (xy 121.376533 -55.515631)
			(xy 121.406256 -55.561597) (xy 121.4291 -55.611341) (xy 121.444596 -55.66384) (xy 121.452426 -55.718016)
			(xy 121.452428 -55.772754) (xy 121.444602 -55.82693) (xy 121.42911 -55.879431) (xy 121.40627 -55.929176)
			(xy 121.376552 -55.975144) (xy 121.358914 -55.996078) (xy 121.35866 -55.996332) (xy 121.353091 -56.00343)
			(xy 121.346835 -56.020338) (xy 121.346468 -56.029352) (xy 121.346468 -56.096408) (xy 121.346828 -56.105424)
			(xy 121.353074 -56.122341) (xy 121.35866 -56.129428) (xy 121.358914 -56.129428) (xy 121.358914 -56.129682)
			(xy 121.37656 -56.150608) (xy 121.406271 -56.196583) (xy 121.429105 -56.246332) (xy 121.444594 -56.298834)
			(xy 121.452421 -56.35301) (xy 121.452894 -56.38038) (xy 121.452408 -56.407631) (xy 121.444652 -56.461579)
			(xy 121.429297 -56.513874) (xy 121.406655 -56.563451) (xy 121.377189 -56.609301) (xy 121.341498 -56.650492)
			(xy 121.300307 -56.686183) (xy 121.254457 -56.715649) (xy 121.20488 -56.738291) (xy 121.152585 -56.753646)
			(xy 121.098637 -56.761402) (xy 121.044135 -56.761402) (xy 120.990187 -56.753646) (xy 120.937892 -56.738291)
			(xy 120.888315 -56.715649) (xy 120.842465 -56.686183) (xy 120.801274 -56.650492) (xy 120.765583 -56.609301)
			(xy 120.736117 -56.563451) (xy 120.713475 -56.513874) (xy 120.69812 -56.461579) (xy 120.690364 -56.407631)
			(xy 120.689878 -56.38038) (xy 120.690313 -56.353008) (xy 120.698136 -56.298827) (xy 120.713631 -56.246323)
			(xy 120.73648 -56.196577) (xy 120.766213 -56.150612) (xy 120.783858 -56.129682) (xy 120.784112 -56.129428)
			(xy 120.789694 -56.122339) (xy 120.795943 -56.105424) (xy 120.796304 -56.096408) (xy 120.796304 -56.029352)
			(xy 120.795921 -56.020338) (xy 120.789691 -56.003421) (xy 120.784112 -55.996332) (xy 120.783858 -55.996332)
			(xy 120.783858 -55.996078) (xy 120.766196 -55.975162) (xy 120.73647 -55.929192) (xy 120.713624 -55.879443)
			(xy 120.698128 -55.826938) (xy 120.690301 -55.772757) (xy 120.690303 -55.718013) (xy 120.698134 -55.663832)
			(xy 120.713635 -55.611329) (xy 120.736485 -55.561582) (xy 120.766215 -55.515614) (xy 120.783858 -55.494682)
			(xy 120.784112 -55.494428) (xy 120.789694 -55.487339) (xy 120.795943 -55.470424) (xy 120.796304 -55.461408)
			(xy 120.796304 -55.394352) (xy 120.795921 -55.385338) (xy 120.789691 -55.368421) (xy 120.784112 -55.361332)
			(xy 120.783858 -55.360824) (xy 120.772912 -55.348091) (xy 120.753072 -55.320999) (xy 120.744234 -55.306722)
			(xy 120.7389 -55.297832) (xy 120.721882 -55.28564) (xy 120.628664 -55.26532) (xy 120.60809 -55.269638)
			(xy 120.599454 -55.27548) (xy 120.575403 -55.2915) (xy 120.523467 -55.316838) (xy 120.468305 -55.334059)
			(xy 120.411178 -55.342767) (xy 120.382284 -55.343298) (xy 120.355033 -55.342831) (xy 120.301085 -55.335073)
			(xy 120.248791 -55.319716) (xy 120.199215 -55.297073) (xy 120.153365 -55.267605) (xy 120.112176 -55.231913)
			(xy 120.076485 -55.190722) (xy 120.047019 -55.144871) (xy 120.024379 -55.095294) (xy 120.009024 -55.042999)
			(xy 120.001268 -54.989051) (xy 110.950248 -54.989051) (xy 110.950248 -55.140352) (xy 110.951264 -55.150004)
			(xy 110.952899 -55.157244) (xy 110.959753 -55.1704) (xy 110.964726 -55.175912) (xy 110.96498 -55.176166)
			(xy 110.989872 -55.200804) (xy 110.993682 -55.203852) (xy 111.448342 -55.203852) (xy 111.481505 -55.20433)
			(xy 111.547411 -55.211779) (xy 111.61207 -55.226558) (xy 111.674668 -55.248481) (xy 111.73442 -55.277271)
			(xy 111.790574 -55.312568) (xy 111.842425 -55.353927) (xy 111.866172 -55.37708) (xy 111.909943 -55.420851)
			(xy 118.324868 -55.420851) (xy 118.324868 -55.366349) (xy 118.332624 -55.312401) (xy 118.347979 -55.260106)
			(xy 118.370619 -55.210529) (xy 118.400085 -55.164678) (xy 118.435776 -55.123487) (xy 118.476965 -55.087795)
			(xy 118.522815 -55.058327) (xy 118.572391 -55.035684) (xy 118.624685 -55.020327) (xy 118.678633 -55.012569)
			(xy 118.705884 -55.012082) (xy 118.732197 -55.012566) (xy 118.784325 -55.019798) (xy 118.834967 -55.034114)
			(xy 118.883166 -55.055244) (xy 118.92801 -55.082787) (xy 118.968651 -55.116222) (xy 118.986808 -55.135272)
			(xy 118.994328 -55.142675) (xy 119.013609 -55.1512) (xy 119.024146 -55.151782) (xy 119.098822 -55.151782)
			(xy 119.109369 -55.15123) (xy 119.128665 -55.142711) (xy 119.13616 -55.135272) (xy 119.154288 -55.116189)
			(xy 119.194924 -55.082735) (xy 119.23977 -55.055181) (xy 119.287977 -55.034047) (xy 119.338629 -55.019736)
			(xy 119.390766 -55.012517) (xy 119.417084 -55.012082) (xy 119.444337 -55.012564) (xy 119.498288 -55.020319)
			(xy 119.550587 -55.035673) (xy 119.600167 -55.058314) (xy 119.646021 -55.087781) (xy 119.687215 -55.123474)
			(xy 119.722909 -55.164666) (xy 119.752378 -55.210519) (xy 119.775021 -55.260098) (xy 119.790377 -55.312396)
			(xy 119.798135 -55.366347) (xy 119.798135 -55.420853) (xy 119.790377 -55.474804) (xy 119.775021 -55.527102)
			(xy 119.752378 -55.576681) (xy 119.722909 -55.622534) (xy 119.687215 -55.663726) (xy 119.646021 -55.699419)
			(xy 119.600167 -55.728886) (xy 119.550587 -55.751527) (xy 119.498288 -55.766881) (xy 119.444337 -55.774636)
			(xy 119.417084 -55.775098) (xy 119.39077 -55.774642) (xy 119.338641 -55.767405) (xy 119.287998 -55.753084)
			(xy 119.239799 -55.731949) (xy 119.194955 -55.704401) (xy 119.154316 -55.67096) (xy 119.13616 -55.651908)
			(xy 119.128654 -55.644488) (xy 119.109362 -55.635974) (xy 119.098822 -55.635398) (xy 119.024146 -55.635398)
			(xy 119.013598 -55.635939) (xy 118.994302 -55.644466) (xy 118.986808 -55.651908) (xy 118.968643 -55.670954)
			(xy 118.928015 -55.704412) (xy 118.883177 -55.731972) (xy 118.834978 -55.753112) (xy 118.784332 -55.767431)
			(xy 118.7322 -55.774658) (xy 118.705884 -55.775098) (xy 118.678633 -55.774631) (xy 118.624685 -55.766873)
			(xy 118.572391 -55.751516) (xy 118.522815 -55.728873) (xy 118.476965 -55.699405) (xy 118.435776 -55.663713)
			(xy 118.400085 -55.622522) (xy 118.370619 -55.576671) (xy 118.347979 -55.527094) (xy 118.332624 -55.474799)
			(xy 118.324868 -55.420851) (xy 111.909943 -55.420851) (xy 112.464596 -55.975504) (xy 112.487738 -55.999263)
			(xy 112.52911 -56.051105) (xy 112.564418 -56.107254) (xy 112.593215 -56.167004) (xy 112.615142 -56.229602)
			(xy 112.629921 -56.294262) (xy 112.637366 -56.36017) (xy 112.637824 -56.393334) (xy 112.637824 -56.847994)
			(xy 112.640872 -56.851804) (xy 112.654334 -56.86552) (xy 112.654842 -56.866028) (xy 112.65662 -56.867806)
			(xy 112.66402 -56.874648) (xy 112.682618 -56.882375) (xy 112.692688 -56.882792) (xy 113.127028 -56.882792)
			(xy 113.160182 -56.883257) (xy 113.226075 -56.89068) (xy 113.290722 -56.905429) (xy 113.353314 -56.927319)
			(xy 113.413063 -56.956075) (xy 113.469219 -56.991336) (xy 113.521077 -57.03266) (xy 113.544858 -57.055766)
			(xy 113.974372 -57.48528) (xy 120.706132 -57.48528) (xy 120.710203 -57.429658) (xy 120.722329 -57.375221)
			(xy 120.742252 -57.32313) (xy 120.769548 -57.274495) (xy 120.803634 -57.230352) (xy 120.843783 -57.191643)
			(xy 120.889141 -57.159192) (xy 120.938741 -57.133691) (xy 120.991525 -57.115684) (xy 121.046368 -57.105554)
			(xy 121.102102 -57.103517) (xy 121.157539 -57.109617) (xy 121.211496 -57.123723) (xy 121.262825 -57.145535)
			(xy 121.310431 -57.174589) (xy 121.353299 -57.210264) (xy 121.390516 -57.251801) (xy 121.421289 -57.298314)
			(xy 121.444961 -57.348811) (xy 121.461029 -57.402218) (xy 121.469149 -57.457394) (xy 121.469658 -57.48528)
			(xy 121.469149 -57.513166) (xy 121.461029 -57.568342) (xy 121.444961 -57.621749) (xy 121.421289 -57.672246)
			(xy 121.390516 -57.718759) (xy 121.353299 -57.760296) (xy 121.310431 -57.795971) (xy 121.262825 -57.825025)
			(xy 121.211496 -57.846837) (xy 121.157539 -57.860943) (xy 121.102102 -57.867043) (xy 121.046368 -57.865006)
			(xy 120.991525 -57.854876) (xy 120.938741 -57.836869) (xy 120.889141 -57.811368) (xy 120.843783 -57.778917)
			(xy 120.803634 -57.740208) (xy 120.769548 -57.696065) (xy 120.742252 -57.64743) (xy 120.722329 -57.595339)
			(xy 120.710203 -57.540902) (xy 120.706132 -57.48528) (xy 113.974372 -57.48528) (xy 114.143282 -57.65419)
			(xy 114.166389 -57.67797) (xy 114.207716 -57.729825) (xy 114.242978 -57.78598) (xy 114.271732 -57.84573)
			(xy 114.293616 -57.908323) (xy 114.308356 -57.972972) (xy 114.315766 -58.038866) (xy 114.316256 -58.07202)
			(xy 114.316256 -58.076084) (xy 121.458226 -58.076084) (xy 121.462297 -58.020462) (xy 121.474423 -57.966025)
			(xy 121.494346 -57.913934) (xy 121.521642 -57.865299) (xy 121.555728 -57.821156) (xy 121.595877 -57.782447)
			(xy 121.641235 -57.749996) (xy 121.690835 -57.724495) (xy 121.743619 -57.706488) (xy 121.798462 -57.696358)
			(xy 121.854196 -57.694321) (xy 121.909633 -57.700421) (xy 121.96359 -57.714527) (xy 122.014919 -57.736339)
			(xy 122.062525 -57.765393) (xy 122.105393 -57.801068) (xy 122.14261 -57.842605) (xy 122.158946 -57.867296)
			(xy 123.74321 -57.867296) (xy 123.747281 -57.811674) (xy 123.759407 -57.757237) (xy 123.77933 -57.705146)
			(xy 123.806626 -57.656511) (xy 123.840712 -57.612368) (xy 123.880861 -57.573659) (xy 123.926219 -57.541208)
			(xy 123.975819 -57.515707) (xy 124.028603 -57.4977) (xy 124.083446 -57.48757) (xy 124.13918 -57.485533)
			(xy 124.194617 -57.491633) (xy 124.248574 -57.505739) (xy 124.299903 -57.527551) (xy 124.347509 -57.556605)
			(xy 124.390377 -57.59228) (xy 124.427594 -57.633817) (xy 124.458367 -57.68033) (xy 124.482039 -57.730827)
			(xy 124.498107 -57.784234) (xy 124.506227 -57.83941) (xy 124.506736 -57.867296) (xy 124.506227 -57.895182)
			(xy 124.498107 -57.950358) (xy 124.482039 -58.003765) (xy 124.458367 -58.054262) (xy 124.427594 -58.100775)
			(xy 124.390377 -58.142312) (xy 124.347509 -58.177987) (xy 124.299903 -58.207041) (xy 124.248574 -58.228853)
			(xy 124.194617 -58.242959) (xy 124.13918 -58.249059) (xy 124.083446 -58.247022) (xy 124.028603 -58.236892)
			(xy 123.975819 -58.218885) (xy 123.926219 -58.193384) (xy 123.880861 -58.160933) (xy 123.840712 -58.122224)
			(xy 123.806626 -58.078081) (xy 123.77933 -58.029446) (xy 123.759407 -57.977355) (xy 123.747281 -57.922918)
			(xy 123.74321 -57.867296) (xy 122.158946 -57.867296) (xy 122.173383 -57.889118) (xy 122.197055 -57.939615)
			(xy 122.213123 -57.993022) (xy 122.221243 -58.048198) (xy 122.221752 -58.076084) (xy 122.221243 -58.10397)
			(xy 122.213123 -58.159146) (xy 122.197055 -58.212553) (xy 122.173383 -58.26305) (xy 122.14261 -58.309563)
			(xy 122.105393 -58.3511) (xy 122.062525 -58.386775) (xy 122.014919 -58.415829) (xy 121.96359 -58.437641)
			(xy 121.909633 -58.451747) (xy 121.854196 -58.457847) (xy 121.798462 -58.45581) (xy 121.743619 -58.44568)
			(xy 121.690835 -58.427673) (xy 121.641235 -58.402172) (xy 121.595877 -58.369721) (xy 121.555728 -58.331012)
			(xy 121.521642 -58.286869) (xy 121.494346 -58.238234) (xy 121.474423 -58.186143) (xy 121.462297 -58.131706)
			(xy 121.458226 -58.076084) (xy 114.316256 -58.076084) (xy 114.316256 -58.526172) (xy 114.322606 -58.533792)
			(xy 114.33302 -58.544206) (xy 114.333528 -58.544714) (xy 114.347244 -58.558176) (xy 114.351054 -58.561224)
			(xy 114.805714 -58.561224) (xy 122.66244 -58.561224) (xy 122.666511 -58.505602) (xy 122.678637 -58.451165)
			(xy 122.69856 -58.399074) (xy 122.725856 -58.350439) (xy 122.759942 -58.306296) (xy 122.800091 -58.267587)
			(xy 122.845449 -58.235136) (xy 122.895049 -58.209635) (xy 122.947833 -58.191628) (xy 123.002676 -58.181498)
			(xy 123.05841 -58.179461) (xy 123.113847 -58.185561) (xy 123.167804 -58.199667) (xy 123.219133 -58.221479)
			(xy 123.266739 -58.250533) (xy 123.309607 -58.286208) (xy 123.346824 -58.327745) (xy 123.377597 -58.374258)
			(xy 123.401269 -58.424755) (xy 123.408779 -58.449718) (xy 124.90907 -58.449718) (xy 124.913141 -58.394096)
			(xy 124.925267 -58.339659) (xy 124.94519 -58.287568) (xy 124.972486 -58.238933) (xy 125.006572 -58.19479)
			(xy 125.046721 -58.156081) (xy 125.092079 -58.12363) (xy 125.141679 -58.098129) (xy 125.194463 -58.080122)
			(xy 125.249306 -58.069992) (xy 125.30504 -58.067955) (xy 125.360477 -58.074055) (xy 125.414434 -58.088161)
			(xy 125.465763 -58.109973) (xy 125.513369 -58.139027) (xy 125.556237 -58.174702) (xy 125.593454 -58.216239)
			(xy 125.624227 -58.262752) (xy 125.647899 -58.313249) (xy 125.663967 -58.366656) (xy 125.672087 -58.421832)
			(xy 125.672596 -58.449718) (xy 125.672087 -58.477604) (xy 125.663967 -58.53278) (xy 125.647899 -58.586187)
			(xy 125.624227 -58.636684) (xy 125.593454 -58.683197) (xy 125.556237 -58.724734) (xy 125.513369 -58.760409)
			(xy 125.465763 -58.789463) (xy 125.414434 -58.811275) (xy 125.360477 -58.825381) (xy 125.30504 -58.831481)
			(xy 125.249306 -58.829444) (xy 125.194463 -58.819314) (xy 125.141679 -58.801307) (xy 125.092079 -58.775806)
			(xy 125.046721 -58.743355) (xy 125.006572 -58.704646) (xy 124.972486 -58.660503) (xy 124.94519 -58.611868)
			(xy 124.925267 -58.559777) (xy 124.913141 -58.50534) (xy 124.90907 -58.449718) (xy 123.408779 -58.449718)
			(xy 123.417337 -58.478162) (xy 123.425457 -58.533338) (xy 123.425966 -58.561224) (xy 123.425457 -58.58911)
			(xy 123.417337 -58.644286) (xy 123.401269 -58.697693) (xy 123.377597 -58.74819) (xy 123.346824 -58.794703)
			(xy 123.309607 -58.83624) (xy 123.266739 -58.871915) (xy 123.219133 -58.900969) (xy 123.167804 -58.922781)
			(xy 123.113847 -58.936887) (xy 123.05841 -58.942987) (xy 123.002676 -58.94095) (xy 122.947833 -58.93082)
			(xy 122.895049 -58.912813) (xy 122.845449 -58.887312) (xy 122.800091 -58.854861) (xy 122.759942 -58.816152)
			(xy 122.725856 -58.772009) (xy 122.69856 -58.723374) (xy 122.678637 -58.671283) (xy 122.666511 -58.616846)
			(xy 122.66244 -58.561224) (xy 114.805714 -58.561224) (xy 114.838875 -58.561706) (xy 114.904776 -58.569164)
			(xy 114.969429 -58.583951) (xy 115.032021 -58.605881) (xy 115.091764 -58.634679) (xy 115.14791 -58.669982)
			(xy 115.199751 -58.711348) (xy 115.223544 -58.734452) (xy 115.663726 -59.174634) (xy 121.193304 -59.174634)
			(xy 121.197375 -59.119012) (xy 121.209501 -59.064575) (xy 121.229424 -59.012484) (xy 121.25672 -58.963849)
			(xy 121.290806 -58.919706) (xy 121.330955 -58.880997) (xy 121.376313 -58.848546) (xy 121.425913 -58.823045)
			(xy 121.478697 -58.805038) (xy 121.53354 -58.794908) (xy 121.589274 -58.792871) (xy 121.644711 -58.798971)
			(xy 121.698668 -58.813077) (xy 121.749997 -58.834889) (xy 121.797603 -58.863943) (xy 121.840471 -58.899618)
			(xy 121.877688 -58.941155) (xy 121.908461 -58.987668) (xy 121.932133 -59.038165) (xy 121.948201 -59.091572)
			(xy 121.956321 -59.146748) (xy 121.95683 -59.174634) (xy 121.956321 -59.20252) (xy 121.948201 -59.257696)
			(xy 121.932133 -59.311103) (xy 121.908461 -59.3616) (xy 121.877688 -59.408113) (xy 121.840471 -59.44965)
			(xy 121.797603 -59.485325) (xy 121.749997 -59.514379) (xy 121.698668 -59.536191) (xy 121.644711 -59.550297)
			(xy 121.589274 -59.556397) (xy 121.53354 -59.55436) (xy 121.478697 -59.54423) (xy 121.425913 -59.526223)
			(xy 121.376313 -59.500722) (xy 121.330955 -59.468271) (xy 121.290806 -59.429562) (xy 121.25672 -59.385419)
			(xy 121.229424 -59.336784) (xy 121.209501 -59.284693) (xy 121.197375 -59.230256) (xy 121.193304 -59.174634)
			(xy 115.663726 -59.174634) (xy 115.821968 -59.332876) (xy 115.845112 -59.356634) (xy 115.886489 -59.408475)
			(xy 115.9218 -59.464623) (xy 115.950603 -59.524373) (xy 115.972533 -59.586971) (xy 115.987315 -59.651632)
			(xy 115.994764 -59.717542) (xy 115.995196 -59.750706) (xy 115.995196 -60.186062) (xy 115.994717 -60.219224)
			(xy 115.987265 -60.285129) (xy 115.972483 -60.349785) (xy 115.950557 -60.412381) (xy 115.921764 -60.472129)
			(xy 115.886464 -60.52828) (xy 115.845101 -60.580127) (xy 115.821968 -60.603892) (xy 115.792504 -60.633356)
			(xy 123.897134 -60.633356) (xy 123.901205 -60.577734) (xy 123.913331 -60.523297) (xy 123.933254 -60.471206)
			(xy 123.96055 -60.422571) (xy 123.994636 -60.378428) (xy 124.034785 -60.339719) (xy 124.080143 -60.307268)
			(xy 124.129743 -60.281767) (xy 124.182527 -60.26376) (xy 124.23737 -60.25363) (xy 124.293104 -60.251593)
			(xy 124.348541 -60.257693) (xy 124.402498 -60.271799) (xy 124.453827 -60.293611) (xy 124.501433 -60.322665)
			(xy 124.544301 -60.35834) (xy 124.581518 -60.399877) (xy 124.612291 -60.44639) (xy 124.635963 -60.496887)
			(xy 124.652031 -60.550294) (xy 124.660151 -60.60547) (xy 124.66066 -60.633356) (xy 124.660151 -60.661242)
			(xy 124.652031 -60.716418) (xy 124.635963 -60.769825) (xy 124.612291 -60.820322) (xy 124.581518 -60.866835)
			(xy 124.544301 -60.908372) (xy 124.501433 -60.944047) (xy 124.453827 -60.973101) (xy 124.402498 -60.994913)
			(xy 124.348541 -61.009019) (xy 124.293104 -61.015119) (xy 124.23737 -61.013082) (xy 124.182527 -61.002952)
			(xy 124.129743 -60.984945) (xy 124.080143 -60.959444) (xy 124.034785 -60.926993) (xy 123.994636 -60.888284)
			(xy 123.96055 -60.844141) (xy 123.933254 -60.795506) (xy 123.913331 -60.743415) (xy 123.901205 -60.688978)
			(xy 123.897134 -60.633356) (xy 115.792504 -60.633356) (xy 114.944144 -61.481716) (xy 114.938565 -61.487812)
			(xy 122.40463 -61.487812) (xy 122.408701 -61.43219) (xy 122.420827 -61.377753) (xy 122.44075 -61.325662)
			(xy 122.468046 -61.277027) (xy 122.502132 -61.232884) (xy 122.542281 -61.194175) (xy 122.587639 -61.161724)
			(xy 122.637239 -61.136223) (xy 122.690023 -61.118216) (xy 122.744866 -61.108086) (xy 122.8006 -61.106049)
			(xy 122.856037 -61.112149) (xy 122.909994 -61.126255) (xy 122.961323 -61.148067) (xy 123.008929 -61.177121)
			(xy 123.051797 -61.212796) (xy 123.089014 -61.254333) (xy 123.119787 -61.300846) (xy 123.143459 -61.351343)
			(xy 123.159527 -61.40475) (xy 123.167647 -61.459926) (xy 123.168156 -61.487812) (xy 123.167647 -61.515698)
			(xy 123.159527 -61.570874) (xy 123.143459 -61.624281) (xy 123.119787 -61.674778) (xy 123.089014 -61.721291)
			(xy 123.051797 -61.762828) (xy 123.008929 -61.798503) (xy 122.961323 -61.827557) (xy 122.909994 -61.849369)
			(xy 122.856037 -61.863475) (xy 122.8006 -61.869575) (xy 122.744866 -61.867538) (xy 122.690023 -61.857408)
			(xy 122.637239 -61.839401) (xy 122.587639 -61.8139) (xy 122.542281 -61.781449) (xy 122.502132 -61.74274)
			(xy 122.468046 -61.698597) (xy 122.44075 -61.649962) (xy 122.420827 -61.597871) (xy 122.408701 -61.543434)
			(xy 122.40463 -61.487812) (xy 114.938565 -61.487812) (xy 114.937343 -61.489147) (xy 114.929686 -61.507762)
			(xy 114.929736 -61.527891) (xy 114.933222 -61.537342) (xy 114.937481 -61.54637) (xy 114.951571 -61.56048)
			(xy 114.969988 -61.568125) (xy 114.979958 -61.568584) (xy 115.270788 -61.568584) (xy 115.303518 -61.56902)
			(xy 115.368577 -61.576248) (xy 115.432438 -61.590629) (xy 115.494316 -61.611985) (xy 115.553452 -61.640054)
			(xy 115.60912 -61.674493) (xy 115.660638 -61.714877) (xy 115.6843 -61.737494) (xy 115.685316 -61.73851)
			(xy 115.703096 -61.755528) (xy 116.068602 -62.121034) (xy 120.342404 -62.121034) (xy 120.346475 -62.065412)
			(xy 120.358601 -62.010975) (xy 120.378524 -61.958884) (xy 120.40582 -61.910249) (xy 120.439906 -61.866106)
			(xy 120.480055 -61.827397) (xy 120.525413 -61.794946) (xy 120.575013 -61.769445) (xy 120.627797 -61.751438)
			(xy 120.68264 -61.741308) (xy 120.738374 -61.739271) (xy 120.793811 -61.745371) (xy 120.847768 -61.759477)
			(xy 120.899097 -61.781289) (xy 120.946703 -61.810343) (xy 120.989571 -61.846018) (xy 121.026788 -61.887555)
			(xy 121.057561 -61.934068) (xy 121.081233 -61.984565) (xy 121.097301 -62.037972) (xy 121.105421 -62.093148)
			(xy 121.10593 -62.121034) (xy 121.105421 -62.14892) (xy 121.097301 -62.204096) (xy 121.081233 -62.257503)
			(xy 121.057561 -62.308) (xy 121.026788 -62.354513) (xy 120.989571 -62.39605) (xy 120.946703 -62.431725)
			(xy 120.899097 -62.460779) (xy 120.847768 -62.482591) (xy 120.793811 -62.496697) (xy 120.738374 -62.502797)
			(xy 120.68264 -62.50076) (xy 120.627797 -62.49063) (xy 120.575013 -62.472623) (xy 120.525413 -62.447122)
			(xy 120.480055 -62.414671) (xy 120.439906 -62.375962) (xy 120.40582 -62.331819) (xy 120.378524 -62.283184)
			(xy 120.358601 -62.231093) (xy 120.346475 -62.176656) (xy 120.342404 -62.121034) (xy 116.068602 -62.121034)
			(xy 117.033802 -63.086234) (xy 117.487698 -63.086234) (xy 117.491769 -63.030612) (xy 117.503895 -62.976175)
			(xy 117.523818 -62.924084) (xy 117.551114 -62.875449) (xy 117.5852 -62.831306) (xy 117.625349 -62.792597)
			(xy 117.670707 -62.760146) (xy 117.720307 -62.734645) (xy 117.773091 -62.716638) (xy 117.827934 -62.706508)
			(xy 117.883668 -62.704471) (xy 117.939105 -62.710571) (xy 117.993062 -62.724677) (xy 118.013208 -62.733238)
			(xy 123.76625 -62.733238) (xy 123.766253 -62.67873) (xy 123.774012 -62.624778) (xy 123.789371 -62.57248)
			(xy 123.812017 -62.522899) (xy 123.841488 -62.477047) (xy 123.877185 -62.435855) (xy 123.91838 -62.400162)
			(xy 123.964236 -62.370696) (xy 124.013819 -62.348056) (xy 124.066119 -62.332703) (xy 124.120072 -62.32495)
			(xy 124.147326 -62.324488) (xy 124.170881 -62.324863) (xy 124.217625 -62.330724) (xy 124.240544 -62.336172)
			(xy 124.2543 -62.339208) (xy 124.28245 -62.338353) (xy 124.309298 -62.329846) (xy 124.332804 -62.314336)
			(xy 124.351185 -62.292998) (xy 124.363044 -62.267454) (xy 124.367481 -62.239643) (xy 124.364159 -62.211677)
			(xy 124.359162 -62.198504) (xy 124.349851 -62.175114) (xy 124.336726 -62.126514) (xy 124.330103 -62.076609)
			(xy 124.329698 -62.051438) (xy 124.330114 -62.024182) (xy 124.337867 -61.970224) (xy 124.35322 -61.917918)
			(xy 124.37586 -61.86833) (xy 124.405328 -61.822469) (xy 124.441022 -61.781268) (xy 124.482217 -61.745567)
			(xy 124.528073 -61.716092) (xy 124.577657 -61.693443) (xy 124.62996 -61.678081) (xy 124.683917 -61.670319)
			(xy 124.738429 -61.670315) (xy 124.792387 -61.678069) (xy 124.844692 -61.693424) (xy 124.894279 -61.716066)
			(xy 124.94014 -61.745534) (xy 124.981339 -61.78123) (xy 125.017039 -61.822425) (xy 125.046513 -61.868282)
			(xy 125.069161 -61.917867) (xy 125.084521 -61.97017) (xy 125.092282 -62.024127) (xy 125.092284 -62.078639)
			(xy 125.084529 -62.132597) (xy 125.069173 -62.184902) (xy 125.046529 -62.234489) (xy 125.017059 -62.280348)
			(xy 124.981363 -62.321547) (xy 124.940166 -62.357246) (xy 124.894308 -62.386718) (xy 124.844723 -62.409365)
			(xy 124.792419 -62.424724) (xy 124.738462 -62.432483) (xy 124.711206 -62.432946) (xy 124.687652 -62.432564)
			(xy 124.640907 -62.426708) (xy 124.617988 -62.421262) (xy 124.604232 -62.418212) (xy 124.576076 -62.41906)
			(xy 124.549222 -62.427563) (xy 124.525709 -62.443075) (xy 124.507325 -62.464417) (xy 124.495467 -62.489968)
			(xy 124.491035 -62.517786) (xy 124.494367 -62.545757) (xy 124.49937 -62.55893) (xy 124.508692 -62.582315)
			(xy 124.521813 -62.630918) (xy 124.528431 -62.680824) (xy 124.528834 -62.705996) (xy 124.528349 -62.73325)
			(xy 124.520592 -62.787202) (xy 124.505236 -62.839501) (xy 124.482593 -62.889083) (xy 124.453124 -62.934937)
			(xy 124.41743 -62.976131) (xy 124.376236 -63.011826) (xy 124.330381 -63.041294) (xy 124.2808 -63.063937)
			(xy 124.2285 -63.079293) (xy 124.174548 -63.087049) (xy 124.12004 -63.087048) (xy 124.066088 -63.07929)
			(xy 124.013789 -63.063933) (xy 123.964208 -63.041288) (xy 123.918355 -63.011818) (xy 123.877162 -62.976123)
			(xy 123.841468 -62.934928) (xy 123.812001 -62.889072) (xy 123.78936 -62.83949) (xy 123.774005 -62.78719)
			(xy 123.76625 -62.733238) (xy 118.013208 -62.733238) (xy 118.044391 -62.746489) (xy 118.091997 -62.775543)
			(xy 118.134865 -62.811218) (xy 118.172082 -62.852755) (xy 118.202855 -62.899268) (xy 118.226527 -62.949765)
			(xy 118.242595 -63.003172) (xy 118.250715 -63.058348) (xy 118.251224 -63.086234) (xy 118.250715 -63.11412)
			(xy 118.242595 -63.169296) (xy 118.226527 -63.222703) (xy 118.202855 -63.2732) (xy 118.202702 -63.273432)
			(xy 119.676924 -63.273432) (xy 119.680995 -63.21781) (xy 119.693121 -63.163373) (xy 119.713044 -63.111282)
			(xy 119.74034 -63.062647) (xy 119.774426 -63.018504) (xy 119.814575 -62.979795) (xy 119.859933 -62.947344)
			(xy 119.909533 -62.921843) (xy 119.962317 -62.903836) (xy 120.01716 -62.893706) (xy 120.072894 -62.891669)
			(xy 120.128331 -62.897769) (xy 120.182288 -62.911875) (xy 120.233617 -62.933687) (xy 120.281223 -62.962741)
			(xy 120.324091 -62.998416) (xy 120.361308 -63.039953) (xy 120.392081 -63.086466) (xy 120.415753 -63.136963)
			(xy 120.431821 -63.19037) (xy 120.439941 -63.245546) (xy 120.44045 -63.273432) (xy 120.439941 -63.301318)
			(xy 120.431821 -63.356494) (xy 120.415753 -63.409901) (xy 120.392081 -63.460398) (xy 120.361308 -63.506911)
			(xy 120.324091 -63.548448) (xy 120.281223 -63.584123) (xy 120.233617 -63.613177) (xy 120.182288 -63.634989)
			(xy 120.128331 -63.649095) (xy 120.072894 -63.655195) (xy 120.01716 -63.653158) (xy 119.962317 -63.643028)
			(xy 119.909533 -63.625021) (xy 119.859933 -63.59952) (xy 119.814575 -63.567069) (xy 119.774426 -63.52836)
			(xy 119.74034 -63.484217) (xy 119.713044 -63.435582) (xy 119.693121 -63.383491) (xy 119.680995 -63.329054)
			(xy 119.676924 -63.273432) (xy 118.202702 -63.273432) (xy 118.172082 -63.319713) (xy 118.134865 -63.36125)
			(xy 118.091997 -63.396925) (xy 118.044391 -63.425979) (xy 117.993062 -63.447791) (xy 117.939105 -63.461897)
			(xy 117.883668 -63.467997) (xy 117.827934 -63.46596) (xy 117.773091 -63.45583) (xy 117.720307 -63.437823)
			(xy 117.670707 -63.412322) (xy 117.625349 -63.379871) (xy 117.5852 -63.341162) (xy 117.551114 -63.297019)
			(xy 117.523818 -63.248384) (xy 117.503895 -63.196293) (xy 117.491769 -63.141856) (xy 117.487698 -63.086234)
			(xy 117.033802 -63.086234) (xy 117.68074 -63.733172) (xy 117.683534 -63.735712) (xy 117.685312 -63.737236)
			(xy 117.693988 -63.743403) (xy 117.714632 -63.748511) (xy 117.72519 -63.747142) (xy 117.736112 -63.744856)
			(xy 117.739668 -63.743586) (xy 117.769416 -63.733448) (xy 117.8312 -63.721952) (xy 117.862604 -63.720726)
			(xy 117.870224 -63.720726) (xy 117.89734 -63.721245) (xy 117.951014 -63.729003) (xy 118.003052 -63.744276)
			(xy 118.052407 -63.766755) (xy 118.098086 -63.795989) (xy 118.139171 -63.83139) (xy 118.174835 -63.872246)
			(xy 118.204362 -63.917736) (xy 118.227159 -63.966945) (xy 118.235476 -63.99276) (xy 118.235476 -63.993014)
			(xy 118.238524 -64.00292) (xy 118.264432 -64.034416) (xy 118.27383 -64.039242) (xy 118.285768 -64.045592)
			(xy 118.322137 -64.066224) (xy 118.389077 -64.116329) (xy 118.419118 -64.145414) (xy 118.48084 -64.207136)
			(xy 118.484142 -64.209422) (xy 118.504217 -64.22401) (xy 118.542111 -64.256059) (xy 118.559834 -64.27343)
			(xy 119.41048 -65.124076) (xy 122.207526 -65.124076) (xy 122.211597 -65.068454) (xy 122.223723 -65.014017)
			(xy 122.243646 -64.961926) (xy 122.270942 -64.913291) (xy 122.305028 -64.869148) (xy 122.345177 -64.830439)
			(xy 122.390535 -64.797988) (xy 122.440135 -64.772487) (xy 122.492919 -64.75448) (xy 122.547762 -64.74435)
			(xy 122.603496 -64.742313) (xy 122.658933 -64.748413) (xy 122.71289 -64.762519) (xy 122.764219 -64.784331)
			(xy 122.811825 -64.813385) (xy 122.854693 -64.84906) (xy 122.89191 -64.890597) (xy 122.922683 -64.93711)
			(xy 122.946355 -64.987607) (xy 122.962423 -65.041014) (xy 122.970543 -65.09619) (xy 122.971052 -65.124076)
			(xy 122.970543 -65.151962) (xy 122.962423 -65.207138) (xy 122.946355 -65.260545) (xy 122.922683 -65.311042)
			(xy 122.89191 -65.357555) (xy 122.854693 -65.399092) (xy 122.811825 -65.434767) (xy 122.764219 -65.463821)
			(xy 122.71289 -65.485633) (xy 122.658933 -65.499739) (xy 122.603496 -65.505839) (xy 122.547762 -65.503802)
			(xy 122.492919 -65.493672) (xy 122.440135 -65.475665) (xy 122.390535 -65.450164) (xy 122.345177 -65.417713)
			(xy 122.305028 -65.379004) (xy 122.270942 -65.334861) (xy 122.243646 -65.286226) (xy 122.223723 -65.234135)
			(xy 122.211597 -65.179698) (xy 122.207526 -65.124076) (xy 119.41048 -65.124076) (xy 121.160032 -66.873628)
			(xy 121.163842 -66.874136) (xy 121.166636 -66.87439) (xy 124.117608 -66.87439) (xy 124.126106 -66.87402)
			(xy 124.142134 -66.868355) (xy 124.155422 -66.857753) (xy 124.16028 -66.850768) (xy 124.16028 -66.73215)
			(xy 124.160804 -66.697263) (xy 124.16905 -66.627978) (xy 124.185396 -66.560145) (xy 124.209615 -66.494709)
			(xy 124.22505 -66.463418) (xy 124.225558 -66.462402) (xy 124.240177 -66.432921) (xy 124.275113 -66.377154)
			(xy 124.316127 -66.325691) (xy 124.339096 -66.302128) (xy 124.586238 -66.054986) (xy 124.646944 -65.994534)
			(xy 124.669676 -65.97238) (xy 124.719163 -65.932626) (xy 124.772686 -65.898497) (xy 124.829606 -65.870399)
			(xy 124.859288 -65.859152) (xy 124.860304 -65.858644) (xy 124.894483 -65.846026) (xy 124.965166 -65.828346)
			(xy 125.037487 -65.819502) (xy 125.073918 -65.81902) (xy 127.778256 -65.81902) (xy 127.788285 -65.818608)
			(xy 127.80682 -65.810947) (xy 127.821011 -65.796774) (xy 127.828696 -65.778248) (xy 127.829056 -65.76822)
			(xy 127.829056 -42.60596) (xy 127.829522 -42.572806) (xy 127.836945 -42.506914) (xy 127.851695 -42.442266)
			(xy 127.873585 -42.379675) (xy 127.90234 -42.319925) (xy 127.937601 -42.263769) (xy 127.978923 -42.21191)
			(xy 128.00203 -42.18813) (xy 129.30632 -40.88384) (xy 129.313686 -40.870124) (xy 129.314956 -40.862504)
			(xy 129.321859 -40.827326) (xy 129.343064 -40.758845) (xy 129.372392 -40.693428) (xy 129.40941 -40.632036)
			(xy 129.453577 -40.575567) (xy 129.478532 -40.54983) (xy 129.829052 -40.19931) (xy 129.851768 -40.177161)
			(xy 129.901151 -40.137325) (xy 129.927604 -40.119808) (xy 129.932176 -40.117014) (xy 129.982468 -40.066722)
			(xy 130.009993 -40.040043) (xy 130.070829 -39.993404) (xy 130.137259 -39.955153) (xy 130.17246 -39.939976)
			(xy 130.200908 -39.90975) (xy 130.212319 -39.878659) (xy 130.24112 -39.819017) (xy 130.276415 -39.762974)
			(xy 130.31776 -39.711232) (xy 130.340862 -39.6875) (xy 130.691382 -39.33698) (xy 130.714583 -39.314342)
			(xy 130.765115 -39.273734) (xy 130.79222 -39.255954) (xy 130.79984 -39.250112) (xy 130.82326 -39.228659)
			(xy 130.873991 -39.19044) (xy 130.92859 -39.157988) (xy 130.95732 -39.144448) (xy 130.972258 -39.137734)
			(xy 131.002756 -39.125789) (xy 131.01828 -39.120572) (xy 131.0513 -39.085774) (xy 131.062036 -39.04917)
			(xy 131.091649 -38.978871) (xy 131.130061 -38.912966) (xy 131.176635 -38.852553) (xy 131.203192 -38.82517)
			(xy 131.553712 -38.47465) (xy 131.575824 -38.453108) (xy 131.623794 -38.414245) (xy 131.675554 -38.380595)
			(xy 131.73054 -38.352524) (xy 131.759198 -38.341046) (xy 131.761992 -38.34003) (xy 131.8006 -38.324028)
			(xy 131.813933 -38.319128) (xy 131.840996 -38.310487) (xy 131.854702 -38.306756) (xy 131.891532 -38.297104)
			(xy 131.892548 -38.295834) (xy 131.892548 -36.434268) (xy 131.893013 -36.401113) (xy 131.900436 -36.335221)
			(xy 131.915185 -36.270573) (xy 131.937074 -36.207981) (xy 131.965829 -36.14823) (xy 132.001088 -36.092073)
			(xy 132.04241 -36.040213) (xy 132.065522 -36.016438) (xy 133.134862 -34.947098) (xy 133.141712 -34.939701)
			(xy 133.149452 -34.921103) (xy 133.149848 -34.91103) (xy 133.149848 -34.758376) (xy 133.145784 -34.744406)
			(xy 133.14172 -34.73831) (xy 133.12403 -34.709778) (xy 133.094507 -34.649482) (xy 133.072019 -34.586225)
			(xy 133.056858 -34.520823) (xy 133.049219 -34.454124) (xy 133.048756 -34.420556) (xy 133.048756 -34.374836)
			(xy 133.046978 -34.369756) (xy 133.046216 -34.367216) (xy 133.041176 -34.350869) (xy 133.032789 -34.3177)
			(xy 133.029452 -34.300922) (xy 133.024273 -34.271815) (xy 133.019149 -34.212913) (xy 133.020028 -34.153796)
			(xy 133.023102 -34.124392) (xy 133.023356 -34.121344) (xy 133.023356 -33.76041) (xy 133.023793 -33.72811)
			(xy 133.030945 -33.663906) (xy 133.045163 -33.600889) (xy 133.066271 -33.539834) (xy 133.079744 -33.510474)
			(xy 133.095238 -33.47974) (xy 133.101334 -33.455356) (xy 133.09727 -33.43529) (xy 133.084722 -33.405106)
			(xy 133.065593 -33.342597) (xy 133.053461 -33.278363) (xy 133.050534 -33.245806) (xy 133.048502 -33.234884)
			(xy 133.040544 -33.207486) (xy 133.02938 -33.151533) (xy 133.023741 -33.094756) (xy 133.023356 -33.066228)
			(xy 133.023356 -32.622998) (xy 133.023794 -32.590698) (xy 133.030947 -32.526494) (xy 133.045166 -32.463478)
			(xy 133.066275 -32.402424) (xy 133.079744 -32.373062) (xy 133.087633 -32.356658) (xy 133.105169 -32.324756)
			(xy 133.114796 -32.309308) (xy 133.118606 -32.302958) (xy 133.120384 -32.296608) (xy 133.121417 -32.293011)
			(xy 133.122558 -32.285616) (xy 133.12267 -32.281876) (xy 133.12267 -32.26816) (xy 133.116828 -32.256984)
			(xy 133.109952 -32.243805) (xy 133.097371 -32.216869) (xy 133.091682 -32.203136) (xy 133.089904 -32.199072)
			(xy 133.079744 -32.178752) (xy 133.079744 -32.178244) (xy 133.066275 -32.148916) (xy 133.045172 -32.087925)
			(xy 133.030951 -32.024972) (xy 133.023787 -31.960831) (xy 133.023356 -31.928562) (xy 133.023356 -31.485586)
			(xy 133.023794 -31.453286) (xy 133.030949 -31.389083) (xy 133.045169 -31.326067) (xy 133.06628 -31.265013)
			(xy 133.079744 -31.23565) (xy 133.087634 -31.219246) (xy 133.10517 -31.187345) (xy 133.114796 -31.171896)
			(xy 133.118606 -31.165546) (xy 133.120384 -31.159196) (xy 133.121423 -31.1556) (xy 133.122576 -31.148205)
			(xy 133.12267 -31.144464) (xy 133.12267 -31.132272) (xy 133.122592 -31.128529) (xy 133.121449 -31.121129)
			(xy 133.120384 -31.11754) (xy 133.118606 -31.11119) (xy 133.114796 -31.10484) (xy 133.105158 -31.089398)
			(xy 133.087621 -31.057496) (xy 133.079744 -31.041086) (xy 133.066271 -31.011726) (xy 133.045164 -30.950671)
			(xy 133.030944 -30.887654) (xy 133.023788 -30.82345) (xy 133.023356 -30.79115) (xy 133.023356 -30.347412)
			(xy 133.023918 -30.311941) (xy 133.032601 -30.241533) (xy 133.049768 -30.172699) (xy 133.061964 -30.139386)
			(xy 133.063996 -30.132782) (xy 133.073814 -30.09367) (xy 133.102617 -30.018352) (xy 133.1214 -29.982668)
			(xy 133.118606 -29.973778) (xy 133.114796 -29.967428) (xy 133.105156 -29.951987) (xy 133.087614 -29.920088)
			(xy 133.079744 -29.903674) (xy 133.066272 -29.874314) (xy 133.045166 -29.813258) (xy 133.030948 -29.750242)
			(xy 133.023793 -29.686038) (xy 133.023356 -29.653738) (xy 133.023356 -29.21) (xy 133.0241 -29.168661)
			(xy 133.03583 -29.086817) (xy 133.046724 -29.046932) (xy 133.048756 -29.033978) (xy 133.050094 -28.998664)
			(xy 133.060156 -28.928713) (xy 133.078493 -28.860462) (xy 133.091174 -28.827476) (xy 133.094739 -28.817122)
			(xy 133.093699 -28.795268) (xy 133.089142 -28.785312) (xy 133.079744 -28.766262) (xy 133.066272 -28.736902)
			(xy 133.045167 -28.675846) (xy 133.030951 -28.612829) (xy 133.023797 -28.548626) (xy 133.023356 -28.516326)
			(xy 133.023356 -28.073096) (xy 133.023356 -28.065476) (xy 133.023356 -28.057348) (xy 133.02361 -28.048712)
			(xy 133.02361 -28.048204) (xy 133.024372 -28.034742) (xy 133.024372 -28.032964) (xy 133.024626 -28.0289)
			(xy 133.026912 -28.006548) (xy 133.026912 -28.00604) (xy 133.027166 -28.004262) (xy 133.027674 -28.000198)
			(xy 133.027674 -27.999436) (xy 133.027928 -27.997658) (xy 133.028944 -27.990292) (xy 133.025134 -27.973274)
			(xy 133.024022 -27.969584) (xy 133.020834 -27.962568) (xy 133.018784 -27.959304) (xy 133.010656 -27.947112)
			(xy 133.00456 -27.94) (xy 132.998718 -27.934158) (xy 132.99059 -27.927554) (xy 132.989066 -27.926538)
			(xy 132.976112 -27.924252) (xy 132.94247 -27.917669) (xy 132.876877 -27.897749) (xy 132.814029 -27.87037)
			(xy 132.754773 -27.835902) (xy 132.699905 -27.794806) (xy 132.650162 -27.747636) (xy 132.606213 -27.695025)
			(xy 132.568648 -27.637682) (xy 132.537974 -27.576375) (xy 132.514602 -27.511931) (xy 132.498845 -27.445214)
			(xy 132.490917 -27.377122) (xy 132.490464 -27.342846) (xy 132.490906 -27.310554) (xy 132.49797 -27.246357)
			(xy 132.511998 -27.183314) (xy 132.53282 -27.122178) (xy 132.560189 -27.06368) (xy 132.593779 -27.008517)
			(xy 132.613146 -26.982674) (xy 132.613146 -26.98242) (xy 132.618226 -26.975816) (xy 132.62356 -26.960322)
			(xy 132.62356 -26.870152) (xy 132.623236 -26.861873) (xy 132.617918 -26.846192) (xy 132.613146 -26.839418)
			(xy 132.593798 -26.813562) (xy 132.560228 -26.758392) (xy 132.532866 -26.699893) (xy 132.51204 -26.638762)
			(xy 132.497997 -26.575727) (xy 132.490903 -26.511536) (xy 132.490464 -26.479246) (xy 132.49091 -26.446077)
			(xy 132.498333 -26.380155) (xy 132.51309 -26.315479) (xy 132.534997 -26.252862) (xy 132.563777 -26.193092)
			(xy 132.599069 -26.136921) (xy 132.640429 -26.085054) (xy 132.687337 -26.038145) (xy 132.739201 -25.996783)
			(xy 132.795371 -25.961489) (xy 132.85514 -25.932706) (xy 132.917756 -25.910797) (xy 132.982431 -25.896037)
			(xy 133.048353 -25.888611) (xy 133.081522 -25.888188) (xy 133.114683 -25.88867) (xy 133.180584 -25.896128)
			(xy 133.245237 -25.910915) (xy 133.307829 -25.932845) (xy 133.367573 -25.961642) (xy 133.42372 -25.996945)
			(xy 133.475562 -26.038309) (xy 133.499352 -26.061416) (xy 133.601206 -26.16327) (xy 133.608603 -26.170119)
			(xy 133.627202 -26.177856) (xy 133.637274 -26.178256) (xy 133.702806 -26.178256) (xy 133.735961 -26.17872)
			(xy 133.801855 -26.18614) (xy 133.866505 -26.200886) (xy 133.929098 -26.222774) (xy 133.98885 -26.251527)
			(xy 134.04501 -26.286786) (xy 134.096872 -26.328106) (xy 134.120636 -26.35123) (xy 134.130288 -26.360882)
			(xy 135.18972 -26.360882) (xy 135.193791 -26.30526) (xy 135.205917 -26.250823) (xy 135.22584 -26.198732)
			(xy 135.253136 -26.150097) (xy 135.287222 -26.105954) (xy 135.327371 -26.067245) (xy 135.372729 -26.034794)
			(xy 135.422329 -26.009293) (xy 135.475113 -25.991286) (xy 135.529956 -25.981156) (xy 135.58569 -25.979119)
			(xy 135.641127 -25.985219) (xy 135.695084 -25.999325) (xy 135.746413 -26.021137) (xy 135.794019 -26.050191)
			(xy 135.836887 -26.085866) (xy 135.874104 -26.127403) (xy 135.904877 -26.173916) (xy 135.928549 -26.224413)
			(xy 135.944617 -26.27782) (xy 135.950785 -26.319734) (xy 140.942058 -26.319734) (xy 140.946129 -26.264112)
			(xy 140.958255 -26.209675) (xy 140.978178 -26.157584) (xy 141.005474 -26.108949) (xy 141.03956 -26.064806)
			(xy 141.079709 -26.026097) (xy 141.125067 -25.993646) (xy 141.174667 -25.968145) (xy 141.227451 -25.950138)
			(xy 141.282294 -25.940008) (xy 141.338028 -25.937971) (xy 141.393465 -25.944071) (xy 141.447422 -25.958177)
			(xy 141.498751 -25.979989) (xy 141.546357 -26.009043) (xy 141.576022 -26.03373) (xy 147.368004 -26.03373)
			(xy 147.372075 -25.978108) (xy 147.384201 -25.923671) (xy 147.404124 -25.87158) (xy 147.43142 -25.822945)
			(xy 147.465506 -25.778802) (xy 147.505655 -25.740093) (xy 147.551013 -25.707642) (xy 147.600613 -25.682141)
			(xy 147.653397 -25.664134) (xy 147.70824 -25.654004) (xy 147.763974 -25.651967) (xy 147.819411 -25.658067)
			(xy 147.873368 -25.672173) (xy 147.924697 -25.693985) (xy 147.972303 -25.723039) (xy 148.015171 -25.758714)
			(xy 148.052388 -25.800251) (xy 148.083161 -25.846764) (xy 148.106833 -25.897261) (xy 148.122901 -25.950668)
			(xy 148.131021 -26.005844) (xy 148.13153 -26.03373) (xy 148.131021 -26.061616) (xy 148.122901 -26.116792)
			(xy 148.106833 -26.170199) (xy 148.083161 -26.220696) (xy 148.052927 -26.266394) (xy 150.62073 -26.266394)
			(xy 150.621216 -26.239143) (xy 150.628972 -26.185195) (xy 150.644327 -26.1329) (xy 150.666969 -26.083323)
			(xy 150.696435 -26.037473) (xy 150.732126 -25.996282) (xy 150.773317 -25.960591) (xy 150.819167 -25.931125)
			(xy 150.868744 -25.908483) (xy 150.921039 -25.893128) (xy 150.974987 -25.885372) (xy 151.029489 -25.885372)
			(xy 151.083437 -25.893128) (xy 151.135732 -25.908483) (xy 151.185309 -25.931125) (xy 151.231159 -25.960591)
			(xy 151.27235 -25.996282) (xy 151.308041 -26.037473) (xy 151.337507 -26.083323) (xy 151.360149 -26.1329)
			(xy 151.375504 -26.185195) (xy 151.38326 -26.239143) (xy 151.383746 -26.266394) (xy 151.383176 -26.295881)
			(xy 151.374082 -26.35415) (xy 151.356127 -26.410324) (xy 151.329737 -26.463064) (xy 151.295542 -26.511112)
			(xy 151.254358 -26.553324) (xy 151.231092 -26.571448) (xy 151.219936 -26.580307) (xy 151.20275 -26.603017)
			(xy 151.192502 -26.629589) (xy 151.189989 -26.657958) (xy 151.195405 -26.685918) (xy 151.208331 -26.711295)
			(xy 151.227761 -26.732118) (xy 151.239728 -26.73985) (xy 151.263471 -26.754745) (xy 151.306705 -26.790413)
			(xy 151.344255 -26.832023) (xy 151.375314 -26.878679) (xy 151.399212 -26.929376) (xy 151.415437 -26.983025)
			(xy 151.423637 -27.03847) (xy 151.424132 -27.066494) (xy 151.423646 -27.093745) (xy 151.41589 -27.147693)
			(xy 151.400535 -27.199988) (xy 151.377893 -27.249565) (xy 151.348427 -27.295415) (xy 151.312736 -27.336606)
			(xy 151.271545 -27.372297) (xy 151.225695 -27.401763) (xy 151.176118 -27.424405) (xy 151.123823 -27.43976)
			(xy 151.069875 -27.447516) (xy 151.015373 -27.447516) (xy 150.961425 -27.43976) (xy 150.90913 -27.424405)
			(xy 150.859553 -27.401763) (xy 150.813703 -27.372297) (xy 150.772512 -27.336606) (xy 150.736821 -27.295415)
			(xy 150.707355 -27.249565) (xy 150.684713 -27.199988) (xy 150.669358 -27.147693) (xy 150.661602 -27.093745)
			(xy 150.661116 -27.066494) (xy 150.661653 -27.037006) (xy 150.67075 -26.978734) (xy 150.688711 -26.922558)
			(xy 150.715107 -26.869818) (xy 150.749308 -26.82177) (xy 150.7905 -26.779562) (xy 150.81377 -26.76144)
			(xy 150.824826 -26.752469) (xy 150.842 -26.729783) (xy 150.852247 -26.703238) (xy 150.85477 -26.674896)
			(xy 150.849375 -26.646958) (xy 150.836478 -26.621594) (xy 150.817084 -26.600774) (xy 150.805134 -26.593038)
			(xy 150.7814 -26.578129) (xy 150.738163 -26.542466) (xy 150.70061 -26.500859) (xy 150.669549 -26.454206)
			(xy 150.645649 -26.40351) (xy 150.629424 -26.349862) (xy 150.621224 -26.294418) (xy 150.62073 -26.266394)
			(xy 148.052927 -26.266394) (xy 148.052388 -26.267209) (xy 148.015171 -26.308746) (xy 147.972303 -26.344421)
			(xy 147.924697 -26.373475) (xy 147.873368 -26.395287) (xy 147.819411 -26.409393) (xy 147.763974 -26.415493)
			(xy 147.70824 -26.413456) (xy 147.653397 -26.403326) (xy 147.600613 -26.385319) (xy 147.551013 -26.359818)
			(xy 147.505655 -26.327367) (xy 147.465506 -26.288658) (xy 147.43142 -26.244515) (xy 147.404124 -26.19588)
			(xy 147.384201 -26.143789) (xy 147.372075 -26.089352) (xy 147.368004 -26.03373) (xy 141.576022 -26.03373)
			(xy 141.589225 -26.044718) (xy 141.626442 -26.086255) (xy 141.657215 -26.132768) (xy 141.680887 -26.183265)
			(xy 141.696955 -26.236672) (xy 141.705075 -26.291848) (xy 141.705584 -26.319734) (xy 141.705075 -26.34762)
			(xy 141.696955 -26.402796) (xy 141.680887 -26.456203) (xy 141.657215 -26.5067) (xy 141.626442 -26.553213)
			(xy 141.589225 -26.59475) (xy 141.546357 -26.630425) (xy 141.498751 -26.659479) (xy 141.447422 -26.681291)
			(xy 141.393465 -26.695397) (xy 141.338028 -26.701497) (xy 141.282294 -26.69946) (xy 141.227451 -26.68933)
			(xy 141.174667 -26.671323) (xy 141.125067 -26.645822) (xy 141.079709 -26.613371) (xy 141.03956 -26.574662)
			(xy 141.005474 -26.530519) (xy 140.978178 -26.481884) (xy 140.958255 -26.429793) (xy 140.946129 -26.375356)
			(xy 140.942058 -26.319734) (xy 135.950785 -26.319734) (xy 135.952737 -26.332996) (xy 135.953246 -26.360882)
			(xy 135.952737 -26.388768) (xy 135.944617 -26.443944) (xy 135.928549 -26.497351) (xy 135.904877 -26.547848)
			(xy 135.874104 -26.594361) (xy 135.836887 -26.635898) (xy 135.794019 -26.671573) (xy 135.746413 -26.700627)
			(xy 135.695084 -26.722439) (xy 135.641127 -26.736545) (xy 135.58569 -26.742645) (xy 135.529956 -26.740608)
			(xy 135.475113 -26.730478) (xy 135.422329 -26.712471) (xy 135.372729 -26.68697) (xy 135.327371 -26.654519)
			(xy 135.287222 -26.61581) (xy 135.253136 -26.571667) (xy 135.22584 -26.523032) (xy 135.205917 -26.470941)
			(xy 135.193791 -26.416504) (xy 135.18972 -26.360882) (xy 134.130288 -26.360882) (xy 134.45363 -26.684224)
			(xy 134.476742 -26.708002) (xy 134.518078 -26.759854) (xy 134.553349 -26.816007) (xy 134.582113 -26.875757)
			(xy 134.604006 -26.938351) (xy 134.611509 -26.971244) (xy 136.95121 -26.971244) (xy 136.955281 -26.915622)
			(xy 136.967407 -26.861185) (xy 136.98733 -26.809094) (xy 137.014626 -26.760459) (xy 137.048712 -26.716316)
			(xy 137.088861 -26.677607) (xy 137.134219 -26.645156) (xy 137.183819 -26.619655) (xy 137.236603 -26.601648)
			(xy 137.291446 -26.591518) (xy 137.34718 -26.589481) (xy 137.402617 -26.595581) (xy 137.456574 -26.609687)
			(xy 137.507903 -26.631499) (xy 137.555509 -26.660553) (xy 137.598377 -26.696228) (xy 137.635594 -26.737765)
			(xy 137.666367 -26.784278) (xy 137.690039 -26.834775) (xy 137.706107 -26.888182) (xy 137.714227 -26.943358)
			(xy 137.714736 -26.971244) (xy 137.714227 -26.99913) (xy 137.706107 -27.054306) (xy 137.690039 -27.107713)
			(xy 137.666367 -27.15821) (xy 137.635594 -27.204723) (xy 137.598377 -27.24626) (xy 137.555509 -27.281935)
			(xy 137.507903 -27.310989) (xy 137.456574 -27.332801) (xy 137.402617 -27.346907) (xy 137.34718 -27.353007)
			(xy 137.291446 -27.35097) (xy 137.236603 -27.34084) (xy 137.183819 -27.322833) (xy 137.134219 -27.297332)
			(xy 137.088861 -27.264881) (xy 137.048712 -27.226172) (xy 137.014626 -27.182029) (xy 136.98733 -27.133394)
			(xy 136.967407 -27.081303) (xy 136.955281 -27.026866) (xy 136.95121 -26.971244) (xy 134.611509 -26.971244)
			(xy 134.618754 -27.003002) (xy 134.626172 -27.068898) (xy 134.626604 -27.102054) (xy 134.626604 -29.114242)
			(xy 134.94766 -29.114242) (xy 134.94766 -28.250642) (xy 134.94815 -28.220674) (xy 134.955973 -28.161252)
			(xy 134.971486 -28.103359) (xy 134.994422 -28.047986) (xy 135.024389 -27.99608) (xy 135.060876 -27.94853)
			(xy 135.103256 -27.90615) (xy 135.150806 -27.869663) (xy 135.202712 -27.839696) (xy 135.258085 -27.81676)
			(xy 135.315978 -27.801247) (xy 135.3754 -27.793424) (xy 135.435336 -27.793424) (xy 135.494758 -27.801247)
			(xy 135.552651 -27.81676) (xy 135.608024 -27.839696) (xy 135.65993 -27.869663) (xy 135.70748 -27.90615)
			(xy 135.74986 -27.94853) (xy 135.786347 -27.99608) (xy 135.816314 -28.047986) (xy 135.83925 -28.103359)
			(xy 135.854763 -28.161252) (xy 135.862586 -28.220674) (xy 135.863076 -28.250642) (xy 135.863076 -28.469082)
			(xy 139.852652 -28.469082) (xy 139.856723 -28.41346) (xy 139.868849 -28.359023) (xy 139.888772 -28.306932)
			(xy 139.916068 -28.258297) (xy 139.950154 -28.214154) (xy 139.990303 -28.175445) (xy 140.035661 -28.142994)
			(xy 140.085261 -28.117493) (xy 140.138045 -28.099486) (xy 140.192888 -28.089356) (xy 140.248622 -28.087319)
			(xy 140.304059 -28.093419) (xy 140.358016 -28.107525) (xy 140.409345 -28.129337) (xy 140.425401 -28.139136)
			(xy 144.498058 -28.139136) (xy 144.502129 -28.083514) (xy 144.514255 -28.029077) (xy 144.534178 -27.976986)
			(xy 144.561474 -27.928351) (xy 144.59556 -27.884208) (xy 144.635709 -27.845499) (xy 144.681067 -27.813048)
			(xy 144.730667 -27.787547) (xy 144.783451 -27.76954) (xy 144.838294 -27.75941) (xy 144.894028 -27.757373)
			(xy 144.949465 -27.763473) (xy 145.003422 -27.777579) (xy 145.054751 -27.799391) (xy 145.102357 -27.828445)
			(xy 145.145225 -27.86412) (xy 145.182442 -27.905657) (xy 145.213215 -27.95217) (xy 145.236887 -28.002667)
			(xy 145.252955 -28.056074) (xy 145.261075 -28.11125) (xy 145.261584 -28.139136) (xy 145.768058 -28.139136)
			(xy 145.772129 -28.083514) (xy 145.784255 -28.029077) (xy 145.804178 -27.976986) (xy 145.831474 -27.928351)
			(xy 145.86556 -27.884208) (xy 145.905709 -27.845499) (xy 145.951067 -27.813048) (xy 146.000667 -27.787547)
			(xy 146.053451 -27.76954) (xy 146.108294 -27.75941) (xy 146.164028 -27.757373) (xy 146.219465 -27.763473)
			(xy 146.273422 -27.777579) (xy 146.324751 -27.799391) (xy 146.372357 -27.828445) (xy 146.415225 -27.86412)
			(xy 146.452442 -27.905657) (xy 146.483215 -27.95217) (xy 146.506887 -28.002667) (xy 146.522955 -28.056074)
			(xy 146.531075 -28.11125) (xy 146.531584 -28.139136) (xy 146.531075 -28.167022) (xy 146.522955 -28.222198)
			(xy 146.506887 -28.275605) (xy 146.483215 -28.326102) (xy 146.452442 -28.372615) (xy 146.415225 -28.414152)
			(xy 146.372357 -28.449827) (xy 146.324751 -28.478881) (xy 146.273422 -28.500693) (xy 146.219465 -28.514799)
			(xy 146.164028 -28.520899) (xy 146.108294 -28.518862) (xy 146.053451 -28.508732) (xy 146.000667 -28.490725)
			(xy 145.951067 -28.465224) (xy 145.905709 -28.432773) (xy 145.86556 -28.394064) (xy 145.831474 -28.349921)
			(xy 145.804178 -28.301286) (xy 145.784255 -28.249195) (xy 145.772129 -28.194758) (xy 145.768058 -28.139136)
			(xy 145.261584 -28.139136) (xy 145.261075 -28.167022) (xy 145.252955 -28.222198) (xy 145.236887 -28.275605)
			(xy 145.213215 -28.326102) (xy 145.182442 -28.372615) (xy 145.145225 -28.414152) (xy 145.102357 -28.449827)
			(xy 145.054751 -28.478881) (xy 145.003422 -28.500693) (xy 144.949465 -28.514799) (xy 144.894028 -28.520899)
			(xy 144.838294 -28.518862) (xy 144.783451 -28.508732) (xy 144.730667 -28.490725) (xy 144.681067 -28.465224)
			(xy 144.635709 -28.432773) (xy 144.59556 -28.394064) (xy 144.561474 -28.349921) (xy 144.534178 -28.301286)
			(xy 144.514255 -28.249195) (xy 144.502129 -28.194758) (xy 144.498058 -28.139136) (xy 140.425401 -28.139136)
			(xy 140.456951 -28.158391) (xy 140.499819 -28.194066) (xy 140.537036 -28.235603) (xy 140.567809 -28.282116)
			(xy 140.591481 -28.332613) (xy 140.607549 -28.38602) (xy 140.615669 -28.441196) (xy 140.616178 -28.469082)
			(xy 140.615669 -28.496968) (xy 140.607549 -28.552144) (xy 140.591481 -28.605551) (xy 140.567809 -28.656048)
			(xy 140.537036 -28.702561) (xy 140.499819 -28.744098) (xy 140.456951 -28.779773) (xy 140.409345 -28.808827)
			(xy 140.358016 -28.830639) (xy 140.304059 -28.844745) (xy 140.248622 -28.850845) (xy 140.192888 -28.848808)
			(xy 140.138045 -28.838678) (xy 140.085261 -28.820671) (xy 140.035661 -28.79517) (xy 139.990303 -28.762719)
			(xy 139.950154 -28.72401) (xy 139.916068 -28.679867) (xy 139.888772 -28.631232) (xy 139.868849 -28.579141)
			(xy 139.856723 -28.524704) (xy 139.852652 -28.469082) (xy 135.863076 -28.469082) (xy 135.863076 -29.114242)
			(xy 135.862943 -29.12237) (xy 150.706836 -29.12237) (xy 150.706836 -28.25877) (xy 150.707326 -28.228786)
			(xy 150.715154 -28.16933) (xy 150.730675 -28.111405) (xy 150.753624 -28.056001) (xy 150.783608 -28.004067)
			(xy 150.820114 -27.956491) (xy 150.862519 -27.914086) (xy 150.910095 -27.87758) (xy 150.962029 -27.847596)
			(xy 151.017433 -27.824647) (xy 151.075358 -27.809126) (xy 151.134814 -27.801298) (xy 151.194782 -27.801298)
			(xy 151.254238 -27.809126) (xy 151.312163 -27.824647) (xy 151.367567 -27.847596) (xy 151.419501 -27.87758)
			(xy 151.467077 -27.914086) (xy 151.509482 -27.956491) (xy 151.545988 -28.004067) (xy 151.575972 -28.056001)
			(xy 151.598921 -28.111405) (xy 151.614442 -28.16933) (xy 151.62227 -28.228786) (xy 151.62276 -28.25877)
			(xy 151.62276 -29.12237) (xy 151.62227 -29.152354) (xy 151.614442 -29.21181) (xy 151.598921 -29.269735)
			(xy 151.575972 -29.325139) (xy 151.545988 -29.377073) (xy 151.509482 -29.424649) (xy 151.467077 -29.467054)
			(xy 151.419501 -29.50356) (xy 151.367567 -29.533544) (xy 151.312163 -29.556493) (xy 151.254238 -29.572014)
			(xy 151.194782 -29.579842) (xy 151.134814 -29.579842) (xy 151.075358 -29.572014) (xy 151.017433 -29.556493)
			(xy 150.962029 -29.533544) (xy 150.910095 -29.50356) (xy 150.862519 -29.467054) (xy 150.820114 -29.424649)
			(xy 150.783608 -29.377073) (xy 150.753624 -29.325139) (xy 150.730675 -29.269735) (xy 150.715154 -29.21181)
			(xy 150.707326 -29.152354) (xy 150.706836 -29.12237) (xy 135.862943 -29.12237) (xy 135.862586 -29.14421)
			(xy 135.854763 -29.203632) (xy 135.83925 -29.261525) (xy 135.816314 -29.316898) (xy 135.786347 -29.368804)
			(xy 135.74986 -29.416354) (xy 135.70748 -29.458734) (xy 135.65993 -29.495221) (xy 135.608024 -29.525188)
			(xy 135.552651 -29.548124) (xy 135.494758 -29.563637) (xy 135.435336 -29.57146) (xy 135.3754 -29.57146)
			(xy 135.315978 -29.563637) (xy 135.258085 -29.548124) (xy 135.202712 -29.525188) (xy 135.150806 -29.495221)
			(xy 135.103256 -29.458734) (xy 135.060876 -29.416354) (xy 135.024389 -29.368804) (xy 134.994422 -29.316898)
			(xy 134.971486 -29.261525) (xy 134.955973 -29.203632) (xy 134.94815 -29.14421) (xy 134.94766 -29.114242)
			(xy 134.626604 -29.114242) (xy 134.626604 -30.92069) (xy 137.589768 -30.92069) (xy 137.589768 -30.05709)
			(xy 137.590258 -30.027122) (xy 137.598081 -29.9677) (xy 137.613594 -29.909807) (xy 137.63653 -29.854434)
			(xy 137.666497 -29.802528) (xy 137.702984 -29.754978) (xy 137.745364 -29.712598) (xy 137.792914 -29.676111)
			(xy 137.84482 -29.646144) (xy 137.900193 -29.623208) (xy 137.958086 -29.607695) (xy 138.017508 -29.599872)
			(xy 138.077444 -29.599872) (xy 138.136866 -29.607695) (xy 138.194759 -29.623208) (xy 138.250132 -29.646144)
			(xy 138.302038 -29.676111) (xy 138.349588 -29.712598) (xy 138.391968 -29.754978) (xy 138.428455 -29.802528)
			(xy 138.458422 -29.854434) (xy 138.481358 -29.909807) (xy 138.496871 -29.9677) (xy 138.504694 -30.027122)
			(xy 138.505184 -30.05709) (xy 138.505184 -30.376876) (xy 142.989046 -30.376876) (xy 142.989602 -30.34796)
			(xy 142.998321 -30.29079) (xy 143.01557 -30.235591) (xy 143.040955 -30.183629) (xy 143.073892 -30.136094)
			(xy 143.113629 -30.094077) (xy 143.136112 -30.075886) (xy 143.144917 -30.068277) (xy 143.155101 -30.047378)
			(xy 143.15567 -30.035754) (xy 143.15567 -29.955998) (xy 143.155128 -29.944366) (xy 143.144942 -29.923456)
			(xy 143.136112 -29.915866) (xy 143.113615 -29.897691) (xy 143.07388 -29.855668) (xy 143.040942 -29.80813)
			(xy 143.015556 -29.756166) (xy 142.998303 -29.700965) (xy 142.989578 -29.643793) (xy 142.989046 -29.614876)
			(xy 142.989532 -29.587625) (xy 142.997288 -29.533677) (xy 143.012643 -29.481382) (xy 143.035285 -29.431805)
			(xy 143.064751 -29.385955) (xy 143.100442 -29.344764) (xy 143.141633 -29.309073) (xy 143.187483 -29.279607)
			(xy 143.23706 -29.256965) (xy 143.289355 -29.24161) (xy 143.343303 -29.233854) (xy 143.397805 -29.233854)
			(xy 143.451753 -29.24161) (xy 143.504048 -29.256965) (xy 143.553625 -29.279607) (xy 143.599475 -29.309073)
			(xy 143.640666 -29.344764) (xy 143.676357 -29.385955) (xy 143.705823 -29.431805) (xy 143.728465 -29.481382)
			(xy 143.74382 -29.533677) (xy 143.751576 -29.587625) (xy 143.752062 -29.614876) (xy 143.751541 -29.643793)
			(xy 143.742814 -29.700965) (xy 143.725558 -29.756164) (xy 143.700167 -29.808126) (xy 143.667223 -29.85566)
			(xy 143.627482 -29.897676) (xy 143.604996 -29.915866) (xy 143.596214 -29.923497) (xy 143.586017 -29.94438)
			(xy 143.585438 -29.955998) (xy 143.585438 -30.035754) (xy 143.585947 -30.04739) (xy 143.596156 -30.0683)
			(xy 143.604996 -30.075886) (xy 143.627472 -30.094086) (xy 143.667208 -30.136104) (xy 143.700148 -30.183637)
			(xy 143.725538 -30.235596) (xy 143.742795 -30.290792) (xy 143.751526 -30.347961) (xy 143.752062 -30.376876)
			(xy 146.029172 -30.376876) (xy 146.029718 -30.34796) (xy 146.038437 -30.290789) (xy 146.055688 -30.235589)
			(xy 146.081074 -30.183627) (xy 146.114015 -30.136092) (xy 146.153753 -30.094076) (xy 146.176238 -30.075886)
			(xy 146.185048 -30.068282) (xy 146.195228 -30.047379) (xy 146.195796 -30.035754) (xy 146.195796 -29.955998)
			(xy 146.195245 -29.944368) (xy 146.185065 -29.923458) (xy 146.176238 -29.915866) (xy 146.153746 -29.897685)
			(xy 146.11401 -29.855664) (xy 146.081071 -29.808127) (xy 146.055683 -29.756164) (xy 146.03843 -29.700964)
			(xy 146.029704 -29.643793) (xy 146.029172 -29.614876) (xy 146.029658 -29.587625) (xy 146.037414 -29.533677)
			(xy 146.052769 -29.481382) (xy 146.075411 -29.431805) (xy 146.104877 -29.385955) (xy 146.140568 -29.344764)
			(xy 146.181759 -29.309073) (xy 146.227609 -29.279607) (xy 146.277186 -29.256965) (xy 146.329481 -29.24161)
			(xy 146.383429 -29.233854) (xy 146.437931 -29.233854) (xy 146.491879 -29.24161) (xy 146.544174 -29.256965)
			(xy 146.593751 -29.279607) (xy 146.639601 -29.309073) (xy 146.680792 -29.344764) (xy 146.716483 -29.385955)
			(xy 146.745949 -29.431805) (xy 146.768591 -29.481382) (xy 146.783946 -29.533677) (xy 146.791702 -29.587625)
			(xy 146.792188 -29.614876) (xy 146.791657 -29.643792) (xy 146.782931 -29.700963) (xy 146.765676 -29.756162)
			(xy 146.740287 -29.808124) (xy 146.707345 -29.855658) (xy 146.667606 -29.897676) (xy 146.645122 -29.915866)
			(xy 146.636327 -29.923484) (xy 146.62614 -29.944377) (xy 146.625564 -29.955998) (xy 146.625564 -30.035754)
			(xy 146.626064 -30.047391) (xy 146.636278 -30.068302) (xy 146.645122 -30.075886) (xy 146.667603 -30.094079)
			(xy 146.707338 -30.136099) (xy 146.740276 -30.183634) (xy 146.765665 -30.235595) (xy 146.782922 -30.290791)
			(xy 146.791652 -30.34796) (xy 146.792188 -30.376876) (xy 146.791702 -30.404127) (xy 146.783946 -30.458075)
			(xy 146.768591 -30.51037) (xy 146.745949 -30.559947) (xy 146.716483 -30.605797) (xy 146.680792 -30.646988)
			(xy 146.639601 -30.682679) (xy 146.593751 -30.712145) (xy 146.544174 -30.734787) (xy 146.491879 -30.750142)
			(xy 146.437931 -30.757898) (xy 146.383429 -30.757898) (xy 146.329481 -30.750142) (xy 146.277186 -30.734787)
			(xy 146.227609 -30.712145) (xy 146.181759 -30.682679) (xy 146.140568 -30.646988) (xy 146.104877 -30.605797)
			(xy 146.075411 -30.559947) (xy 146.052769 -30.51037) (xy 146.037414 -30.458075) (xy 146.029658 -30.404127)
			(xy 146.029172 -30.376876) (xy 143.752062 -30.376876) (xy 143.751576 -30.404127) (xy 143.74382 -30.458075)
			(xy 143.728465 -30.51037) (xy 143.705823 -30.559947) (xy 143.676357 -30.605797) (xy 143.640666 -30.646988)
			(xy 143.599475 -30.682679) (xy 143.553625 -30.712145) (xy 143.504048 -30.734787) (xy 143.451753 -30.750142)
			(xy 143.397805 -30.757898) (xy 143.343303 -30.757898) (xy 143.289355 -30.750142) (xy 143.23706 -30.734787)
			(xy 143.187483 -30.712145) (xy 143.141633 -30.682679) (xy 143.100442 -30.646988) (xy 143.064751 -30.605797)
			(xy 143.035285 -30.559947) (xy 143.012643 -30.51037) (xy 142.997288 -30.458075) (xy 142.989532 -30.404127)
			(xy 142.989046 -30.376876) (xy 138.505184 -30.376876) (xy 138.505184 -30.92069) (xy 138.505155 -30.922468)
			(xy 148.852636 -30.922468) (xy 148.852636 -30.058868) (xy 148.853126 -30.028884) (xy 148.860954 -29.969428)
			(xy 148.876475 -29.911503) (xy 148.899424 -29.856099) (xy 148.929408 -29.804165) (xy 148.965914 -29.756589)
			(xy 149.008319 -29.714184) (xy 149.055895 -29.677678) (xy 149.107829 -29.647694) (xy 149.163233 -29.624745)
			(xy 149.221158 -29.609224) (xy 149.280614 -29.601396) (xy 149.340582 -29.601396) (xy 149.400038 -29.609224)
			(xy 149.457963 -29.624745) (xy 149.513367 -29.647694) (xy 149.565301 -29.677678) (xy 149.612877 -29.714184)
			(xy 149.655282 -29.756589) (xy 149.691788 -29.804165) (xy 149.721772 -29.856099) (xy 149.744721 -29.911503)
			(xy 149.760242 -29.969428) (xy 149.76807 -30.028884) (xy 149.76856 -30.058868) (xy 149.76856 -30.922468)
			(xy 149.76807 -30.952452) (xy 149.760242 -31.011908) (xy 149.744721 -31.069833) (xy 149.721772 -31.125237)
			(xy 149.691788 -31.177171) (xy 149.655282 -31.224747) (xy 149.612877 -31.267152) (xy 149.565301 -31.303658)
			(xy 149.513367 -31.333642) (xy 149.457963 -31.356591) (xy 149.400038 -31.372112) (xy 149.340582 -31.37994)
			(xy 149.280614 -31.37994) (xy 149.221158 -31.372112) (xy 149.163233 -31.356591) (xy 149.107829 -31.333642)
			(xy 149.055895 -31.303658) (xy 149.008319 -31.267152) (xy 148.965914 -31.224747) (xy 148.929408 -31.177171)
			(xy 148.899424 -31.125237) (xy 148.876475 -31.069833) (xy 148.860954 -31.011908) (xy 148.853126 -30.952452)
			(xy 148.852636 -30.922468) (xy 138.505155 -30.922468) (xy 138.504694 -30.950658) (xy 138.496871 -31.01008)
			(xy 138.481358 -31.067973) (xy 138.458422 -31.123346) (xy 138.428455 -31.175252) (xy 138.391968 -31.222802)
			(xy 138.349588 -31.265182) (xy 138.302038 -31.301669) (xy 138.250132 -31.331636) (xy 138.194759 -31.354572)
			(xy 138.136866 -31.370085) (xy 138.077444 -31.377908) (xy 138.017508 -31.377908) (xy 137.958086 -31.370085)
			(xy 137.900193 -31.354572) (xy 137.84482 -31.331636) (xy 137.792914 -31.301669) (xy 137.745364 -31.265182)
			(xy 137.702984 -31.222802) (xy 137.666497 -31.175252) (xy 137.63653 -31.123346) (xy 137.613594 -31.067973)
			(xy 137.598081 -31.01008) (xy 137.590258 -30.950658) (xy 137.589768 -30.92069) (xy 134.626604 -30.92069)
			(xy 134.626604 -32.714184) (xy 134.94766 -32.714184) (xy 134.94766 -31.850584) (xy 134.94815 -31.820616)
			(xy 134.955973 -31.761194) (xy 134.971486 -31.703301) (xy 134.994422 -31.647928) (xy 135.024389 -31.596022)
			(xy 135.060876 -31.548472) (xy 135.103256 -31.506092) (xy 135.150806 -31.469605) (xy 135.202712 -31.439638)
			(xy 135.258085 -31.416702) (xy 135.315978 -31.401189) (xy 135.3754 -31.393366) (xy 135.435336 -31.393366)
			(xy 135.494758 -31.401189) (xy 135.552651 -31.416702) (xy 135.608024 -31.439638) (xy 135.65993 -31.469605)
			(xy 135.70748 -31.506092) (xy 135.74986 -31.548472) (xy 135.764754 -31.567882) (xy 143.098772 -31.567882)
			(xy 143.102843 -31.51226) (xy 143.114969 -31.457823) (xy 143.134892 -31.405732) (xy 143.162188 -31.357097)
			(xy 143.196274 -31.312954) (xy 143.236423 -31.274245) (xy 143.281781 -31.241794) (xy 143.331381 -31.216293)
			(xy 143.384165 -31.198286) (xy 143.439008 -31.188156) (xy 143.494742 -31.186119) (xy 143.550179 -31.192219)
			(xy 143.604136 -31.206325) (xy 143.655465 -31.228137) (xy 143.703071 -31.257191) (xy 143.745939 -31.292866)
			(xy 143.783156 -31.334403) (xy 143.813929 -31.380916) (xy 143.837601 -31.431413) (xy 143.853669 -31.48482)
			(xy 143.861789 -31.539996) (xy 143.862298 -31.567882) (xy 143.861789 -31.595768) (xy 143.853669 -31.650944)
			(xy 143.837601 -31.704351) (xy 143.830609 -31.719266) (xy 144.385536 -31.719266) (xy 144.389607 -31.663644)
			(xy 144.401733 -31.609207) (xy 144.421656 -31.557116) (xy 144.448952 -31.508481) (xy 144.483038 -31.464338)
			(xy 144.523187 -31.425629) (xy 144.568545 -31.393178) (xy 144.618145 -31.367677) (xy 144.670929 -31.34967)
			(xy 144.725772 -31.33954) (xy 144.781506 -31.337503) (xy 144.836943 -31.343603) (xy 144.8909 -31.357709)
			(xy 144.942229 -31.379521) (xy 144.989835 -31.408575) (xy 145.032703 -31.44425) (xy 145.06992 -31.485787)
			(xy 145.100693 -31.5323) (xy 145.124365 -31.582797) (xy 145.140433 -31.636204) (xy 145.144583 -31.664402)
			(xy 145.661124 -31.664402) (xy 145.665195 -31.60878) (xy 145.677321 -31.554343) (xy 145.697244 -31.502252)
			(xy 145.72454 -31.453617) (xy 145.758626 -31.409474) (xy 145.798775 -31.370765) (xy 145.844133 -31.338314)
			(xy 145.893733 -31.312813) (xy 145.946517 -31.294806) (xy 146.00136 -31.284676) (xy 146.057094 -31.282639)
			(xy 146.112531 -31.288739) (xy 146.166488 -31.302845) (xy 146.217817 -31.324657) (xy 146.265423 -31.353711)
			(xy 146.308291 -31.389386) (xy 146.345508 -31.430923) (xy 146.376281 -31.477436) (xy 146.399953 -31.527933)
			(xy 146.416021 -31.58134) (xy 146.424141 -31.636516) (xy 146.42465 -31.664402) (xy 146.424141 -31.692288)
			(xy 146.416021 -31.747464) (xy 146.407081 -31.777178) (xy 146.926298 -31.777178) (xy 146.930369 -31.721556)
			(xy 146.942495 -31.667119) (xy 146.962418 -31.615028) (xy 146.989714 -31.566393) (xy 147.0238 -31.52225)
			(xy 147.063949 -31.483541) (xy 147.109307 -31.45109) (xy 147.158907 -31.425589) (xy 147.211691 -31.407582)
			(xy 147.266534 -31.397452) (xy 147.322268 -31.395415) (xy 147.377705 -31.401515) (xy 147.431662 -31.415621)
			(xy 147.482991 -31.437433) (xy 147.530597 -31.466487) (xy 147.573465 -31.502162) (xy 147.610682 -31.543699)
			(xy 147.641455 -31.590212) (xy 147.665127 -31.640709) (xy 147.681195 -31.694116) (xy 147.689315 -31.749292)
			(xy 147.689824 -31.777178) (xy 147.689315 -31.805064) (xy 147.681195 -31.86024) (xy 147.665127 -31.913647)
			(xy 147.641455 -31.964144) (xy 147.610682 -32.010657) (xy 147.573465 -32.052194) (xy 147.530597 -32.087869)
			(xy 147.482991 -32.116923) (xy 147.431662 -32.138735) (xy 147.377705 -32.152841) (xy 147.322268 -32.158941)
			(xy 147.266534 -32.156904) (xy 147.211691 -32.146774) (xy 147.158907 -32.128767) (xy 147.109307 -32.103266)
			(xy 147.063949 -32.070815) (xy 147.0238 -32.032106) (xy 146.989714 -31.987963) (xy 146.962418 -31.939328)
			(xy 146.942495 -31.887237) (xy 146.930369 -31.8328) (xy 146.926298 -31.777178) (xy 146.407081 -31.777178)
			(xy 146.399953 -31.800871) (xy 146.376281 -31.851368) (xy 146.345508 -31.897881) (xy 146.308291 -31.939418)
			(xy 146.265423 -31.975093) (xy 146.217817 -32.004147) (xy 146.166488 -32.025959) (xy 146.112531 -32.040065)
			(xy 146.057094 -32.046165) (xy 146.00136 -32.044128) (xy 145.946517 -32.033998) (xy 145.893733 -32.015991)
			(xy 145.844133 -31.99049) (xy 145.798775 -31.958039) (xy 145.758626 -31.91933) (xy 145.72454 -31.875187)
			(xy 145.697244 -31.826552) (xy 145.677321 -31.774461) (xy 145.665195 -31.720024) (xy 145.661124 -31.664402)
			(xy 145.144583 -31.664402) (xy 145.148553 -31.69138) (xy 145.149062 -31.719266) (xy 145.148553 -31.747152)
			(xy 145.140433 -31.802328) (xy 145.124365 -31.855735) (xy 145.100693 -31.906232) (xy 145.06992 -31.952745)
			(xy 145.032703 -31.994282) (xy 144.989835 -32.029957) (xy 144.942229 -32.059011) (xy 144.8909 -32.080823)
			(xy 144.836943 -32.094929) (xy 144.781506 -32.101029) (xy 144.725772 -32.098992) (xy 144.670929 -32.088862)
			(xy 144.618145 -32.070855) (xy 144.568545 -32.045354) (xy 144.523187 -32.012903) (xy 144.483038 -31.974194)
			(xy 144.448952 -31.930051) (xy 144.421656 -31.881416) (xy 144.401733 -31.829325) (xy 144.389607 -31.774888)
			(xy 144.385536 -31.719266) (xy 143.830609 -31.719266) (xy 143.813929 -31.754848) (xy 143.783156 -31.801361)
			(xy 143.745939 -31.842898) (xy 143.703071 -31.878573) (xy 143.655465 -31.907627) (xy 143.604136 -31.929439)
			(xy 143.550179 -31.943545) (xy 143.494742 -31.949645) (xy 143.439008 -31.947608) (xy 143.384165 -31.937478)
			(xy 143.331381 -31.919471) (xy 143.281781 -31.89397) (xy 143.236423 -31.861519) (xy 143.196274 -31.82281)
			(xy 143.162188 -31.778667) (xy 143.134892 -31.730032) (xy 143.114969 -31.677941) (xy 143.102843 -31.623504)
			(xy 143.098772 -31.567882) (xy 135.764754 -31.567882) (xy 135.786347 -31.596022) (xy 135.816314 -31.647928)
			(xy 135.83925 -31.703301) (xy 135.854763 -31.761194) (xy 135.862586 -31.820616) (xy 135.863076 -31.850584)
			(xy 135.863076 -32.714184) (xy 135.862943 -32.722312) (xy 150.706836 -32.722312) (xy 150.706836 -31.858712)
			(xy 150.707326 -31.828728) (xy 150.715154 -31.769272) (xy 150.730675 -31.711347) (xy 150.753624 -31.655943)
			(xy 150.783608 -31.604009) (xy 150.820114 -31.556433) (xy 150.862519 -31.514028) (xy 150.910095 -31.477522)
			(xy 150.962029 -31.447538) (xy 151.017433 -31.424589) (xy 151.075358 -31.409068) (xy 151.134814 -31.40124)
			(xy 151.194782 -31.40124) (xy 151.254238 -31.409068) (xy 151.312163 -31.424589) (xy 151.367567 -31.447538)
			(xy 151.419501 -31.477522) (xy 151.467077 -31.514028) (xy 151.509482 -31.556433) (xy 151.545988 -31.604009)
			(xy 151.575972 -31.655943) (xy 151.598921 -31.711347) (xy 151.614442 -31.769272) (xy 151.62227 -31.828728)
			(xy 151.62276 -31.858712) (xy 151.62276 -32.722312) (xy 151.62227 -32.752296) (xy 151.614442 -32.811752)
			(xy 151.598921 -32.869677) (xy 151.575972 -32.925081) (xy 151.545988 -32.977015) (xy 151.509482 -33.024591)
			(xy 151.467077 -33.066996) (xy 151.419501 -33.103502) (xy 151.367567 -33.133486) (xy 151.312163 -33.156435)
			(xy 151.254238 -33.171956) (xy 151.194782 -33.179784) (xy 151.134814 -33.179784) (xy 151.075358 -33.171956)
			(xy 151.017433 -33.156435) (xy 150.962029 -33.133486) (xy 150.910095 -33.103502) (xy 150.862519 -33.066996)
			(xy 150.820114 -33.024591) (xy 150.783608 -32.977015) (xy 150.753624 -32.925081) (xy 150.730675 -32.869677)
			(xy 150.715154 -32.811752) (xy 150.707326 -32.752296) (xy 150.706836 -32.722312) (xy 135.862943 -32.722312)
			(xy 135.862586 -32.744152) (xy 135.854763 -32.803574) (xy 135.83925 -32.861467) (xy 135.816314 -32.91684)
			(xy 135.786347 -32.968746) (xy 135.74986 -33.016296) (xy 135.70748 -33.058676) (xy 135.65993 -33.095163)
			(xy 135.608024 -33.12513) (xy 135.552651 -33.148066) (xy 135.494758 -33.163579) (xy 135.435336 -33.171402)
			(xy 135.3754 -33.171402) (xy 135.315978 -33.163579) (xy 135.258085 -33.148066) (xy 135.202712 -33.12513)
			(xy 135.150806 -33.095163) (xy 135.103256 -33.058676) (xy 135.060876 -33.016296) (xy 135.024389 -32.968746)
			(xy 134.994422 -32.91684) (xy 134.971486 -32.861467) (xy 134.955973 -32.803574) (xy 134.94815 -32.744152)
			(xy 134.94766 -32.714184) (xy 134.626604 -32.714184) (xy 134.626604 -34.520886) (xy 137.589768 -34.520886)
			(xy 137.589768 -33.657286) (xy 137.590258 -33.627318) (xy 137.598081 -33.567896) (xy 137.613594 -33.510003)
			(xy 137.63653 -33.45463) (xy 137.666497 -33.402724) (xy 137.702984 -33.355174) (xy 137.745364 -33.312794)
			(xy 137.792914 -33.276307) (xy 137.84482 -33.24634) (xy 137.900193 -33.223404) (xy 137.958086 -33.207891)
			(xy 138.017508 -33.200068) (xy 138.077444 -33.200068) (xy 138.136866 -33.207891) (xy 138.194759 -33.223404)
			(xy 138.250132 -33.24634) (xy 138.302038 -33.276307) (xy 138.349588 -33.312794) (xy 138.391968 -33.355174)
			(xy 138.428455 -33.402724) (xy 138.458422 -33.45463) (xy 138.481358 -33.510003) (xy 138.496871 -33.567896)
			(xy 138.504694 -33.627318) (xy 138.505184 -33.657286) (xy 138.505184 -34.520886) (xy 138.505159 -34.52241)
			(xy 148.852636 -34.52241) (xy 148.852636 -33.65881) (xy 148.853126 -33.628826) (xy 148.860954 -33.56937)
			(xy 148.876475 -33.511445) (xy 148.899424 -33.456041) (xy 148.929408 -33.404107) (xy 148.965914 -33.356531)
			(xy 149.008319 -33.314126) (xy 149.055895 -33.27762) (xy 149.107829 -33.247636) (xy 149.163233 -33.224687)
			(xy 149.221158 -33.209166) (xy 149.280614 -33.201338) (xy 149.340582 -33.201338) (xy 149.400038 -33.209166)
			(xy 149.457963 -33.224687) (xy 149.513367 -33.247636) (xy 149.565301 -33.27762) (xy 149.612877 -33.314126)
			(xy 149.655282 -33.356531) (xy 149.691788 -33.404107) (xy 149.721772 -33.456041) (xy 149.744721 -33.511445)
			(xy 149.760242 -33.56937) (xy 149.76807 -33.628826) (xy 149.76856 -33.65881) (xy 149.76856 -34.52241)
			(xy 149.76807 -34.552394) (xy 149.760242 -34.61185) (xy 149.744721 -34.669775) (xy 149.721772 -34.725179)
			(xy 149.691788 -34.777113) (xy 149.655282 -34.824689) (xy 149.612877 -34.867094) (xy 149.565301 -34.9036)
			(xy 149.513367 -34.933584) (xy 149.457963 -34.956533) (xy 149.400038 -34.972054) (xy 149.340582 -34.979882)
			(xy 149.280614 -34.979882) (xy 149.221158 -34.972054) (xy 149.163233 -34.956533) (xy 149.107829 -34.933584)
			(xy 149.055895 -34.9036) (xy 149.008319 -34.867094) (xy 148.965914 -34.824689) (xy 148.929408 -34.777113)
			(xy 148.899424 -34.725179) (xy 148.876475 -34.669775) (xy 148.860954 -34.61185) (xy 148.853126 -34.552394)
			(xy 148.852636 -34.52241) (xy 138.505159 -34.52241) (xy 138.504694 -34.550854) (xy 138.496871 -34.610276)
			(xy 138.481358 -34.668169) (xy 138.458422 -34.723542) (xy 138.428455 -34.775448) (xy 138.391968 -34.822998)
			(xy 138.349588 -34.865378) (xy 138.302038 -34.901865) (xy 138.250132 -34.931832) (xy 138.194759 -34.954768)
			(xy 138.136866 -34.970281) (xy 138.077444 -34.978104) (xy 138.017508 -34.978104) (xy 137.958086 -34.970281)
			(xy 137.900193 -34.954768) (xy 137.84482 -34.931832) (xy 137.792914 -34.901865) (xy 137.745364 -34.865378)
			(xy 137.702984 -34.822998) (xy 137.666497 -34.775448) (xy 137.63653 -34.723542) (xy 137.613594 -34.668169)
			(xy 137.598081 -34.610276) (xy 137.590258 -34.550854) (xy 137.589768 -34.520886) (xy 134.626604 -34.520886)
			(xy 134.626604 -35.264852) (xy 146.0025 -35.264852) (xy 146.006571 -35.20923) (xy 146.018697 -35.154793)
			(xy 146.03862 -35.102702) (xy 146.065916 -35.054067) (xy 146.100002 -35.009924) (xy 146.140151 -34.971215)
			(xy 146.185509 -34.938764) (xy 146.235109 -34.913263) (xy 146.287893 -34.895256) (xy 146.342736 -34.885126)
			(xy 146.39847 -34.883089) (xy 146.453907 -34.889189) (xy 146.507864 -34.903295) (xy 146.559193 -34.925107)
			(xy 146.606799 -34.954161) (xy 146.649667 -34.989836) (xy 146.686884 -35.031373) (xy 146.717657 -35.077886)
			(xy 146.741329 -35.128383) (xy 146.757397 -35.18179) (xy 146.765517 -35.236966) (xy 146.766026 -35.264852)
			(xy 146.765517 -35.292738) (xy 146.757397 -35.347914) (xy 146.741329 -35.401321) (xy 146.717657 -35.451818)
			(xy 146.686884 -35.498331) (xy 146.649667 -35.539868) (xy 146.606799 -35.575543) (xy 146.559193 -35.604597)
			(xy 146.507864 -35.626409) (xy 146.453907 -35.640515) (xy 146.39847 -35.646615) (xy 146.342736 -35.644578)
			(xy 146.287893 -35.634448) (xy 146.235109 -35.616441) (xy 146.185509 -35.59094) (xy 146.140151 -35.558489)
			(xy 146.100002 -35.51978) (xy 146.065916 -35.475637) (xy 146.03862 -35.427002) (xy 146.018697 -35.374911)
			(xy 146.006571 -35.320474) (xy 146.0025 -35.264852) (xy 134.626604 -35.264852) (xy 134.626604 -35.281362)
			(xy 134.626112 -35.315408) (xy 134.618255 -35.383045) (xy 134.602663 -35.449329) (xy 134.591552 -35.481514)
			(xy 134.588504 -35.489896) (xy 134.588504 -35.517328) (xy 134.588055 -35.549992) (xy 134.580721 -35.614906)
			(xy 134.566162 -35.678591) (xy 134.544559 -35.740243) (xy 134.516184 -35.799087) (xy 134.481396 -35.854381)
			(xy 134.463543 -35.876738) (xy 134.817356 -35.876738) (xy 134.821427 -35.821116) (xy 134.833553 -35.766679)
			(xy 134.853476 -35.714588) (xy 134.880772 -35.665953) (xy 134.914858 -35.62181) (xy 134.955007 -35.583101)
			(xy 135.000365 -35.55065) (xy 135.049965 -35.525149) (xy 135.102749 -35.507142) (xy 135.157592 -35.497012)
			(xy 135.213326 -35.494975) (xy 135.268763 -35.501075) (xy 135.32272 -35.515181) (xy 135.374049 -35.536993)
			(xy 135.421655 -35.566047) (xy 135.464523 -35.601722) (xy 135.50174 -35.643259) (xy 135.532513 -35.689772)
			(xy 135.556185 -35.740269) (xy 135.572253 -35.793676) (xy 135.580373 -35.848852) (xy 135.580882 -35.876738)
			(xy 138.888976 -35.876738) (xy 138.893047 -35.821116) (xy 138.905173 -35.766679) (xy 138.925096 -35.714588)
			(xy 138.952392 -35.665953) (xy 138.986478 -35.62181) (xy 139.026627 -35.583101) (xy 139.071985 -35.55065)
			(xy 139.121585 -35.525149) (xy 139.174369 -35.507142) (xy 139.229212 -35.497012) (xy 139.284946 -35.494975)
			(xy 139.340383 -35.501075) (xy 139.39434 -35.515181) (xy 139.445669 -35.536993) (xy 139.493275 -35.566047)
			(xy 139.536143 -35.601722) (xy 139.57336 -35.643259) (xy 139.604133 -35.689772) (xy 139.627805 -35.740269)
			(xy 139.643873 -35.793676) (xy 139.651993 -35.848852) (xy 139.652502 -35.876738) (xy 139.651993 -35.904624)
			(xy 139.643873 -35.9598) (xy 139.627805 -36.013207) (xy 139.604133 -36.063704) (xy 139.57336 -36.110217)
			(xy 139.536143 -36.151754) (xy 139.493275 -36.187429) (xy 139.445669 -36.216483) (xy 139.39434 -36.238295)
			(xy 139.340383 -36.252401) (xy 139.284946 -36.258501) (xy 139.229212 -36.256464) (xy 139.174369 -36.246334)
			(xy 139.121585 -36.228327) (xy 139.071985 -36.202826) (xy 139.026627 -36.170375) (xy 138.986478 -36.131666)
			(xy 138.952392 -36.087523) (xy 138.925096 -36.038888) (xy 138.905173 -35.986797) (xy 138.893047 -35.93236)
			(xy 138.888976 -35.876738) (xy 135.580882 -35.876738) (xy 135.580373 -35.904624) (xy 135.572253 -35.9598)
			(xy 135.556185 -36.013207) (xy 135.532513 -36.063704) (xy 135.50174 -36.110217) (xy 135.464523 -36.151754)
			(xy 135.421655 -36.187429) (xy 135.374049 -36.216483) (xy 135.32272 -36.238295) (xy 135.268763 -36.252401)
			(xy 135.213326 -36.258501) (xy 135.157592 -36.256464) (xy 135.102749 -36.246334) (xy 135.049965 -36.228327)
			(xy 135.000365 -36.202826) (xy 134.955007 -36.170375) (xy 134.914858 -36.131666) (xy 134.880772 -36.087523)
			(xy 134.853476 -36.038888) (xy 134.833553 -35.986797) (xy 134.821427 -35.93236) (xy 134.817356 -35.876738)
			(xy 134.463543 -35.876738) (xy 134.440632 -35.90543) (xy 134.417816 -35.928808) (xy 133.836664 -36.50996)
			(xy 136.713974 -36.50996) (xy 136.718045 -36.454338) (xy 136.730171 -36.399901) (xy 136.750094 -36.34781)
			(xy 136.77739 -36.299175) (xy 136.811476 -36.255032) (xy 136.851625 -36.216323) (xy 136.896983 -36.183872)
			(xy 136.946583 -36.158371) (xy 136.999367 -36.140364) (xy 137.05421 -36.130234) (xy 137.109944 -36.128197)
			(xy 137.165381 -36.134297) (xy 137.219338 -36.148403) (xy 137.270667 -36.170215) (xy 137.318273 -36.199269)
			(xy 137.361141 -36.234944) (xy 137.398358 -36.276481) (xy 137.429131 -36.322994) (xy 137.452803 -36.373491)
			(xy 137.468871 -36.426898) (xy 137.472796 -36.453572) (xy 140.028674 -36.453572) (xy 140.032745 -36.39795)
			(xy 140.044871 -36.343513) (xy 140.064794 -36.291422) (xy 140.09209 -36.242787) (xy 140.126176 -36.198644)
			(xy 140.166325 -36.159935) (xy 140.211683 -36.127484) (xy 140.261283 -36.101983) (xy 140.314067 -36.083976)
			(xy 140.36891 -36.073846) (xy 140.424644 -36.071809) (xy 140.480081 -36.077909) (xy 140.534038 -36.092015)
			(xy 140.585367 -36.113827) (xy 140.632973 -36.142881) (xy 140.675841 -36.178556) (xy 140.713058 -36.220093)
			(xy 140.743831 -36.266606) (xy 140.753367 -36.286948) (xy 147.30044 -36.286948) (xy 147.304511 -36.231326)
			(xy 147.316637 -36.176889) (xy 147.33656 -36.124798) (xy 147.363856 -36.076163) (xy 147.397942 -36.03202)
			(xy 147.438091 -35.993311) (xy 147.483449 -35.96086) (xy 147.533049 -35.935359) (xy 147.585833 -35.917352)
			(xy 147.640676 -35.907222) (xy 147.69641 -35.905185) (xy 147.751847 -35.911285) (xy 147.805804 -35.925391)
			(xy 147.857133 -35.947203) (xy 147.904739 -35.976257) (xy 147.947607 -36.011932) (xy 147.984824 -36.053469)
			(xy 148.015597 -36.099982) (xy 148.039269 -36.150479) (xy 148.055337 -36.203886) (xy 148.063457 -36.259062)
			(xy 148.063966 -36.286948) (xy 148.063457 -36.314834) (xy 148.055337 -36.37001) (xy 148.039269 -36.423417)
			(xy 148.015597 -36.473914) (xy 147.988052 -36.515548) (xy 149.114254 -36.515548) (xy 149.118325 -36.459926)
			(xy 149.130451 -36.405489) (xy 149.150374 -36.353398) (xy 149.17767 -36.304763) (xy 149.211756 -36.26062)
			(xy 149.251905 -36.221911) (xy 149.297263 -36.18946) (xy 149.346863 -36.163959) (xy 149.399647 -36.145952)
			(xy 149.45449 -36.135822) (xy 149.510224 -36.133785) (xy 149.565661 -36.139885) (xy 149.619618 -36.153991)
			(xy 149.670947 -36.175803) (xy 149.718553 -36.204857) (xy 149.761421 -36.240532) (xy 149.798638 -36.282069)
			(xy 149.829411 -36.328582) (xy 149.853083 -36.379079) (xy 149.869151 -36.432486) (xy 149.877271 -36.487662)
			(xy 149.87778 -36.515548) (xy 149.877271 -36.543434) (xy 149.869151 -36.59861) (xy 149.868694 -36.60013)
			(xy 154.098251 -36.60013) (xy 154.102256 -36.512222) (xy 154.114239 -36.425042) (xy 154.134099 -36.339313)
			(xy 154.161674 -36.255745) (xy 154.196733 -36.175031) (xy 154.238986 -36.097839) (xy 154.288084 -36.02481)
			(xy 154.34362 -35.956548) (xy 154.405132 -35.893618) (xy 154.472113 -35.836544) (xy 154.544006 -35.785796)
			(xy 154.620215 -35.741796) (xy 154.70011 -35.704909) (xy 154.783029 -35.67544) (xy 154.868284 -35.653633)
			(xy 154.955168 -35.639669) (xy 155.042962 -35.633663) (xy 155.130939 -35.635667) (xy 155.218369 -35.645662)
			(xy 155.304528 -35.663566) (xy 155.388702 -35.68923) (xy 155.470193 -35.722443) (xy 155.548327 -35.762929)
			(xy 155.622455 -35.810351) (xy 155.691963 -35.864318) (xy 155.756277 -35.924383) (xy 155.814861 -35.990047)
			(xy 155.867232 -36.060766) (xy 155.912955 -36.135954) (xy 155.951652 -36.214989) (xy 155.983001 -36.297215)
			(xy 156.006743 -36.381951) (xy 156.022681 -36.468495) (xy 156.030683 -36.55613) (xy 156.031184 -36.60013)
			(xy 156.030683 -36.64413) (xy 156.022681 -36.731765) (xy 156.006743 -36.818309) (xy 155.983001 -36.903045)
			(xy 155.951652 -36.985271) (xy 155.912955 -37.064306) (xy 155.867232 -37.139494) (xy 155.814861 -37.210213)
			(xy 155.756277 -37.275877) (xy 155.691963 -37.335942) (xy 155.622455 -37.389909) (xy 155.548327 -37.437331)
			(xy 155.470193 -37.477817) (xy 155.388702 -37.51103) (xy 155.304528 -37.536694) (xy 155.218369 -37.554598)
			(xy 155.130939 -37.564593) (xy 155.042962 -37.566597) (xy 154.955168 -37.560591) (xy 154.868284 -37.546627)
			(xy 154.783029 -37.52482) (xy 154.70011 -37.495351) (xy 154.620215 -37.458464) (xy 154.544006 -37.414464)
			(xy 154.472113 -37.363716) (xy 154.405132 -37.306642) (xy 154.34362 -37.243712) (xy 154.288084 -37.17545)
			(xy 154.238986 -37.102421) (xy 154.196733 -37.025229) (xy 154.161674 -36.944515) (xy 154.134099 -36.860947)
			(xy 154.114239 -36.775218) (xy 154.102256 -36.688038) (xy 154.098251 -36.60013) (xy 149.868694 -36.60013)
			(xy 149.853083 -36.652017) (xy 149.829411 -36.702514) (xy 149.798638 -36.749027) (xy 149.761421 -36.790564)
			(xy 149.718553 -36.826239) (xy 149.670947 -36.855293) (xy 149.619618 -36.877105) (xy 149.565661 -36.891211)
			(xy 149.510224 -36.897311) (xy 149.45449 -36.895274) (xy 149.399647 -36.885144) (xy 149.346863 -36.867137)
			(xy 149.297263 -36.841636) (xy 149.251905 -36.809185) (xy 149.211756 -36.770476) (xy 149.17767 -36.726333)
			(xy 149.150374 -36.677698) (xy 149.130451 -36.625607) (xy 149.118325 -36.57117) (xy 149.114254 -36.515548)
			(xy 147.988052 -36.515548) (xy 147.984824 -36.520427) (xy 147.947607 -36.561964) (xy 147.904739 -36.597639)
			(xy 147.857133 -36.626693) (xy 147.805804 -36.648505) (xy 147.751847 -36.662611) (xy 147.69641 -36.668711)
			(xy 147.640676 -36.666674) (xy 147.585833 -36.656544) (xy 147.533049 -36.638537) (xy 147.483449 -36.613036)
			(xy 147.438091 -36.580585) (xy 147.397942 -36.541876) (xy 147.363856 -36.497733) (xy 147.33656 -36.449098)
			(xy 147.316637 -36.397007) (xy 147.304511 -36.34257) (xy 147.30044 -36.286948) (xy 140.753367 -36.286948)
			(xy 140.767503 -36.317103) (xy 140.783571 -36.37051) (xy 140.791691 -36.425686) (xy 140.7922 -36.453572)
			(xy 140.791691 -36.481458) (xy 140.783571 -36.536634) (xy 140.767503 -36.590041) (xy 140.743831 -36.640538)
			(xy 140.713058 -36.687051) (xy 140.675841 -36.728588) (xy 140.632973 -36.764263) (xy 140.585367 -36.793317)
			(xy 140.534038 -36.815129) (xy 140.480081 -36.829235) (xy 140.424644 -36.835335) (xy 140.36891 -36.833298)
			(xy 140.314067 -36.823168) (xy 140.261283 -36.805161) (xy 140.211683 -36.77966) (xy 140.166325 -36.747209)
			(xy 140.126176 -36.7085) (xy 140.09209 -36.664357) (xy 140.064794 -36.615722) (xy 140.044871 -36.563631)
			(xy 140.032745 -36.509194) (xy 140.028674 -36.453572) (xy 137.472796 -36.453572) (xy 137.476991 -36.482074)
			(xy 137.4775 -36.50996) (xy 137.476991 -36.537846) (xy 137.468871 -36.593022) (xy 137.452803 -36.646429)
			(xy 137.429131 -36.696926) (xy 137.398358 -36.743439) (xy 137.361141 -36.784976) (xy 137.318273 -36.820651)
			(xy 137.270667 -36.849705) (xy 137.219338 -36.871517) (xy 137.165381 -36.885623) (xy 137.109944 -36.891723)
			(xy 137.05421 -36.889686) (xy 136.999367 -36.879556) (xy 136.946583 -36.861549) (xy 136.896983 -36.836048)
			(xy 136.851625 -36.803597) (xy 136.811476 -36.764888) (xy 136.77739 -36.720745) (xy 136.750094 -36.67211)
			(xy 136.730171 -36.620019) (xy 136.718045 -36.565582) (xy 136.713974 -36.50996) (xy 133.836664 -36.50996)
			(xy 133.674612 -36.672012) (xy 133.366002 -36.980368) (xy 133.362995 -36.983454) (xy 133.358004 -36.990475)
			(xy 133.356096 -36.994338) (xy 133.356096 -37.47516) (xy 133.859268 -37.47516) (xy 133.863339 -37.419538)
			(xy 133.875465 -37.365101) (xy 133.895388 -37.31301) (xy 133.922684 -37.264375) (xy 133.95677 -37.220232)
			(xy 133.996919 -37.181523) (xy 134.042277 -37.149072) (xy 134.091877 -37.123571) (xy 134.144661 -37.105564)
			(xy 134.199504 -37.095434) (xy 134.255238 -37.093397) (xy 134.310675 -37.099497) (xy 134.364632 -37.113603)
			(xy 134.415961 -37.135415) (xy 134.463567 -37.164469) (xy 134.506435 -37.200144) (xy 134.543652 -37.241681)
			(xy 134.574425 -37.288194) (xy 134.598097 -37.338691) (xy 134.614165 -37.392098) (xy 134.622285 -37.447274)
			(xy 134.622794 -37.47516) (xy 134.622285 -37.503046) (xy 134.614165 -37.558222) (xy 134.598097 -37.611629)
			(xy 134.574425 -37.662126) (xy 134.574272 -37.662358) (xy 136.048494 -37.662358) (xy 136.052565 -37.606736)
			(xy 136.064691 -37.552299) (xy 136.084614 -37.500208) (xy 136.11191 -37.451573) (xy 136.145996 -37.40743)
			(xy 136.186145 -37.368721) (xy 136.231503 -37.33627) (xy 136.281103 -37.310769) (xy 136.333887 -37.292762)
			(xy 136.38873 -37.282632) (xy 136.444464 -37.280595) (xy 136.499901 -37.286695) (xy 136.553858 -37.300801)
			(xy 136.605187 -37.322613) (xy 136.652793 -37.351667) (xy 136.695661 -37.387342) (xy 136.732878 -37.428879)
			(xy 136.763651 -37.475392) (xy 136.787323 -37.525889) (xy 136.803391 -37.579296) (xy 136.811511 -37.634472)
			(xy 136.81202 -37.662358) (xy 136.811511 -37.690244) (xy 136.803391 -37.74542) (xy 136.794757 -37.774118)
			(xy 147.564854 -37.774118) (xy 147.568925 -37.718496) (xy 147.581051 -37.664059) (xy 147.600974 -37.611968)
			(xy 147.62827 -37.563333) (xy 147.662356 -37.51919) (xy 147.702505 -37.480481) (xy 147.747863 -37.44803)
			(xy 147.797463 -37.422529) (xy 147.850247 -37.404522) (xy 147.90509 -37.394392) (xy 147.960824 -37.392355)
			(xy 148.016261 -37.398455) (xy 148.070218 -37.412561) (xy 148.121547 -37.434373) (xy 148.169153 -37.463427)
			(xy 148.212021 -37.499102) (xy 148.249238 -37.540639) (xy 148.280011 -37.587152) (xy 148.303683 -37.637649)
			(xy 148.319751 -37.691056) (xy 148.327871 -37.746232) (xy 148.32838 -37.774118) (xy 148.327871 -37.802004)
			(xy 148.319751 -37.85718) (xy 148.303683 -37.910587) (xy 148.280011 -37.961084) (xy 148.249238 -38.007597)
			(xy 148.212021 -38.049134) (xy 148.169153 -38.084809) (xy 148.121547 -38.113863) (xy 148.070218 -38.135675)
			(xy 148.016261 -38.149781) (xy 147.960824 -38.155881) (xy 147.90509 -38.153844) (xy 147.850247 -38.143714)
			(xy 147.797463 -38.125707) (xy 147.747863 -38.100206) (xy 147.702505 -38.067755) (xy 147.662356 -38.029046)
			(xy 147.62827 -37.984903) (xy 147.600974 -37.936268) (xy 147.581051 -37.884177) (xy 147.568925 -37.82974)
			(xy 147.564854 -37.774118) (xy 136.794757 -37.774118) (xy 136.787323 -37.798827) (xy 136.763651 -37.849324)
			(xy 136.732878 -37.895837) (xy 136.695661 -37.937374) (xy 136.652793 -37.973049) (xy 136.605187 -38.002103)
			(xy 136.553858 -38.023915) (xy 136.499901 -38.038021) (xy 136.444464 -38.044121) (xy 136.38873 -38.042084)
			(xy 136.333887 -38.031954) (xy 136.281103 -38.013947) (xy 136.231503 -37.988446) (xy 136.186145 -37.955995)
			(xy 136.145996 -37.917286) (xy 136.11191 -37.873143) (xy 136.084614 -37.824508) (xy 136.064691 -37.772417)
			(xy 136.052565 -37.71798) (xy 136.048494 -37.662358) (xy 134.574272 -37.662358) (xy 134.543652 -37.708639)
			(xy 134.506435 -37.750176) (xy 134.463567 -37.785851) (xy 134.415961 -37.814905) (xy 134.364632 -37.836717)
			(xy 134.310675 -37.850823) (xy 134.255238 -37.856923) (xy 134.199504 -37.854886) (xy 134.144661 -37.844756)
			(xy 134.091877 -37.826749) (xy 134.042277 -37.801248) (xy 133.996919 -37.768797) (xy 133.95677 -37.730088)
			(xy 133.922684 -37.685945) (xy 133.895388 -37.63731) (xy 133.875465 -37.585219) (xy 133.863339 -37.530782)
			(xy 133.859268 -37.47516) (xy 133.356096 -37.47516) (xy 133.356096 -38.659816) (xy 133.355482 -38.697589)
			(xy 133.351311 -38.729948) (xy 139.80112 -38.729948) (xy 139.80112 -38.675452) (xy 139.808876 -38.621511)
			(xy 139.824229 -38.569223) (xy 139.846867 -38.519652) (xy 139.876329 -38.473807) (xy 139.912016 -38.432621)
			(xy 139.9532 -38.396934) (xy 139.999045 -38.36747) (xy 140.048615 -38.344831) (xy 140.100903 -38.329477)
			(xy 140.154844 -38.321721) (xy 140.182092 -38.321234) (xy 140.210397 -38.321714) (xy 140.266386 -38.330066)
			(xy 140.320526 -38.346602) (xy 140.371628 -38.370958) (xy 140.418567 -38.402601) (xy 140.460314 -38.440834)
			(xy 140.495952 -38.484818) (xy 140.510768 -38.50894) (xy 140.518441 -38.520923) (xy 140.539044 -38.540521)
			(xy 140.56426 -38.553665) (xy 140.592126 -38.559331) (xy 140.620472 -38.557077) (xy 140.647093 -38.547079)
			(xy 140.669915 -38.530116) (xy 140.678916 -38.5191) (xy 140.697098 -38.49622) (xy 140.739262 -38.455757)
			(xy 140.787099 -38.42219) (xy 140.839491 -38.396303) (xy 140.895216 -38.378702) (xy 140.952973 -38.369797)
			(xy 140.982192 -38.36924) (xy 141.009449 -38.369606) (xy 141.063407 -38.377363) (xy 141.115713 -38.392721)
			(xy 141.1653 -38.415366) (xy 141.21116 -38.444837) (xy 141.252359 -38.480535) (xy 141.288058 -38.521733)
			(xy 141.317531 -38.567593) (xy 141.340176 -38.61718) (xy 141.355535 -38.669485) (xy 141.363293 -38.723443)
			(xy 141.363293 -38.777957) (xy 141.355535 -38.831915) (xy 141.340176 -38.88422) (xy 141.317531 -38.933807)
			(xy 141.288058 -38.979667) (xy 141.252359 -39.020865) (xy 141.21116 -39.056563) (xy 141.1653 -39.086034)
			(xy 141.115713 -39.108679) (xy 141.063407 -39.124037) (xy 141.009449 -39.131794) (xy 140.982192 -39.132256)
			(xy 140.953887 -39.131793) (xy 140.897896 -39.123439) (xy 140.843755 -39.106901) (xy 140.792654 -39.082541)
			(xy 140.745714 -39.050896) (xy 140.703968 -39.01266) (xy 140.668332 -38.968674) (xy 140.653516 -38.94455)
			(xy 140.645864 -38.932553) (xy 140.625256 -38.912955) (xy 140.600036 -38.899813) (xy 140.572166 -38.89415)
			(xy 140.543817 -38.896407) (xy 140.517194 -38.906407) (xy 140.49437 -38.923373) (xy 140.485368 -38.93439)
			(xy 140.467192 -38.957275) (xy 140.425028 -38.997739) (xy 140.37719 -39.031306) (xy 140.324796 -39.057191)
			(xy 140.269069 -39.074791) (xy 140.211312 -39.083695) (xy 140.182092 -39.08425) (xy 140.154844 -39.083679)
			(xy 140.100903 -39.075923) (xy 140.048615 -39.060569) (xy 139.999045 -39.03793) (xy 139.9532 -39.008466)
			(xy 139.912016 -38.972779) (xy 139.876329 -38.931593) (xy 139.846867 -38.885748) (xy 139.824229 -38.836177)
			(xy 139.808876 -38.783889) (xy 139.80112 -38.729948) (xy 133.351311 -38.729948) (xy 133.345823 -38.772516)
			(xy 133.326688 -38.8456) (xy 133.298392 -38.915647) (xy 133.280404 -38.948868) (xy 133.279896 -38.949376)
			(xy 133.259369 -38.985657) (xy 133.209521 -39.052469) (xy 133.180582 -39.082472) (xy 132.291133 -39.97198)
			(xy 141.995904 -39.97198) (xy 141.999975 -39.916358) (xy 142.012101 -39.861921) (xy 142.032024 -39.80983)
			(xy 142.05932 -39.761195) (xy 142.093406 -39.717052) (xy 142.133555 -39.678343) (xy 142.178913 -39.645892)
			(xy 142.228513 -39.620391) (xy 142.281297 -39.602384) (xy 142.33614 -39.592254) (xy 142.391874 -39.590217)
			(xy 142.447311 -39.596317) (xy 142.501268 -39.610423) (xy 142.552597 -39.632235) (xy 142.600203 -39.661289)
			(xy 142.643071 -39.696964) (xy 142.680288 -39.738501) (xy 142.711061 -39.785014) (xy 142.734733 -39.835511)
			(xy 142.750801 -39.888918) (xy 142.758921 -39.944094) (xy 142.75943 -39.97198) (xy 142.758921 -39.999866)
			(xy 142.750801 -40.055042) (xy 142.734733 -40.108449) (xy 142.711061 -40.158946) (xy 142.680288 -40.205459)
			(xy 142.643071 -40.246996) (xy 142.600203 -40.282671) (xy 142.552597 -40.311725) (xy 142.501268 -40.333537)
			(xy 142.447311 -40.347643) (xy 142.391874 -40.353743) (xy 142.33614 -40.351706) (xy 142.281297 -40.341576)
			(xy 142.228513 -40.323569) (xy 142.178913 -40.298068) (xy 142.133555 -40.265617) (xy 142.093406 -40.226908)
			(xy 142.05932 -40.182765) (xy 142.032024 -40.13413) (xy 142.012101 -40.082039) (xy 141.999975 -40.027602)
			(xy 141.995904 -39.97198) (xy 132.291133 -39.97198) (xy 130.994443 -41.268755) (xy 131.944027 -41.268755)
			(xy 131.944027 -41.214245) (xy 131.951785 -41.160289) (xy 131.967142 -41.107986) (xy 131.989787 -41.058402)
			(xy 132.019258 -41.012545) (xy 132.054956 -40.971349) (xy 132.096153 -40.935652) (xy 132.142011 -40.906183)
			(xy 132.191596 -40.883539) (xy 132.243899 -40.868183) (xy 132.297855 -40.860426) (xy 132.32511 -40.859964)
			(xy 132.353849 -40.860491) (xy 132.410675 -40.869114) (xy 132.465566 -40.886164) (xy 132.517278 -40.911255)
			(xy 132.564641 -40.943818) (xy 132.585968 -40.963088) (xy 132.592826 -40.969692) (xy 132.61086 -40.976804)
			(xy 132.69976 -40.976804) (xy 132.717794 -40.969692) (xy 132.724652 -40.963088) (xy 132.745982 -40.943821)
			(xy 132.793343 -40.911252) (xy 132.845053 -40.886158) (xy 132.899944 -40.869107) (xy 132.956771 -40.860484)
			(xy 132.98551 -40.859964) (xy 133.012759 -40.860507) (xy 133.066701 -40.868264) (xy 133.118991 -40.883619)
			(xy 133.168563 -40.906259) (xy 133.214409 -40.935723) (xy 133.255595 -40.971412) (xy 133.291283 -41.012599)
			(xy 133.320746 -41.058445) (xy 133.343385 -41.108018) (xy 133.358738 -41.160308) (xy 133.366494 -41.214251)
			(xy 133.366494 -41.268749) (xy 133.358738 -41.322692) (xy 133.343385 -41.374982) (xy 133.320746 -41.424555)
			(xy 133.291283 -41.470401) (xy 133.255595 -41.511588) (xy 133.214409 -41.547277) (xy 133.168563 -41.576741)
			(xy 133.118991 -41.599381) (xy 133.066701 -41.614736) (xy 133.012759 -41.622493) (xy 132.98551 -41.62298)
			(xy 132.956772 -41.622429) (xy 132.899947 -41.61381) (xy 132.845058 -41.596765) (xy 132.793345 -41.57168)
			(xy 132.745981 -41.539123) (xy 132.724652 -41.519856) (xy 132.717794 -41.513252) (xy 132.69976 -41.50614)
			(xy 132.61086 -41.50614) (xy 132.592826 -41.513252) (xy 132.585968 -41.519856) (xy 132.564636 -41.539121)
			(xy 132.517275 -41.571688) (xy 132.465565 -41.596782) (xy 132.410675 -41.613834) (xy 132.353849 -41.622458)
			(xy 132.32511 -41.62298) (xy 132.297855 -41.622574) (xy 132.243899 -41.614817) (xy 132.191596 -41.599461)
			(xy 132.142011 -41.576817) (xy 132.096153 -41.547348) (xy 132.054956 -41.511651) (xy 132.019258 -41.470455)
			(xy 131.989787 -41.424598) (xy 131.967142 -41.375014) (xy 131.951785 -41.322711) (xy 131.944027 -41.268755)
			(xy 130.994443 -41.268755) (xy 129.314702 -42.948606) (xy 129.309622 -42.954448) (xy 129.305073 -42.961091)
			(xy 129.300037 -42.976374) (xy 129.299716 -42.98442) (xy 129.299716 -43.305222) (xy 134.407402 -43.305222)
			(xy 134.40788 -43.277852) (xy 134.415695 -43.223674) (xy 134.431181 -43.171171) (xy 134.45402 -43.121424)
			(xy 134.483742 -43.075456) (xy 134.501382 -43.054524) (xy 134.501636 -43.05427) (xy 134.507203 -43.047171)
			(xy 134.513461 -43.030263) (xy 134.513828 -43.02125) (xy 134.513828 -42.954194) (xy 134.513468 -42.945178)
			(xy 134.507222 -42.928261) (xy 134.501636 -42.921174) (xy 134.501382 -42.921174) (xy 134.501382 -42.92092)
			(xy 134.483736 -42.899994) (xy 134.454026 -42.854019) (xy 134.431192 -42.80427) (xy 134.415702 -42.751768)
			(xy 134.407875 -42.697592) (xy 134.407402 -42.670222) (xy 134.407939 -42.641484) (xy 134.416558 -42.584657)
			(xy 134.433605 -42.529766) (xy 134.458694 -42.478054) (xy 134.491256 -42.430691) (xy 134.510526 -42.409364)
			(xy 134.51713 -42.402506) (xy 134.524242 -42.384472) (xy 134.524242 -42.295572) (xy 134.51713 -42.277538)
			(xy 134.510526 -42.27068) (xy 134.491277 -42.249334) (xy 134.458711 -42.201975) (xy 134.433618 -42.150267)
			(xy 134.416566 -42.095379) (xy 134.407941 -42.038554) (xy 134.407939 -41.981078) (xy 134.416559 -41.924253)
			(xy 134.433606 -41.869363) (xy 134.458695 -41.817653) (xy 134.491257 -41.770291) (xy 134.510526 -41.748964)
			(xy 134.51713 -41.742106) (xy 134.524242 -41.724072) (xy 134.524242 -41.635172) (xy 134.51713 -41.617138)
			(xy 134.510526 -41.61028) (xy 134.491264 -41.588946) (xy 134.458697 -41.541585) (xy 134.433603 -41.489876)
			(xy 134.41655 -41.434987) (xy 134.407925 -41.37816) (xy 134.407402 -41.349422) (xy 134.407888 -41.322171)
			(xy 134.415644 -41.268223) (xy 134.430999 -41.215928) (xy 134.453641 -41.166351) (xy 134.483107 -41.120501)
			(xy 134.518798 -41.07931) (xy 134.559989 -41.043619) (xy 134.605839 -41.014153) (xy 134.655416 -40.991511)
			(xy 134.707711 -40.976156) (xy 134.761659 -40.9684) (xy 134.816161 -40.9684) (xy 134.839282 -40.971724)
			(xy 142.69415 -40.971724) (xy 142.698221 -40.916102) (xy 142.710347 -40.861665) (xy 142.73027 -40.809574)
			(xy 142.757566 -40.760939) (xy 142.791652 -40.716796) (xy 142.831801 -40.678087) (xy 142.877159 -40.645636)
			(xy 142.926759 -40.620135) (xy 142.979543 -40.602128) (xy 143.034386 -40.591998) (xy 143.09012 -40.589961)
			(xy 143.145557 -40.596061) (xy 143.199514 -40.610167) (xy 143.250843 -40.631979) (xy 143.298449 -40.661033)
			(xy 143.341317 -40.696708) (xy 143.378534 -40.738245) (xy 143.409307 -40.784758) (xy 143.432979 -40.835255)
			(xy 143.449047 -40.888662) (xy 143.457167 -40.943838) (xy 143.457676 -40.971724) (xy 143.457167 -40.99961)
			(xy 143.449047 -41.054786) (xy 143.432979 -41.108193) (xy 143.409307 -41.15869) (xy 143.378534 -41.205203)
			(xy 143.341317 -41.24674) (xy 143.298449 -41.282415) (xy 143.250843 -41.311469) (xy 143.199514 -41.333281)
			(xy 143.145557 -41.347387) (xy 143.09012 -41.353487) (xy 143.034386 -41.35145) (xy 142.979543 -41.34132)
			(xy 142.926759 -41.323313) (xy 142.877159 -41.297812) (xy 142.831801 -41.265361) (xy 142.791652 -41.226652)
			(xy 142.757566 -41.182509) (xy 142.73027 -41.133874) (xy 142.710347 -41.081783) (xy 142.698221 -41.027346)
			(xy 142.69415 -40.971724) (xy 134.839282 -40.971724) (xy 134.870109 -40.976156) (xy 134.922404 -40.991511)
			(xy 134.971981 -41.014153) (xy 135.017831 -41.043619) (xy 135.059022 -41.07931) (xy 135.094713 -41.120501)
			(xy 135.124179 -41.166351) (xy 135.146821 -41.215928) (xy 135.162176 -41.268223) (xy 135.169932 -41.322171)
			(xy 135.170418 -41.349422) (xy 135.169903 -41.378161) (xy 135.161277 -41.434989) (xy 135.144225 -41.489879)
			(xy 135.119132 -41.541591) (xy 135.086565 -41.588953) (xy 135.067294 -41.61028) (xy 135.06069 -41.617138)
			(xy 135.053578 -41.635172) (xy 135.053578 -41.724072) (xy 135.06069 -41.742106) (xy 135.067294 -41.748964)
			(xy 135.086586 -41.770272) (xy 135.119149 -41.817638) (xy 135.144238 -41.869353) (xy 135.161286 -41.924247)
			(xy 135.169906 -41.981076) (xy 135.169903 -42.038556) (xy 135.161278 -42.095385) (xy 135.144226 -42.150277)
			(xy 135.119133 -42.201989) (xy 135.086566 -42.249353) (xy 135.067294 -42.27068) (xy 135.06069 -42.277538)
			(xy 135.053578 -42.295572) (xy 135.053578 -42.384472) (xy 135.06069 -42.402506) (xy 135.067294 -42.409364)
			(xy 135.086564 -42.430692) (xy 135.119132 -42.478053) (xy 135.144226 -42.529764) (xy 135.161277 -42.584655)
			(xy 135.169898 -42.641483) (xy 135.170418 -42.670222) (xy 135.169985 -42.697594) (xy 135.162162 -42.751775)
			(xy 135.146666 -42.804279) (xy 135.126108 -42.849038) (xy 136.992104 -42.849038) (xy 136.996175 -42.793416)
			(xy 137.008301 -42.738979) (xy 137.028224 -42.686888) (xy 137.05552 -42.638253) (xy 137.089606 -42.59411)
			(xy 137.129755 -42.555401) (xy 137.175113 -42.52295) (xy 137.224713 -42.497449) (xy 137.277497 -42.479442)
			(xy 137.33234 -42.469312) (xy 137.388074 -42.467275) (xy 137.443511 -42.473375) (xy 137.497468 -42.487481)
			(xy 137.548797 -42.509293) (xy 137.596403 -42.538347) (xy 137.639271 -42.574022) (xy 137.676488 -42.615559)
			(xy 137.707261 -42.662072) (xy 137.730933 -42.712569) (xy 137.747001 -42.765976) (xy 137.755121 -42.821152)
			(xy 137.755482 -42.84091) (xy 143.03324 -42.84091) (xy 143.037311 -42.785288) (xy 143.049437 -42.730851)
			(xy 143.06936 -42.67876) (xy 143.096656 -42.630125) (xy 143.130742 -42.585982) (xy 143.170891 -42.547273)
			(xy 143.216249 -42.514822) (xy 143.265849 -42.489321) (xy 143.318633 -42.471314) (xy 143.373476 -42.461184)
			(xy 143.42921 -42.459147) (xy 143.484647 -42.465247) (xy 143.538604 -42.479353) (xy 143.589933 -42.501165)
			(xy 143.637539 -42.530219) (xy 143.680407 -42.565894) (xy 143.717624 -42.607431) (xy 143.748397 -42.653944)
			(xy 143.772069 -42.704441) (xy 143.788137 -42.757848) (xy 143.796257 -42.813024) (xy 143.796766 -42.84091)
			(xy 143.796257 -42.868796) (xy 143.788137 -42.923972) (xy 143.772069 -42.977379) (xy 143.748397 -43.027876)
			(xy 143.717624 -43.074389) (xy 143.680407 -43.115926) (xy 143.637539 -43.151601) (xy 143.589933 -43.180655)
			(xy 143.538604 -43.202467) (xy 143.484647 -43.216573) (xy 143.42921 -43.222673) (xy 143.373476 -43.220636)
			(xy 143.318633 -43.210506) (xy 143.265849 -43.192499) (xy 143.216249 -43.166998) (xy 143.170891 -43.134547)
			(xy 143.130742 -43.095838) (xy 143.096656 -43.051695) (xy 143.06936 -43.00306) (xy 143.049437 -42.950969)
			(xy 143.037311 -42.896532) (xy 143.03324 -42.84091) (xy 137.755482 -42.84091) (xy 137.75563 -42.849038)
			(xy 137.755121 -42.876924) (xy 137.747001 -42.9321) (xy 137.730933 -42.985507) (xy 137.707261 -43.036004)
			(xy 137.676488 -43.082517) (xy 137.639271 -43.124054) (xy 137.596403 -43.159729) (xy 137.548797 -43.188783)
			(xy 137.497468 -43.210595) (xy 137.443511 -43.224701) (xy 137.388074 -43.230801) (xy 137.33234 -43.228764)
			(xy 137.277497 -43.218634) (xy 137.224713 -43.200627) (xy 137.175113 -43.175126) (xy 137.129755 -43.142675)
			(xy 137.089606 -43.103966) (xy 137.05552 -43.059823) (xy 137.028224 -43.011188) (xy 137.008301 -42.959097)
			(xy 136.996175 -42.90466) (xy 136.992104 -42.849038) (xy 135.126108 -42.849038) (xy 135.123817 -42.854026)
			(xy 135.094084 -42.89999) (xy 135.076438 -42.92092) (xy 135.076184 -42.921174) (xy 135.0706 -42.928263)
			(xy 135.064352 -42.945178) (xy 135.063992 -42.954194) (xy 135.063992 -43.02125) (xy 135.064374 -43.030264)
			(xy 135.070604 -43.047181) (xy 135.076184 -43.05427) (xy 135.076438 -43.05427) (xy 135.076438 -43.054524)
			(xy 135.094061 -43.075469) (xy 135.123774 -43.121439) (xy 135.146613 -43.171183) (xy 135.162108 -43.223681)
			(xy 135.169941 -43.277854) (xy 135.170418 -43.305222) (xy 135.169932 -43.332473) (xy 135.162176 -43.386421)
			(xy 135.146821 -43.438716) (xy 135.124179 -43.488293) (xy 135.094713 -43.534143) (xy 135.059022 -43.575334)
			(xy 135.017831 -43.611025) (xy 134.971981 -43.640491) (xy 134.922404 -43.663133) (xy 134.870109 -43.678488)
			(xy 134.816161 -43.686244) (xy 134.761659 -43.686244) (xy 134.707711 -43.678488) (xy 134.655416 -43.663133)
			(xy 134.605839 -43.640491) (xy 134.559989 -43.611025) (xy 134.518798 -43.575334) (xy 134.483107 -43.534143)
			(xy 134.453641 -43.488293) (xy 134.430999 -43.438716) (xy 134.415644 -43.386421) (xy 134.407888 -43.332473)
			(xy 134.407402 -43.305222) (xy 129.299716 -43.305222) (xy 129.299716 -43.73626) (xy 136.313162 -43.73626)
			(xy 136.317233 -43.680638) (xy 136.329359 -43.626201) (xy 136.349282 -43.57411) (xy 136.376578 -43.525475)
			(xy 136.410664 -43.481332) (xy 136.450813 -43.442623) (xy 136.496171 -43.410172) (xy 136.545771 -43.384671)
			(xy 136.598555 -43.366664) (xy 136.653398 -43.356534) (xy 136.709132 -43.354497) (xy 136.764569 -43.360597)
			(xy 136.818526 -43.374703) (xy 136.869855 -43.396515) (xy 136.917461 -43.425569) (xy 136.960329 -43.461244)
			(xy 136.997546 -43.502781) (xy 137.028319 -43.549294) (xy 137.051991 -43.599791) (xy 137.068059 -43.653198)
			(xy 137.076179 -43.708374) (xy 137.076688 -43.73626) (xy 137.076179 -43.764146) (xy 137.068059 -43.819322)
			(xy 137.05675 -43.85691) (xy 140.819884 -43.85691) (xy 140.823955 -43.801288) (xy 140.836081 -43.746851)
			(xy 140.856004 -43.69476) (xy 140.8833 -43.646125) (xy 140.917386 -43.601982) (xy 140.957535 -43.563273)
			(xy 141.002893 -43.530822) (xy 141.052493 -43.505321) (xy 141.105277 -43.487314) (xy 141.16012 -43.477184)
			(xy 141.215854 -43.475147) (xy 141.271291 -43.481247) (xy 141.325248 -43.495353) (xy 141.376577 -43.517165)
			(xy 141.424183 -43.546219) (xy 141.467051 -43.581894) (xy 141.504268 -43.623431) (xy 141.535041 -43.669944)
			(xy 141.558713 -43.720441) (xy 141.574781 -43.773848) (xy 141.582901 -43.829024) (xy 141.58341 -43.85691)
			(xy 141.582901 -43.884796) (xy 141.574781 -43.939972) (xy 141.558713 -43.993379) (xy 141.535041 -44.043876)
			(xy 141.504268 -44.090389) (xy 141.467051 -44.131926) (xy 141.424183 -44.167601) (xy 141.376577 -44.196655)
			(xy 141.325248 -44.218467) (xy 141.271291 -44.232573) (xy 141.215854 -44.238673) (xy 141.16012 -44.236636)
			(xy 141.105277 -44.226506) (xy 141.052493 -44.208499) (xy 141.002893 -44.182998) (xy 140.957535 -44.150547)
			(xy 140.917386 -44.111838) (xy 140.8833 -44.067695) (xy 140.856004 -44.01906) (xy 140.836081 -43.966969)
			(xy 140.823955 -43.912532) (xy 140.819884 -43.85691) (xy 137.05675 -43.85691) (xy 137.051991 -43.872729)
			(xy 137.028319 -43.923226) (xy 136.997546 -43.969739) (xy 136.960329 -44.011276) (xy 136.917461 -44.046951)
			(xy 136.869855 -44.076005) (xy 136.818526 -44.097817) (xy 136.764569 -44.111923) (xy 136.709132 -44.118023)
			(xy 136.653398 -44.115986) (xy 136.598555 -44.105856) (xy 136.545771 -44.087849) (xy 136.496171 -44.062348)
			(xy 136.450813 -44.029897) (xy 136.410664 -43.991188) (xy 136.376578 -43.947045) (xy 136.349282 -43.89841)
			(xy 136.329359 -43.846319) (xy 136.317233 -43.791882) (xy 136.313162 -43.73626) (xy 129.299716 -43.73626)
			(xy 129.299716 -45.114464) (xy 136.165588 -45.114464) (xy 136.169659 -45.058842) (xy 136.181785 -45.004405)
			(xy 136.201708 -44.952314) (xy 136.229004 -44.903679) (xy 136.26309 -44.859536) (xy 136.303239 -44.820827)
			(xy 136.348597 -44.788376) (xy 136.398197 -44.762875) (xy 136.450981 -44.744868) (xy 136.505824 -44.734738)
			(xy 136.561558 -44.732701) (xy 136.616995 -44.738801) (xy 136.670952 -44.752907) (xy 136.722281 -44.774719)
			(xy 136.769887 -44.803773) (xy 136.812755 -44.839448) (xy 136.842737 -44.87291) (xy 143.03324 -44.87291)
			(xy 143.037311 -44.817288) (xy 143.049437 -44.762851) (xy 143.06936 -44.71076) (xy 143.096656 -44.662125)
			(xy 143.130742 -44.617982) (xy 143.170891 -44.579273) (xy 143.216249 -44.546822) (xy 143.265849 -44.521321)
			(xy 143.318633 -44.503314) (xy 143.373476 -44.493184) (xy 143.42921 -44.491147) (xy 143.484647 -44.497247)
			(xy 143.538604 -44.511353) (xy 143.589933 -44.533165) (xy 143.637539 -44.562219) (xy 143.680407 -44.597894)
			(xy 143.717624 -44.639431) (xy 143.748397 -44.685944) (xy 143.772069 -44.736441) (xy 143.788137 -44.789848)
			(xy 143.796257 -44.845024) (xy 143.796766 -44.87291) (xy 143.796257 -44.900796) (xy 143.788137 -44.955972)
			(xy 143.772069 -45.009379) (xy 143.748397 -45.059876) (xy 143.717624 -45.106389) (xy 143.680407 -45.147926)
			(xy 143.637539 -45.183601) (xy 143.589933 -45.212655) (xy 143.538604 -45.234467) (xy 143.484647 -45.248573)
			(xy 143.42921 -45.254673) (xy 143.373476 -45.252636) (xy 143.318633 -45.242506) (xy 143.265849 -45.224499)
			(xy 143.216249 -45.198998) (xy 143.170891 -45.166547) (xy 143.130742 -45.127838) (xy 143.096656 -45.083695)
			(xy 143.06936 -45.03506) (xy 143.049437 -44.982969) (xy 143.037311 -44.928532) (xy 143.03324 -44.87291)
			(xy 136.842737 -44.87291) (xy 136.849972 -44.880985) (xy 136.880745 -44.927498) (xy 136.904417 -44.977995)
			(xy 136.920485 -45.031402) (xy 136.928605 -45.086578) (xy 136.929114 -45.114464) (xy 136.928605 -45.14235)
			(xy 136.920485 -45.197526) (xy 136.904417 -45.250933) (xy 136.880745 -45.30143) (xy 136.849972 -45.347943)
			(xy 136.84433 -45.35424) (xy 140.803882 -45.35424) (xy 140.807953 -45.298618) (xy 140.820079 -45.244181)
			(xy 140.840002 -45.19209) (xy 140.867298 -45.143455) (xy 140.901384 -45.099312) (xy 140.941533 -45.060603)
			(xy 140.986891 -45.028152) (xy 141.036491 -45.002651) (xy 141.089275 -44.984644) (xy 141.144118 -44.974514)
			(xy 141.199852 -44.972477) (xy 141.255289 -44.978577) (xy 141.309246 -44.992683) (xy 141.360575 -45.014495)
			(xy 141.408181 -45.043549) (xy 141.451049 -45.079224) (xy 141.488266 -45.120761) (xy 141.519039 -45.167274)
			(xy 141.542711 -45.217771) (xy 141.558779 -45.271178) (xy 141.566899 -45.326354) (xy 141.567408 -45.35424)
			(xy 141.566899 -45.382126) (xy 141.558779 -45.437302) (xy 141.542711 -45.490709) (xy 141.519039 -45.541206)
			(xy 141.488266 -45.587719) (xy 141.451049 -45.629256) (xy 141.408181 -45.664931) (xy 141.360575 -45.693985)
			(xy 141.309246 -45.715797) (xy 141.255289 -45.729903) (xy 141.199852 -45.736003) (xy 141.144118 -45.733966)
			(xy 141.089275 -45.723836) (xy 141.036491 -45.705829) (xy 140.986891 -45.680328) (xy 140.941533 -45.647877)
			(xy 140.901384 -45.609168) (xy 140.867298 -45.565025) (xy 140.840002 -45.51639) (xy 140.820079 -45.464299)
			(xy 140.807953 -45.409862) (xy 140.803882 -45.35424) (xy 136.84433 -45.35424) (xy 136.812755 -45.38948)
			(xy 136.769887 -45.425155) (xy 136.722281 -45.454209) (xy 136.670952 -45.476021) (xy 136.616995 -45.490127)
			(xy 136.561558 -45.496227) (xy 136.505824 -45.49419) (xy 136.450981 -45.48406) (xy 136.398197 -45.466053)
			(xy 136.348597 -45.440552) (xy 136.303239 -45.408101) (xy 136.26309 -45.369392) (xy 136.229004 -45.325249)
			(xy 136.201708 -45.276614) (xy 136.181785 -45.224523) (xy 136.169659 -45.170086) (xy 136.165588 -45.114464)
			(xy 129.299716 -45.114464) (xy 129.299716 -46.082204) (xy 134.15264 -46.082204) (xy 134.153059 -46.054949)
			(xy 134.160817 -46.000994) (xy 134.176175 -45.948692) (xy 134.19882 -45.899109) (xy 134.228292 -45.853254)
			(xy 134.263991 -45.81206) (xy 134.305189 -45.776366) (xy 134.351048 -45.746899) (xy 134.400634 -45.724259)
			(xy 134.452937 -45.708908) (xy 134.506893 -45.701156) (xy 134.534148 -45.700696) (xy 134.561052 -45.701122)
			(xy 134.614323 -45.7087) (xy 134.666003 -45.723686) (xy 134.715064 -45.745782) (xy 134.760536 -45.77455)
			(xy 134.801517 -45.80942) (xy 134.837193 -45.8497) (xy 134.85241 -45.871892) (xy 134.859522 -45.882814)
			(xy 134.882382 -45.894752) (xy 134.99465 -45.89272) (xy 135.017002 -45.879766) (xy 135.02386 -45.86859)
			(xy 135.038754 -45.84497) (xy 135.074438 -45.802019) (xy 135.116001 -45.764727) (xy 135.162555 -45.733892)
			(xy 135.213107 -45.710171) (xy 135.266577 -45.694073) (xy 135.321822 -45.685939) (xy 135.349742 -45.685456)
			(xy 135.376736 -45.685893) (xy 135.430185 -45.693505) (xy 135.482029 -45.70857) (xy 135.531233 -45.73079)
			(xy 135.576816 -45.75972) (xy 135.597646 -45.776896) (xy 135.605774 -45.784008) (xy 135.626348 -45.790104)
			(xy 135.711692 -45.779182) (xy 135.722238 -45.777414) (xy 135.74052 -45.766355) (xy 135.746998 -45.757846)
			(xy 135.762359 -45.736621) (xy 135.797945 -45.698168) (xy 135.838461 -45.664949) (xy 135.883142 -45.63759)
			(xy 135.931149 -45.616605) (xy 135.981577 -45.602391) (xy 136.033476 -45.595214) (xy 136.059672 -45.594778)
			(xy 136.086925 -45.595267) (xy 136.140877 -45.603021) (xy 136.193176 -45.618374) (xy 136.242758 -45.641014)
			(xy 136.288613 -45.67048) (xy 136.329808 -45.706172) (xy 136.365503 -45.747364) (xy 136.394973 -45.793217)
			(xy 136.417616 -45.842797) (xy 136.432973 -45.895095) (xy 136.440731 -45.949047) (xy 136.440731 -46.003553)
			(xy 136.432973 -46.057505) (xy 136.417616 -46.109803) (xy 136.394973 -46.159383) (xy 136.365503 -46.205236)
			(xy 136.329808 -46.246428) (xy 136.288613 -46.28212) (xy 136.242758 -46.311586) (xy 136.193176 -46.334226)
			(xy 136.140877 -46.349579) (xy 136.086925 -46.357333) (xy 136.059672 -46.357794) (xy 136.032679 -46.357337)
			(xy 135.979231 -46.349728) (xy 135.927388 -46.334667) (xy 135.878183 -46.312452) (xy 135.832599 -46.283528)
			(xy 135.811768 -46.266354) (xy 135.80364 -46.259242) (xy 135.783066 -46.253146) (xy 135.697722 -46.264068)
			(xy 135.687182 -46.265861) (xy 135.668899 -46.276903) (xy 135.662416 -46.285404) (xy 135.644798 -46.3097)
			(xy 135.603206 -46.352962) (xy 135.579612 -46.37151) (xy 135.571738 -46.377352) (xy 135.561324 -46.394878)
			(xy 135.548116 -46.485302) (xy 135.552942 -46.504606) (xy 135.558784 -46.51248) (xy 135.558784 -46.512734)
			(xy 135.576288 -46.537477) (xy 135.60409 -46.591331) (xy 135.623026 -46.648903) (xy 135.630229 -46.693836)
			(xy 140.776452 -46.693836) (xy 140.776938 -46.666585) (xy 140.784694 -46.612637) (xy 140.800049 -46.560342)
			(xy 140.822691 -46.510765) (xy 140.852157 -46.464915) (xy 140.887848 -46.423724) (xy 140.929039 -46.388033)
			(xy 140.974889 -46.358567) (xy 141.024466 -46.335925) (xy 141.076761 -46.32057) (xy 141.130709 -46.312814)
			(xy 141.185211 -46.312814) (xy 141.239159 -46.32057) (xy 141.291454 -46.335925) (xy 141.341031 -46.358567)
			(xy 141.386881 -46.388033) (xy 141.428072 -46.423724) (xy 141.463763 -46.464915) (xy 141.493229 -46.510765)
			(xy 141.515871 -46.560342) (xy 141.531226 -46.612637) (xy 141.538982 -46.666585) (xy 141.539468 -46.693836)
			(xy 141.539 -46.720264) (xy 141.53169 -46.772611) (xy 141.517215 -46.823446) (xy 141.495853 -46.871793)
			(xy 141.482318 -46.894496) (xy 141.482064 -46.89475) (xy 141.476728 -46.904768) (xy 141.47447 -46.927318)
			(xy 141.477746 -46.938184) (xy 141.503908 -47.01286) (xy 141.508267 -47.023389) (xy 141.524373 -47.039472)
			(xy 141.534896 -47.043848) (xy 141.53515 -47.043848) (xy 141.55966 -47.052915) (xy 141.606112 -47.076858)
			(xy 141.648864 -47.106915) (xy 141.687116 -47.142522) (xy 141.720152 -47.183015) (xy 141.747356 -47.227637)
			(xy 141.768217 -47.275552) (xy 141.782347 -47.325865) (xy 141.789481 -47.377636) (xy 141.789912 -47.403766)
			(xy 141.789426 -47.431017) (xy 141.787903 -47.441612) (xy 143.061942 -47.441612) (xy 143.066013 -47.38599)
			(xy 143.078139 -47.331553) (xy 143.098062 -47.279462) (xy 143.125358 -47.230827) (xy 143.159444 -47.186684)
			(xy 143.199593 -47.147975) (xy 143.244951 -47.115524) (xy 143.294551 -47.090023) (xy 143.347335 -47.072016)
			(xy 143.402178 -47.061886) (xy 143.457912 -47.059849) (xy 143.513349 -47.065949) (xy 143.567306 -47.080055)
			(xy 143.618635 -47.101867) (xy 143.666241 -47.130921) (xy 143.709109 -47.166596) (xy 143.746326 -47.208133)
			(xy 143.777099 -47.254646) (xy 143.800771 -47.305143) (xy 143.816839 -47.35855) (xy 143.824959 -47.413726)
			(xy 143.825468 -47.441612) (xy 143.824959 -47.469498) (xy 143.816839 -47.524674) (xy 143.800771 -47.578081)
			(xy 143.777099 -47.628578) (xy 143.746326 -47.675091) (xy 143.709109 -47.716628) (xy 143.666241 -47.752303)
			(xy 143.618635 -47.781357) (xy 143.567306 -47.803169) (xy 143.513349 -47.817275) (xy 143.457912 -47.823375)
			(xy 143.402178 -47.821338) (xy 143.347335 -47.811208) (xy 143.294551 -47.793201) (xy 143.244951 -47.7677)
			(xy 143.199593 -47.735249) (xy 143.159444 -47.69654) (xy 143.125358 -47.652397) (xy 143.098062 -47.603762)
			(xy 143.078139 -47.551671) (xy 143.066013 -47.497234) (xy 143.061942 -47.441612) (xy 141.787903 -47.441612)
			(xy 141.78167 -47.484965) (xy 141.766315 -47.53726) (xy 141.743673 -47.586837) (xy 141.714207 -47.632687)
			(xy 141.678516 -47.673878) (xy 141.637325 -47.709569) (xy 141.591475 -47.739035) (xy 141.541898 -47.761677)
			(xy 141.489603 -47.777032) (xy 141.435655 -47.784788) (xy 141.381153 -47.784788) (xy 141.327205 -47.777032)
			(xy 141.27491 -47.761677) (xy 141.225333 -47.739035) (xy 141.179483 -47.709569) (xy 141.138292 -47.673878)
			(xy 141.102601 -47.632687) (xy 141.073135 -47.586837) (xy 141.050493 -47.53726) (xy 141.035138 -47.484965)
			(xy 141.027382 -47.431017) (xy 141.026896 -47.403766) (xy 141.02737 -47.377338) (xy 141.034679 -47.324991)
			(xy 141.049152 -47.274156) (xy 141.070511 -47.225809) (xy 141.084046 -47.203106) (xy 141.0843 -47.202852)
			(xy 141.089635 -47.192833) (xy 141.091896 -47.170283) (xy 141.088618 -47.159418) (xy 141.062456 -47.084742)
			(xy 141.058067 -47.074229) (xy 141.041982 -47.058139) (xy 141.031468 -47.053754) (xy 141.031214 -47.053754)
			(xy 141.006697 -47.044705) (xy 140.960246 -47.020758) (xy 140.917495 -46.990699) (xy 140.879245 -46.955088)
			(xy 140.846209 -46.914593) (xy 140.819007 -46.86997) (xy 140.798146 -46.822053) (xy 140.784017 -46.771738)
			(xy 140.776883 -46.719966) (xy 140.776452 -46.693836) (xy 135.630229 -46.693836) (xy 135.632619 -46.708745)
			(xy 135.633206 -46.739048) (xy 135.632767 -46.766301) (xy 135.625004 -46.82025) (xy 135.609642 -46.872546)
			(xy 135.586996 -46.922123) (xy 135.557524 -46.967974) (xy 135.521828 -47.009163) (xy 135.480633 -47.044854)
			(xy 135.434779 -47.07432) (xy 135.385199 -47.09696) (xy 135.332901 -47.112314) (xy 135.278951 -47.12007)
			(xy 135.251698 -47.120556) (xy 135.225665 -47.120102) (xy 135.174082 -47.113016) (xy 135.123941 -47.098988)
			(xy 135.07617 -47.078278) (xy 135.031655 -47.051271) (xy 135.01116 -47.035212) (xy 135.003392 -47.029487)
			(xy 134.98499 -47.023736) (xy 134.975346 -47.024036) (xy 134.89559 -47.030386) (xy 134.87781 -47.039022)
			(xy 134.87146 -47.046388) (xy 134.853272 -47.066027) (xy 134.812366 -47.10055) (xy 134.767038 -47.12902)
			(xy 134.718178 -47.150878) (xy 134.666744 -47.165697) (xy 134.613743 -47.173186) (xy 134.58698 -47.173642)
			(xy 134.55973 -47.173141) (xy 134.505784 -47.165383) (xy 134.453492 -47.150027) (xy 134.403917 -47.127386)
			(xy 134.358068 -47.09792) (xy 134.316879 -47.062231) (xy 134.281188 -47.021043) (xy 134.251721 -46.975195)
			(xy 134.229078 -46.925621) (xy 134.21372 -46.873329) (xy 134.20596 -46.819384) (xy 134.205472 -46.792134)
			(xy 134.206004 -46.76336) (xy 134.214654 -46.706467) (xy 134.231749 -46.651517) (xy 134.256901 -46.599757)
			(xy 134.289539 -46.55236) (xy 134.30885 -46.531022) (xy 134.316216 -46.523148) (xy 134.323328 -46.503336)
			(xy 134.315962 -46.40707) (xy 134.306056 -46.388274) (xy 134.297674 -46.38167) (xy 134.27548 -46.363457)
			(xy 134.236273 -46.321518) (xy 134.203789 -46.274179) (xy 134.178763 -46.222509) (xy 134.161758 -46.167674)
			(xy 134.153158 -46.11091) (xy 134.15264 -46.082204) (xy 129.299716 -46.082204) (xy 129.299716 -48.30699)
			(xy 140.654022 -48.30699) (xy 140.658093 -48.251368) (xy 140.670219 -48.196931) (xy 140.690142 -48.14484)
			(xy 140.717438 -48.096205) (xy 140.751524 -48.052062) (xy 140.791673 -48.013353) (xy 140.837031 -47.980902)
			(xy 140.886631 -47.955401) (xy 140.939415 -47.937394) (xy 140.994258 -47.927264) (xy 141.049992 -47.925227)
			(xy 141.105429 -47.931327) (xy 141.159386 -47.945433) (xy 141.210715 -47.967245) (xy 141.258321 -47.996299)
			(xy 141.301189 -48.031974) (xy 141.338406 -48.073511) (xy 141.369179 -48.120024) (xy 141.392851 -48.170521)
			(xy 141.408919 -48.223928) (xy 141.417039 -48.279104) (xy 141.417548 -48.30699) (xy 141.417039 -48.334876)
			(xy 141.408919 -48.390052) (xy 141.392851 -48.443459) (xy 141.369179 -48.493956) (xy 141.338406 -48.540469)
			(xy 141.301189 -48.582006) (xy 141.258321 -48.617681) (xy 141.210715 -48.646735) (xy 141.159386 -48.668547)
			(xy 141.105429 -48.682653) (xy 141.049992 -48.688753) (xy 140.994258 -48.686716) (xy 140.939415 -48.676586)
			(xy 140.886631 -48.658579) (xy 140.837031 -48.633078) (xy 140.791673 -48.600627) (xy 140.751524 -48.561918)
			(xy 140.717438 -48.517775) (xy 140.690142 -48.46914) (xy 140.670219 -48.417049) (xy 140.658093 -48.362612)
			(xy 140.654022 -48.30699) (xy 129.299716 -48.30699) (xy 129.299716 -48.753014) (xy 137.268456 -48.753014)
			(xy 137.272527 -48.697392) (xy 137.284653 -48.642955) (xy 137.304576 -48.590864) (xy 137.331872 -48.542229)
			(xy 137.365958 -48.498086) (xy 137.406107 -48.459377) (xy 137.451465 -48.426926) (xy 137.501065 -48.401425)
			(xy 137.553849 -48.383418) (xy 137.608692 -48.373288) (xy 137.664426 -48.371251) (xy 137.719863 -48.377351)
			(xy 137.77382 -48.391457) (xy 137.825149 -48.413269) (xy 137.872755 -48.442323) (xy 137.915623 -48.477998)
			(xy 137.95284 -48.519535) (xy 137.983613 -48.566048) (xy 138.007285 -48.616545) (xy 138.023353 -48.669952)
			(xy 138.031473 -48.725128) (xy 138.031982 -48.753014) (xy 138.031473 -48.7809) (xy 138.023353 -48.836076)
			(xy 138.007285 -48.889483) (xy 138.005889 -48.89246) (xy 139.314172 -48.89246) (xy 139.318243 -48.836838)
			(xy 139.330369 -48.782401) (xy 139.350292 -48.73031) (xy 139.377588 -48.681675) (xy 139.411674 -48.637532)
			(xy 139.451823 -48.598823) (xy 139.497181 -48.566372) (xy 139.546781 -48.540871) (xy 139.599565 -48.522864)
			(xy 139.654408 -48.512734) (xy 139.710142 -48.510697) (xy 139.765579 -48.516797) (xy 139.819536 -48.530903)
			(xy 139.870865 -48.552715) (xy 139.918471 -48.581769) (xy 139.961339 -48.617444) (xy 139.998556 -48.658981)
			(xy 140.029329 -48.705494) (xy 140.053001 -48.755991) (xy 140.069069 -48.809398) (xy 140.077189 -48.864574)
			(xy 140.077698 -48.89246) (xy 140.077189 -48.920346) (xy 140.074751 -48.93691) (xy 143.03324 -48.93691)
			(xy 143.037311 -48.881288) (xy 143.049437 -48.826851) (xy 143.06936 -48.77476) (xy 143.096656 -48.726125)
			(xy 143.130742 -48.681982) (xy 143.170891 -48.643273) (xy 143.216249 -48.610822) (xy 143.265849 -48.585321)
			(xy 143.318633 -48.567314) (xy 143.373476 -48.557184) (xy 143.42921 -48.555147) (xy 143.484647 -48.561247)
			(xy 143.538604 -48.575353) (xy 143.589933 -48.597165) (xy 143.637539 -48.626219) (xy 143.680407 -48.661894)
			(xy 143.717624 -48.703431) (xy 143.748397 -48.749944) (xy 143.772069 -48.800441) (xy 143.788137 -48.853848)
			(xy 143.796257 -48.909024) (xy 143.796766 -48.93691) (xy 143.796257 -48.964796) (xy 143.788137 -49.019972)
			(xy 143.772069 -49.073379) (xy 143.748397 -49.123876) (xy 143.717624 -49.170389) (xy 143.680407 -49.211926)
			(xy 143.637539 -49.247601) (xy 143.589933 -49.276655) (xy 143.538604 -49.298467) (xy 143.484647 -49.312573)
			(xy 143.42921 -49.318673) (xy 143.373476 -49.316636) (xy 143.318633 -49.306506) (xy 143.265849 -49.288499)
			(xy 143.216249 -49.262998) (xy 143.170891 -49.230547) (xy 143.130742 -49.191838) (xy 143.096656 -49.147695)
			(xy 143.06936 -49.09906) (xy 143.049437 -49.046969) (xy 143.037311 -48.992532) (xy 143.03324 -48.93691)
			(xy 140.074751 -48.93691) (xy 140.069069 -48.975522) (xy 140.053001 -49.028929) (xy 140.029329 -49.079426)
			(xy 139.998556 -49.125939) (xy 139.961339 -49.167476) (xy 139.918471 -49.203151) (xy 139.870865 -49.232205)
			(xy 139.819536 -49.254017) (xy 139.765579 -49.268123) (xy 139.710142 -49.274223) (xy 139.654408 -49.272186)
			(xy 139.599565 -49.262056) (xy 139.546781 -49.244049) (xy 139.497181 -49.218548) (xy 139.451823 -49.186097)
			(xy 139.411674 -49.147388) (xy 139.377588 -49.103245) (xy 139.350292 -49.05461) (xy 139.330369 -49.002519)
			(xy 139.318243 -48.948082) (xy 139.314172 -48.89246) (xy 138.005889 -48.89246) (xy 137.983613 -48.93998)
			(xy 137.95284 -48.986493) (xy 137.915623 -49.02803) (xy 137.872755 -49.063705) (xy 137.825149 -49.092759)
			(xy 137.77382 -49.114571) (xy 137.719863 -49.128677) (xy 137.664426 -49.134777) (xy 137.608692 -49.13274)
			(xy 137.553849 -49.12261) (xy 137.501065 -49.104603) (xy 137.451465 -49.079102) (xy 137.406107 -49.046651)
			(xy 137.365958 -49.007942) (xy 137.331872 -48.963799) (xy 137.304576 -48.915164) (xy 137.284653 -48.863073)
			(xy 137.272527 -48.808636) (xy 137.268456 -48.753014) (xy 129.299716 -48.753014) (xy 129.299716 -49.95291)
			(xy 143.03324 -49.95291) (xy 143.037311 -49.897288) (xy 143.049437 -49.842851) (xy 143.06936 -49.79076)
			(xy 143.096656 -49.742125) (xy 143.130742 -49.697982) (xy 143.170891 -49.659273) (xy 143.216249 -49.626822)
			(xy 143.265849 -49.601321) (xy 143.318633 -49.583314) (xy 143.373476 -49.573184) (xy 143.42921 -49.571147)
			(xy 143.484647 -49.577247) (xy 143.538604 -49.591353) (xy 143.563539 -49.601949) (xy 148.213082 -49.601949)
			(xy 148.213082 -49.547451) (xy 148.220837 -49.493507) (xy 148.23619 -49.441215) (xy 148.258829 -49.391641)
			(xy 148.288291 -49.345793) (xy 148.323978 -49.304604) (xy 148.365164 -49.268913) (xy 148.411009 -49.239446)
			(xy 148.460582 -49.216803) (xy 148.512871 -49.201445) (xy 148.566815 -49.193684) (xy 148.594064 -49.193196)
			(xy 148.621433 -49.193684) (xy 148.675612 -49.201497) (xy 148.728114 -49.216981) (xy 148.777862 -49.239818)
			(xy 148.823829 -49.269537) (xy 148.844762 -49.287176) (xy 148.845016 -49.28743) (xy 148.852091 -49.293033)
			(xy 148.869017 -49.299269) (xy 148.878036 -49.299622) (xy 148.945092 -49.299622) (xy 148.954108 -49.299256)
			(xy 148.971025 -49.293014) (xy 148.978112 -49.28743) (xy 148.978112 -49.287176) (xy 148.978366 -49.287176)
			(xy 148.999299 -49.269535) (xy 149.045267 -49.239811) (xy 149.095013 -49.216965) (xy 149.147515 -49.201469)
			(xy 149.201693 -49.19364) (xy 149.256435 -49.19364) (xy 149.310613 -49.201469) (xy 149.363115 -49.216965)
			(xy 149.412861 -49.239811) (xy 149.458829 -49.269535) (xy 149.479762 -49.287176) (xy 149.480016 -49.28743)
			(xy 149.487091 -49.293033) (xy 149.504017 -49.299269) (xy 149.513036 -49.299622) (xy 149.580092 -49.299622)
			(xy 149.589108 -49.299256) (xy 149.606025 -49.293014) (xy 149.613112 -49.28743) (xy 149.613112 -49.287176)
			(xy 149.613366 -49.287176) (xy 149.634299 -49.269535) (xy 149.680267 -49.239811) (xy 149.730013 -49.216965)
			(xy 149.782515 -49.201469) (xy 149.836693 -49.19364) (xy 149.891435 -49.19364) (xy 149.945613 -49.201469)
			(xy 149.998115 -49.216965) (xy 150.047861 -49.239811) (xy 150.093829 -49.269535) (xy 150.114762 -49.287176)
			(xy 150.115016 -49.28743) (xy 150.122091 -49.293033) (xy 150.139017 -49.299269) (xy 150.148036 -49.299622)
			(xy 150.215092 -49.299622) (xy 150.224108 -49.299256) (xy 150.241025 -49.293014) (xy 150.248112 -49.28743)
			(xy 150.248112 -49.287176) (xy 150.248366 -49.287176) (xy 150.269297 -49.269536) (xy 150.31527 -49.239825)
			(xy 150.365018 -49.21699) (xy 150.417519 -49.201499) (xy 150.471695 -49.19367) (xy 150.499064 -49.193196)
			(xy 150.526319 -49.193649) (xy 150.580274 -49.201402) (xy 150.632577 -49.216755) (xy 150.682162 -49.239396)
			(xy 150.72802 -49.268863) (xy 150.769218 -49.304557) (xy 150.804916 -49.345751) (xy 150.834387 -49.391606)
			(xy 150.857033 -49.441189) (xy 150.872391 -49.493491) (xy 150.880149 -49.547445) (xy 150.880149 -49.601955)
			(xy 150.872391 -49.655909) (xy 150.857033 -49.708211) (xy 150.834387 -49.757794) (xy 150.804916 -49.803649)
			(xy 150.769218 -49.844843) (xy 150.72802 -49.880537) (xy 150.682162 -49.910004) (xy 150.632577 -49.932645)
			(xy 150.580274 -49.947998) (xy 150.526319 -49.955751) (xy 150.499064 -49.956212) (xy 150.471693 -49.955764)
			(xy 150.417513 -49.947941) (xy 150.36501 -49.932448) (xy 150.315264 -49.909602) (xy 150.269297 -49.879875)
			(xy 150.248366 -49.862232) (xy 150.248112 -49.861978) (xy 150.241028 -49.856388) (xy 150.224109 -49.850144)
			(xy 150.215092 -49.849786) (xy 150.148036 -49.849786) (xy 150.139021 -49.850163) (xy 150.122104 -49.856397)
			(xy 150.115016 -49.861978) (xy 150.114762 -49.862232) (xy 150.093829 -49.879873) (xy 150.047861 -49.909597)
			(xy 149.998115 -49.932443) (xy 149.945613 -49.947939) (xy 149.891435 -49.955768) (xy 149.836693 -49.955768)
			(xy 149.782515 -49.947939) (xy 149.730013 -49.932443) (xy 149.680267 -49.909597) (xy 149.634299 -49.879873)
			(xy 149.613366 -49.862232) (xy 149.613112 -49.861978) (xy 149.606028 -49.856388) (xy 149.589109 -49.850144)
			(xy 149.580092 -49.849786) (xy 149.513036 -49.849786) (xy 149.504021 -49.850163) (xy 149.487104 -49.856397)
			(xy 149.480016 -49.861978) (xy 149.480016 -49.862232) (xy 149.479762 -49.862232) (xy 149.458829 -49.879873)
			(xy 149.412861 -49.909597) (xy 149.363115 -49.932443) (xy 149.310613 -49.947939) (xy 149.256435 -49.955768)
			(xy 149.201693 -49.955768) (xy 149.147515 -49.947939) (xy 149.095013 -49.932443) (xy 149.045267 -49.909597)
			(xy 148.999299 -49.879873) (xy 148.978366 -49.862232) (xy 148.978112 -49.861978) (xy 148.971028 -49.856388)
			(xy 148.954109 -49.850144) (xy 148.945092 -49.849786) (xy 148.878036 -49.849786) (xy 148.869021 -49.850163)
			(xy 148.852104 -49.856397) (xy 148.845016 -49.861978) (xy 148.845016 -49.862232) (xy 148.844762 -49.862232)
			(xy 148.823821 -49.87986) (xy 148.77785 -49.909573) (xy 148.728105 -49.93241) (xy 148.675606 -49.947904)
			(xy 148.621433 -49.955736) (xy 148.594064 -49.956212) (xy 148.566815 -49.955716) (xy 148.512871 -49.947955)
			(xy 148.460582 -49.932597) (xy 148.411009 -49.909954) (xy 148.365164 -49.880487) (xy 148.323978 -49.844796)
			(xy 148.288291 -49.803607) (xy 148.258829 -49.757759) (xy 148.23619 -49.708185) (xy 148.220837 -49.655893)
			(xy 148.213082 -49.601949) (xy 143.563539 -49.601949) (xy 143.589933 -49.613165) (xy 143.637539 -49.642219)
			(xy 143.680407 -49.677894) (xy 143.717624 -49.719431) (xy 143.748397 -49.765944) (xy 143.772069 -49.816441)
			(xy 143.788137 -49.869848) (xy 143.796257 -49.925024) (xy 143.796766 -49.95291) (xy 143.796257 -49.980796)
			(xy 143.788137 -50.035972) (xy 143.772069 -50.089379) (xy 143.748397 -50.139876) (xy 143.717624 -50.186389)
			(xy 143.680407 -50.227926) (xy 143.637539 -50.263601) (xy 143.589933 -50.292655) (xy 143.538604 -50.314467)
			(xy 143.484647 -50.328573) (xy 143.42921 -50.334673) (xy 143.373476 -50.332636) (xy 143.318633 -50.322506)
			(xy 143.265849 -50.304499) (xy 143.216249 -50.278998) (xy 143.170891 -50.246547) (xy 143.130742 -50.207838)
			(xy 143.096656 -50.163695) (xy 143.06936 -50.11506) (xy 143.049437 -50.062969) (xy 143.037311 -50.008532)
			(xy 143.03324 -49.95291) (xy 129.299716 -49.95291) (xy 129.299716 -51.019456) (xy 140.849602 -51.019456)
			(xy 140.853673 -50.963834) (xy 140.865799 -50.909397) (xy 140.885722 -50.857306) (xy 140.913018 -50.808671)
			(xy 140.947104 -50.764528) (xy 140.987253 -50.725819) (xy 141.032611 -50.693368) (xy 141.082211 -50.667867)
			(xy 141.134995 -50.64986) (xy 141.189838 -50.63973) (xy 141.245572 -50.637693) (xy 141.301009 -50.643793)
			(xy 141.354966 -50.657899) (xy 141.406295 -50.679711) (xy 141.453901 -50.708765) (xy 141.496769 -50.74444)
			(xy 141.533986 -50.785977) (xy 141.564759 -50.83249) (xy 141.588431 -50.882987) (xy 141.604499 -50.936394)
			(xy 141.612619 -50.99157) (xy 141.613128 -51.019456) (xy 141.612619 -51.047342) (xy 141.604499 -51.102518)
			(xy 141.588431 -51.155925) (xy 141.564759 -51.206422) (xy 141.539903 -51.243992) (xy 149.233128 -51.243992)
			(xy 149.233583 -51.216621) (xy 149.241402 -51.162441) (xy 149.256894 -51.109938) (xy 149.279738 -51.060191)
			(xy 149.309465 -51.014225) (xy 149.327108 -50.993294) (xy 149.327362 -50.99304) (xy 149.332945 -50.985951)
			(xy 149.339192 -50.969036) (xy 149.339554 -50.96002) (xy 149.339554 -50.892964) (xy 149.339224 -50.883944)
			(xy 149.332959 -50.867027) (xy 149.327362 -50.859944) (xy 149.327108 -50.859944) (xy 149.327108 -50.85969)
			(xy 149.309452 -50.838772) (xy 149.279742 -50.792795) (xy 149.25691 -50.743044) (xy 149.241423 -50.69054)
			(xy 149.233599 -50.636362) (xy 149.233128 -50.608992) (xy 149.233548 -50.581737) (xy 149.241307 -50.527783)
			(xy 149.256666 -50.475482) (xy 149.279312 -50.4259) (xy 149.308784 -50.380045) (xy 149.344482 -50.338851)
			(xy 149.38568 -50.303158) (xy 149.431538 -50.273691) (xy 149.481123 -50.25105) (xy 149.533426 -50.235698)
			(xy 149.587381 -50.227945) (xy 149.614636 -50.227484) (xy 149.643553 -50.228017) (xy 149.700725 -50.236738)
			(xy 149.755925 -50.253991) (xy 149.807887 -50.27938) (xy 149.855421 -50.312323) (xy 149.897437 -50.352064)
			(xy 149.915626 -50.37455) (xy 149.923223 -50.383368) (xy 149.944132 -50.393544) (xy 149.955758 -50.394108)
			(xy 150.035514 -50.394108) (xy 150.047145 -50.39356) (xy 150.068054 -50.383377) (xy 150.075646 -50.37455)
			(xy 150.093855 -50.352082) (xy 150.135872 -50.312348) (xy 150.183404 -50.279409) (xy 150.235362 -50.254018)
			(xy 150.290555 -50.236758) (xy 150.347721 -50.228023) (xy 150.376636 -50.227484) (xy 150.403888 -50.227944)
			(xy 150.457836 -50.235706) (xy 150.510131 -50.251065) (xy 150.559708 -50.27371) (xy 150.605557 -50.303179)
			(xy 150.646747 -50.338873) (xy 150.682438 -50.380065) (xy 150.711904 -50.425917) (xy 150.734545 -50.475496)
			(xy 150.7499 -50.527791) (xy 150.757658 -50.58174) (xy 150.758144 -50.608992) (xy 150.757689 -50.635307)
			(xy 150.750454 -50.687436) (xy 150.736134 -50.73808) (xy 150.714999 -50.786279) (xy 150.68745 -50.831122)
			(xy 150.654008 -50.871761) (xy 150.634954 -50.889916) (xy 150.627551 -50.897437) (xy 150.619026 -50.916717)
			(xy 150.618444 -50.927254) (xy 150.618444 -51.00193) (xy 150.618984 -51.012479) (xy 150.62751 -51.031775)
			(xy 150.634954 -51.039268) (xy 150.654046 -51.057387) (xy 150.687498 -51.098026) (xy 150.715051 -51.142874)
			(xy 150.736182 -51.191082) (xy 150.750492 -51.241735) (xy 150.757709 -51.293874) (xy 150.758144 -51.320192)
			(xy 150.757615 -51.347441) (xy 150.74986 -51.401386) (xy 150.734508 -51.453677) (xy 150.711871 -51.503252)
			(xy 150.682408 -51.549101) (xy 150.646722 -51.59029) (xy 150.605536 -51.625982) (xy 150.559691 -51.655449)
			(xy 150.510119 -51.678093) (xy 150.457829 -51.693451) (xy 150.403885 -51.701212) (xy 150.376636 -51.7017)
			(xy 150.348972 -51.70116) (xy 150.294224 -51.693165) (xy 150.241203 -51.677354) (xy 150.191019 -51.654055)
			(xy 150.144723 -51.623758) (xy 150.103284 -51.587097) (xy 150.06757 -51.544839) (xy 150.052532 -51.521614)
			(xy 150.04589 -51.511942) (xy 150.026032 -51.499497) (xy 150.014432 -51.497738) (xy 149.934422 -51.489864)
			(xy 149.922784 -51.489249) (xy 149.900947 -51.497317) (xy 149.892512 -51.505358) (xy 149.892258 -51.505612)
			(xy 149.874182 -51.524198) (xy 149.833849 -51.556776) (xy 149.789473 -51.583588) (xy 149.741874 -51.604139)
			(xy 149.691929 -51.618052) (xy 149.640559 -51.625069) (xy 149.614636 -51.6255) (xy 149.587384 -51.625011)
			(xy 149.533433 -51.617259) (xy 149.481135 -51.601907) (xy 149.431555 -51.579268) (xy 149.385701 -51.549803)
			(xy 149.344508 -51.514112) (xy 149.308814 -51.472921) (xy 149.279345 -51.42707) (xy 149.256703 -51.377491)
			(xy 149.241347 -51.325194) (xy 149.233591 -51.271244) (xy 149.233128 -51.243992) (xy 141.539903 -51.243992)
			(xy 141.533986 -51.252935) (xy 141.496769 -51.294472) (xy 141.453901 -51.330147) (xy 141.406295 -51.359201)
			(xy 141.354966 -51.381013) (xy 141.301009 -51.395119) (xy 141.245572 -51.401219) (xy 141.189838 -51.399182)
			(xy 141.134995 -51.389052) (xy 141.082211 -51.371045) (xy 141.032611 -51.345544) (xy 140.987253 -51.313093)
			(xy 140.947104 -51.274384) (xy 140.913018 -51.230241) (xy 140.885722 -51.181606) (xy 140.865799 -51.129515)
			(xy 140.853673 -51.075078) (xy 140.849602 -51.019456) (xy 129.299716 -51.019456) (xy 129.299716 -52.035456)
			(xy 143.041368 -52.035456) (xy 143.045439 -51.979834) (xy 143.057565 -51.925397) (xy 143.077488 -51.873306)
			(xy 143.104784 -51.824671) (xy 143.13887 -51.780528) (xy 143.179019 -51.741819) (xy 143.224377 -51.709368)
			(xy 143.273977 -51.683867) (xy 143.326761 -51.66586) (xy 143.381604 -51.65573) (xy 143.437338 -51.653693)
			(xy 143.492775 -51.659793) (xy 143.546732 -51.673899) (xy 143.598061 -51.695711) (xy 143.645667 -51.724765)
			(xy 143.688535 -51.76044) (xy 143.725752 -51.801977) (xy 143.756525 -51.84849) (xy 143.780197 -51.898987)
			(xy 143.796265 -51.952394) (xy 143.804385 -52.00757) (xy 143.804894 -52.035456) (xy 143.804385 -52.063342)
			(xy 143.796265 -52.118518) (xy 143.780197 -52.171925) (xy 143.756525 -52.222422) (xy 143.725752 -52.268935)
			(xy 143.688535 -52.310472) (xy 143.645667 -52.346147) (xy 143.598061 -52.375201) (xy 143.546732 -52.397013)
			(xy 143.492775 -52.411119) (xy 143.437338 -52.417219) (xy 143.381604 -52.415182) (xy 143.326761 -52.405052)
			(xy 143.273977 -52.387045) (xy 143.224377 -52.361544) (xy 143.179019 -52.329093) (xy 143.13887 -52.290384)
			(xy 143.104784 -52.246241) (xy 143.077488 -52.197606) (xy 143.057565 -52.145515) (xy 143.045439 -52.091078)
			(xy 143.041368 -52.035456) (xy 129.299716 -52.035456) (xy 129.299716 -54.731412) (xy 129.620772 -54.731412)
			(xy 129.621228 -54.704041) (xy 129.629045 -54.649861) (xy 129.644536 -54.597357) (xy 129.66738 -54.54761)
			(xy 129.697109 -54.501645) (xy 129.714752 -54.480714) (xy 129.715006 -54.48046) (xy 129.720574 -54.473361)
			(xy 129.726832 -54.456454) (xy 129.727198 -54.44744) (xy 129.727198 -54.380384) (xy 129.726849 -54.371366)
			(xy 129.720596 -54.354449) (xy 129.715006 -54.347364) (xy 129.714752 -54.347364) (xy 129.714752 -54.34711)
			(xy 129.697122 -54.326168) (xy 129.667395 -54.280203) (xy 129.644547 -54.230458) (xy 129.629049 -54.177957)
			(xy 129.621219 -54.123779) (xy 129.621217 -54.069039) (xy 129.629045 -54.014861) (xy 129.644541 -53.962359)
			(xy 129.667386 -53.912613) (xy 129.697111 -53.866646) (xy 129.714752 -53.845714) (xy 129.715006 -53.84546)
			(xy 129.720574 -53.838361) (xy 129.726832 -53.821454) (xy 129.727198 -53.81244) (xy 129.727198 -53.745384)
			(xy 129.726849 -53.736366) (xy 129.720596 -53.719449) (xy 129.715006 -53.712364) (xy 129.714752 -53.712364)
			(xy 129.714752 -53.71211) (xy 129.697122 -53.691168) (xy 129.667395 -53.645203) (xy 129.644547 -53.595458)
			(xy 129.629049 -53.542957) (xy 129.621219 -53.488779) (xy 129.621217 -53.434039) (xy 129.629045 -53.379861)
			(xy 129.644541 -53.327359) (xy 129.667386 -53.277613) (xy 129.697111 -53.231646) (xy 129.714752 -53.210714)
			(xy 129.715006 -53.21046) (xy 129.720574 -53.203361) (xy 129.726832 -53.186454) (xy 129.727198 -53.17744)
			(xy 129.727198 -53.110384) (xy 129.726849 -53.101366) (xy 129.720596 -53.084449) (xy 129.715006 -53.077364)
			(xy 129.714752 -53.077364) (xy 129.714752 -53.07711) (xy 129.697112 -53.056178) (xy 129.667399 -53.010206)
			(xy 129.644562 -52.960459) (xy 129.629071 -52.907958) (xy 129.621245 -52.853781) (xy 129.620772 -52.826412)
			(xy 129.621258 -52.799161) (xy 129.629014 -52.745213) (xy 129.644369 -52.692918) (xy 129.667011 -52.643341)
			(xy 129.696477 -52.597491) (xy 129.732168 -52.5563) (xy 129.773359 -52.520609) (xy 129.819209 -52.491143)
			(xy 129.868786 -52.468501) (xy 129.921081 -52.453146) (xy 129.975029 -52.44539) (xy 130.029531 -52.44539)
			(xy 130.083479 -52.453146) (xy 130.135774 -52.468501) (xy 130.185351 -52.491143) (xy 130.231201 -52.520609)
			(xy 130.272392 -52.5563) (xy 130.308083 -52.597491) (xy 130.337549 -52.643341) (xy 130.360191 -52.692918)
			(xy 130.375546 -52.745213) (xy 130.383302 -52.799161) (xy 130.383788 -52.826412) (xy 130.383332 -52.853783)
			(xy 130.375512 -52.907962) (xy 130.360021 -52.960466) (xy 130.337177 -53.010212) (xy 130.30745 -53.056179)
			(xy 130.289808 -53.07711) (xy 130.289554 -53.077364) (xy 130.283971 -53.084453) (xy 130.277723 -53.101368)
			(xy 130.277362 -53.110384) (xy 130.277362 -53.17744) (xy 130.277708 -53.186458) (xy 130.283964 -53.203374)
			(xy 130.289554 -53.21046) (xy 130.289808 -53.21046) (xy 130.289808 -53.210714) (xy 130.307459 -53.231638)
			(xy 130.337181 -53.277608) (xy 130.360023 -53.327356) (xy 130.375517 -53.379859) (xy 130.383344 -53.434038)
			(xy 130.383342 -53.48878) (xy 130.375513 -53.542959) (xy 130.360017 -53.595461) (xy 130.337172 -53.645208)
			(xy 130.307448 -53.691177) (xy 130.289808 -53.71211) (xy 130.289554 -53.712364) (xy 130.283971 -53.719453)
			(xy 130.277723 -53.736368) (xy 130.277362 -53.745384) (xy 130.277362 -53.81244) (xy 130.277708 -53.821458)
			(xy 130.283964 -53.838374) (xy 130.289554 -53.84546) (xy 130.289808 -53.84546) (xy 130.289808 -53.845714)
			(xy 130.307459 -53.866638) (xy 130.337181 -53.912608) (xy 130.360023 -53.962356) (xy 130.375517 -54.014859)
			(xy 130.383344 -54.069038) (xy 130.383342 -54.12378) (xy 130.375513 -54.177959) (xy 130.360017 -54.230461)
			(xy 130.337172 -54.280208) (xy 130.307448 -54.326177) (xy 130.289808 -54.34711) (xy 130.289554 -54.347364)
			(xy 130.283971 -54.354453) (xy 130.277723 -54.371368) (xy 130.277362 -54.380384) (xy 130.277362 -54.44744)
			(xy 130.277708 -54.456458) (xy 130.283964 -54.473374) (xy 130.289554 -54.48046) (xy 130.289808 -54.48046)
			(xy 130.289808 -54.480714) (xy 130.307421 -54.501667) (xy 130.337137 -54.547634) (xy 130.359978 -54.597376)
			(xy 130.375475 -54.649872) (xy 130.38331 -54.704044) (xy 130.383788 -54.731412) (xy 130.383302 -54.758663)
			(xy 130.378638 -54.791102) (xy 132.276596 -54.791102) (xy 132.277064 -54.763732) (xy 132.284882 -54.709553)
			(xy 132.30037 -54.65705) (xy 132.323212 -54.607303) (xy 132.352935 -54.561336) (xy 132.370576 -54.540404)
			(xy 132.37083 -54.54015) (xy 132.376405 -54.533056) (xy 132.382658 -54.516145) (xy 132.383022 -54.50713)
			(xy 132.383022 -54.440074) (xy 132.382673 -54.431056) (xy 132.376419 -54.41414) (xy 132.37083 -54.407054)
			(xy 132.370576 -54.407054) (xy 132.370576 -54.4068) (xy 132.352935 -54.385867) (xy 132.323207 -54.3399)
			(xy 132.300358 -54.290154) (xy 132.28486 -54.237652) (xy 132.27703 -54.183473) (xy 132.27703 -54.12873)
			(xy 132.284859 -54.074551) (xy 132.300357 -54.022049) (xy 132.323205 -53.972302) (xy 132.352933 -53.926336)
			(xy 132.370576 -53.905404) (xy 132.37083 -53.90515) (xy 132.376405 -53.898056) (xy 132.382658 -53.881145)
			(xy 132.383022 -53.87213) (xy 132.383022 -53.805074) (xy 132.382673 -53.796056) (xy 132.376419 -53.77914)
			(xy 132.37083 -53.772054) (xy 132.370576 -53.772054) (xy 132.370576 -53.7718) (xy 132.352935 -53.750867)
			(xy 132.323207 -53.7049) (xy 132.300358 -53.655154) (xy 132.28486 -53.602652) (xy 132.27703 -53.548473)
			(xy 132.27703 -53.49373) (xy 132.284859 -53.439551) (xy 132.300357 -53.387049) (xy 132.323205 -53.337302)
			(xy 132.352933 -53.291336) (xy 132.370576 -53.270404) (xy 132.37083 -53.27015) (xy 132.376405 -53.263056)
			(xy 132.382658 -53.246145) (xy 132.383022 -53.23713) (xy 132.383022 -53.170074) (xy 132.382673 -53.161056)
			(xy 132.376419 -53.14414) (xy 132.37083 -53.137054) (xy 132.370576 -53.137054) (xy 132.370576 -53.1368)
			(xy 132.35292 -53.115882) (xy 132.323211 -53.069905) (xy 132.300379 -53.020154) (xy 132.284892 -52.96765)
			(xy 132.277068 -52.913472) (xy 132.276596 -52.886102) (xy 132.277082 -52.858851) (xy 132.284838 -52.804903)
			(xy 132.300193 -52.752608) (xy 132.322835 -52.703031) (xy 132.352301 -52.657181) (xy 132.387992 -52.61599)
			(xy 132.429183 -52.580299) (xy 132.475033 -52.550833) (xy 132.52461 -52.528191) (xy 132.576905 -52.512836)
			(xy 132.630853 -52.50508) (xy 132.685355 -52.50508) (xy 132.739303 -52.512836) (xy 132.791598 -52.528191)
			(xy 132.830698 -52.546048) (xy 137.779796 -52.546048) (xy 137.779796 -52.491552) (xy 137.787551 -52.43761)
			(xy 137.802904 -52.385321) (xy 137.825541 -52.335749) (xy 137.855002 -52.289903) (xy 137.890687 -52.248716)
			(xy 137.931871 -52.213026) (xy 137.977714 -52.18356) (xy 138.027284 -52.160918) (xy 138.079571 -52.14556)
			(xy 138.133512 -52.137799) (xy 138.16076 -52.13731) (xy 138.18813 -52.137797) (xy 138.242308 -52.145609)
			(xy 138.294811 -52.161093) (xy 138.344558 -52.183931) (xy 138.390526 -52.213651) (xy 138.411458 -52.23129)
			(xy 138.411712 -52.231544) (xy 138.418787 -52.237147) (xy 138.435713 -52.243383) (xy 138.444732 -52.243736)
			(xy 138.511788 -52.243736) (xy 138.520803 -52.243365) (xy 138.53772 -52.237126) (xy 138.544808 -52.231544)
			(xy 138.544808 -52.23129) (xy 138.545062 -52.23129) (xy 138.565995 -52.213649) (xy 138.611963 -52.183925)
			(xy 138.661709 -52.161079) (xy 138.714211 -52.145583) (xy 138.768389 -52.137754) (xy 138.823131 -52.137754)
			(xy 138.877309 -52.145583) (xy 138.929811 -52.161079) (xy 138.979557 -52.183925) (xy 139.025525 -52.213649)
			(xy 139.046458 -52.23129) (xy 139.046712 -52.231544) (xy 139.053787 -52.237147) (xy 139.070713 -52.243383)
			(xy 139.079732 -52.243736) (xy 139.146788 -52.243736) (xy 139.155803 -52.243365) (xy 139.17272 -52.237126)
			(xy 139.179808 -52.231544) (xy 139.179808 -52.23129) (xy 139.180062 -52.23129) (xy 139.200996 -52.213654)
			(xy 139.246969 -52.183942) (xy 139.296716 -52.161105) (xy 139.349216 -52.145614) (xy 139.403391 -52.137785)
			(xy 139.43076 -52.13731) (xy 139.458016 -52.137734) (xy 139.511974 -52.145487) (xy 139.564279 -52.16084)
			(xy 139.613867 -52.183482) (xy 139.659727 -52.21295) (xy 139.700926 -52.248645) (xy 139.736626 -52.289841)
			(xy 139.766099 -52.335698) (xy 139.788746 -52.385283) (xy 139.804105 -52.437587) (xy 139.811863 -52.491544)
			(xy 139.811863 -52.546056) (xy 139.805919 -52.587398) (xy 140.855444 -52.587398) (xy 140.859515 -52.531776)
			(xy 140.871641 -52.477339) (xy 140.891564 -52.425248) (xy 140.91886 -52.376613) (xy 140.952946 -52.33247)
			(xy 140.993095 -52.293761) (xy 141.038453 -52.26131) (xy 141.088053 -52.235809) (xy 141.140837 -52.217802)
			(xy 141.19568 -52.207672) (xy 141.251414 -52.205635) (xy 141.306851 -52.211735) (xy 141.360808 -52.225841)
			(xy 141.412137 -52.247653) (xy 141.459743 -52.276707) (xy 141.502611 -52.312382) (xy 141.539828 -52.353919)
			(xy 141.570601 -52.400432) (xy 141.594273 -52.450929) (xy 141.610341 -52.504336) (xy 141.617937 -52.555949)
			(xy 148.684002 -52.555949) (xy 148.684002 -52.501451) (xy 148.691758 -52.447509) (xy 148.707111 -52.395219)
			(xy 148.729749 -52.345646) (xy 148.759212 -52.2998) (xy 148.794899 -52.258613) (xy 148.836084 -52.222924)
			(xy 148.881929 -52.193459) (xy 148.9315 -52.170818) (xy 148.983789 -52.155462) (xy 149.037731 -52.147704)
			(xy 149.06498 -52.147216) (xy 149.09235 -52.14769) (xy 149.146529 -52.155505) (xy 149.199032 -52.170992)
			(xy 149.248779 -52.193832) (xy 149.294746 -52.223555) (xy 149.315678 -52.241196) (xy 149.315932 -52.24145)
			(xy 149.32303 -52.24702) (xy 149.339938 -52.253276) (xy 149.348952 -52.253642) (xy 149.416008 -52.253642)
			(xy 149.425027 -52.253301) (xy 149.441944 -52.247044) (xy 149.449028 -52.24145) (xy 149.449028 -52.241196)
			(xy 149.449282 -52.241196) (xy 149.47021 -52.223551) (xy 149.516184 -52.19384) (xy 149.565932 -52.171006)
			(xy 149.618434 -52.155516) (xy 149.672611 -52.147689) (xy 149.69998 -52.147216) (xy 149.727236 -52.14763)
			(xy 149.781192 -52.155385) (xy 149.833496 -52.17074) (xy 149.883081 -52.193383) (xy 149.92894 -52.222852)
			(xy 149.970138 -52.258548) (xy 150.005836 -52.299744) (xy 150.035308 -52.345601) (xy 150.057953 -52.395186)
			(xy 150.073311 -52.447488) (xy 150.081069 -52.501444) (xy 150.081069 -52.555956) (xy 150.073311 -52.609912)
			(xy 150.057953 -52.662214) (xy 150.035308 -52.711799) (xy 150.005836 -52.757656) (xy 149.970138 -52.798852)
			(xy 149.92894 -52.834548) (xy 149.883081 -52.864017) (xy 149.833496 -52.88666) (xy 149.781192 -52.902015)
			(xy 149.727236 -52.90977) (xy 149.69998 -52.910232) (xy 149.672609 -52.909794) (xy 149.618428 -52.901972)
			(xy 149.565924 -52.886477) (xy 149.516177 -52.863629) (xy 149.470212 -52.833897) (xy 149.449282 -52.816252)
			(xy 149.449028 -52.815998) (xy 149.441938 -52.810417) (xy 149.425024 -52.804167) (xy 149.416008 -52.803806)
			(xy 149.348952 -52.803806) (xy 149.339938 -52.804187) (xy 149.32302 -52.810418) (xy 149.315932 -52.815998)
			(xy 149.315932 -52.816252) (xy 149.315678 -52.816252) (xy 149.294721 -52.833861) (xy 149.248756 -52.863579)
			(xy 149.199015 -52.886421) (xy 149.146519 -52.901919) (xy 149.092348 -52.909754) (xy 149.06498 -52.910232)
			(xy 149.037731 -52.909696) (xy 148.983789 -52.901938) (xy 148.9315 -52.886582) (xy 148.881929 -52.863941)
			(xy 148.836084 -52.834476) (xy 148.794899 -52.798787) (xy 148.759212 -52.7576) (xy 148.729749 -52.711754)
			(xy 148.707111 -52.662181) (xy 148.691758 -52.609891) (xy 148.684002 -52.555949) (xy 141.617937 -52.555949)
			(xy 141.618461 -52.559512) (xy 141.61897 -52.587398) (xy 141.618461 -52.615284) (xy 141.610341 -52.67046)
			(xy 141.594273 -52.723867) (xy 141.570601 -52.774364) (xy 141.539828 -52.820877) (xy 141.502611 -52.862414)
			(xy 141.459743 -52.898089) (xy 141.412137 -52.927143) (xy 141.360808 -52.948955) (xy 141.306851 -52.963061)
			(xy 141.251414 -52.969161) (xy 141.19568 -52.967124) (xy 141.140837 -52.956994) (xy 141.088053 -52.938987)
			(xy 141.038453 -52.913486) (xy 140.993095 -52.881035) (xy 140.952946 -52.842326) (xy 140.91886 -52.798183)
			(xy 140.891564 -52.749548) (xy 140.871641 -52.697457) (xy 140.859515 -52.64302) (xy 140.855444 -52.587398)
			(xy 139.805919 -52.587398) (xy 139.804105 -52.600013) (xy 139.788746 -52.652317) (xy 139.766099 -52.701902)
			(xy 139.736626 -52.747759) (xy 139.700926 -52.788955) (xy 139.659727 -52.82465) (xy 139.613867 -52.854118)
			(xy 139.564279 -52.87676) (xy 139.511974 -52.892113) (xy 139.458016 -52.899866) (xy 139.43076 -52.900326)
			(xy 139.40339 -52.899843) (xy 139.349211 -52.892032) (xy 139.296707 -52.876548) (xy 139.24696 -52.853709)
			(xy 139.200993 -52.823987) (xy 139.180062 -52.806346) (xy 139.179808 -52.806092) (xy 139.172724 -52.800502)
			(xy 139.155805 -52.794258) (xy 139.146788 -52.7939) (xy 139.079732 -52.7939) (xy 139.070717 -52.794272)
			(xy 139.0538 -52.800509) (xy 139.046712 -52.806092) (xy 139.046458 -52.806346) (xy 139.025525 -52.823987)
			(xy 138.979557 -52.853711) (xy 138.929811 -52.876557) (xy 138.877309 -52.892053) (xy 138.823131 -52.899882)
			(xy 138.768389 -52.899882) (xy 138.714211 -52.892053) (xy 138.661709 -52.876557) (xy 138.611963 -52.853711)
			(xy 138.565995 -52.823987) (xy 138.545062 -52.806346) (xy 138.544808 -52.806092) (xy 138.537724 -52.800502)
			(xy 138.520805 -52.794258) (xy 138.511788 -52.7939) (xy 138.444732 -52.7939) (xy 138.435717 -52.794272)
			(xy 138.4188 -52.800509) (xy 138.411712 -52.806092) (xy 138.411712 -52.806346) (xy 138.411458 -52.806346)
			(xy 138.390508 -52.823963) (xy 138.344541 -52.85368) (xy 138.294798 -52.876521) (xy 138.242301 -52.892017)
			(xy 138.188128 -52.89985) (xy 138.16076 -52.900326) (xy 138.133512 -52.899801) (xy 138.079571 -52.89204)
			(xy 138.027284 -52.876682) (xy 137.977714 -52.85404) (xy 137.931871 -52.824574) (xy 137.890687 -52.788884)
			(xy 137.855002 -52.747697) (xy 137.825541 -52.701851) (xy 137.802904 -52.652279) (xy 137.787551 -52.59999)
			(xy 137.779796 -52.546048) (xy 132.830698 -52.546048) (xy 132.841175 -52.550833) (xy 132.887025 -52.580299)
			(xy 132.928216 -52.61599) (xy 132.963907 -52.657181) (xy 132.993373 -52.703031) (xy 133.016015 -52.752608)
			(xy 133.03137 -52.804903) (xy 133.039126 -52.858851) (xy 133.039612 -52.886102) (xy 133.039144 -52.913472)
			(xy 133.031326 -52.967651) (xy 133.015837 -53.020154) (xy 132.992996 -53.069901) (xy 132.963273 -53.115868)
			(xy 132.945632 -53.1368) (xy 132.945378 -53.137054) (xy 132.939802 -53.144148) (xy 132.93355 -53.161059)
			(xy 132.933186 -53.170074) (xy 132.933186 -53.23713) (xy 132.933531 -53.246148) (xy 132.939787 -53.263065)
			(xy 132.945378 -53.27015) (xy 132.945632 -53.27015) (xy 132.945632 -53.270404) (xy 132.963276 -53.291334)
			(xy 132.993004 -53.337302) (xy 133.015852 -53.387048) (xy 133.03135 -53.439551) (xy 133.039179 -53.49373)
			(xy 133.039179 -53.548473) (xy 133.031349 -53.602652) (xy 133.015851 -53.655155) (xy 132.993003 -53.704901)
			(xy 132.963275 -53.750868) (xy 132.946702 -53.77053) (xy 133.310884 -53.77053) (xy 133.311392 -53.741612)
			(xy 133.320119 -53.684439) (xy 133.337376 -53.629239) (xy 133.36277 -53.577276) (xy 133.395717 -53.529743)
			(xy 133.435462 -53.487728) (xy 133.45795 -53.46954) (xy 133.466738 -53.461914) (xy 133.47693 -53.441027)
			(xy 133.477508 -53.429408) (xy 133.477508 -53.349652) (xy 133.476979 -53.338019) (xy 133.466783 -53.31711)
			(xy 133.45795 -53.30952) (xy 133.435466 -53.29133) (xy 133.395733 -53.249309) (xy 133.362795 -53.201773)
			(xy 133.337408 -53.149812) (xy 133.320151 -53.094615) (xy 133.31142 -53.037446) (xy 133.310884 -53.00853)
			(xy 133.311383 -52.981278) (xy 133.319136 -52.927329) (xy 133.334488 -52.875032) (xy 133.357126 -52.825453)
			(xy 133.38659 -52.7796) (xy 133.42228 -52.738407) (xy 133.463469 -52.702713) (xy 133.509319 -52.673244)
			(xy 133.558897 -52.650601) (xy 133.611192 -52.635244) (xy 133.66514 -52.627486) (xy 133.692392 -52.627022)
			(xy 133.718706 -52.627488) (xy 133.770835 -52.634722) (xy 133.821478 -52.649041) (xy 133.869677 -52.670174)
			(xy 133.914521 -52.69772) (xy 133.95516 -52.73116) (xy 133.973316 -52.750212) (xy 133.980828 -52.757625)
			(xy 134.000115 -52.766142) (xy 134.010654 -52.766722) (xy 134.08533 -52.766722) (xy 134.095876 -52.766162)
			(xy 134.115171 -52.757648) (xy 134.122668 -52.750212) (xy 134.1408 -52.731133) (xy 134.181434 -52.697677)
			(xy 134.22628 -52.670121) (xy 134.274485 -52.648987) (xy 134.325137 -52.634675) (xy 134.377274 -52.627457)
			(xy 134.403592 -52.627022) (xy 134.430846 -52.627463) (xy 134.484799 -52.63522) (xy 134.537099 -52.650576)
			(xy 134.586682 -52.67322) (xy 134.632536 -52.70269) (xy 134.67373 -52.738386) (xy 134.709423 -52.779582)
			(xy 134.738891 -52.825438) (xy 134.761532 -52.875021) (xy 134.776885 -52.927322) (xy 134.784639 -52.981276)
			(xy 134.7851 -53.00853) (xy 134.784611 -53.036196) (xy 134.78238 -53.051456) (xy 143.041368 -53.051456)
			(xy 143.045439 -52.995834) (xy 143.057565 -52.941397) (xy 143.077488 -52.889306) (xy 143.104784 -52.840671)
			(xy 143.13887 -52.796528) (xy 143.179019 -52.757819) (xy 143.224377 -52.725368) (xy 143.273977 -52.699867)
			(xy 143.326761 -52.68186) (xy 143.381604 -52.67173) (xy 143.437338 -52.669693) (xy 143.492775 -52.675793)
			(xy 143.546732 -52.689899) (xy 143.598061 -52.711711) (xy 143.645667 -52.740765) (xy 143.688535 -52.77644)
			(xy 143.725752 -52.817977) (xy 143.756525 -52.86449) (xy 143.780197 -52.914987) (xy 143.796265 -52.968394)
			(xy 143.804385 -53.02357) (xy 143.804894 -53.051456) (xy 143.804385 -53.079342) (xy 143.796265 -53.134518)
			(xy 143.780197 -53.187925) (xy 143.756525 -53.238422) (xy 143.725752 -53.284935) (xy 143.688535 -53.326472)
			(xy 143.645667 -53.362147) (xy 143.598061 -53.391201) (xy 143.546732 -53.413013) (xy 143.492775 -53.427119)
			(xy 143.437338 -53.433219) (xy 143.381604 -53.431182) (xy 143.326761 -53.421052) (xy 143.273977 -53.403045)
			(xy 143.224377 -53.377544) (xy 143.179019 -53.345093) (xy 143.13887 -53.306384) (xy 143.104784 -53.262241)
			(xy 143.077488 -53.213606) (xy 143.057565 -53.161515) (xy 143.045439 -53.107078) (xy 143.041368 -53.051456)
			(xy 134.78238 -53.051456) (xy 134.776608 -53.090946) (xy 134.760787 -53.143968) (xy 134.73748 -53.194152)
			(xy 134.707175 -53.240448) (xy 134.670507 -53.281885) (xy 134.628242 -53.317597) (xy 134.605014 -53.332634)
			(xy 134.595316 -53.339245) (xy 134.582884 -53.359125) (xy 134.581138 -53.370734) (xy 134.573264 -53.450744)
			(xy 134.572608 -53.462383) (xy 134.580704 -53.484222) (xy 134.588758 -53.492654) (xy 134.589012 -53.492908)
			(xy 134.607581 -53.511) (xy 134.640161 -53.55133) (xy 134.666975 -53.595702) (xy 134.68753 -53.643298)
			(xy 134.701446 -53.69324) (xy 134.708466 -53.744608) (xy 134.7089 -53.77053) (xy 134.70845 -53.797782)
			(xy 134.700689 -53.851732) (xy 134.68533 -53.904028) (xy 134.662685 -53.953606) (xy 134.633215 -53.999456)
			(xy 134.597519 -54.040646) (xy 134.556326 -54.076337) (xy 134.510472 -54.105803) (xy 134.460892 -54.128443)
			(xy 134.408595 -54.143797) (xy 134.354644 -54.151553) (xy 134.327392 -54.152038) (xy 134.300021 -54.151592)
			(xy 134.24584 -54.143771) (xy 134.193336 -54.128279) (xy 134.14359 -54.105432) (xy 134.097624 -54.075702)
			(xy 134.076694 -54.058058) (xy 134.07644 -54.057804) (xy 134.069346 -54.052228) (xy 134.052435 -54.045975)
			(xy 134.04342 -54.045612) (xy 133.976364 -54.045612) (xy 133.967345 -54.045949) (xy 133.950428 -54.05221)
			(xy 133.943344 -54.057804) (xy 133.943344 -54.058058) (xy 133.94309 -54.058058) (xy 133.922167 -54.075709)
			(xy 133.876192 -54.10542) (xy 133.826443 -54.128255) (xy 133.77394 -54.143743) (xy 133.719762 -54.151567)
			(xy 133.692392 -54.152038) (xy 133.665142 -54.15153) (xy 133.611197 -54.143773) (xy 133.558904 -54.128418)
			(xy 133.509329 -54.105778) (xy 133.46348 -54.076314) (xy 133.422291 -54.040625) (xy 133.386599 -53.999438)
			(xy 133.357132 -53.953591) (xy 133.334489 -53.904017) (xy 133.319132 -53.851725) (xy 133.311372 -53.79778)
			(xy 133.310884 -53.77053) (xy 132.946702 -53.77053) (xy 132.945632 -53.7718) (xy 132.945378 -53.772054)
			(xy 132.939802 -53.779148) (xy 132.93355 -53.796059) (xy 132.933186 -53.805074) (xy 132.933186 -53.87213)
			(xy 132.933531 -53.881148) (xy 132.939787 -53.898065) (xy 132.945378 -53.90515) (xy 132.945632 -53.90515)
			(xy 132.945632 -53.905404) (xy 132.963276 -53.926334) (xy 132.993004 -53.972302) (xy 133.015852 -54.022048)
			(xy 133.03135 -54.074551) (xy 133.039179 -54.12873) (xy 133.039179 -54.183473) (xy 133.031349 -54.237652)
			(xy 133.015851 -54.290155) (xy 133.002058 -54.320186) (xy 135.230616 -54.320186) (xy 135.23107 -54.292815)
			(xy 135.23889 -54.238636) (xy 135.254382 -54.186132) (xy 135.277226 -54.136385) (xy 135.306954 -54.090419)
			(xy 135.324596 -54.069488) (xy 135.32485 -54.069234) (xy 135.330434 -54.062146) (xy 135.336681 -54.04523)
			(xy 135.337042 -54.036214) (xy 135.337042 -53.969158) (xy 135.33667 -53.960142) (xy 135.330434 -53.943225)
			(xy 135.32485 -53.936138) (xy 135.324596 -53.936138) (xy 135.324596 -53.935884) (xy 135.306982 -53.914932)
			(xy 135.277267 -53.868964) (xy 135.254426 -53.819222) (xy 135.238929 -53.766726) (xy 135.231094 -53.712554)
			(xy 135.230616 -53.685186) (xy 135.231102 -53.657935) (xy 135.238858 -53.603987) (xy 135.254213 -53.551692)
			(xy 135.276855 -53.502115) (xy 135.306321 -53.456265) (xy 135.342012 -53.415074) (xy 135.383203 -53.379383)
			(xy 135.429053 -53.349917) (xy 135.47863 -53.327275) (xy 135.530925 -53.31192) (xy 135.584873 -53.304164)
			(xy 135.639375 -53.304164) (xy 135.693323 -53.31192) (xy 135.745618 -53.327275) (xy 135.795195 -53.349917)
			(xy 135.841045 -53.379383) (xy 135.882236 -53.415074) (xy 135.917927 -53.456265) (xy 135.94382 -53.496556)
			(xy 148.233541 -53.496556) (xy 148.233541 -53.442044) (xy 148.241299 -53.388088) (xy 148.256658 -53.335785)
			(xy 148.279304 -53.286201) (xy 148.308777 -53.240344) (xy 148.344476 -53.199149) (xy 148.385674 -53.163454)
			(xy 148.431534 -53.133986) (xy 148.481121 -53.111344) (xy 148.533425 -53.095991) (xy 148.587382 -53.088238)
			(xy 148.614638 -53.087778) (xy 148.642008 -53.088261) (xy 148.696187 -53.096072) (xy 148.748691 -53.111556)
			(xy 148.798438 -53.134394) (xy 148.844405 -53.164117) (xy 148.865336 -53.181758) (xy 148.86559 -53.182012)
			(xy 148.872674 -53.187602) (xy 148.889593 -53.193846) (xy 148.89861 -53.194204) (xy 148.965666 -53.194204)
			(xy 148.974681 -53.19383) (xy 148.991598 -53.187594) (xy 148.998686 -53.182012) (xy 148.998686 -53.181758)
			(xy 148.99894 -53.181758) (xy 149.019878 -53.164127) (xy 149.06585 -53.134415) (xy 149.115596 -53.111578)
			(xy 149.168095 -53.096085) (xy 149.222269 -53.088254) (xy 149.249638 -53.087778) (xy 149.276886 -53.088295)
			(xy 149.330828 -53.096055) (xy 149.383116 -53.111413) (xy 149.432687 -53.134056) (xy 149.478531 -53.163522)
			(xy 149.519715 -53.199212) (xy 149.555401 -53.2404) (xy 149.584863 -53.286247) (xy 149.6075 -53.335819)
			(xy 149.622853 -53.388109) (xy 149.630608 -53.442052) (xy 149.630608 -53.496548) (xy 149.622853 -53.550491)
			(xy 149.6075 -53.602781) (xy 149.584863 -53.652353) (xy 149.555401 -53.6982) (xy 149.519715 -53.739388)
			(xy 149.478531 -53.775078) (xy 149.432687 -53.804544) (xy 149.383116 -53.827187) (xy 149.330828 -53.842545)
			(xy 149.276886 -53.850305) (xy 149.249638 -53.850794) (xy 149.222269 -53.850307) (xy 149.16809 -53.842495)
			(xy 149.115587 -53.82701) (xy 149.06584 -53.804173) (xy 149.019872 -53.774453) (xy 148.99894 -53.756814)
			(xy 148.998686 -53.75656) (xy 148.991611 -53.750957) (xy 148.974685 -53.744721) (xy 148.965666 -53.744368)
			(xy 148.89861 -53.744368) (xy 148.889594 -53.744737) (xy 148.872678 -53.750977) (xy 148.86559 -53.75656)
			(xy 148.86559 -53.756814) (xy 148.865336 -53.756814) (xy 148.844403 -53.774452) (xy 148.79843 -53.804163)
			(xy 148.748683 -53.826999) (xy 148.696183 -53.842491) (xy 148.642007 -53.85032) (xy 148.614638 -53.850794)
			(xy 148.587382 -53.850362) (xy 148.533425 -53.842609) (xy 148.481121 -53.827256) (xy 148.431534 -53.804614)
			(xy 148.385674 -53.775146) (xy 148.344476 -53.739451) (xy 148.308777 -53.698256) (xy 148.279304 -53.652399)
			(xy 148.256658 -53.602815) (xy 148.241299 -53.550512) (xy 148.233541 -53.496556) (xy 135.94382 -53.496556)
			(xy 135.947393 -53.502115) (xy 135.970035 -53.551692) (xy 135.98539 -53.603987) (xy 135.993146 -53.657935)
			(xy 135.993632 -53.685186) (xy 135.993174 -53.712557) (xy 135.985357 -53.766737) (xy 135.969867 -53.819241)
			(xy 135.947023 -53.868987) (xy 135.917295 -53.914953) (xy 135.899652 -53.935884) (xy 135.899398 -53.936138)
			(xy 135.893831 -53.943238) (xy 135.887573 -53.960144) (xy 135.887206 -53.969158) (xy 135.887206 -54.036214)
			(xy 135.887555 -54.045232) (xy 135.893808 -54.062149) (xy 135.899398 -54.069234) (xy 135.899652 -54.069234)
			(xy 135.899652 -54.069488) (xy 135.917291 -54.09042) (xy 135.947005 -54.136392) (xy 135.969842 -54.186139)
			(xy 135.985332 -54.23864) (xy 135.993159 -54.292817) (xy 135.993632 -54.320186) (xy 135.993146 -54.347437)
			(xy 135.98539 -54.401385) (xy 135.970035 -54.45368) (xy 135.947393 -54.503257) (xy 135.917927 -54.549107)
			(xy 135.882236 -54.590298) (xy 135.841045 -54.625989) (xy 135.795195 -54.655455) (xy 135.745618 -54.678097)
			(xy 135.693323 -54.693452) (xy 135.639375 -54.701208) (xy 135.584873 -54.701208) (xy 135.530925 -54.693452)
			(xy 135.47863 -54.678097) (xy 135.429053 -54.655455) (xy 135.383203 -54.625989) (xy 135.342012 -54.590298)
			(xy 135.306321 -54.549107) (xy 135.276855 -54.503257) (xy 135.254213 -54.45368) (xy 135.238858 -54.401385)
			(xy 135.231102 -54.347437) (xy 135.230616 -54.320186) (xy 133.002058 -54.320186) (xy 132.993003 -54.339901)
			(xy 132.963275 -54.385868) (xy 132.945632 -54.4068) (xy 132.945378 -54.407054) (xy 132.939802 -54.414148)
			(xy 132.93355 -54.431059) (xy 132.933186 -54.440074) (xy 132.933186 -54.50713) (xy 132.933531 -54.516148)
			(xy 132.939787 -54.533065) (xy 132.945378 -54.54015) (xy 132.945632 -54.54015) (xy 132.945632 -54.540404)
			(xy 132.963291 -54.56132) (xy 132.992999 -54.607297) (xy 133.015831 -54.657049) (xy 133.031317 -54.709553)
			(xy 133.03914 -54.763732) (xy 133.039257 -54.770528) (xy 136.171178 -54.770528) (xy 136.171641 -54.743157)
			(xy 136.179457 -54.688977) (xy 136.194946 -54.636474) (xy 136.217788 -54.586727) (xy 136.247515 -54.540761)
			(xy 136.265158 -54.51983) (xy 136.265412 -54.519576) (xy 136.271016 -54.512501) (xy 136.277252 -54.495575)
			(xy 136.277604 -54.486556) (xy 136.277604 -54.4195) (xy 136.277246 -54.410483) (xy 136.270999 -54.393566)
			(xy 136.265412 -54.38648) (xy 136.265158 -54.38648) (xy 136.265158 -54.386226) (xy 136.247511 -54.365301)
			(xy 136.217801 -54.319325) (xy 136.194968 -54.269576) (xy 136.179478 -54.217074) (xy 136.171651 -54.162898)
			(xy 136.171178 -54.135528) (xy 136.171664 -54.108277) (xy 136.17942 -54.054329) (xy 136.194775 -54.002034)
			(xy 136.217417 -53.952457) (xy 136.246883 -53.906607) (xy 136.282574 -53.865416) (xy 136.323765 -53.829725)
			(xy 136.369615 -53.800259) (xy 136.419192 -53.777617) (xy 136.471487 -53.762262) (xy 136.525435 -53.754506)
			(xy 136.579937 -53.754506) (xy 136.633885 -53.762262) (xy 136.68618 -53.777617) (xy 136.735757 -53.800259)
			(xy 136.781607 -53.829725) (xy 136.822798 -53.865416) (xy 136.858489 -53.906607) (xy 136.887955 -53.952457)
			(xy 136.89303 -53.96357) (xy 140.872208 -53.96357) (xy 140.876279 -53.907948) (xy 140.888405 -53.853511)
			(xy 140.908328 -53.80142) (xy 140.935624 -53.752785) (xy 140.96971 -53.708642) (xy 141.009859 -53.669933)
			(xy 141.055217 -53.637482) (xy 141.104817 -53.611981) (xy 141.157601 -53.593974) (xy 141.212444 -53.583844)
			(xy 141.268178 -53.581807) (xy 141.323615 -53.587907) (xy 141.377572 -53.602013) (xy 141.428901 -53.623825)
			(xy 141.476507 -53.652879) (xy 141.519375 -53.688554) (xy 141.556592 -53.730091) (xy 141.587365 -53.776604)
			(xy 141.611037 -53.827101) (xy 141.627105 -53.880508) (xy 141.635225 -53.935684) (xy 141.635734 -53.96357)
			(xy 141.635225 -53.991456) (xy 141.627105 -54.046632) (xy 141.611037 -54.100039) (xy 141.587365 -54.150536)
			(xy 141.556592 -54.197049) (xy 141.519375 -54.238586) (xy 141.476507 -54.274261) (xy 141.428901 -54.303315)
			(xy 141.377572 -54.325127) (xy 141.323615 -54.339233) (xy 141.268178 -54.345333) (xy 141.212444 -54.343296)
			(xy 141.157601 -54.333166) (xy 141.104817 -54.315159) (xy 141.055217 -54.289658) (xy 141.009859 -54.257207)
			(xy 140.96971 -54.218498) (xy 140.935624 -54.174355) (xy 140.908328 -54.12572) (xy 140.888405 -54.073629)
			(xy 140.876279 -54.019192) (xy 140.872208 -53.96357) (xy 136.89303 -53.96357) (xy 136.910597 -54.002034)
			(xy 136.925952 -54.054329) (xy 136.933708 -54.108277) (xy 136.934194 -54.135528) (xy 136.933746 -54.162899)
			(xy 136.925924 -54.217079) (xy 136.910431 -54.269582) (xy 136.887585 -54.319329) (xy 136.857857 -54.365295)
			(xy 136.840214 -54.386226) (xy 136.83996 -54.38648) (xy 136.834371 -54.393565) (xy 136.828127 -54.410483)
			(xy 136.827768 -54.4195) (xy 136.827768 -54.486556) (xy 136.828153 -54.49557) (xy 136.834382 -54.512487)
			(xy 136.83996 -54.519576) (xy 136.840214 -54.519576) (xy 136.840214 -54.51983) (xy 136.857836 -54.540776)
			(xy 136.88755 -54.586745) (xy 136.910389 -54.636489) (xy 136.925884 -54.688987) (xy 136.933717 -54.74316)
			(xy 136.934194 -54.770528) (xy 136.933708 -54.797779) (xy 136.925952 -54.851727) (xy 136.910597 -54.904022)
			(xy 136.887955 -54.953599) (xy 136.865169 -54.989055) (xy 146.001145 -54.989055) (xy 146.001145 -54.934545)
			(xy 146.008903 -54.88059) (xy 146.024261 -54.828288) (xy 146.046906 -54.778704) (xy 146.076378 -54.732848)
			(xy 146.112076 -54.691654) (xy 146.153274 -54.655959) (xy 146.199132 -54.626491) (xy 146.248718 -54.60385)
			(xy 146.301021 -54.588496) (xy 146.354977 -54.580743) (xy 146.382232 -54.580282) (xy 146.410324 -54.580751)
			(xy 146.465903 -54.588983) (xy 146.519672 -54.605279) (xy 146.57047 -54.629286) (xy 146.617196 -54.660484)
			(xy 146.658841 -54.6982) (xy 146.694502 -54.741616) (xy 146.709384 -54.765448) (xy 146.714718 -54.774338)
			(xy 146.731736 -54.78653) (xy 146.824954 -54.80685) (xy 146.845528 -54.802532) (xy 146.854164 -54.79669)
			(xy 146.878235 -54.780702) (xy 146.930164 -54.755357) (xy 146.98532 -54.738128) (xy 147.042442 -54.729409)
			(xy 147.071334 -54.728872) (xy 147.098585 -54.729346) (xy 147.152532 -54.737107) (xy 147.204826 -54.752465)
			(xy 147.254402 -54.775109) (xy 147.300251 -54.804577) (xy 147.341441 -54.840269) (xy 147.377132 -54.88146)
			(xy 147.406598 -54.92731) (xy 147.42924 -54.976887) (xy 147.444596 -55.029181) (xy 147.452355 -55.083129)
			(xy 147.452842 -55.11038) (xy 147.452378 -55.13775) (xy 147.444562 -55.19193) (xy 147.429073 -55.244434)
			(xy 147.406231 -55.294181) (xy 147.376504 -55.340147) (xy 147.358862 -55.361078) (xy 147.358608 -55.361332)
			(xy 147.353045 -55.368435) (xy 147.346784 -55.385339) (xy 147.346416 -55.394352) (xy 147.346416 -55.461408)
			(xy 147.346766 -55.470426) (xy 147.353018 -55.487343) (xy 147.358608 -55.494428) (xy 147.358862 -55.494428)
			(xy 147.358862 -55.494682) (xy 147.376484 -55.51563) (xy 147.40621 -55.561595) (xy 147.429057 -55.611339)
			(xy 147.444555 -55.663839) (xy 147.452386 -55.718015) (xy 147.452388 -55.772755) (xy 147.444562 -55.826932)
			(xy 147.429068 -55.879433) (xy 147.406225 -55.929178) (xy 147.376502 -55.975146) (xy 147.358862 -55.996078)
			(xy 147.358608 -55.996332) (xy 147.353045 -56.003435) (xy 147.346784 -56.020339) (xy 147.346416 -56.029352)
			(xy 147.346416 -56.096408) (xy 147.346766 -56.105426) (xy 147.353018 -56.122343) (xy 147.358608 -56.129428)
			(xy 147.358862 -56.129428) (xy 147.358862 -56.129682) (xy 147.3765 -56.150615) (xy 147.406213 -56.196587)
			(xy 147.42905 -56.246334) (xy 147.444541 -56.298835) (xy 147.452369 -56.353011) (xy 147.452842 -56.38038)
			(xy 147.452356 -56.407631) (xy 147.4446 -56.461579) (xy 147.429245 -56.513874) (xy 147.406603 -56.563451)
			(xy 147.377137 -56.609301) (xy 147.341446 -56.650492) (xy 147.300255 -56.686183) (xy 147.254405 -56.715649)
			(xy 147.204828 -56.738291) (xy 147.152533 -56.753646) (xy 147.098585 -56.761402) (xy 147.044083 -56.761402)
			(xy 146.990135 -56.753646) (xy 146.93784 -56.738291) (xy 146.888263 -56.715649) (xy 146.842413 -56.686183)
			(xy 146.801222 -56.650492) (xy 146.765531 -56.609301) (xy 146.736065 -56.563451) (xy 146.713423 -56.513874)
			(xy 146.698068 -56.461579) (xy 146.690312 -56.407631) (xy 146.689826 -56.38038) (xy 146.690274 -56.353009)
			(xy 146.698095 -56.298829) (xy 146.713588 -56.246325) (xy 146.736434 -56.196579) (xy 146.766163 -56.150613)
			(xy 146.783806 -56.129682) (xy 146.78406 -56.129428) (xy 146.789648 -56.122343) (xy 146.795892 -56.105425)
			(xy 146.796252 -56.096408) (xy 146.796252 -56.029352) (xy 146.795881 -56.020336) (xy 146.789644 -56.003419)
			(xy 146.78406 -55.996332) (xy 146.783806 -55.996332) (xy 146.783806 -55.996078) (xy 146.766147 -55.975161)
			(xy 146.736424 -55.92919) (xy 146.713581 -55.879441) (xy 146.698087 -55.826937) (xy 146.690261 -55.772756)
			(xy 146.690263 -55.718014) (xy 146.698094 -55.663834) (xy 146.713592 -55.611331) (xy 146.736439 -55.561584)
			(xy 146.766165 -55.515615) (xy 146.783806 -55.494682) (xy 146.78406 -55.494428) (xy 146.789648 -55.487343)
			(xy 146.795892 -55.470425) (xy 146.796252 -55.461408) (xy 146.796252 -55.394352) (xy 146.795881 -55.385336)
			(xy 146.789644 -55.368419) (xy 146.78406 -55.361332) (xy 146.783806 -55.360824) (xy 146.772863 -55.348089)
			(xy 146.753021 -55.320998) (xy 146.744182 -55.306722) (xy 146.738848 -55.297832) (xy 146.72183 -55.28564)
			(xy 146.628612 -55.26532) (xy 146.608038 -55.269638) (xy 146.599402 -55.27548) (xy 146.575338 -55.291479)
			(xy 146.523407 -55.316823) (xy 146.468249 -55.334049) (xy 146.411125 -55.342764) (xy 146.382232 -55.343298)
			(xy 146.354977 -55.342857) (xy 146.301021 -55.335104) (xy 146.248718 -55.31975) (xy 146.199132 -55.297109)
			(xy 146.153274 -55.267641) (xy 146.112076 -55.231946) (xy 146.076378 -55.190752) (xy 146.046906 -55.144896)
			(xy 146.024261 -55.095312) (xy 146.008903 -55.04301) (xy 146.001145 -54.989055) (xy 136.865169 -54.989055)
			(xy 136.858489 -54.999449) (xy 136.822798 -55.04064) (xy 136.781607 -55.076331) (xy 136.735757 -55.105797)
			(xy 136.68618 -55.128439) (xy 136.633885 -55.143794) (xy 136.579937 -55.15155) (xy 136.525435 -55.15155)
			(xy 136.471487 -55.143794) (xy 136.419192 -55.128439) (xy 136.369615 -55.105797) (xy 136.323765 -55.076331)
			(xy 136.282574 -55.04064) (xy 136.246883 -54.999449) (xy 136.217417 -54.953599) (xy 136.194775 -54.904022)
			(xy 136.17942 -54.851727) (xy 136.171664 -54.797779) (xy 136.171178 -54.770528) (xy 133.039257 -54.770528)
			(xy 133.039612 -54.791102) (xy 133.039126 -54.818353) (xy 133.03137 -54.872301) (xy 133.016015 -54.924596)
			(xy 132.993373 -54.974173) (xy 132.963907 -55.020023) (xy 132.928216 -55.061214) (xy 132.887025 -55.096905)
			(xy 132.841175 -55.126371) (xy 132.791598 -55.149013) (xy 132.739303 -55.164368) (xy 132.685355 -55.172124)
			(xy 132.630853 -55.172124) (xy 132.576905 -55.164368) (xy 132.52461 -55.149013) (xy 132.475033 -55.126371)
			(xy 132.429183 -55.096905) (xy 132.387992 -55.061214) (xy 132.352301 -55.020023) (xy 132.322835 -54.974173)
			(xy 132.300193 -54.924596) (xy 132.284838 -54.872301) (xy 132.277082 -54.818353) (xy 132.276596 -54.791102)
			(xy 130.378638 -54.791102) (xy 130.375546 -54.812611) (xy 130.360191 -54.864906) (xy 130.337549 -54.914483)
			(xy 130.308083 -54.960333) (xy 130.272392 -55.001524) (xy 130.231201 -55.037215) (xy 130.185351 -55.066681)
			(xy 130.135774 -55.089323) (xy 130.083479 -55.104678) (xy 130.029531 -55.112434) (xy 129.975029 -55.112434)
			(xy 129.921081 -55.104678) (xy 129.868786 -55.089323) (xy 129.819209 -55.066681) (xy 129.773359 -55.037215)
			(xy 129.732168 -55.001524) (xy 129.696477 -54.960333) (xy 129.667011 -54.914483) (xy 129.644369 -54.864906)
			(xy 129.629014 -54.812611) (xy 129.621258 -54.758663) (xy 129.620772 -54.731412) (xy 129.299716 -54.731412)
			(xy 129.299716 -55.722266) (xy 141.934182 -55.722266) (xy 141.938253 -55.666644) (xy 141.950379 -55.612207)
			(xy 141.970302 -55.560116) (xy 141.997598 -55.511481) (xy 142.031684 -55.467338) (xy 142.071833 -55.428629)
			(xy 142.117191 -55.396178) (xy 142.166791 -55.370677) (xy 142.219575 -55.35267) (xy 142.274418 -55.34254)
			(xy 142.330152 -55.340503) (xy 142.385589 -55.346603) (xy 142.439546 -55.360709) (xy 142.490875 -55.382521)
			(xy 142.538481 -55.411575) (xy 142.549632 -55.420855) (xy 144.324745 -55.420855) (xy 144.324745 -55.366345)
			(xy 144.332503 -55.31239) (xy 144.347861 -55.260088) (xy 144.370506 -55.210504) (xy 144.399978 -55.164648)
			(xy 144.435676 -55.123454) (xy 144.476874 -55.087759) (xy 144.522732 -55.058291) (xy 144.572318 -55.03565)
			(xy 144.624621 -55.020296) (xy 144.678577 -55.012543) (xy 144.705832 -55.012082) (xy 144.732146 -55.012534)
			(xy 144.784275 -55.019773) (xy 144.834918 -55.034095) (xy 144.883117 -55.055231) (xy 144.92796 -55.082779)
			(xy 144.968599 -55.11622) (xy 144.986756 -55.135272) (xy 144.994296 -55.142652) (xy 145.013562 -55.15119)
			(xy 145.024094 -55.151782) (xy 145.09877 -55.151782) (xy 145.10932 -55.151256) (xy 145.128616 -55.142719)
			(xy 145.136108 -55.135272) (xy 145.154261 -55.116214) (xy 145.194892 -55.082758) (xy 145.239733 -55.0552)
			(xy 145.287934 -55.034062) (xy 145.338582 -55.019745) (xy 145.390716 -55.012521) (xy 145.417032 -55.012082)
			(xy 145.444281 -55.01259) (xy 145.498224 -55.02035) (xy 145.550513 -55.035708) (xy 145.600085 -55.05835)
			(xy 145.64593 -55.087817) (xy 145.687116 -55.123507) (xy 145.722803 -55.164695) (xy 145.752265 -55.210543)
			(xy 145.774903 -55.260117) (xy 145.790256 -55.312408) (xy 145.798012 -55.366351) (xy 145.798012 -55.420849)
			(xy 145.790256 -55.474792) (xy 145.774903 -55.527083) (xy 145.752265 -55.576657) (xy 145.722803 -55.622505)
			(xy 145.687116 -55.663693) (xy 145.64593 -55.699383) (xy 145.600085 -55.72885) (xy 145.550513 -55.751492)
			(xy 145.498224 -55.76685) (xy 145.444281 -55.77461) (xy 145.417032 -55.775098) (xy 145.390716 -55.774677)
			(xy 145.338586 -55.767432) (xy 145.287942 -55.753104) (xy 145.239744 -55.731963) (xy 145.194901 -55.704409)
			(xy 145.154263 -55.670963) (xy 145.136108 -55.651908) (xy 145.128584 -55.644509) (xy 145.109306 -55.635983)
			(xy 145.09877 -55.635398) (xy 145.024094 -55.635398) (xy 145.013542 -55.635911) (xy 144.994247 -55.644457)
			(xy 144.986756 -55.651908) (xy 144.968616 -55.670979) (xy 144.927983 -55.704435) (xy 144.883139 -55.731992)
			(xy 144.834936 -55.753127) (xy 144.784285 -55.767441) (xy 144.732149 -55.774662) (xy 144.705832 -55.775098)
			(xy 144.678577 -55.774657) (xy 144.624621 -55.766904) (xy 144.572318 -55.75155) (xy 144.522732 -55.728909)
			(xy 144.476874 -55.699441) (xy 144.435676 -55.663746) (xy 144.399978 -55.622552) (xy 144.370506 -55.576696)
			(xy 144.347861 -55.527112) (xy 144.332503 -55.47481) (xy 144.324745 -55.420855) (xy 142.549632 -55.420855)
			(xy 142.581349 -55.44725) (xy 142.618566 -55.488787) (xy 142.649339 -55.5353) (xy 142.673011 -55.585797)
			(xy 142.689079 -55.639204) (xy 142.697199 -55.69438) (xy 142.697708 -55.722266) (xy 142.697199 -55.750152)
			(xy 142.689079 -55.805328) (xy 142.673011 -55.858735) (xy 142.649339 -55.909232) (xy 142.618566 -55.955745)
			(xy 142.581349 -55.997282) (xy 142.538481 -56.032957) (xy 142.490875 -56.062011) (xy 142.439546 -56.083823)
			(xy 142.385589 -56.097929) (xy 142.330152 -56.104029) (xy 142.274418 -56.101992) (xy 142.219575 -56.091862)
			(xy 142.166791 -56.073855) (xy 142.117191 -56.048354) (xy 142.071833 -56.015903) (xy 142.031684 -55.977194)
			(xy 141.997598 -55.933051) (xy 141.970302 -55.884416) (xy 141.950379 -55.832325) (xy 141.938253 -55.777888)
			(xy 141.934182 -55.722266) (xy 129.299716 -55.722266) (xy 129.299716 -57.002934) (xy 137.663682 -57.002934)
			(xy 137.664204 -56.974843) (xy 137.672426 -56.919268) (xy 137.688712 -56.865499) (xy 137.712711 -56.814702)
			(xy 137.743901 -56.767975) (xy 137.78161 -56.726329) (xy 137.825019 -56.690665) (xy 137.848848 -56.675782)
			(xy 137.857738 -56.670448) (xy 137.86993 -56.65343) (xy 137.89025 -56.560212) (xy 137.885932 -56.539638)
			(xy 137.88009 -56.531002) (xy 137.864087 -56.50694) (xy 137.838746 -56.455008) (xy 137.821521 -56.399849)
			(xy 137.812806 -56.342725) (xy 137.812272 -56.313832) (xy 137.812785 -56.286581) (xy 137.820537 -56.232633)
			(xy 137.835888 -56.180337) (xy 137.858525 -56.130758) (xy 137.887988 -56.084906) (xy 137.923677 -56.043714)
			(xy 137.964864 -56.008019) (xy 138.010713 -55.97855) (xy 138.060288 -55.955906) (xy 138.112582 -55.940548)
			(xy 138.166529 -55.932789) (xy 138.19378 -55.932324) (xy 138.22115 -55.932796) (xy 138.275329 -55.940611)
			(xy 138.327832 -55.956099) (xy 138.377579 -55.978939) (xy 138.423546 -56.008663) (xy 138.444478 -56.026304)
			(xy 138.444732 -56.026558) (xy 138.451829 -56.032129) (xy 138.468738 -56.038384) (xy 138.477752 -56.03875)
			(xy 138.544808 -56.03875) (xy 138.553827 -56.038407) (xy 138.570744 -56.032151) (xy 138.577828 -56.026558)
			(xy 138.577828 -56.026304) (xy 138.578082 -56.026304) (xy 138.599015 -56.008663) (xy 138.644983 -55.978939)
			(xy 138.694729 -55.956093) (xy 138.747231 -55.940597) (xy 138.801409 -55.932768) (xy 138.856151 -55.932768)
			(xy 138.910329 -55.940597) (xy 138.962831 -55.956093) (xy 139.012577 -55.978939) (xy 139.058545 -56.008663)
			(xy 139.079478 -56.026304) (xy 139.079732 -56.026558) (xy 139.086829 -56.032129) (xy 139.103738 -56.038384)
			(xy 139.112752 -56.03875) (xy 139.179808 -56.03875) (xy 139.188827 -56.038407) (xy 139.205744 -56.032151)
			(xy 139.212828 -56.026558) (xy 139.212828 -56.026304) (xy 139.213082 -56.026304) (xy 139.234011 -56.008661)
			(xy 139.279984 -55.978949) (xy 139.329733 -55.956114) (xy 139.382234 -55.940624) (xy 139.436411 -55.932797)
			(xy 139.46378 -55.932324) (xy 139.491036 -55.932722) (xy 139.544994 -55.940477) (xy 139.597298 -55.955832)
			(xy 139.646885 -55.978476) (xy 139.692745 -56.007946) (xy 139.733943 -56.043642) (xy 139.769642 -56.084839)
			(xy 139.799115 -56.130697) (xy 139.821761 -56.180283) (xy 139.837119 -56.232587) (xy 139.844877 -56.286544)
			(xy 139.844877 -56.297068) (xy 140.186662 -56.297068) (xy 140.190733 -56.241446) (xy 140.202859 -56.187009)
			(xy 140.222782 -56.134918) (xy 140.250078 -56.086283) (xy 140.284164 -56.04214) (xy 140.324313 -56.003431)
			(xy 140.369671 -55.97098) (xy 140.419271 -55.945479) (xy 140.472055 -55.927472) (xy 140.526898 -55.917342)
			(xy 140.582632 -55.915305) (xy 140.638069 -55.921405) (xy 140.692026 -55.935511) (xy 140.743355 -55.957323)
			(xy 140.790961 -55.986377) (xy 140.833829 -56.022052) (xy 140.871046 -56.063589) (xy 140.901819 -56.110102)
			(xy 140.925491 -56.160599) (xy 140.941559 -56.214006) (xy 140.949679 -56.269182) (xy 140.950188 -56.297068)
			(xy 140.949679 -56.324954) (xy 140.941559 -56.38013) (xy 140.925491 -56.433537) (xy 140.901819 -56.484034)
			(xy 140.871046 -56.530547) (xy 140.833829 -56.572084) (xy 140.790961 -56.607759) (xy 140.743355 -56.636813)
			(xy 140.692026 -56.658625) (xy 140.638069 -56.672731) (xy 140.582632 -56.678831) (xy 140.526898 -56.676794)
			(xy 140.472055 -56.666664) (xy 140.419271 -56.648657) (xy 140.369671 -56.623156) (xy 140.324313 -56.590705)
			(xy 140.284164 -56.551996) (xy 140.250078 -56.507853) (xy 140.222782 -56.459218) (xy 140.202859 -56.407127)
			(xy 140.190733 -56.35269) (xy 140.186662 -56.297068) (xy 139.844877 -56.297068) (xy 139.844877 -56.341056)
			(xy 139.837119 -56.395013) (xy 139.821761 -56.447317) (xy 139.799115 -56.496903) (xy 139.769642 -56.542761)
			(xy 139.733943 -56.583958) (xy 139.692745 -56.619654) (xy 139.646885 -56.649124) (xy 139.597298 -56.671768)
			(xy 139.544994 -56.687123) (xy 139.491036 -56.694878) (xy 139.46378 -56.69534) (xy 139.436409 -56.6949)
			(xy 139.382228 -56.687078) (xy 139.329724 -56.671584) (xy 139.279977 -56.648736) (xy 139.234012 -56.619005)
			(xy 139.213082 -56.60136) (xy 139.212828 -56.601106) (xy 139.205737 -56.595526) (xy 139.188824 -56.589275)
			(xy 139.179808 -56.588914) (xy 139.112752 -56.588914) (xy 139.103737 -56.589293) (xy 139.08682 -56.595525)
			(xy 139.079732 -56.601106) (xy 139.079732 -56.60136) (xy 139.079478 -56.60136) (xy 139.058545 -56.619001)
			(xy 139.012577 -56.648725) (xy 138.962831 -56.671571) (xy 138.910329 -56.687067) (xy 138.856151 -56.694896)
			(xy 138.801409 -56.694896) (xy 138.747231 -56.687067) (xy 138.694729 -56.671571) (xy 138.644983 -56.648725)
			(xy 138.599015 -56.619001) (xy 138.578082 -56.60136) (xy 138.577828 -56.601106) (xy 138.570737 -56.595526)
			(xy 138.553824 -56.589275) (xy 138.544808 -56.588914) (xy 138.477752 -56.588914) (xy 138.468737 -56.589293)
			(xy 138.45182 -56.595525) (xy 138.444732 -56.601106) (xy 138.444224 -56.60136) (xy 138.431492 -56.612307)
			(xy 138.404399 -56.632146) (xy 138.390122 -56.640984) (xy 138.381232 -56.646318) (xy 138.36904 -56.663336)
			(xy 138.34872 -56.756554) (xy 138.353038 -56.777128) (xy 138.35888 -56.785764) (xy 138.374865 -56.809838)
			(xy 138.400211 -56.861765) (xy 138.417441 -56.91692) (xy 138.426161 -56.974042) (xy 138.426698 -57.002934)
			(xy 138.426212 -57.030185) (xy 138.418456 -57.084133) (xy 138.403101 -57.136428) (xy 138.380459 -57.186005)
			(xy 138.350993 -57.231855) (xy 138.315302 -57.273046) (xy 138.274111 -57.308737) (xy 138.228261 -57.338203)
			(xy 138.178684 -57.360845) (xy 138.126389 -57.3762) (xy 138.072441 -57.383956) (xy 138.017939 -57.383956)
			(xy 137.963991 -57.3762) (xy 137.911696 -57.360845) (xy 137.862119 -57.338203) (xy 137.816269 -57.308737)
			(xy 137.775078 -57.273046) (xy 137.739387 -57.231855) (xy 137.709921 -57.186005) (xy 137.687279 -57.136428)
			(xy 137.671924 -57.084133) (xy 137.664168 -57.030185) (xy 137.663682 -57.002934) (xy 129.299716 -57.002934)
			(xy 129.299716 -57.48528) (xy 146.70608 -57.48528) (xy 146.710151 -57.429658) (xy 146.722277 -57.375221)
			(xy 146.7422 -57.32313) (xy 146.769496 -57.274495) (xy 146.803582 -57.230352) (xy 146.843731 -57.191643)
			(xy 146.889089 -57.159192) (xy 146.938689 -57.133691) (xy 146.991473 -57.115684) (xy 147.046316 -57.105554)
			(xy 147.10205 -57.103517) (xy 147.157487 -57.109617) (xy 147.211444 -57.123723) (xy 147.262773 -57.145535)
			(xy 147.310379 -57.174589) (xy 147.353247 -57.210264) (xy 147.390464 -57.251801) (xy 147.421237 -57.298314)
			(xy 147.444909 -57.348811) (xy 147.460977 -57.402218) (xy 147.469097 -57.457394) (xy 147.469606 -57.48528)
			(xy 147.469097 -57.513166) (xy 147.460977 -57.568342) (xy 147.444909 -57.621749) (xy 147.421237 -57.672246)
			(xy 147.390464 -57.718759) (xy 147.353247 -57.760296) (xy 147.310379 -57.795971) (xy 147.262773 -57.825025)
			(xy 147.211444 -57.846837) (xy 147.157487 -57.860943) (xy 147.10205 -57.867043) (xy 147.046316 -57.865006)
			(xy 146.991473 -57.854876) (xy 146.938689 -57.836869) (xy 146.889089 -57.811368) (xy 146.843731 -57.778917)
			(xy 146.803582 -57.740208) (xy 146.769496 -57.696065) (xy 146.7422 -57.64743) (xy 146.722277 -57.595339)
			(xy 146.710151 -57.540902) (xy 146.70608 -57.48528) (xy 129.299716 -57.48528) (xy 129.299716 -58.679334)
			(xy 138.095482 -58.679334) (xy 138.095911 -58.653019) (xy 138.103155 -58.600889) (xy 138.117482 -58.550246)
			(xy 138.138621 -58.502047) (xy 138.166174 -58.457204) (xy 138.199618 -58.416566) (xy 138.218672 -58.39841)
			(xy 138.226067 -58.390883) (xy 138.234596 -58.371607) (xy 138.235182 -58.361072) (xy 138.235182 -58.286396)
			(xy 138.234674 -58.275844) (xy 138.226124 -58.256548) (xy 138.218672 -58.249058) (xy 138.199598 -58.230921)
			(xy 138.166143 -58.190287) (xy 138.138588 -58.145443) (xy 138.117453 -58.097238) (xy 138.103139 -58.046588)
			(xy 138.095918 -57.994451) (xy 138.095482 -57.968134) (xy 138.095968 -57.940883) (xy 138.103724 -57.886935)
			(xy 138.119079 -57.83464) (xy 138.141721 -57.785063) (xy 138.171187 -57.739213) (xy 138.206878 -57.698022)
			(xy 138.248069 -57.662331) (xy 138.293919 -57.632865) (xy 138.343496 -57.610223) (xy 138.395791 -57.594868)
			(xy 138.449739 -57.587112) (xy 138.504241 -57.587112) (xy 138.558189 -57.594868) (xy 138.610484 -57.610223)
			(xy 138.660061 -57.632865) (xy 138.705911 -57.662331) (xy 138.747102 -57.698022) (xy 138.782793 -57.739213)
			(xy 138.812259 -57.785063) (xy 138.834901 -57.83464) (xy 138.850256 -57.886935) (xy 138.858012 -57.940883)
			(xy 138.858498 -57.968134) (xy 138.858054 -57.994449) (xy 138.850814 -58.046578) (xy 138.843547 -58.072274)
			(xy 142.093694 -58.072274) (xy 142.097765 -58.016652) (xy 142.109891 -57.962215) (xy 142.129814 -57.910124)
			(xy 142.15711 -57.861489) (xy 142.191196 -57.817346) (xy 142.231345 -57.778637) (xy 142.276703 -57.746186)
			(xy 142.326303 -57.720685) (xy 142.379087 -57.702678) (xy 142.43393 -57.692548) (xy 142.489664 -57.690511)
			(xy 142.545101 -57.696611) (xy 142.599058 -57.710717) (xy 142.650387 -57.732529) (xy 142.697993 -57.761583)
			(xy 142.740861 -57.797258) (xy 142.778078 -57.838795) (xy 142.808851 -57.885308) (xy 142.832523 -57.935805)
			(xy 142.848591 -57.989212) (xy 142.856711 -58.044388) (xy 142.85722 -58.072274) (xy 142.85715 -58.076084)
			(xy 147.458174 -58.076084) (xy 147.462245 -58.020462) (xy 147.474371 -57.966025) (xy 147.494294 -57.913934)
			(xy 147.52159 -57.865299) (xy 147.555676 -57.821156) (xy 147.595825 -57.782447) (xy 147.641183 -57.749996)
			(xy 147.690783 -57.724495) (xy 147.743567 -57.706488) (xy 147.79841 -57.696358) (xy 147.854144 -57.694321)
			(xy 147.909581 -57.700421) (xy 147.963538 -57.714527) (xy 148.014867 -57.736339) (xy 148.062473 -57.765393)
			(xy 148.105341 -57.801068) (xy 148.142558 -57.842605) (xy 148.158894 -57.867296) (xy 149.743158 -57.867296)
			(xy 149.747229 -57.811674) (xy 149.759355 -57.757237) (xy 149.779278 -57.705146) (xy 149.806574 -57.656511)
			(xy 149.84066 -57.612368) (xy 149.880809 -57.573659) (xy 149.926167 -57.541208) (xy 149.975767 -57.515707)
			(xy 150.028551 -57.4977) (xy 150.083394 -57.48757) (xy 150.139128 -57.485533) (xy 150.194565 -57.491633)
			(xy 150.248522 -57.505739) (xy 150.299851 -57.527551) (xy 150.347457 -57.556605) (xy 150.390325 -57.59228)
			(xy 150.427542 -57.633817) (xy 150.458315 -57.68033) (xy 150.481987 -57.730827) (xy 150.498055 -57.784234)
			(xy 150.506175 -57.83941) (xy 150.506684 -57.867296) (xy 150.506175 -57.895182) (xy 150.498055 -57.950358)
			(xy 150.481987 -58.003765) (xy 150.458315 -58.054262) (xy 150.427542 -58.100775) (xy 150.390325 -58.142312)
			(xy 150.347457 -58.177987) (xy 150.299851 -58.207041) (xy 150.248522 -58.228853) (xy 150.194565 -58.242959)
			(xy 150.139128 -58.249059) (xy 150.083394 -58.247022) (xy 150.028551 -58.236892) (xy 149.975767 -58.218885)
			(xy 149.926167 -58.193384) (xy 149.880809 -58.160933) (xy 149.84066 -58.122224) (xy 149.806574 -58.078081)
			(xy 149.779278 -58.029446) (xy 149.759355 -57.977355) (xy 149.747229 -57.922918) (xy 149.743158 -57.867296)
			(xy 148.158894 -57.867296) (xy 148.173331 -57.889118) (xy 148.197003 -57.939615) (xy 148.213071 -57.993022)
			(xy 148.221191 -58.048198) (xy 148.2217 -58.076084) (xy 148.221191 -58.10397) (xy 148.213071 -58.159146)
			(xy 148.197003 -58.212553) (xy 148.173331 -58.26305) (xy 148.142558 -58.309563) (xy 148.105341 -58.3511)
			(xy 148.062473 -58.386775) (xy 148.014867 -58.415829) (xy 147.963538 -58.437641) (xy 147.909581 -58.451747)
			(xy 147.854144 -58.457847) (xy 147.79841 -58.45581) (xy 147.743567 -58.44568) (xy 147.690783 -58.427673)
			(xy 147.641183 -58.402172) (xy 147.595825 -58.369721) (xy 147.555676 -58.331012) (xy 147.52159 -58.286869)
			(xy 147.494294 -58.238234) (xy 147.474371 -58.186143) (xy 147.462245 -58.131706) (xy 147.458174 -58.076084)
			(xy 142.85715 -58.076084) (xy 142.856711 -58.10016) (xy 142.848591 -58.155336) (xy 142.832523 -58.208743)
			(xy 142.808851 -58.25924) (xy 142.778078 -58.305753) (xy 142.740861 -58.34729) (xy 142.697993 -58.382965)
			(xy 142.650387 -58.412019) (xy 142.599058 -58.433831) (xy 142.545101 -58.447937) (xy 142.489664 -58.454037)
			(xy 142.43393 -58.452) (xy 142.379087 -58.44187) (xy 142.326303 -58.423863) (xy 142.276703 -58.398362)
			(xy 142.231345 -58.365911) (xy 142.191196 -58.327202) (xy 142.15711 -58.283059) (xy 142.129814 -58.234424)
			(xy 142.109891 -58.182333) (xy 142.097765 -58.127896) (xy 142.093694 -58.072274) (xy 138.843547 -58.072274)
			(xy 138.836491 -58.097221) (xy 138.815354 -58.14542) (xy 138.787804 -58.190263) (xy 138.754361 -58.230902)
			(xy 138.735308 -58.249058) (xy 138.727924 -58.256594) (xy 138.719389 -58.275863) (xy 138.718798 -58.286396)
			(xy 138.718798 -58.361072) (xy 138.719329 -58.371621) (xy 138.727863 -58.390917) (xy 138.735308 -58.39841)
			(xy 138.754363 -58.416566) (xy 138.78782 -58.457196) (xy 138.815379 -58.502036) (xy 138.836517 -58.550237)
			(xy 138.839623 -58.561224) (xy 148.662388 -58.561224) (xy 148.666459 -58.505602) (xy 148.678585 -58.451165)
			(xy 148.698508 -58.399074) (xy 148.725804 -58.350439) (xy 148.75989 -58.306296) (xy 148.800039 -58.267587)
			(xy 148.845397 -58.235136) (xy 148.894997 -58.209635) (xy 148.947781 -58.191628) (xy 149.002624 -58.181498)
			(xy 149.058358 -58.179461) (xy 149.113795 -58.185561) (xy 149.167752 -58.199667) (xy 149.219081 -58.221479)
			(xy 149.266687 -58.250533) (xy 149.309555 -58.286208) (xy 149.346772 -58.327745) (xy 149.377545 -58.374258)
			(xy 149.401217 -58.424755) (xy 149.408727 -58.449718) (xy 150.909018 -58.449718) (xy 150.913089 -58.394096)
			(xy 150.925215 -58.339659) (xy 150.945138 -58.287568) (xy 150.972434 -58.238933) (xy 151.00652 -58.19479)
			(xy 151.046669 -58.156081) (xy 151.092027 -58.12363) (xy 151.141627 -58.098129) (xy 151.194411 -58.080122)
			(xy 151.249254 -58.069992) (xy 151.304988 -58.067955) (xy 151.360425 -58.074055) (xy 151.414382 -58.088161)
			(xy 151.465711 -58.109973) (xy 151.513317 -58.139027) (xy 151.556185 -58.174702) (xy 151.593402 -58.216239)
			(xy 151.624175 -58.262752) (xy 151.647847 -58.313249) (xy 151.663915 -58.366656) (xy 151.672035 -58.421832)
			(xy 151.672544 -58.449718) (xy 151.672035 -58.477604) (xy 151.663915 -58.53278) (xy 151.647847 -58.586187)
			(xy 151.624175 -58.636684) (xy 151.593402 -58.683197) (xy 151.556185 -58.724734) (xy 151.513317 -58.760409)
			(xy 151.465711 -58.789463) (xy 151.414382 -58.811275) (xy 151.360425 -58.825381) (xy 151.304988 -58.831481)
			(xy 151.249254 -58.829444) (xy 151.194411 -58.819314) (xy 151.141627 -58.801307) (xy 151.092027 -58.775806)
			(xy 151.046669 -58.743355) (xy 151.00652 -58.704646) (xy 150.972434 -58.660503) (xy 150.945138 -58.611868)
			(xy 150.925215 -58.559777) (xy 150.913089 -58.50534) (xy 150.909018 -58.449718) (xy 149.408727 -58.449718)
			(xy 149.417285 -58.478162) (xy 149.425405 -58.533338) (xy 149.425914 -58.561224) (xy 149.425405 -58.58911)
			(xy 149.417285 -58.644286) (xy 149.401217 -58.697693) (xy 149.377545 -58.74819) (xy 149.346772 -58.794703)
			(xy 149.309555 -58.83624) (xy 149.266687 -58.871915) (xy 149.219081 -58.900969) (xy 149.167752 -58.922781)
			(xy 149.113795 -58.936887) (xy 149.058358 -58.942987) (xy 149.002624 -58.94095) (xy 148.947781 -58.93082)
			(xy 148.894997 -58.912813) (xy 148.845397 -58.887312) (xy 148.800039 -58.854861) (xy 148.75989 -58.816152)
			(xy 148.725804 -58.772009) (xy 148.698508 -58.723374) (xy 148.678585 -58.671283) (xy 148.666459 -58.616846)
			(xy 148.662388 -58.561224) (xy 138.839623 -58.561224) (xy 138.850835 -58.600884) (xy 138.858059 -58.653018)
			(xy 138.858498 -58.679334) (xy 138.858012 -58.706585) (xy 138.850256 -58.760533) (xy 138.834901 -58.812828)
			(xy 138.812259 -58.862405) (xy 138.782793 -58.908255) (xy 138.747102 -58.949446) (xy 138.705911 -58.985137)
			(xy 138.660061 -59.014603) (xy 138.610484 -59.037245) (xy 138.558189 -59.0526) (xy 138.504241 -59.060356)
			(xy 138.449739 -59.060356) (xy 138.395791 -59.0526) (xy 138.343496 -59.037245) (xy 138.293919 -59.014603)
			(xy 138.248069 -58.985137) (xy 138.206878 -58.949446) (xy 138.171187 -58.908255) (xy 138.141721 -58.862405)
			(xy 138.119079 -58.812828) (xy 138.103724 -58.760533) (xy 138.095968 -58.706585) (xy 138.095482 -58.679334)
			(xy 129.299716 -58.679334) (xy 129.299716 -59.174634) (xy 147.193252 -59.174634) (xy 147.197323 -59.119012)
			(xy 147.209449 -59.064575) (xy 147.229372 -59.012484) (xy 147.256668 -58.963849) (xy 147.290754 -58.919706)
			(xy 147.330903 -58.880997) (xy 147.376261 -58.848546) (xy 147.425861 -58.823045) (xy 147.478645 -58.805038)
			(xy 147.533488 -58.794908) (xy 147.589222 -58.792871) (xy 147.644659 -58.798971) (xy 147.698616 -58.813077)
			(xy 147.749945 -58.834889) (xy 147.797551 -58.863943) (xy 147.840419 -58.899618) (xy 147.877636 -58.941155)
			(xy 147.908409 -58.987668) (xy 147.932081 -59.038165) (xy 147.948149 -59.091572) (xy 147.956269 -59.146748)
			(xy 147.956778 -59.174634) (xy 147.956269 -59.20252) (xy 147.948149 -59.257696) (xy 147.932081 -59.311103)
			(xy 147.908409 -59.3616) (xy 147.877636 -59.408113) (xy 147.840419 -59.44965) (xy 147.797551 -59.485325)
			(xy 147.749945 -59.514379) (xy 147.698616 -59.536191) (xy 147.644659 -59.550297) (xy 147.589222 -59.556397)
			(xy 147.533488 -59.55436) (xy 147.478645 -59.54423) (xy 147.425861 -59.526223) (xy 147.376261 -59.500722)
			(xy 147.330903 -59.468271) (xy 147.290754 -59.429562) (xy 147.256668 -59.385419) (xy 147.229372 -59.336784)
			(xy 147.209449 -59.284693) (xy 147.197323 -59.230256) (xy 147.193252 -59.174634) (xy 129.299716 -59.174634)
			(xy 129.299716 -60.019254) (xy 138.235861 -60.019254) (xy 138.235861 -59.964746) (xy 138.243619 -59.910792)
			(xy 138.258977 -59.858491) (xy 138.281623 -59.808909) (xy 138.311094 -59.763054) (xy 138.346792 -59.721861)
			(xy 138.38799 -59.686168) (xy 138.433848 -59.656702) (xy 138.483432 -59.634062) (xy 138.535735 -59.61871)
			(xy 138.58969 -59.610958) (xy 138.616944 -59.610498) (xy 138.644313 -59.610997) (xy 138.698491 -59.618807)
			(xy 138.750993 -59.634289) (xy 138.800741 -59.657123) (xy 138.846709 -59.68684) (xy 138.867642 -59.704478)
			(xy 138.867896 -59.704732) (xy 138.874977 -59.710327) (xy 138.891898 -59.716567) (xy 138.900916 -59.716924)
			(xy 138.967972 -59.716924) (xy 138.976987 -59.716548) (xy 138.993904 -59.710313) (xy 139.000992 -59.704732)
			(xy 139.000992 -59.704478) (xy 139.001246 -59.704478) (xy 139.022179 -59.686837) (xy 139.068147 -59.657113)
			(xy 139.117893 -59.634267) (xy 139.170395 -59.618771) (xy 139.224573 -59.610942) (xy 139.279315 -59.610942)
			(xy 139.333493 -59.618771) (xy 139.385995 -59.634267) (xy 139.435741 -59.657113) (xy 139.481709 -59.686837)
			(xy 139.502642 -59.704478) (xy 139.502896 -59.704732) (xy 139.509977 -59.710327) (xy 139.526898 -59.716567)
			(xy 139.535916 -59.716924) (xy 139.602972 -59.716924) (xy 139.611987 -59.716548) (xy 139.628904 -59.710313)
			(xy 139.635992 -59.704732) (xy 139.635992 -59.704478) (xy 139.636246 -59.704478) (xy 139.657185 -59.686847)
			(xy 139.703156 -59.657135) (xy 139.752902 -59.634298) (xy 139.805401 -59.618805) (xy 139.859575 -59.610974)
			(xy 139.886944 -59.610498) (xy 139.914194 -59.610975) (xy 139.968137 -59.618737) (xy 140.020428 -59.634096)
			(xy 140.07 -59.65674) (xy 140.115846 -59.686208) (xy 140.157031 -59.7219) (xy 140.192719 -59.763089)
			(xy 140.222181 -59.808938) (xy 140.24482 -59.858514) (xy 140.260173 -59.910806) (xy 140.267928 -59.96475)
			(xy 140.267928 -60.01925) (xy 140.260173 -60.073194) (xy 140.24482 -60.125486) (xy 140.222181 -60.175062)
			(xy 140.192719 -60.220911) (xy 140.157031 -60.2621) (xy 140.115846 -60.297792) (xy 140.07 -60.32726)
			(xy 140.020428 -60.349904) (xy 139.968137 -60.365263) (xy 139.914194 -60.373025) (xy 139.886944 -60.373514)
			(xy 139.859575 -60.373019) (xy 139.805397 -60.365207) (xy 139.752894 -60.349725) (xy 139.703147 -60.32689)
			(xy 139.657179 -60.297172) (xy 139.636246 -60.279534) (xy 139.635992 -60.27928) (xy 139.628914 -60.273682)
			(xy 139.61199 -60.267443) (xy 139.602972 -60.267088) (xy 139.535916 -60.267088) (xy 139.5269 -60.267455)
			(xy 139.509983 -60.273696) (xy 139.502896 -60.27928) (xy 139.502642 -60.279534) (xy 139.481709 -60.297175)
			(xy 139.435741 -60.326899) (xy 139.385995 -60.349745) (xy 139.333493 -60.365241) (xy 139.279315 -60.37307)
			(xy 139.224573 -60.37307) (xy 139.170395 -60.365241) (xy 139.117893 -60.349745) (xy 139.068147 -60.326899)
			(xy 139.022179 -60.297175) (xy 139.001246 -60.279534) (xy 139.000992 -60.27928) (xy 138.993914 -60.273682)
			(xy 138.97699 -60.267443) (xy 138.967972 -60.267088) (xy 138.900916 -60.267088) (xy 138.8919 -60.267455)
			(xy 138.874983 -60.273696) (xy 138.867896 -60.27928) (xy 138.867896 -60.279534) (xy 138.867642 -60.279534)
			(xy 138.846709 -60.297172) (xy 138.800736 -60.326883) (xy 138.750989 -60.349719) (xy 138.698488 -60.36521)
			(xy 138.644313 -60.373039) (xy 138.616944 -60.373514) (xy 138.58969 -60.373042) (xy 138.535735 -60.36529)
			(xy 138.483432 -60.349938) (xy 138.433847 -60.327298) (xy 138.38799 -60.297832) (xy 138.346792 -60.262139)
			(xy 138.311094 -60.220946) (xy 138.281623 -60.175091) (xy 138.258977 -60.125509) (xy 138.243619 -60.073208)
			(xy 138.235861 -60.019254) (xy 129.299716 -60.019254) (xy 129.299716 -60.633356) (xy 149.897082 -60.633356)
			(xy 149.901153 -60.577734) (xy 149.913279 -60.523297) (xy 149.933202 -60.471206) (xy 149.960498 -60.422571)
			(xy 149.994584 -60.378428) (xy 150.034733 -60.339719) (xy 150.080091 -60.307268) (xy 150.129691 -60.281767)
			(xy 150.182475 -60.26376) (xy 150.237318 -60.25363) (xy 150.293052 -60.251593) (xy 150.348489 -60.257693)
			(xy 150.402446 -60.271799) (xy 150.453775 -60.293611) (xy 150.501381 -60.322665) (xy 150.544249 -60.35834)
			(xy 150.581466 -60.399877) (xy 150.612239 -60.44639) (xy 150.635911 -60.496887) (xy 150.651979 -60.550294)
			(xy 150.660099 -60.60547) (xy 150.660608 -60.633356) (xy 150.660099 -60.661242) (xy 150.651979 -60.716418)
			(xy 150.635911 -60.769825) (xy 150.612239 -60.820322) (xy 150.581466 -60.866835) (xy 150.544249 -60.908372)
			(xy 150.501381 -60.944047) (xy 150.453775 -60.973101) (xy 150.402446 -60.994913) (xy 150.348489 -61.009019)
			(xy 150.293052 -61.015119) (xy 150.237318 -61.013082) (xy 150.182475 -61.002952) (xy 150.129691 -60.984945)
			(xy 150.080091 -60.959444) (xy 150.034733 -60.926993) (xy 149.994584 -60.888284) (xy 149.960498 -60.844141)
			(xy 149.933202 -60.795506) (xy 149.913279 -60.743415) (xy 149.901153 -60.688978) (xy 149.897082 -60.633356)
			(xy 129.299716 -60.633356) (xy 129.299716 -61.487812) (xy 148.404578 -61.487812) (xy 148.408649 -61.43219)
			(xy 148.420775 -61.377753) (xy 148.440698 -61.325662) (xy 148.467994 -61.277027) (xy 148.50208 -61.232884)
			(xy 148.542229 -61.194175) (xy 148.587587 -61.161724) (xy 148.637187 -61.136223) (xy 148.689971 -61.118216)
			(xy 148.744814 -61.108086) (xy 148.800548 -61.106049) (xy 148.855985 -61.112149) (xy 148.909942 -61.126255)
			(xy 148.961271 -61.148067) (xy 149.008877 -61.177121) (xy 149.051745 -61.212796) (xy 149.088962 -61.254333)
			(xy 149.119735 -61.300846) (xy 149.143407 -61.351343) (xy 149.159475 -61.40475) (xy 149.167595 -61.459926)
			(xy 149.168104 -61.487812) (xy 149.167595 -61.515698) (xy 149.159475 -61.570874) (xy 149.143407 -61.624281)
			(xy 149.119735 -61.674778) (xy 149.088962 -61.721291) (xy 149.051745 -61.762828) (xy 149.008877 -61.798503)
			(xy 148.961271 -61.827557) (xy 148.909942 -61.849369) (xy 148.855985 -61.863475) (xy 148.800548 -61.869575)
			(xy 148.744814 -61.867538) (xy 148.689971 -61.857408) (xy 148.637187 -61.839401) (xy 148.587587 -61.8139)
			(xy 148.542229 -61.781449) (xy 148.50208 -61.74274) (xy 148.467994 -61.698597) (xy 148.440698 -61.649962)
			(xy 148.420775 -61.597871) (xy 148.408649 -61.543434) (xy 148.404578 -61.487812) (xy 129.299716 -61.487812)
			(xy 129.299716 -62.121034) (xy 146.342352 -62.121034) (xy 146.346423 -62.065412) (xy 146.358549 -62.010975)
			(xy 146.378472 -61.958884) (xy 146.405768 -61.910249) (xy 146.439854 -61.866106) (xy 146.480003 -61.827397)
			(xy 146.525361 -61.794946) (xy 146.574961 -61.769445) (xy 146.627745 -61.751438) (xy 146.682588 -61.741308)
			(xy 146.738322 -61.739271) (xy 146.793759 -61.745371) (xy 146.847716 -61.759477) (xy 146.899045 -61.781289)
			(xy 146.946651 -61.810343) (xy 146.989519 -61.846018) (xy 147.026736 -61.887555) (xy 147.057509 -61.934068)
			(xy 147.081181 -61.984565) (xy 147.097249 -62.037972) (xy 147.105369 -62.093148) (xy 147.105878 -62.121034)
			(xy 147.105369 -62.14892) (xy 147.097249 -62.204096) (xy 147.081181 -62.257503) (xy 147.057509 -62.308)
			(xy 147.026736 -62.354513) (xy 146.989519 -62.39605) (xy 146.946651 -62.431725) (xy 146.899045 -62.460779)
			(xy 146.847716 -62.482591) (xy 146.793759 -62.496697) (xy 146.738322 -62.502797) (xy 146.682588 -62.50076)
			(xy 146.627745 -62.49063) (xy 146.574961 -62.472623) (xy 146.525361 -62.447122) (xy 146.480003 -62.414671)
			(xy 146.439854 -62.375962) (xy 146.405768 -62.331819) (xy 146.378472 -62.283184) (xy 146.358549 -62.231093)
			(xy 146.346423 -62.176656) (xy 146.342352 -62.121034) (xy 129.299716 -62.121034) (xy 129.299716 -62.678767)
			(xy 149.766272 -62.678767) (xy 149.774026 -62.624819) (xy 149.789379 -62.572524) (xy 149.812017 -62.522946)
			(xy 149.841481 -62.477094) (xy 149.87717 -62.435901) (xy 149.918358 -62.400207) (xy 149.964206 -62.370738)
			(xy 150.013782 -62.348094) (xy 150.066076 -62.332736) (xy 150.120023 -62.324976) (xy 150.147274 -62.324488)
			(xy 150.170828 -62.324873) (xy 150.217573 -62.330727) (xy 150.240492 -62.336172) (xy 150.254259 -62.339155)
			(xy 150.282405 -62.338311) (xy 150.309251 -62.329815) (xy 150.332757 -62.314312) (xy 150.351138 -62.292981)
			(xy 150.362997 -62.267442) (xy 150.367433 -62.239635) (xy 150.364108 -62.211674) (xy 150.35911 -62.198504)
			(xy 150.349797 -62.175115) (xy 150.336673 -62.126514) (xy 150.330051 -62.076609) (xy 150.329646 -62.051438)
			(xy 150.330114 -62.024181) (xy 150.337867 -61.970221) (xy 150.353221 -61.917915) (xy 150.375863 -61.868325)
			(xy 150.405332 -61.822463) (xy 150.441028 -61.781262) (xy 150.482225 -61.745561) (xy 150.528083 -61.716086)
			(xy 150.57767 -61.693438) (xy 150.629975 -61.678078) (xy 150.683933 -61.670318) (xy 150.738447 -61.670316)
			(xy 150.792406 -61.678073) (xy 150.844712 -61.693431) (xy 150.894299 -61.716077) (xy 150.940159 -61.745549)
			(xy 150.981358 -61.781248) (xy 151.017056 -61.822447) (xy 151.046527 -61.868308) (xy 151.069172 -61.917896)
			(xy 151.084528 -61.970202) (xy 151.092284 -62.024161) (xy 151.092282 -62.078675) (xy 151.084521 -62.132633)
			(xy 151.069159 -62.184938) (xy 151.04651 -62.234524) (xy 151.017034 -62.280382) (xy 150.981332 -62.321577)
			(xy 150.94013 -62.357273) (xy 150.894268 -62.386741) (xy 150.844678 -62.409382) (xy 150.792371 -62.424734)
			(xy 150.738411 -62.432486) (xy 150.711154 -62.432946) (xy 150.687599 -62.432573) (xy 150.640855 -62.426711)
			(xy 150.617936 -62.421262) (xy 150.60417 -62.418261) (xy 150.576018 -62.419098) (xy 150.549165 -62.427592)
			(xy 150.525652 -62.443096) (xy 150.507268 -62.464433) (xy 150.49541 -62.489979) (xy 150.490979 -62.517793)
			(xy 150.494313 -62.545759) (xy 150.499318 -62.55893) (xy 150.508643 -62.582314) (xy 150.521762 -62.630918)
			(xy 150.528379 -62.680824) (xy 150.528782 -62.705996) (xy 150.528327 -62.733247) (xy 150.520571 -62.787195)
			(xy 150.505216 -62.83949) (xy 150.482576 -62.889067) (xy 150.453111 -62.934918) (xy 150.41742 -62.976109)
			(xy 150.37623 -63.011801) (xy 150.330381 -63.041269) (xy 150.280804 -63.063911) (xy 150.22851 -63.079267)
			(xy 150.174563 -63.087025) (xy 150.12006 -63.087027) (xy 150.066112 -63.079272) (xy 150.013817 -63.063919)
			(xy 149.964239 -63.041279) (xy 149.918388 -63.011815) (xy 149.877196 -62.976125) (xy 149.841503 -62.934936)
			(xy 149.812035 -62.889087) (xy 149.789392 -62.839511) (xy 149.774034 -62.787217) (xy 149.766275 -62.73327)
			(xy 149.766272 -62.678767) (xy 129.299716 -62.678767) (xy 129.299716 -63.213549) (xy 138.220988 -63.213549)
			(xy 138.220988 -63.159051) (xy 138.228743 -63.105109) (xy 138.244096 -63.052819) (xy 138.266733 -63.003246)
			(xy 138.296195 -62.957399) (xy 138.331881 -62.916211) (xy 138.373065 -62.88052) (xy 138.418909 -62.851054)
			(xy 138.468479 -62.828411) (xy 138.520768 -62.813052) (xy 138.574709 -62.805291) (xy 138.601958 -62.804802)
			(xy 138.629327 -62.805292) (xy 138.683505 -62.813104) (xy 138.736008 -62.828588) (xy 138.785756 -62.851424)
			(xy 138.831723 -62.881143) (xy 138.852656 -62.898782) (xy 138.85291 -62.899036) (xy 138.859987 -62.904637)
			(xy 138.876911 -62.910874) (xy 138.88593 -62.911228) (xy 138.952986 -62.911228) (xy 138.962001 -62.910858)
			(xy 138.978918 -62.904619) (xy 138.986006 -62.899036) (xy 138.986006 -62.898782) (xy 138.98626 -62.898782)
			(xy 139.007193 -62.881141) (xy 139.053161 -62.851417) (xy 139.102907 -62.828571) (xy 139.155409 -62.813075)
			(xy 139.209587 -62.805246) (xy 139.264329 -62.805246) (xy 139.318507 -62.813075) (xy 139.371009 -62.828571)
			(xy 139.420755 -62.851417) (xy 139.466723 -62.881141) (xy 139.487656 -62.898782) (xy 139.48791 -62.899036)
			(xy 139.494987 -62.904637) (xy 139.511911 -62.910874) (xy 139.52093 -62.911228) (xy 139.587986 -62.911228)
			(xy 139.597001 -62.910858) (xy 139.613918 -62.904619) (xy 139.621006 -62.899036) (xy 139.621006 -62.898782)
			(xy 139.62126 -62.898782) (xy 139.642194 -62.881145) (xy 139.688167 -62.851434) (xy 139.737914 -62.828598)
			(xy 139.790414 -62.813106) (xy 139.844589 -62.805277) (xy 139.871958 -62.804802) (xy 139.899214 -62.805242)
			(xy 139.953171 -62.812994) (xy 140.005475 -62.828347) (xy 140.055062 -62.850988) (xy 140.100921 -62.880456)
			(xy 140.14212 -62.91615) (xy 140.177819 -62.957345) (xy 140.207292 -63.003201) (xy 140.229938 -63.052786)
			(xy 140.23976 -63.086234) (xy 143.487646 -63.086234) (xy 143.491717 -63.030612) (xy 143.503843 -62.976175)
			(xy 143.523766 -62.924084) (xy 143.551062 -62.875449) (xy 143.585148 -62.831306) (xy 143.625297 -62.792597)
			(xy 143.670655 -62.760146) (xy 143.720255 -62.734645) (xy 143.773039 -62.716638) (xy 143.827882 -62.706508)
			(xy 143.883616 -62.704471) (xy 143.939053 -62.710571) (xy 143.99301 -62.724677) (xy 144.044339 -62.746489)
			(xy 144.091945 -62.775543) (xy 144.134813 -62.811218) (xy 144.17203 -62.852755) (xy 144.202803 -62.899268)
			(xy 144.226475 -62.949765) (xy 144.242543 -63.003172) (xy 144.250663 -63.058348) (xy 144.251172 -63.086234)
			(xy 144.250663 -63.11412) (xy 144.242543 -63.169296) (xy 144.226475 -63.222703) (xy 144.202803 -63.2732)
			(xy 144.20265 -63.273432) (xy 145.676872 -63.273432) (xy 145.680943 -63.21781) (xy 145.693069 -63.163373)
			(xy 145.712992 -63.111282) (xy 145.740288 -63.062647) (xy 145.774374 -63.018504) (xy 145.814523 -62.979795)
			(xy 145.859881 -62.947344) (xy 145.909481 -62.921843) (xy 145.962265 -62.903836) (xy 146.017108 -62.893706)
			(xy 146.072842 -62.891669) (xy 146.128279 -62.897769) (xy 146.182236 -62.911875) (xy 146.233565 -62.933687)
			(xy 146.281171 -62.962741) (xy 146.324039 -62.998416) (xy 146.361256 -63.039953) (xy 146.392029 -63.086466)
			(xy 146.415701 -63.136963) (xy 146.431769 -63.19037) (xy 146.439889 -63.245546) (xy 146.440398 -63.273432)
			(xy 146.439889 -63.301318) (xy 146.431769 -63.356494) (xy 146.415701 -63.409901) (xy 146.392029 -63.460398)
			(xy 146.361256 -63.506911) (xy 146.324039 -63.548448) (xy 146.281171 -63.584123) (xy 146.233565 -63.613177)
			(xy 146.182236 -63.634989) (xy 146.128279 -63.649095) (xy 146.072842 -63.655195) (xy 146.017108 -63.653158)
			(xy 145.962265 -63.643028) (xy 145.909481 -63.625021) (xy 145.859881 -63.59952) (xy 145.814523 -63.567069)
			(xy 145.774374 -63.52836) (xy 145.740288 -63.484217) (xy 145.712992 -63.435582) (xy 145.693069 -63.383491)
			(xy 145.680943 -63.329054) (xy 145.676872 -63.273432) (xy 144.20265 -63.273432) (xy 144.17203 -63.319713)
			(xy 144.134813 -63.36125) (xy 144.091945 -63.396925) (xy 144.044339 -63.425979) (xy 143.99301 -63.447791)
			(xy 143.939053 -63.461897) (xy 143.883616 -63.467997) (xy 143.827882 -63.46596) (xy 143.773039 -63.45583)
			(xy 143.720255 -63.437823) (xy 143.670655 -63.412322) (xy 143.625297 -63.379871) (xy 143.585148 -63.341162)
			(xy 143.551062 -63.297019) (xy 143.523766 -63.248384) (xy 143.503843 -63.196293) (xy 143.491717 -63.141856)
			(xy 143.487646 -63.086234) (xy 140.23976 -63.086234) (xy 140.245297 -63.105088) (xy 140.253055 -63.159044)
			(xy 140.253055 -63.213556) (xy 140.245297 -63.267512) (xy 140.229938 -63.319814) (xy 140.207292 -63.369399)
			(xy 140.177819 -63.415255) (xy 140.14212 -63.45645) (xy 140.100921 -63.492144) (xy 140.055062 -63.521612)
			(xy 140.005475 -63.544253) (xy 139.953171 -63.559606) (xy 139.899214 -63.567358) (xy 139.871958 -63.567818)
			(xy 139.844588 -63.567338) (xy 139.790409 -63.559527) (xy 139.737905 -63.544042) (xy 139.688158 -63.521203)
			(xy 139.642191 -63.491479) (xy 139.62126 -63.473838) (xy 139.621006 -63.473584) (xy 139.613923 -63.467992)
			(xy 139.597003 -63.461749) (xy 139.587986 -63.461392) (xy 139.52093 -63.461392) (xy 139.511915 -63.461765)
			(xy 139.494998 -63.468002) (xy 139.48791 -63.473584) (xy 139.487656 -63.473838) (xy 139.466723 -63.491479)
			(xy 139.420755 -63.521203) (xy 139.371009 -63.544049) (xy 139.318507 -63.559545) (xy 139.264329 -63.567374)
			(xy 139.209587 -63.567374) (xy 139.155409 -63.559545) (xy 139.102907 -63.544049) (xy 139.053161 -63.521203)
			(xy 139.007193 -63.491479) (xy 138.98626 -63.473838) (xy 138.986006 -63.473584) (xy 138.978923 -63.467992)
			(xy 138.962003 -63.461749) (xy 138.952986 -63.461392) (xy 138.88593 -63.461392) (xy 138.876915 -63.461765)
			(xy 138.859998 -63.468002) (xy 138.85291 -63.473584) (xy 138.85291 -63.473838) (xy 138.852656 -63.473838)
			(xy 138.831719 -63.491471) (xy 138.785747 -63.521182) (xy 138.736001 -63.544019) (xy 138.683501 -63.559512)
			(xy 138.629327 -63.567343) (xy 138.601958 -63.567818) (xy 138.574709 -63.567309) (xy 138.520768 -63.559548)
			(xy 138.468479 -63.544189) (xy 138.418909 -63.521546) (xy 138.373065 -63.49208) (xy 138.331881 -63.456389)
			(xy 138.296195 -63.415201) (xy 138.266733 -63.369354) (xy 138.244096 -63.319781) (xy 138.228743 -63.267491)
			(xy 138.220988 -63.213549) (xy 129.299716 -63.213549) (xy 129.299716 -65.100962) (xy 136.232644 -65.100962)
			(xy 136.236715 -65.04534) (xy 136.248841 -64.990903) (xy 136.268764 -64.938812) (xy 136.29606 -64.890177)
			(xy 136.330146 -64.846034) (xy 136.370295 -64.807325) (xy 136.415653 -64.774874) (xy 136.465253 -64.749373)
			(xy 136.518037 -64.731366) (xy 136.57288 -64.721236) (xy 136.628614 -64.719199) (xy 136.684051 -64.725299)
			(xy 136.738008 -64.739405) (xy 136.789337 -64.761217) (xy 136.836943 -64.790271) (xy 136.879811 -64.825946)
			(xy 136.917028 -64.867483) (xy 136.947801 -64.913996) (xy 136.971473 -64.964493) (xy 136.987541 -65.0179)
			(xy 136.995661 -65.073076) (xy 136.99617 -65.100962) (xy 136.995748 -65.124076) (xy 148.207474 -65.124076)
			(xy 148.211545 -65.068454) (xy 148.223671 -65.014017) (xy 148.243594 -64.961926) (xy 148.27089 -64.913291)
			(xy 148.304976 -64.869148) (xy 148.345125 -64.830439) (xy 148.390483 -64.797988) (xy 148.440083 -64.772487)
			(xy 148.492867 -64.75448) (xy 148.54771 -64.74435) (xy 148.603444 -64.742313) (xy 148.658881 -64.748413)
			(xy 148.712838 -64.762519) (xy 148.764167 -64.784331) (xy 148.811773 -64.813385) (xy 148.854641 -64.84906)
			(xy 148.891858 -64.890597) (xy 148.922631 -64.93711) (xy 148.946303 -64.987607) (xy 148.962371 -65.041014)
			(xy 148.970491 -65.09619) (xy 148.971 -65.124076) (xy 148.970491 -65.151962) (xy 148.962371 -65.207138)
			(xy 148.946303 -65.260545) (xy 148.922631 -65.311042) (xy 148.891858 -65.357555) (xy 148.854641 -65.399092)
			(xy 148.811773 -65.434767) (xy 148.764167 -65.463821) (xy 148.712838 -65.485633) (xy 148.658881 -65.499739)
			(xy 148.603444 -65.505839) (xy 148.54771 -65.503802) (xy 148.492867 -65.493672) (xy 148.440083 -65.475665)
			(xy 148.390483 -65.450164) (xy 148.345125 -65.417713) (xy 148.304976 -65.379004) (xy 148.27089 -65.334861)
			(xy 148.243594 -65.286226) (xy 148.223671 -65.234135) (xy 148.211545 -65.179698) (xy 148.207474 -65.124076)
			(xy 136.995748 -65.124076) (xy 136.995661 -65.128848) (xy 136.987541 -65.184024) (xy 136.971473 -65.237431)
			(xy 136.947801 -65.287928) (xy 136.917028 -65.334441) (xy 136.879811 -65.375978) (xy 136.836943 -65.411653)
			(xy 136.789337 -65.440707) (xy 136.738008 -65.462519) (xy 136.684051 -65.476625) (xy 136.628614 -65.482725)
			(xy 136.57288 -65.480688) (xy 136.518037 -65.470558) (xy 136.465253 -65.452551) (xy 136.415653 -65.42705)
			(xy 136.370295 -65.394599) (xy 136.330146 -65.35589) (xy 136.29606 -65.311747) (xy 136.268764 -65.263112)
			(xy 136.248841 -65.211021) (xy 136.236715 -65.156584) (xy 136.232644 -65.100962) (xy 129.299716 -65.100962)
			(xy 129.299716 -65.75552) (xy 130.446778 -65.75552) (xy 130.450849 -65.699898) (xy 130.462975 -65.645461)
			(xy 130.482898 -65.59337) (xy 130.510194 -65.544735) (xy 130.54428 -65.500592) (xy 130.584429 -65.461883)
			(xy 130.629787 -65.429432) (xy 130.679387 -65.403931) (xy 130.732171 -65.385924) (xy 130.787014 -65.375794)
			(xy 130.842748 -65.373757) (xy 130.898185 -65.379857) (xy 130.952142 -65.393963) (xy 131.003471 -65.415775)
			(xy 131.051077 -65.444829) (xy 131.093945 -65.480504) (xy 131.131162 -65.522041) (xy 131.161935 -65.568554)
			(xy 131.185607 -65.619051) (xy 131.201675 -65.672458) (xy 131.209795 -65.727634) (xy 131.210304 -65.75552)
			(xy 131.209795 -65.783406) (xy 131.201675 -65.838582) (xy 131.185607 -65.891989) (xy 131.161935 -65.942486)
			(xy 131.131162 -65.988999) (xy 131.093945 -66.030536) (xy 131.051077 -66.066211) (xy 131.003471 -66.095265)
			(xy 130.952142 -66.117077) (xy 130.898185 -66.131183) (xy 130.842748 -66.137283) (xy 130.787014 -66.135246)
			(xy 130.732171 -66.125116) (xy 130.679387 -66.107109) (xy 130.629787 -66.081608) (xy 130.584429 -66.049157)
			(xy 130.54428 -66.010448) (xy 130.510194 -65.966305) (xy 130.482898 -65.91767) (xy 130.462975 -65.865579)
			(xy 130.450849 -65.811142) (xy 130.446778 -65.75552) (xy 129.299716 -65.75552) (xy 129.299716 -65.866264)
			(xy 129.29997 -65.87109) (xy 129.29997 -65.871344) (xy 129.30093 -65.87807) (xy 129.305959 -65.890685)
			(xy 129.309876 -65.896236) (xy 129.314448 -65.90157) (xy 129.525014 -66.112136) (xy 129.531864 -66.119532)
			(xy 129.539599 -66.138131) (xy 129.54 -66.148204) (xy 129.54 -67.128954) (xy 130.466775 -67.128954)
			(xy 130.466775 -67.074446) (xy 130.474533 -67.020494) (xy 130.489891 -66.968196) (xy 130.512535 -66.918615)
			(xy 130.542006 -66.872762) (xy 130.577703 -66.83157) (xy 130.618899 -66.795879) (xy 130.664755 -66.766413)
			(xy 130.714339 -66.743775) (xy 130.766639 -66.728423) (xy 130.820592 -66.720672) (xy 130.847846 -66.720212)
			(xy 130.875215 -66.720707) (xy 130.929393 -66.728517) (xy 130.981896 -66.743999) (xy 131.031643 -66.766835)
			(xy 131.077611 -66.796553) (xy 131.098544 -66.814192) (xy 131.098798 -66.814446) (xy 131.105877 -66.820043)
			(xy 131.1228 -66.826282) (xy 131.131818 -66.826638) (xy 131.198874 -66.826638) (xy 131.207889 -66.82626)
			(xy 131.224805 -66.820026) (xy 131.231894 -66.814446) (xy 131.231894 -66.814192) (xy 131.232148 -66.814192)
			(xy 131.253088 -66.796563) (xy 131.299059 -66.76685) (xy 131.348804 -66.744012) (xy 131.401303 -66.728519)
			(xy 131.455477 -66.720688) (xy 131.482846 -66.720212) (xy 131.510097 -66.720661) (xy 131.564042 -66.728423)
			(xy 131.616334 -66.743783) (xy 131.665908 -66.766428) (xy 131.711755 -66.795897) (xy 131.752942 -66.831591)
			(xy 131.78863 -66.872782) (xy 131.818094 -66.918632) (xy 131.840733 -66.968209) (xy 131.856087 -67.020503)
			(xy 131.863842 -67.074449) (xy 131.863842 -67.128951) (xy 131.856087 -67.182897) (xy 131.840733 -67.235191)
			(xy 131.818094 -67.284768) (xy 131.78863 -67.330618) (xy 131.752942 -67.371809) (xy 131.711755 -67.407503)
			(xy 131.665908 -67.436972) (xy 131.616334 -67.459617) (xy 131.564042 -67.474977) (xy 131.510097 -67.482739)
			(xy 131.482846 -67.483228) (xy 131.455476 -67.482753) (xy 131.401297 -67.47494) (xy 131.348793 -67.459454)
			(xy 131.299046 -67.436614) (xy 131.253079 -67.406889) (xy 131.232148 -67.389248) (xy 131.231894 -67.388994)
			(xy 131.224814 -67.383398) (xy 131.207892 -67.377157) (xy 131.198874 -67.376802) (xy 131.131818 -67.376802)
			(xy 131.122802 -67.377167) (xy 131.105885 -67.383409) (xy 131.098798 -67.388994) (xy 131.098798 -67.389248)
			(xy 131.098544 -67.389248) (xy 131.077599 -67.406872) (xy 131.031631 -67.436588) (xy 130.981887 -67.459427)
			(xy 130.929388 -67.474922) (xy 130.875214 -67.482753) (xy 130.847846 -67.483228) (xy 130.820592 -67.482728)
			(xy 130.766639 -67.474977) (xy 130.714339 -67.459625) (xy 130.664755 -67.436987) (xy 130.618899 -67.407521)
			(xy 130.577703 -67.37183) (xy 130.542006 -67.330638) (xy 130.512535 -67.284785) (xy 130.489891 -67.235204)
			(xy 130.474533 -67.182906) (xy 130.466775 -67.128954) (xy 129.54 -67.128954) (xy 129.54 -67.488054)
			(xy 134.879332 -67.488054) (xy 134.883403 -67.432432) (xy 134.895529 -67.377995) (xy 134.915452 -67.325904)
			(xy 134.942748 -67.277269) (xy 134.976834 -67.233126) (xy 135.016983 -67.194417) (xy 135.062341 -67.161966)
			(xy 135.111941 -67.136465) (xy 135.164725 -67.118458) (xy 135.219568 -67.108328) (xy 135.275302 -67.106291)
			(xy 135.330739 -67.112391) (xy 135.384696 -67.126497) (xy 135.436025 -67.148309) (xy 135.483631 -67.177363)
			(xy 135.526499 -67.213038) (xy 135.563716 -67.254575) (xy 135.594489 -67.301088) (xy 135.618161 -67.351585)
			(xy 135.634229 -67.404992) (xy 135.642349 -67.460168) (xy 135.642858 -67.488054) (xy 135.642349 -67.51594)
			(xy 135.639164 -67.537584) (xy 136.17143 -67.537584) (xy 136.175501 -67.481962) (xy 136.187627 -67.427525)
			(xy 136.20755 -67.375434) (xy 136.234846 -67.326799) (xy 136.268932 -67.282656) (xy 136.309081 -67.243947)
			(xy 136.354439 -67.211496) (xy 136.404039 -67.185995) (xy 136.456823 -67.167988) (xy 136.511666 -67.157858)
			(xy 136.5674 -67.155821) (xy 136.622837 -67.161921) (xy 136.676794 -67.176027) (xy 136.728123 -67.197839)
			(xy 136.775729 -67.226893) (xy 136.818597 -67.262568) (xy 136.855814 -67.304105) (xy 136.886587 -67.350618)
			(xy 136.910259 -67.401115) (xy 136.926327 -67.454522) (xy 136.934447 -67.509698) (xy 136.934956 -67.537584)
			(xy 136.934447 -67.56547) (xy 136.930402 -67.592956) (xy 137.445494 -67.592956) (xy 137.449565 -67.537334)
			(xy 137.461691 -67.482897) (xy 137.481614 -67.430806) (xy 137.50891 -67.382171) (xy 137.542996 -67.338028)
			(xy 137.583145 -67.299319) (xy 137.628503 -67.266868) (xy 137.678103 -67.241367) (xy 137.730887 -67.22336)
			(xy 137.78573 -67.21323) (xy 137.841464 -67.211193) (xy 137.896901 -67.217293) (xy 137.950858 -67.231399)
			(xy 138.002187 -67.253211) (xy 138.049793 -67.282265) (xy 138.092661 -67.31794) (xy 138.129878 -67.359477)
			(xy 138.160651 -67.40599) (xy 138.184323 -67.456487) (xy 138.200391 -67.509894) (xy 138.208508 -67.565052)
			(xy 140.546793 -67.565052) (xy 140.546793 -67.510548) (xy 140.55455 -67.4566) (xy 140.569907 -67.404304)
			(xy 140.59255 -67.354726) (xy 140.622018 -67.308876) (xy 140.657712 -67.267687) (xy 140.698905 -67.231996)
			(xy 140.744758 -67.202532) (xy 140.794338 -67.179894) (xy 140.846635 -67.164543) (xy 140.900584 -67.156791)
			(xy 140.927836 -67.15633) (xy 140.955207 -67.156768) (xy 141.009388 -67.164591) (xy 141.061892 -67.180087)
			(xy 141.111638 -67.202935) (xy 141.157603 -67.232666) (xy 141.178534 -67.25031) (xy 141.178788 -67.250564)
			(xy 141.185868 -67.256159) (xy 141.20279 -67.262399) (xy 141.211808 -67.262756) (xy 141.278864 -67.262756)
			(xy 141.28788 -67.262391) (xy 141.304798 -67.25615) (xy 141.311884 -67.250564) (xy 141.311884 -67.25031)
			(xy 141.312138 -67.25031) (xy 141.333084 -67.232688) (xy 141.379053 -67.202973) (xy 141.428797 -67.180134)
			(xy 141.481294 -67.164639) (xy 141.535468 -67.156806) (xy 141.562836 -67.15633) (xy 141.590088 -67.156742)
			(xy 141.644037 -67.164504) (xy 141.696333 -67.179864) (xy 141.745911 -67.202509) (xy 141.791761 -67.231979)
			(xy 141.832951 -67.267674) (xy 141.868642 -67.308868) (xy 141.898108 -67.354721) (xy 141.920749 -67.404301)
			(xy 141.936104 -67.456598) (xy 141.94386 -67.510548) (xy 141.94386 -67.565052) (xy 141.936104 -67.619002)
			(xy 141.920749 -67.671299) (xy 141.898108 -67.720879) (xy 141.868642 -67.766732) (xy 141.832951 -67.807926)
			(xy 141.791761 -67.843621) (xy 141.745911 -67.873091) (xy 141.696333 -67.895736) (xy 141.644037 -67.911096)
			(xy 141.590088 -67.918858) (xy 141.562836 -67.919346) (xy 141.535466 -67.918872) (xy 141.481287 -67.911058)
			(xy 141.428783 -67.895572) (xy 141.379036 -67.872731) (xy 141.333069 -67.843007) (xy 141.312138 -67.825366)
			(xy 141.311884 -67.825112) (xy 141.304805 -67.819514) (xy 141.287883 -67.813274) (xy 141.278864 -67.81292)
			(xy 141.211808 -67.81292) (xy 141.202791 -67.813276) (xy 141.185874 -67.819524) (xy 141.178788 -67.825112)
			(xy 141.178788 -67.825366) (xy 141.178534 -67.825366) (xy 141.157596 -67.842997) (xy 141.111625 -67.872711)
			(xy 141.061879 -67.895549) (xy 141.00938 -67.911042) (xy 140.955205 -67.918872) (xy 140.927836 -67.919346)
			(xy 140.900584 -67.918809) (xy 140.846635 -67.911057) (xy 140.794338 -67.895706) (xy 140.744758 -67.873068)
			(xy 140.698905 -67.843604) (xy 140.657712 -67.807913) (xy 140.622018 -67.766724) (xy 140.59255 -67.720874)
			(xy 140.569907 -67.671296) (xy 140.55455 -67.619) (xy 140.546793 -67.565052) (xy 138.208508 -67.565052)
			(xy 138.208511 -67.56507) (xy 138.20902 -67.592956) (xy 138.208511 -67.620842) (xy 138.200391 -67.676018)
			(xy 138.184323 -67.729425) (xy 138.160651 -67.779922) (xy 138.129878 -67.826435) (xy 138.092661 -67.867972)
			(xy 138.049793 -67.903647) (xy 138.002187 -67.932701) (xy 137.950858 -67.954513) (xy 137.896901 -67.968619)
			(xy 137.841464 -67.974719) (xy 137.78573 -67.972682) (xy 137.730887 -67.962552) (xy 137.678103 -67.944545)
			(xy 137.628503 -67.919044) (xy 137.583145 -67.886593) (xy 137.542996 -67.847884) (xy 137.50891 -67.803741)
			(xy 137.481614 -67.755106) (xy 137.461691 -67.703015) (xy 137.449565 -67.648578) (xy 137.445494 -67.592956)
			(xy 136.930402 -67.592956) (xy 136.926327 -67.620646) (xy 136.910259 -67.674053) (xy 136.886587 -67.72455)
			(xy 136.855814 -67.771063) (xy 136.818597 -67.8126) (xy 136.775729 -67.848275) (xy 136.728123 -67.877329)
			(xy 136.676794 -67.899141) (xy 136.622837 -67.913247) (xy 136.5674 -67.919347) (xy 136.511666 -67.91731)
			(xy 136.456823 -67.90718) (xy 136.404039 -67.889173) (xy 136.354439 -67.863672) (xy 136.309081 -67.831221)
			(xy 136.268932 -67.792512) (xy 136.234846 -67.748369) (xy 136.20755 -67.699734) (xy 136.187627 -67.647643)
			(xy 136.175501 -67.593206) (xy 136.17143 -67.537584) (xy 135.639164 -67.537584) (xy 135.634229 -67.571116)
			(xy 135.618161 -67.624523) (xy 135.594489 -67.67502) (xy 135.563716 -67.721533) (xy 135.526499 -67.76307)
			(xy 135.483631 -67.798745) (xy 135.436025 -67.827799) (xy 135.384696 -67.849611) (xy 135.330739 -67.863717)
			(xy 135.275302 -67.869817) (xy 135.219568 -67.86778) (xy 135.164725 -67.85765) (xy 135.111941 -67.839643)
			(xy 135.062341 -67.814142) (xy 135.016983 -67.781691) (xy 134.976834 -67.742982) (xy 134.942748 -67.698839)
			(xy 134.915452 -67.650204) (xy 134.895529 -67.598113) (xy 134.883403 -67.543676) (xy 134.879332 -67.488054)
			(xy 129.54 -67.488054) (xy 129.54 -68.586604) (xy 132.725414 -68.586604) (xy 132.725879 -68.559234)
			(xy 132.733697 -68.505054) (xy 132.749186 -68.452551) (xy 132.772028 -68.402804) (xy 132.801753 -68.356838)
			(xy 132.819394 -68.335906) (xy 132.819648 -68.335652) (xy 132.825225 -68.328559) (xy 132.831476 -68.311647)
			(xy 132.83184 -68.302632) (xy 132.83184 -68.235576) (xy 132.831507 -68.226556) (xy 132.825244 -68.209639)
			(xy 132.819648 -68.202556) (xy 132.819394 -68.202556) (xy 132.819394 -68.202302) (xy 132.801741 -68.181381)
			(xy 132.772032 -68.135405) (xy 132.749199 -68.085655) (xy 132.733711 -68.033152) (xy 132.725886 -67.978974)
			(xy 132.725414 -67.951604) (xy 132.725859 -67.92435) (xy 132.733616 -67.870398) (xy 132.748973 -67.818098)
			(xy 132.771616 -67.768516) (xy 132.801086 -67.722662) (xy 132.836782 -67.681469) (xy 132.877977 -67.645775)
			(xy 132.923832 -67.616308) (xy 132.973415 -67.593666) (xy 133.025715 -67.578312) (xy 133.079668 -67.570558)
			(xy 133.106922 -67.570096) (xy 133.133236 -67.57055) (xy 133.185365 -67.577788) (xy 133.236008 -67.59211)
			(xy 133.284207 -67.613245) (xy 133.32905 -67.640793) (xy 133.36969 -67.674234) (xy 133.387846 -67.693286)
			(xy 133.39535 -67.700708) (xy 133.414643 -67.709221) (xy 133.425184 -67.709796) (xy 133.49986 -67.709796)
			(xy 133.510409 -67.70926) (xy 133.529704 -67.70073) (xy 133.537198 -67.693286) (xy 133.555359 -67.674236)
			(xy 133.595988 -67.640779) (xy 133.640827 -67.613219) (xy 133.689027 -67.59208) (xy 133.739673 -67.577762)
			(xy 133.791806 -67.570535) (xy 133.818122 -67.570096) (xy 133.845493 -67.57055) (xy 133.899672 -67.578371)
			(xy 133.952175 -67.593863) (xy 134.001922 -67.616707) (xy 134.047889 -67.646434) (xy 134.06882 -67.664076)
			(xy 134.069074 -67.66433) (xy 134.076161 -67.669915) (xy 134.093078 -67.676162) (xy 134.102094 -67.676522)
			(xy 134.16915 -67.676522) (xy 134.178164 -67.676136) (xy 134.195081 -67.669908) (xy 134.20217 -67.66433)
			(xy 134.20217 -67.664076) (xy 134.202424 -67.664076) (xy 134.223371 -67.646455) (xy 134.26934 -67.616742)
			(xy 134.319084 -67.593902) (xy 134.371581 -67.578407) (xy 134.425754 -67.570573) (xy 134.453122 -67.570096)
			(xy 134.480374 -67.570557) (xy 134.534323 -67.578317) (xy 134.586618 -67.593675) (xy 134.636196 -67.616319)
			(xy 134.682046 -67.645788) (xy 134.723236 -67.681482) (xy 134.758928 -67.722675) (xy 134.788393 -67.768527)
			(xy 134.811034 -67.818106) (xy 134.826389 -67.870403) (xy 134.834145 -67.924352) (xy 134.83463 -67.951604)
			(xy 134.834183 -67.978975) (xy 134.826363 -68.033156) (xy 134.810871 -68.08566) (xy 134.788024 -68.135406)
			(xy 134.758294 -68.181372) (xy 134.74065 -68.202302) (xy 134.740396 -68.202556) (xy 134.734821 -68.209651)
			(xy 134.728568 -68.226561) (xy 134.728204 -68.235576) (xy 134.728204 -68.302632) (xy 134.728545 -68.311651)
			(xy 134.734804 -68.328567) (xy 134.740396 -68.335652) (xy 134.74065 -68.335652) (xy 134.74065 -68.335906)
			(xy 134.758298 -68.356831) (xy 134.78801 -68.402805) (xy 134.810845 -68.452554) (xy 134.826334 -68.505057)
			(xy 134.834158 -68.559234) (xy 134.83463 -68.586604) (xy 134.834126 -68.613854) (xy 134.82637 -68.6678)
			(xy 134.811015 -68.720093) (xy 134.794375 -68.75653) (xy 138.270488 -68.75653) (xy 138.270975 -68.729161)
			(xy 138.278788 -68.674982) (xy 138.294272 -68.62248) (xy 138.317109 -68.572733) (xy 138.346829 -68.526765)
			(xy 138.364468 -68.505832) (xy 138.364722 -68.505578) (xy 138.370326 -68.498504) (xy 138.376562 -68.481577)
			(xy 138.376914 -68.472558) (xy 138.376914 -68.405502) (xy 138.376553 -68.396486) (xy 138.370308 -68.379569)
			(xy 138.364722 -68.372482) (xy 138.364468 -68.372482) (xy 138.364468 -68.372228) (xy 138.346824 -68.3513)
			(xy 138.317114 -68.305326) (xy 138.294279 -68.255577) (xy 138.278789 -68.203076) (xy 138.270962 -68.148899)
			(xy 138.270488 -68.12153) (xy 138.270983 -68.094278) (xy 138.278736 -68.040328) (xy 138.294088 -67.988031)
			(xy 138.316727 -67.938452) (xy 138.346191 -67.892599) (xy 138.381882 -67.851406) (xy 138.423071 -67.815712)
			(xy 138.468922 -67.786243) (xy 138.5185 -67.7636) (xy 138.570795 -67.748243) (xy 138.624744 -67.740486)
			(xy 138.651996 -67.740022) (xy 138.679366 -67.740485) (xy 138.733546 -67.748303) (xy 138.786049 -67.763792)
			(xy 138.835796 -67.786635) (xy 138.881763 -67.81636) (xy 138.902694 -67.834002) (xy 138.902948 -67.834256)
			(xy 138.91004 -67.839834) (xy 138.926953 -67.846084) (xy 138.935968 -67.846448) (xy 139.003024 -67.846448)
			(xy 139.012043 -67.846114) (xy 139.028961 -67.839852) (xy 139.036044 -67.834256) (xy 139.036044 -67.834002)
			(xy 139.036298 -67.834002) (xy 139.05722 -67.816351) (xy 139.103196 -67.786641) (xy 139.152946 -67.763807)
			(xy 139.205449 -67.748319) (xy 139.259626 -67.740494) (xy 139.286996 -67.740022) (xy 139.31331 -67.740485)
			(xy 139.365439 -67.74772) (xy 139.416082 -67.762039) (xy 139.464281 -67.783173) (xy 139.509125 -67.81072)
			(xy 139.549764 -67.84416) (xy 139.56792 -67.863212) (xy 139.575431 -67.870626) (xy 139.594719 -67.879143)
			(xy 139.605258 -67.879722) (xy 139.679934 -67.879722) (xy 139.69048 -67.879164) (xy 139.709776 -67.870649)
			(xy 139.717272 -67.863212) (xy 139.735451 -67.844179) (xy 139.776075 -67.81072) (xy 139.82091 -67.783157)
			(xy 139.869107 -67.762015) (xy 139.91975 -67.747693) (xy 139.971881 -67.740463) (xy 139.998196 -67.740022)
			(xy 140.02545 -67.740459) (xy 140.079404 -67.748216) (xy 140.131704 -67.763573) (xy 140.181286 -67.786218)
			(xy 140.22714 -67.815688) (xy 140.268334 -67.851385) (xy 140.304028 -67.89258) (xy 140.333495 -67.938437)
			(xy 140.356136 -67.988021) (xy 140.371489 -68.040322) (xy 140.379243 -68.094276) (xy 140.379704 -68.12153)
			(xy 140.379255 -68.148901) (xy 140.371433 -68.203081) (xy 140.35594 -68.255584) (xy 140.333094 -68.30533)
			(xy 140.303367 -68.351297) (xy 140.285724 -68.372228) (xy 140.28547 -68.372482) (xy 140.279881 -68.379567)
			(xy 140.273637 -68.396485) (xy 140.273278 -68.405502) (xy 140.273278 -68.472558) (xy 140.27366 -68.481572)
			(xy 140.279891 -68.498489) (xy 140.28547 -68.505578) (xy 140.285724 -68.505578) (xy 140.285724 -68.505832)
			(xy 140.303348 -68.526776) (xy 140.333062 -68.572746) (xy 140.3559 -68.62249) (xy 140.371395 -68.674988)
			(xy 140.379227 -68.729162) (xy 140.379704 -68.75653) (xy 140.37925 -68.783782) (xy 140.371489 -68.837731)
			(xy 140.35613 -68.890027) (xy 140.333485 -68.939604) (xy 140.304016 -68.985455) (xy 140.268321 -69.026645)
			(xy 140.227128 -69.062336) (xy 140.181275 -69.091802) (xy 140.131695 -69.114442) (xy 140.079398 -69.129797)
			(xy 140.025448 -69.137553) (xy 139.998196 -69.138038) (xy 139.971881 -69.137593) (xy 139.919751 -69.130356)
			(xy 139.869107 -69.116034) (xy 139.820907 -69.094898) (xy 139.776065 -69.067347) (xy 139.735427 -69.033902)
			(xy 139.717272 -69.014848) (xy 139.709756 -69.007439) (xy 139.690472 -68.998917) (xy 139.679934 -68.998338)
			(xy 139.605258 -68.998338) (xy 139.594709 -68.998874) (xy 139.575413 -69.007403) (xy 139.56792 -69.014848)
			(xy 139.549757 -69.033896) (xy 139.509128 -69.067352) (xy 139.464289 -69.094911) (xy 139.41609 -69.11605)
			(xy 139.365444 -69.13037) (xy 139.313312 -69.137597) (xy 139.286996 -69.138038) (xy 139.259625 -69.137589)
			(xy 139.205445 -69.12977) (xy 139.152941 -69.114277) (xy 139.103194 -69.091431) (xy 139.057229 -69.061702)
			(xy 139.036298 -69.044058) (xy 139.036044 -69.043804) (xy 139.028949 -69.03823) (xy 139.012039 -69.031976)
			(xy 139.003024 -69.031612) (xy 138.935968 -69.031612) (xy 138.926949 -69.031951) (xy 138.910032 -69.038211)
			(xy 138.902948 -69.043804) (xy 138.902948 -69.044058) (xy 138.902694 -69.044058) (xy 138.88177 -69.061707)
			(xy 138.835795 -69.091419) (xy 138.786046 -69.114253) (xy 138.733543 -69.129742) (xy 138.679366 -69.137566)
			(xy 138.651996 -69.138038) (xy 138.624746 -69.137526) (xy 138.570801 -69.12977) (xy 138.518508 -69.114416)
			(xy 138.468933 -69.091776) (xy 138.423084 -69.062312) (xy 138.381895 -69.026624) (xy 138.346203 -68.985437)
			(xy 138.316736 -68.93959) (xy 138.294093 -68.890016) (xy 138.278736 -68.837725) (xy 138.270976 -68.78378)
			(xy 138.270488 -68.75653) (xy 134.794375 -68.75653) (xy 134.788375 -68.769669) (xy 134.75891 -68.815518)
			(xy 134.723221 -68.856708) (xy 134.682033 -68.8924) (xy 134.636185 -68.921866) (xy 134.58661 -68.944509)
			(xy 134.534318 -68.959866) (xy 134.480372 -68.967625) (xy 134.453122 -68.968112) (xy 134.425752 -68.96763)
			(xy 134.371574 -68.959816) (xy 134.319071 -68.94433) (xy 134.269324 -68.921492) (xy 134.223356 -68.891771)
			(xy 134.202424 -68.874132) (xy 134.20217 -68.873878) (xy 134.195069 -68.868312) (xy 134.178163 -68.862054)
			(xy 134.16915 -68.861686) (xy 134.102094 -68.861686) (xy 134.093077 -68.862043) (xy 134.07616 -68.868291)
			(xy 134.069074 -68.873878) (xy 134.069074 -68.874132) (xy 134.06882 -68.874132) (xy 134.047895 -68.89178)
			(xy 134.00192 -68.92149) (xy 133.952171 -68.944323) (xy 133.899668 -68.959812) (xy 133.845492 -68.967639)
			(xy 133.818122 -68.968112) (xy 133.791809 -68.967626) (xy 133.739681 -68.960394) (xy 133.689039 -68.946079)
			(xy 133.64084 -68.92495) (xy 133.595996 -68.897407) (xy 133.555355 -68.863972) (xy 133.537198 -68.844922)
			(xy 133.529676 -68.837521) (xy 133.510396 -68.828995) (xy 133.49986 -68.828412) (xy 133.425184 -68.828412)
			(xy 133.414631 -68.828915) (xy 133.395336 -68.837468) (xy 133.387846 -68.844922) (xy 133.369714 -68.864001)
			(xy 133.329079 -68.897455) (xy 133.284233 -68.925011) (xy 133.236028 -68.946145) (xy 133.185377 -68.960457)
			(xy 133.133239 -68.967676) (xy 133.106922 -68.968112) (xy 133.07967 -68.967624) (xy 133.02572 -68.95987)
			(xy 132.973423 -68.944517) (xy 132.923843 -68.921878) (xy 132.87799 -68.892412) (xy 132.836797 -68.856721)
			(xy 132.801103 -68.815531) (xy 132.771635 -68.76968) (xy 132.748992 -68.720102) (xy 132.733635 -68.667805)
			(xy 132.725878 -68.613856) (xy 132.725414 -68.586604) (xy 129.54 -68.586604) (xy 129.54 -71.555864)
			(xy 135.294622 -71.555864) (xy 135.298693 -71.500242) (xy 135.310819 -71.445805) (xy 135.330742 -71.393714)
			(xy 135.358038 -71.345079) (xy 135.392124 -71.300936) (xy 135.432273 -71.262227) (xy 135.477631 -71.229776)
			(xy 135.527231 -71.204275) (xy 135.580015 -71.186268) (xy 135.634858 -71.176138) (xy 135.690592 -71.174101)
			(xy 135.746029 -71.180201) (xy 135.799986 -71.194307) (xy 135.851315 -71.216119) (xy 135.898921 -71.245173)
			(xy 135.941789 -71.280848) (xy 135.979006 -71.322385) (xy 136.009779 -71.368898) (xy 136.033451 -71.419395)
			(xy 136.049519 -71.472802) (xy 136.057639 -71.527978) (xy 136.058148 -71.555864) (xy 136.057639 -71.58375)
			(xy 136.0518 -71.623428) (xy 136.803636 -71.623428) (xy 136.807707 -71.567806) (xy 136.819833 -71.513369)
			(xy 136.839756 -71.461278) (xy 136.867052 -71.412643) (xy 136.901138 -71.3685) (xy 136.941287 -71.329791)
			(xy 136.986645 -71.29734) (xy 137.036245 -71.271839) (xy 137.089029 -71.253832) (xy 137.143872 -71.243702)
			(xy 137.199606 -71.241665) (xy 137.255043 -71.247765) (xy 137.309 -71.261871) (xy 137.360329 -71.283683)
			(xy 137.407935 -71.312737) (xy 137.450803 -71.348412) (xy 137.48802 -71.389949) (xy 137.518793 -71.436462)
			(xy 137.542465 -71.486959) (xy 137.558533 -71.540366) (xy 137.566653 -71.595542) (xy 137.567162 -71.623428)
			(xy 137.566653 -71.651314) (xy 137.558533 -71.70649) (xy 137.542465 -71.759897) (xy 137.518793 -71.810394)
			(xy 137.48802 -71.856907) (xy 137.450803 -71.898444) (xy 137.407935 -71.934119) (xy 137.360329 -71.963173)
			(xy 137.309 -71.984985) (xy 137.255043 -71.999091) (xy 137.199606 -72.005191) (xy 137.143872 -72.003154)
			(xy 137.089029 -71.993024) (xy 137.036245 -71.975017) (xy 136.986645 -71.949516) (xy 136.941287 -71.917065)
			(xy 136.901138 -71.878356) (xy 136.867052 -71.834213) (xy 136.839756 -71.785578) (xy 136.819833 -71.733487)
			(xy 136.807707 -71.67905) (xy 136.803636 -71.623428) (xy 136.0518 -71.623428) (xy 136.049519 -71.638926)
			(xy 136.033451 -71.692333) (xy 136.009779 -71.74283) (xy 135.979006 -71.789343) (xy 135.941789 -71.83088)
			(xy 135.898921 -71.866555) (xy 135.851315 -71.895609) (xy 135.799986 -71.917421) (xy 135.746029 -71.931527)
			(xy 135.690592 -71.937627) (xy 135.634858 -71.93559) (xy 135.580015 -71.92546) (xy 135.527231 -71.907453)
			(xy 135.477631 -71.881952) (xy 135.432273 -71.849501) (xy 135.392124 -71.810792) (xy 135.358038 -71.766649)
			(xy 135.330742 -71.718014) (xy 135.310819 -71.665923) (xy 135.298693 -71.611486) (xy 135.294622 -71.555864)
			(xy 129.54 -71.555864) (xy 129.54 -76.620116) (xy 129.540254 -76.624942) (xy 129.540254 -76.625196)
			(xy 129.541505 -76.633491) (xy 129.548629 -76.648665) (xy 129.554224 -76.654914) (xy 129.880106 -76.980542)
			(xy 129.883662 -76.983336) (xy 139.482068 -76.983336) (xy 139.492131 -76.982899) (xy 139.510712 -76.97516)
			(xy 139.518136 -76.96835) (xy 143.12265 -73.36409) (xy 143.129331 -73.356679) (xy 143.136922 -73.338249)
			(xy 143.136916 -73.318317) (xy 143.129312 -73.299892) (xy 143.12265 -73.292462) (xy 142.41653 -72.586342)
			(xy 142.399152 -72.568626) (xy 142.367105 -72.530729) (xy 142.352522 -72.51065) (xy 142.350236 -72.507348)
			(xy 142.267432 -72.424544) (xy 142.260591 -72.417144) (xy 142.252872 -72.398545) (xy 142.252446 -72.388476)
			(xy 142.252446 -72.271382) (xy 142.251684 -72.267318) (xy 142.247828 -72.2428) (xy 142.24376 -72.193331)
			(xy 142.243556 -72.168512) (xy 142.243556 -71.733156) (xy 142.243778 -71.708338) (xy 142.247851 -71.658871)
			(xy 142.251684 -71.63435) (xy 142.252446 -71.630286) (xy 142.252446 -71.513192) (xy 142.252872 -71.503123)
			(xy 142.260594 -71.484526) (xy 142.267432 -71.477124) (xy 142.350236 -71.39432) (xy 142.352522 -71.391018)
			(xy 142.367109 -71.370941) (xy 142.399155 -71.333045) (xy 142.41653 -71.315326) (xy 143.022574 -70.709282)
			(xy 143.040291 -70.691905) (xy 143.07819 -70.659862) (xy 143.098266 -70.645274) (xy 143.101568 -70.642988)
			(xy 143.176752 -70.567804) (xy 143.184153 -70.560965) (xy 143.202751 -70.553249) (xy 143.21282 -70.552818)
			(xy 143.300958 -70.552818) (xy 143.3068 -70.551548) (xy 143.339613 -70.544428) (xy 143.406323 -70.536787)
			(xy 143.439896 -70.536308) (xy 143.874744 -70.536308) (xy 143.884811 -70.535877) (xy 143.903405 -70.528153)
			(xy 143.910812 -70.521322) (xy 143.914368 -70.517766) (xy 143.914368 -70.051422) (xy 143.914871 -70.017714)
			(xy 143.922637 -69.950746) (xy 143.929862 -69.917818) (xy 143.931132 -69.911976) (xy 143.931132 -69.834506)
			(xy 143.931555 -69.824436) (xy 143.939271 -69.805833) (xy 143.946118 -69.798438) (xy 143.996918 -69.747638)
			(xy 144.00403 -69.738748) (xy 144.022247 -69.710438) (xy 144.064133 -69.657733) (xy 144.087596 -69.633592)
			(xy 144.690592 -69.030596) (xy 144.714731 -69.007131) (xy 144.767437 -68.965245) (xy 144.795748 -68.94703)
			(xy 144.800574 -68.943982) (xy 144.855438 -68.889118) (xy 144.862838 -68.882276) (xy 144.881436 -68.874552)
			(xy 144.891506 -68.874132) (xy 144.968976 -68.874132) (xy 144.974818 -68.872862) (xy 145.007751 -68.865668)
			(xy 145.074716 -68.857907) (xy 145.108422 -68.857368) (xy 145.553684 -68.857368) (xy 145.563747 -68.856929)
			(xy 145.582326 -68.849189) (xy 145.589752 -68.842382) (xy 145.593816 -68.838318) (xy 145.593816 -68.368926)
			(xy 145.594297 -68.336003) (xy 145.601684 -68.270573) (xy 145.608548 -68.23837) (xy 145.609818 -68.232782)
			(xy 145.609818 -68.15582) (xy 145.610256 -68.145757) (xy 145.617993 -68.127175) (xy 145.624804 -68.119752)
			(xy 145.675858 -68.068698) (xy 145.67916 -68.063364) (xy 145.698107 -68.033054) (xy 145.742167 -67.976765)
			(xy 145.767044 -67.951096) (xy 146.365468 -67.352672) (xy 146.391109 -67.327764) (xy 146.447402 -67.283702)
			(xy 146.477736 -67.264788) (xy 146.48307 -67.261486) (xy 146.534124 -67.210432) (xy 146.541522 -67.203586)
			(xy 146.560121 -67.195855) (xy 146.570192 -67.195446) (xy 146.647154 -67.195446) (xy 146.652742 -67.194176)
			(xy 146.684946 -67.187319) (xy 146.750376 -67.17994) (xy 146.783298 -67.179444) (xy 147.229322 -67.179444)
			(xy 147.262245 -67.179922) (xy 147.327677 -67.187303) (xy 147.359878 -67.194176) (xy 147.365466 -67.195446)
			(xy 147.445476 -67.195446) (xy 147.455539 -67.195884) (xy 147.474119 -67.203623) (xy 147.481544 -67.210432)
			(xy 147.53717 -67.266058) (xy 147.541996 -67.269106) (xy 147.570308 -67.28732) (xy 147.623017 -67.329202)
			(xy 147.647152 -67.352672) (xy 148.389086 -68.094606) (xy 148.396498 -68.10129) (xy 148.414931 -68.108887)
			(xy 148.434869 -68.108887) (xy 148.453302 -68.10129) (xy 148.460714 -68.094606) (xy 153.409396 -63.145924)
			(xy 153.415519 -63.139284) (xy 153.423071 -63.12289) (xy 153.424128 -63.11392) (xy 153.565352 -61.287406)
			(xy 153.565352 -61.280294) (xy 152.941528 -50.874168) (xy 152.940512 -50.838862) (xy 152.940766 -50.819812)
			(xy 153.186638 -43.231308) (xy 153.187662 -43.206365) (xy 153.193386 -43.156769) (xy 153.198068 -43.132248)
			(xy 153.199084 -43.128438) (xy 153.203148 -43.001438) (xy 153.203894 -42.99184) (xy 153.211597 -42.974215)
			(xy 153.218134 -42.967148) (xy 153.358342 -42.82694) (xy 153.35885 -42.826432) (xy 153.366216 -42.819066)
			(xy 156.268928 -39.9161) (xy 156.27604 -39.902892) (xy 156.27731 -39.895526) (xy 156.284513 -39.861193)
			(xy 156.305989 -39.794407) (xy 156.335216 -39.730631) (xy 156.371782 -39.670761) (xy 156.415174 -39.615636)
			(xy 156.439616 -39.590472) (xy 156.790136 -39.239952) (xy 156.814777 -39.215984) (xy 156.868698 -39.173343)
			(xy 156.927206 -39.137254) (xy 156.98951 -39.108204) (xy 157.054767 -39.086589) (xy 157.088332 -39.07917)
			(xy 157.095444 -39.077646) (xy 157.102636 -39.075923) (xy 157.115674 -39.068957) (xy 157.121098 -39.06393)
			(xy 157.122622 -39.062406) (xy 157.128972 -39.054786) (xy 157.128972 -38.385242) (xy 157.129191 -38.360424)
			(xy 157.133256 -38.310955) (xy 157.1371 -38.286436) (xy 157.137862 -38.282372) (xy 157.137862 -38.165278)
			(xy 157.138291 -38.155211) (xy 157.146018 -38.136618) (xy 157.152848 -38.12921) (xy 157.235652 -38.046406)
			(xy 157.237938 -38.043104) (xy 157.252525 -38.023028) (xy 157.284573 -37.985132) (xy 157.301946 -37.967412)
			(xy 158.295086 -36.974272) (xy 158.297118 -36.961318) (xy 158.297118 -36.826698) (xy 158.297542 -36.816628)
			(xy 158.305259 -36.798026) (xy 158.312104 -36.79063) (xy 158.447232 -36.655502) (xy 158.453328 -36.648898)
			(xy 158.472886 -36.629086) (xy 158.473394 -36.628578) (xy 158.780226 -36.322) (xy 158.793434 -36.3093)
			(xy 158.79445 -36.308284) (xy 158.935928 -36.166806) (xy 158.943328 -36.159963) (xy 158.961926 -36.152238)
			(xy 158.971996 -36.15182) (xy 159.046164 -36.15182) (xy 159.053784 -36.149534) (xy 159.067655 -36.14531)
			(xy 159.095735 -36.13807) (xy 159.109918 -36.135056) (xy 159.132778 -36.13023) (xy 159.145478 -36.123372)
			(xy 159.150304 -36.118546) (xy 159.150304 -36.045648) (xy 159.149999 -36.038158) (xy 159.145612 -36.02383)
			(xy 159.141668 -36.017454) (xy 159.141414 -36.0172) (xy 159.121433 -35.987462) (xy 159.088023 -35.924082)
			(xy 159.062514 -35.857131) (xy 159.045279 -35.787588) (xy 159.03657 -35.716473) (xy 159.036004 -35.68065)
			(xy 159.036004 -35.299904) (xy 159.034734 -35.29457) (xy 159.033782 -35.291091) (xy 159.032755 -35.283952)
			(xy 159.032702 -35.280346) (xy 159.032702 -35.075114) (xy 159.032448 -35.061398) (xy 159.032448 -34.61766)
			(xy 159.032702 -34.603182) (xy 159.032702 -34.398458) (xy 159.032768 -34.394853) (xy 159.033793 -34.387715)
			(xy 159.034734 -34.384234) (xy 159.036004 -34.3789) (xy 159.036004 -34.162492) (xy 159.034734 -34.157158)
			(xy 159.033782 -34.153679) (xy 159.032758 -34.14654) (xy 159.032702 -34.142934) (xy 159.032702 -33.93821)
			(xy 159.032448 -33.923732) (xy 159.032448 -33.480248) (xy 159.032702 -33.46577) (xy 159.032702 -33.261046)
			(xy 159.032769 -33.257441) (xy 159.033796 -33.250304) (xy 159.034734 -33.246822) (xy 159.036004 -33.241488)
			(xy 159.036004 -33.02508) (xy 159.034734 -33.019746) (xy 159.033783 -33.016267) (xy 159.03276 -33.009128)
			(xy 159.032702 -33.005522) (xy 159.032702 -32.800798) (xy 159.032448 -32.78632) (xy 159.032448 -32.342836)
			(xy 159.032702 -32.328358) (xy 159.032702 -32.123634) (xy 159.032786 -32.118958) (xy 159.034447 -32.109756)
			(xy 159.036004 -32.105346) (xy 159.037941 -32.099782) (xy 159.039489 -32.088107) (xy 159.039052 -32.082232)
			(xy 159.037641 -32.067477) (xy 159.036118 -32.037872) (xy 159.036004 -32.02305) (xy 159.036004 -31.887668)
			(xy 159.034734 -31.882334) (xy 159.033784 -31.878855) (xy 159.032763 -31.871716) (xy 159.032702 -31.86811)
			(xy 159.032702 -31.663386) (xy 159.032448 -31.648908) (xy 159.032448 -31.205424) (xy 159.032702 -31.190946)
			(xy 159.032702 -30.986222) (xy 159.03314 -30.976158) (xy 159.040874 -30.957575) (xy 159.047688 -30.950154)
			(xy 159.053276 -30.944566) (xy 159.045266 -30.909937) (xy 159.036609 -30.839388) (xy 159.036004 -30.80385)
			(xy 159.036004 -30.750256) (xy 159.034734 -30.744922) (xy 159.033785 -30.741443) (xy 159.032765 -30.734304)
			(xy 159.032702 -30.730698) (xy 159.032702 -30.525974) (xy 159.032448 -30.511496) (xy 159.032448 -30.068012)
			(xy 159.032702 -30.053534) (xy 159.032702 -29.84881) (xy 159.033123 -29.838739) (xy 159.040836 -29.820132)
			(xy 159.047688 -29.812742) (xy 159.049974 -29.810456) (xy 159.056244 -29.8037) (xy 159.063882 -29.786942)
			(xy 159.065044 -29.768562) (xy 159.062674 -29.759656) (xy 159.062674 -29.759402) (xy 159.052683 -29.725431)
			(xy 159.039944 -29.655773) (xy 159.037274 -29.620464) (xy 159.034988 -29.608526) (xy 159.033935 -29.604869)
			(xy 159.032789 -29.597345) (xy 159.032702 -29.59354) (xy 159.032702 -29.388562) (xy 159.032448 -29.374084)
			(xy 159.032448 -28.9306) (xy 159.032702 -28.916122) (xy 159.032702 -28.711398) (xy 159.033126 -28.701328)
			(xy 159.040841 -28.682724) (xy 159.047688 -28.67533) (xy 159.071818 -28.6512) (xy 159.078626 -28.643771)
			(xy 159.086295 -28.625154) (xy 159.08625 -28.605018) (xy 159.08274 -28.595574) (xy 159.072689 -28.571043)
			(xy 159.056532 -28.520547) (xy 159.050482 -28.494736) (xy 159.047688 -28.491942) (xy 159.040841 -28.484545)
			(xy 159.033114 -28.465945) (xy 159.032702 -28.455874) (xy 159.032702 -28.25115) (xy 159.032448 -28.236672)
			(xy 159.032448 -27.97556) (xy 159.032005 -27.965382) (xy 159.024098 -27.946625) (xy 159.00951 -27.93243)
			(xy 159.00019 -27.928316) (xy 158.989522 -27.926538) (xy 158.982664 -27.925522) (xy 158.9786 -27.92476)
			(xy 158.861506 -27.92476) (xy 158.851436 -27.924337) (xy 158.832834 -27.916619) (xy 158.825438 -27.909774)
			(xy 158.742634 -27.82697) (xy 158.739332 -27.824684) (xy 158.712617 -27.80515) (xy 158.663273 -27.761043)
			(xy 158.619164 -27.7117) (xy 158.599632 -27.684984) (xy 158.597346 -27.681682) (xy 158.514542 -27.598878)
			(xy 158.507694 -27.59148) (xy 158.499961 -27.572882) (xy 158.499556 -27.56281) (xy 158.499556 -27.445716)
			(xy 158.498794 -27.441652) (xy 158.494893 -27.417136) (xy 158.490696 -27.367669) (xy 158.490412 -27.342846)
			(xy 158.490677 -27.318023) (xy 158.494875 -27.268554) (xy 158.498794 -27.24404) (xy 158.499556 -27.239976)
			(xy 158.499556 -27.122882) (xy 158.499984 -27.112814) (xy 158.507709 -27.09422) (xy 158.514542 -27.086814)
			(xy 158.597346 -27.00401) (xy 158.599632 -27.000708) (xy 158.61284 -26.982928) (xy 158.613348 -26.98242)
			(xy 158.621222 -26.972006) (xy 158.622287 -26.968286) (xy 158.623431 -26.960635) (xy 158.623508 -26.956766)
			(xy 158.623508 -26.870152) (xy 158.623184 -26.861873) (xy 158.617861 -26.846195) (xy 158.613094 -26.839418)
			(xy 158.593744 -26.813563) (xy 158.560171 -26.758393) (xy 158.532808 -26.699895) (xy 158.51198 -26.638764)
			(xy 158.497935 -26.575728) (xy 158.490841 -26.511537) (xy 158.490412 -26.479246) (xy 158.490857 -26.446076)
			(xy 158.49828 -26.380152) (xy 158.513037 -26.315474) (xy 158.534944 -26.252854) (xy 158.563723 -26.193082)
			(xy 158.599015 -26.136907) (xy 158.640374 -26.085037) (xy 158.687281 -26.038125) (xy 158.739145 -25.996759)
			(xy 158.795315 -25.96146) (xy 158.855084 -25.932673) (xy 158.917701 -25.910758) (xy 158.982377 -25.895993)
			(xy 159.0483 -25.888561) (xy 159.08147 -25.888188) (xy 159.114632 -25.888667) (xy 159.180536 -25.89612)
			(xy 159.245193 -25.910903) (xy 159.307788 -25.932828) (xy 159.367536 -25.961622) (xy 159.423687 -25.996921)
			(xy 159.475534 -26.038284) (xy 159.4993 -26.061416) (xy 159.60598 -26.168096) (xy 159.613403 -26.174877)
			(xy 159.632 -26.182479) (xy 159.642048 -26.182828) (xy 159.730948 -26.182828) (xy 159.76411 -26.183307)
			(xy 159.830015 -26.190758) (xy 159.894672 -26.205539) (xy 159.957268 -26.227464) (xy 160.017017 -26.256257)
			(xy 160.073168 -26.291557) (xy 160.125015 -26.332921) (xy 160.148778 -26.356056) (xy 160.153604 -26.360882)
			(xy 161.189668 -26.360882) (xy 161.193739 -26.30526) (xy 161.205865 -26.250823) (xy 161.225788 -26.198732)
			(xy 161.253084 -26.150097) (xy 161.28717 -26.105954) (xy 161.327319 -26.067245) (xy 161.372677 -26.034794)
			(xy 161.422277 -26.009293) (xy 161.475061 -25.991286) (xy 161.529904 -25.981156) (xy 161.585638 -25.979119)
			(xy 161.641075 -25.985219) (xy 161.695032 -25.999325) (xy 161.746361 -26.021137) (xy 161.793967 -26.050191)
			(xy 161.836835 -26.085866) (xy 161.874052 -26.127403) (xy 161.904825 -26.173916) (xy 161.928497 -26.224413)
			(xy 161.944565 -26.27782) (xy 161.950733 -26.319734) (xy 166.942006 -26.319734) (xy 166.946077 -26.264112)
			(xy 166.958203 -26.209675) (xy 166.978126 -26.157584) (xy 167.005422 -26.108949) (xy 167.039508 -26.064806)
			(xy 167.079657 -26.026097) (xy 167.125015 -25.993646) (xy 167.174615 -25.968145) (xy 167.227399 -25.950138)
			(xy 167.282242 -25.940008) (xy 167.337976 -25.937971) (xy 167.393413 -25.944071) (xy 167.44737 -25.958177)
			(xy 167.498699 -25.979989) (xy 167.546305 -26.009043) (xy 167.57597 -26.03373) (xy 173.367952 -26.03373)
			(xy 173.372023 -25.978108) (xy 173.384149 -25.923671) (xy 173.404072 -25.87158) (xy 173.431368 -25.822945)
			(xy 173.465454 -25.778802) (xy 173.505603 -25.740093) (xy 173.550961 -25.707642) (xy 173.600561 -25.682141)
			(xy 173.653345 -25.664134) (xy 173.708188 -25.654004) (xy 173.763922 -25.651967) (xy 173.819359 -25.658067)
			(xy 173.873316 -25.672173) (xy 173.924645 -25.693985) (xy 173.972251 -25.723039) (xy 174.015119 -25.758714)
			(xy 174.052336 -25.800251) (xy 174.083109 -25.846764) (xy 174.106781 -25.897261) (xy 174.122849 -25.950668)
			(xy 174.130969 -26.005844) (xy 174.131478 -26.03373) (xy 174.130969 -26.061616) (xy 174.122849 -26.116792)
			(xy 174.106781 -26.170199) (xy 174.083109 -26.220696) (xy 174.052875 -26.266394) (xy 176.620678 -26.266394)
			(xy 176.621164 -26.239143) (xy 176.62892 -26.185195) (xy 176.644275 -26.1329) (xy 176.666917 -26.083323)
			(xy 176.696383 -26.037473) (xy 176.732074 -25.996282) (xy 176.773265 -25.960591) (xy 176.819115 -25.931125)
			(xy 176.868692 -25.908483) (xy 176.920987 -25.893128) (xy 176.974935 -25.885372) (xy 177.029437 -25.885372)
			(xy 177.083385 -25.893128) (xy 177.13568 -25.908483) (xy 177.185257 -25.931125) (xy 177.231107 -25.960591)
			(xy 177.272298 -25.996282) (xy 177.307989 -26.037473) (xy 177.337455 -26.083323) (xy 177.360097 -26.1329)
			(xy 177.375452 -26.185195) (xy 177.383208 -26.239143) (xy 177.383694 -26.266394) (xy 177.383144 -26.295882)
			(xy 177.37405 -26.354153) (xy 177.356091 -26.410328) (xy 177.329697 -26.463069) (xy 177.295498 -26.511116)
			(xy 177.254308 -26.553325) (xy 177.23104 -26.571448) (xy 177.219892 -26.580313) (xy 177.202715 -26.603024)
			(xy 177.192474 -26.629594) (xy 177.189962 -26.657958) (xy 177.195375 -26.685913) (xy 177.208294 -26.711289)
			(xy 177.227714 -26.732115) (xy 177.239676 -26.73985) (xy 177.263407 -26.754763) (xy 177.306643 -26.790427)
			(xy 177.344196 -26.832032) (xy 177.375257 -26.878685) (xy 177.399158 -26.92938) (xy 177.415384 -26.983027)
			(xy 177.423585 -27.038471) (xy 177.42408 -27.066494) (xy 177.423594 -27.093745) (xy 177.415838 -27.147693)
			(xy 177.400483 -27.199988) (xy 177.377841 -27.249565) (xy 177.348375 -27.295415) (xy 177.312684 -27.336606)
			(xy 177.271493 -27.372297) (xy 177.225643 -27.401763) (xy 177.176066 -27.424405) (xy 177.123771 -27.43976)
			(xy 177.069823 -27.447516) (xy 177.015321 -27.447516) (xy 176.961373 -27.43976) (xy 176.909078 -27.424405)
			(xy 176.859501 -27.401763) (xy 176.813651 -27.372297) (xy 176.77246 -27.336606) (xy 176.736769 -27.295415)
			(xy 176.707303 -27.249565) (xy 176.684661 -27.199988) (xy 176.669306 -27.147693) (xy 176.66155 -27.093745)
			(xy 176.661064 -27.066494) (xy 176.661622 -27.037007) (xy 176.670717 -26.978737) (xy 176.688675 -26.922563)
			(xy 176.715067 -26.869822) (xy 176.749265 -26.821774) (xy 176.790451 -26.779564) (xy 176.813718 -26.76144)
			(xy 176.824782 -26.752475) (xy 176.841965 -26.72979) (xy 176.852218 -26.703242) (xy 176.854743 -26.674895)
			(xy 176.849344 -26.646953) (xy 176.836441 -26.621588) (xy 176.817036 -26.600771) (xy 176.805082 -26.593038)
			(xy 176.781336 -26.578148) (xy 176.738102 -26.542479) (xy 176.700551 -26.500869) (xy 176.669493 -26.454212)
			(xy 176.645595 -26.403514) (xy 176.629371 -26.349864) (xy 176.621172 -26.294418) (xy 176.620678 -26.266394)
			(xy 174.052875 -26.266394) (xy 174.052336 -26.267209) (xy 174.015119 -26.308746) (xy 173.972251 -26.344421)
			(xy 173.924645 -26.373475) (xy 173.873316 -26.395287) (xy 173.819359 -26.409393) (xy 173.763922 -26.415493)
			(xy 173.708188 -26.413456) (xy 173.653345 -26.403326) (xy 173.600561 -26.385319) (xy 173.550961 -26.359818)
			(xy 173.505603 -26.327367) (xy 173.465454 -26.288658) (xy 173.431368 -26.244515) (xy 173.404072 -26.19588)
			(xy 173.384149 -26.143789) (xy 173.372023 -26.089352) (xy 173.367952 -26.03373) (xy 167.57597 -26.03373)
			(xy 167.589173 -26.044718) (xy 167.62639 -26.086255) (xy 167.657163 -26.132768) (xy 167.680835 -26.183265)
			(xy 167.696903 -26.236672) (xy 167.705023 -26.291848) (xy 167.705532 -26.319734) (xy 167.705023 -26.34762)
			(xy 167.696903 -26.402796) (xy 167.680835 -26.456203) (xy 167.657163 -26.5067) (xy 167.62639 -26.553213)
			(xy 167.589173 -26.59475) (xy 167.546305 -26.630425) (xy 167.498699 -26.659479) (xy 167.44737 -26.681291)
			(xy 167.393413 -26.695397) (xy 167.337976 -26.701497) (xy 167.282242 -26.69946) (xy 167.227399 -26.68933)
			(xy 167.174615 -26.671323) (xy 167.125015 -26.645822) (xy 167.079657 -26.613371) (xy 167.039508 -26.574662)
			(xy 167.005422 -26.530519) (xy 166.978126 -26.481884) (xy 166.958203 -26.429793) (xy 166.946077 -26.375356)
			(xy 166.942006 -26.319734) (xy 161.950733 -26.319734) (xy 161.952685 -26.332996) (xy 161.953194 -26.360882)
			(xy 161.952685 -26.388768) (xy 161.944565 -26.443944) (xy 161.928497 -26.497351) (xy 161.904825 -26.547848)
			(xy 161.874052 -26.594361) (xy 161.836835 -26.635898) (xy 161.793967 -26.671573) (xy 161.746361 -26.700627)
			(xy 161.695032 -26.722439) (xy 161.641075 -26.736545) (xy 161.585638 -26.742645) (xy 161.529904 -26.740608)
			(xy 161.475061 -26.730478) (xy 161.422277 -26.712471) (xy 161.372677 -26.68697) (xy 161.327319 -26.654519)
			(xy 161.28717 -26.61581) (xy 161.253084 -26.571667) (xy 161.225788 -26.523032) (xy 161.205865 -26.470941)
			(xy 161.193739 -26.416504) (xy 161.189668 -26.360882) (xy 160.153604 -26.360882) (xy 160.441132 -26.64841)
			(xy 160.464272 -26.67217) (xy 160.505642 -26.724013) (xy 160.540946 -26.780163) (xy 160.569742 -26.839912)
			(xy 160.591666 -26.90251) (xy 160.606443 -26.96717) (xy 160.606903 -26.971244) (xy 162.951158 -26.971244)
			(xy 162.955229 -26.915622) (xy 162.967355 -26.861185) (xy 162.987278 -26.809094) (xy 163.014574 -26.760459)
			(xy 163.04866 -26.716316) (xy 163.088809 -26.677607) (xy 163.134167 -26.645156) (xy 163.183767 -26.619655)
			(xy 163.236551 -26.601648) (xy 163.291394 -26.591518) (xy 163.347128 -26.589481) (xy 163.402565 -26.595581)
			(xy 163.456522 -26.609687) (xy 163.507851 -26.631499) (xy 163.555457 -26.660553) (xy 163.598325 -26.696228)
			(xy 163.635542 -26.737765) (xy 163.666315 -26.784278) (xy 163.689987 -26.834775) (xy 163.706055 -26.888182)
			(xy 163.714175 -26.943358) (xy 163.714684 -26.971244) (xy 163.714175 -26.99913) (xy 163.706055 -27.054306)
			(xy 163.689987 -27.107713) (xy 163.666315 -27.15821) (xy 163.635542 -27.204723) (xy 163.598325 -27.24626)
			(xy 163.555457 -27.281935) (xy 163.507851 -27.310989) (xy 163.456522 -27.332801) (xy 163.402565 -27.346907)
			(xy 163.347128 -27.353007) (xy 163.291394 -27.35097) (xy 163.236551 -27.34084) (xy 163.183767 -27.322833)
			(xy 163.134167 -27.297332) (xy 163.088809 -27.264881) (xy 163.04866 -27.226172) (xy 163.014574 -27.182029)
			(xy 162.987278 -27.133394) (xy 162.967355 -27.081303) (xy 162.955229 -27.026866) (xy 162.951158 -26.971244)
			(xy 160.606903 -26.971244) (xy 160.613888 -27.033077) (xy 160.61436 -27.06624) (xy 160.61436 -29.114242)
			(xy 160.947608 -29.114242) (xy 160.947608 -28.250642) (xy 160.948098 -28.220674) (xy 160.955921 -28.161252)
			(xy 160.971434 -28.103359) (xy 160.99437 -28.047986) (xy 161.024337 -27.99608) (xy 161.060824 -27.94853)
			(xy 161.103204 -27.90615) (xy 161.150754 -27.869663) (xy 161.20266 -27.839696) (xy 161.258033 -27.81676)
			(xy 161.315926 -27.801247) (xy 161.375348 -27.793424) (xy 161.435284 -27.793424) (xy 161.494706 -27.801247)
			(xy 161.552599 -27.81676) (xy 161.607972 -27.839696) (xy 161.659878 -27.869663) (xy 161.707428 -27.90615)
			(xy 161.749808 -27.94853) (xy 161.786295 -27.99608) (xy 161.816262 -28.047986) (xy 161.839198 -28.103359)
			(xy 161.854711 -28.161252) (xy 161.862534 -28.220674) (xy 161.863024 -28.250642) (xy 161.863024 -28.469082)
			(xy 165.8526 -28.469082) (xy 165.856671 -28.41346) (xy 165.868797 -28.359023) (xy 165.88872 -28.306932)
			(xy 165.916016 -28.258297) (xy 165.950102 -28.214154) (xy 165.990251 -28.175445) (xy 166.035609 -28.142994)
			(xy 166.085209 -28.117493) (xy 166.137993 -28.099486) (xy 166.192836 -28.089356) (xy 166.24857 -28.087319)
			(xy 166.304007 -28.093419) (xy 166.357964 -28.107525) (xy 166.409293 -28.129337) (xy 166.425349 -28.139136)
			(xy 170.498006 -28.139136) (xy 170.502077 -28.083514) (xy 170.514203 -28.029077) (xy 170.534126 -27.976986)
			(xy 170.561422 -27.928351) (xy 170.595508 -27.884208) (xy 170.635657 -27.845499) (xy 170.681015 -27.813048)
			(xy 170.730615 -27.787547) (xy 170.783399 -27.76954) (xy 170.838242 -27.75941) (xy 170.893976 -27.757373)
			(xy 170.949413 -27.763473) (xy 171.00337 -27.777579) (xy 171.054699 -27.799391) (xy 171.102305 -27.828445)
			(xy 171.145173 -27.86412) (xy 171.18239 -27.905657) (xy 171.213163 -27.95217) (xy 171.236835 -28.002667)
			(xy 171.252903 -28.056074) (xy 171.261023 -28.11125) (xy 171.261532 -28.139136) (xy 171.768006 -28.139136)
			(xy 171.772077 -28.083514) (xy 171.784203 -28.029077) (xy 171.804126 -27.976986) (xy 171.831422 -27.928351)
			(xy 171.865508 -27.884208) (xy 171.905657 -27.845499) (xy 171.951015 -27.813048) (xy 172.000615 -27.787547)
			(xy 172.053399 -27.76954) (xy 172.108242 -27.75941) (xy 172.163976 -27.757373) (xy 172.219413 -27.763473)
			(xy 172.27337 -27.777579) (xy 172.324699 -27.799391) (xy 172.372305 -27.828445) (xy 172.415173 -27.86412)
			(xy 172.45239 -27.905657) (xy 172.483163 -27.95217) (xy 172.506835 -28.002667) (xy 172.522903 -28.056074)
			(xy 172.531023 -28.11125) (xy 172.531532 -28.139136) (xy 172.531023 -28.167022) (xy 172.522903 -28.222198)
			(xy 172.506835 -28.275605) (xy 172.483163 -28.326102) (xy 172.45239 -28.372615) (xy 172.415173 -28.414152)
			(xy 172.372305 -28.449827) (xy 172.324699 -28.478881) (xy 172.27337 -28.500693) (xy 172.219413 -28.514799)
			(xy 172.163976 -28.520899) (xy 172.108242 -28.518862) (xy 172.053399 -28.508732) (xy 172.000615 -28.490725)
			(xy 171.951015 -28.465224) (xy 171.905657 -28.432773) (xy 171.865508 -28.394064) (xy 171.831422 -28.349921)
			(xy 171.804126 -28.301286) (xy 171.784203 -28.249195) (xy 171.772077 -28.194758) (xy 171.768006 -28.139136)
			(xy 171.261532 -28.139136) (xy 171.261023 -28.167022) (xy 171.252903 -28.222198) (xy 171.236835 -28.275605)
			(xy 171.213163 -28.326102) (xy 171.18239 -28.372615) (xy 171.145173 -28.414152) (xy 171.102305 -28.449827)
			(xy 171.054699 -28.478881) (xy 171.00337 -28.500693) (xy 170.949413 -28.514799) (xy 170.893976 -28.520899)
			(xy 170.838242 -28.518862) (xy 170.783399 -28.508732) (xy 170.730615 -28.490725) (xy 170.681015 -28.465224)
			(xy 170.635657 -28.432773) (xy 170.595508 -28.394064) (xy 170.561422 -28.349921) (xy 170.534126 -28.301286)
			(xy 170.514203 -28.249195) (xy 170.502077 -28.194758) (xy 170.498006 -28.139136) (xy 166.425349 -28.139136)
			(xy 166.456899 -28.158391) (xy 166.499767 -28.194066) (xy 166.536984 -28.235603) (xy 166.567757 -28.282116)
			(xy 166.591429 -28.332613) (xy 166.607497 -28.38602) (xy 166.615617 -28.441196) (xy 166.616126 -28.469082)
			(xy 166.615617 -28.496968) (xy 166.607497 -28.552144) (xy 166.591429 -28.605551) (xy 166.567757 -28.656048)
			(xy 166.536984 -28.702561) (xy 166.499767 -28.744098) (xy 166.456899 -28.779773) (xy 166.409293 -28.808827)
			(xy 166.357964 -28.830639) (xy 166.304007 -28.844745) (xy 166.24857 -28.850845) (xy 166.192836 -28.848808)
			(xy 166.137993 -28.838678) (xy 166.085209 -28.820671) (xy 166.035609 -28.79517) (xy 165.990251 -28.762719)
			(xy 165.950102 -28.72401) (xy 165.916016 -28.679867) (xy 165.88872 -28.631232) (xy 165.868797 -28.579141)
			(xy 165.856671 -28.524704) (xy 165.8526 -28.469082) (xy 161.863024 -28.469082) (xy 161.863024 -29.114242)
			(xy 161.862891 -29.12237) (xy 176.706784 -29.12237) (xy 176.706784 -28.25877) (xy 176.707274 -28.228786)
			(xy 176.715102 -28.16933) (xy 176.730623 -28.111405) (xy 176.753572 -28.056001) (xy 176.783556 -28.004067)
			(xy 176.820062 -27.956491) (xy 176.862467 -27.914086) (xy 176.910043 -27.87758) (xy 176.961977 -27.847596)
			(xy 177.017381 -27.824647) (xy 177.075306 -27.809126) (xy 177.134762 -27.801298) (xy 177.19473 -27.801298)
			(xy 177.254186 -27.809126) (xy 177.312111 -27.824647) (xy 177.367515 -27.847596) (xy 177.419449 -27.87758)
			(xy 177.467025 -27.914086) (xy 177.50943 -27.956491) (xy 177.545936 -28.004067) (xy 177.57592 -28.056001)
			(xy 177.598869 -28.111405) (xy 177.61439 -28.16933) (xy 177.622218 -28.228786) (xy 177.622708 -28.25877)
			(xy 177.622708 -29.12237) (xy 177.622218 -29.152354) (xy 177.61439 -29.21181) (xy 177.598869 -29.269735)
			(xy 177.57592 -29.325139) (xy 177.545936 -29.377073) (xy 177.50943 -29.424649) (xy 177.467025 -29.467054)
			(xy 177.419449 -29.50356) (xy 177.367515 -29.533544) (xy 177.312111 -29.556493) (xy 177.254186 -29.572014)
			(xy 177.19473 -29.579842) (xy 177.134762 -29.579842) (xy 177.075306 -29.572014) (xy 177.017381 -29.556493)
			(xy 176.961977 -29.533544) (xy 176.910043 -29.50356) (xy 176.862467 -29.467054) (xy 176.820062 -29.424649)
			(xy 176.783556 -29.377073) (xy 176.753572 -29.325139) (xy 176.730623 -29.269735) (xy 176.715102 -29.21181)
			(xy 176.707274 -29.152354) (xy 176.706784 -29.12237) (xy 161.862891 -29.12237) (xy 161.862534 -29.14421)
			(xy 161.854711 -29.203632) (xy 161.839198 -29.261525) (xy 161.816262 -29.316898) (xy 161.786295 -29.368804)
			(xy 161.749808 -29.416354) (xy 161.707428 -29.458734) (xy 161.659878 -29.495221) (xy 161.607972 -29.525188)
			(xy 161.552599 -29.548124) (xy 161.494706 -29.563637) (xy 161.435284 -29.57146) (xy 161.375348 -29.57146)
			(xy 161.315926 -29.563637) (xy 161.258033 -29.548124) (xy 161.20266 -29.525188) (xy 161.150754 -29.495221)
			(xy 161.103204 -29.458734) (xy 161.060824 -29.416354) (xy 161.024337 -29.368804) (xy 160.99437 -29.316898)
			(xy 160.971434 -29.261525) (xy 160.955921 -29.203632) (xy 160.948098 -29.14421) (xy 160.947608 -29.114242)
			(xy 160.61436 -29.114242) (xy 160.61436 -30.92069) (xy 163.589716 -30.92069) (xy 163.589716 -30.05709)
			(xy 163.590206 -30.027122) (xy 163.598029 -29.9677) (xy 163.613542 -29.909807) (xy 163.636478 -29.854434)
			(xy 163.666445 -29.802528) (xy 163.702932 -29.754978) (xy 163.745312 -29.712598) (xy 163.792862 -29.676111)
			(xy 163.844768 -29.646144) (xy 163.900141 -29.623208) (xy 163.958034 -29.607695) (xy 164.017456 -29.599872)
			(xy 164.077392 -29.599872) (xy 164.136814 -29.607695) (xy 164.194707 -29.623208) (xy 164.25008 -29.646144)
			(xy 164.301986 -29.676111) (xy 164.349536 -29.712598) (xy 164.391916 -29.754978) (xy 164.428403 -29.802528)
			(xy 164.45837 -29.854434) (xy 164.481306 -29.909807) (xy 164.496819 -29.9677) (xy 164.504642 -30.027122)
			(xy 164.505132 -30.05709) (xy 164.505132 -30.376876) (xy 168.988994 -30.376876) (xy 168.989531 -30.347959)
			(xy 168.998251 -30.290787) (xy 169.015503 -30.235587) (xy 169.040891 -30.183625) (xy 169.073833 -30.136091)
			(xy 169.113574 -30.094075) (xy 169.13606 -30.075886) (xy 169.144874 -30.068286) (xy 169.155051 -30.047379)
			(xy 169.155618 -30.035754) (xy 169.155618 -29.955998) (xy 169.155059 -29.944369) (xy 169.144884 -29.923459)
			(xy 169.13606 -29.915866) (xy 169.113552 -29.897704) (xy 169.07382 -29.855677) (xy 169.040885 -29.808136)
			(xy 169.015501 -29.756169) (xy 168.99825 -29.700967) (xy 168.989526 -29.643794) (xy 168.988994 -29.614876)
			(xy 168.98948 -29.587625) (xy 168.997236 -29.533677) (xy 169.012591 -29.481382) (xy 169.035233 -29.431805)
			(xy 169.064699 -29.385955) (xy 169.10039 -29.344764) (xy 169.141581 -29.309073) (xy 169.187431 -29.279607)
			(xy 169.237008 -29.256965) (xy 169.289303 -29.24161) (xy 169.343251 -29.233854) (xy 169.397753 -29.233854)
			(xy 169.451701 -29.24161) (xy 169.503996 -29.256965) (xy 169.553573 -29.279607) (xy 169.599423 -29.309073)
			(xy 169.640614 -29.344764) (xy 169.676305 -29.385955) (xy 169.705771 -29.431805) (xy 169.728413 -29.481382)
			(xy 169.743768 -29.533677) (xy 169.751524 -29.587625) (xy 169.75201 -29.614876) (xy 169.751509 -29.643794)
			(xy 169.742781 -29.700968) (xy 169.725522 -29.756168) (xy 169.700127 -29.808131) (xy 169.667179 -29.855664)
			(xy 169.627432 -29.897678) (xy 169.604944 -29.915866) (xy 169.596153 -29.923488) (xy 169.585963 -29.944378)
			(xy 169.585386 -29.955998) (xy 169.585386 -30.035754) (xy 169.585913 -30.047387) (xy 169.596111 -30.068296)
			(xy 169.604944 -30.075886) (xy 169.62743 -30.094074) (xy 169.667163 -30.136096) (xy 169.7001 -30.183632)
			(xy 169.725488 -30.235593) (xy 169.742744 -30.290791) (xy 169.751474 -30.34796) (xy 169.75201 -30.376876)
			(xy 172.02912 -30.376876) (xy 172.029685 -30.347961) (xy 172.038403 -30.290791) (xy 172.055651 -30.235593)
			(xy 172.081034 -30.183631) (xy 172.11397 -30.136096) (xy 172.153704 -30.094077) (xy 172.176186 -30.075886)
			(xy 172.185004 -30.06829) (xy 172.195178 -30.04738) (xy 172.195744 -30.035754) (xy 172.195744 -29.955998)
			(xy 172.195211 -29.944365) (xy 172.18502 -29.923454) (xy 172.176186 -29.915866) (xy 172.153683 -29.897698)
			(xy 172.11395 -29.855673) (xy 172.081014 -29.808133) (xy 172.055629 -29.756167) (xy 172.038377 -29.700966)
			(xy 172.029652 -29.643793) (xy 172.02912 -29.614876) (xy 172.029606 -29.587625) (xy 172.037362 -29.533677)
			(xy 172.052717 -29.481382) (xy 172.075359 -29.431805) (xy 172.104825 -29.385955) (xy 172.140516 -29.344764)
			(xy 172.181707 -29.309073) (xy 172.227557 -29.279607) (xy 172.277134 -29.256965) (xy 172.329429 -29.24161)
			(xy 172.383377 -29.233854) (xy 172.437879 -29.233854) (xy 172.491827 -29.24161) (xy 172.544122 -29.256965)
			(xy 172.593699 -29.279607) (xy 172.639549 -29.309073) (xy 172.68074 -29.344764) (xy 172.716431 -29.385955)
			(xy 172.745897 -29.431805) (xy 172.768539 -29.481382) (xy 172.783894 -29.533677) (xy 172.79165 -29.587625)
			(xy 172.792136 -29.614876) (xy 172.791625 -29.643793) (xy 172.782898 -29.700966) (xy 172.76564 -29.756166)
			(xy 172.740247 -29.808128) (xy 172.707301 -29.855662) (xy 172.667557 -29.897677) (xy 172.64507 -29.915866)
			(xy 172.636283 -29.923493) (xy 172.62609 -29.944379) (xy 172.625512 -29.955998) (xy 172.625512 -30.035754)
			(xy 172.62603 -30.047389) (xy 172.636233 -30.068298) (xy 172.64507 -30.075886) (xy 172.667541 -30.094093)
			(xy 172.707278 -30.136108) (xy 172.740219 -30.18364) (xy 172.76561 -30.235598) (xy 172.782869 -30.290793)
			(xy 172.7916 -30.347961) (xy 172.792136 -30.376876) (xy 172.79165 -30.404127) (xy 172.783894 -30.458075)
			(xy 172.768539 -30.51037) (xy 172.745897 -30.559947) (xy 172.716431 -30.605797) (xy 172.68074 -30.646988)
			(xy 172.639549 -30.682679) (xy 172.593699 -30.712145) (xy 172.544122 -30.734787) (xy 172.491827 -30.750142)
			(xy 172.437879 -30.757898) (xy 172.383377 -30.757898) (xy 172.329429 -30.750142) (xy 172.277134 -30.734787)
			(xy 172.227557 -30.712145) (xy 172.181707 -30.682679) (xy 172.140516 -30.646988) (xy 172.104825 -30.605797)
			(xy 172.075359 -30.559947) (xy 172.052717 -30.51037) (xy 172.037362 -30.458075) (xy 172.029606 -30.404127)
			(xy 172.02912 -30.376876) (xy 169.75201 -30.376876) (xy 169.751524 -30.404127) (xy 169.743768 -30.458075)
			(xy 169.728413 -30.51037) (xy 169.705771 -30.559947) (xy 169.676305 -30.605797) (xy 169.640614 -30.646988)
			(xy 169.599423 -30.682679) (xy 169.553573 -30.712145) (xy 169.503996 -30.734787) (xy 169.451701 -30.750142)
			(xy 169.397753 -30.757898) (xy 169.343251 -30.757898) (xy 169.289303 -30.750142) (xy 169.237008 -30.734787)
			(xy 169.187431 -30.712145) (xy 169.141581 -30.682679) (xy 169.10039 -30.646988) (xy 169.064699 -30.605797)
			(xy 169.035233 -30.559947) (xy 169.012591 -30.51037) (xy 168.997236 -30.458075) (xy 168.98948 -30.404127)
			(xy 168.988994 -30.376876) (xy 164.505132 -30.376876) (xy 164.505132 -30.92069) (xy 164.505103 -30.922468)
			(xy 174.852584 -30.922468) (xy 174.852584 -30.058868) (xy 174.853074 -30.028884) (xy 174.860902 -29.969428)
			(xy 174.876423 -29.911503) (xy 174.899372 -29.856099) (xy 174.929356 -29.804165) (xy 174.965862 -29.756589)
			(xy 175.008267 -29.714184) (xy 175.055843 -29.677678) (xy 175.107777 -29.647694) (xy 175.163181 -29.624745)
			(xy 175.221106 -29.609224) (xy 175.280562 -29.601396) (xy 175.34053 -29.601396) (xy 175.399986 -29.609224)
			(xy 175.457911 -29.624745) (xy 175.513315 -29.647694) (xy 175.565249 -29.677678) (xy 175.612825 -29.714184)
			(xy 175.65523 -29.756589) (xy 175.691736 -29.804165) (xy 175.72172 -29.856099) (xy 175.744669 -29.911503)
			(xy 175.76019 -29.969428) (xy 175.768018 -30.028884) (xy 175.768508 -30.058868) (xy 175.768508 -30.922468)
			(xy 175.768018 -30.952452) (xy 175.76019 -31.011908) (xy 175.744669 -31.069833) (xy 175.72172 -31.125237)
			(xy 175.691736 -31.177171) (xy 175.65523 -31.224747) (xy 175.612825 -31.267152) (xy 175.565249 -31.303658)
			(xy 175.513315 -31.333642) (xy 175.457911 -31.356591) (xy 175.399986 -31.372112) (xy 175.34053 -31.37994)
			(xy 175.280562 -31.37994) (xy 175.221106 -31.372112) (xy 175.163181 -31.356591) (xy 175.107777 -31.333642)
			(xy 175.055843 -31.303658) (xy 175.008267 -31.267152) (xy 174.965862 -31.224747) (xy 174.929356 -31.177171)
			(xy 174.899372 -31.125237) (xy 174.876423 -31.069833) (xy 174.860902 -31.011908) (xy 174.853074 -30.952452)
			(xy 174.852584 -30.922468) (xy 164.505103 -30.922468) (xy 164.504642 -30.950658) (xy 164.496819 -31.01008)
			(xy 164.481306 -31.067973) (xy 164.45837 -31.123346) (xy 164.428403 -31.175252) (xy 164.391916 -31.222802)
			(xy 164.349536 -31.265182) (xy 164.301986 -31.301669) (xy 164.25008 -31.331636) (xy 164.194707 -31.354572)
			(xy 164.136814 -31.370085) (xy 164.077392 -31.377908) (xy 164.017456 -31.377908) (xy 163.958034 -31.370085)
			(xy 163.900141 -31.354572) (xy 163.844768 -31.331636) (xy 163.792862 -31.301669) (xy 163.745312 -31.265182)
			(xy 163.702932 -31.222802) (xy 163.666445 -31.175252) (xy 163.636478 -31.123346) (xy 163.613542 -31.067973)
			(xy 163.598029 -31.01008) (xy 163.590206 -30.950658) (xy 163.589716 -30.92069) (xy 160.61436 -30.92069)
			(xy 160.61436 -32.714184) (xy 160.947608 -32.714184) (xy 160.947608 -31.850584) (xy 160.948098 -31.820616)
			(xy 160.955921 -31.761194) (xy 160.971434 -31.703301) (xy 160.99437 -31.647928) (xy 161.024337 -31.596022)
			(xy 161.060824 -31.548472) (xy 161.103204 -31.506092) (xy 161.150754 -31.469605) (xy 161.20266 -31.439638)
			(xy 161.258033 -31.416702) (xy 161.315926 -31.401189) (xy 161.375348 -31.393366) (xy 161.435284 -31.393366)
			(xy 161.494706 -31.401189) (xy 161.552599 -31.416702) (xy 161.607972 -31.439638) (xy 161.659878 -31.469605)
			(xy 161.707428 -31.506092) (xy 161.749808 -31.548472) (xy 161.764702 -31.567882) (xy 169.09872 -31.567882)
			(xy 169.102791 -31.51226) (xy 169.114917 -31.457823) (xy 169.13484 -31.405732) (xy 169.162136 -31.357097)
			(xy 169.196222 -31.312954) (xy 169.236371 -31.274245) (xy 169.281729 -31.241794) (xy 169.331329 -31.216293)
			(xy 169.384113 -31.198286) (xy 169.438956 -31.188156) (xy 169.49469 -31.186119) (xy 169.550127 -31.192219)
			(xy 169.604084 -31.206325) (xy 169.655413 -31.228137) (xy 169.703019 -31.257191) (xy 169.745887 -31.292866)
			(xy 169.783104 -31.334403) (xy 169.813877 -31.380916) (xy 169.837549 -31.431413) (xy 169.853617 -31.48482)
			(xy 169.861737 -31.539996) (xy 169.862246 -31.567882) (xy 169.861737 -31.595768) (xy 169.853617 -31.650944)
			(xy 169.837549 -31.704351) (xy 169.830557 -31.719266) (xy 170.385484 -31.719266) (xy 170.389555 -31.663644)
			(xy 170.401681 -31.609207) (xy 170.421604 -31.557116) (xy 170.4489 -31.508481) (xy 170.482986 -31.464338)
			(xy 170.523135 -31.425629) (xy 170.568493 -31.393178) (xy 170.618093 -31.367677) (xy 170.670877 -31.34967)
			(xy 170.72572 -31.33954) (xy 170.781454 -31.337503) (xy 170.836891 -31.343603) (xy 170.890848 -31.357709)
			(xy 170.942177 -31.379521) (xy 170.989783 -31.408575) (xy 171.032651 -31.44425) (xy 171.069868 -31.485787)
			(xy 171.100641 -31.5323) (xy 171.124313 -31.582797) (xy 171.140381 -31.636204) (xy 171.144531 -31.664402)
			(xy 171.661072 -31.664402) (xy 171.665143 -31.60878) (xy 171.677269 -31.554343) (xy 171.697192 -31.502252)
			(xy 171.724488 -31.453617) (xy 171.758574 -31.409474) (xy 171.798723 -31.370765) (xy 171.844081 -31.338314)
			(xy 171.893681 -31.312813) (xy 171.946465 -31.294806) (xy 172.001308 -31.284676) (xy 172.057042 -31.282639)
			(xy 172.112479 -31.288739) (xy 172.166436 -31.302845) (xy 172.217765 -31.324657) (xy 172.265371 -31.353711)
			(xy 172.308239 -31.389386) (xy 172.345456 -31.430923) (xy 172.376229 -31.477436) (xy 172.399901 -31.527933)
			(xy 172.415969 -31.58134) (xy 172.424089 -31.636516) (xy 172.424598 -31.664402) (xy 172.424089 -31.692288)
			(xy 172.415969 -31.747464) (xy 172.407029 -31.777178) (xy 172.926246 -31.777178) (xy 172.930317 -31.721556)
			(xy 172.942443 -31.667119) (xy 172.962366 -31.615028) (xy 172.989662 -31.566393) (xy 173.023748 -31.52225)
			(xy 173.063897 -31.483541) (xy 173.109255 -31.45109) (xy 173.158855 -31.425589) (xy 173.211639 -31.407582)
			(xy 173.266482 -31.397452) (xy 173.322216 -31.395415) (xy 173.377653 -31.401515) (xy 173.43161 -31.415621)
			(xy 173.482939 -31.437433) (xy 173.530545 -31.466487) (xy 173.573413 -31.502162) (xy 173.61063 -31.543699)
			(xy 173.641403 -31.590212) (xy 173.665075 -31.640709) (xy 173.681143 -31.694116) (xy 173.689263 -31.749292)
			(xy 173.689772 -31.777178) (xy 173.689263 -31.805064) (xy 173.681143 -31.86024) (xy 173.665075 -31.913647)
			(xy 173.641403 -31.964144) (xy 173.61063 -32.010657) (xy 173.573413 -32.052194) (xy 173.530545 -32.087869)
			(xy 173.482939 -32.116923) (xy 173.43161 -32.138735) (xy 173.377653 -32.152841) (xy 173.322216 -32.158941)
			(xy 173.266482 -32.156904) (xy 173.211639 -32.146774) (xy 173.158855 -32.128767) (xy 173.109255 -32.103266)
			(xy 173.063897 -32.070815) (xy 173.023748 -32.032106) (xy 172.989662 -31.987963) (xy 172.962366 -31.939328)
			(xy 172.942443 -31.887237) (xy 172.930317 -31.8328) (xy 172.926246 -31.777178) (xy 172.407029 -31.777178)
			(xy 172.399901 -31.800871) (xy 172.376229 -31.851368) (xy 172.345456 -31.897881) (xy 172.308239 -31.939418)
			(xy 172.265371 -31.975093) (xy 172.217765 -32.004147) (xy 172.166436 -32.025959) (xy 172.112479 -32.040065)
			(xy 172.057042 -32.046165) (xy 172.001308 -32.044128) (xy 171.946465 -32.033998) (xy 171.893681 -32.015991)
			(xy 171.844081 -31.99049) (xy 171.798723 -31.958039) (xy 171.758574 -31.91933) (xy 171.724488 -31.875187)
			(xy 171.697192 -31.826552) (xy 171.677269 -31.774461) (xy 171.665143 -31.720024) (xy 171.661072 -31.664402)
			(xy 171.144531 -31.664402) (xy 171.148501 -31.69138) (xy 171.14901 -31.719266) (xy 171.148501 -31.747152)
			(xy 171.140381 -31.802328) (xy 171.124313 -31.855735) (xy 171.100641 -31.906232) (xy 171.069868 -31.952745)
			(xy 171.032651 -31.994282) (xy 170.989783 -32.029957) (xy 170.942177 -32.059011) (xy 170.890848 -32.080823)
			(xy 170.836891 -32.094929) (xy 170.781454 -32.101029) (xy 170.72572 -32.098992) (xy 170.670877 -32.088862)
			(xy 170.618093 -32.070855) (xy 170.568493 -32.045354) (xy 170.523135 -32.012903) (xy 170.482986 -31.974194)
			(xy 170.4489 -31.930051) (xy 170.421604 -31.881416) (xy 170.401681 -31.829325) (xy 170.389555 -31.774888)
			(xy 170.385484 -31.719266) (xy 169.830557 -31.719266) (xy 169.813877 -31.754848) (xy 169.783104 -31.801361)
			(xy 169.745887 -31.842898) (xy 169.703019 -31.878573) (xy 169.655413 -31.907627) (xy 169.604084 -31.929439)
			(xy 169.550127 -31.943545) (xy 169.49469 -31.949645) (xy 169.438956 -31.947608) (xy 169.384113 -31.937478)
			(xy 169.331329 -31.919471) (xy 169.281729 -31.89397) (xy 169.236371 -31.861519) (xy 169.196222 -31.82281)
			(xy 169.162136 -31.778667) (xy 169.13484 -31.730032) (xy 169.114917 -31.677941) (xy 169.102791 -31.623504)
			(xy 169.09872 -31.567882) (xy 161.764702 -31.567882) (xy 161.786295 -31.596022) (xy 161.816262 -31.647928)
			(xy 161.839198 -31.703301) (xy 161.854711 -31.761194) (xy 161.862534 -31.820616) (xy 161.863024 -31.850584)
			(xy 161.863024 -32.714184) (xy 161.862891 -32.722312) (xy 176.706784 -32.722312) (xy 176.706784 -31.858712)
			(xy 176.707274 -31.828728) (xy 176.715102 -31.769272) (xy 176.730623 -31.711347) (xy 176.753572 -31.655943)
			(xy 176.783556 -31.604009) (xy 176.820062 -31.556433) (xy 176.862467 -31.514028) (xy 176.910043 -31.477522)
			(xy 176.961977 -31.447538) (xy 177.017381 -31.424589) (xy 177.075306 -31.409068) (xy 177.134762 -31.40124)
			(xy 177.19473 -31.40124) (xy 177.254186 -31.409068) (xy 177.312111 -31.424589) (xy 177.367515 -31.447538)
			(xy 177.419449 -31.477522) (xy 177.467025 -31.514028) (xy 177.50943 -31.556433) (xy 177.545936 -31.604009)
			(xy 177.57592 -31.655943) (xy 177.598869 -31.711347) (xy 177.61439 -31.769272) (xy 177.622218 -31.828728)
			(xy 177.622708 -31.858712) (xy 177.622708 -32.722312) (xy 177.622218 -32.752296) (xy 177.61439 -32.811752)
			(xy 177.598869 -32.869677) (xy 177.57592 -32.925081) (xy 177.545936 -32.977015) (xy 177.50943 -33.024591)
			(xy 177.467025 -33.066996) (xy 177.419449 -33.103502) (xy 177.367515 -33.133486) (xy 177.312111 -33.156435)
			(xy 177.254186 -33.171956) (xy 177.19473 -33.179784) (xy 177.134762 -33.179784) (xy 177.075306 -33.171956)
			(xy 177.017381 -33.156435) (xy 176.961977 -33.133486) (xy 176.910043 -33.103502) (xy 176.862467 -33.066996)
			(xy 176.820062 -33.024591) (xy 176.783556 -32.977015) (xy 176.753572 -32.925081) (xy 176.730623 -32.869677)
			(xy 176.715102 -32.811752) (xy 176.707274 -32.752296) (xy 176.706784 -32.722312) (xy 161.862891 -32.722312)
			(xy 161.862534 -32.744152) (xy 161.854711 -32.803574) (xy 161.839198 -32.861467) (xy 161.816262 -32.91684)
			(xy 161.786295 -32.968746) (xy 161.749808 -33.016296) (xy 161.707428 -33.058676) (xy 161.659878 -33.095163)
			(xy 161.607972 -33.12513) (xy 161.552599 -33.148066) (xy 161.494706 -33.163579) (xy 161.435284 -33.171402)
			(xy 161.375348 -33.171402) (xy 161.315926 -33.163579) (xy 161.258033 -33.148066) (xy 161.20266 -33.12513)
			(xy 161.150754 -33.095163) (xy 161.103204 -33.058676) (xy 161.060824 -33.016296) (xy 161.024337 -32.968746)
			(xy 160.99437 -32.91684) (xy 160.971434 -32.861467) (xy 160.955921 -32.803574) (xy 160.948098 -32.744152)
			(xy 160.947608 -32.714184) (xy 160.61436 -32.714184) (xy 160.61436 -34.520886) (xy 163.589716 -34.520886)
			(xy 163.589716 -33.657286) (xy 163.590206 -33.627318) (xy 163.598029 -33.567896) (xy 163.613542 -33.510003)
			(xy 163.636478 -33.45463) (xy 163.666445 -33.402724) (xy 163.702932 -33.355174) (xy 163.745312 -33.312794)
			(xy 163.792862 -33.276307) (xy 163.844768 -33.24634) (xy 163.900141 -33.223404) (xy 163.958034 -33.207891)
			(xy 164.017456 -33.200068) (xy 164.077392 -33.200068) (xy 164.136814 -33.207891) (xy 164.194707 -33.223404)
			(xy 164.25008 -33.24634) (xy 164.301986 -33.276307) (xy 164.349536 -33.312794) (xy 164.391916 -33.355174)
			(xy 164.428403 -33.402724) (xy 164.45837 -33.45463) (xy 164.481306 -33.510003) (xy 164.496819 -33.567896)
			(xy 164.504642 -33.627318) (xy 164.505132 -33.657286) (xy 164.505132 -34.520886) (xy 164.505107 -34.52241)
			(xy 174.852584 -34.52241) (xy 174.852584 -33.65881) (xy 174.853074 -33.628826) (xy 174.860902 -33.56937)
			(xy 174.876423 -33.511445) (xy 174.899372 -33.456041) (xy 174.929356 -33.404107) (xy 174.965862 -33.356531)
			(xy 175.008267 -33.314126) (xy 175.055843 -33.27762) (xy 175.107777 -33.247636) (xy 175.163181 -33.224687)
			(xy 175.221106 -33.209166) (xy 175.280562 -33.201338) (xy 175.34053 -33.201338) (xy 175.399986 -33.209166)
			(xy 175.457911 -33.224687) (xy 175.513315 -33.247636) (xy 175.565249 -33.27762) (xy 175.612825 -33.314126)
			(xy 175.65523 -33.356531) (xy 175.691736 -33.404107) (xy 175.72172 -33.456041) (xy 175.744669 -33.511445)
			(xy 175.76019 -33.56937) (xy 175.768018 -33.628826) (xy 175.768508 -33.65881) (xy 175.768508 -34.52241)
			(xy 175.768018 -34.552394) (xy 175.76019 -34.61185) (xy 175.744669 -34.669775) (xy 175.72172 -34.725179)
			(xy 175.691736 -34.777113) (xy 175.65523 -34.824689) (xy 175.612825 -34.867094) (xy 175.565249 -34.9036)
			(xy 175.513315 -34.933584) (xy 175.457911 -34.956533) (xy 175.399986 -34.972054) (xy 175.34053 -34.979882)
			(xy 175.280562 -34.979882) (xy 175.221106 -34.972054) (xy 175.163181 -34.956533) (xy 175.107777 -34.933584)
			(xy 175.055843 -34.9036) (xy 175.008267 -34.867094) (xy 174.965862 -34.824689) (xy 174.929356 -34.777113)
			(xy 174.899372 -34.725179) (xy 174.876423 -34.669775) (xy 174.860902 -34.61185) (xy 174.853074 -34.552394)
			(xy 174.852584 -34.52241) (xy 164.505107 -34.52241) (xy 164.504642 -34.550854) (xy 164.496819 -34.610276)
			(xy 164.481306 -34.668169) (xy 164.45837 -34.723542) (xy 164.428403 -34.775448) (xy 164.391916 -34.822998)
			(xy 164.349536 -34.865378) (xy 164.301986 -34.901865) (xy 164.25008 -34.931832) (xy 164.194707 -34.954768)
			(xy 164.136814 -34.970281) (xy 164.077392 -34.978104) (xy 164.017456 -34.978104) (xy 163.958034 -34.970281)
			(xy 163.900141 -34.954768) (xy 163.844768 -34.931832) (xy 163.792862 -34.901865) (xy 163.745312 -34.865378)
			(xy 163.702932 -34.822998) (xy 163.666445 -34.775448) (xy 163.636478 -34.723542) (xy 163.613542 -34.668169)
			(xy 163.598029 -34.610276) (xy 163.590206 -34.550854) (xy 163.589716 -34.520886) (xy 160.61436 -34.520886)
			(xy 160.61436 -35.264852) (xy 172.002448 -35.264852) (xy 172.006519 -35.20923) (xy 172.018645 -35.154793)
			(xy 172.038568 -35.102702) (xy 172.065864 -35.054067) (xy 172.09995 -35.009924) (xy 172.140099 -34.971215)
			(xy 172.185457 -34.938764) (xy 172.235057 -34.913263) (xy 172.287841 -34.895256) (xy 172.342684 -34.885126)
			(xy 172.398418 -34.883089) (xy 172.453855 -34.889189) (xy 172.507812 -34.903295) (xy 172.559141 -34.925107)
			(xy 172.606747 -34.954161) (xy 172.649615 -34.989836) (xy 172.686832 -35.031373) (xy 172.717605 -35.077886)
			(xy 172.741277 -35.128383) (xy 172.757345 -35.18179) (xy 172.765465 -35.236966) (xy 172.765974 -35.264852)
			(xy 172.765465 -35.292738) (xy 172.757345 -35.347914) (xy 172.741277 -35.401321) (xy 172.717605 -35.451818)
			(xy 172.686832 -35.498331) (xy 172.649615 -35.539868) (xy 172.606747 -35.575543) (xy 172.559141 -35.604597)
			(xy 172.507812 -35.626409) (xy 172.453855 -35.640515) (xy 172.398418 -35.646615) (xy 172.342684 -35.644578)
			(xy 172.287841 -35.634448) (xy 172.235057 -35.616441) (xy 172.185457 -35.59094) (xy 172.140099 -35.558489)
			(xy 172.09995 -35.51978) (xy 172.065864 -35.475637) (xy 172.038568 -35.427002) (xy 172.018645 -35.374911)
			(xy 172.006519 -35.320474) (xy 172.002448 -35.264852) (xy 160.61436 -35.264852) (xy 160.61436 -35.876738)
			(xy 160.817304 -35.876738) (xy 160.821375 -35.821116) (xy 160.833501 -35.766679) (xy 160.853424 -35.714588)
			(xy 160.88072 -35.665953) (xy 160.914806 -35.62181) (xy 160.954955 -35.583101) (xy 161.000313 -35.55065)
			(xy 161.049913 -35.525149) (xy 161.102697 -35.507142) (xy 161.15754 -35.497012) (xy 161.213274 -35.494975)
			(xy 161.268711 -35.501075) (xy 161.322668 -35.515181) (xy 161.373997 -35.536993) (xy 161.421603 -35.566047)
			(xy 161.464471 -35.601722) (xy 161.501688 -35.643259) (xy 161.532461 -35.689772) (xy 161.556133 -35.740269)
			(xy 161.572201 -35.793676) (xy 161.580321 -35.848852) (xy 161.58083 -35.876738) (xy 164.888924 -35.876738)
			(xy 164.892995 -35.821116) (xy 164.905121 -35.766679) (xy 164.925044 -35.714588) (xy 164.95234 -35.665953)
			(xy 164.986426 -35.62181) (xy 165.026575 -35.583101) (xy 165.071933 -35.55065) (xy 165.121533 -35.525149)
			(xy 165.174317 -35.507142) (xy 165.22916 -35.497012) (xy 165.284894 -35.494975) (xy 165.340331 -35.501075)
			(xy 165.394288 -35.515181) (xy 165.445617 -35.536993) (xy 165.493223 -35.566047) (xy 165.536091 -35.601722)
			(xy 165.573308 -35.643259) (xy 165.604081 -35.689772) (xy 165.627753 -35.740269) (xy 165.643821 -35.793676)
			(xy 165.651941 -35.848852) (xy 165.65245 -35.876738) (xy 165.651941 -35.904624) (xy 165.643821 -35.9598)
			(xy 165.627753 -36.013207) (xy 165.604081 -36.063704) (xy 165.573308 -36.110217) (xy 165.536091 -36.151754)
			(xy 165.493223 -36.187429) (xy 165.445617 -36.216483) (xy 165.394288 -36.238295) (xy 165.340331 -36.252401)
			(xy 165.284894 -36.258501) (xy 165.22916 -36.256464) (xy 165.174317 -36.246334) (xy 165.121533 -36.228327)
			(xy 165.071933 -36.202826) (xy 165.026575 -36.170375) (xy 164.986426 -36.131666) (xy 164.95234 -36.087523)
			(xy 164.925044 -36.038888) (xy 164.905121 -35.986797) (xy 164.892995 -35.93236) (xy 164.888924 -35.876738)
			(xy 161.58083 -35.876738) (xy 161.580321 -35.904624) (xy 161.572201 -35.9598) (xy 161.556133 -36.013207)
			(xy 161.532461 -36.063704) (xy 161.501688 -36.110217) (xy 161.464471 -36.151754) (xy 161.421603 -36.187429)
			(xy 161.373997 -36.216483) (xy 161.322668 -36.238295) (xy 161.268711 -36.252401) (xy 161.213274 -36.258501)
			(xy 161.15754 -36.256464) (xy 161.102697 -36.246334) (xy 161.049913 -36.228327) (xy 161.000313 -36.202826)
			(xy 160.954955 -36.170375) (xy 160.914806 -36.131666) (xy 160.88072 -36.087523) (xy 160.853424 -36.038888)
			(xy 160.833501 -35.986797) (xy 160.821375 -35.93236) (xy 160.817304 -35.876738) (xy 160.61436 -35.876738)
			(xy 160.61436 -36.480496) (xy 160.613933 -36.50996) (xy 162.713922 -36.50996) (xy 162.717993 -36.454338)
			(xy 162.730119 -36.399901) (xy 162.750042 -36.34781) (xy 162.777338 -36.299175) (xy 162.811424 -36.255032)
			(xy 162.851573 -36.216323) (xy 162.896931 -36.183872) (xy 162.946531 -36.158371) (xy 162.999315 -36.140364)
			(xy 163.054158 -36.130234) (xy 163.109892 -36.128197) (xy 163.165329 -36.134297) (xy 163.219286 -36.148403)
			(xy 163.270615 -36.170215) (xy 163.318221 -36.199269) (xy 163.361089 -36.234944) (xy 163.398306 -36.276481)
			(xy 163.429079 -36.322994) (xy 163.452751 -36.373491) (xy 163.468819 -36.426898) (xy 163.472744 -36.453572)
			(xy 166.028622 -36.453572) (xy 166.032693 -36.39795) (xy 166.044819 -36.343513) (xy 166.064742 -36.291422)
			(xy 166.092038 -36.242787) (xy 166.126124 -36.198644) (xy 166.166273 -36.159935) (xy 166.211631 -36.127484)
			(xy 166.261231 -36.101983) (xy 166.314015 -36.083976) (xy 166.368858 -36.073846) (xy 166.424592 -36.071809)
			(xy 166.480029 -36.077909) (xy 166.533986 -36.092015) (xy 166.585315 -36.113827) (xy 166.632921 -36.142881)
			(xy 166.675789 -36.178556) (xy 166.713006 -36.220093) (xy 166.743779 -36.266606) (xy 166.753315 -36.286948)
			(xy 173.300388 -36.286948) (xy 173.304459 -36.231326) (xy 173.316585 -36.176889) (xy 173.336508 -36.124798)
			(xy 173.363804 -36.076163) (xy 173.39789 -36.03202) (xy 173.438039 -35.993311) (xy 173.483397 -35.96086)
			(xy 173.532997 -35.935359) (xy 173.585781 -35.917352) (xy 173.640624 -35.907222) (xy 173.696358 -35.905185)
			(xy 173.751795 -35.911285) (xy 173.805752 -35.925391) (xy 173.857081 -35.947203) (xy 173.904687 -35.976257)
			(xy 173.947555 -36.011932) (xy 173.984772 -36.053469) (xy 174.015545 -36.099982) (xy 174.039217 -36.150479)
			(xy 174.055285 -36.203886) (xy 174.063405 -36.259062) (xy 174.063914 -36.286948) (xy 174.063405 -36.314834)
			(xy 174.055285 -36.37001) (xy 174.039217 -36.423417) (xy 174.015545 -36.473914) (xy 173.988 -36.515548)
			(xy 175.114202 -36.515548) (xy 175.118273 -36.459926) (xy 175.130399 -36.405489) (xy 175.150322 -36.353398)
			(xy 175.177618 -36.304763) (xy 175.211704 -36.26062) (xy 175.251853 -36.221911) (xy 175.297211 -36.18946)
			(xy 175.346811 -36.163959) (xy 175.399595 -36.145952) (xy 175.454438 -36.135822) (xy 175.510172 -36.133785)
			(xy 175.565609 -36.139885) (xy 175.619566 -36.153991) (xy 175.670895 -36.175803) (xy 175.718501 -36.204857)
			(xy 175.761369 -36.240532) (xy 175.798586 -36.282069) (xy 175.829359 -36.328582) (xy 175.853031 -36.379079)
			(xy 175.869099 -36.432486) (xy 175.877219 -36.487662) (xy 175.877728 -36.515548) (xy 175.877219 -36.543434)
			(xy 175.869099 -36.59861) (xy 175.868642 -36.60013) (xy 180.098199 -36.60013) (xy 180.102204 -36.512222)
			(xy 180.114187 -36.425042) (xy 180.134047 -36.339313) (xy 180.161622 -36.255745) (xy 180.196681 -36.175031)
			(xy 180.238934 -36.097839) (xy 180.288032 -36.02481) (xy 180.343568 -35.956548) (xy 180.40508 -35.893618)
			(xy 180.472061 -35.836544) (xy 180.543954 -35.785796) (xy 180.620163 -35.741796) (xy 180.700058 -35.704909)
			(xy 180.782977 -35.67544) (xy 180.868232 -35.653633) (xy 180.955116 -35.639669) (xy 181.04291 -35.633663)
			(xy 181.130887 -35.635667) (xy 181.218317 -35.645662) (xy 181.304476 -35.663566) (xy 181.38865 -35.68923)
			(xy 181.470141 -35.722443) (xy 181.548275 -35.762929) (xy 181.622403 -35.810351) (xy 181.691911 -35.864318)
			(xy 181.756225 -35.924383) (xy 181.814809 -35.990047) (xy 181.86718 -36.060766) (xy 181.912903 -36.135954)
			(xy 181.9516 -36.214989) (xy 181.982949 -36.297215) (xy 182.006691 -36.381951) (xy 182.022629 -36.468495)
			(xy 182.030631 -36.55613) (xy 182.031132 -36.60013) (xy 182.030631 -36.64413) (xy 182.022629 -36.731765)
			(xy 182.006691 -36.818309) (xy 181.982949 -36.903045) (xy 181.9516 -36.985271) (xy 181.912903 -37.064306)
			(xy 181.86718 -37.139494) (xy 181.814809 -37.210213) (xy 181.756225 -37.275877) (xy 181.691911 -37.335942)
			(xy 181.622403 -37.389909) (xy 181.548275 -37.437331) (xy 181.470141 -37.477817) (xy 181.38865 -37.51103)
			(xy 181.304476 -37.536694) (xy 181.218317 -37.554598) (xy 181.130887 -37.564593) (xy 181.04291 -37.566597)
			(xy 180.955116 -37.560591) (xy 180.868232 -37.546627) (xy 180.782977 -37.52482) (xy 180.700058 -37.495351)
			(xy 180.620163 -37.458464) (xy 180.543954 -37.414464) (xy 180.472061 -37.363716) (xy 180.40508 -37.306642)
			(xy 180.343568 -37.243712) (xy 180.288032 -37.17545) (xy 180.238934 -37.102421) (xy 180.196681 -37.025229)
			(xy 180.161622 -36.944515) (xy 180.134047 -36.860947) (xy 180.114187 -36.775218) (xy 180.102204 -36.688038)
			(xy 180.098199 -36.60013) (xy 175.868642 -36.60013) (xy 175.853031 -36.652017) (xy 175.829359 -36.702514)
			(xy 175.798586 -36.749027) (xy 175.761369 -36.790564) (xy 175.718501 -36.826239) (xy 175.670895 -36.855293)
			(xy 175.619566 -36.877105) (xy 175.565609 -36.891211) (xy 175.510172 -36.897311) (xy 175.454438 -36.895274)
			(xy 175.399595 -36.885144) (xy 175.346811 -36.867137) (xy 175.297211 -36.841636) (xy 175.251853 -36.809185)
			(xy 175.211704 -36.770476) (xy 175.177618 -36.726333) (xy 175.150322 -36.677698) (xy 175.130399 -36.625607)
			(xy 175.118273 -36.57117) (xy 175.114202 -36.515548) (xy 173.988 -36.515548) (xy 173.984772 -36.520427)
			(xy 173.947555 -36.561964) (xy 173.904687 -36.597639) (xy 173.857081 -36.626693) (xy 173.805752 -36.648505)
			(xy 173.751795 -36.662611) (xy 173.696358 -36.668711) (xy 173.640624 -36.666674) (xy 173.585781 -36.656544)
			(xy 173.532997 -36.638537) (xy 173.483397 -36.613036) (xy 173.438039 -36.580585) (xy 173.39789 -36.541876)
			(xy 173.363804 -36.497733) (xy 173.336508 -36.449098) (xy 173.316585 -36.397007) (xy 173.304459 -36.34257)
			(xy 173.300388 -36.286948) (xy 166.753315 -36.286948) (xy 166.767451 -36.317103) (xy 166.783519 -36.37051)
			(xy 166.791639 -36.425686) (xy 166.792148 -36.453572) (xy 166.791639 -36.481458) (xy 166.783519 -36.536634)
			(xy 166.767451 -36.590041) (xy 166.743779 -36.640538) (xy 166.713006 -36.687051) (xy 166.675789 -36.728588)
			(xy 166.632921 -36.764263) (xy 166.585315 -36.793317) (xy 166.533986 -36.815129) (xy 166.480029 -36.829235)
			(xy 166.424592 -36.835335) (xy 166.368858 -36.833298) (xy 166.314015 -36.823168) (xy 166.261231 -36.805161)
			(xy 166.211631 -36.77966) (xy 166.166273 -36.747209) (xy 166.126124 -36.7085) (xy 166.092038 -36.664357)
			(xy 166.064742 -36.615722) (xy 166.044819 -36.563631) (xy 166.032693 -36.509194) (xy 166.028622 -36.453572)
			(xy 163.472744 -36.453572) (xy 163.476939 -36.482074) (xy 163.477448 -36.50996) (xy 163.476939 -36.537846)
			(xy 163.468819 -36.593022) (xy 163.452751 -36.646429) (xy 163.429079 -36.696926) (xy 163.398306 -36.743439)
			(xy 163.361089 -36.784976) (xy 163.318221 -36.820651) (xy 163.270615 -36.849705) (xy 163.219286 -36.871517)
			(xy 163.165329 -36.885623) (xy 163.109892 -36.891723) (xy 163.054158 -36.889686) (xy 162.999315 -36.879556)
			(xy 162.946531 -36.861549) (xy 162.896931 -36.836048) (xy 162.851573 -36.803597) (xy 162.811424 -36.764888)
			(xy 162.777338 -36.720745) (xy 162.750042 -36.67211) (xy 162.730119 -36.620019) (xy 162.717993 -36.565582)
			(xy 162.713922 -36.50996) (xy 160.613933 -36.50996) (xy 160.613879 -36.513658) (xy 160.606424 -36.579561)
			(xy 160.591641 -36.644217) (xy 160.569714 -36.706811) (xy 160.540921 -36.766559) (xy 160.505622 -36.822709)
			(xy 160.464261 -36.874556) (xy 160.441132 -36.898326) (xy 160.343088 -36.99637) (xy 160.343088 -37.000688)
			(xy 160.344104 -37.006022) (xy 160.349184 -37.031676) (xy 160.360614 -37.088572) (xy 160.362035 -37.094161)
			(xy 160.367039 -37.104548) (xy 160.37052 -37.109146) (xy 160.374584 -37.113972) (xy 160.38449 -37.121592)
			(xy 160.38703 -37.122608) (xy 160.390078 -37.123878) (xy 160.415585 -37.135218) (xy 160.463255 -37.16426)
			(xy 160.506184 -37.199939) (xy 160.543455 -37.241494) (xy 160.574272 -37.288036) (xy 160.597978 -37.338573)
			(xy 160.614065 -37.392024) (xy 160.622191 -37.44725) (xy 160.622742 -37.47516) (xy 160.622282 -37.502416)
			(xy 160.61453 -37.556373) (xy 160.599178 -37.608677) (xy 160.576538 -37.658265) (xy 160.573908 -37.662358)
			(xy 162.048442 -37.662358) (xy 162.052513 -37.606736) (xy 162.064639 -37.552299) (xy 162.084562 -37.500208)
			(xy 162.111858 -37.451573) (xy 162.145944 -37.40743) (xy 162.186093 -37.368721) (xy 162.231451 -37.33627)
			(xy 162.281051 -37.310769) (xy 162.333835 -37.292762) (xy 162.388678 -37.282632) (xy 162.444412 -37.280595)
			(xy 162.499849 -37.286695) (xy 162.553806 -37.300801) (xy 162.605135 -37.322613) (xy 162.652741 -37.351667)
			(xy 162.695609 -37.387342) (xy 162.732826 -37.428879) (xy 162.763599 -37.475392) (xy 162.787271 -37.525889)
			(xy 162.803339 -37.579296) (xy 162.811459 -37.634472) (xy 162.811968 -37.662358) (xy 162.811459 -37.690244)
			(xy 162.803339 -37.74542) (xy 162.794705 -37.774118) (xy 173.564802 -37.774118) (xy 173.568873 -37.718496)
			(xy 173.580999 -37.664059) (xy 173.600922 -37.611968) (xy 173.628218 -37.563333) (xy 173.662304 -37.51919)
			(xy 173.702453 -37.480481) (xy 173.747811 -37.44803) (xy 173.797411 -37.422529) (xy 173.850195 -37.404522)
			(xy 173.905038 -37.394392) (xy 173.960772 -37.392355) (xy 174.016209 -37.398455) (xy 174.070166 -37.412561)
			(xy 174.121495 -37.434373) (xy 174.169101 -37.463427) (xy 174.211969 -37.499102) (xy 174.249186 -37.540639)
			(xy 174.279959 -37.587152) (xy 174.303631 -37.637649) (xy 174.319699 -37.691056) (xy 174.327819 -37.746232)
			(xy 174.328328 -37.774118) (xy 174.327819 -37.802004) (xy 174.319699 -37.85718) (xy 174.303631 -37.910587)
			(xy 174.279959 -37.961084) (xy 174.249186 -38.007597) (xy 174.211969 -38.049134) (xy 174.169101 -38.084809)
			(xy 174.121495 -38.113863) (xy 174.070166 -38.135675) (xy 174.016209 -38.149781) (xy 173.960772 -38.155881)
			(xy 173.905038 -38.153844) (xy 173.850195 -38.143714) (xy 173.797411 -38.125707) (xy 173.747811 -38.100206)
			(xy 173.702453 -38.067755) (xy 173.662304 -38.029046) (xy 173.628218 -37.984903) (xy 173.600922 -37.936268)
			(xy 173.580999 -37.884177) (xy 173.568873 -37.82974) (xy 173.564802 -37.774118) (xy 162.794705 -37.774118)
			(xy 162.787271 -37.798827) (xy 162.763599 -37.849324) (xy 162.732826 -37.895837) (xy 162.695609 -37.937374)
			(xy 162.652741 -37.973049) (xy 162.605135 -38.002103) (xy 162.553806 -38.023915) (xy 162.499849 -38.038021)
			(xy 162.444412 -38.044121) (xy 162.388678 -38.042084) (xy 162.333835 -38.031954) (xy 162.281051 -38.013947)
			(xy 162.231451 -37.988446) (xy 162.186093 -37.955995) (xy 162.145944 -37.917286) (xy 162.111858 -37.873143)
			(xy 162.084562 -37.824508) (xy 162.064639 -37.772417) (xy 162.052513 -37.71798) (xy 162.048442 -37.662358)
			(xy 160.573908 -37.662358) (xy 160.547071 -37.704125) (xy 160.511378 -37.745326) (xy 160.470185 -37.781027)
			(xy 160.42433 -37.810502) (xy 160.374747 -37.833152) (xy 160.322445 -37.848514) (xy 160.26849 -37.856277)
			(xy 160.241234 -37.856668) (xy 160.21331 -37.856184) (xy 160.158058 -37.848053) (xy 160.104579 -37.831958)
			(xy 160.054017 -37.808244) (xy 160.007448 -37.777416) (xy 159.965868 -37.740132) (xy 159.930164 -37.697188)
			(xy 159.901097 -37.649501) (xy 159.889698 -37.624004) (xy 159.889444 -37.62375) (xy 159.8869 -37.618147)
			(xy 159.879589 -37.608253) (xy 159.874966 -37.604192) (xy 159.870394 -37.600382) (xy 159.859472 -37.595302)
			(xy 159.83331 -37.589968) (xy 159.832802 -37.589968) (xy 159.767778 -37.577522) (xy 159.762698 -37.577014)
			(xy 158.609506 -38.729952) (xy 165.800997 -38.729952) (xy 165.800997 -38.675448) (xy 165.808755 -38.6215)
			(xy 165.824111 -38.569205) (xy 165.846754 -38.519627) (xy 165.876222 -38.473777) (xy 165.911916 -38.432588)
			(xy 165.953109 -38.396898) (xy 165.998962 -38.367435) (xy 166.048542 -38.344797) (xy 166.100839 -38.329446)
			(xy 166.154788 -38.321695) (xy 166.18204 -38.321234) (xy 166.210343 -38.321755) (xy 166.266331 -38.330099)
			(xy 166.32047 -38.346628) (xy 166.371571 -38.370978) (xy 166.418512 -38.402614) (xy 166.46026 -38.440841)
			(xy 166.495899 -38.48482) (xy 166.510716 -38.50894) (xy 166.518326 -38.520966) (xy 166.538943 -38.540567)
			(xy 166.564172 -38.55371) (xy 166.59205 -38.55937) (xy 166.620407 -38.557108) (xy 166.647036 -38.547099)
			(xy 166.669862 -38.530123) (xy 166.678864 -38.5191) (xy 166.697076 -38.496245) (xy 166.739234 -38.45578)
			(xy 166.787064 -38.42221) (xy 166.839451 -38.396319) (xy 166.895171 -38.378712) (xy 166.952922 -38.3698)
			(xy 166.98214 -38.36924) (xy 167.009393 -38.369633) (xy 167.063343 -38.377395) (xy 167.11564 -38.392755)
			(xy 167.165218 -38.415402) (xy 167.211069 -38.444873) (xy 167.25226 -38.480569) (xy 167.287951 -38.521763)
			(xy 167.317418 -38.567617) (xy 167.340059 -38.617198) (xy 167.355414 -38.669496) (xy 167.36317 -38.723447)
			(xy 167.36317 -38.777953) (xy 167.355414 -38.831904) (xy 167.340059 -38.884202) (xy 167.317418 -38.933783)
			(xy 167.287951 -38.979637) (xy 167.25226 -39.020831) (xy 167.211069 -39.056527) (xy 167.165218 -39.085998)
			(xy 167.11564 -39.108645) (xy 167.063343 -39.124005) (xy 167.009393 -39.131767) (xy 166.98214 -39.132256)
			(xy 166.953836 -39.131756) (xy 166.897847 -39.123408) (xy 166.843707 -39.106877) (xy 166.792606 -39.082523)
			(xy 166.745666 -39.050884) (xy 166.703918 -39.012653) (xy 166.668281 -38.968671) (xy 166.653464 -38.94455)
			(xy 166.64588 -38.932507) (xy 166.625257 -38.912906) (xy 166.600023 -38.899765) (xy 166.57214 -38.894107)
			(xy 166.543779 -38.896373) (xy 166.517147 -38.906385) (xy 166.494319 -38.923365) (xy 166.485316 -38.93439)
			(xy 166.467113 -38.957252) (xy 166.424954 -38.997717) (xy 166.377122 -39.031287) (xy 166.324733 -39.057176)
			(xy 166.269012 -39.074781) (xy 166.211258 -39.083691) (xy 166.18204 -39.08425) (xy 166.154788 -39.083705)
			(xy 166.100839 -39.075954) (xy 166.048542 -39.060603) (xy 165.998962 -39.037965) (xy 165.953109 -39.008502)
			(xy 165.911916 -38.972812) (xy 165.876222 -38.931623) (xy 165.846754 -38.885773) (xy 165.824111 -38.836195)
			(xy 165.808755 -38.7839) (xy 165.800997 -38.729952) (xy 158.609506 -38.729952) (xy 158.607506 -38.731952)
			(xy 158.600667 -38.739353) (xy 158.592951 -38.757951) (xy 158.59252 -38.76802) (xy 158.59252 -39.42461)
			(xy 158.592056 -39.457765) (xy 158.584635 -39.523658) (xy 158.569888 -39.588307) (xy 158.548 -39.6509)
			(xy 158.519245 -39.710651) (xy 158.483985 -39.766809) (xy 158.442663 -39.818669) (xy 158.419546 -39.84244)
			(xy 158.290045 -39.97198) (xy 167.995852 -39.97198) (xy 167.999923 -39.916358) (xy 168.012049 -39.861921)
			(xy 168.031972 -39.80983) (xy 168.059268 -39.761195) (xy 168.093354 -39.717052) (xy 168.133503 -39.678343)
			(xy 168.178861 -39.645892) (xy 168.228461 -39.620391) (xy 168.281245 -39.602384) (xy 168.336088 -39.592254)
			(xy 168.391822 -39.590217) (xy 168.447259 -39.596317) (xy 168.501216 -39.610423) (xy 168.552545 -39.632235)
			(xy 168.600151 -39.661289) (xy 168.643019 -39.696964) (xy 168.680236 -39.738501) (xy 168.711009 -39.785014)
			(xy 168.734681 -39.835511) (xy 168.750749 -39.888918) (xy 168.758869 -39.944094) (xy 168.759378 -39.97198)
			(xy 168.758869 -39.999866) (xy 168.750749 -40.055042) (xy 168.734681 -40.108449) (xy 168.711009 -40.158946)
			(xy 168.680236 -40.205459) (xy 168.643019 -40.246996) (xy 168.600151 -40.282671) (xy 168.552545 -40.311725)
			(xy 168.501216 -40.333537) (xy 168.447259 -40.347643) (xy 168.391822 -40.353743) (xy 168.336088 -40.351706)
			(xy 168.281245 -40.341576) (xy 168.228461 -40.323569) (xy 168.178861 -40.298068) (xy 168.133503 -40.265617)
			(xy 168.093354 -40.226908) (xy 168.059268 -40.182765) (xy 168.031972 -40.13413) (xy 168.012049 -40.082039)
			(xy 167.999923 -40.027602) (xy 167.995852 -39.97198) (xy 158.290045 -39.97198) (xy 157.57525 -40.68699)
			(xy 157.568424 -40.694513) (xy 157.560801 -40.713325) (xy 157.56099 -40.733622) (xy 157.564582 -40.743124)
			(xy 157.608524 -40.844216) (xy 157.63494 -40.860726) (xy 157.650688 -40.860218) (xy 157.664658 -40.859964)
			(xy 157.693398 -40.860482) (xy 157.750228 -40.8691) (xy 157.805121 -40.886148) (xy 157.856835 -40.911239)
			(xy 157.904199 -40.943806) (xy 157.925516 -40.963088) (xy 157.932374 -40.969692) (xy 157.950408 -40.976804)
			(xy 158.039308 -40.976804) (xy 158.057342 -40.969692) (xy 158.0642 -40.963088) (xy 158.085527 -40.943818)
			(xy 158.13289 -40.911253) (xy 158.184601 -40.886162) (xy 158.239492 -40.869112) (xy 158.296319 -40.86049)
			(xy 158.353797 -40.86049) (xy 158.410624 -40.869112) (xy 158.465515 -40.886162) (xy 158.517226 -40.911253)
			(xy 158.564589 -40.943818) (xy 158.585916 -40.963088) (xy 158.592774 -40.969692) (xy 158.610808 -40.976804)
			(xy 158.699708 -40.976804) (xy 158.717742 -40.969692) (xy 158.7246 -40.963088) (xy 158.745927 -40.943816)
			(xy 158.793289 -40.911249) (xy 158.845 -40.886154) (xy 158.899891 -40.8691) (xy 158.956719 -40.860472)
			(xy 158.985458 -40.859964) (xy 159.012715 -40.860424) (xy 159.066674 -40.868177) (xy 159.118981 -40.88353)
			(xy 159.16857 -40.906172) (xy 159.214432 -40.935641) (xy 159.255633 -40.971337) (xy 159.291334 -41.012534)
			(xy 159.320808 -41.058393) (xy 159.343455 -41.107979) (xy 159.358814 -41.160285) (xy 159.366573 -41.214243)
			(xy 159.366573 -41.268757) (xy 159.358814 -41.322715) (xy 159.343455 -41.375021) (xy 159.320808 -41.424607)
			(xy 159.291334 -41.470466) (xy 159.255633 -41.511663) (xy 159.214432 -41.547359) (xy 159.16857 -41.576828)
			(xy 159.118981 -41.59947) (xy 159.066674 -41.614823) (xy 159.012715 -41.622576) (xy 158.985458 -41.62298)
			(xy 158.956717 -41.622463) (xy 158.899886 -41.613848) (xy 158.84499 -41.596804) (xy 158.793272 -41.571716)
			(xy 158.745904 -41.539153) (xy 158.7246 -41.519856) (xy 158.717742 -41.513252) (xy 158.699708 -41.50614)
			(xy 158.610808 -41.50614) (xy 158.592774 -41.513252) (xy 158.585916 -41.519856) (xy 158.564589 -41.539126)
			(xy 158.517226 -41.571691) (xy 158.465515 -41.596782) (xy 158.410624 -41.613832) (xy 158.353797 -41.622454)
			(xy 158.296319 -41.622454) (xy 158.239492 -41.613832) (xy 158.184601 -41.596782) (xy 158.13289 -41.571691)
			(xy 158.085527 -41.539126) (xy 158.0642 -41.519856) (xy 158.057342 -41.513252) (xy 158.039308 -41.50614)
			(xy 157.950408 -41.50614) (xy 157.932374 -41.513252) (xy 157.925516 -41.519856) (xy 157.904189 -41.539127)
			(xy 157.856826 -41.571692) (xy 157.805114 -41.596786) (xy 157.750224 -41.613841) (xy 157.693397 -41.62247)
			(xy 157.664658 -41.62298) (xy 157.637409 -41.622491) (xy 157.583468 -41.614729) (xy 157.53118 -41.59937)
			(xy 157.48161 -41.576726) (xy 157.435767 -41.547259) (xy 157.394584 -41.511567) (xy 157.358899 -41.470377)
			(xy 157.32944 -41.424529) (xy 157.306805 -41.374955) (xy 157.291456 -41.322664) (xy 157.283704 -41.268721)
			(xy 157.28315 -41.241472) (xy 157.283404 -41.227502) (xy 157.283912 -41.211754) (xy 157.267402 -41.185338)
			(xy 157.16631 -41.141396) (xy 157.156814 -41.137729) (xy 157.136478 -41.137467) (xy 157.117648 -41.145154)
			(xy 157.110176 -41.152064) (xy 154.957018 -43.305222) (xy 160.40735 -43.305222) (xy 160.407817 -43.277852)
			(xy 160.415633 -43.223672) (xy 160.431121 -43.171169) (xy 160.453963 -43.121422) (xy 160.483688 -43.075455)
			(xy 160.50133 -43.054524) (xy 160.501584 -43.05427) (xy 160.507146 -43.047166) (xy 160.513408 -43.030263)
			(xy 160.513776 -43.02125) (xy 160.513776 -42.954194) (xy 160.513427 -42.945176) (xy 160.507175 -42.928259)
			(xy 160.501584 -42.921174) (xy 160.50133 -42.921174) (xy 160.50133 -42.92092) (xy 160.483691 -42.899987)
			(xy 160.453979 -42.854015) (xy 160.431142 -42.804268) (xy 160.415651 -42.751767) (xy 160.407823 -42.697591)
			(xy 160.40735 -42.670222) (xy 160.4079 -42.641484) (xy 160.416519 -42.584659) (xy 160.433563 -42.529769)
			(xy 160.458648 -42.478057) (xy 160.491207 -42.430692) (xy 160.510474 -42.409364) (xy 160.517078 -42.402506)
			(xy 160.52419 -42.384472) (xy 160.52419 -42.295572) (xy 160.517078 -42.277538) (xy 160.510474 -42.27068)
			(xy 160.491227 -42.249333) (xy 160.458665 -42.201973) (xy 160.433576 -42.150264) (xy 160.416527 -42.095377)
			(xy 160.407903 -42.038553) (xy 160.407901 -41.981079) (xy 160.41652 -41.924255) (xy 160.433564 -41.869366)
			(xy 160.458649 -41.817655) (xy 160.491207 -41.770292) (xy 160.510474 -41.748964) (xy 160.517078 -41.742106)
			(xy 160.52419 -41.724072) (xy 160.52419 -41.635172) (xy 160.517078 -41.617138) (xy 160.510474 -41.61028)
			(xy 160.49122 -41.588939) (xy 160.45865 -41.541581) (xy 160.433554 -41.489873) (xy 160.416499 -41.434985)
			(xy 160.407873 -41.37816) (xy 160.40735 -41.349422) (xy 160.407836 -41.322171) (xy 160.415592 -41.268223)
			(xy 160.430947 -41.215928) (xy 160.453589 -41.166351) (xy 160.483055 -41.120501) (xy 160.518746 -41.07931)
			(xy 160.559937 -41.043619) (xy 160.605787 -41.014153) (xy 160.655364 -40.991511) (xy 160.707659 -40.976156)
			(xy 160.761607 -40.9684) (xy 160.816109 -40.9684) (xy 160.83923 -40.971724) (xy 168.694098 -40.971724)
			(xy 168.698169 -40.916102) (xy 168.710295 -40.861665) (xy 168.730218 -40.809574) (xy 168.757514 -40.760939)
			(xy 168.7916 -40.716796) (xy 168.831749 -40.678087) (xy 168.877107 -40.645636) (xy 168.926707 -40.620135)
			(xy 168.979491 -40.602128) (xy 169.034334 -40.591998) (xy 169.090068 -40.589961) (xy 169.145505 -40.596061)
			(xy 169.199462 -40.610167) (xy 169.250791 -40.631979) (xy 169.298397 -40.661033) (xy 169.341265 -40.696708)
			(xy 169.378482 -40.738245) (xy 169.409255 -40.784758) (xy 169.432927 -40.835255) (xy 169.448995 -40.888662)
			(xy 169.457115 -40.943838) (xy 169.457624 -40.971724) (xy 169.457115 -40.99961) (xy 169.448995 -41.054786)
			(xy 169.432927 -41.108193) (xy 169.409255 -41.15869) (xy 169.378482 -41.205203) (xy 169.341265 -41.24674)
			(xy 169.298397 -41.282415) (xy 169.250791 -41.311469) (xy 169.199462 -41.333281) (xy 169.145505 -41.347387)
			(xy 169.090068 -41.353487) (xy 169.034334 -41.35145) (xy 168.979491 -41.34132) (xy 168.926707 -41.323313)
			(xy 168.877107 -41.297812) (xy 168.831749 -41.265361) (xy 168.7916 -41.226652) (xy 168.757514 -41.182509)
			(xy 168.730218 -41.133874) (xy 168.710295 -41.081783) (xy 168.698169 -41.027346) (xy 168.694098 -40.971724)
			(xy 160.83923 -40.971724) (xy 160.870057 -40.976156) (xy 160.922352 -40.991511) (xy 160.971929 -41.014153)
			(xy 161.017779 -41.043619) (xy 161.05897 -41.07931) (xy 161.094661 -41.120501) (xy 161.124127 -41.166351)
			(xy 161.146769 -41.215928) (xy 161.162124 -41.268223) (xy 161.16988 -41.322171) (xy 161.170366 -41.349422)
			(xy 161.169838 -41.378161) (xy 161.161214 -41.434987) (xy 161.144164 -41.489877) (xy 161.119074 -41.541589)
			(xy 161.086511 -41.588952) (xy 161.067242 -41.61028) (xy 161.060638 -41.617138) (xy 161.053526 -41.635172)
			(xy 161.053526 -41.724072) (xy 161.060638 -41.742106) (xy 161.067242 -41.748964) (xy 161.086536 -41.770271)
			(xy 161.119103 -41.817636) (xy 161.144196 -41.869351) (xy 161.161246 -41.924245) (xy 161.169868 -41.981076)
			(xy 161.169865 -42.038557) (xy 161.161239 -42.095387) (xy 161.144184 -42.150279) (xy 161.119087 -42.201992)
			(xy 161.086516 -42.249354) (xy 161.067242 -42.27068) (xy 161.060638 -42.277538) (xy 161.053526 -42.295572)
			(xy 161.053526 -42.384472) (xy 161.060638 -42.402506) (xy 161.067242 -42.409364) (xy 161.08652 -42.430685)
			(xy 161.119086 -42.478048) (xy 161.144177 -42.529761) (xy 161.161226 -42.584654) (xy 161.169847 -42.641483)
			(xy 161.170366 -42.670222) (xy 161.169921 -42.697593) (xy 161.162099 -42.751773) (xy 161.146606 -42.804277)
			(xy 161.126049 -42.849038) (xy 162.992052 -42.849038) (xy 162.996123 -42.793416) (xy 163.008249 -42.738979)
			(xy 163.028172 -42.686888) (xy 163.055468 -42.638253) (xy 163.089554 -42.59411) (xy 163.129703 -42.555401)
			(xy 163.175061 -42.52295) (xy 163.224661 -42.497449) (xy 163.277445 -42.479442) (xy 163.332288 -42.469312)
			(xy 163.388022 -42.467275) (xy 163.443459 -42.473375) (xy 163.497416 -42.487481) (xy 163.548745 -42.509293)
			(xy 163.596351 -42.538347) (xy 163.639219 -42.574022) (xy 163.676436 -42.615559) (xy 163.707209 -42.662072)
			(xy 163.730881 -42.712569) (xy 163.746949 -42.765976) (xy 163.755069 -42.821152) (xy 163.75543 -42.84091)
			(xy 169.033188 -42.84091) (xy 169.037259 -42.785288) (xy 169.049385 -42.730851) (xy 169.069308 -42.67876)
			(xy 169.096604 -42.630125) (xy 169.13069 -42.585982) (xy 169.170839 -42.547273) (xy 169.216197 -42.514822)
			(xy 169.265797 -42.489321) (xy 169.318581 -42.471314) (xy 169.373424 -42.461184) (xy 169.429158 -42.459147)
			(xy 169.484595 -42.465247) (xy 169.538552 -42.479353) (xy 169.589881 -42.501165) (xy 169.637487 -42.530219)
			(xy 169.680355 -42.565894) (xy 169.717572 -42.607431) (xy 169.748345 -42.653944) (xy 169.772017 -42.704441)
			(xy 169.788085 -42.757848) (xy 169.796205 -42.813024) (xy 169.796714 -42.84091) (xy 169.796205 -42.868796)
			(xy 169.788085 -42.923972) (xy 169.772017 -42.977379) (xy 169.748345 -43.027876) (xy 169.717572 -43.074389)
			(xy 169.680355 -43.115926) (xy 169.637487 -43.151601) (xy 169.589881 -43.180655) (xy 169.538552 -43.202467)
			(xy 169.484595 -43.216573) (xy 169.429158 -43.222673) (xy 169.373424 -43.220636) (xy 169.318581 -43.210506)
			(xy 169.265797 -43.192499) (xy 169.216197 -43.166998) (xy 169.170839 -43.134547) (xy 169.13069 -43.095838)
			(xy 169.096604 -43.051695) (xy 169.069308 -43.00306) (xy 169.049385 -42.950969) (xy 169.037259 -42.896532)
			(xy 169.033188 -42.84091) (xy 163.75543 -42.84091) (xy 163.755578 -42.849038) (xy 163.755069 -42.876924)
			(xy 163.746949 -42.9321) (xy 163.730881 -42.985507) (xy 163.707209 -43.036004) (xy 163.676436 -43.082517)
			(xy 163.639219 -43.124054) (xy 163.596351 -43.159729) (xy 163.548745 -43.188783) (xy 163.497416 -43.210595)
			(xy 163.443459 -43.224701) (xy 163.388022 -43.230801) (xy 163.332288 -43.228764) (xy 163.277445 -43.218634)
			(xy 163.224661 -43.200627) (xy 163.175061 -43.175126) (xy 163.129703 -43.142675) (xy 163.089554 -43.103966)
			(xy 163.055468 -43.059823) (xy 163.028172 -43.011188) (xy 163.008249 -42.959097) (xy 162.996123 -42.90466)
			(xy 162.992052 -42.849038) (xy 161.126049 -42.849038) (xy 161.123759 -42.854024) (xy 161.09403 -42.899989)
			(xy 161.076386 -42.92092) (xy 161.076132 -42.921174) (xy 161.070542 -42.928258) (xy 161.064299 -42.945177)
			(xy 161.06394 -42.954194) (xy 161.06394 -43.02125) (xy 161.064312 -43.030266) (xy 161.070548 -43.047183)
			(xy 161.076132 -43.05427) (xy 161.076386 -43.05427) (xy 161.076386 -43.054524) (xy 161.094001 -43.075476)
			(xy 161.123717 -43.121443) (xy 161.146558 -43.171185) (xy 161.162054 -43.223682) (xy 161.169889 -43.277854)
			(xy 161.170366 -43.305222) (xy 161.16988 -43.332473) (xy 161.162124 -43.386421) (xy 161.146769 -43.438716)
			(xy 161.124127 -43.488293) (xy 161.094661 -43.534143) (xy 161.05897 -43.575334) (xy 161.017779 -43.611025)
			(xy 160.971929 -43.640491) (xy 160.922352 -43.663133) (xy 160.870057 -43.678488) (xy 160.816109 -43.686244)
			(xy 160.761607 -43.686244) (xy 160.707659 -43.678488) (xy 160.655364 -43.663133) (xy 160.605787 -43.640491)
			(xy 160.559937 -43.611025) (xy 160.518746 -43.575334) (xy 160.483055 -43.534143) (xy 160.453589 -43.488293)
			(xy 160.430947 -43.438716) (xy 160.415592 -43.386421) (xy 160.407836 -43.332473) (xy 160.40735 -43.305222)
			(xy 154.957018 -43.305222) (xy 154.652726 -43.609514) (xy 154.646195 -43.616584) (xy 154.638497 -43.634208)
			(xy 154.63774 -43.643804) (xy 154.634748 -43.73626) (xy 162.31311 -43.73626) (xy 162.317181 -43.680638)
			(xy 162.329307 -43.626201) (xy 162.34923 -43.57411) (xy 162.376526 -43.525475) (xy 162.410612 -43.481332)
			(xy 162.450761 -43.442623) (xy 162.496119 -43.410172) (xy 162.545719 -43.384671) (xy 162.598503 -43.366664)
			(xy 162.653346 -43.356534) (xy 162.70908 -43.354497) (xy 162.764517 -43.360597) (xy 162.818474 -43.374703)
			(xy 162.869803 -43.396515) (xy 162.917409 -43.425569) (xy 162.960277 -43.461244) (xy 162.997494 -43.502781)
			(xy 163.028267 -43.549294) (xy 163.051939 -43.599791) (xy 163.068007 -43.653198) (xy 163.076127 -43.708374)
			(xy 163.076636 -43.73626) (xy 163.076127 -43.764146) (xy 163.068007 -43.819322) (xy 163.056698 -43.85691)
			(xy 166.819832 -43.85691) (xy 166.823903 -43.801288) (xy 166.836029 -43.746851) (xy 166.855952 -43.69476)
			(xy 166.883248 -43.646125) (xy 166.917334 -43.601982) (xy 166.957483 -43.563273) (xy 167.002841 -43.530822)
			(xy 167.052441 -43.505321) (xy 167.105225 -43.487314) (xy 167.160068 -43.477184) (xy 167.215802 -43.475147)
			(xy 167.271239 -43.481247) (xy 167.325196 -43.495353) (xy 167.376525 -43.517165) (xy 167.424131 -43.546219)
			(xy 167.466999 -43.581894) (xy 167.504216 -43.623431) (xy 167.534989 -43.669944) (xy 167.558661 -43.720441)
			(xy 167.574729 -43.773848) (xy 167.582849 -43.829024) (xy 167.583358 -43.85691) (xy 167.582849 -43.884796)
			(xy 167.574729 -43.939972) (xy 167.558661 -43.993379) (xy 167.534989 -44.043876) (xy 167.504216 -44.090389)
			(xy 167.466999 -44.131926) (xy 167.424131 -44.167601) (xy 167.376525 -44.196655) (xy 167.325196 -44.218467)
			(xy 167.271239 -44.232573) (xy 167.215802 -44.238673) (xy 167.160068 -44.236636) (xy 167.105225 -44.226506)
			(xy 167.052441 -44.208499) (xy 167.002841 -44.182998) (xy 166.957483 -44.150547) (xy 166.917334 -44.111838)
			(xy 166.883248 -44.067695) (xy 166.855952 -44.01906) (xy 166.836029 -43.966969) (xy 166.823903 -43.912532)
			(xy 166.819832 -43.85691) (xy 163.056698 -43.85691) (xy 163.051939 -43.872729) (xy 163.028267 -43.923226)
			(xy 162.997494 -43.969739) (xy 162.960277 -44.011276) (xy 162.917409 -44.046951) (xy 162.869803 -44.076005)
			(xy 162.818474 -44.097817) (xy 162.764517 -44.111923) (xy 162.70908 -44.118023) (xy 162.653346 -44.115986)
			(xy 162.598503 -44.105856) (xy 162.545719 -44.087849) (xy 162.496119 -44.062348) (xy 162.450761 -44.029897)
			(xy 162.410612 -43.991188) (xy 162.376526 -43.947045) (xy 162.34923 -43.89841) (xy 162.329307 -43.846319)
			(xy 162.317181 -43.791882) (xy 162.31311 -43.73626) (xy 154.634748 -43.73626) (xy 154.590141 -45.114464)
			(xy 162.165536 -45.114464) (xy 162.169607 -45.058842) (xy 162.181733 -45.004405) (xy 162.201656 -44.952314)
			(xy 162.228952 -44.903679) (xy 162.263038 -44.859536) (xy 162.303187 -44.820827) (xy 162.348545 -44.788376)
			(xy 162.398145 -44.762875) (xy 162.450929 -44.744868) (xy 162.505772 -44.734738) (xy 162.561506 -44.732701)
			(xy 162.616943 -44.738801) (xy 162.6709 -44.752907) (xy 162.722229 -44.774719) (xy 162.769835 -44.803773)
			(xy 162.812703 -44.839448) (xy 162.842685 -44.87291) (xy 169.033188 -44.87291) (xy 169.037259 -44.817288)
			(xy 169.049385 -44.762851) (xy 169.069308 -44.71076) (xy 169.096604 -44.662125) (xy 169.13069 -44.617982)
			(xy 169.170839 -44.579273) (xy 169.216197 -44.546822) (xy 169.265797 -44.521321) (xy 169.318581 -44.503314)
			(xy 169.373424 -44.493184) (xy 169.429158 -44.491147) (xy 169.484595 -44.497247) (xy 169.538552 -44.511353)
			(xy 169.589881 -44.533165) (xy 169.637487 -44.562219) (xy 169.680355 -44.597894) (xy 169.717572 -44.639431)
			(xy 169.748345 -44.685944) (xy 169.772017 -44.736441) (xy 169.788085 -44.789848) (xy 169.796205 -44.845024)
			(xy 169.796714 -44.87291) (xy 169.796205 -44.900796) (xy 169.788085 -44.955972) (xy 169.772017 -45.009379)
			(xy 169.748345 -45.059876) (xy 169.717572 -45.106389) (xy 169.680355 -45.147926) (xy 169.637487 -45.183601)
			(xy 169.589881 -45.212655) (xy 169.538552 -45.234467) (xy 169.484595 -45.248573) (xy 169.429158 -45.254673)
			(xy 169.373424 -45.252636) (xy 169.318581 -45.242506) (xy 169.265797 -45.224499) (xy 169.216197 -45.198998)
			(xy 169.170839 -45.166547) (xy 169.13069 -45.127838) (xy 169.096604 -45.083695) (xy 169.069308 -45.03506)
			(xy 169.049385 -44.982969) (xy 169.037259 -44.928532) (xy 169.033188 -44.87291) (xy 162.842685 -44.87291)
			(xy 162.84992 -44.880985) (xy 162.880693 -44.927498) (xy 162.904365 -44.977995) (xy 162.920433 -45.031402)
			(xy 162.928553 -45.086578) (xy 162.929062 -45.114464) (xy 162.928553 -45.14235) (xy 162.920433 -45.197526)
			(xy 162.904365 -45.250933) (xy 162.880693 -45.30143) (xy 162.84992 -45.347943) (xy 162.844278 -45.35424)
			(xy 166.80383 -45.35424) (xy 166.807901 -45.298618) (xy 166.820027 -45.244181) (xy 166.83995 -45.19209)
			(xy 166.867246 -45.143455) (xy 166.901332 -45.099312) (xy 166.941481 -45.060603) (xy 166.986839 -45.028152)
			(xy 167.036439 -45.002651) (xy 167.089223 -44.984644) (xy 167.144066 -44.974514) (xy 167.1998 -44.972477)
			(xy 167.255237 -44.978577) (xy 167.309194 -44.992683) (xy 167.360523 -45.014495) (xy 167.408129 -45.043549)
			(xy 167.450997 -45.079224) (xy 167.488214 -45.120761) (xy 167.518987 -45.167274) (xy 167.542659 -45.217771)
			(xy 167.558727 -45.271178) (xy 167.566847 -45.326354) (xy 167.567356 -45.35424) (xy 167.566847 -45.382126)
			(xy 167.558727 -45.437302) (xy 167.542659 -45.490709) (xy 167.518987 -45.541206) (xy 167.488214 -45.587719)
			(xy 167.450997 -45.629256) (xy 167.408129 -45.664931) (xy 167.360523 -45.693985) (xy 167.309194 -45.715797)
			(xy 167.255237 -45.729903) (xy 167.1998 -45.736003) (xy 167.144066 -45.733966) (xy 167.089223 -45.723836)
			(xy 167.036439 -45.705829) (xy 166.986839 -45.680328) (xy 166.941481 -45.647877) (xy 166.901332 -45.609168)
			(xy 166.867246 -45.565025) (xy 166.83995 -45.51639) (xy 166.820027 -45.464299) (xy 166.807901 -45.409862)
			(xy 166.80383 -45.35424) (xy 162.844278 -45.35424) (xy 162.812703 -45.38948) (xy 162.769835 -45.425155)
			(xy 162.722229 -45.454209) (xy 162.6709 -45.476021) (xy 162.616943 -45.490127) (xy 162.561506 -45.496227)
			(xy 162.505772 -45.49419) (xy 162.450929 -45.48406) (xy 162.398145 -45.466053) (xy 162.348545 -45.440552)
			(xy 162.303187 -45.408101) (xy 162.263038 -45.369392) (xy 162.228952 -45.325249) (xy 162.201656 -45.276614)
			(xy 162.181733 -45.224523) (xy 162.169607 -45.170086) (xy 162.165536 -45.114464) (xy 154.590141 -45.114464)
			(xy 154.55882 -46.082204) (xy 160.152588 -46.082204) (xy 160.153081 -46.054953) (xy 160.160837 -46.001006)
			(xy 160.176192 -45.948711) (xy 160.198832 -45.899134) (xy 160.228298 -45.853284) (xy 160.263988 -45.812094)
			(xy 160.305178 -45.776402) (xy 160.351027 -45.746936) (xy 160.400604 -45.724295) (xy 160.452898 -45.708939)
			(xy 160.506845 -45.701182) (xy 160.534096 -45.700696) (xy 160.560998 -45.701161) (xy 160.614268 -45.708733)
			(xy 160.665947 -45.723711) (xy 160.715008 -45.745801) (xy 160.760481 -45.774563) (xy 160.801462 -45.809427)
			(xy 160.83714 -45.849702) (xy 160.852358 -45.871892) (xy 160.85947 -45.882814) (xy 160.88233 -45.894752)
			(xy 160.994598 -45.89272) (xy 161.01695 -45.879766) (xy 161.023808 -45.86859) (xy 161.038738 -45.844994)
			(xy 161.074415 -45.802042) (xy 161.115972 -45.764749) (xy 161.162521 -45.733911) (xy 161.213067 -45.710187)
			(xy 161.266531 -45.694083) (xy 161.321772 -45.685943) (xy 161.34969 -45.685456) (xy 161.376683 -45.685923)
			(xy 161.430131 -45.693527) (xy 161.481974 -45.708586) (xy 161.531179 -45.730799) (xy 161.576763 -45.759722)
			(xy 161.597594 -45.776896) (xy 161.605722 -45.784008) (xy 161.626296 -45.790104) (xy 161.71164 -45.779182)
			(xy 161.72218 -45.777388) (xy 161.740465 -45.766348) (xy 161.746946 -45.757846) (xy 161.762277 -45.736599)
			(xy 161.797868 -45.698146) (xy 161.838389 -45.664929) (xy 161.883076 -45.637572) (xy 161.931087 -45.616592)
			(xy 161.98152 -45.602382) (xy 162.033422 -45.595211) (xy 162.05962 -45.594778) (xy 162.086869 -45.595294)
			(xy 162.140813 -45.603052) (xy 162.193103 -45.618408) (xy 162.242676 -45.64105) (xy 162.288522 -45.670516)
			(xy 162.329708 -45.706206) (xy 162.365396 -45.747394) (xy 162.39486 -45.793242) (xy 162.417499 -45.842816)
			(xy 162.432852 -45.895107) (xy 162.440608 -45.949051) (xy 162.440608 -46.003549) (xy 162.432852 -46.057493)
			(xy 162.417499 -46.109784) (xy 162.39486 -46.159358) (xy 162.365396 -46.205206) (xy 162.329708 -46.246394)
			(xy 162.288522 -46.282084) (xy 162.242676 -46.31155) (xy 162.193103 -46.334192) (xy 162.140813 -46.349548)
			(xy 162.086869 -46.357306) (xy 162.05962 -46.357794) (xy 162.032628 -46.357309) (xy 161.979181 -46.349707)
			(xy 161.927338 -46.334652) (xy 161.878133 -46.312444) (xy 161.832548 -46.283525) (xy 161.811716 -46.266354)
			(xy 161.803588 -46.259242) (xy 161.783014 -46.253146) (xy 161.69767 -46.264068) (xy 161.687124 -46.265835)
			(xy 161.668843 -46.276896) (xy 161.662364 -46.285404) (xy 161.644753 -46.309706) (xy 161.603156 -46.352964)
			(xy 161.57956 -46.37151) (xy 161.571686 -46.377352) (xy 161.561272 -46.394878) (xy 161.548064 -46.485302)
			(xy 161.55289 -46.504606) (xy 161.558732 -46.51248) (xy 161.558732 -46.512734) (xy 161.57623 -46.537482)
			(xy 161.604035 -46.591333) (xy 161.622973 -46.648904) (xy 161.630176 -46.693836) (xy 166.7764 -46.693836)
			(xy 166.776886 -46.666585) (xy 166.784642 -46.612637) (xy 166.799997 -46.560342) (xy 166.822639 -46.510765)
			(xy 166.852105 -46.464915) (xy 166.887796 -46.423724) (xy 166.928987 -46.388033) (xy 166.974837 -46.358567)
			(xy 167.024414 -46.335925) (xy 167.076709 -46.32057) (xy 167.130657 -46.312814) (xy 167.185159 -46.312814)
			(xy 167.239107 -46.32057) (xy 167.291402 -46.335925) (xy 167.340979 -46.358567) (xy 167.386829 -46.388033)
			(xy 167.42802 -46.423724) (xy 167.463711 -46.464915) (xy 167.493177 -46.510765) (xy 167.515819 -46.560342)
			(xy 167.531174 -46.612637) (xy 167.53893 -46.666585) (xy 167.539416 -46.693836) (xy 167.538941 -46.720263)
			(xy 167.531632 -46.772611) (xy 167.517159 -46.823446) (xy 167.4958 -46.871793) (xy 167.482266 -46.894496)
			(xy 167.482012 -46.89475) (xy 167.476675 -46.904768) (xy 167.474419 -46.927318) (xy 167.477694 -46.938184)
			(xy 167.503856 -47.01286) (xy 167.508238 -47.023376) (xy 167.524328 -47.039464) (xy 167.534844 -47.043848)
			(xy 167.535098 -47.043848) (xy 167.559618 -47.052888) (xy 167.606069 -47.076837) (xy 167.648819 -47.106898)
			(xy 167.68707 -47.14251) (xy 167.720104 -47.183006) (xy 167.747306 -47.22763) (xy 167.768167 -47.275548)
			(xy 167.782296 -47.325863) (xy 167.789429 -47.377635) (xy 167.78986 -47.403766) (xy 167.789374 -47.431017)
			(xy 167.787851 -47.441612) (xy 169.06189 -47.441612) (xy 169.065961 -47.38599) (xy 169.078087 -47.331553)
			(xy 169.09801 -47.279462) (xy 169.125306 -47.230827) (xy 169.159392 -47.186684) (xy 169.199541 -47.147975)
			(xy 169.244899 -47.115524) (xy 169.294499 -47.090023) (xy 169.347283 -47.072016) (xy 169.402126 -47.061886)
			(xy 169.45786 -47.059849) (xy 169.513297 -47.065949) (xy 169.567254 -47.080055) (xy 169.618583 -47.101867)
			(xy 169.666189 -47.130921) (xy 169.709057 -47.166596) (xy 169.746274 -47.208133) (xy 169.777047 -47.254646)
			(xy 169.800719 -47.305143) (xy 169.816787 -47.35855) (xy 169.824907 -47.413726) (xy 169.825416 -47.441612)
			(xy 169.824907 -47.469498) (xy 169.816787 -47.524674) (xy 169.800719 -47.578081) (xy 169.777047 -47.628578)
			(xy 169.746274 -47.675091) (xy 169.709057 -47.716628) (xy 169.666189 -47.752303) (xy 169.618583 -47.781357)
			(xy 169.567254 -47.803169) (xy 169.513297 -47.817275) (xy 169.45786 -47.823375) (xy 169.402126 -47.821338)
			(xy 169.347283 -47.811208) (xy 169.294499 -47.793201) (xy 169.244899 -47.7677) (xy 169.199541 -47.735249)
			(xy 169.159392 -47.69654) (xy 169.125306 -47.652397) (xy 169.09801 -47.603762) (xy 169.078087 -47.551671)
			(xy 169.065961 -47.497234) (xy 169.06189 -47.441612) (xy 167.787851 -47.441612) (xy 167.781618 -47.484965)
			(xy 167.766263 -47.53726) (xy 167.743621 -47.586837) (xy 167.714155 -47.632687) (xy 167.678464 -47.673878)
			(xy 167.637273 -47.709569) (xy 167.591423 -47.739035) (xy 167.541846 -47.761677) (xy 167.489551 -47.777032)
			(xy 167.435603 -47.784788) (xy 167.381101 -47.784788) (xy 167.327153 -47.777032) (xy 167.274858 -47.761677)
			(xy 167.225281 -47.739035) (xy 167.179431 -47.709569) (xy 167.13824 -47.673878) (xy 167.102549 -47.632687)
			(xy 167.073083 -47.586837) (xy 167.050441 -47.53726) (xy 167.035086 -47.484965) (xy 167.02733 -47.431017)
			(xy 167.026844 -47.403766) (xy 167.027312 -47.377338) (xy 167.034622 -47.32499) (xy 167.049096 -47.274155)
			(xy 167.070458 -47.225809) (xy 167.083994 -47.203106) (xy 167.084248 -47.202852) (xy 167.089583 -47.192834)
			(xy 167.091842 -47.170284) (xy 167.088566 -47.159418) (xy 167.062404 -47.084742) (xy 167.058039 -47.074217)
			(xy 167.041938 -47.058132) (xy 167.031416 -47.053754) (xy 167.031162 -47.053754) (xy 167.006656 -47.044678)
			(xy 166.960203 -47.020737) (xy 166.917451 -46.990682) (xy 166.879199 -46.955076) (xy 166.846162 -46.914584)
			(xy 166.818958 -46.869963) (xy 166.798096 -46.822048) (xy 166.783965 -46.771736) (xy 166.776831 -46.719966)
			(xy 166.7764 -46.693836) (xy 161.630176 -46.693836) (xy 161.632566 -46.708745) (xy 161.633154 -46.739048)
			(xy 161.632667 -46.766298) (xy 161.624905 -46.820244) (xy 161.609546 -46.872536) (xy 161.586903 -46.92211)
			(xy 161.557436 -46.967958) (xy 161.521745 -47.009146) (xy 161.480556 -47.044837) (xy 161.434708 -47.074304)
			(xy 161.385134 -47.096947) (xy 161.332842 -47.112306) (xy 161.278896 -47.120067) (xy 161.251646 -47.120556)
			(xy 161.225612 -47.120132) (xy 161.174028 -47.113038) (xy 161.123886 -47.099003) (xy 161.076116 -47.078287)
			(xy 161.031602 -47.051274) (xy 161.011108 -47.035212) (xy 161.003355 -47.029463) (xy 160.984941 -47.023727)
			(xy 160.975294 -47.024036) (xy 160.895538 -47.030386) (xy 160.877758 -47.039022) (xy 160.871408 -47.046388)
			(xy 160.853246 -47.066052) (xy 160.812334 -47.100573) (xy 160.767001 -47.129039) (xy 160.718136 -47.150894)
			(xy 160.666697 -47.165707) (xy 160.613693 -47.173189) (xy 160.586928 -47.173642) (xy 160.559679 -47.173096)
			(xy 160.505735 -47.165344) (xy 160.453444 -47.149994) (xy 160.403869 -47.127359) (xy 160.35802 -47.097899)
			(xy 160.31683 -47.062213) (xy 160.281139 -47.02103) (xy 160.251671 -46.975185) (xy 160.229028 -46.925614)
			(xy 160.213669 -46.873325) (xy 160.205909 -46.819383) (xy 160.20542 -46.792134) (xy 160.205939 -46.76336)
			(xy 160.214591 -46.706465) (xy 160.231688 -46.651514) (xy 160.256843 -46.599754) (xy 160.289485 -46.552359)
			(xy 160.308798 -46.531022) (xy 160.316164 -46.523148) (xy 160.323276 -46.503336) (xy 160.31591 -46.40707)
			(xy 160.306004 -46.388274) (xy 160.297622 -46.38167) (xy 160.275438 -46.363445) (xy 160.236228 -46.32151)
			(xy 160.203742 -46.274174) (xy 160.178713 -46.222506) (xy 160.161707 -46.167672) (xy 160.153106 -46.110909)
			(xy 160.152588 -46.082204) (xy 154.55882 -46.082204) (xy 154.486815 -48.30699) (xy 166.65397 -48.30699)
			(xy 166.658041 -48.251368) (xy 166.670167 -48.196931) (xy 166.69009 -48.14484) (xy 166.717386 -48.096205)
			(xy 166.751472 -48.052062) (xy 166.791621 -48.013353) (xy 166.836979 -47.980902) (xy 166.886579 -47.955401)
			(xy 166.939363 -47.937394) (xy 166.994206 -47.927264) (xy 167.04994 -47.925227) (xy 167.105377 -47.931327)
			(xy 167.159334 -47.945433) (xy 167.210663 -47.967245) (xy 167.258269 -47.996299) (xy 167.301137 -48.031974)
			(xy 167.338354 -48.073511) (xy 167.369127 -48.120024) (xy 167.392799 -48.170521) (xy 167.408867 -48.223928)
			(xy 167.416987 -48.279104) (xy 167.417496 -48.30699) (xy 167.416987 -48.334876) (xy 167.408867 -48.390052)
			(xy 167.392799 -48.443459) (xy 167.369127 -48.493956) (xy 167.338354 -48.540469) (xy 167.301137 -48.582006)
			(xy 167.258269 -48.617681) (xy 167.210663 -48.646735) (xy 167.159334 -48.668547) (xy 167.105377 -48.682653)
			(xy 167.04994 -48.688753) (xy 166.994206 -48.686716) (xy 166.939363 -48.676586) (xy 166.886579 -48.658579)
			(xy 166.836979 -48.633078) (xy 166.791621 -48.600627) (xy 166.751472 -48.561918) (xy 166.717386 -48.517775)
			(xy 166.69009 -48.46914) (xy 166.670167 -48.417049) (xy 166.658041 -48.362612) (xy 166.65397 -48.30699)
			(xy 154.486815 -48.30699) (xy 154.472379 -48.753014) (xy 163.268404 -48.753014) (xy 163.272475 -48.697392)
			(xy 163.284601 -48.642955) (xy 163.304524 -48.590864) (xy 163.33182 -48.542229) (xy 163.365906 -48.498086)
			(xy 163.406055 -48.459377) (xy 163.451413 -48.426926) (xy 163.501013 -48.401425) (xy 163.553797 -48.383418)
			(xy 163.60864 -48.373288) (xy 163.664374 -48.371251) (xy 163.719811 -48.377351) (xy 163.773768 -48.391457)
			(xy 163.825097 -48.413269) (xy 163.872703 -48.442323) (xy 163.915571 -48.477998) (xy 163.952788 -48.519535)
			(xy 163.983561 -48.566048) (xy 164.007233 -48.616545) (xy 164.023301 -48.669952) (xy 164.031421 -48.725128)
			(xy 164.03193 -48.753014) (xy 164.031421 -48.7809) (xy 164.023301 -48.836076) (xy 164.007233 -48.889483)
			(xy 164.005837 -48.89246) (xy 165.31412 -48.89246) (xy 165.318191 -48.836838) (xy 165.330317 -48.782401)
			(xy 165.35024 -48.73031) (xy 165.377536 -48.681675) (xy 165.411622 -48.637532) (xy 165.451771 -48.598823)
			(xy 165.497129 -48.566372) (xy 165.546729 -48.540871) (xy 165.599513 -48.522864) (xy 165.654356 -48.512734)
			(xy 165.71009 -48.510697) (xy 165.765527 -48.516797) (xy 165.819484 -48.530903) (xy 165.870813 -48.552715)
			(xy 165.918419 -48.581769) (xy 165.961287 -48.617444) (xy 165.998504 -48.658981) (xy 166.029277 -48.705494)
			(xy 166.052949 -48.755991) (xy 166.069017 -48.809398) (xy 166.077137 -48.864574) (xy 166.077646 -48.89246)
			(xy 166.077137 -48.920346) (xy 166.074699 -48.93691) (xy 169.033188 -48.93691) (xy 169.037259 -48.881288)
			(xy 169.049385 -48.826851) (xy 169.069308 -48.77476) (xy 169.096604 -48.726125) (xy 169.13069 -48.681982)
			(xy 169.170839 -48.643273) (xy 169.216197 -48.610822) (xy 169.265797 -48.585321) (xy 169.318581 -48.567314)
			(xy 169.373424 -48.557184) (xy 169.429158 -48.555147) (xy 169.484595 -48.561247) (xy 169.538552 -48.575353)
			(xy 169.589881 -48.597165) (xy 169.637487 -48.626219) (xy 169.680355 -48.661894) (xy 169.717572 -48.703431)
			(xy 169.748345 -48.749944) (xy 169.772017 -48.800441) (xy 169.788085 -48.853848) (xy 169.796205 -48.909024)
			(xy 169.796714 -48.93691) (xy 169.796205 -48.964796) (xy 169.788085 -49.019972) (xy 169.772017 -49.073379)
			(xy 169.748345 -49.123876) (xy 169.717572 -49.170389) (xy 169.680355 -49.211926) (xy 169.637487 -49.247601)
			(xy 169.589881 -49.276655) (xy 169.538552 -49.298467) (xy 169.484595 -49.312573) (xy 169.429158 -49.318673)
			(xy 169.373424 -49.316636) (xy 169.318581 -49.306506) (xy 169.265797 -49.288499) (xy 169.216197 -49.262998)
			(xy 169.170839 -49.230547) (xy 169.13069 -49.191838) (xy 169.096604 -49.147695) (xy 169.069308 -49.09906)
			(xy 169.049385 -49.046969) (xy 169.037259 -48.992532) (xy 169.033188 -48.93691) (xy 166.074699 -48.93691)
			(xy 166.069017 -48.975522) (xy 166.052949 -49.028929) (xy 166.029277 -49.079426) (xy 165.998504 -49.125939)
			(xy 165.961287 -49.167476) (xy 165.918419 -49.203151) (xy 165.870813 -49.232205) (xy 165.819484 -49.254017)
			(xy 165.765527 -49.268123) (xy 165.71009 -49.274223) (xy 165.654356 -49.272186) (xy 165.599513 -49.262056)
			(xy 165.546729 -49.244049) (xy 165.497129 -49.218548) (xy 165.451771 -49.186097) (xy 165.411622 -49.147388)
			(xy 165.377536 -49.103245) (xy 165.35024 -49.05461) (xy 165.330317 -49.002519) (xy 165.318191 -48.948082)
			(xy 165.31412 -48.89246) (xy 164.005837 -48.89246) (xy 163.983561 -48.93998) (xy 163.952788 -48.986493)
			(xy 163.915571 -49.02803) (xy 163.872703 -49.063705) (xy 163.825097 -49.092759) (xy 163.773768 -49.114571)
			(xy 163.719811 -49.128677) (xy 163.664374 -49.134777) (xy 163.60864 -49.13274) (xy 163.553797 -49.12261)
			(xy 163.501013 -49.104603) (xy 163.451413 -49.079102) (xy 163.406055 -49.046651) (xy 163.365906 -49.007942)
			(xy 163.33182 -48.963799) (xy 163.304524 -48.915164) (xy 163.284601 -48.863073) (xy 163.272475 -48.808636)
			(xy 163.268404 -48.753014) (xy 154.472379 -48.753014) (xy 154.433544 -49.95291) (xy 169.033188 -49.95291)
			(xy 169.037259 -49.897288) (xy 169.049385 -49.842851) (xy 169.069308 -49.79076) (xy 169.096604 -49.742125)
			(xy 169.13069 -49.697982) (xy 169.170839 -49.659273) (xy 169.216197 -49.626822) (xy 169.265797 -49.601321)
			(xy 169.318581 -49.583314) (xy 169.373424 -49.573184) (xy 169.429158 -49.571147) (xy 169.484595 -49.577247)
			(xy 169.538552 -49.591353) (xy 169.563496 -49.601953) (xy 174.212959 -49.601953) (xy 174.212959 -49.547447)
			(xy 174.220717 -49.493495) (xy 174.236073 -49.441197) (xy 174.258716 -49.391617) (xy 174.288185 -49.345764)
			(xy 174.32388 -49.304571) (xy 174.365073 -49.268878) (xy 174.410927 -49.23941) (xy 174.460508 -49.216769)
			(xy 174.512807 -49.201414) (xy 174.566759 -49.193659) (xy 174.594012 -49.193196) (xy 174.621382 -49.193656)
			(xy 174.675562 -49.201475) (xy 174.728065 -49.216966) (xy 174.777812 -49.239809) (xy 174.823778 -49.269534)
			(xy 174.84471 -49.287176) (xy 174.844964 -49.28743) (xy 174.852054 -49.293011) (xy 174.868968 -49.29926)
			(xy 174.877984 -49.299622) (xy 174.94504 -49.299622) (xy 174.954058 -49.299279) (xy 174.970975 -49.293021)
			(xy 174.97806 -49.28743) (xy 174.97806 -49.287176) (xy 174.978314 -49.287176) (xy 174.999247 -49.269535)
			(xy 175.045215 -49.239811) (xy 175.094961 -49.216965) (xy 175.147463 -49.201469) (xy 175.201641 -49.19364)
			(xy 175.256383 -49.19364) (xy 175.310561 -49.201469) (xy 175.363063 -49.216965) (xy 175.412809 -49.239811)
			(xy 175.458777 -49.269535) (xy 175.47971 -49.287176) (xy 175.479964 -49.28743) (xy 175.487054 -49.293011)
			(xy 175.503968 -49.29926) (xy 175.512984 -49.299622) (xy 175.58004 -49.299622) (xy 175.589058 -49.299279)
			(xy 175.605975 -49.293021) (xy 175.61306 -49.28743) (xy 175.61306 -49.287176) (xy 175.613314 -49.287176)
			(xy 175.634247 -49.269535) (xy 175.680215 -49.239811) (xy 175.729961 -49.216965) (xy 175.782463 -49.201469)
			(xy 175.836641 -49.19364) (xy 175.891383 -49.19364) (xy 175.945561 -49.201469) (xy 175.998063 -49.216965)
			(xy 176.047809 -49.239811) (xy 176.093777 -49.269535) (xy 176.11471 -49.287176) (xy 176.114964 -49.28743)
			(xy 176.122054 -49.293011) (xy 176.138968 -49.29926) (xy 176.147984 -49.299622) (xy 176.21504 -49.299622)
			(xy 176.224058 -49.299279) (xy 176.240975 -49.293021) (xy 176.24806 -49.28743) (xy 176.24806 -49.287176)
			(xy 176.248314 -49.287176) (xy 176.269265 -49.26956) (xy 176.315233 -49.239846) (xy 176.364976 -49.217006)
			(xy 176.417472 -49.201509) (xy 176.471644 -49.193674) (xy 176.499012 -49.193196) (xy 176.526263 -49.193675)
			(xy 176.58021 -49.201433) (xy 176.632504 -49.216789) (xy 176.68208 -49.239431) (xy 176.727929 -49.268898)
			(xy 176.769119 -49.30459) (xy 176.804809 -49.34578) (xy 176.834275 -49.39163) (xy 176.856915 -49.441207)
			(xy 176.87227 -49.493502) (xy 176.880026 -49.547449) (xy 176.880026 -49.601951) (xy 176.87227 -49.655898)
			(xy 176.856915 -49.708193) (xy 176.834275 -49.75777) (xy 176.804809 -49.80362) (xy 176.769119 -49.84481)
			(xy 176.727929 -49.880502) (xy 176.68208 -49.909969) (xy 176.632504 -49.932611) (xy 176.58021 -49.947967)
			(xy 176.526263 -49.955725) (xy 176.499012 -49.956212) (xy 176.471642 -49.955736) (xy 176.417464 -49.94792)
			(xy 176.364961 -49.932433) (xy 176.315214 -49.909594) (xy 176.269246 -49.879872) (xy 176.248314 -49.862232)
			(xy 176.24806 -49.861978) (xy 176.240962 -49.856408) (xy 176.224054 -49.850152) (xy 176.21504 -49.849786)
			(xy 176.147984 -49.849786) (xy 176.138967 -49.850139) (xy 176.12205 -49.85639) (xy 176.114964 -49.861978)
			(xy 176.11471 -49.862232) (xy 176.093777 -49.879873) (xy 176.047809 -49.909597) (xy 175.998063 -49.932443)
			(xy 175.945561 -49.947939) (xy 175.891383 -49.955768) (xy 175.836641 -49.955768) (xy 175.782463 -49.947939)
			(xy 175.729961 -49.932443) (xy 175.680215 -49.909597) (xy 175.634247 -49.879873) (xy 175.613314 -49.862232)
			(xy 175.61306 -49.861978) (xy 175.605962 -49.856408) (xy 175.589054 -49.850152) (xy 175.58004 -49.849786)
			(xy 175.512984 -49.849786) (xy 175.503967 -49.850139) (xy 175.48705 -49.85639) (xy 175.479964 -49.861978)
			(xy 175.479964 -49.862232) (xy 175.47971 -49.862232) (xy 175.458777 -49.879873) (xy 175.412809 -49.909597)
			(xy 175.363063 -49.932443) (xy 175.310561 -49.947939) (xy 175.256383 -49.955768) (xy 175.201641 -49.955768)
			(xy 175.147463 -49.947939) (xy 175.094961 -49.932443) (xy 175.045215 -49.909597) (xy 174.999247 -49.879873)
			(xy 174.978314 -49.862232) (xy 174.97806 -49.861978) (xy 174.970962 -49.856408) (xy 174.954054 -49.850152)
			(xy 174.94504 -49.849786) (xy 174.877984 -49.849786) (xy 174.868967 -49.850139) (xy 174.85205 -49.85639)
			(xy 174.844964 -49.861978) (xy 174.844964 -49.862232) (xy 174.84471 -49.862232) (xy 174.823789 -49.879885)
			(xy 174.777813 -49.909594) (xy 174.728062 -49.932426) (xy 174.675559 -49.947914) (xy 174.621382 -49.955739)
			(xy 174.594012 -49.956212) (xy 174.566759 -49.955741) (xy 174.512807 -49.947986) (xy 174.460508 -49.932631)
			(xy 174.410927 -49.90999) (xy 174.365073 -49.880522) (xy 174.32388 -49.844829) (xy 174.288185 -49.803636)
			(xy 174.258716 -49.757783) (xy 174.236073 -49.708203) (xy 174.220717 -49.655905) (xy 174.212959 -49.601953)
			(xy 169.563496 -49.601953) (xy 169.589881 -49.613165) (xy 169.637487 -49.642219) (xy 169.680355 -49.677894)
			(xy 169.717572 -49.719431) (xy 169.748345 -49.765944) (xy 169.772017 -49.816441) (xy 169.788085 -49.869848)
			(xy 169.796205 -49.925024) (xy 169.796714 -49.95291) (xy 169.796205 -49.980796) (xy 169.788085 -50.035972)
			(xy 169.772017 -50.089379) (xy 169.748345 -50.139876) (xy 169.717572 -50.186389) (xy 169.680355 -50.227926)
			(xy 169.637487 -50.263601) (xy 169.589881 -50.292655) (xy 169.538552 -50.314467) (xy 169.484595 -50.328573)
			(xy 169.429158 -50.334673) (xy 169.373424 -50.332636) (xy 169.318581 -50.322506) (xy 169.265797 -50.304499)
			(xy 169.216197 -50.278998) (xy 169.170839 -50.246547) (xy 169.13069 -50.207838) (xy 169.096604 -50.163695)
			(xy 169.069308 -50.11506) (xy 169.049385 -50.062969) (xy 169.037259 -50.008532) (xy 169.033188 -49.95291)
			(xy 154.433544 -49.95291) (xy 154.40533 -50.824638) (xy 154.405584 -50.82921) (xy 154.416985 -51.019456)
			(xy 166.84955 -51.019456) (xy 166.853621 -50.963834) (xy 166.865747 -50.909397) (xy 166.88567 -50.857306)
			(xy 166.912966 -50.808671) (xy 166.947052 -50.764528) (xy 166.987201 -50.725819) (xy 167.032559 -50.693368)
			(xy 167.082159 -50.667867) (xy 167.134943 -50.64986) (xy 167.189786 -50.63973) (xy 167.24552 -50.637693)
			(xy 167.300957 -50.643793) (xy 167.354914 -50.657899) (xy 167.406243 -50.679711) (xy 167.453849 -50.708765)
			(xy 167.496717 -50.74444) (xy 167.533934 -50.785977) (xy 167.564707 -50.83249) (xy 167.588379 -50.882987)
			(xy 167.604447 -50.936394) (xy 167.612567 -50.99157) (xy 167.613076 -51.019456) (xy 167.612567 -51.047342)
			(xy 167.604447 -51.102518) (xy 167.588379 -51.155925) (xy 167.564707 -51.206422) (xy 167.539851 -51.243992)
			(xy 175.233076 -51.243992) (xy 175.233519 -51.216621) (xy 175.241339 -51.16244) (xy 175.256833 -51.109936)
			(xy 175.27968 -51.060189) (xy 175.309411 -51.014224) (xy 175.327056 -50.993294) (xy 175.32731 -50.99304)
			(xy 175.332887 -50.985947) (xy 175.339139 -50.969035) (xy 175.339502 -50.96002) (xy 175.339502 -50.892964)
			(xy 175.339162 -50.883945) (xy 175.332902 -50.867029) (xy 175.32731 -50.859944) (xy 175.327056 -50.859944)
			(xy 175.327056 -50.85969) (xy 175.309392 -50.838778) (xy 175.279685 -50.792799) (xy 175.256854 -50.743047)
			(xy 175.241369 -50.690542) (xy 175.233547 -50.636362) (xy 175.233076 -50.608992) (xy 175.23357 -50.581741)
			(xy 175.241327 -50.527795) (xy 175.256683 -50.475501) (xy 175.279324 -50.425925) (xy 175.308789 -50.380075)
			(xy 175.34448 -50.338886) (xy 175.385669 -50.303194) (xy 175.431518 -50.273728) (xy 175.481094 -50.251086)
			(xy 175.533387 -50.235729) (xy 175.587333 -50.227971) (xy 175.614584 -50.227484) (xy 175.643502 -50.227982)
			(xy 175.700676 -50.236711) (xy 175.755876 -50.25397) (xy 175.807839 -50.279366) (xy 175.855372 -50.312315)
			(xy 175.897386 -50.352061) (xy 175.915574 -50.37455) (xy 175.923194 -50.383344) (xy 175.944085 -50.393533)
			(xy 175.955706 -50.394108) (xy 176.035462 -50.394108) (xy 176.047096 -50.393587) (xy 176.068005 -50.383385)
			(xy 176.075594 -50.37455) (xy 176.093776 -50.352059) (xy 176.135799 -50.312327) (xy 176.183336 -50.27939)
			(xy 176.235299 -50.254003) (xy 176.290498 -50.236748) (xy 176.347668 -50.228019) (xy 176.376584 -50.227484)
			(xy 176.403836 -50.22797) (xy 176.457786 -50.235725) (xy 176.510083 -50.251078) (xy 176.559662 -50.273718)
			(xy 176.605515 -50.303184) (xy 176.646708 -50.338875) (xy 176.682402 -50.380066) (xy 176.71187 -50.425917)
			(xy 176.734513 -50.475495) (xy 176.74987 -50.527791) (xy 176.757628 -50.58174) (xy 176.758092 -50.608992)
			(xy 176.757622 -50.635306) (xy 176.750388 -50.687434) (xy 176.736069 -50.738077) (xy 176.714938 -50.786276)
			(xy 176.687392 -50.83112) (xy 176.653953 -50.871759) (xy 176.634902 -50.889916) (xy 176.627492 -50.89743)
			(xy 176.618972 -50.916716) (xy 176.618392 -50.927254) (xy 176.618392 -51.00193) (xy 176.618948 -51.012476)
			(xy 176.627465 -51.031772) (xy 176.634902 -51.039268) (xy 176.653984 -51.057397) (xy 176.687439 -51.098033)
			(xy 176.714994 -51.142878) (xy 176.736128 -51.191084) (xy 176.750439 -51.241736) (xy 176.757657 -51.293874)
			(xy 176.758092 -51.320192) (xy 176.757637 -51.347445) (xy 176.749881 -51.401397) (xy 176.734525 -51.453696)
			(xy 176.711882 -51.503278) (xy 176.682414 -51.549132) (xy 176.646719 -51.590325) (xy 176.605525 -51.626018)
			(xy 176.559671 -51.655486) (xy 176.510089 -51.678128) (xy 176.45779 -51.693483) (xy 176.403837 -51.701238)
			(xy 176.376584 -51.7017) (xy 176.348918 -51.7012) (xy 176.294169 -51.693199) (xy 176.241147 -51.67738)
			(xy 176.190963 -51.654075) (xy 176.144667 -51.623772) (xy 176.103229 -51.587105) (xy 176.067517 -51.544842)
			(xy 176.05248 -51.521614) (xy 176.045862 -51.511922) (xy 176.025987 -51.499487) (xy 176.01438 -51.497738)
			(xy 175.93437 -51.489864) (xy 175.922731 -51.489217) (xy 175.900893 -51.497307) (xy 175.89246 -51.505358)
			(xy 175.892206 -51.505612) (xy 175.874107 -51.524175) (xy 175.833779 -51.556755) (xy 175.789408 -51.58357)
			(xy 175.741813 -51.604126) (xy 175.691872 -51.618043) (xy 175.640506 -51.625065) (xy 175.614584 -51.6255)
			(xy 175.587332 -51.625037) (xy 175.533383 -51.617278) (xy 175.481087 -51.601921) (xy 175.43151 -51.579277)
			(xy 175.385659 -51.549808) (xy 175.344469 -51.514114) (xy 175.308777 -51.472922) (xy 175.279311 -51.427069)
			(xy 175.256671 -51.37749) (xy 175.241317 -51.325193) (xy 175.233561 -51.271244) (xy 175.233076 -51.243992)
			(xy 167.539851 -51.243992) (xy 167.533934 -51.252935) (xy 167.496717 -51.294472) (xy 167.453849 -51.330147)
			(xy 167.406243 -51.359201) (xy 167.354914 -51.381013) (xy 167.300957 -51.395119) (xy 167.24552 -51.401219)
			(xy 167.189786 -51.399182) (xy 167.134943 -51.389052) (xy 167.082159 -51.371045) (xy 167.032559 -51.345544)
			(xy 166.987201 -51.313093) (xy 166.947052 -51.274384) (xy 166.912966 -51.230241) (xy 166.88567 -51.181606)
			(xy 166.865747 -51.129515) (xy 166.853621 -51.075078) (xy 166.84955 -51.019456) (xy 154.416985 -51.019456)
			(xy 154.477869 -52.035456) (xy 169.041316 -52.035456) (xy 169.045387 -51.979834) (xy 169.057513 -51.925397)
			(xy 169.077436 -51.873306) (xy 169.104732 -51.824671) (xy 169.138818 -51.780528) (xy 169.178967 -51.741819)
			(xy 169.224325 -51.709368) (xy 169.273925 -51.683867) (xy 169.326709 -51.66586) (xy 169.381552 -51.65573)
			(xy 169.437286 -51.653693) (xy 169.492723 -51.659793) (xy 169.54668 -51.673899) (xy 169.598009 -51.695711)
			(xy 169.645615 -51.724765) (xy 169.688483 -51.76044) (xy 169.7257 -51.801977) (xy 169.756473 -51.84849)
			(xy 169.780145 -51.898987) (xy 169.796213 -51.952394) (xy 169.804333 -52.00757) (xy 169.804842 -52.035456)
			(xy 169.804333 -52.063342) (xy 169.796213 -52.118518) (xy 169.780145 -52.171925) (xy 169.756473 -52.222422)
			(xy 169.7257 -52.268935) (xy 169.688483 -52.310472) (xy 169.645615 -52.346147) (xy 169.598009 -52.375201)
			(xy 169.54668 -52.397013) (xy 169.492723 -52.411119) (xy 169.437286 -52.417219) (xy 169.381552 -52.415182)
			(xy 169.326709 -52.405052) (xy 169.273925 -52.387045) (xy 169.224325 -52.361544) (xy 169.178967 -52.329093)
			(xy 169.138818 -52.290384) (xy 169.104732 -52.246241) (xy 169.077436 -52.197606) (xy 169.057513 -52.145515)
			(xy 169.045387 -52.091078) (xy 169.041316 -52.035456) (xy 154.477869 -52.035456) (xy 154.639425 -54.731412)
			(xy 155.62072 -54.731412) (xy 155.621188 -54.704042) (xy 155.629005 -54.649863) (xy 155.644493 -54.597359)
			(xy 155.667334 -54.547612) (xy 155.697059 -54.501646) (xy 155.7147 -54.480714) (xy 155.714954 -54.48046)
			(xy 155.720528 -54.473365) (xy 155.726781 -54.456455) (xy 155.727146 -54.44744) (xy 155.727146 -54.380384)
			(xy 155.726808 -54.371365) (xy 155.720548 -54.354448) (xy 155.714954 -54.347364) (xy 155.7147 -54.347364)
			(xy 155.7147 -54.34711) (xy 155.697072 -54.326167) (xy 155.667349 -54.2802) (xy 155.644505 -54.230456)
			(xy 155.629009 -54.177955) (xy 155.621179 -54.123779) (xy 155.621178 -54.069039) (xy 155.629005 -54.014862)
			(xy 155.644498 -53.962361) (xy 155.66734 -53.912615) (xy 155.697061 -53.866647) (xy 155.7147 -53.845714)
			(xy 155.714954 -53.84546) (xy 155.720528 -53.838365) (xy 155.726781 -53.821455) (xy 155.727146 -53.81244)
			(xy 155.727146 -53.745384) (xy 155.726808 -53.736365) (xy 155.720548 -53.719448) (xy 155.714954 -53.712364)
			(xy 155.7147 -53.712364) (xy 155.7147 -53.71211) (xy 155.697072 -53.691167) (xy 155.667349 -53.6452)
			(xy 155.644505 -53.595456) (xy 155.629009 -53.542955) (xy 155.621179 -53.488779) (xy 155.621178 -53.434039)
			(xy 155.629005 -53.379862) (xy 155.644498 -53.327361) (xy 155.66734 -53.277615) (xy 155.697061 -53.231647)
			(xy 155.7147 -53.210714) (xy 155.714954 -53.21046) (xy 155.720528 -53.203365) (xy 155.726781 -53.186455)
			(xy 155.727146 -53.17744) (xy 155.727146 -53.110384) (xy 155.726808 -53.101365) (xy 155.720548 -53.084448)
			(xy 155.714954 -53.077364) (xy 155.7147 -53.077364) (xy 155.7147 -53.07711) (xy 155.697052 -53.056185)
			(xy 155.667342 -53.01021) (xy 155.644507 -52.960461) (xy 155.629018 -52.907959) (xy 155.621193 -52.853782)
			(xy 155.62072 -52.826412) (xy 155.621206 -52.799161) (xy 155.628962 -52.745213) (xy 155.644317 -52.692918)
			(xy 155.666959 -52.643341) (xy 155.696425 -52.597491) (xy 155.732116 -52.5563) (xy 155.773307 -52.520609)
			(xy 155.819157 -52.491143) (xy 155.868734 -52.468501) (xy 155.921029 -52.453146) (xy 155.974977 -52.44539)
			(xy 156.029479 -52.44539) (xy 156.083427 -52.453146) (xy 156.135722 -52.468501) (xy 156.185299 -52.491143)
			(xy 156.231149 -52.520609) (xy 156.27234 -52.5563) (xy 156.308031 -52.597491) (xy 156.337497 -52.643341)
			(xy 156.360139 -52.692918) (xy 156.375494 -52.745213) (xy 156.38325 -52.799161) (xy 156.383736 -52.826412)
			(xy 156.383293 -52.853783) (xy 156.375472 -52.907964) (xy 156.359978 -52.960468) (xy 156.337131 -53.010214)
			(xy 156.3074 -53.05618) (xy 156.289756 -53.07711) (xy 156.289502 -53.077364) (xy 156.283925 -53.084457)
			(xy 156.277672 -53.101369) (xy 156.27731 -53.110384) (xy 156.27731 -53.17744) (xy 156.277646 -53.186459)
			(xy 156.283908 -53.203376) (xy 156.289502 -53.21046) (xy 156.289756 -53.21046) (xy 156.289756 -53.210714)
			(xy 156.307409 -53.231637) (xy 156.337135 -53.277606) (xy 156.35998 -53.327354) (xy 156.375477 -53.379857)
			(xy 156.383304 -53.434038) (xy 156.383303 -53.48878) (xy 156.375473 -53.54296) (xy 156.359974 -53.595463)
			(xy 156.337126 -53.64521) (xy 156.307398 -53.691178) (xy 156.289756 -53.71211) (xy 156.289502 -53.712364)
			(xy 156.283925 -53.719457) (xy 156.277672 -53.736369) (xy 156.27731 -53.745384) (xy 156.27731 -53.81244)
			(xy 156.277646 -53.821459) (xy 156.283908 -53.838376) (xy 156.289502 -53.84546) (xy 156.289756 -53.84546)
			(xy 156.289756 -53.845714) (xy 156.307409 -53.866637) (xy 156.337135 -53.912606) (xy 156.35998 -53.962354)
			(xy 156.375477 -54.014857) (xy 156.383304 -54.069038) (xy 156.383303 -54.12378) (xy 156.375473 -54.17796)
			(xy 156.359974 -54.230463) (xy 156.337126 -54.28021) (xy 156.307398 -54.326178) (xy 156.289756 -54.34711)
			(xy 156.289502 -54.347364) (xy 156.283925 -54.354457) (xy 156.277672 -54.371369) (xy 156.27731 -54.380384)
			(xy 156.27731 -54.44744) (xy 156.277646 -54.456459) (xy 156.283908 -54.473376) (xy 156.289502 -54.48046)
			(xy 156.289756 -54.48046) (xy 156.289756 -54.480714) (xy 156.307361 -54.501673) (xy 156.33708 -54.547638)
			(xy 156.359923 -54.597378) (xy 156.375422 -54.649873) (xy 156.383258 -54.704045) (xy 156.383736 -54.731412)
			(xy 156.38325 -54.758663) (xy 156.378586 -54.791102) (xy 158.276544 -54.791102) (xy 158.277001 -54.763731)
			(xy 158.284819 -54.709551) (xy 158.30031 -54.657048) (xy 158.323154 -54.607301) (xy 158.352881 -54.561335)
			(xy 158.370524 -54.540404) (xy 158.370778 -54.54015) (xy 158.376359 -54.53306) (xy 158.382607 -54.516146)
			(xy 158.38297 -54.50713) (xy 158.38297 -54.440074) (xy 158.382632 -54.431055) (xy 158.376372 -54.414138)
			(xy 158.370778 -54.407054) (xy 158.370524 -54.407054) (xy 158.370524 -54.4068) (xy 158.352885 -54.385866)
			(xy 158.323161 -54.339898) (xy 158.300315 -54.290152) (xy 158.284819 -54.23765) (xy 158.27699 -54.183472)
			(xy 158.27699 -54.128731) (xy 158.284819 -54.074553) (xy 158.300314 -54.022051) (xy 158.323159 -53.972305)
			(xy 158.352884 -53.926337) (xy 158.370524 -53.905404) (xy 158.370778 -53.90515) (xy 158.376359 -53.89806)
			(xy 158.382607 -53.881146) (xy 158.38297 -53.87213) (xy 158.38297 -53.805074) (xy 158.382632 -53.796055)
			(xy 158.376372 -53.779138) (xy 158.370778 -53.772054) (xy 158.370524 -53.772054) (xy 158.370524 -53.7718)
			(xy 158.352885 -53.750866) (xy 158.323161 -53.704898) (xy 158.300315 -53.655152) (xy 158.284819 -53.60265)
			(xy 158.27699 -53.548472) (xy 158.27699 -53.493731) (xy 158.284819 -53.439553) (xy 158.300314 -53.387051)
			(xy 158.323159 -53.337305) (xy 158.352884 -53.291337) (xy 158.370524 -53.270404) (xy 158.370778 -53.27015)
			(xy 158.376359 -53.26306) (xy 158.382607 -53.246146) (xy 158.38297 -53.23713) (xy 158.38297 -53.170074)
			(xy 158.382632 -53.161055) (xy 158.376372 -53.144138) (xy 158.370778 -53.137054) (xy 158.370524 -53.137054)
			(xy 158.370524 -53.1368) (xy 158.352875 -53.115876) (xy 158.323164 -53.069901) (xy 158.30033 -53.020152)
			(xy 158.284841 -52.967649) (xy 158.277016 -52.913472) (xy 158.276544 -52.886102) (xy 158.27703 -52.858851)
			(xy 158.284786 -52.804903) (xy 158.300141 -52.752608) (xy 158.322783 -52.703031) (xy 158.352249 -52.657181)
			(xy 158.38794 -52.61599) (xy 158.429131 -52.580299) (xy 158.474981 -52.550833) (xy 158.524558 -52.528191)
			(xy 158.576853 -52.512836) (xy 158.630801 -52.50508) (xy 158.685303 -52.50508) (xy 158.739251 -52.512836)
			(xy 158.791546 -52.528191) (xy 158.830655 -52.546052) (xy 163.779673 -52.546052) (xy 163.779673 -52.491548)
			(xy 163.78743 -52.437599) (xy 163.802786 -52.385303) (xy 163.825428 -52.335725) (xy 163.854895 -52.289873)
			(xy 163.890588 -52.248682) (xy 163.93178 -52.21299) (xy 163.977632 -52.183524) (xy 164.02721 -52.160883)
			(xy 164.079507 -52.145528) (xy 164.133456 -52.137773) (xy 164.160708 -52.13731) (xy 164.188079 -52.137769)
			(xy 164.242258 -52.145588) (xy 164.294761 -52.161079) (xy 164.344508 -52.183922) (xy 164.390475 -52.213648)
			(xy 164.411406 -52.23129) (xy 164.41166 -52.231544) (xy 164.41875 -52.237125) (xy 164.435664 -52.243374)
			(xy 164.44468 -52.243736) (xy 164.511736 -52.243736) (xy 164.520754 -52.243388) (xy 164.53767 -52.237134)
			(xy 164.544756 -52.231544) (xy 164.544756 -52.23129) (xy 164.54501 -52.23129) (xy 164.565943 -52.213649)
			(xy 164.611911 -52.183925) (xy 164.661657 -52.161079) (xy 164.714159 -52.145583) (xy 164.768337 -52.137754)
			(xy 164.823079 -52.137754) (xy 164.877257 -52.145583) (xy 164.929759 -52.161079) (xy 164.979505 -52.183925)
			(xy 165.025473 -52.213649) (xy 165.046406 -52.23129) (xy 165.04666 -52.231544) (xy 165.05375 -52.237125)
			(xy 165.070664 -52.243374) (xy 165.07968 -52.243736) (xy 165.146736 -52.243736) (xy 165.155754 -52.243388)
			(xy 165.17267 -52.237134) (xy 165.179756 -52.231544) (xy 165.179756 -52.23129) (xy 165.18001 -52.23129)
			(xy 165.200926 -52.213631) (xy 165.246904 -52.183923) (xy 165.296655 -52.161091) (xy 165.349159 -52.145604)
			(xy 165.403338 -52.137781) (xy 165.430708 -52.13731) (xy 165.45796 -52.13776) (xy 165.51191 -52.145518)
			(xy 165.564206 -52.160875) (xy 165.613784 -52.183517) (xy 165.659636 -52.212985) (xy 165.700827 -52.248678)
			(xy 165.73652 -52.28987) (xy 165.765986 -52.335723) (xy 165.788628 -52.385302) (xy 165.803984 -52.437598)
			(xy 165.81174 -52.491548) (xy 165.81174 -52.546052) (xy 165.805796 -52.587398) (xy 166.855392 -52.587398)
			(xy 166.859463 -52.531776) (xy 166.871589 -52.477339) (xy 166.891512 -52.425248) (xy 166.918808 -52.376613)
			(xy 166.952894 -52.33247) (xy 166.993043 -52.293761) (xy 167.038401 -52.26131) (xy 167.088001 -52.235809)
			(xy 167.140785 -52.217802) (xy 167.195628 -52.207672) (xy 167.251362 -52.205635) (xy 167.306799 -52.211735)
			(xy 167.360756 -52.225841) (xy 167.412085 -52.247653) (xy 167.459691 -52.276707) (xy 167.502559 -52.312382)
			(xy 167.539776 -52.353919) (xy 167.570549 -52.400432) (xy 167.594221 -52.450929) (xy 167.610289 -52.504336)
			(xy 167.617885 -52.555952) (xy 174.683879 -52.555952) (xy 174.683879 -52.501448) (xy 174.691637 -52.447498)
			(xy 174.706993 -52.395201) (xy 174.729636 -52.345622) (xy 174.759105 -52.29977) (xy 174.794799 -52.25858)
			(xy 174.835993 -52.222888) (xy 174.881847 -52.193423) (xy 174.931427 -52.170783) (xy 174.983725 -52.155431)
			(xy 175.037676 -52.147677) (xy 175.064928 -52.147216) (xy 175.092299 -52.147662) (xy 175.146479 -52.155484)
			(xy 175.198983 -52.170978) (xy 175.248729 -52.193824) (xy 175.294695 -52.223553) (xy 175.315626 -52.241196)
			(xy 175.31588 -52.24145) (xy 175.322964 -52.24704) (xy 175.339883 -52.253284) (xy 175.3489 -52.253642)
			(xy 175.415956 -52.253642) (xy 175.424972 -52.253277) (xy 175.44189 -52.247036) (xy 175.448976 -52.24145)
			(xy 175.448976 -52.241196) (xy 175.44923 -52.241196) (xy 175.470177 -52.223576) (xy 175.516146 -52.193861)
			(xy 175.56589 -52.171022) (xy 175.618387 -52.155526) (xy 175.67256 -52.147693) (xy 175.699928 -52.147216)
			(xy 175.72718 -52.147656) (xy 175.781128 -52.155416) (xy 175.833422 -52.170775) (xy 175.882999 -52.193419)
			(xy 175.928849 -52.222888) (xy 175.970038 -52.258581) (xy 176.005729 -52.299773) (xy 176.035195 -52.345625)
			(xy 176.057835 -52.395204) (xy 176.07319 -52.4475) (xy 176.080946 -52.501448) (xy 176.080946 -52.555952)
			(xy 176.07319 -52.6099) (xy 176.057835 -52.662196) (xy 176.035195 -52.711775) (xy 176.005729 -52.757627)
			(xy 175.970038 -52.798819) (xy 175.928849 -52.834512) (xy 175.882999 -52.863981) (xy 175.833422 -52.886625)
			(xy 175.781128 -52.901984) (xy 175.72718 -52.909744) (xy 175.699928 -52.910232) (xy 175.672558 -52.909766)
			(xy 175.618378 -52.901951) (xy 175.565874 -52.886463) (xy 175.516127 -52.86362) (xy 175.470161 -52.833894)
			(xy 175.44923 -52.816252) (xy 175.448976 -52.815998) (xy 175.441901 -52.810395) (xy 175.424975 -52.804158)
			(xy 175.415956 -52.803806) (xy 175.3489 -52.803806) (xy 175.339883 -52.804162) (xy 175.322966 -52.81041)
			(xy 175.31588 -52.815998) (xy 175.31588 -52.816252) (xy 175.315626 -52.816252) (xy 175.294689 -52.833885)
			(xy 175.248718 -52.863599) (xy 175.198972 -52.886437) (xy 175.146472 -52.90193) (xy 175.092297 -52.909758)
			(xy 175.064928 -52.910232) (xy 175.037676 -52.909723) (xy 174.983725 -52.901969) (xy 174.931427 -52.886617)
			(xy 174.881847 -52.863977) (xy 174.835993 -52.834512) (xy 174.794799 -52.79882) (xy 174.759105 -52.75763)
			(xy 174.729636 -52.711778) (xy 174.706993 -52.662199) (xy 174.691637 -52.609902) (xy 174.683879 -52.555952)
			(xy 167.617885 -52.555952) (xy 167.618409 -52.559512) (xy 167.618918 -52.587398) (xy 167.618409 -52.615284)
			(xy 167.610289 -52.67046) (xy 167.594221 -52.723867) (xy 167.570549 -52.774364) (xy 167.539776 -52.820877)
			(xy 167.502559 -52.862414) (xy 167.459691 -52.898089) (xy 167.412085 -52.927143) (xy 167.360756 -52.948955)
			(xy 167.306799 -52.963061) (xy 167.251362 -52.969161) (xy 167.195628 -52.967124) (xy 167.140785 -52.956994)
			(xy 167.088001 -52.938987) (xy 167.038401 -52.913486) (xy 166.993043 -52.881035) (xy 166.952894 -52.842326)
			(xy 166.918808 -52.798183) (xy 166.891512 -52.749548) (xy 166.871589 -52.697457) (xy 166.859463 -52.64302)
			(xy 166.855392 -52.587398) (xy 165.805796 -52.587398) (xy 165.803984 -52.600002) (xy 165.788628 -52.652298)
			(xy 165.765986 -52.701877) (xy 165.73652 -52.74773) (xy 165.700827 -52.788922) (xy 165.659636 -52.824615)
			(xy 165.613784 -52.854083) (xy 165.564206 -52.876725) (xy 165.51191 -52.892082) (xy 165.45796 -52.89984)
			(xy 165.430708 -52.900326) (xy 165.403337 -52.899873) (xy 165.349157 -52.892055) (xy 165.296653 -52.876564)
			(xy 165.246906 -52.853719) (xy 165.20094 -52.82399) (xy 165.18001 -52.806346) (xy 165.179756 -52.806092)
			(xy 165.172658 -52.800522) (xy 165.15575 -52.794266) (xy 165.146736 -52.7939) (xy 165.07968 -52.7939)
			(xy 165.070662 -52.794248) (xy 165.053745 -52.800502) (xy 165.04666 -52.806092) (xy 165.046406 -52.806346)
			(xy 165.025473 -52.823987) (xy 164.979505 -52.853711) (xy 164.929759 -52.876557) (xy 164.877257 -52.892053)
			(xy 164.823079 -52.899882) (xy 164.768337 -52.899882) (xy 164.714159 -52.892053) (xy 164.661657 -52.876557)
			(xy 164.611911 -52.853711) (xy 164.565943 -52.823987) (xy 164.54501 -52.806346) (xy 164.544756 -52.806092)
			(xy 164.537658 -52.800522) (xy 164.52075 -52.794266) (xy 164.511736 -52.7939) (xy 164.44468 -52.7939)
			(xy 164.435662 -52.794248) (xy 164.418745 -52.800502) (xy 164.41166 -52.806092) (xy 164.41166 -52.806346)
			(xy 164.411406 -52.806346) (xy 164.390476 -52.823987) (xy 164.344503 -52.853701) (xy 164.294755 -52.876537)
			(xy 164.242254 -52.892027) (xy 164.188077 -52.899854) (xy 164.160708 -52.900326) (xy 164.133456 -52.899827)
			(xy 164.079507 -52.892072) (xy 164.02721 -52.876717) (xy 163.977632 -52.854076) (xy 163.93178 -52.82461)
			(xy 163.890588 -52.788918) (xy 163.854895 -52.747727) (xy 163.825428 -52.701875) (xy 163.802786 -52.652297)
			(xy 163.78743 -52.600001) (xy 163.779673 -52.546052) (xy 158.830655 -52.546052) (xy 158.841123 -52.550833)
			(xy 158.886973 -52.580299) (xy 158.928164 -52.61599) (xy 158.963855 -52.657181) (xy 158.993321 -52.703031)
			(xy 159.015963 -52.752608) (xy 159.031318 -52.804903) (xy 159.039074 -52.858851) (xy 159.03956 -52.886102)
			(xy 159.039105 -52.913473) (xy 159.031286 -52.967653) (xy 159.015795 -53.020156) (xy 158.99295 -53.069903)
			(xy 158.963223 -53.115869) (xy 158.94558 -53.1368) (xy 158.945326 -53.137054) (xy 158.939744 -53.144143)
			(xy 158.933496 -53.161058) (xy 158.933134 -53.170074) (xy 158.933134 -53.23713) (xy 158.933469 -53.246149)
			(xy 158.939731 -53.263066) (xy 158.945326 -53.27015) (xy 158.94558 -53.27015) (xy 158.94558 -53.270404)
			(xy 158.963222 -53.291335) (xy 158.992947 -53.337304) (xy 159.015791 -53.38705) (xy 159.031287 -53.439552)
			(xy 159.039115 -53.493731) (xy 159.039115 -53.548472) (xy 159.031287 -53.602651) (xy 159.01579 -53.655153)
			(xy 158.992945 -53.704899) (xy 158.963221 -53.750867) (xy 158.94665 -53.77053) (xy 159.310832 -53.77053)
			(xy 159.31136 -53.741613) (xy 159.320085 -53.684442) (xy 159.33734 -53.629243) (xy 159.36273 -53.577281)
			(xy 159.395673 -53.529747) (xy 159.435413 -53.48773) (xy 159.457898 -53.46954) (xy 159.466677 -53.461905)
			(xy 159.476876 -53.441026) (xy 159.477456 -53.429408) (xy 159.477456 -53.349652) (xy 159.476946 -53.338016)
			(xy 159.466738 -53.317106) (xy 159.457898 -53.30952) (xy 159.435424 -53.291318) (xy 159.395688 -53.249301)
			(xy 159.362748 -53.201768) (xy 159.337358 -53.149809) (xy 159.3201 -53.094613) (xy 159.311368 -53.037445)
			(xy 159.310832 -53.00853) (xy 159.311283 -52.981276) (xy 159.319037 -52.927323) (xy 159.334392 -52.875022)
			(xy 159.357033 -52.825439) (xy 159.386502 -52.779584) (xy 159.422197 -52.73839) (xy 159.463392 -52.702696)
			(xy 159.509248 -52.673229) (xy 159.558831 -52.650588) (xy 159.611132 -52.635235) (xy 159.665086 -52.627483)
			(xy 159.69234 -52.627022) (xy 159.718655 -52.627456) (xy 159.770785 -52.634696) (xy 159.821429 -52.649022)
			(xy 159.869628 -52.67016) (xy 159.914471 -52.697713) (xy 159.955109 -52.731158) (xy 159.973264 -52.750212)
			(xy 159.980795 -52.757602) (xy 160.000068 -52.766133) (xy 160.010602 -52.766722) (xy 160.085278 -52.766722)
			(xy 160.095827 -52.766188) (xy 160.115122 -52.757655) (xy 160.122616 -52.750212) (xy 160.140773 -52.731158)
			(xy 160.181402 -52.6977) (xy 160.226242 -52.670141) (xy 160.274443 -52.649002) (xy 160.32509 -52.634685)
			(xy 160.377224 -52.62746) (xy 160.40354 -52.627022) (xy 160.430794 -52.627441) (xy 160.484745 -52.635203)
			(xy 160.537043 -52.650565) (xy 160.586622 -52.673213) (xy 160.632474 -52.702686) (xy 160.673665 -52.738385)
			(xy 160.709356 -52.779582) (xy 160.73882 -52.825439) (xy 160.761459 -52.875023) (xy 160.776811 -52.927323)
			(xy 160.784564 -52.981276) (xy 160.785048 -53.00853) (xy 160.784583 -53.036197) (xy 160.782352 -53.051456)
			(xy 169.041316 -53.051456) (xy 169.045387 -52.995834) (xy 169.057513 -52.941397) (xy 169.077436 -52.889306)
			(xy 169.104732 -52.840671) (xy 169.138818 -52.796528) (xy 169.178967 -52.757819) (xy 169.224325 -52.725368)
			(xy 169.273925 -52.699867) (xy 169.326709 -52.68186) (xy 169.381552 -52.67173) (xy 169.437286 -52.669693)
			(xy 169.492723 -52.675793) (xy 169.54668 -52.689899) (xy 169.598009 -52.711711) (xy 169.645615 -52.740765)
			(xy 169.688483 -52.77644) (xy 169.7257 -52.817977) (xy 169.756473 -52.86449) (xy 169.780145 -52.914987)
			(xy 169.796213 -52.968394) (xy 169.804333 -53.02357) (xy 169.804842 -53.051456) (xy 169.804333 -53.079342)
			(xy 169.796213 -53.134518) (xy 169.780145 -53.187925) (xy 169.756473 -53.238422) (xy 169.7257 -53.284935)
			(xy 169.688483 -53.326472) (xy 169.645615 -53.362147) (xy 169.598009 -53.391201) (xy 169.54668 -53.413013)
			(xy 169.492723 -53.427119) (xy 169.437286 -53.433219) (xy 169.381552 -53.431182) (xy 169.326709 -53.421052)
			(xy 169.273925 -53.403045) (xy 169.224325 -53.377544) (xy 169.178967 -53.345093) (xy 169.138818 -53.306384)
			(xy 169.104732 -53.262241) (xy 169.077436 -53.213606) (xy 169.057513 -53.161515) (xy 169.045387 -53.107078)
			(xy 169.041316 -53.051456) (xy 160.782352 -53.051456) (xy 160.776578 -53.090949) (xy 160.760755 -53.143973)
			(xy 160.737445 -53.194158) (xy 160.707136 -53.240453) (xy 160.670462 -53.28189) (xy 160.628193 -53.317599)
			(xy 160.604962 -53.332634) (xy 160.595274 -53.339257) (xy 160.582835 -53.359128) (xy 160.581086 -53.370734)
			(xy 160.573212 -53.450744) (xy 160.572572 -53.462382) (xy 160.580659 -53.484219) (xy 160.588706 -53.492654)
			(xy 160.58896 -53.492908) (xy 160.60752 -53.51101) (xy 160.640102 -53.551337) (xy 160.666919 -53.595706)
			(xy 160.687475 -53.643301) (xy 160.701393 -53.693242) (xy 160.708414 -53.744608) (xy 160.708848 -53.77053)
			(xy 160.70835 -53.79778) (xy 160.700591 -53.851725) (xy 160.685234 -53.904017) (xy 160.662592 -53.953592)
			(xy 160.633126 -53.99944) (xy 160.597436 -54.040629) (xy 160.556248 -54.07632) (xy 160.510401 -54.105787)
			(xy 160.460827 -54.12843) (xy 160.408535 -54.143789) (xy 160.35459 -54.15155) (xy 160.32734 -54.152038)
			(xy 160.29997 -54.151564) (xy 160.245791 -54.14375) (xy 160.193287 -54.128264) (xy 160.14354 -54.105424)
			(xy 160.097573 -54.075699) (xy 160.076642 -54.058058) (xy 160.076388 -54.057804) (xy 160.069309 -54.052207)
			(xy 160.052386 -54.045966) (xy 160.043368 -54.045612) (xy 159.976312 -54.045612) (xy 159.967295 -54.045972)
			(xy 159.950378 -54.052217) (xy 159.943292 -54.057804) (xy 159.943292 -54.058058) (xy 159.943038 -54.058058)
			(xy 159.922097 -54.075686) (xy 159.876127 -54.105401) (xy 159.826382 -54.12824) (xy 159.773883 -54.143733)
			(xy 159.719709 -54.151563) (xy 159.69234 -54.152038) (xy 159.665089 -54.151508) (xy 159.611143 -54.143757)
			(xy 159.558848 -54.128407) (xy 159.50927 -54.105772) (xy 159.463418 -54.076311) (xy 159.422226 -54.040624)
			(xy 159.386531 -53.999438) (xy 159.357062 -53.953592) (xy 159.334417 -53.904018) (xy 159.319058 -53.851726)
			(xy 159.311297 -53.79778) (xy 159.310832 -53.77053) (xy 158.94665 -53.77053) (xy 158.94558 -53.7718)
			(xy 158.945326 -53.772054) (xy 158.939744 -53.779143) (xy 158.933496 -53.796058) (xy 158.933134 -53.805074)
			(xy 158.933134 -53.87213) (xy 158.933469 -53.881149) (xy 158.939731 -53.898066) (xy 158.945326 -53.90515)
			(xy 158.94558 -53.90515) (xy 158.94558 -53.905404) (xy 158.963222 -53.926335) (xy 158.992947 -53.972304)
			(xy 159.015791 -54.02205) (xy 159.031287 -54.074552) (xy 159.039115 -54.128731) (xy 159.039115 -54.183472)
			(xy 159.031287 -54.237651) (xy 159.01579 -54.290153) (xy 159.001998 -54.320186) (xy 161.230564 -54.320186)
			(xy 161.231006 -54.292815) (xy 161.238827 -54.238634) (xy 161.254321 -54.18613) (xy 161.277169 -54.136383)
			(xy 161.3069 -54.090418) (xy 161.324544 -54.069488) (xy 161.324798 -54.069234) (xy 161.330376 -54.062142)
			(xy 161.336628 -54.045229) (xy 161.33699 -54.036214) (xy 161.33699 -53.969158) (xy 161.336607 -53.960144)
			(xy 161.330378 -53.943226) (xy 161.324798 -53.936138) (xy 161.324544 -53.936138) (xy 161.324544 -53.935884)
			(xy 161.306938 -53.914925) (xy 161.277219 -53.868961) (xy 161.254376 -53.81922) (xy 161.238878 -53.766725)
			(xy 161.231042 -53.712553) (xy 161.230564 -53.685186) (xy 161.23105 -53.657935) (xy 161.238806 -53.603987)
			(xy 161.254161 -53.551692) (xy 161.276803 -53.502115) (xy 161.306269 -53.456265) (xy 161.34196 -53.415074)
			(xy 161.383151 -53.379383) (xy 161.429001 -53.349917) (xy 161.478578 -53.327275) (xy 161.530873 -53.31192)
			(xy 161.584821 -53.304164) (xy 161.639323 -53.304164) (xy 161.693271 -53.31192) (xy 161.745566 -53.327275)
			(xy 161.795143 -53.349917) (xy 161.840993 -53.379383) (xy 161.882184 -53.415074) (xy 161.917875 -53.456265)
			(xy 161.943766 -53.496552) (xy 174.233564 -53.496552) (xy 174.233564 -53.442048) (xy 174.24132 -53.3881)
			(xy 174.256675 -53.335804) (xy 174.279316 -53.286226) (xy 174.308782 -53.240375) (xy 174.344474 -53.199183)
			(xy 174.385664 -53.163491) (xy 174.431514 -53.134023) (xy 174.481091 -53.11138) (xy 174.533386 -53.096023)
			(xy 174.587334 -53.088265) (xy 174.614586 -53.087778) (xy 174.641957 -53.088233) (xy 174.696137 -53.096051)
			(xy 174.748641 -53.111541) (xy 174.798388 -53.134386) (xy 174.844353 -53.164114) (xy 174.865284 -53.181758)
			(xy 174.865538 -53.182012) (xy 174.872637 -53.18758) (xy 174.889544 -53.193838) (xy 174.898558 -53.194204)
			(xy 174.965614 -53.194204) (xy 174.974631 -53.193853) (xy 174.991548 -53.187601) (xy 174.998634 -53.182012)
			(xy 174.998634 -53.181758) (xy 174.998888 -53.181758) (xy 175.019808 -53.164104) (xy 175.065785 -53.134396)
			(xy 175.115535 -53.111563) (xy 175.168039 -53.096075) (xy 175.222216 -53.08825) (xy 175.249586 -53.087778)
			(xy 175.276839 -53.088268) (xy 175.330789 -53.096023) (xy 175.383087 -53.111378) (xy 175.432667 -53.134019)
			(xy 175.47852 -53.163485) (xy 175.519713 -53.199177) (xy 175.555407 -53.240369) (xy 175.584875 -53.286221)
			(xy 175.607517 -53.3358) (xy 175.622874 -53.388097) (xy 175.630631 -53.442048) (xy 175.630631 -53.496552)
			(xy 175.622874 -53.550503) (xy 175.607517 -53.6028) (xy 175.584875 -53.652379) (xy 175.555407 -53.698231)
			(xy 175.519713 -53.739423) (xy 175.47852 -53.775115) (xy 175.432667 -53.804581) (xy 175.383087 -53.827222)
			(xy 175.330789 -53.842577) (xy 175.276839 -53.850332) (xy 175.249586 -53.850794) (xy 175.222215 -53.850338)
			(xy 175.168036 -53.842518) (xy 175.115533 -53.827026) (xy 175.065786 -53.804183) (xy 175.019819 -53.774456)
			(xy 174.998888 -53.756814) (xy 174.998634 -53.75656) (xy 174.991545 -53.750977) (xy 174.97463 -53.744729)
			(xy 174.965614 -53.744368) (xy 174.898558 -53.744368) (xy 174.889545 -53.74476) (xy 174.872628 -53.750984)
			(xy 174.865538 -53.75656) (xy 174.865538 -53.756814) (xy 174.865284 -53.756814) (xy 174.844333 -53.774429)
			(xy 174.798365 -53.804144) (xy 174.748622 -53.826985) (xy 174.696126 -53.842481) (xy 174.641954 -53.850316)
			(xy 174.614586 -53.850794) (xy 174.587334 -53.850335) (xy 174.533386 -53.842577) (xy 174.481091 -53.82722)
			(xy 174.431514 -53.804577) (xy 174.385664 -53.775109) (xy 174.344474 -53.739417) (xy 174.308782 -53.698225)
			(xy 174.279316 -53.652374) (xy 174.256675 -53.602796) (xy 174.24132 -53.5505) (xy 174.233564 -53.496552)
			(xy 161.943766 -53.496552) (xy 161.947341 -53.502115) (xy 161.969983 -53.551692) (xy 161.985338 -53.603987)
			(xy 161.993094 -53.657935) (xy 161.99358 -53.685186) (xy 161.993111 -53.712556) (xy 161.985294 -53.766735)
			(xy 161.969806 -53.819239) (xy 161.946965 -53.868986) (xy 161.917241 -53.914952) (xy 161.8996 -53.935884)
			(xy 161.899346 -53.936138) (xy 161.893773 -53.943233) (xy 161.887519 -53.960144) (xy 161.887154 -53.969158)
			(xy 161.887154 -54.036214) (xy 161.887493 -54.045233) (xy 161.893752 -54.06215) (xy 161.899346 -54.069234)
			(xy 161.8996 -54.069234) (xy 161.8996 -54.069488) (xy 161.917247 -54.090414) (xy 161.946958 -54.136388)
			(xy 161.969792 -54.186137) (xy 161.985281 -54.238639) (xy 161.993107 -54.292816) (xy 161.99358 -54.320186)
			(xy 161.993094 -54.347437) (xy 161.985338 -54.401385) (xy 161.969983 -54.45368) (xy 161.947341 -54.503257)
			(xy 161.917875 -54.549107) (xy 161.882184 -54.590298) (xy 161.840993 -54.625989) (xy 161.795143 -54.655455)
			(xy 161.745566 -54.678097) (xy 161.693271 -54.693452) (xy 161.639323 -54.701208) (xy 161.584821 -54.701208)
			(xy 161.530873 -54.693452) (xy 161.478578 -54.678097) (xy 161.429001 -54.655455) (xy 161.383151 -54.625989)
			(xy 161.34196 -54.590298) (xy 161.306269 -54.549107) (xy 161.276803 -54.503257) (xy 161.254161 -54.45368)
			(xy 161.238806 -54.401385) (xy 161.23105 -54.347437) (xy 161.230564 -54.320186) (xy 159.001998 -54.320186)
			(xy 158.992945 -54.339899) (xy 158.963221 -54.385867) (xy 158.94558 -54.4068) (xy 158.945326 -54.407054)
			(xy 158.939744 -54.414143) (xy 158.933496 -54.431058) (xy 158.933134 -54.440074) (xy 158.933134 -54.50713)
			(xy 158.933469 -54.516149) (xy 158.939731 -54.533066) (xy 158.945326 -54.54015) (xy 158.94558 -54.54015)
			(xy 158.94558 -54.540404) (xy 158.963231 -54.561326) (xy 158.992942 -54.607301) (xy 159.015776 -54.657051)
			(xy 159.031264 -54.709554) (xy 159.039088 -54.763732) (xy 159.039205 -54.770528) (xy 162.171126 -54.770528)
			(xy 162.171602 -54.743158) (xy 162.179417 -54.688979) (xy 162.194903 -54.636476) (xy 162.217743 -54.586729)
			(xy 162.247465 -54.540762) (xy 162.265106 -54.51983) (xy 162.26536 -54.519576) (xy 162.27097 -54.512506)
			(xy 162.277201 -54.495576) (xy 162.277552 -54.486556) (xy 162.277552 -54.4195) (xy 162.277205 -54.410482)
			(xy 162.270952 -54.393565) (xy 162.26536 -54.38648) (xy 162.265106 -54.38648) (xy 162.265106 -54.386226)
			(xy 162.247467 -54.365294) (xy 162.217755 -54.319321) (xy 162.194919 -54.269574) (xy 162.179428 -54.217073)
			(xy 162.1716 -54.162897) (xy 162.171126 -54.135528) (xy 162.171612 -54.108277) (xy 162.179368 -54.054329)
			(xy 162.194723 -54.002034) (xy 162.217365 -53.952457) (xy 162.246831 -53.906607) (xy 162.282522 -53.865416)
			(xy 162.323713 -53.829725) (xy 162.369563 -53.800259) (xy 162.41914 -53.777617) (xy 162.471435 -53.762262)
			(xy 162.525383 -53.754506) (xy 162.579885 -53.754506) (xy 162.633833 -53.762262) (xy 162.686128 -53.777617)
			(xy 162.735705 -53.800259) (xy 162.781555 -53.829725) (xy 162.822746 -53.865416) (xy 162.858437 -53.906607)
			(xy 162.887903 -53.952457) (xy 162.892978 -53.96357) (xy 166.872156 -53.96357) (xy 166.876227 -53.907948)
			(xy 166.888353 -53.853511) (xy 166.908276 -53.80142) (xy 166.935572 -53.752785) (xy 166.969658 -53.708642)
			(xy 167.009807 -53.669933) (xy 167.055165 -53.637482) (xy 167.104765 -53.611981) (xy 167.157549 -53.593974)
			(xy 167.212392 -53.583844) (xy 167.268126 -53.581807) (xy 167.323563 -53.587907) (xy 167.37752 -53.602013)
			(xy 167.428849 -53.623825) (xy 167.476455 -53.652879) (xy 167.519323 -53.688554) (xy 167.55654 -53.730091)
			(xy 167.587313 -53.776604) (xy 167.610985 -53.827101) (xy 167.627053 -53.880508) (xy 167.635173 -53.935684)
			(xy 167.635682 -53.96357) (xy 167.635173 -53.991456) (xy 167.627053 -54.046632) (xy 167.610985 -54.100039)
			(xy 167.587313 -54.150536) (xy 167.55654 -54.197049) (xy 167.519323 -54.238586) (xy 167.476455 -54.274261)
			(xy 167.428849 -54.303315) (xy 167.37752 -54.325127) (xy 167.323563 -54.339233) (xy 167.268126 -54.345333)
			(xy 167.212392 -54.343296) (xy 167.157549 -54.333166) (xy 167.104765 -54.315159) (xy 167.055165 -54.289658)
			(xy 167.009807 -54.257207) (xy 166.969658 -54.218498) (xy 166.935572 -54.174355) (xy 166.908276 -54.12572)
			(xy 166.888353 -54.073629) (xy 166.876227 -54.019192) (xy 166.872156 -53.96357) (xy 162.892978 -53.96357)
			(xy 162.910545 -54.002034) (xy 162.9259 -54.054329) (xy 162.933656 -54.108277) (xy 162.934142 -54.135528)
			(xy 162.933706 -54.162899) (xy 162.925883 -54.21708) (xy 162.910388 -54.269584) (xy 162.887539 -54.319331)
			(xy 162.857807 -54.365296) (xy 162.840162 -54.386226) (xy 162.839908 -54.38648) (xy 162.834325 -54.393569)
			(xy 162.828076 -54.410484) (xy 162.827716 -54.4195) (xy 162.827716 -54.486556) (xy 162.828091 -54.495571)
			(xy 162.834326 -54.512488) (xy 162.839908 -54.519576) (xy 162.840162 -54.519576) (xy 162.840162 -54.51983)
			(xy 162.857776 -54.540783) (xy 162.887493 -54.586749) (xy 162.910334 -54.636491) (xy 162.925831 -54.688988)
			(xy 162.933665 -54.74316) (xy 162.934142 -54.770528) (xy 162.933656 -54.797779) (xy 162.9259 -54.851727)
			(xy 162.910545 -54.904022) (xy 162.887903 -54.953599) (xy 162.865119 -54.989051) (xy 172.001168 -54.989051)
			(xy 172.001168 -54.934549) (xy 172.008924 -54.880602) (xy 172.024278 -54.828307) (xy 172.046919 -54.77873)
			(xy 172.076384 -54.732879) (xy 172.112074 -54.691688) (xy 172.153263 -54.655996) (xy 172.199112 -54.626528)
			(xy 172.248688 -54.603885) (xy 172.300982 -54.588528) (xy 172.354929 -54.580769) (xy 172.38218 -54.580282)
			(xy 172.410271 -54.580793) (xy 172.465847 -54.589017) (xy 172.519616 -54.605305) (xy 172.570413 -54.629305)
			(xy 172.61714 -54.660498) (xy 172.658786 -54.698208) (xy 172.694449 -54.741619) (xy 172.709332 -54.765448)
			(xy 172.714666 -54.774338) (xy 172.731684 -54.78653) (xy 172.824902 -54.80685) (xy 172.845476 -54.802532)
			(xy 172.854112 -54.79669) (xy 172.87817 -54.780681) (xy 172.930104 -54.755341) (xy 172.985264 -54.738118)
			(xy 173.042389 -54.729405) (xy 173.071282 -54.728872) (xy 173.098532 -54.729395) (xy 173.152477 -54.737148)
			(xy 173.20477 -54.7525) (xy 173.254346 -54.775138) (xy 173.300195 -54.8046) (xy 173.341385 -54.840288)
			(xy 173.377077 -54.881474) (xy 173.406544 -54.927321) (xy 173.429186 -54.976894) (xy 173.444543 -55.029186)
			(xy 173.452302 -55.08313) (xy 173.45279 -55.11038) (xy 173.452315 -55.13775) (xy 173.444499 -55.191929)
			(xy 173.429013 -55.244432) (xy 173.406173 -55.294179) (xy 173.37645 -55.340146) (xy 173.35881 -55.361078)
			(xy 173.358556 -55.361332) (xy 173.352986 -55.36843) (xy 173.346731 -55.385338) (xy 173.346364 -55.394352)
			(xy 173.346364 -55.461408) (xy 173.346725 -55.470424) (xy 173.35297 -55.487341) (xy 173.358556 -55.494428)
			(xy 173.35881 -55.494428) (xy 173.35881 -55.494682) (xy 173.37643 -55.515631) (xy 173.406152 -55.561597)
			(xy 173.428997 -55.611341) (xy 173.444493 -55.66384) (xy 173.452323 -55.718016) (xy 173.452325 -55.772754)
			(xy 173.444499 -55.82693) (xy 173.429007 -55.879431) (xy 173.406167 -55.929176) (xy 173.376448 -55.975145)
			(xy 173.35881 -55.996078) (xy 173.358556 -55.996332) (xy 173.352986 -56.00343) (xy 173.346731 -56.020338)
			(xy 173.346364 -56.029352) (xy 173.346364 -56.096408) (xy 173.346725 -56.105424) (xy 173.35297 -56.122341)
			(xy 173.358556 -56.129428) (xy 173.35881 -56.129428) (xy 173.35881 -56.129682) (xy 173.376456 -56.150609)
			(xy 173.406166 -56.196583) (xy 173.429001 -56.246332) (xy 173.44449 -56.298834) (xy 173.452317 -56.35301)
			(xy 173.45279 -56.38038) (xy 173.452304 -56.407631) (xy 173.444548 -56.461579) (xy 173.429193 -56.513874)
			(xy 173.406551 -56.563451) (xy 173.377085 -56.609301) (xy 173.341394 -56.650492) (xy 173.300203 -56.686183)
			(xy 173.254353 -56.715649) (xy 173.204776 -56.738291) (xy 173.152481 -56.753646) (xy 173.098533 -56.761402)
			(xy 173.044031 -56.761402) (xy 172.990083 -56.753646) (xy 172.937788 -56.738291) (xy 172.888211 -56.715649)
			(xy 172.842361 -56.686183) (xy 172.80117 -56.650492) (xy 172.765479 -56.609301) (xy 172.736013 -56.563451)
			(xy 172.713371 -56.513874) (xy 172.698016 -56.461579) (xy 172.69026 -56.407631) (xy 172.689774 -56.38038)
			(xy 172.69021 -56.353008) (xy 172.698033 -56.298827) (xy 172.713528 -56.246323) (xy 172.736376 -56.196577)
			(xy 172.766109 -56.150612) (xy 172.783754 -56.129682) (xy 172.784008 -56.129428) (xy 172.78959 -56.122338)
			(xy 172.795839 -56.105424) (xy 172.7962 -56.096408) (xy 172.7962 -56.029352) (xy 172.795818 -56.020338)
			(xy 172.789588 -56.003421) (xy 172.784008 -55.996332) (xy 172.783754 -55.996332) (xy 172.783754 -55.996078)
			(xy 172.766093 -55.975162) (xy 172.736367 -55.929192) (xy 172.713521 -55.879443) (xy 172.698025 -55.826938)
			(xy 172.690197 -55.772757) (xy 172.6902 -55.718013) (xy 172.698031 -55.663832) (xy 172.713531 -55.611329)
			(xy 172.736381 -55.561582) (xy 172.766111 -55.515614) (xy 172.783754 -55.494682) (xy 172.784008 -55.494428)
			(xy 172.78959 -55.487338) (xy 172.795839 -55.470424) (xy 172.7962 -55.461408) (xy 172.7962 -55.394352)
			(xy 172.795818 -55.385338) (xy 172.789588 -55.368421) (xy 172.784008 -55.361332) (xy 172.783754 -55.360824)
			(xy 172.772808 -55.348091) (xy 172.752968 -55.320999) (xy 172.74413 -55.306722) (xy 172.738796 -55.297832)
			(xy 172.721778 -55.28564) (xy 172.62856 -55.26532) (xy 172.607986 -55.269638) (xy 172.59935 -55.27548)
			(xy 172.575273 -55.291459) (xy 172.523346 -55.316807) (xy 172.468192 -55.334038) (xy 172.411071 -55.34276)
			(xy 172.38218 -55.343298) (xy 172.354929 -55.342831) (xy 172.300982 -55.335072) (xy 172.248688 -55.319715)
			(xy 172.199112 -55.297072) (xy 172.153263 -55.267604) (xy 172.112074 -55.231912) (xy 172.076384 -55.190721)
			(xy 172.046919 -55.14487) (xy 172.024278 -55.095293) (xy 172.008924 -55.042998) (xy 172.001168 -54.989051)
			(xy 162.865119 -54.989051) (xy 162.858437 -54.999449) (xy 162.822746 -55.04064) (xy 162.781555 -55.076331)
			(xy 162.735705 -55.105797) (xy 162.686128 -55.128439) (xy 162.633833 -55.143794) (xy 162.579885 -55.15155)
			(xy 162.525383 -55.15155) (xy 162.471435 -55.143794) (xy 162.41914 -55.128439) (xy 162.369563 -55.105797)
			(xy 162.323713 -55.076331) (xy 162.282522 -55.04064) (xy 162.246831 -54.999449) (xy 162.217365 -54.953599)
			(xy 162.194723 -54.904022) (xy 162.179368 -54.851727) (xy 162.171612 -54.797779) (xy 162.171126 -54.770528)
			(xy 159.039205 -54.770528) (xy 159.03956 -54.791102) (xy 159.039074 -54.818353) (xy 159.031318 -54.872301)
			(xy 159.015963 -54.924596) (xy 158.993321 -54.974173) (xy 158.963855 -55.020023) (xy 158.928164 -55.061214)
			(xy 158.886973 -55.096905) (xy 158.841123 -55.126371) (xy 158.791546 -55.149013) (xy 158.739251 -55.164368)
			(xy 158.685303 -55.172124) (xy 158.630801 -55.172124) (xy 158.576853 -55.164368) (xy 158.524558 -55.149013)
			(xy 158.474981 -55.126371) (xy 158.429131 -55.096905) (xy 158.38794 -55.061214) (xy 158.352249 -55.020023)
			(xy 158.322783 -54.974173) (xy 158.300141 -54.924596) (xy 158.284786 -54.872301) (xy 158.27703 -54.818353)
			(xy 158.276544 -54.791102) (xy 156.378586 -54.791102) (xy 156.375494 -54.812611) (xy 156.360139 -54.864906)
			(xy 156.337497 -54.914483) (xy 156.308031 -54.960333) (xy 156.27234 -55.001524) (xy 156.231149 -55.037215)
			(xy 156.185299 -55.066681) (xy 156.135722 -55.089323) (xy 156.083427 -55.104678) (xy 156.029479 -55.112434)
			(xy 155.974977 -55.112434) (xy 155.921029 -55.104678) (xy 155.868734 -55.089323) (xy 155.819157 -55.066681)
			(xy 155.773307 -55.037215) (xy 155.732116 -55.001524) (xy 155.696425 -54.960333) (xy 155.666959 -54.914483)
			(xy 155.644317 -54.864906) (xy 155.628962 -54.812611) (xy 155.621206 -54.758663) (xy 155.62072 -54.731412)
			(xy 154.639425 -54.731412) (xy 154.698802 -55.722266) (xy 167.93413 -55.722266) (xy 167.938201 -55.666644)
			(xy 167.950327 -55.612207) (xy 167.97025 -55.560116) (xy 167.997546 -55.511481) (xy 168.031632 -55.467338)
			(xy 168.071781 -55.428629) (xy 168.117139 -55.396178) (xy 168.166739 -55.370677) (xy 168.219523 -55.35267)
			(xy 168.274366 -55.34254) (xy 168.3301 -55.340503) (xy 168.385537 -55.346603) (xy 168.439494 -55.360709)
			(xy 168.490823 -55.382521) (xy 168.538429 -55.411575) (xy 168.549575 -55.420851) (xy 170.324768 -55.420851)
			(xy 170.324768 -55.366349) (xy 170.332524 -55.312402) (xy 170.347878 -55.260107) (xy 170.370519 -55.21053)
			(xy 170.399984 -55.164679) (xy 170.435674 -55.123488) (xy 170.476863 -55.087796) (xy 170.522712 -55.058328)
			(xy 170.572288 -55.035685) (xy 170.624582 -55.020328) (xy 170.678529 -55.012569) (xy 170.70578 -55.012082)
			(xy 170.732093 -55.012569) (xy 170.784221 -55.0198) (xy 170.834863 -55.034116) (xy 170.883062 -55.055245)
			(xy 170.927906 -55.082787) (xy 170.968547 -55.116222) (xy 170.986704 -55.135272) (xy 170.994226 -55.142673)
			(xy 171.013506 -55.151199) (xy 171.024042 -55.151782) (xy 171.098718 -55.151782) (xy 171.109265 -55.151227)
			(xy 171.128561 -55.142711) (xy 171.136056 -55.135272) (xy 171.154186 -55.116191) (xy 171.194822 -55.082737)
			(xy 171.239668 -55.055182) (xy 171.287873 -55.034048) (xy 171.338525 -55.019736) (xy 171.390662 -55.012517)
			(xy 171.41698 -55.012082) (xy 171.444233 -55.012564) (xy 171.498185 -55.020318) (xy 171.550484 -55.035672)
			(xy 171.600065 -55.058313) (xy 171.645919 -55.08778) (xy 171.687113 -55.123472) (xy 171.722808 -55.164665)
			(xy 171.752277 -55.210517) (xy 171.774921 -55.260098) (xy 171.790277 -55.312396) (xy 171.798035 -55.366347)
			(xy 171.798035 -55.420853) (xy 171.790277 -55.474804) (xy 171.774921 -55.527102) (xy 171.752277 -55.576683)
			(xy 171.722808 -55.622535) (xy 171.687113 -55.663728) (xy 171.645919 -55.69942) (xy 171.600065 -55.728887)
			(xy 171.550484 -55.751528) (xy 171.498185 -55.766882) (xy 171.444233 -55.774636) (xy 171.41698 -55.775098)
			(xy 171.390666 -55.774645) (xy 171.338536 -55.767407) (xy 171.287893 -55.753085) (xy 171.239694 -55.73195)
			(xy 171.194851 -55.704402) (xy 171.154212 -55.670961) (xy 171.136056 -55.651908) (xy 171.128552 -55.644486)
			(xy 171.109259 -55.635973) (xy 171.098718 -55.635398) (xy 171.024042 -55.635398) (xy 171.013493 -55.635937)
			(xy 170.994198 -55.644465) (xy 170.986704 -55.651908) (xy 170.968541 -55.670956) (xy 170.927913 -55.704414)
			(xy 170.883074 -55.731973) (xy 170.834875 -55.753113) (xy 170.784229 -55.767432) (xy 170.732096 -55.774658)
			(xy 170.70578 -55.775098) (xy 170.678529 -55.774631) (xy 170.624582 -55.766872) (xy 170.572288 -55.751515)
			(xy 170.522712 -55.728872) (xy 170.476863 -55.699404) (xy 170.435674 -55.663712) (xy 170.399984 -55.622521)
			(xy 170.370519 -55.57667) (xy 170.347878 -55.527093) (xy 170.332524 -55.474798) (xy 170.324768 -55.420851)
			(xy 168.549575 -55.420851) (xy 168.581297 -55.44725) (xy 168.618514 -55.488787) (xy 168.649287 -55.5353)
			(xy 168.672959 -55.585797) (xy 168.689027 -55.639204) (xy 168.697147 -55.69438) (xy 168.697656 -55.722266)
			(xy 168.697147 -55.750152) (xy 168.689027 -55.805328) (xy 168.672959 -55.858735) (xy 168.649287 -55.909232)
			(xy 168.618514 -55.955745) (xy 168.581297 -55.997282) (xy 168.538429 -56.032957) (xy 168.490823 -56.062011)
			(xy 168.439494 -56.083823) (xy 168.385537 -56.097929) (xy 168.3301 -56.104029) (xy 168.274366 -56.101992)
			(xy 168.219523 -56.091862) (xy 168.166739 -56.073855) (xy 168.117139 -56.048354) (xy 168.071781 -56.015903)
			(xy 168.031632 -55.977194) (xy 167.997546 -55.933051) (xy 167.97025 -55.884416) (xy 167.950327 -55.832325)
			(xy 167.938201 -55.777888) (xy 167.93413 -55.722266) (xy 154.698802 -55.722266) (xy 154.775547 -57.002934)
			(xy 163.66363 -57.002934) (xy 163.664128 -56.974842) (xy 163.672352 -56.919264) (xy 163.688641 -56.865494)
			(xy 163.712642 -56.814696) (xy 163.743837 -56.767969) (xy 163.78155 -56.726324) (xy 163.824965 -56.690663)
			(xy 163.848796 -56.675782) (xy 163.857686 -56.670448) (xy 163.869878 -56.65343) (xy 163.890198 -56.560212)
			(xy 163.88588 -56.539638) (xy 163.880038 -56.531002) (xy 163.864041 -56.506936) (xy 163.838697 -56.455006)
			(xy 163.82147 -56.399848) (xy 163.812754 -56.342724) (xy 163.81222 -56.313832) (xy 163.812685 -56.286579)
			(xy 163.820439 -56.232626) (xy 163.835792 -56.180327) (xy 163.858433 -56.130745) (xy 163.8879 -56.08489)
			(xy 163.923594 -56.043697) (xy 163.964787 -56.008002) (xy 164.010641 -55.978535) (xy 164.060223 -55.955893)
			(xy 164.112522 -55.940539) (xy 164.166475 -55.932785) (xy 164.193728 -55.932324) (xy 164.221099 -55.932768)
			(xy 164.275279 -55.94059) (xy 164.327783 -55.956084) (xy 164.377529 -55.978931) (xy 164.423495 -56.00866)
			(xy 164.444426 -56.026304) (xy 164.44468 -56.026558) (xy 164.451763 -56.032149) (xy 164.468683 -56.038392)
			(xy 164.4777 -56.03875) (xy 164.544756 -56.03875) (xy 164.553772 -56.038383) (xy 164.57069 -56.032144)
			(xy 164.577776 -56.026558) (xy 164.577776 -56.026304) (xy 164.57803 -56.026304) (xy 164.598963 -56.008663)
			(xy 164.644931 -55.978939) (xy 164.694677 -55.956093) (xy 164.747179 -55.940597) (xy 164.801357 -55.932768)
			(xy 164.856099 -55.932768) (xy 164.910277 -55.940597) (xy 164.962779 -55.956093) (xy 165.012525 -55.978939)
			(xy 165.058493 -56.008663) (xy 165.079426 -56.026304) (xy 165.07968 -56.026558) (xy 165.086763 -56.032149)
			(xy 165.103683 -56.038392) (xy 165.1127 -56.03875) (xy 165.179756 -56.03875) (xy 165.188772 -56.038383)
			(xy 165.20569 -56.032144) (xy 165.212776 -56.026558) (xy 165.212776 -56.026304) (xy 165.21303 -56.026304)
			(xy 165.233978 -56.008685) (xy 165.279946 -55.97897) (xy 165.32969 -55.95613) (xy 165.382187 -55.940634)
			(xy 165.43636 -55.932801) (xy 165.463728 -55.932324) (xy 165.49098 -55.932748) (xy 165.544929 -55.940508)
			(xy 165.597225 -55.955867) (xy 165.646803 -55.978512) (xy 165.692654 -56.007981) (xy 165.733844 -56.043676)
			(xy 165.769536 -56.084869) (xy 165.799002 -56.130722) (xy 165.821643 -56.180301) (xy 165.836998 -56.232598)
			(xy 165.844754 -56.286548) (xy 165.844754 -56.297068) (xy 166.18661 -56.297068) (xy 166.190681 -56.241446)
			(xy 166.202807 -56.187009) (xy 166.22273 -56.134918) (xy 166.250026 -56.086283) (xy 166.284112 -56.04214)
			(xy 166.324261 -56.003431) (xy 166.369619 -55.97098) (xy 166.419219 -55.945479) (xy 166.472003 -55.927472)
			(xy 166.526846 -55.917342) (xy 166.58258 -55.915305) (xy 166.638017 -55.921405) (xy 166.691974 -55.935511)
			(xy 166.743303 -55.957323) (xy 166.790909 -55.986377) (xy 166.833777 -56.022052) (xy 166.870994 -56.063589)
			(xy 166.901767 -56.110102) (xy 166.925439 -56.160599) (xy 166.941507 -56.214006) (xy 166.949627 -56.269182)
			(xy 166.950136 -56.297068) (xy 166.949627 -56.324954) (xy 166.941507 -56.38013) (xy 166.925439 -56.433537)
			(xy 166.901767 -56.484034) (xy 166.870994 -56.530547) (xy 166.833777 -56.572084) (xy 166.790909 -56.607759)
			(xy 166.743303 -56.636813) (xy 166.691974 -56.658625) (xy 166.638017 -56.672731) (xy 166.58258 -56.678831)
			(xy 166.526846 -56.676794) (xy 166.472003 -56.666664) (xy 166.419219 -56.648657) (xy 166.369619 -56.623156)
			(xy 166.324261 -56.590705) (xy 166.284112 -56.551996) (xy 166.250026 -56.507853) (xy 166.22273 -56.459218)
			(xy 166.202807 -56.407127) (xy 166.190681 -56.35269) (xy 166.18661 -56.297068) (xy 165.844754 -56.297068)
			(xy 165.844754 -56.341052) (xy 165.836998 -56.395002) (xy 165.821643 -56.447299) (xy 165.799002 -56.496878)
			(xy 165.769536 -56.542731) (xy 165.733844 -56.583924) (xy 165.692654 -56.619619) (xy 165.646803 -56.649088)
			(xy 165.597225 -56.671733) (xy 165.544929 -56.687092) (xy 165.49098 -56.694852) (xy 165.463728 -56.69534)
			(xy 165.436358 -56.694872) (xy 165.382178 -56.687057) (xy 165.329674 -56.671569) (xy 165.279927 -56.648727)
			(xy 165.233961 -56.619002) (xy 165.21303 -56.60136) (xy 165.212776 -56.601106) (xy 165.2057 -56.595504)
			(xy 165.188775 -56.589266) (xy 165.179756 -56.588914) (xy 165.1127 -56.588914) (xy 165.103683 -56.589268)
			(xy 165.086766 -56.595517) (xy 165.07968 -56.601106) (xy 165.07968 -56.60136) (xy 165.079426 -56.60136)
			(xy 165.058493 -56.619001) (xy 165.012525 -56.648725) (xy 164.962779 -56.671571) (xy 164.910277 -56.687067)
			(xy 164.856099 -56.694896) (xy 164.801357 -56.694896) (xy 164.747179 -56.687067) (xy 164.694677 -56.671571)
			(xy 164.644931 -56.648725) (xy 164.598963 -56.619001) (xy 164.57803 -56.60136) (xy 164.577776 -56.601106)
			(xy 164.5707 -56.595504) (xy 164.553775 -56.589266) (xy 164.544756 -56.588914) (xy 164.4777 -56.588914)
			(xy 164.468683 -56.589268) (xy 164.451766 -56.595517) (xy 164.44468 -56.601106) (xy 164.444172 -56.60136)
			(xy 164.431437 -56.612303) (xy 164.404346 -56.632145) (xy 164.39007 -56.640984) (xy 164.38118 -56.646318)
			(xy 164.368988 -56.663336) (xy 164.348668 -56.756554) (xy 164.352986 -56.777128) (xy 164.358828 -56.785764)
			(xy 164.374818 -56.809834) (xy 164.400162 -56.861764) (xy 164.417391 -56.91692) (xy 164.426109 -56.974042)
			(xy 164.426646 -57.002934) (xy 164.42616 -57.030185) (xy 164.418404 -57.084133) (xy 164.403049 -57.136428)
			(xy 164.380407 -57.186005) (xy 164.350941 -57.231855) (xy 164.31525 -57.273046) (xy 164.274059 -57.308737)
			(xy 164.228209 -57.338203) (xy 164.178632 -57.360845) (xy 164.126337 -57.3762) (xy 164.072389 -57.383956)
			(xy 164.017887 -57.383956) (xy 163.963939 -57.3762) (xy 163.911644 -57.360845) (xy 163.862067 -57.338203)
			(xy 163.816217 -57.308737) (xy 163.775026 -57.273046) (xy 163.739335 -57.231855) (xy 163.709869 -57.186005)
			(xy 163.687227 -57.136428) (xy 163.671872 -57.084133) (xy 163.664116 -57.030185) (xy 163.66363 -57.002934)
			(xy 154.775547 -57.002934) (xy 154.804452 -57.48528) (xy 172.706028 -57.48528) (xy 172.710099 -57.429658)
			(xy 172.722225 -57.375221) (xy 172.742148 -57.32313) (xy 172.769444 -57.274495) (xy 172.80353 -57.230352)
			(xy 172.843679 -57.191643) (xy 172.889037 -57.159192) (xy 172.938637 -57.133691) (xy 172.991421 -57.115684)
			(xy 173.046264 -57.105554) (xy 173.101998 -57.103517) (xy 173.157435 -57.109617) (xy 173.211392 -57.123723)
			(xy 173.262721 -57.145535) (xy 173.310327 -57.174589) (xy 173.353195 -57.210264) (xy 173.390412 -57.251801)
			(xy 173.421185 -57.298314) (xy 173.444857 -57.348811) (xy 173.460925 -57.402218) (xy 173.469045 -57.457394)
			(xy 173.469554 -57.48528) (xy 173.469045 -57.513166) (xy 173.460925 -57.568342) (xy 173.444857 -57.621749)
			(xy 173.421185 -57.672246) (xy 173.390412 -57.718759) (xy 173.353195 -57.760296) (xy 173.310327 -57.795971)
			(xy 173.262721 -57.825025) (xy 173.211392 -57.846837) (xy 173.157435 -57.860943) (xy 173.101998 -57.867043)
			(xy 173.046264 -57.865006) (xy 172.991421 -57.854876) (xy 172.938637 -57.836869) (xy 172.889037 -57.811368)
			(xy 172.843679 -57.778917) (xy 172.80353 -57.740208) (xy 172.769444 -57.696065) (xy 172.742148 -57.64743)
			(xy 172.722225 -57.595339) (xy 172.710099 -57.540902) (xy 172.706028 -57.48528) (xy 154.804452 -57.48528)
			(xy 154.876006 -58.679334) (xy 164.09543 -58.679334) (xy 164.095844 -58.653018) (xy 164.103088 -58.600887)
			(xy 164.117417 -58.550243) (xy 164.13856 -58.502044) (xy 164.166116 -58.457202) (xy 164.199564 -58.416565)
			(xy 164.21862 -58.39841) (xy 164.226022 -58.390889) (xy 164.234546 -58.371608) (xy 164.23513 -58.361072)
			(xy 164.23513 -58.286396) (xy 164.234608 -58.275846) (xy 164.226067 -58.256551) (xy 164.21862 -58.249058)
			(xy 164.199555 -58.230912) (xy 164.166098 -58.190281) (xy 164.13854 -58.145439) (xy 164.117403 -58.097236)
			(xy 164.103088 -58.046586) (xy 164.095866 -57.994451) (xy 164.09543 -57.968134) (xy 164.095916 -57.940883)
			(xy 164.103672 -57.886935) (xy 164.119027 -57.83464) (xy 164.141669 -57.785063) (xy 164.171135 -57.739213)
			(xy 164.206826 -57.698022) (xy 164.248017 -57.662331) (xy 164.293867 -57.632865) (xy 164.343444 -57.610223)
			(xy 164.395739 -57.594868) (xy 164.449687 -57.587112) (xy 164.504189 -57.587112) (xy 164.558137 -57.594868)
			(xy 164.610432 -57.610223) (xy 164.660009 -57.632865) (xy 164.705859 -57.662331) (xy 164.74705 -57.698022)
			(xy 164.782741 -57.739213) (xy 164.812207 -57.785063) (xy 164.834849 -57.83464) (xy 164.850204 -57.886935)
			(xy 164.85796 -57.940883) (xy 164.858446 -57.968134) (xy 164.858018 -57.99445) (xy 164.850778 -58.04658)
			(xy 164.84351 -58.072274) (xy 168.093642 -58.072274) (xy 168.097713 -58.016652) (xy 168.109839 -57.962215)
			(xy 168.129762 -57.910124) (xy 168.157058 -57.861489) (xy 168.191144 -57.817346) (xy 168.231293 -57.778637)
			(xy 168.276651 -57.746186) (xy 168.326251 -57.720685) (xy 168.379035 -57.702678) (xy 168.433878 -57.692548)
			(xy 168.489612 -57.690511) (xy 168.545049 -57.696611) (xy 168.599006 -57.710717) (xy 168.650335 -57.732529)
			(xy 168.697941 -57.761583) (xy 168.740809 -57.797258) (xy 168.778026 -57.838795) (xy 168.808799 -57.885308)
			(xy 168.832471 -57.935805) (xy 168.848539 -57.989212) (xy 168.856659 -58.044388) (xy 168.857168 -58.072274)
			(xy 168.857098 -58.076084) (xy 173.458122 -58.076084) (xy 173.462193 -58.020462) (xy 173.474319 -57.966025)
			(xy 173.494242 -57.913934) (xy 173.521538 -57.865299) (xy 173.555624 -57.821156) (xy 173.595773 -57.782447)
			(xy 173.641131 -57.749996) (xy 173.690731 -57.724495) (xy 173.743515 -57.706488) (xy 173.798358 -57.696358)
			(xy 173.854092 -57.694321) (xy 173.909529 -57.700421) (xy 173.963486 -57.714527) (xy 174.014815 -57.736339)
			(xy 174.062421 -57.765393) (xy 174.105289 -57.801068) (xy 174.142506 -57.842605) (xy 174.158842 -57.867296)
			(xy 175.743106 -57.867296) (xy 175.747177 -57.811674) (xy 175.759303 -57.757237) (xy 175.779226 -57.705146)
			(xy 175.806522 -57.656511) (xy 175.840608 -57.612368) (xy 175.880757 -57.573659) (xy 175.926115 -57.541208)
			(xy 175.975715 -57.515707) (xy 176.028499 -57.4977) (xy 176.083342 -57.48757) (xy 176.139076 -57.485533)
			(xy 176.194513 -57.491633) (xy 176.24847 -57.505739) (xy 176.299799 -57.527551) (xy 176.347405 -57.556605)
			(xy 176.390273 -57.59228) (xy 176.42749 -57.633817) (xy 176.458263 -57.68033) (xy 176.481935 -57.730827)
			(xy 176.498003 -57.784234) (xy 176.506123 -57.83941) (xy 176.506632 -57.867296) (xy 176.506123 -57.895182)
			(xy 176.498003 -57.950358) (xy 176.481935 -58.003765) (xy 176.458263 -58.054262) (xy 176.42749 -58.100775)
			(xy 176.390273 -58.142312) (xy 176.347405 -58.177987) (xy 176.299799 -58.207041) (xy 176.24847 -58.228853)
			(xy 176.194513 -58.242959) (xy 176.139076 -58.249059) (xy 176.083342 -58.247022) (xy 176.028499 -58.236892)
			(xy 175.975715 -58.218885) (xy 175.926115 -58.193384) (xy 175.880757 -58.160933) (xy 175.840608 -58.122224)
			(xy 175.806522 -58.078081) (xy 175.779226 -58.029446) (xy 175.759303 -57.977355) (xy 175.747177 -57.922918)
			(xy 175.743106 -57.867296) (xy 174.158842 -57.867296) (xy 174.173279 -57.889118) (xy 174.196951 -57.939615)
			(xy 174.213019 -57.993022) (xy 174.221139 -58.048198) (xy 174.221648 -58.076084) (xy 174.221139 -58.10397)
			(xy 174.213019 -58.159146) (xy 174.196951 -58.212553) (xy 174.173279 -58.26305) (xy 174.142506 -58.309563)
			(xy 174.105289 -58.3511) (xy 174.062421 -58.386775) (xy 174.014815 -58.415829) (xy 173.963486 -58.437641)
			(xy 173.909529 -58.451747) (xy 173.854092 -58.457847) (xy 173.798358 -58.45581) (xy 173.743515 -58.44568)
			(xy 173.690731 -58.427673) (xy 173.641131 -58.402172) (xy 173.595773 -58.369721) (xy 173.555624 -58.331012)
			(xy 173.521538 -58.286869) (xy 173.494242 -58.238234) (xy 173.474319 -58.186143) (xy 173.462193 -58.131706)
			(xy 173.458122 -58.076084) (xy 168.857098 -58.076084) (xy 168.856659 -58.10016) (xy 168.848539 -58.155336)
			(xy 168.832471 -58.208743) (xy 168.808799 -58.25924) (xy 168.778026 -58.305753) (xy 168.740809 -58.34729)
			(xy 168.697941 -58.382965) (xy 168.650335 -58.412019) (xy 168.599006 -58.433831) (xy 168.545049 -58.447937)
			(xy 168.489612 -58.454037) (xy 168.433878 -58.452) (xy 168.379035 -58.44187) (xy 168.326251 -58.423863)
			(xy 168.276651 -58.398362) (xy 168.231293 -58.365911) (xy 168.191144 -58.327202) (xy 168.157058 -58.283059)
			(xy 168.129762 -58.234424) (xy 168.109839 -58.182333) (xy 168.097713 -58.127896) (xy 168.093642 -58.072274)
			(xy 164.84351 -58.072274) (xy 164.836452 -58.097225) (xy 164.815312 -58.145424) (xy 164.787758 -58.190266)
			(xy 164.754312 -58.230903) (xy 164.735256 -58.249058) (xy 164.727879 -58.256601) (xy 164.719339 -58.275864)
			(xy 164.718746 -58.286396) (xy 164.718746 -58.361072) (xy 164.719263 -58.371623) (xy 164.727805 -58.390919)
			(xy 164.735256 -58.39841) (xy 164.75432 -58.416557) (xy 164.787774 -58.45719) (xy 164.815331 -58.502032)
			(xy 164.836467 -58.550234) (xy 164.839573 -58.561224) (xy 174.662336 -58.561224) (xy 174.666407 -58.505602)
			(xy 174.678533 -58.451165) (xy 174.698456 -58.399074) (xy 174.725752 -58.350439) (xy 174.759838 -58.306296)
			(xy 174.799987 -58.267587) (xy 174.845345 -58.235136) (xy 174.894945 -58.209635) (xy 174.947729 -58.191628)
			(xy 175.002572 -58.181498) (xy 175.058306 -58.179461) (xy 175.113743 -58.185561) (xy 175.1677 -58.199667)
			(xy 175.219029 -58.221479) (xy 175.266635 -58.250533) (xy 175.309503 -58.286208) (xy 175.34672 -58.327745)
			(xy 175.377493 -58.374258) (xy 175.401165 -58.424755) (xy 175.408675 -58.449718) (xy 176.908966 -58.449718)
			(xy 176.913037 -58.394096) (xy 176.925163 -58.339659) (xy 176.945086 -58.287568) (xy 176.972382 -58.238933)
			(xy 177.006468 -58.19479) (xy 177.046617 -58.156081) (xy 177.091975 -58.12363) (xy 177.141575 -58.098129)
			(xy 177.194359 -58.080122) (xy 177.249202 -58.069992) (xy 177.304936 -58.067955) (xy 177.360373 -58.074055)
			(xy 177.41433 -58.088161) (xy 177.465659 -58.109973) (xy 177.513265 -58.139027) (xy 177.556133 -58.174702)
			(xy 177.59335 -58.216239) (xy 177.624123 -58.262752) (xy 177.647795 -58.313249) (xy 177.663863 -58.366656)
			(xy 177.671983 -58.421832) (xy 177.672492 -58.449718) (xy 177.671983 -58.477604) (xy 177.663863 -58.53278)
			(xy 177.647795 -58.586187) (xy 177.624123 -58.636684) (xy 177.59335 -58.683197) (xy 177.556133 -58.724734)
			(xy 177.513265 -58.760409) (xy 177.465659 -58.789463) (xy 177.41433 -58.811275) (xy 177.360373 -58.825381)
			(xy 177.304936 -58.831481) (xy 177.249202 -58.829444) (xy 177.194359 -58.819314) (xy 177.141575 -58.801307)
			(xy 177.091975 -58.775806) (xy 177.046617 -58.743355) (xy 177.006468 -58.704646) (xy 176.972382 -58.660503)
			(xy 176.945086 -58.611868) (xy 176.925163 -58.559777) (xy 176.913037 -58.50534) (xy 176.908966 -58.449718)
			(xy 175.408675 -58.449718) (xy 175.417233 -58.478162) (xy 175.425353 -58.533338) (xy 175.425862 -58.561224)
			(xy 175.425353 -58.58911) (xy 175.417233 -58.644286) (xy 175.401165 -58.697693) (xy 175.377493 -58.74819)
			(xy 175.34672 -58.794703) (xy 175.309503 -58.83624) (xy 175.266635 -58.871915) (xy 175.219029 -58.900969)
			(xy 175.1677 -58.922781) (xy 175.113743 -58.936887) (xy 175.058306 -58.942987) (xy 175.002572 -58.94095)
			(xy 174.947729 -58.93082) (xy 174.894945 -58.912813) (xy 174.845345 -58.887312) (xy 174.799987 -58.854861)
			(xy 174.759838 -58.816152) (xy 174.725752 -58.772009) (xy 174.698456 -58.723374) (xy 174.678533 -58.671283)
			(xy 174.666407 -58.616846) (xy 174.662336 -58.561224) (xy 164.839573 -58.561224) (xy 164.850783 -58.600883)
			(xy 164.858008 -58.653018) (xy 164.858446 -58.679334) (xy 164.85796 -58.706585) (xy 164.850204 -58.760533)
			(xy 164.834849 -58.812828) (xy 164.812207 -58.862405) (xy 164.782741 -58.908255) (xy 164.74705 -58.949446)
			(xy 164.705859 -58.985137) (xy 164.660009 -59.014603) (xy 164.610432 -59.037245) (xy 164.558137 -59.0526)
			(xy 164.504189 -59.060356) (xy 164.449687 -59.060356) (xy 164.395739 -59.0526) (xy 164.343444 -59.037245)
			(xy 164.293867 -59.014603) (xy 164.248017 -58.985137) (xy 164.206826 -58.949446) (xy 164.171135 -58.908255)
			(xy 164.141669 -58.862405) (xy 164.119027 -58.812828) (xy 164.103672 -58.760533) (xy 164.095916 -58.706585)
			(xy 164.09543 -58.679334) (xy 154.876006 -58.679334) (xy 154.905687 -59.174634) (xy 173.1932 -59.174634)
			(xy 173.197271 -59.119012) (xy 173.209397 -59.064575) (xy 173.22932 -59.012484) (xy 173.256616 -58.963849)
			(xy 173.290702 -58.919706) (xy 173.330851 -58.880997) (xy 173.376209 -58.848546) (xy 173.425809 -58.823045)
			(xy 173.478593 -58.805038) (xy 173.533436 -58.794908) (xy 173.58917 -58.792871) (xy 173.644607 -58.798971)
			(xy 173.698564 -58.813077) (xy 173.749893 -58.834889) (xy 173.797499 -58.863943) (xy 173.840367 -58.899618)
			(xy 173.877584 -58.941155) (xy 173.908357 -58.987668) (xy 173.932029 -59.038165) (xy 173.948097 -59.091572)
			(xy 173.956217 -59.146748) (xy 173.956726 -59.174634) (xy 173.956217 -59.20252) (xy 173.948097 -59.257696)
			(xy 173.932029 -59.311103) (xy 173.908357 -59.3616) (xy 173.877584 -59.408113) (xy 173.840367 -59.44965)
			(xy 173.797499 -59.485325) (xy 173.749893 -59.514379) (xy 173.698564 -59.536191) (xy 173.644607 -59.550297)
			(xy 173.58917 -59.556397) (xy 173.533436 -59.55436) (xy 173.478593 -59.54423) (xy 173.425809 -59.526223)
			(xy 173.376209 -59.500722) (xy 173.330851 -59.468271) (xy 173.290702 -59.429562) (xy 173.256616 -59.385419)
			(xy 173.22932 -59.336784) (xy 173.209397 -59.284693) (xy 173.197271 -59.230256) (xy 173.1932 -59.174634)
			(xy 154.905687 -59.174634) (xy 154.956301 -60.01925) (xy 164.235884 -60.01925) (xy 164.235884 -59.96475)
			(xy 164.24364 -59.910803) (xy 164.258994 -59.85851) (xy 164.281635 -59.808934) (xy 164.3111 -59.763085)
			(xy 164.34679 -59.721895) (xy 164.387978 -59.686204) (xy 164.433827 -59.656738) (xy 164.483403 -59.634097)
			(xy 164.535696 -59.618742) (xy 164.589642 -59.610984) (xy 164.616892 -59.610498) (xy 164.644262 -59.610969)
			(xy 164.698441 -59.618786) (xy 164.750944 -59.634274) (xy 164.800691 -59.657114) (xy 164.846658 -59.686837)
			(xy 164.86759 -59.704478) (xy 164.867844 -59.704732) (xy 164.87494 -59.710305) (xy 164.89185 -59.716559)
			(xy 164.900864 -59.716924) (xy 164.96792 -59.716924) (xy 164.976937 -59.716572) (xy 164.993854 -59.71032)
			(xy 165.00094 -59.704732) (xy 165.00094 -59.704478) (xy 165.001194 -59.704478) (xy 165.022127 -59.686837)
			(xy 165.068095 -59.657113) (xy 165.117841 -59.634267) (xy 165.170343 -59.618771) (xy 165.224521 -59.610942)
			(xy 165.279263 -59.610942) (xy 165.333441 -59.618771) (xy 165.385943 -59.634267) (xy 165.435689 -59.657113)
			(xy 165.481657 -59.686837) (xy 165.50259 -59.704478) (xy 165.502844 -59.704732) (xy 165.50994 -59.710305)
			(xy 165.52685 -59.716559) (xy 165.535864 -59.716924) (xy 165.60292 -59.716924) (xy 165.611937 -59.716572)
			(xy 165.628854 -59.71032) (xy 165.63594 -59.704732) (xy 165.63594 -59.704478) (xy 165.636194 -59.704478)
			(xy 165.657115 -59.686825) (xy 165.703091 -59.657116) (xy 165.752841 -59.634283) (xy 165.805344 -59.618795)
			(xy 165.859522 -59.61097) (xy 165.886892 -59.610498) (xy 165.914146 -59.610949) (xy 165.968098 -59.618705)
			(xy 166.020398 -59.634061) (xy 166.06998 -59.656703) (xy 166.115835 -59.686171) (xy 166.157029 -59.721865)
			(xy 166.192724 -59.763059) (xy 166.222193 -59.808913) (xy 166.244837 -59.858495) (xy 166.260193 -59.910794)
			(xy 166.267951 -59.964746) (xy 166.267951 -60.019254) (xy 166.260193 -60.073206) (xy 166.244837 -60.125505)
			(xy 166.222193 -60.175087) (xy 166.192724 -60.220941) (xy 166.157029 -60.262135) (xy 166.115835 -60.297829)
			(xy 166.06998 -60.327297) (xy 166.020398 -60.349939) (xy 165.968098 -60.365295) (xy 165.914146 -60.373051)
			(xy 165.886892 -60.373514) (xy 165.859522 -60.373049) (xy 165.805343 -60.365231) (xy 165.75284 -60.349741)
			(xy 165.703093 -60.326899) (xy 165.657126 -60.297175) (xy 165.636194 -60.279534) (xy 165.63594 -60.27928)
			(xy 165.628848 -60.273702) (xy 165.611935 -60.267451) (xy 165.60292 -60.267088) (xy 165.535864 -60.267088)
			(xy 165.526846 -60.26743) (xy 165.509929 -60.273688) (xy 165.502844 -60.27928) (xy 165.50259 -60.279534)
			(xy 165.481657 -60.297175) (xy 165.435689 -60.326899) (xy 165.385943 -60.349745) (xy 165.333441 -60.365241)
			(xy 165.279263 -60.37307) (xy 165.224521 -60.37307) (xy 165.170343 -60.365241) (xy 165.117841 -60.349745)
			(xy 165.068095 -60.326899) (xy 165.022127 -60.297175) (xy 165.001194 -60.279534) (xy 165.00094 -60.27928)
			(xy 164.993848 -60.273702) (xy 164.976935 -60.267451) (xy 164.96792 -60.267088) (xy 164.900864 -60.267088)
			(xy 164.891846 -60.26743) (xy 164.874929 -60.273688) (xy 164.867844 -60.27928) (xy 164.867844 -60.279534)
			(xy 164.86759 -60.279534) (xy 164.846677 -60.297197) (xy 164.800698 -60.326904) (xy 164.750946 -60.349735)
			(xy 164.698441 -60.36522) (xy 164.644262 -60.373043) (xy 164.616892 -60.373514) (xy 164.589642 -60.373016)
			(xy 164.535696 -60.365258) (xy 164.483403 -60.349903) (xy 164.433827 -60.327262) (xy 164.387978 -60.297796)
			(xy 164.34679 -60.262105) (xy 164.3111 -60.220915) (xy 164.281635 -60.175066) (xy 164.258994 -60.12549)
			(xy 164.24364 -60.073197) (xy 164.235884 -60.01925) (xy 154.956301 -60.01925) (xy 154.993102 -60.633356)
			(xy 175.89703 -60.633356) (xy 175.901101 -60.577734) (xy 175.913227 -60.523297) (xy 175.93315 -60.471206)
			(xy 175.960446 -60.422571) (xy 175.994532 -60.378428) (xy 176.034681 -60.339719) (xy 176.080039 -60.307268)
			(xy 176.129639 -60.281767) (xy 176.182423 -60.26376) (xy 176.237266 -60.25363) (xy 176.293 -60.251593)
			(xy 176.348437 -60.257693) (xy 176.402394 -60.271799) (xy 176.453723 -60.293611) (xy 176.501329 -60.322665)
			(xy 176.544197 -60.35834) (xy 176.581414 -60.399877) (xy 176.612187 -60.44639) (xy 176.635859 -60.496887)
			(xy 176.651927 -60.550294) (xy 176.660047 -60.60547) (xy 176.660556 -60.633356) (xy 176.660047 -60.661242)
			(xy 176.651927 -60.716418) (xy 176.635859 -60.769825) (xy 176.612187 -60.820322) (xy 176.581414 -60.866835)
			(xy 176.544197 -60.908372) (xy 176.501329 -60.944047) (xy 176.453723 -60.973101) (xy 176.402394 -60.994913)
			(xy 176.348437 -61.009019) (xy 176.293 -61.015119) (xy 176.237266 -61.013082) (xy 176.182423 -61.002952)
			(xy 176.129639 -60.984945) (xy 176.080039 -60.959444) (xy 176.034681 -60.926993) (xy 175.994532 -60.888284)
			(xy 175.960446 -60.844141) (xy 175.93315 -60.795506) (xy 175.913227 -60.743415) (xy 175.901101 -60.688978)
			(xy 175.89703 -60.633356) (xy 154.993102 -60.633356) (xy 155.030424 -61.256164) (xy 155.03144 -61.291216)
			(xy 155.03144 -61.291724) (xy 155.029916 -61.336936) (xy 155.018249 -61.487812) (xy 174.404526 -61.487812)
			(xy 174.408597 -61.43219) (xy 174.420723 -61.377753) (xy 174.440646 -61.325662) (xy 174.467942 -61.277027)
			(xy 174.502028 -61.232884) (xy 174.542177 -61.194175) (xy 174.587535 -61.161724) (xy 174.637135 -61.136223)
			(xy 174.689919 -61.118216) (xy 174.744762 -61.108086) (xy 174.800496 -61.106049) (xy 174.855933 -61.112149)
			(xy 174.90989 -61.126255) (xy 174.961219 -61.148067) (xy 175.008825 -61.177121) (xy 175.051693 -61.212796)
			(xy 175.08891 -61.254333) (xy 175.119683 -61.300846) (xy 175.143355 -61.351343) (xy 175.159423 -61.40475)
			(xy 175.167543 -61.459926) (xy 175.168052 -61.487812) (xy 175.167543 -61.515698) (xy 175.159423 -61.570874)
			(xy 175.143355 -61.624281) (xy 175.119683 -61.674778) (xy 175.08891 -61.721291) (xy 175.051693 -61.762828)
			(xy 175.008825 -61.798503) (xy 174.961219 -61.827557) (xy 174.90989 -61.849369) (xy 174.855933 -61.863475)
			(xy 174.800496 -61.869575) (xy 174.744762 -61.867538) (xy 174.689919 -61.857408) (xy 174.637135 -61.839401)
			(xy 174.587535 -61.8139) (xy 174.542177 -61.781449) (xy 174.502028 -61.74274) (xy 174.467942 -61.698597)
			(xy 174.440646 -61.649962) (xy 174.420723 -61.597871) (xy 174.408597 -61.543434) (xy 174.404526 -61.487812)
			(xy 155.018249 -61.487812) (xy 154.969285 -62.121034) (xy 172.3423 -62.121034) (xy 172.346371 -62.065412)
			(xy 172.358497 -62.010975) (xy 172.37842 -61.958884) (xy 172.405716 -61.910249) (xy 172.439802 -61.866106)
			(xy 172.479951 -61.827397) (xy 172.525309 -61.794946) (xy 172.574909 -61.769445) (xy 172.627693 -61.751438)
			(xy 172.682536 -61.741308) (xy 172.73827 -61.739271) (xy 172.793707 -61.745371) (xy 172.847664 -61.759477)
			(xy 172.898993 -61.781289) (xy 172.946599 -61.810343) (xy 172.989467 -61.846018) (xy 173.026684 -61.887555)
			(xy 173.057457 -61.934068) (xy 173.081129 -61.984565) (xy 173.097197 -62.037972) (xy 173.105317 -62.093148)
			(xy 173.105826 -62.121034) (xy 173.105317 -62.14892) (xy 173.097197 -62.204096) (xy 173.081129 -62.257503)
			(xy 173.057457 -62.308) (xy 173.026684 -62.354513) (xy 172.989467 -62.39605) (xy 172.946599 -62.431725)
			(xy 172.898993 -62.460779) (xy 172.847664 -62.482591) (xy 172.793707 -62.496697) (xy 172.73827 -62.502797)
			(xy 172.682536 -62.50076) (xy 172.627693 -62.49063) (xy 172.574909 -62.472623) (xy 172.525309 -62.447122)
			(xy 172.479951 -62.414671) (xy 172.439802 -62.375962) (xy 172.405716 -62.331819) (xy 172.37842 -62.283184)
			(xy 172.358497 -62.231093) (xy 172.346371 -62.176656) (xy 172.3423 -62.121034) (xy 154.969285 -62.121034)
			(xy 154.884805 -63.213552) (xy 164.220865 -63.213552) (xy 164.220865 -63.159048) (xy 164.228622 -63.105098)
			(xy 164.243978 -63.052801) (xy 164.266621 -63.003221) (xy 164.296088 -62.957369) (xy 164.331782 -62.916177)
			(xy 164.372974 -62.880485) (xy 164.418827 -62.851018) (xy 164.468406 -62.828376) (xy 164.520703 -62.813021)
			(xy 164.574654 -62.805265) (xy 164.601906 -62.804802) (xy 164.629276 -62.805264) (xy 164.683456 -62.813083)
			(xy 164.735959 -62.828573) (xy 164.785706 -62.851415) (xy 164.831672 -62.881141) (xy 164.852604 -62.898782)
			(xy 164.852858 -62.899036) (xy 164.859949 -62.904615) (xy 164.876863 -62.910865) (xy 164.885878 -62.911228)
			(xy 164.952934 -62.911228) (xy 164.961952 -62.910881) (xy 164.978868 -62.904626) (xy 164.985954 -62.899036)
			(xy 164.985954 -62.898782) (xy 164.986208 -62.898782) (xy 165.007141 -62.881141) (xy 165.053109 -62.851417)
			(xy 165.102855 -62.828571) (xy 165.155357 -62.813075) (xy 165.209535 -62.805246) (xy 165.264277 -62.805246)
			(xy 165.318455 -62.813075) (xy 165.370957 -62.828571) (xy 165.420703 -62.851417) (xy 165.466671 -62.881141)
			(xy 165.487604 -62.898782) (xy 165.487858 -62.899036) (xy 165.494949 -62.904615) (xy 165.511863 -62.910865)
			(xy 165.520878 -62.911228) (xy 165.587934 -62.911228) (xy 165.596952 -62.910881) (xy 165.613868 -62.904626)
			(xy 165.620954 -62.899036) (xy 165.620954 -62.898782) (xy 165.621208 -62.898782) (xy 165.642124 -62.881123)
			(xy 165.688101 -62.851415) (xy 165.737853 -62.828583) (xy 165.790357 -62.813096) (xy 165.844536 -62.805273)
			(xy 165.871906 -62.804802) (xy 165.899158 -62.805268) (xy 165.953106 -62.813026) (xy 166.005402 -62.828382)
			(xy 166.054979 -62.851024) (xy 166.10083 -62.880491) (xy 166.142021 -62.916183) (xy 166.177713 -62.957375)
			(xy 166.207179 -63.003226) (xy 166.22982 -63.052804) (xy 166.239636 -63.086234) (xy 169.515026 -63.086234)
			(xy 169.519097 -63.030612) (xy 169.531223 -62.976175) (xy 169.551146 -62.924084) (xy 169.578442 -62.875449)
			(xy 169.612528 -62.831306) (xy 169.652677 -62.792597) (xy 169.698035 -62.760146) (xy 169.747635 -62.734645)
			(xy 169.800419 -62.716638) (xy 169.855262 -62.706508) (xy 169.910996 -62.704471) (xy 169.966433 -62.710571)
			(xy 170.02039 -62.724677) (xy 170.040541 -62.73324) (xy 175.76615 -62.73324) (xy 175.766152 -62.678733)
			(xy 175.773911 -62.624781) (xy 175.78927 -62.572483) (xy 175.811915 -62.522902) (xy 175.841386 -62.477049)
			(xy 175.877082 -62.435857) (xy 175.918278 -62.400165) (xy 175.964133 -62.370698) (xy 176.013716 -62.348058)
			(xy 176.066016 -62.332704) (xy 176.119968 -62.32495) (xy 176.147222 -62.324488) (xy 176.170777 -62.324864)
			(xy 176.217521 -62.330724) (xy 176.24044 -62.336172) (xy 176.254197 -62.339204) (xy 176.282347 -62.338349)
			(xy 176.309194 -62.329844) (xy 176.332701 -62.314334) (xy 176.351082 -62.292997) (xy 176.362941 -62.267453)
			(xy 176.367378 -62.239642) (xy 176.364056 -62.211676) (xy 176.359058 -62.198504) (xy 176.349747 -62.175114)
			(xy 176.336622 -62.126514) (xy 176.329999 -62.076609) (xy 176.329594 -62.051438) (xy 176.330014 -62.024182)
			(xy 176.337767 -61.970224) (xy 176.35312 -61.917918) (xy 176.375761 -61.86833) (xy 176.405228 -61.822469)
			(xy 176.440923 -61.781268) (xy 176.482117 -61.745567) (xy 176.527974 -61.716091) (xy 176.577558 -61.693442)
			(xy 176.629861 -61.678081) (xy 176.683818 -61.670319) (xy 176.73833 -61.670315) (xy 176.792288 -61.67807)
			(xy 176.844593 -61.693424) (xy 176.894181 -61.716066) (xy 176.940041 -61.745535) (xy 176.981241 -61.781231)
			(xy 177.016941 -61.822427) (xy 177.046414 -61.868284) (xy 177.069062 -61.917869) (xy 177.084422 -61.970173)
			(xy 177.092182 -62.02413) (xy 177.092184 -62.078642) (xy 177.084428 -62.1326) (xy 177.069072 -62.184904)
			(xy 177.046428 -62.234491) (xy 177.016957 -62.280351) (xy 176.98126 -62.321549) (xy 176.940063 -62.357248)
			(xy 176.894205 -62.38672) (xy 176.844619 -62.409366) (xy 176.792316 -62.424725) (xy 176.738358 -62.432483)
			(xy 176.711102 -62.432946) (xy 176.687548 -62.432565) (xy 176.640803 -62.426708) (xy 176.617884 -62.421262)
			(xy 176.604129 -62.418208) (xy 176.575973 -62.419057) (xy 176.549118 -62.427561) (xy 176.525606 -62.443073)
			(xy 176.507222 -62.464416) (xy 176.495363 -62.489967) (xy 176.490931 -62.517785) (xy 176.494263 -62.545756)
			(xy 176.499266 -62.55893) (xy 176.508588 -62.582315) (xy 176.521709 -62.630918) (xy 176.528327 -62.680824)
			(xy 176.52873 -62.705996) (xy 176.528249 -62.73325) (xy 176.520492 -62.787202) (xy 176.505136 -62.839501)
			(xy 176.482493 -62.889083) (xy 176.453025 -62.934937) (xy 176.41733 -62.976131) (xy 176.376136 -63.011825)
			(xy 176.330282 -63.041294) (xy 176.2807 -63.063936) (xy 176.228401 -63.079292) (xy 176.174449 -63.087049)
			(xy 176.119942 -63.087048) (xy 176.06599 -63.07929) (xy 176.013691 -63.063933) (xy 175.96411 -63.041289)
			(xy 175.918256 -63.011819) (xy 175.877063 -62.976124) (xy 175.84137 -62.934929) (xy 175.811902 -62.889074)
			(xy 175.789261 -62.839492) (xy 175.773906 -62.787193) (xy 175.76615 -62.73324) (xy 170.040541 -62.73324)
			(xy 170.071719 -62.746489) (xy 170.119325 -62.775543) (xy 170.162193 -62.811218) (xy 170.19941 -62.852755)
			(xy 170.230183 -62.899268) (xy 170.253855 -62.949765) (xy 170.269923 -63.003172) (xy 170.278043 -63.058348)
			(xy 170.278552 -63.086234) (xy 170.278043 -63.11412) (xy 170.269923 -63.169296) (xy 170.253855 -63.222703)
			(xy 170.230183 -63.2732) (xy 170.23003 -63.273432) (xy 171.67682 -63.273432) (xy 171.680891 -63.21781)
			(xy 171.693017 -63.163373) (xy 171.71294 -63.111282) (xy 171.740236 -63.062647) (xy 171.774322 -63.018504)
			(xy 171.814471 -62.979795) (xy 171.859829 -62.947344) (xy 171.909429 -62.921843) (xy 171.962213 -62.903836)
			(xy 172.017056 -62.893706) (xy 172.07279 -62.891669) (xy 172.128227 -62.897769) (xy 172.182184 -62.911875)
			(xy 172.233513 -62.933687) (xy 172.281119 -62.962741) (xy 172.323987 -62.998416) (xy 172.361204 -63.039953)
			(xy 172.391977 -63.086466) (xy 172.415649 -63.136963) (xy 172.431717 -63.19037) (xy 172.439837 -63.245546)
			(xy 172.440346 -63.273432) (xy 172.439837 -63.301318) (xy 172.431717 -63.356494) (xy 172.415649 -63.409901)
			(xy 172.391977 -63.460398) (xy 172.361204 -63.506911) (xy 172.323987 -63.548448) (xy 172.281119 -63.584123)
			(xy 172.233513 -63.613177) (xy 172.182184 -63.634989) (xy 172.128227 -63.649095) (xy 172.07279 -63.655195)
			(xy 172.017056 -63.653158) (xy 171.962213 -63.643028) (xy 171.909429 -63.625021) (xy 171.859829 -63.59952)
			(xy 171.814471 -63.567069) (xy 171.774322 -63.52836) (xy 171.740236 -63.484217) (xy 171.71294 -63.435582)
			(xy 171.693017 -63.383491) (xy 171.680891 -63.329054) (xy 171.67682 -63.273432) (xy 170.23003 -63.273432)
			(xy 170.19941 -63.319713) (xy 170.162193 -63.36125) (xy 170.119325 -63.396925) (xy 170.071719 -63.425979)
			(xy 170.02039 -63.447791) (xy 169.966433 -63.461897) (xy 169.910996 -63.467997) (xy 169.855262 -63.46596)
			(xy 169.800419 -63.45583) (xy 169.747635 -63.437823) (xy 169.698035 -63.412322) (xy 169.652677 -63.379871)
			(xy 169.612528 -63.341162) (xy 169.578442 -63.297019) (xy 169.551146 -63.248384) (xy 169.531223 -63.196293)
			(xy 169.519097 -63.141856) (xy 169.515026 -63.086234) (xy 166.239636 -63.086234) (xy 166.245176 -63.1051)
			(xy 166.252932 -63.159048) (xy 166.252932 -63.213552) (xy 166.245176 -63.2675) (xy 166.22982 -63.319796)
			(xy 166.207179 -63.369374) (xy 166.177713 -63.415225) (xy 166.142021 -63.456417) (xy 166.10083 -63.492109)
			(xy 166.054979 -63.521576) (xy 166.005402 -63.544218) (xy 165.953106 -63.559574) (xy 165.899158 -63.567332)
			(xy 165.871906 -63.567818) (xy 165.844535 -63.567368) (xy 165.790354 -63.55955) (xy 165.73785 -63.544058)
			(xy 165.688104 -63.521212) (xy 165.642138 -63.491482) (xy 165.621208 -63.473838) (xy 165.620954 -63.473584)
			(xy 165.613857 -63.468012) (xy 165.596948 -63.461757) (xy 165.587934 -63.461392) (xy 165.520878 -63.461392)
			(xy 165.51186 -63.46174) (xy 165.494944 -63.467994) (xy 165.487858 -63.473584) (xy 165.487604 -63.473838)
			(xy 165.466671 -63.491479) (xy 165.420703 -63.521203) (xy 165.370957 -63.544049) (xy 165.318455 -63.559545)
			(xy 165.264277 -63.567374) (xy 165.209535 -63.567374) (xy 165.155357 -63.559545) (xy 165.102855 -63.544049)
			(xy 165.053109 -63.521203) (xy 165.007141 -63.491479) (xy 164.986208 -63.473838) (xy 164.985954 -63.473584)
			(xy 164.978857 -63.468012) (xy 164.961948 -63.461757) (xy 164.952934 -63.461392) (xy 164.885878 -63.461392)
			(xy 164.87686 -63.46174) (xy 164.859944 -63.467994) (xy 164.852858 -63.473584) (xy 164.852858 -63.473838)
			(xy 164.852604 -63.473838) (xy 164.831686 -63.491495) (xy 164.785709 -63.521203) (xy 164.735958 -63.544035)
			(xy 164.683454 -63.559522) (xy 164.629276 -63.567346) (xy 164.601906 -63.567818) (xy 164.574654 -63.567335)
			(xy 164.520703 -63.559579) (xy 164.468406 -63.544224) (xy 164.418827 -63.521582) (xy 164.372974 -63.492115)
			(xy 164.331782 -63.456423) (xy 164.296088 -63.415231) (xy 164.266621 -63.369379) (xy 164.243978 -63.319799)
			(xy 164.228622 -63.267502) (xy 164.220865 -63.213552) (xy 154.884805 -63.213552) (xy 154.85745 -63.56731)
			(xy 154.854239 -63.602061) (xy 154.840678 -63.670523) (xy 154.819154 -63.736912) (xy 154.789963 -63.800306)
			(xy 154.753514 -63.859823) (xy 154.710311 -63.914635) (xy 154.686 -63.939674) (xy 154.313382 -64.312292)
			(xy 175.005998 -64.312292) (xy 175.010069 -64.25667) (xy 175.022195 -64.202233) (xy 175.042118 -64.150142)
			(xy 175.069414 -64.101507) (xy 175.1035 -64.057364) (xy 175.143649 -64.018655) (xy 175.189007 -63.986204)
			(xy 175.238607 -63.960703) (xy 175.291391 -63.942696) (xy 175.346234 -63.932566) (xy 175.401968 -63.930529)
			(xy 175.457405 -63.936629) (xy 175.511362 -63.950735) (xy 175.562691 -63.972547) (xy 175.610297 -64.001601)
			(xy 175.653165 -64.037276) (xy 175.690382 -64.078813) (xy 175.721155 -64.125326) (xy 175.744827 -64.175823)
			(xy 175.760895 -64.22923) (xy 175.769015 -64.284406) (xy 175.769524 -64.312292) (xy 175.769015 -64.340178)
			(xy 175.760895 -64.395354) (xy 175.744827 -64.448761) (xy 175.721155 -64.499258) (xy 175.690382 -64.545771)
			(xy 175.653165 -64.587308) (xy 175.610297 -64.622983) (xy 175.562691 -64.652037) (xy 175.511362 -64.673849)
			(xy 175.457405 -64.687955) (xy 175.401968 -64.694055) (xy 175.346234 -64.692018) (xy 175.291391 -64.681888)
			(xy 175.238607 -64.663881) (xy 175.189007 -64.63838) (xy 175.143649 -64.605929) (xy 175.1035 -64.56722)
			(xy 175.069414 -64.523077) (xy 175.042118 -64.474442) (xy 175.022195 -64.422351) (xy 175.010069 -64.367914)
			(xy 175.005998 -64.312292) (xy 154.313382 -64.312292) (xy 153.524712 -65.100962) (xy 162.232592 -65.100962)
			(xy 162.236663 -65.04534) (xy 162.248789 -64.990903) (xy 162.268712 -64.938812) (xy 162.296008 -64.890177)
			(xy 162.330094 -64.846034) (xy 162.370243 -64.807325) (xy 162.415601 -64.774874) (xy 162.465201 -64.749373)
			(xy 162.517985 -64.731366) (xy 162.572828 -64.721236) (xy 162.628562 -64.719199) (xy 162.683999 -64.725299)
			(xy 162.737956 -64.739405) (xy 162.789285 -64.761217) (xy 162.836891 -64.790271) (xy 162.879759 -64.825946)
			(xy 162.916976 -64.867483) (xy 162.947749 -64.913996) (xy 162.971421 -64.964493) (xy 162.987489 -65.0179)
			(xy 162.995609 -65.073076) (xy 162.996118 -65.100962) (xy 162.995609 -65.128848) (xy 162.987489 -65.184024)
			(xy 162.971421 -65.237431) (xy 162.947749 -65.287928) (xy 162.916976 -65.334441) (xy 162.879759 -65.375978)
			(xy 162.836891 -65.411653) (xy 162.789285 -65.440707) (xy 162.737956 -65.462519) (xy 162.683999 -65.476625)
			(xy 162.628562 -65.482725) (xy 162.572828 -65.480688) (xy 162.517985 -65.470558) (xy 162.465201 -65.452551)
			(xy 162.415601 -65.42705) (xy 162.370243 -65.394599) (xy 162.330094 -65.35589) (xy 162.296008 -65.311747)
			(xy 162.268712 -65.263112) (xy 162.248789 -65.211021) (xy 162.236663 -65.156584) (xy 162.232592 -65.100962)
			(xy 153.524712 -65.100962) (xy 152.870154 -65.75552) (xy 156.446726 -65.75552) (xy 156.450797 -65.699898)
			(xy 156.462923 -65.645461) (xy 156.482846 -65.59337) (xy 156.510142 -65.544735) (xy 156.544228 -65.500592)
			(xy 156.584377 -65.461883) (xy 156.629735 -65.429432) (xy 156.679335 -65.403931) (xy 156.732119 -65.385924)
			(xy 156.786962 -65.375794) (xy 156.842696 -65.373757) (xy 156.898133 -65.379857) (xy 156.95209 -65.393963)
			(xy 157.003419 -65.415775) (xy 157.051025 -65.444829) (xy 157.093893 -65.480504) (xy 157.13111 -65.522041)
			(xy 157.161883 -65.568554) (xy 157.185555 -65.619051) (xy 157.201623 -65.672458) (xy 157.209743 -65.727634)
			(xy 157.210252 -65.75552) (xy 157.209743 -65.783406) (xy 157.201623 -65.838582) (xy 157.185555 -65.891989)
			(xy 157.161883 -65.942486) (xy 157.13111 -65.988999) (xy 157.093893 -66.030536) (xy 157.051025 -66.066211)
			(xy 157.003419 -66.095265) (xy 156.95209 -66.117077) (xy 156.898133 -66.131183) (xy 156.842696 -66.137283)
			(xy 156.786962 -66.135246) (xy 156.732119 -66.125116) (xy 156.679335 -66.107109) (xy 156.629735 -66.081608)
			(xy 156.584377 -66.049157) (xy 156.544228 -66.010448) (xy 156.510142 -65.966305) (xy 156.482846 -65.91767)
			(xy 156.462923 -65.865579) (xy 156.450797 -65.811142) (xy 156.446726 -65.75552) (xy 152.870154 -65.75552)
			(xy 151.496724 -67.12895) (xy 156.466798 -67.12895) (xy 156.466798 -67.07445) (xy 156.474554 -67.020506)
			(xy 156.489908 -66.968215) (xy 156.512548 -66.918641) (xy 156.542012 -66.872793) (xy 156.577701 -66.831605)
			(xy 156.618888 -66.795915) (xy 156.664735 -66.766451) (xy 156.714309 -66.74381) (xy 156.7666 -66.728455)
			(xy 156.820544 -66.720699) (xy 156.847794 -66.720212) (xy 156.875164 -66.720679) (xy 156.929343 -66.728496)
			(xy 156.981847 -66.743985) (xy 157.031594 -66.766826) (xy 157.07756 -66.796551) (xy 157.098492 -66.814192)
			(xy 157.098746 -66.814446) (xy 157.10584 -66.820022) (xy 157.122751 -66.826274) (xy 157.131766 -66.826638)
			(xy 157.198822 -66.826638) (xy 157.207839 -66.826283) (xy 157.224756 -66.820033) (xy 157.231842 -66.814446)
			(xy 157.231842 -66.814192) (xy 157.232096 -66.814192) (xy 157.253018 -66.79654) (xy 157.298993 -66.76683)
			(xy 157.348744 -66.743997) (xy 157.401247 -66.728509) (xy 157.455424 -66.720684) (xy 157.482794 -66.720212)
			(xy 157.510049 -66.720634) (xy 157.564003 -66.728391) (xy 157.616304 -66.743748) (xy 157.665888 -66.766391)
			(xy 157.711744 -66.79586) (xy 157.75294 -66.831556) (xy 157.788636 -66.872751) (xy 157.818106 -66.918607)
			(xy 157.84075 -66.96819) (xy 157.856108 -67.020491) (xy 157.863865 -67.074445) (xy 157.863865 -67.128955)
			(xy 157.856108 -67.182909) (xy 157.84075 -67.23521) (xy 157.818106 -67.284793) (xy 157.788636 -67.330649)
			(xy 157.75294 -67.371844) (xy 157.711744 -67.40754) (xy 157.665888 -67.437009) (xy 157.616304 -67.459652)
			(xy 157.564003 -67.475009) (xy 157.510049 -67.482766) (xy 157.482794 -67.483228) (xy 157.455423 -67.482783)
			(xy 157.401242 -67.474963) (xy 157.348738 -67.45947) (xy 157.298991 -67.436623) (xy 157.253026 -67.406892)
			(xy 157.232096 -67.389248) (xy 157.231842 -67.388994) (xy 157.224748 -67.383418) (xy 157.207837 -67.377165)
			(xy 157.198822 -67.376802) (xy 157.131766 -67.376802) (xy 157.122747 -67.377142) (xy 157.105831 -67.383402)
			(xy 157.098746 -67.388994) (xy 157.098746 -67.389248) (xy 157.098492 -67.389248) (xy 157.077567 -67.406896)
			(xy 157.031593 -67.436608) (xy 156.981844 -67.459443) (xy 156.929341 -67.474932) (xy 156.875164 -67.482757)
			(xy 156.847794 -67.483228) (xy 156.820544 -67.482701) (xy 156.7666 -67.474945) (xy 156.714309 -67.45959)
			(xy 156.664735 -67.436949) (xy 156.618888 -67.407485) (xy 156.577701 -67.371795) (xy 156.542012 -67.330607)
			(xy 156.512548 -67.284759) (xy 156.489908 -67.235185) (xy 156.474554 -67.182894) (xy 156.466798 -67.12895)
			(xy 151.496724 -67.12895) (xy 151.13762 -67.488054) (xy 160.87928 -67.488054) (xy 160.883351 -67.432432)
			(xy 160.895477 -67.377995) (xy 160.9154 -67.325904) (xy 160.942696 -67.277269) (xy 160.976782 -67.233126)
			(xy 161.016931 -67.194417) (xy 161.062289 -67.161966) (xy 161.111889 -67.136465) (xy 161.164673 -67.118458)
			(xy 161.219516 -67.108328) (xy 161.27525 -67.106291) (xy 161.330687 -67.112391) (xy 161.384644 -67.126497)
			(xy 161.435973 -67.148309) (xy 161.483579 -67.177363) (xy 161.526447 -67.213038) (xy 161.563664 -67.254575)
			(xy 161.594437 -67.301088) (xy 161.618109 -67.351585) (xy 161.634177 -67.404992) (xy 161.642297 -67.460168)
			(xy 161.642806 -67.488054) (xy 161.642297 -67.51594) (xy 161.639112 -67.537584) (xy 162.171378 -67.537584)
			(xy 162.175449 -67.481962) (xy 162.187575 -67.427525) (xy 162.207498 -67.375434) (xy 162.234794 -67.326799)
			(xy 162.26888 -67.282656) (xy 162.309029 -67.243947) (xy 162.354387 -67.211496) (xy 162.403987 -67.185995)
			(xy 162.456771 -67.167988) (xy 162.511614 -67.157858) (xy 162.567348 -67.155821) (xy 162.622785 -67.161921)
			(xy 162.676742 -67.176027) (xy 162.728071 -67.197839) (xy 162.775677 -67.226893) (xy 162.818545 -67.262568)
			(xy 162.855762 -67.304105) (xy 162.886535 -67.350618) (xy 162.910207 -67.401115) (xy 162.926275 -67.454522)
			(xy 162.934395 -67.509698) (xy 162.934904 -67.537584) (xy 162.934395 -67.56547) (xy 162.93035 -67.592956)
			(xy 163.445442 -67.592956) (xy 163.449513 -67.537334) (xy 163.461639 -67.482897) (xy 163.481562 -67.430806)
			(xy 163.508858 -67.382171) (xy 163.542944 -67.338028) (xy 163.583093 -67.299319) (xy 163.628451 -67.266868)
			(xy 163.678051 -67.241367) (xy 163.730835 -67.22336) (xy 163.785678 -67.21323) (xy 163.841412 -67.211193)
			(xy 163.896849 -67.217293) (xy 163.950806 -67.231399) (xy 164.002135 -67.253211) (xy 164.049741 -67.282265)
			(xy 164.092609 -67.31794) (xy 164.129826 -67.359477) (xy 164.160599 -67.40599) (xy 164.184271 -67.456487)
			(xy 164.200339 -67.509894) (xy 164.208456 -67.565048) (xy 166.546816 -67.565048) (xy 166.546816 -67.510552)
			(xy 166.554571 -67.456611) (xy 166.569924 -67.404323) (xy 166.592562 -67.354752) (xy 166.622024 -67.308907)
			(xy 166.65771 -67.267721) (xy 166.698894 -67.232033) (xy 166.744738 -67.20257) (xy 166.794308 -67.17993)
			(xy 166.846596 -67.164575) (xy 166.900536 -67.156817) (xy 166.927784 -67.15633) (xy 166.955154 -67.156798)
			(xy 167.009334 -67.164614) (xy 167.061837 -67.180103) (xy 167.111584 -67.202944) (xy 167.157551 -67.232669)
			(xy 167.178482 -67.25031) (xy 167.178736 -67.250564) (xy 167.185831 -67.256137) (xy 167.202742 -67.26239)
			(xy 167.211756 -67.262756) (xy 167.278812 -67.262756) (xy 167.287831 -67.262414) (xy 167.304748 -67.256157)
			(xy 167.311832 -67.250564) (xy 167.311832 -67.25031) (xy 167.312086 -67.25031) (xy 167.333014 -67.232666)
			(xy 167.378988 -67.202954) (xy 167.428736 -67.180119) (xy 167.481238 -67.164629) (xy 167.535415 -67.156803)
			(xy 167.562784 -67.15633) (xy 167.59004 -67.156716) (xy 167.643998 -67.164472) (xy 167.696303 -67.179828)
			(xy 167.745891 -67.202472) (xy 167.79175 -67.231942) (xy 167.832949 -67.26764) (xy 167.868648 -67.308837)
			(xy 167.898121 -67.354695) (xy 167.920766 -67.404282) (xy 167.936125 -67.456586) (xy 167.943883 -67.510544)
			(xy 167.943883 -67.565056) (xy 167.936125 -67.619014) (xy 167.920766 -67.671318) (xy 167.898121 -67.720905)
			(xy 167.868648 -67.766763) (xy 167.832949 -67.80796) (xy 167.79175 -67.843658) (xy 167.745891 -67.873128)
			(xy 167.696303 -67.895772) (xy 167.643998 -67.911128) (xy 167.59004 -67.918884) (xy 167.562784 -67.919346)
			(xy 167.535413 -67.918902) (xy 167.481232 -67.911081) (xy 167.428728 -67.895588) (xy 167.378982 -67.872741)
			(xy 167.333016 -67.84301) (xy 167.312086 -67.825366) (xy 167.311832 -67.825112) (xy 167.304739 -67.819534)
			(xy 167.287827 -67.813282) (xy 167.278812 -67.81292) (xy 167.211756 -67.81292) (xy 167.202741 -67.8133)
			(xy 167.185824 -67.819531) (xy 167.178736 -67.825112) (xy 167.178736 -67.825366) (xy 167.178482 -67.825366)
			(xy 167.157525 -67.842975) (xy 167.11156 -67.872692) (xy 167.061819 -67.895535) (xy 167.009323 -67.911033)
			(xy 166.955152 -67.918868) (xy 166.927784 -67.919346) (xy 166.900536 -67.918783) (xy 166.846596 -67.911025)
			(xy 166.794308 -67.89567) (xy 166.744738 -67.87303) (xy 166.698894 -67.843567) (xy 166.65771 -67.807879)
			(xy 166.622024 -67.766693) (xy 166.592562 -67.720848) (xy 166.569924 -67.671277) (xy 166.554571 -67.618989)
			(xy 166.546816 -67.565048) (xy 164.208456 -67.565048) (xy 164.208459 -67.56507) (xy 164.208968 -67.592956)
			(xy 164.208459 -67.620842) (xy 164.200339 -67.676018) (xy 164.184271 -67.729425) (xy 164.160599 -67.779922)
			(xy 164.129826 -67.826435) (xy 164.092609 -67.867972) (xy 164.049741 -67.903647) (xy 164.002135 -67.932701)
			(xy 163.950806 -67.954513) (xy 163.896849 -67.968619) (xy 163.841412 -67.974719) (xy 163.785678 -67.972682)
			(xy 163.730835 -67.962552) (xy 163.678051 -67.944545) (xy 163.628451 -67.919044) (xy 163.583093 -67.886593)
			(xy 163.542944 -67.847884) (xy 163.508858 -67.803741) (xy 163.481562 -67.755106) (xy 163.461639 -67.703015)
			(xy 163.449513 -67.648578) (xy 163.445442 -67.592956) (xy 162.93035 -67.592956) (xy 162.926275 -67.620646)
			(xy 162.910207 -67.674053) (xy 162.886535 -67.72455) (xy 162.855762 -67.771063) (xy 162.818545 -67.8126)
			(xy 162.775677 -67.848275) (xy 162.728071 -67.877329) (xy 162.676742 -67.899141) (xy 162.622785 -67.913247)
			(xy 162.567348 -67.919347) (xy 162.511614 -67.91731) (xy 162.456771 -67.90718) (xy 162.403987 -67.889173)
			(xy 162.354387 -67.863672) (xy 162.309029 -67.831221) (xy 162.26888 -67.792512) (xy 162.234794 -67.748369)
			(xy 162.207498 -67.699734) (xy 162.187575 -67.647643) (xy 162.175449 -67.593206) (xy 162.171378 -67.537584)
			(xy 161.639112 -67.537584) (xy 161.634177 -67.571116) (xy 161.618109 -67.624523) (xy 161.594437 -67.67502)
			(xy 161.563664 -67.721533) (xy 161.526447 -67.76307) (xy 161.483579 -67.798745) (xy 161.435973 -67.827799)
			(xy 161.384644 -67.849611) (xy 161.330687 -67.863717) (xy 161.27525 -67.869817) (xy 161.219516 -67.86778)
			(xy 161.164673 -67.85765) (xy 161.111889 -67.839643) (xy 161.062289 -67.814142) (xy 161.016931 -67.781691)
			(xy 160.976782 -67.742982) (xy 160.942696 -67.698839) (xy 160.9154 -67.650204) (xy 160.895477 -67.598113)
			(xy 160.883351 -67.543676) (xy 160.87928 -67.488054) (xy 151.13762 -67.488054) (xy 150.03907 -68.586604)
			(xy 158.725362 -68.586604) (xy 158.725815 -68.559233) (xy 158.733634 -68.505053) (xy 158.749125 -68.452549)
			(xy 158.77197 -68.402802) (xy 158.801699 -68.356837) (xy 158.819342 -68.335906) (xy 158.819596 -68.335652)
			(xy 158.825167 -68.328554) (xy 158.831423 -68.311646) (xy 158.831788 -68.302632) (xy 158.831788 -68.235576)
			(xy 158.831445 -68.226558) (xy 158.825188 -68.209641) (xy 158.819596 -68.202556) (xy 158.819342 -68.202556)
			(xy 158.819342 -68.202302) (xy 158.801697 -68.181375) (xy 158.771985 -68.135401) (xy 158.749149 -68.085653)
			(xy 158.73366 -68.033151) (xy 158.725834 -67.978974) (xy 158.725362 -67.951604) (xy 158.725881 -67.924354)
			(xy 158.733637 -67.870409) (xy 158.74899 -67.818117) (xy 158.771628 -67.768542) (xy 158.801091 -67.722693)
			(xy 158.836779 -67.681503) (xy 158.877966 -67.645812) (xy 158.923812 -67.616345) (xy 158.973385 -67.593702)
			(xy 159.025676 -67.578344) (xy 159.07962 -67.570584) (xy 159.10687 -67.570096) (xy 159.133185 -67.570518)
			(xy 159.185316 -67.577762) (xy 159.235959 -67.59209) (xy 159.284158 -67.613231) (xy 159.329001 -67.640785)
			(xy 159.369639 -67.674231) (xy 159.387794 -67.693286) (xy 159.395318 -67.700685) (xy 159.414596 -67.709211)
			(xy 159.425132 -67.709796) (xy 159.499808 -67.709796) (xy 159.51036 -67.709286) (xy 159.529655 -67.700738)
			(xy 159.537146 -67.693286) (xy 159.555283 -67.674212) (xy 159.595917 -67.640757) (xy 159.640762 -67.613201)
			(xy 159.688966 -67.592066) (xy 159.739616 -67.577752) (xy 159.791753 -67.570532) (xy 159.81807 -67.570096)
			(xy 159.84544 -67.570581) (xy 159.899618 -67.578394) (xy 159.952121 -67.593879) (xy 160.001868 -67.616716)
			(xy 160.047836 -67.646437) (xy 160.068768 -67.664076) (xy 160.069022 -67.66433) (xy 160.076096 -67.669935)
			(xy 160.093022 -67.67617) (xy 160.102042 -67.676522) (xy 160.169098 -67.676522) (xy 160.178114 -67.676159)
			(xy 160.195031 -67.669915) (xy 160.202118 -67.66433) (xy 160.202118 -67.664076) (xy 160.202372 -67.664076)
			(xy 160.223301 -67.646433) (xy 160.269275 -67.616722) (xy 160.319023 -67.593888) (xy 160.371524 -67.578397)
			(xy 160.425701 -67.57057) (xy 160.45307 -67.570096) (xy 160.480322 -67.570583) (xy 160.534273 -67.578336)
			(xy 160.58657 -67.593689) (xy 160.636151 -67.616328) (xy 160.682004 -67.645793) (xy 160.723197 -67.681484)
			(xy 160.758891 -67.722675) (xy 160.78836 -67.768527) (xy 160.811002 -67.818105) (xy 160.826358 -67.870402)
			(xy 160.834115 -67.924352) (xy 160.834578 -67.951604) (xy 160.83412 -67.978975) (xy 160.826301 -68.033154)
			(xy 160.81081 -68.085658) (xy 160.787967 -68.135404) (xy 160.75824 -68.181371) (xy 160.740598 -68.202302)
			(xy 160.740344 -68.202556) (xy 160.734763 -68.209646) (xy 160.728514 -68.22656) (xy 160.728152 -68.235576)
			(xy 160.728152 -68.302632) (xy 160.728482 -68.311652) (xy 160.734747 -68.328569) (xy 160.740344 -68.335652)
			(xy 160.740598 -68.335652) (xy 160.740598 -68.335906) (xy 160.758253 -68.356825) (xy 160.787963 -68.402802)
			(xy 160.810795 -68.452552) (xy 160.826283 -68.505056) (xy 160.834106 -68.559234) (xy 160.834578 -68.586604)
			(xy 160.834148 -68.613858) (xy 160.82639 -68.667812) (xy 160.811032 -68.720112) (xy 160.794399 -68.75653)
			(xy 164.270436 -68.75653) (xy 164.270911 -68.72916) (xy 164.278725 -68.674981) (xy 164.294212 -68.622478)
			(xy 164.317052 -68.572731) (xy 164.346775 -68.526764) (xy 164.364416 -68.505832) (xy 164.36467 -68.505578)
			(xy 164.37028 -68.498508) (xy 164.376511 -68.481578) (xy 164.376862 -68.472558) (xy 164.376862 -68.405502)
			(xy 164.376512 -68.396484) (xy 164.37026 -68.379567) (xy 164.36467 -68.372482) (xy 164.364416 -68.372482)
			(xy 164.364416 -68.372228) (xy 164.346779 -68.351294) (xy 164.317066 -68.305322) (xy 164.29423 -68.255575)
			(xy 164.278738 -68.203075) (xy 164.27091 -68.148899) (xy 164.270436 -68.12153) (xy 164.270883 -68.094276)
			(xy 164.278637 -68.040322) (xy 164.293992 -67.988021) (xy 164.316634 -67.938438) (xy 164.346103 -67.892583)
			(xy 164.381799 -67.851389) (xy 164.422994 -67.815695) (xy 164.468851 -67.786227) (xy 164.518434 -67.763587)
			(xy 164.570736 -67.748234) (xy 164.62469 -67.740482) (xy 164.651944 -67.740022) (xy 164.679313 -67.740516)
			(xy 164.733491 -67.748326) (xy 164.785994 -67.763808) (xy 164.835742 -67.786644) (xy 164.88171 -67.816363)
			(xy 164.902642 -67.834002) (xy 164.902896 -67.834256) (xy 164.909975 -67.839854) (xy 164.926898 -67.846092)
			(xy 164.935916 -67.846448) (xy 165.002972 -67.846448) (xy 165.011989 -67.846089) (xy 165.028906 -67.839844)
			(xy 165.035992 -67.834256) (xy 165.035992 -67.834002) (xy 165.036246 -67.834002) (xy 165.057188 -67.816375)
			(xy 165.103158 -67.786661) (xy 165.152903 -67.763823) (xy 165.205401 -67.748329) (xy 165.259575 -67.740498)
			(xy 165.286944 -67.740022) (xy 165.313259 -67.740453) (xy 165.36539 -67.747694) (xy 165.416033 -67.76202)
			(xy 165.464232 -67.783159) (xy 165.509075 -67.810712) (xy 165.549713 -67.844157) (xy 165.567868 -67.863212)
			(xy 165.575398 -67.870603) (xy 165.594672 -67.879133) (xy 165.605206 -67.879722) (xy 165.679882 -67.879722)
			(xy 165.690431 -67.87919) (xy 165.709726 -67.870656) (xy 165.71722 -67.863212) (xy 165.735375 -67.844156)
			(xy 165.776005 -67.810698) (xy 165.820845 -67.783139) (xy 165.869046 -67.762001) (xy 165.919694 -67.747684)
			(xy 165.971828 -67.74046) (xy 165.998144 -67.740022) (xy 166.025398 -67.740437) (xy 166.07935 -67.7482)
			(xy 166.131647 -67.763562) (xy 166.181227 -67.786211) (xy 166.227078 -67.815685) (xy 166.268269 -67.851383)
			(xy 166.30396 -67.892581) (xy 166.333425 -67.938438) (xy 166.356063 -67.988022) (xy 166.371415 -68.040323)
			(xy 166.379168 -68.094276) (xy 166.379652 -68.12153) (xy 166.379215 -68.148901) (xy 166.371392 -68.203082)
			(xy 166.355897 -68.255586) (xy 166.333048 -68.305333) (xy 166.303317 -68.351298) (xy 166.285672 -68.372228)
			(xy 166.285418 -68.372482) (xy 166.279835 -68.379571) (xy 166.273586 -68.396486) (xy 166.273226 -68.405502)
			(xy 166.273226 -68.472558) (xy 166.273598 -68.481574) (xy 166.279834 -68.498491) (xy 166.285418 -68.505578)
			(xy 166.285672 -68.505578) (xy 166.285672 -68.505832) (xy 166.303288 -68.526782) (xy 166.333005 -68.57275)
			(xy 166.355845 -68.622493) (xy 166.371342 -68.674989) (xy 166.379175 -68.729162) (xy 166.379652 -68.75653)
			(xy 166.37915 -68.78378) (xy 166.371391 -68.837725) (xy 166.356034 -68.890017) (xy 166.333393 -68.939591)
			(xy 166.303927 -68.985439) (xy 166.268238 -69.026628) (xy 166.22705 -69.062319) (xy 166.181203 -69.091786)
			(xy 166.13163 -69.114429) (xy 166.079339 -69.129788) (xy 166.025394 -69.137549) (xy 165.998144 -69.138038)
			(xy 165.971828 -69.137628) (xy 165.919696 -69.130384) (xy 165.869051 -69.116055) (xy 165.820852 -69.094912)
			(xy 165.77601 -69.067355) (xy 165.735374 -69.033905) (xy 165.71722 -69.014848) (xy 165.709686 -69.00746)
			(xy 165.690416 -68.998926) (xy 165.679882 -68.998338) (xy 165.605206 -68.998338) (xy 165.594653 -68.998846)
			(xy 165.575358 -69.007395) (xy 165.567868 -69.014848) (xy 165.54973 -69.033921) (xy 165.509096 -69.067375)
			(xy 165.464251 -69.09493) (xy 165.416047 -69.116065) (xy 165.365397 -69.130379) (xy 165.313261 -69.137601)
			(xy 165.286944 -69.138038) (xy 165.259574 -69.137561) (xy 165.205395 -69.129748) (xy 165.152891 -69.114263)
			(xy 165.103144 -69.091423) (xy 165.057177 -69.061699) (xy 165.036246 -69.044058) (xy 165.035992 -69.043804)
			(xy 165.028912 -69.038208) (xy 165.01199 -69.031967) (xy 165.002972 -69.031612) (xy 164.935916 -69.031612)
			(xy 164.9269 -69.031974) (xy 164.909982 -69.038218) (xy 164.902896 -69.043804) (xy 164.902896 -69.044058)
			(xy 164.902642 -69.044058) (xy 164.8817 -69.061684) (xy 164.83573 -69.0914) (xy 164.785985 -69.114239)
			(xy 164.733487 -69.129733) (xy 164.679313 -69.137563) (xy 164.651944 -69.138038) (xy 164.624694 -69.137504)
			(xy 164.570747 -69.129754) (xy 164.518452 -69.114405) (xy 164.468874 -69.09177) (xy 164.423022 -69.062309)
			(xy 164.38183 -69.026623) (xy 164.346135 -68.985437) (xy 164.316666 -68.939591) (xy 164.294021 -68.890017)
			(xy 164.278662 -68.837726) (xy 164.270901 -68.78378) (xy 164.270436 -68.75653) (xy 160.794399 -68.75653)
			(xy 160.788387 -68.769694) (xy 160.758916 -68.815549) (xy 160.723218 -68.856742) (xy 160.682022 -68.892436)
			(xy 160.636165 -68.921903) (xy 160.58658 -68.944544) (xy 160.534279 -68.959897) (xy 160.480324 -68.967651)
			(xy 160.45307 -68.968112) (xy 160.425699 -68.967661) (xy 160.37152 -68.959839) (xy 160.319017 -68.944346)
			(xy 160.26927 -68.921501) (xy 160.223304 -68.891774) (xy 160.202372 -68.874132) (xy 160.202118 -68.873878)
			(xy 160.195032 -68.86829) (xy 160.178115 -68.862045) (xy 160.169098 -68.861686) (xy 160.102042 -68.861686)
			(xy 160.093028 -68.862066) (xy 160.076111 -68.868298) (xy 160.069022 -68.873878) (xy 160.069022 -68.874132)
			(xy 160.068768 -68.874132) (xy 160.047825 -68.891758) (xy 160.001855 -68.92147) (xy 159.95211 -68.944308)
			(xy 159.899612 -68.959803) (xy 159.845438 -68.967635) (xy 159.81807 -68.968112) (xy 159.791756 -68.967661)
			(xy 159.739626 -68.960422) (xy 159.688984 -68.9461) (xy 159.640785 -68.924964) (xy 159.595942 -68.897415)
			(xy 159.555302 -68.863974) (xy 159.537146 -68.844922) (xy 159.529643 -68.837498) (xy 159.510349 -68.828986)
			(xy 159.499808 -68.828412) (xy 159.425132 -68.828412) (xy 159.414582 -68.828941) (xy 159.395287 -68.837476)
			(xy 159.387794 -68.844922) (xy 159.369639 -68.863978) (xy 159.329008 -68.897434) (xy 159.284168 -68.924992)
			(xy 159.235967 -68.946131) (xy 159.18532 -68.960448) (xy 159.133186 -68.967673) (xy 159.10687 -68.968112)
			(xy 159.079618 -68.96765) (xy 159.02567 -68.95989) (xy 158.973375 -68.944531) (xy 158.923798 -68.921887)
			(xy 158.877948 -68.892418) (xy 158.836758 -68.856724) (xy 158.801067 -68.815531) (xy 158.771601 -68.769679)
			(xy 158.74896 -68.720101) (xy 158.733605 -68.667805) (xy 158.725848 -68.613856) (xy 158.725362 -68.586604)
			(xy 150.03907 -68.586604) (xy 149.060916 -69.564758) (xy 149.037137 -69.587866) (xy 148.985283 -69.629195)
			(xy 148.929128 -69.664459) (xy 148.869378 -69.693215) (xy 148.806785 -69.715101) (xy 148.742135 -69.729842)
			(xy 148.676241 -69.737253) (xy 148.643086 -69.737732) (xy 148.18741 -69.737732) (xy 148.180044 -69.743828)
			(xy 148.1582 -69.765672) (xy 148.152104 -69.773038) (xy 148.152104 -70.22846) (xy 148.151637 -70.261614)
			(xy 148.144211 -70.327504) (xy 148.129459 -70.39215) (xy 148.107566 -70.454739) (xy 148.078808 -70.514485)
			(xy 148.043545 -70.570639) (xy 148.00222 -70.622494) (xy 147.97913 -70.64629) (xy 147.381976 -71.243444)
			(xy 147.358216 -71.266583) (xy 147.306372 -71.307951) (xy 147.250222 -71.343253) (xy 147.190472 -71.372047)
			(xy 147.127874 -71.393969) (xy 147.063215 -71.408744) (xy 146.997309 -71.416187) (xy 146.964146 -71.416672)
			(xy 146.508216 -71.416672) (xy 146.501612 -71.42226) (xy 146.47926 -71.444612) (xy 146.473672 -71.451216)
			(xy 146.473672 -71.555864) (xy 161.29457 -71.555864) (xy 161.298641 -71.500242) (xy 161.310767 -71.445805)
			(xy 161.33069 -71.393714) (xy 161.357986 -71.345079) (xy 161.392072 -71.300936) (xy 161.432221 -71.262227)
			(xy 161.477579 -71.229776) (xy 161.527179 -71.204275) (xy 161.579963 -71.186268) (xy 161.634806 -71.176138)
			(xy 161.69054 -71.174101) (xy 161.745977 -71.180201) (xy 161.799934 -71.194307) (xy 161.851263 -71.216119)
			(xy 161.898869 -71.245173) (xy 161.941737 -71.280848) (xy 161.978954 -71.322385) (xy 162.009727 -71.368898)
			(xy 162.033399 -71.419395) (xy 162.049467 -71.472802) (xy 162.057587 -71.527978) (xy 162.058096 -71.555864)
			(xy 162.057587 -71.58375) (xy 162.051748 -71.623428) (xy 162.803584 -71.623428) (xy 162.807655 -71.567806)
			(xy 162.819781 -71.513369) (xy 162.839704 -71.461278) (xy 162.867 -71.412643) (xy 162.901086 -71.3685)
			(xy 162.941235 -71.329791) (xy 162.986593 -71.29734) (xy 163.036193 -71.271839) (xy 163.088977 -71.253832)
			(xy 163.14382 -71.243702) (xy 163.199554 -71.241665) (xy 163.254991 -71.247765) (xy 163.308948 -71.261871)
			(xy 163.360277 -71.283683) (xy 163.407883 -71.312737) (xy 163.450751 -71.348412) (xy 163.487968 -71.389949)
			(xy 163.518741 -71.436462) (xy 163.542413 -71.486959) (xy 163.558481 -71.540366) (xy 163.566601 -71.595542)
			(xy 163.56711 -71.623428) (xy 163.566601 -71.651314) (xy 163.558481 -71.70649) (xy 163.542413 -71.759897)
			(xy 163.518741 -71.810394) (xy 163.487968 -71.856907) (xy 163.450751 -71.898444) (xy 163.407883 -71.934119)
			(xy 163.360277 -71.963173) (xy 163.308948 -71.984985) (xy 163.254991 -71.999091) (xy 163.199554 -72.005191)
			(xy 163.14382 -72.003154) (xy 163.088977 -71.993024) (xy 163.036193 -71.975017) (xy 162.986593 -71.949516)
			(xy 162.941235 -71.917065) (xy 162.901086 -71.878356) (xy 162.867 -71.834213) (xy 162.839704 -71.785578)
			(xy 162.819781 -71.733487) (xy 162.807655 -71.67905) (xy 162.803584 -71.623428) (xy 162.051748 -71.623428)
			(xy 162.049467 -71.638926) (xy 162.033399 -71.692333) (xy 162.009727 -71.74283) (xy 161.978954 -71.789343)
			(xy 161.941737 -71.83088) (xy 161.898869 -71.866555) (xy 161.851263 -71.895609) (xy 161.799934 -71.917421)
			(xy 161.745977 -71.931527) (xy 161.69054 -71.937627) (xy 161.634806 -71.93559) (xy 161.579963 -71.92546)
			(xy 161.527179 -71.907453) (xy 161.477579 -71.881952) (xy 161.432221 -71.849501) (xy 161.392072 -71.810792)
			(xy 161.357986 -71.766649) (xy 161.33069 -71.718014) (xy 161.310767 -71.665923) (xy 161.298641 -71.611486)
			(xy 161.29457 -71.555864) (xy 146.473672 -71.555864) (xy 146.473672 -71.907146) (xy 146.473194 -71.940308)
			(xy 146.465743 -72.006213) (xy 146.450962 -72.07087) (xy 146.429037 -72.133467) (xy 146.400243 -72.193216)
			(xy 146.364943 -72.249367) (xy 146.32358 -72.301213) (xy 146.300444 -72.324976) (xy 145.70329 -72.92213)
			(xy 145.679512 -72.945243) (xy 145.627661 -72.98658) (xy 145.571507 -73.021853) (xy 145.511758 -73.050617)
			(xy 145.449164 -73.072512) (xy 145.384513 -73.087262) (xy 145.318616 -73.094681) (xy 145.28546 -73.095104)
			(xy 144.830038 -73.095104) (xy 144.822672 -73.1012) (xy 144.800828 -73.123044) (xy 144.798124 -73.125897)
			(xy 144.793537 -73.132278) (xy 144.791684 -73.135744) (xy 144.789102 -73.141171) (xy 144.786279 -73.152851)
			(xy 144.786096 -73.158858) (xy 144.786096 -73.586086) (xy 144.785644 -73.618748) (xy 144.778304 -73.68366)
			(xy 144.763739 -73.74734) (xy 144.742131 -73.808988) (xy 144.713753 -73.867827) (xy 144.678961 -73.923116)
			(xy 144.638194 -73.97416) (xy 144.615408 -73.997566) (xy 143.123412 -75.489562) (xy 143.120705 -75.492412)
			(xy 143.11611 -75.49879) (xy 143.114268 -75.502262) (xy 143.111688 -75.50769) (xy 143.108871 -75.519369)
			(xy 143.10868 -75.525376) (xy 143.10868 -77.002386) (xy 143.108934 -77.007212) (xy 143.108934 -77.007466)
			(xy 143.109886 -77.014195) (xy 143.114904 -77.026818) (xy 143.11884 -77.032358) (xy 143.123412 -77.037692)
			(xy 143.314674 -77.228954) (xy 143.321012 -77.234857) (xy 143.33659 -77.242402) (xy 143.345154 -77.243686)
			(xy 143.347948 -77.24394) (xy 148.961348 -77.24394) (xy 148.98751 -77.236574) (xy 149.015198 -77.220332)
			(xy 149.073415 -77.193282) (xy 149.134223 -77.17271) (xy 149.196906 -77.158859) (xy 149.260721 -77.151894)
			(xy 149.292818 -77.151484) (xy 163.630356 -77.151484) (xy 163.640421 -77.15105) (xy 163.65901 -77.14332)
			(xy 163.666424 -77.136498) (xy 179.14747 -61.655706) (xy 179.152877 -61.649824) (xy 179.160132 -61.6356)
			(xy 179.161694 -61.627766) (xy 179.462684 -59.708288) (xy 179.463192 -59.697366) (xy 178.798982 -48.621696)
			(xy 178.798982 -48.621188) (xy 178.797712 -48.58639) (xy 178.797712 -48.585882) (xy 178.798011 -48.560413)
			(xy 178.802459 -48.509668) (xy 178.806602 -48.484536) (xy 178.80711 -48.481234) (xy 178.963574 -43.910758)
			(xy 178.964685 -43.886064) (xy 178.970536 -43.836977) (xy 178.975258 -43.812714) (xy 178.97602 -43.808396)
			(xy 178.990244 -43.393106) (xy 178.990244 -43.391836) (xy 178.990716 -43.359158) (xy 178.998059 -43.294215)
			(xy 179.012624 -43.230503) (xy 179.034227 -43.16882) (xy 179.062596 -43.109942) (xy 179.097377 -43.054608)
			(xy 179.138131 -43.003515) (xy 179.160932 -42.980102) (xy 179.471066 -42.669714) (xy 179.473606 -42.666412)
			(xy 179.487942 -42.646829) (xy 179.519353 -42.609827) (xy 179.536344 -42.592498) (xy 180.942996 -41.185846)
			(xy 180.950362 -41.17213) (xy 180.951632 -41.16451) (xy 180.958534 -41.129332) (xy 180.979739 -41.060849)
			(xy 181.009064 -40.995432) (xy 181.046081 -40.934038) (xy 181.090247 -40.877567) (xy 181.115208 -40.851836)
			(xy 181.465728 -40.501316) (xy 181.491428 -40.476353) (xy 181.547841 -40.432184) (xy 181.609182 -40.395161)
			(xy 181.674551 -40.36583) (xy 181.742987 -40.344619) (xy 181.778148 -40.33774) (xy 181.805072 -40.32377)
			(xy 181.811422 -40.31742) (xy 181.817688 -40.280554) (xy 181.83831 -40.208672) (xy 181.867827 -40.139962)
			(xy 181.905768 -40.075521) (xy 181.951528 -40.016374) (xy 181.977538 -39.989506) (xy 182.328058 -39.638986)
			(xy 182.353759 -39.614025) (xy 182.410174 -39.569861) (xy 182.471517 -39.532843) (xy 182.536886 -39.503517)
			(xy 182.605322 -39.482311) (xy 182.640478 -39.47541) (xy 182.667402 -39.46144) (xy 182.673752 -39.45509)
			(xy 182.680014 -39.418222) (xy 182.70063 -39.346336) (xy 182.730142 -39.277622) (xy 182.76808 -39.213176)
			(xy 182.813837 -39.154025) (xy 182.839868 -39.127176) (xy 183.190388 -38.776656) (xy 183.216088 -38.751694)
			(xy 183.272502 -38.707528) (xy 183.333845 -38.670509) (xy 183.399214 -38.641182) (xy 183.467651 -38.619977)
			(xy 183.502808 -38.61308) (xy 183.529732 -38.59911) (xy 183.536082 -38.59276) (xy 183.542346 -38.555893)
			(xy 183.562966 -38.48401) (xy 183.592482 -38.415299) (xy 183.630423 -38.350857) (xy 183.676184 -38.29171)
			(xy 183.702198 -38.264846) (xy 183.725566 -38.241478) (xy 183.729376 -38.23716) (xy 183.759856 -38.201854)
			(xy 183.779414 -38.182042) (xy 183.779922 -38.181534) (xy 184.0865 -37.87521) (xy 184.108759 -37.853497)
			(xy 184.157144 -37.814436) (xy 184.209415 -37.780752) (xy 184.264977 -37.752827) (xy 184.323197 -37.730979)
			(xy 184.3532 -37.72281) (xy 184.376314 -37.716968) (xy 184.380403 -37.715213) (xy 184.387942 -37.710489)
			(xy 184.3913 -37.70757) (xy 184.3913 -36.513516) (xy 184.39178 -36.480354) (xy 184.399235 -36.414451)
			(xy 184.414018 -36.349796) (xy 184.435945 -36.287201) (xy 184.46474 -36.227455) (xy 184.500041 -36.171306)
			(xy 184.541405 -36.119461) (xy 184.564528 -36.095686) (xy 185.126122 -35.534092) (xy 185.132976 -35.526697)
			(xy 185.140719 -35.508098) (xy 185.141108 -35.498024) (xy 185.141108 -35.43935) (xy 185.140346 -35.438334)
			(xy 185.139584 -35.437318) (xy 185.139584 -35.437064) (xy 185.131456 -35.426142) (xy 185.120653 -35.410712)
			(xy 185.100824 -35.378684) (xy 185.091832 -35.362134) (xy 185.08599 -35.350958) (xy 185.076891 -35.332543)
			(xy 185.061001 -35.294662) (xy 185.05424 -35.275266) (xy 185.053224 -35.272726) (xy 185.049668 -35.263582)
			(xy 185.040778 -35.231578) (xy 185.033134 -35.19933) (xy 185.024354 -35.133637) (xy 185.023252 -35.100514)
			(xy 185.023252 -34.644838) (xy 185.02364 -34.615357) (xy 185.029625 -34.556698) (xy 185.03519 -34.527744)
			(xy 185.036206 -34.517584) (xy 185.035444 -34.508948) (xy 185.031359 -34.483684) (xy 185.027038 -34.432685)
			(xy 185.026808 -34.407094) (xy 185.026808 -34.015172) (xy 185.026554 -34.012632) (xy 185.0263 -34.011362)
			(xy 185.024852 -33.996291) (xy 185.023325 -33.96605) (xy 185.023252 -33.95091) (xy 185.023252 -33.507934)
			(xy 185.023923 -33.469235) (xy 185.034245 -33.392526) (xy 185.043826 -33.355026) (xy 185.045321 -33.348769)
			(xy 185.045459 -33.335909) (xy 185.04408 -33.329626) (xy 185.036036 -33.29481) (xy 185.02738 -33.223877)
			(xy 185.026808 -33.188148) (xy 185.026808 -32.87776) (xy 185.026554 -32.87522) (xy 185.0263 -32.87395)
			(xy 185.024852 -32.858879) (xy 185.023326 -32.828638) (xy 185.023252 -32.813498) (xy 185.023252 -32.370268)
			(xy 185.023707 -32.338227) (xy 185.03077 -32.274533) (xy 185.044773 -32.211999) (xy 185.054748 -32.181546)
			(xy 185.057542 -32.164782) (xy 185.055256 -32.149542) (xy 185.046245 -32.120296) (xy 185.033607 -32.060415)
			(xy 185.027226 -31.999548) (xy 185.026808 -31.968948) (xy 185.026808 -31.740348) (xy 185.026554 -31.737808)
			(xy 185.0263 -31.736538) (xy 185.024852 -31.721467) (xy 185.023327 -31.691226) (xy 185.023252 -31.676086)
			(xy 185.023252 -31.232856) (xy 185.023894 -31.194281) (xy 185.034115 -31.117811) (xy 185.054346 -31.043361)
			(xy 185.068718 -31.007558) (xy 185.072086 -30.998272) (xy 185.072207 -30.978539) (xy 185.068972 -30.969204)
			(xy 185.055641 -30.934301) (xy 185.036886 -30.861978) (xy 185.0274 -30.787867) (xy 185.026808 -30.75051)
			(xy 185.026808 -30.602936) (xy 185.026554 -30.600396) (xy 185.0263 -30.599126) (xy 185.024853 -30.584055)
			(xy 185.023328 -30.553814) (xy 185.023252 -30.538674) (xy 185.023252 -30.095698) (xy 185.02369 -30.063398)
			(xy 185.030843 -29.999194) (xy 185.045062 -29.936178) (xy 185.066171 -29.875124) (xy 185.07964 -29.845762)
			(xy 185.085736 -29.833316) (xy 185.09048 -29.822584) (xy 185.090605 -29.799147) (xy 185.08599 -29.788358)
			(xy 185.071884 -29.758232) (xy 185.049767 -29.695494) (xy 185.034846 -29.630666) (xy 185.027308 -29.564571)
			(xy 185.026808 -29.53131) (xy 185.026808 -29.465524) (xy 185.026554 -29.462984) (xy 185.0263 -29.461714)
			(xy 185.024853 -29.446643) (xy 185.023329 -29.416402) (xy 185.023252 -29.401262) (xy 185.023252 -28.958286)
			(xy 185.02369 -28.925986) (xy 185.030845 -28.861783) (xy 185.045065 -28.798767) (xy 185.066175 -28.737713)
			(xy 185.07964 -28.70835) (xy 185.087726 -28.691471) (xy 185.105774 -28.65868) (xy 185.115708 -28.642818)
			(xy 185.118502 -28.638246) (xy 185.120788 -28.631134) (xy 185.103983 -28.604289) (xy 185.07557 -28.547683)
			(xy 185.053379 -28.48836) (xy 185.037666 -28.427003) (xy 185.02861 -28.364317) (xy 185.027062 -28.332684)
			(xy 185.026808 -28.328874) (xy 185.025147 -28.312924) (xy 185.023366 -28.280902) (xy 185.023252 -28.264866)
			(xy 185.023252 -27.966416) (xy 185.022733 -27.956145) (xy 185.014613 -27.93727) (xy 185.007504 -27.92984)
			(xy 184.981088 -27.925268) (xy 184.94718 -27.91893) (xy 184.881025 -27.89938) (xy 184.817595 -27.872263)
			(xy 184.757752 -27.837948) (xy 184.70231 -27.796901) (xy 184.652022 -27.749679) (xy 184.607573 -27.696926)
			(xy 184.569565 -27.639357) (xy 184.538516 -27.577757) (xy 184.514848 -27.51296) (xy 184.498882 -27.44585)
			(xy 184.490837 -27.377338) (xy 184.49036 -27.342846) (xy 184.490802 -27.310554) (xy 184.497866 -27.246357)
			(xy 184.511893 -27.183314) (xy 184.532716 -27.122178) (xy 184.560085 -27.06368) (xy 184.593674 -27.008517)
			(xy 184.613042 -26.982674) (xy 184.613042 -26.98242) (xy 184.618122 -26.975816) (xy 184.623456 -26.960322)
			(xy 184.623456 -26.870152) (xy 184.623132 -26.861873) (xy 184.617814 -26.846192) (xy 184.613042 -26.839418)
			(xy 184.593694 -26.813562) (xy 184.560124 -26.758392) (xy 184.532763 -26.699893) (xy 184.511937 -26.638762)
			(xy 184.497893 -26.575727) (xy 184.4908 -26.511536) (xy 184.49036 -26.479246) (xy 184.490806 -26.446077)
			(xy 184.498229 -26.380155) (xy 184.512986 -26.315479) (xy 184.534893 -26.252862) (xy 184.563673 -26.193092)
			(xy 184.598965 -26.13692) (xy 184.640325 -26.085053) (xy 184.687232 -26.038144) (xy 184.739097 -25.996782)
			(xy 184.795267 -25.961487) (xy 184.855036 -25.932704) (xy 184.917652 -25.910794) (xy 184.982327 -25.896033)
			(xy 185.048249 -25.888607) (xy 185.081418 -25.888188) (xy 185.114579 -25.88867) (xy 185.180481 -25.896128)
			(xy 185.245134 -25.910914) (xy 185.307726 -25.932844) (xy 185.367471 -25.961641) (xy 185.423617 -25.996943)
			(xy 185.47546 -26.038307) (xy 185.499248 -26.061416) (xy 185.605928 -26.168096) (xy 185.613354 -26.17487)
			(xy 185.631951 -26.182454) (xy 185.641996 -26.182828) (xy 185.698384 -26.182828) (xy 185.731545 -26.183309)
			(xy 185.797449 -26.190763) (xy 185.862103 -26.205548) (xy 185.924697 -26.227476) (xy 185.984443 -26.256271)
			(xy 186.04059 -26.291574) (xy 186.092434 -26.332938) (xy 186.116214 -26.356056) (xy 186.12104 -26.360882)
			(xy 187.189616 -26.360882) (xy 187.193687 -26.30526) (xy 187.205813 -26.250823) (xy 187.225736 -26.198732)
			(xy 187.253032 -26.150097) (xy 187.287118 -26.105954) (xy 187.327267 -26.067245) (xy 187.372625 -26.034794)
			(xy 187.422225 -26.009293) (xy 187.475009 -25.991286) (xy 187.529852 -25.981156) (xy 187.585586 -25.979119)
			(xy 187.641023 -25.985219) (xy 187.69498 -25.999325) (xy 187.746309 -26.021137) (xy 187.793915 -26.050191)
			(xy 187.836783 -26.085866) (xy 187.874 -26.127403) (xy 187.904773 -26.173916) (xy 187.928445 -26.224413)
			(xy 187.944513 -26.27782) (xy 187.950681 -26.319734) (xy 192.941954 -26.319734) (xy 192.946025 -26.264112)
			(xy 192.958151 -26.209675) (xy 192.978074 -26.157584) (xy 193.00537 -26.108949) (xy 193.039456 -26.064806)
			(xy 193.079605 -26.026097) (xy 193.124963 -25.993646) (xy 193.174563 -25.968145) (xy 193.227347 -25.950138)
			(xy 193.28219 -25.940008) (xy 193.337924 -25.937971) (xy 193.393361 -25.944071) (xy 193.447318 -25.958177)
			(xy 193.498647 -25.979989) (xy 193.546253 -26.009043) (xy 193.575918 -26.03373) (xy 199.3679 -26.03373)
			(xy 199.371971 -25.978108) (xy 199.384097 -25.923671) (xy 199.40402 -25.87158) (xy 199.431316 -25.822945)
			(xy 199.465402 -25.778802) (xy 199.505551 -25.740093) (xy 199.550909 -25.707642) (xy 199.600509 -25.682141)
			(xy 199.653293 -25.664134) (xy 199.708136 -25.654004) (xy 199.76387 -25.651967) (xy 199.819307 -25.658067)
			(xy 199.873264 -25.672173) (xy 199.924593 -25.693985) (xy 199.972199 -25.723039) (xy 200.015067 -25.758714)
			(xy 200.052284 -25.800251) (xy 200.083057 -25.846764) (xy 200.106729 -25.897261) (xy 200.122797 -25.950668)
			(xy 200.130917 -26.005844) (xy 200.131426 -26.03373) (xy 200.130917 -26.061616) (xy 200.122797 -26.116792)
			(xy 200.106729 -26.170199) (xy 200.083057 -26.220696) (xy 200.052823 -26.266394) (xy 202.620626 -26.266394)
			(xy 202.621112 -26.239143) (xy 202.628868 -26.185195) (xy 202.644223 -26.1329) (xy 202.666865 -26.083323)
			(xy 202.696331 -26.037473) (xy 202.732022 -25.996282) (xy 202.773213 -25.960591) (xy 202.819063 -25.931125)
			(xy 202.86864 -25.908483) (xy 202.920935 -25.893128) (xy 202.974883 -25.885372) (xy 203.029385 -25.885372)
			(xy 203.083333 -25.893128) (xy 203.135628 -25.908483) (xy 203.185205 -25.931125) (xy 203.231055 -25.960591)
			(xy 203.272246 -25.996282) (xy 203.307937 -26.037473) (xy 203.337403 -26.083323) (xy 203.360045 -26.1329)
			(xy 203.3754 -26.185195) (xy 203.383156 -26.239143) (xy 203.383642 -26.266394) (xy 203.383073 -26.295881)
			(xy 203.37398 -26.35415) (xy 203.356024 -26.410324) (xy 203.329634 -26.463064) (xy 203.295439 -26.511113)
			(xy 203.254254 -26.553324) (xy 203.230988 -26.571448) (xy 203.219833 -26.580307) (xy 203.202647 -26.603017)
			(xy 203.1924 -26.629589) (xy 203.189887 -26.657958) (xy 203.195303 -26.685917) (xy 203.208228 -26.711295)
			(xy 203.227657 -26.732118) (xy 203.239624 -26.73985) (xy 203.263366 -26.754746) (xy 203.3066 -26.790414)
			(xy 203.344151 -26.832024) (xy 203.375209 -26.878679) (xy 203.399108 -26.929377) (xy 203.415333 -26.983025)
			(xy 203.423533 -27.03847) (xy 203.424028 -27.066494) (xy 203.423542 -27.093745) (xy 203.415786 -27.147693)
			(xy 203.400431 -27.199988) (xy 203.377789 -27.249565) (xy 203.348323 -27.295415) (xy 203.312632 -27.336606)
			(xy 203.271441 -27.372297) (xy 203.225591 -27.401763) (xy 203.176014 -27.424405) (xy 203.123719 -27.43976)
			(xy 203.069771 -27.447516) (xy 203.015269 -27.447516) (xy 202.961321 -27.43976) (xy 202.909026 -27.424405)
			(xy 202.859449 -27.401763) (xy 202.813599 -27.372297) (xy 202.772408 -27.336606) (xy 202.736717 -27.295415)
			(xy 202.707251 -27.249565) (xy 202.684609 -27.199988) (xy 202.669254 -27.147693) (xy 202.661498 -27.093745)
			(xy 202.661012 -27.066494) (xy 202.66155 -27.037006) (xy 202.670647 -26.978734) (xy 202.688608 -26.922559)
			(xy 202.715004 -26.869818) (xy 202.749205 -26.821771) (xy 202.790397 -26.779562) (xy 202.813666 -26.76144)
			(xy 202.824723 -26.75247) (xy 202.841898 -26.729783) (xy 202.852145 -26.703238) (xy 202.854668 -26.674896)
			(xy 202.849272 -26.646957) (xy 202.836376 -26.621593) (xy 202.81698 -26.600773) (xy 202.80503 -26.593038)
			(xy 202.781295 -26.578131) (xy 202.738058 -26.542467) (xy 202.700505 -26.50086) (xy 202.669445 -26.454206)
			(xy 202.645545 -26.40351) (xy 202.62932 -26.349862) (xy 202.62112 -26.294418) (xy 202.620626 -26.266394)
			(xy 200.052823 -26.266394) (xy 200.052284 -26.267209) (xy 200.015067 -26.308746) (xy 199.972199 -26.344421)
			(xy 199.924593 -26.373475) (xy 199.873264 -26.395287) (xy 199.819307 -26.409393) (xy 199.76387 -26.415493)
			(xy 199.708136 -26.413456) (xy 199.653293 -26.403326) (xy 199.600509 -26.385319) (xy 199.550909 -26.359818)
			(xy 199.505551 -26.327367) (xy 199.465402 -26.288658) (xy 199.431316 -26.244515) (xy 199.40402 -26.19588)
			(xy 199.384097 -26.143789) (xy 199.371971 -26.089352) (xy 199.3679 -26.03373) (xy 193.575918 -26.03373)
			(xy 193.589121 -26.044718) (xy 193.626338 -26.086255) (xy 193.657111 -26.132768) (xy 193.680783 -26.183265)
			(xy 193.696851 -26.236672) (xy 193.704971 -26.291848) (xy 193.70548 -26.319734) (xy 193.704971 -26.34762)
			(xy 193.696851 -26.402796) (xy 193.680783 -26.456203) (xy 193.657111 -26.5067) (xy 193.626338 -26.553213)
			(xy 193.589121 -26.59475) (xy 193.546253 -26.630425) (xy 193.498647 -26.659479) (xy 193.447318 -26.681291)
			(xy 193.393361 -26.695397) (xy 193.337924 -26.701497) (xy 193.28219 -26.69946) (xy 193.227347 -26.68933)
			(xy 193.174563 -26.671323) (xy 193.124963 -26.645822) (xy 193.079605 -26.613371) (xy 193.039456 -26.574662)
			(xy 193.00537 -26.530519) (xy 192.978074 -26.481884) (xy 192.958151 -26.429793) (xy 192.946025 -26.375356)
			(xy 192.941954 -26.319734) (xy 187.950681 -26.319734) (xy 187.952633 -26.332996) (xy 187.953142 -26.360882)
			(xy 187.952633 -26.388768) (xy 187.944513 -26.443944) (xy 187.928445 -26.497351) (xy 187.904773 -26.547848)
			(xy 187.874 -26.594361) (xy 187.836783 -26.635898) (xy 187.793915 -26.671573) (xy 187.746309 -26.700627)
			(xy 187.69498 -26.722439) (xy 187.641023 -26.736545) (xy 187.585586 -26.742645) (xy 187.529852 -26.740608)
			(xy 187.475009 -26.730478) (xy 187.422225 -26.712471) (xy 187.372625 -26.68697) (xy 187.327267 -26.654519)
			(xy 187.287118 -26.61581) (xy 187.253032 -26.571667) (xy 187.225736 -26.523032) (xy 187.205813 -26.470941)
			(xy 187.193687 -26.416504) (xy 187.189616 -26.360882) (xy 186.12104 -26.360882) (xy 186.431682 -26.671524)
			(xy 186.454792 -26.695303) (xy 186.496125 -26.747156) (xy 186.531393 -26.80331) (xy 186.560154 -26.86306)
			(xy 186.582045 -26.925653) (xy 186.592444 -26.971244) (xy 188.951106 -26.971244) (xy 188.955177 -26.915622)
			(xy 188.967303 -26.861185) (xy 188.987226 -26.809094) (xy 189.014522 -26.760459) (xy 189.048608 -26.716316)
			(xy 189.088757 -26.677607) (xy 189.134115 -26.645156) (xy 189.183715 -26.619655) (xy 189.236499 -26.601648)
			(xy 189.291342 -26.591518) (xy 189.347076 -26.589481) (xy 189.402513 -26.595581) (xy 189.45647 -26.609687)
			(xy 189.507799 -26.631499) (xy 189.555405 -26.660553) (xy 189.598273 -26.696228) (xy 189.63549 -26.737765)
			(xy 189.666263 -26.784278) (xy 189.689935 -26.834775) (xy 189.706003 -26.888182) (xy 189.714123 -26.943358)
			(xy 189.714632 -26.971244) (xy 189.714123 -26.99913) (xy 189.706003 -27.054306) (xy 189.689935 -27.107713)
			(xy 189.666263 -27.15821) (xy 189.63549 -27.204723) (xy 189.598273 -27.24626) (xy 189.555405 -27.281935)
			(xy 189.507799 -27.310989) (xy 189.45647 -27.332801) (xy 189.402513 -27.346907) (xy 189.347076 -27.353007)
			(xy 189.291342 -27.35097) (xy 189.236499 -27.34084) (xy 189.183715 -27.322833) (xy 189.134115 -27.297332)
			(xy 189.088757 -27.264881) (xy 189.048608 -27.226172) (xy 189.014522 -27.182029) (xy 188.987226 -27.133394)
			(xy 188.967303 -27.081303) (xy 188.955177 -27.026866) (xy 188.951106 -26.971244) (xy 186.592444 -26.971244)
			(xy 186.596792 -26.990304) (xy 186.604209 -27.056198) (xy 186.604656 -27.089354) (xy 186.604656 -29.114242)
			(xy 186.947556 -29.114242) (xy 186.947556 -28.250642) (xy 186.948046 -28.220674) (xy 186.955869 -28.161252)
			(xy 186.971382 -28.103359) (xy 186.994318 -28.047986) (xy 187.024285 -27.99608) (xy 187.060772 -27.94853)
			(xy 187.103152 -27.90615) (xy 187.150702 -27.869663) (xy 187.202608 -27.839696) (xy 187.257981 -27.81676)
			(xy 187.315874 -27.801247) (xy 187.375296 -27.793424) (xy 187.435232 -27.793424) (xy 187.494654 -27.801247)
			(xy 187.552547 -27.81676) (xy 187.60792 -27.839696) (xy 187.659826 -27.869663) (xy 187.707376 -27.90615)
			(xy 187.749756 -27.94853) (xy 187.786243 -27.99608) (xy 187.81621 -28.047986) (xy 187.839146 -28.103359)
			(xy 187.854659 -28.161252) (xy 187.862482 -28.220674) (xy 187.862972 -28.250642) (xy 187.862972 -28.469082)
			(xy 191.852548 -28.469082) (xy 191.856619 -28.41346) (xy 191.868745 -28.359023) (xy 191.888668 -28.306932)
			(xy 191.915964 -28.258297) (xy 191.95005 -28.214154) (xy 191.990199 -28.175445) (xy 192.035557 -28.142994)
			(xy 192.085157 -28.117493) (xy 192.137941 -28.099486) (xy 192.192784 -28.089356) (xy 192.248518 -28.087319)
			(xy 192.303955 -28.093419) (xy 192.357912 -28.107525) (xy 192.409241 -28.129337) (xy 192.425297 -28.139136)
			(xy 196.497954 -28.139136) (xy 196.502025 -28.083514) (xy 196.514151 -28.029077) (xy 196.534074 -27.976986)
			(xy 196.56137 -27.928351) (xy 196.595456 -27.884208) (xy 196.635605 -27.845499) (xy 196.680963 -27.813048)
			(xy 196.730563 -27.787547) (xy 196.783347 -27.76954) (xy 196.83819 -27.75941) (xy 196.893924 -27.757373)
			(xy 196.949361 -27.763473) (xy 197.003318 -27.777579) (xy 197.054647 -27.799391) (xy 197.102253 -27.828445)
			(xy 197.145121 -27.86412) (xy 197.182338 -27.905657) (xy 197.213111 -27.95217) (xy 197.236783 -28.002667)
			(xy 197.252851 -28.056074) (xy 197.260971 -28.11125) (xy 197.26148 -28.139136) (xy 197.767954 -28.139136)
			(xy 197.772025 -28.083514) (xy 197.784151 -28.029077) (xy 197.804074 -27.976986) (xy 197.83137 -27.928351)
			(xy 197.865456 -27.884208) (xy 197.905605 -27.845499) (xy 197.950963 -27.813048) (xy 198.000563 -27.787547)
			(xy 198.053347 -27.76954) (xy 198.10819 -27.75941) (xy 198.163924 -27.757373) (xy 198.219361 -27.763473)
			(xy 198.273318 -27.777579) (xy 198.324647 -27.799391) (xy 198.372253 -27.828445) (xy 198.415121 -27.86412)
			(xy 198.452338 -27.905657) (xy 198.483111 -27.95217) (xy 198.506783 -28.002667) (xy 198.522851 -28.056074)
			(xy 198.530971 -28.11125) (xy 198.53148 -28.139136) (xy 198.530971 -28.167022) (xy 198.522851 -28.222198)
			(xy 198.506783 -28.275605) (xy 198.483111 -28.326102) (xy 198.452338 -28.372615) (xy 198.415121 -28.414152)
			(xy 198.372253 -28.449827) (xy 198.324647 -28.478881) (xy 198.273318 -28.500693) (xy 198.219361 -28.514799)
			(xy 198.163924 -28.520899) (xy 198.10819 -28.518862) (xy 198.053347 -28.508732) (xy 198.000563 -28.490725)
			(xy 197.950963 -28.465224) (xy 197.905605 -28.432773) (xy 197.865456 -28.394064) (xy 197.83137 -28.349921)
			(xy 197.804074 -28.301286) (xy 197.784151 -28.249195) (xy 197.772025 -28.194758) (xy 197.767954 -28.139136)
			(xy 197.26148 -28.139136) (xy 197.260971 -28.167022) (xy 197.252851 -28.222198) (xy 197.236783 -28.275605)
			(xy 197.213111 -28.326102) (xy 197.182338 -28.372615) (xy 197.145121 -28.414152) (xy 197.102253 -28.449827)
			(xy 197.054647 -28.478881) (xy 197.003318 -28.500693) (xy 196.949361 -28.514799) (xy 196.893924 -28.520899)
			(xy 196.83819 -28.518862) (xy 196.783347 -28.508732) (xy 196.730563 -28.490725) (xy 196.680963 -28.465224)
			(xy 196.635605 -28.432773) (xy 196.595456 -28.394064) (xy 196.56137 -28.349921) (xy 196.534074 -28.301286)
			(xy 196.514151 -28.249195) (xy 196.502025 -28.194758) (xy 196.497954 -28.139136) (xy 192.425297 -28.139136)
			(xy 192.456847 -28.158391) (xy 192.499715 -28.194066) (xy 192.536932 -28.235603) (xy 192.567705 -28.282116)
			(xy 192.591377 -28.332613) (xy 192.607445 -28.38602) (xy 192.615565 -28.441196) (xy 192.616074 -28.469082)
			(xy 192.615565 -28.496968) (xy 192.607445 -28.552144) (xy 192.591377 -28.605551) (xy 192.567705 -28.656048)
			(xy 192.536932 -28.702561) (xy 192.499715 -28.744098) (xy 192.456847 -28.779773) (xy 192.409241 -28.808827)
			(xy 192.357912 -28.830639) (xy 192.303955 -28.844745) (xy 192.248518 -28.850845) (xy 192.192784 -28.848808)
			(xy 192.137941 -28.838678) (xy 192.085157 -28.820671) (xy 192.035557 -28.79517) (xy 191.990199 -28.762719)
			(xy 191.95005 -28.72401) (xy 191.915964 -28.679867) (xy 191.888668 -28.631232) (xy 191.868745 -28.579141)
			(xy 191.856619 -28.524704) (xy 191.852548 -28.469082) (xy 187.862972 -28.469082) (xy 187.862972 -29.114242)
			(xy 187.862839 -29.12237) (xy 202.706732 -29.12237) (xy 202.706732 -28.25877) (xy 202.707222 -28.228786)
			(xy 202.71505 -28.16933) (xy 202.730571 -28.111405) (xy 202.75352 -28.056001) (xy 202.783504 -28.004067)
			(xy 202.82001 -27.956491) (xy 202.862415 -27.914086) (xy 202.909991 -27.87758) (xy 202.961925 -27.847596)
			(xy 203.017329 -27.824647) (xy 203.075254 -27.809126) (xy 203.13471 -27.801298) (xy 203.194678 -27.801298)
			(xy 203.254134 -27.809126) (xy 203.312059 -27.824647) (xy 203.367463 -27.847596) (xy 203.419397 -27.87758)
			(xy 203.466973 -27.914086) (xy 203.509378 -27.956491) (xy 203.545884 -28.004067) (xy 203.575868 -28.056001)
			(xy 203.598817 -28.111405) (xy 203.614338 -28.16933) (xy 203.622166 -28.228786) (xy 203.622656 -28.25877)
			(xy 203.622656 -29.12237) (xy 203.622166 -29.152354) (xy 203.614338 -29.21181) (xy 203.598817 -29.269735)
			(xy 203.575868 -29.325139) (xy 203.545884 -29.377073) (xy 203.509378 -29.424649) (xy 203.466973 -29.467054)
			(xy 203.419397 -29.50356) (xy 203.367463 -29.533544) (xy 203.312059 -29.556493) (xy 203.254134 -29.572014)
			(xy 203.194678 -29.579842) (xy 203.13471 -29.579842) (xy 203.075254 -29.572014) (xy 203.017329 -29.556493)
			(xy 202.961925 -29.533544) (xy 202.909991 -29.50356) (xy 202.862415 -29.467054) (xy 202.82001 -29.424649)
			(xy 202.783504 -29.377073) (xy 202.75352 -29.325139) (xy 202.730571 -29.269735) (xy 202.71505 -29.21181)
			(xy 202.707222 -29.152354) (xy 202.706732 -29.12237) (xy 187.862839 -29.12237) (xy 187.862482 -29.14421)
			(xy 187.854659 -29.203632) (xy 187.839146 -29.261525) (xy 187.81621 -29.316898) (xy 187.786243 -29.368804)
			(xy 187.749756 -29.416354) (xy 187.707376 -29.458734) (xy 187.659826 -29.495221) (xy 187.60792 -29.525188)
			(xy 187.552547 -29.548124) (xy 187.494654 -29.563637) (xy 187.435232 -29.57146) (xy 187.375296 -29.57146)
			(xy 187.315874 -29.563637) (xy 187.257981 -29.548124) (xy 187.202608 -29.525188) (xy 187.150702 -29.495221)
			(xy 187.103152 -29.458734) (xy 187.060772 -29.416354) (xy 187.024285 -29.368804) (xy 186.994318 -29.316898)
			(xy 186.971382 -29.261525) (xy 186.955869 -29.203632) (xy 186.948046 -29.14421) (xy 186.947556 -29.114242)
			(xy 186.604656 -29.114242) (xy 186.604656 -30.92069) (xy 189.589664 -30.92069) (xy 189.589664 -30.05709)
			(xy 189.590154 -30.027122) (xy 189.597977 -29.9677) (xy 189.61349 -29.909807) (xy 189.636426 -29.854434)
			(xy 189.666393 -29.802528) (xy 189.70288 -29.754978) (xy 189.74526 -29.712598) (xy 189.79281 -29.676111)
			(xy 189.844716 -29.646144) (xy 189.900089 -29.623208) (xy 189.957982 -29.607695) (xy 190.017404 -29.599872)
			(xy 190.07734 -29.599872) (xy 190.136762 -29.607695) (xy 190.194655 -29.623208) (xy 190.250028 -29.646144)
			(xy 190.301934 -29.676111) (xy 190.349484 -29.712598) (xy 190.391864 -29.754978) (xy 190.428351 -29.802528)
			(xy 190.458318 -29.854434) (xy 190.481254 -29.909807) (xy 190.496767 -29.9677) (xy 190.50459 -30.027122)
			(xy 190.50508 -30.05709) (xy 190.50508 -30.376876) (xy 194.988942 -30.376876) (xy 194.989499 -30.34796)
			(xy 194.998218 -30.29079) (xy 195.015467 -30.235592) (xy 195.040851 -30.183629) (xy 195.073789 -30.136095)
			(xy 195.113525 -30.094077) (xy 195.136008 -30.075886) (xy 195.144813 -30.068276) (xy 195.154997 -30.047378)
			(xy 195.155566 -30.035754) (xy 195.155566 -29.955998) (xy 195.155026 -29.944366) (xy 195.144839 -29.923456)
			(xy 195.136008 -29.915866) (xy 195.11351 -29.897692) (xy 195.073775 -29.855669) (xy 195.040838 -29.808131)
			(xy 195.015452 -29.756166) (xy 194.998199 -29.700965) (xy 194.989474 -29.643793) (xy 194.988942 -29.614876)
			(xy 194.989428 -29.587625) (xy 194.997184 -29.533677) (xy 195.012539 -29.481382) (xy 195.035181 -29.431805)
			(xy 195.064647 -29.385955) (xy 195.100338 -29.344764) (xy 195.141529 -29.309073) (xy 195.187379 -29.279607)
			(xy 195.236956 -29.256965) (xy 195.289251 -29.24161) (xy 195.343199 -29.233854) (xy 195.397701 -29.233854)
			(xy 195.451649 -29.24161) (xy 195.503944 -29.256965) (xy 195.553521 -29.279607) (xy 195.599371 -29.309073)
			(xy 195.640562 -29.344764) (xy 195.676253 -29.385955) (xy 195.705719 -29.431805) (xy 195.728361 -29.481382)
			(xy 195.743716 -29.533677) (xy 195.751472 -29.587625) (xy 195.751958 -29.614876) (xy 195.751438 -29.643793)
			(xy 195.742712 -29.700965) (xy 195.725455 -29.756164) (xy 195.700064 -29.808126) (xy 195.66712 -29.85566)
			(xy 195.627378 -29.897676) (xy 195.604892 -29.915866) (xy 195.596109 -29.923497) (xy 195.585912 -29.944379)
			(xy 195.585334 -29.955998) (xy 195.585334 -30.035754) (xy 195.585845 -30.04739) (xy 195.596053 -30.0683)
			(xy 195.604892 -30.075886) (xy 195.627367 -30.094087) (xy 195.667103 -30.136104) (xy 195.700043 -30.183637)
			(xy 195.725433 -30.235597) (xy 195.742691 -30.290792) (xy 195.751422 -30.347961) (xy 195.751958 -30.376876)
			(xy 198.029068 -30.376876) (xy 198.029615 -30.34796) (xy 198.038335 -30.290789) (xy 198.055585 -30.23559)
			(xy 198.080971 -30.183627) (xy 198.113911 -30.136093) (xy 198.15365 -30.094076) (xy 198.176134 -30.075886)
			(xy 198.184943 -30.068281) (xy 198.195124 -30.047378) (xy 198.195692 -30.035754) (xy 198.195692 -29.955998)
			(xy 198.195143 -29.944367) (xy 198.184961 -29.923457) (xy 198.176134 -29.915866) (xy 198.153641 -29.897686)
			(xy 198.113905 -29.855665) (xy 198.080966 -29.808128) (xy 198.055579 -29.756164) (xy 198.038325 -29.700964)
			(xy 198.0296 -29.643793) (xy 198.029068 -29.614876) (xy 198.029554 -29.587625) (xy 198.03731 -29.533677)
			(xy 198.052665 -29.481382) (xy 198.075307 -29.431805) (xy 198.104773 -29.385955) (xy 198.140464 -29.344764)
			(xy 198.181655 -29.309073) (xy 198.227505 -29.279607) (xy 198.277082 -29.256965) (xy 198.329377 -29.24161)
			(xy 198.383325 -29.233854) (xy 198.437827 -29.233854) (xy 198.491775 -29.24161) (xy 198.54407 -29.256965)
			(xy 198.593647 -29.279607) (xy 198.639497 -29.309073) (xy 198.680688 -29.344764) (xy 198.716379 -29.385955)
			(xy 198.745845 -29.431805) (xy 198.768487 -29.481382) (xy 198.783842 -29.533677) (xy 198.791598 -29.587625)
			(xy 198.792084 -29.614876) (xy 198.791554 -29.643793) (xy 198.782829 -29.700964) (xy 198.765573 -29.756162)
			(xy 198.740184 -29.808124) (xy 198.707242 -29.855658) (xy 198.667503 -29.897676) (xy 198.645018 -29.915866)
			(xy 198.636222 -29.923484) (xy 198.626036 -29.944377) (xy 198.62546 -29.955998) (xy 198.62546 -30.035754)
			(xy 198.625961 -30.047391) (xy 198.636175 -30.068302) (xy 198.645018 -30.075886) (xy 198.667499 -30.09408)
			(xy 198.707233 -30.1361) (xy 198.740172 -30.183634) (xy 198.765561 -30.235595) (xy 198.782818 -30.290792)
			(xy 198.791548 -30.34796) (xy 198.792084 -30.376876) (xy 198.791598 -30.404127) (xy 198.783842 -30.458075)
			(xy 198.768487 -30.51037) (xy 198.745845 -30.559947) (xy 198.716379 -30.605797) (xy 198.680688 -30.646988)
			(xy 198.639497 -30.682679) (xy 198.593647 -30.712145) (xy 198.54407 -30.734787) (xy 198.491775 -30.750142)
			(xy 198.437827 -30.757898) (xy 198.383325 -30.757898) (xy 198.329377 -30.750142) (xy 198.277082 -30.734787)
			(xy 198.227505 -30.712145) (xy 198.181655 -30.682679) (xy 198.140464 -30.646988) (xy 198.104773 -30.605797)
			(xy 198.075307 -30.559947) (xy 198.052665 -30.51037) (xy 198.03731 -30.458075) (xy 198.029554 -30.404127)
			(xy 198.029068 -30.376876) (xy 195.751958 -30.376876) (xy 195.751472 -30.404127) (xy 195.743716 -30.458075)
			(xy 195.728361 -30.51037) (xy 195.705719 -30.559947) (xy 195.676253 -30.605797) (xy 195.640562 -30.646988)
			(xy 195.599371 -30.682679) (xy 195.553521 -30.712145) (xy 195.503944 -30.734787) (xy 195.451649 -30.750142)
			(xy 195.397701 -30.757898) (xy 195.343199 -30.757898) (xy 195.289251 -30.750142) (xy 195.236956 -30.734787)
			(xy 195.187379 -30.712145) (xy 195.141529 -30.682679) (xy 195.100338 -30.646988) (xy 195.064647 -30.605797)
			(xy 195.035181 -30.559947) (xy 195.012539 -30.51037) (xy 194.997184 -30.458075) (xy 194.989428 -30.404127)
			(xy 194.988942 -30.376876) (xy 190.50508 -30.376876) (xy 190.50508 -30.92069) (xy 190.505051 -30.922468)
			(xy 200.852532 -30.922468) (xy 200.852532 -30.058868) (xy 200.853022 -30.028884) (xy 200.86085 -29.969428)
			(xy 200.876371 -29.911503) (xy 200.89932 -29.856099) (xy 200.929304 -29.804165) (xy 200.96581 -29.756589)
			(xy 201.008215 -29.714184) (xy 201.055791 -29.677678) (xy 201.107725 -29.647694) (xy 201.163129 -29.624745)
			(xy 201.221054 -29.609224) (xy 201.28051 -29.601396) (xy 201.340478 -29.601396) (xy 201.399934 -29.609224)
			(xy 201.457859 -29.624745) (xy 201.513263 -29.647694) (xy 201.565197 -29.677678) (xy 201.612773 -29.714184)
			(xy 201.655178 -29.756589) (xy 201.691684 -29.804165) (xy 201.721668 -29.856099) (xy 201.744617 -29.911503)
			(xy 201.760138 -29.969428) (xy 201.767966 -30.028884) (xy 201.768456 -30.058868) (xy 201.768456 -30.922468)
			(xy 201.767966 -30.952452) (xy 201.760138 -31.011908) (xy 201.744617 -31.069833) (xy 201.721668 -31.125237)
			(xy 201.691684 -31.177171) (xy 201.655178 -31.224747) (xy 201.612773 -31.267152) (xy 201.565197 -31.303658)
			(xy 201.513263 -31.333642) (xy 201.457859 -31.356591) (xy 201.399934 -31.372112) (xy 201.340478 -31.37994)
			(xy 201.28051 -31.37994) (xy 201.221054 -31.372112) (xy 201.163129 -31.356591) (xy 201.107725 -31.333642)
			(xy 201.055791 -31.303658) (xy 201.008215 -31.267152) (xy 200.96581 -31.224747) (xy 200.929304 -31.177171)
			(xy 200.89932 -31.125237) (xy 200.876371 -31.069833) (xy 200.86085 -31.011908) (xy 200.853022 -30.952452)
			(xy 200.852532 -30.922468) (xy 190.505051 -30.922468) (xy 190.50459 -30.950658) (xy 190.496767 -31.01008)
			(xy 190.481254 -31.067973) (xy 190.458318 -31.123346) (xy 190.428351 -31.175252) (xy 190.391864 -31.222802)
			(xy 190.349484 -31.265182) (xy 190.301934 -31.301669) (xy 190.250028 -31.331636) (xy 190.194655 -31.354572)
			(xy 190.136762 -31.370085) (xy 190.07734 -31.377908) (xy 190.017404 -31.377908) (xy 189.957982 -31.370085)
			(xy 189.900089 -31.354572) (xy 189.844716 -31.331636) (xy 189.79281 -31.301669) (xy 189.74526 -31.265182)
			(xy 189.70288 -31.222802) (xy 189.666393 -31.175252) (xy 189.636426 -31.123346) (xy 189.61349 -31.067973)
			(xy 189.597977 -31.01008) (xy 189.590154 -30.950658) (xy 189.589664 -30.92069) (xy 186.604656 -30.92069)
			(xy 186.604656 -32.714184) (xy 186.947556 -32.714184) (xy 186.947556 -31.850584) (xy 186.948046 -31.820616)
			(xy 186.955869 -31.761194) (xy 186.971382 -31.703301) (xy 186.994318 -31.647928) (xy 187.024285 -31.596022)
			(xy 187.060772 -31.548472) (xy 187.103152 -31.506092) (xy 187.150702 -31.469605) (xy 187.202608 -31.439638)
			(xy 187.257981 -31.416702) (xy 187.315874 -31.401189) (xy 187.375296 -31.393366) (xy 187.435232 -31.393366)
			(xy 187.494654 -31.401189) (xy 187.552547 -31.416702) (xy 187.60792 -31.439638) (xy 187.659826 -31.469605)
			(xy 187.707376 -31.506092) (xy 187.749756 -31.548472) (xy 187.76465 -31.567882) (xy 195.098668 -31.567882)
			(xy 195.102739 -31.51226) (xy 195.114865 -31.457823) (xy 195.134788 -31.405732) (xy 195.162084 -31.357097)
			(xy 195.19617 -31.312954) (xy 195.236319 -31.274245) (xy 195.281677 -31.241794) (xy 195.331277 -31.216293)
			(xy 195.384061 -31.198286) (xy 195.438904 -31.188156) (xy 195.494638 -31.186119) (xy 195.550075 -31.192219)
			(xy 195.604032 -31.206325) (xy 195.655361 -31.228137) (xy 195.702967 -31.257191) (xy 195.745835 -31.292866)
			(xy 195.783052 -31.334403) (xy 195.813825 -31.380916) (xy 195.837497 -31.431413) (xy 195.853565 -31.48482)
			(xy 195.861685 -31.539996) (xy 195.862194 -31.567882) (xy 195.861685 -31.595768) (xy 195.853565 -31.650944)
			(xy 195.837497 -31.704351) (xy 195.830505 -31.719266) (xy 196.385432 -31.719266) (xy 196.389503 -31.663644)
			(xy 196.401629 -31.609207) (xy 196.421552 -31.557116) (xy 196.448848 -31.508481) (xy 196.482934 -31.464338)
			(xy 196.523083 -31.425629) (xy 196.568441 -31.393178) (xy 196.618041 -31.367677) (xy 196.670825 -31.34967)
			(xy 196.725668 -31.33954) (xy 196.781402 -31.337503) (xy 196.836839 -31.343603) (xy 196.890796 -31.357709)
			(xy 196.942125 -31.379521) (xy 196.989731 -31.408575) (xy 197.032599 -31.44425) (xy 197.069816 -31.485787)
			(xy 197.100589 -31.5323) (xy 197.124261 -31.582797) (xy 197.140329 -31.636204) (xy 197.144479 -31.664402)
			(xy 197.66102 -31.664402) (xy 197.665091 -31.60878) (xy 197.677217 -31.554343) (xy 197.69714 -31.502252)
			(xy 197.724436 -31.453617) (xy 197.758522 -31.409474) (xy 197.798671 -31.370765) (xy 197.844029 -31.338314)
			(xy 197.893629 -31.312813) (xy 197.946413 -31.294806) (xy 198.001256 -31.284676) (xy 198.05699 -31.282639)
			(xy 198.112427 -31.288739) (xy 198.166384 -31.302845) (xy 198.217713 -31.324657) (xy 198.265319 -31.353711)
			(xy 198.308187 -31.389386) (xy 198.345404 -31.430923) (xy 198.376177 -31.477436) (xy 198.399849 -31.527933)
			(xy 198.415917 -31.58134) (xy 198.424037 -31.636516) (xy 198.424546 -31.664402) (xy 198.424037 -31.692288)
			(xy 198.415917 -31.747464) (xy 198.406977 -31.777178) (xy 198.926194 -31.777178) (xy 198.930265 -31.721556)
			(xy 198.942391 -31.667119) (xy 198.962314 -31.615028) (xy 198.98961 -31.566393) (xy 199.023696 -31.52225)
			(xy 199.063845 -31.483541) (xy 199.109203 -31.45109) (xy 199.158803 -31.425589) (xy 199.211587 -31.407582)
			(xy 199.26643 -31.397452) (xy 199.322164 -31.395415) (xy 199.377601 -31.401515) (xy 199.431558 -31.415621)
			(xy 199.482887 -31.437433) (xy 199.530493 -31.466487) (xy 199.573361 -31.502162) (xy 199.610578 -31.543699)
			(xy 199.641351 -31.590212) (xy 199.665023 -31.640709) (xy 199.681091 -31.694116) (xy 199.689211 -31.749292)
			(xy 199.68972 -31.777178) (xy 199.689211 -31.805064) (xy 199.681091 -31.86024) (xy 199.665023 -31.913647)
			(xy 199.641351 -31.964144) (xy 199.610578 -32.010657) (xy 199.573361 -32.052194) (xy 199.530493 -32.087869)
			(xy 199.482887 -32.116923) (xy 199.431558 -32.138735) (xy 199.377601 -32.152841) (xy 199.322164 -32.158941)
			(xy 199.26643 -32.156904) (xy 199.211587 -32.146774) (xy 199.158803 -32.128767) (xy 199.109203 -32.103266)
			(xy 199.063845 -32.070815) (xy 199.023696 -32.032106) (xy 198.98961 -31.987963) (xy 198.962314 -31.939328)
			(xy 198.942391 -31.887237) (xy 198.930265 -31.8328) (xy 198.926194 -31.777178) (xy 198.406977 -31.777178)
			(xy 198.399849 -31.800871) (xy 198.376177 -31.851368) (xy 198.345404 -31.897881) (xy 198.308187 -31.939418)
			(xy 198.265319 -31.975093) (xy 198.217713 -32.004147) (xy 198.166384 -32.025959) (xy 198.112427 -32.040065)
			(xy 198.05699 -32.046165) (xy 198.001256 -32.044128) (xy 197.946413 -32.033998) (xy 197.893629 -32.015991)
			(xy 197.844029 -31.99049) (xy 197.798671 -31.958039) (xy 197.758522 -31.91933) (xy 197.724436 -31.875187)
			(xy 197.69714 -31.826552) (xy 197.677217 -31.774461) (xy 197.665091 -31.720024) (xy 197.66102 -31.664402)
			(xy 197.144479 -31.664402) (xy 197.148449 -31.69138) (xy 197.148958 -31.719266) (xy 197.148449 -31.747152)
			(xy 197.140329 -31.802328) (xy 197.124261 -31.855735) (xy 197.100589 -31.906232) (xy 197.069816 -31.952745)
			(xy 197.032599 -31.994282) (xy 196.989731 -32.029957) (xy 196.942125 -32.059011) (xy 196.890796 -32.080823)
			(xy 196.836839 -32.094929) (xy 196.781402 -32.101029) (xy 196.725668 -32.098992) (xy 196.670825 -32.088862)
			(xy 196.618041 -32.070855) (xy 196.568441 -32.045354) (xy 196.523083 -32.012903) (xy 196.482934 -31.974194)
			(xy 196.448848 -31.930051) (xy 196.421552 -31.881416) (xy 196.401629 -31.829325) (xy 196.389503 -31.774888)
			(xy 196.385432 -31.719266) (xy 195.830505 -31.719266) (xy 195.813825 -31.754848) (xy 195.783052 -31.801361)
			(xy 195.745835 -31.842898) (xy 195.702967 -31.878573) (xy 195.655361 -31.907627) (xy 195.604032 -31.929439)
			(xy 195.550075 -31.943545) (xy 195.494638 -31.949645) (xy 195.438904 -31.947608) (xy 195.384061 -31.937478)
			(xy 195.331277 -31.919471) (xy 195.281677 -31.89397) (xy 195.236319 -31.861519) (xy 195.19617 -31.82281)
			(xy 195.162084 -31.778667) (xy 195.134788 -31.730032) (xy 195.114865 -31.677941) (xy 195.102739 -31.623504)
			(xy 195.098668 -31.567882) (xy 187.76465 -31.567882) (xy 187.786243 -31.596022) (xy 187.81621 -31.647928)
			(xy 187.839146 -31.703301) (xy 187.854659 -31.761194) (xy 187.862482 -31.820616) (xy 187.862972 -31.850584)
			(xy 187.862972 -32.714184) (xy 187.862839 -32.722312) (xy 202.706732 -32.722312) (xy 202.706732 -31.858712)
			(xy 202.707222 -31.828728) (xy 202.71505 -31.769272) (xy 202.730571 -31.711347) (xy 202.75352 -31.655943)
			(xy 202.783504 -31.604009) (xy 202.82001 -31.556433) (xy 202.862415 -31.514028) (xy 202.909991 -31.477522)
			(xy 202.961925 -31.447538) (xy 203.017329 -31.424589) (xy 203.075254 -31.409068) (xy 203.13471 -31.40124)
			(xy 203.194678 -31.40124) (xy 203.254134 -31.409068) (xy 203.312059 -31.424589) (xy 203.367463 -31.447538)
			(xy 203.419397 -31.477522) (xy 203.466973 -31.514028) (xy 203.509378 -31.556433) (xy 203.545884 -31.604009)
			(xy 203.575868 -31.655943) (xy 203.598817 -31.711347) (xy 203.614338 -31.769272) (xy 203.622166 -31.828728)
			(xy 203.622656 -31.858712) (xy 203.622656 -32.722312) (xy 203.622166 -32.752296) (xy 203.614338 -32.811752)
			(xy 203.598817 -32.869677) (xy 203.575868 -32.925081) (xy 203.545884 -32.977015) (xy 203.509378 -33.024591)
			(xy 203.466973 -33.066996) (xy 203.419397 -33.103502) (xy 203.367463 -33.133486) (xy 203.312059 -33.156435)
			(xy 203.254134 -33.171956) (xy 203.194678 -33.179784) (xy 203.13471 -33.179784) (xy 203.075254 -33.171956)
			(xy 203.017329 -33.156435) (xy 202.961925 -33.133486) (xy 202.909991 -33.103502) (xy 202.862415 -33.066996)
			(xy 202.82001 -33.024591) (xy 202.783504 -32.977015) (xy 202.75352 -32.925081) (xy 202.730571 -32.869677)
			(xy 202.71505 -32.811752) (xy 202.707222 -32.752296) (xy 202.706732 -32.722312) (xy 187.862839 -32.722312)
			(xy 187.862482 -32.744152) (xy 187.854659 -32.803574) (xy 187.839146 -32.861467) (xy 187.81621 -32.91684)
			(xy 187.786243 -32.968746) (xy 187.749756 -33.016296) (xy 187.707376 -33.058676) (xy 187.659826 -33.095163)
			(xy 187.60792 -33.12513) (xy 187.552547 -33.148066) (xy 187.494654 -33.163579) (xy 187.435232 -33.171402)
			(xy 187.375296 -33.171402) (xy 187.315874 -33.163579) (xy 187.257981 -33.148066) (xy 187.202608 -33.12513)
			(xy 187.150702 -33.095163) (xy 187.103152 -33.058676) (xy 187.060772 -33.016296) (xy 187.024285 -32.968746)
			(xy 186.994318 -32.91684) (xy 186.971382 -32.861467) (xy 186.955869 -32.803574) (xy 186.948046 -32.744152)
			(xy 186.947556 -32.714184) (xy 186.604656 -32.714184) (xy 186.604656 -34.520886) (xy 189.589664 -34.520886)
			(xy 189.589664 -33.657286) (xy 189.590154 -33.627318) (xy 189.597977 -33.567896) (xy 189.61349 -33.510003)
			(xy 189.636426 -33.45463) (xy 189.666393 -33.402724) (xy 189.70288 -33.355174) (xy 189.74526 -33.312794)
			(xy 189.79281 -33.276307) (xy 189.844716 -33.24634) (xy 189.900089 -33.223404) (xy 189.957982 -33.207891)
			(xy 190.017404 -33.200068) (xy 190.07734 -33.200068) (xy 190.136762 -33.207891) (xy 190.194655 -33.223404)
			(xy 190.250028 -33.24634) (xy 190.301934 -33.276307) (xy 190.349484 -33.312794) (xy 190.391864 -33.355174)
			(xy 190.428351 -33.402724) (xy 190.458318 -33.45463) (xy 190.481254 -33.510003) (xy 190.496767 -33.567896)
			(xy 190.50459 -33.627318) (xy 190.50508 -33.657286) (xy 190.50508 -34.520886) (xy 190.505055 -34.52241)
			(xy 200.852532 -34.52241) (xy 200.852532 -33.65881) (xy 200.853022 -33.628826) (xy 200.86085 -33.56937)
			(xy 200.876371 -33.511445) (xy 200.89932 -33.456041) (xy 200.929304 -33.404107) (xy 200.96581 -33.356531)
			(xy 201.008215 -33.314126) (xy 201.055791 -33.27762) (xy 201.107725 -33.247636) (xy 201.163129 -33.224687)
			(xy 201.221054 -33.209166) (xy 201.28051 -33.201338) (xy 201.340478 -33.201338) (xy 201.399934 -33.209166)
			(xy 201.457859 -33.224687) (xy 201.513263 -33.247636) (xy 201.565197 -33.27762) (xy 201.612773 -33.314126)
			(xy 201.655178 -33.356531) (xy 201.691684 -33.404107) (xy 201.721668 -33.456041) (xy 201.744617 -33.511445)
			(xy 201.760138 -33.56937) (xy 201.767966 -33.628826) (xy 201.768456 -33.65881) (xy 201.768456 -34.52241)
			(xy 201.767966 -34.552394) (xy 201.760138 -34.61185) (xy 201.744617 -34.669775) (xy 201.721668 -34.725179)
			(xy 201.691684 -34.777113) (xy 201.655178 -34.824689) (xy 201.612773 -34.867094) (xy 201.565197 -34.9036)
			(xy 201.513263 -34.933584) (xy 201.457859 -34.956533) (xy 201.399934 -34.972054) (xy 201.340478 -34.979882)
			(xy 201.28051 -34.979882) (xy 201.221054 -34.972054) (xy 201.163129 -34.956533) (xy 201.107725 -34.933584)
			(xy 201.055791 -34.9036) (xy 201.008215 -34.867094) (xy 200.96581 -34.824689) (xy 200.929304 -34.777113)
			(xy 200.89932 -34.725179) (xy 200.876371 -34.669775) (xy 200.86085 -34.61185) (xy 200.853022 -34.552394)
			(xy 200.852532 -34.52241) (xy 190.505055 -34.52241) (xy 190.50459 -34.550854) (xy 190.496767 -34.610276)
			(xy 190.481254 -34.668169) (xy 190.458318 -34.723542) (xy 190.428351 -34.775448) (xy 190.391864 -34.822998)
			(xy 190.349484 -34.865378) (xy 190.301934 -34.901865) (xy 190.250028 -34.931832) (xy 190.194655 -34.954768)
			(xy 190.136762 -34.970281) (xy 190.07734 -34.978104) (xy 190.017404 -34.978104) (xy 189.957982 -34.970281)
			(xy 189.900089 -34.954768) (xy 189.844716 -34.931832) (xy 189.79281 -34.901865) (xy 189.74526 -34.865378)
			(xy 189.70288 -34.822998) (xy 189.666393 -34.775448) (xy 189.636426 -34.723542) (xy 189.61349 -34.668169)
			(xy 189.597977 -34.610276) (xy 189.590154 -34.550854) (xy 189.589664 -34.520886) (xy 186.604656 -34.520886)
			(xy 186.604656 -35.264852) (xy 198.002396 -35.264852) (xy 198.006467 -35.20923) (xy 198.018593 -35.154793)
			(xy 198.038516 -35.102702) (xy 198.065812 -35.054067) (xy 198.099898 -35.009924) (xy 198.140047 -34.971215)
			(xy 198.185405 -34.938764) (xy 198.235005 -34.913263) (xy 198.287789 -34.895256) (xy 198.342632 -34.885126)
			(xy 198.398366 -34.883089) (xy 198.453803 -34.889189) (xy 198.50776 -34.903295) (xy 198.559089 -34.925107)
			(xy 198.606695 -34.954161) (xy 198.649563 -34.989836) (xy 198.68678 -35.031373) (xy 198.717553 -35.077886)
			(xy 198.741225 -35.128383) (xy 198.757293 -35.18179) (xy 198.765413 -35.236966) (xy 198.765922 -35.264852)
			(xy 198.765413 -35.292738) (xy 198.757293 -35.347914) (xy 198.741225 -35.401321) (xy 198.717553 -35.451818)
			(xy 198.68678 -35.498331) (xy 198.649563 -35.539868) (xy 198.606695 -35.575543) (xy 198.559089 -35.604597)
			(xy 198.50776 -35.626409) (xy 198.453803 -35.640515) (xy 198.398366 -35.646615) (xy 198.342632 -35.644578)
			(xy 198.287789 -35.634448) (xy 198.235005 -35.616441) (xy 198.185405 -35.59094) (xy 198.140047 -35.558489)
			(xy 198.099898 -35.51978) (xy 198.065812 -35.475637) (xy 198.038516 -35.427002) (xy 198.018593 -35.374911)
			(xy 198.006467 -35.320474) (xy 198.002396 -35.264852) (xy 186.604656 -35.264852) (xy 186.604656 -35.876738)
			(xy 186.817252 -35.876738) (xy 186.821323 -35.821116) (xy 186.833449 -35.766679) (xy 186.853372 -35.714588)
			(xy 186.880668 -35.665953) (xy 186.914754 -35.62181) (xy 186.954903 -35.583101) (xy 187.000261 -35.55065)
			(xy 187.049861 -35.525149) (xy 187.102645 -35.507142) (xy 187.157488 -35.497012) (xy 187.213222 -35.494975)
			(xy 187.268659 -35.501075) (xy 187.322616 -35.515181) (xy 187.373945 -35.536993) (xy 187.421551 -35.566047)
			(xy 187.464419 -35.601722) (xy 187.501636 -35.643259) (xy 187.532409 -35.689772) (xy 187.556081 -35.740269)
			(xy 187.572149 -35.793676) (xy 187.580269 -35.848852) (xy 187.580778 -35.876738) (xy 190.888872 -35.876738)
			(xy 190.892943 -35.821116) (xy 190.905069 -35.766679) (xy 190.924992 -35.714588) (xy 190.952288 -35.665953)
			(xy 190.986374 -35.62181) (xy 191.026523 -35.583101) (xy 191.071881 -35.55065) (xy 191.121481 -35.525149)
			(xy 191.174265 -35.507142) (xy 191.229108 -35.497012) (xy 191.284842 -35.494975) (xy 191.340279 -35.501075)
			(xy 191.394236 -35.515181) (xy 191.445565 -35.536993) (xy 191.493171 -35.566047) (xy 191.536039 -35.601722)
			(xy 191.573256 -35.643259) (xy 191.604029 -35.689772) (xy 191.627701 -35.740269) (xy 191.643769 -35.793676)
			(xy 191.651889 -35.848852) (xy 191.652398 -35.876738) (xy 191.651889 -35.904624) (xy 191.643769 -35.9598)
			(xy 191.627701 -36.013207) (xy 191.604029 -36.063704) (xy 191.573256 -36.110217) (xy 191.536039 -36.151754)
			(xy 191.493171 -36.187429) (xy 191.445565 -36.216483) (xy 191.394236 -36.238295) (xy 191.340279 -36.252401)
			(xy 191.284842 -36.258501) (xy 191.229108 -36.256464) (xy 191.174265 -36.246334) (xy 191.121481 -36.228327)
			(xy 191.071881 -36.202826) (xy 191.026523 -36.170375) (xy 190.986374 -36.131666) (xy 190.952288 -36.087523)
			(xy 190.924992 -36.038888) (xy 190.905069 -35.986797) (xy 190.892943 -35.93236) (xy 190.888872 -35.876738)
			(xy 187.580778 -35.876738) (xy 187.580269 -35.904624) (xy 187.572149 -35.9598) (xy 187.556081 -36.013207)
			(xy 187.532409 -36.063704) (xy 187.501636 -36.110217) (xy 187.464419 -36.151754) (xy 187.421551 -36.187429)
			(xy 187.373945 -36.216483) (xy 187.322616 -36.238295) (xy 187.268659 -36.252401) (xy 187.213222 -36.258501)
			(xy 187.157488 -36.256464) (xy 187.102645 -36.246334) (xy 187.049861 -36.228327) (xy 187.000261 -36.202826)
			(xy 186.954903 -36.170375) (xy 186.914754 -36.131666) (xy 186.880668 -36.087523) (xy 186.853372 -36.038888)
			(xy 186.833449 -35.986797) (xy 186.821323 -35.93236) (xy 186.817252 -35.876738) (xy 186.604656 -35.876738)
			(xy 186.604656 -35.880802) (xy 186.604189 -35.915414) (xy 186.596164 -35.984171) (xy 186.588654 -36.017962)
			(xy 186.587384 -36.026598) (xy 186.584784 -36.061755) (xy 186.572139 -36.13111) (xy 186.551202 -36.198428)
			(xy 186.522282 -36.262722) (xy 186.485802 -36.323049) (xy 186.442298 -36.378523) (xy 186.417712 -36.403788)
			(xy 186.31154 -36.50996) (xy 188.71387 -36.50996) (xy 188.717941 -36.454338) (xy 188.730067 -36.399901)
			(xy 188.74999 -36.34781) (xy 188.777286 -36.299175) (xy 188.811372 -36.255032) (xy 188.851521 -36.216323)
			(xy 188.896879 -36.183872) (xy 188.946479 -36.158371) (xy 188.999263 -36.140364) (xy 189.054106 -36.130234)
			(xy 189.10984 -36.128197) (xy 189.165277 -36.134297) (xy 189.219234 -36.148403) (xy 189.270563 -36.170215)
			(xy 189.318169 -36.199269) (xy 189.361037 -36.234944) (xy 189.398254 -36.276481) (xy 189.429027 -36.322994)
			(xy 189.452699 -36.373491) (xy 189.468767 -36.426898) (xy 189.472692 -36.453572) (xy 192.02857 -36.453572)
			(xy 192.032641 -36.39795) (xy 192.044767 -36.343513) (xy 192.06469 -36.291422) (xy 192.091986 -36.242787)
			(xy 192.126072 -36.198644) (xy 192.166221 -36.159935) (xy 192.211579 -36.127484) (xy 192.261179 -36.101983)
			(xy 192.313963 -36.083976) (xy 192.368806 -36.073846) (xy 192.42454 -36.071809) (xy 192.479977 -36.077909)
			(xy 192.533934 -36.092015) (xy 192.585263 -36.113827) (xy 192.632869 -36.142881) (xy 192.675737 -36.178556)
			(xy 192.712954 -36.220093) (xy 192.743727 -36.266606) (xy 192.753263 -36.286948) (xy 199.300336 -36.286948)
			(xy 199.304407 -36.231326) (xy 199.316533 -36.176889) (xy 199.336456 -36.124798) (xy 199.363752 -36.076163)
			(xy 199.397838 -36.03202) (xy 199.437987 -35.993311) (xy 199.483345 -35.96086) (xy 199.532945 -35.935359)
			(xy 199.585729 -35.917352) (xy 199.640572 -35.907222) (xy 199.696306 -35.905185) (xy 199.751743 -35.911285)
			(xy 199.8057 -35.925391) (xy 199.857029 -35.947203) (xy 199.904635 -35.976257) (xy 199.947503 -36.011932)
			(xy 199.98472 -36.053469) (xy 200.015493 -36.099982) (xy 200.039165 -36.150479) (xy 200.055233 -36.203886)
			(xy 200.063353 -36.259062) (xy 200.063862 -36.286948) (xy 200.063353 -36.314834) (xy 200.055233 -36.37001)
			(xy 200.039165 -36.423417) (xy 200.015493 -36.473914) (xy 199.987948 -36.515548) (xy 201.11415 -36.515548)
			(xy 201.118221 -36.459926) (xy 201.130347 -36.405489) (xy 201.15027 -36.353398) (xy 201.177566 -36.304763)
			(xy 201.211652 -36.26062) (xy 201.251801 -36.221911) (xy 201.297159 -36.18946) (xy 201.346759 -36.163959)
			(xy 201.399543 -36.145952) (xy 201.454386 -36.135822) (xy 201.51012 -36.133785) (xy 201.565557 -36.139885)
			(xy 201.619514 -36.153991) (xy 201.670843 -36.175803) (xy 201.718449 -36.204857) (xy 201.761317 -36.240532)
			(xy 201.798534 -36.282069) (xy 201.829307 -36.328582) (xy 201.852979 -36.379079) (xy 201.869047 -36.432486)
			(xy 201.877167 -36.487662) (xy 201.877676 -36.515548) (xy 201.877167 -36.543434) (xy 201.869047 -36.59861)
			(xy 201.86859 -36.60013) (xy 206.098655 -36.60013) (xy 206.102659 -36.512245) (xy 206.114639 -36.425088)
			(xy 206.134494 -36.339381) (xy 206.162061 -36.255836) (xy 206.197111 -36.175143) (xy 206.239353 -36.097971)
			(xy 206.288438 -36.024961) (xy 206.343959 -35.956717) (xy 206.405456 -35.893804) (xy 206.472418 -35.836744)
			(xy 206.544292 -35.78601) (xy 206.620482 -35.742022) (xy 206.700356 -35.705144) (xy 206.783253 -35.675683)
			(xy 206.868485 -35.653881) (xy 206.955347 -35.639921) (xy 207.043118 -35.633917) (xy 207.131072 -35.63592)
			(xy 207.218479 -35.645912) (xy 207.304615 -35.663812) (xy 207.388767 -35.68947) (xy 207.470237 -35.722674)
			(xy 207.54835 -35.763148) (xy 207.622458 -35.810559) (xy 207.691949 -35.864512) (xy 207.756245 -35.92456)
			(xy 207.814814 -35.990207) (xy 207.867171 -36.060907) (xy 207.912883 -36.136076) (xy 207.951569 -36.21509)
			(xy 207.98291 -36.297295) (xy 208.006645 -36.382009) (xy 208.022579 -36.46853) (xy 208.030579 -36.556142)
			(xy 208.03108 -36.60013) (xy 208.030579 -36.644118) (xy 208.022579 -36.73173) (xy 208.006645 -36.818251)
			(xy 207.98291 -36.902965) (xy 207.951569 -36.98517) (xy 207.912883 -37.064184) (xy 207.867171 -37.139353)
			(xy 207.814814 -37.210053) (xy 207.756245 -37.2757) (xy 207.691949 -37.335748) (xy 207.622458 -37.389701)
			(xy 207.54835 -37.437112) (xy 207.470237 -37.477586) (xy 207.388767 -37.51079) (xy 207.304615 -37.536448)
			(xy 207.218479 -37.554348) (xy 207.131072 -37.56434) (xy 207.043118 -37.566343) (xy 206.955347 -37.560339)
			(xy 206.868485 -37.546379) (xy 206.783253 -37.524577) (xy 206.700356 -37.495116) (xy 206.620482 -37.458238)
			(xy 206.544292 -37.41425) (xy 206.472418 -37.363516) (xy 206.405456 -37.306456) (xy 206.343959 -37.243543)
			(xy 206.288438 -37.175299) (xy 206.239353 -37.102289) (xy 206.197111 -37.025117) (xy 206.162061 -36.944424)
			(xy 206.134494 -36.860879) (xy 206.114639 -36.775172) (xy 206.102659 -36.688015) (xy 206.098655 -36.60013)
			(xy 201.86859 -36.60013) (xy 201.852979 -36.652017) (xy 201.829307 -36.702514) (xy 201.798534 -36.749027)
			(xy 201.761317 -36.790564) (xy 201.718449 -36.826239) (xy 201.670843 -36.855293) (xy 201.619514 -36.877105)
			(xy 201.565557 -36.891211) (xy 201.51012 -36.897311) (xy 201.454386 -36.895274) (xy 201.399543 -36.885144)
			(xy 201.346759 -36.867137) (xy 201.297159 -36.841636) (xy 201.251801 -36.809185) (xy 201.211652 -36.770476)
			(xy 201.177566 -36.726333) (xy 201.15027 -36.677698) (xy 201.130347 -36.625607) (xy 201.118221 -36.57117)
			(xy 201.11415 -36.515548) (xy 199.987948 -36.515548) (xy 199.98472 -36.520427) (xy 199.947503 -36.561964)
			(xy 199.904635 -36.597639) (xy 199.857029 -36.626693) (xy 199.8057 -36.648505) (xy 199.751743 -36.662611)
			(xy 199.696306 -36.668711) (xy 199.640572 -36.666674) (xy 199.585729 -36.656544) (xy 199.532945 -36.638537)
			(xy 199.483345 -36.613036) (xy 199.437987 -36.580585) (xy 199.397838 -36.541876) (xy 199.363752 -36.497733)
			(xy 199.336456 -36.449098) (xy 199.316533 -36.397007) (xy 199.304407 -36.34257) (xy 199.300336 -36.286948)
			(xy 192.753263 -36.286948) (xy 192.767399 -36.317103) (xy 192.783467 -36.37051) (xy 192.791587 -36.425686)
			(xy 192.792096 -36.453572) (xy 192.791587 -36.481458) (xy 192.783467 -36.536634) (xy 192.767399 -36.590041)
			(xy 192.743727 -36.640538) (xy 192.712954 -36.687051) (xy 192.675737 -36.728588) (xy 192.632869 -36.764263)
			(xy 192.585263 -36.793317) (xy 192.533934 -36.815129) (xy 192.479977 -36.829235) (xy 192.42454 -36.835335)
			(xy 192.368806 -36.833298) (xy 192.313963 -36.823168) (xy 192.261179 -36.805161) (xy 192.211579 -36.77966)
			(xy 192.166221 -36.747209) (xy 192.126072 -36.7085) (xy 192.091986 -36.664357) (xy 192.06469 -36.615722)
			(xy 192.044767 -36.563631) (xy 192.032641 -36.509194) (xy 192.02857 -36.453572) (xy 189.472692 -36.453572)
			(xy 189.476887 -36.482074) (xy 189.477396 -36.50996) (xy 189.476887 -36.537846) (xy 189.468767 -36.593022)
			(xy 189.452699 -36.646429) (xy 189.429027 -36.696926) (xy 189.398254 -36.743439) (xy 189.361037 -36.784976)
			(xy 189.318169 -36.820651) (xy 189.270563 -36.849705) (xy 189.219234 -36.871517) (xy 189.165277 -36.885623)
			(xy 189.10984 -36.891723) (xy 189.054106 -36.889686) (xy 188.999263 -36.879556) (xy 188.946479 -36.861549)
			(xy 188.896879 -36.836048) (xy 188.851521 -36.803597) (xy 188.811372 -36.764888) (xy 188.777286 -36.720745)
			(xy 188.74999 -36.67211) (xy 188.730067 -36.620019) (xy 188.717941 -36.565582) (xy 188.71387 -36.50996)
			(xy 186.31154 -36.50996) (xy 186.104784 -36.716716) (xy 185.86069 -36.960556) (xy 185.855356 -36.966906)
			(xy 185.855356 -37.120576) (xy 185.85561 -37.12083) (xy 185.860436 -37.127434) (xy 185.868818 -37.133784)
			(xy 185.917078 -37.157914) (xy 185.917586 -37.157914) (xy 185.954416 -37.175948) (xy 185.959214 -37.178161)
			(xy 185.969461 -37.180729) (xy 185.974736 -37.181028) (xy 185.984642 -37.181282) (xy 186.003184 -37.17417)
			(xy 186.009026 -37.169852) (xy 186.029124 -37.155074) (xy 186.072417 -37.130286) (xy 186.118559 -37.111322)
			(xy 186.166771 -37.098503) (xy 186.216238 -37.092043) (xy 186.241182 -37.09162) (xy 186.268584 -37.092084)
			(xy 186.32283 -37.099881) (xy 186.375414 -37.115319) (xy 186.425265 -37.138084) (xy 186.47137 -37.167711)
			(xy 186.512788 -37.203599) (xy 186.548678 -37.245016) (xy 186.578308 -37.291119) (xy 186.601074 -37.340969)
			(xy 186.616515 -37.393553) (xy 186.624314 -37.447798) (xy 186.624314 -37.502602) (xy 186.616515 -37.556847)
			(xy 186.601074 -37.609431) (xy 186.578308 -37.659281) (xy 186.57633 -37.662358) (xy 188.04839 -37.662358)
			(xy 188.052461 -37.606736) (xy 188.064587 -37.552299) (xy 188.08451 -37.500208) (xy 188.111806 -37.451573)
			(xy 188.145892 -37.40743) (xy 188.186041 -37.368721) (xy 188.231399 -37.33627) (xy 188.280999 -37.310769)
			(xy 188.333783 -37.292762) (xy 188.388626 -37.282632) (xy 188.44436 -37.280595) (xy 188.499797 -37.286695)
			(xy 188.553754 -37.300801) (xy 188.605083 -37.322613) (xy 188.652689 -37.351667) (xy 188.695557 -37.387342)
			(xy 188.732774 -37.428879) (xy 188.763547 -37.475392) (xy 188.787219 -37.525889) (xy 188.803287 -37.579296)
			(xy 188.811407 -37.634472) (xy 188.811916 -37.662358) (xy 188.811407 -37.690244) (xy 188.803287 -37.74542)
			(xy 188.794653 -37.774118) (xy 199.56475 -37.774118) (xy 199.568821 -37.718496) (xy 199.580947 -37.664059)
			(xy 199.60087 -37.611968) (xy 199.628166 -37.563333) (xy 199.662252 -37.51919) (xy 199.702401 -37.480481)
			(xy 199.747759 -37.44803) (xy 199.797359 -37.422529) (xy 199.850143 -37.404522) (xy 199.904986 -37.394392)
			(xy 199.96072 -37.392355) (xy 200.016157 -37.398455) (xy 200.070114 -37.412561) (xy 200.121443 -37.434373)
			(xy 200.169049 -37.463427) (xy 200.211917 -37.499102) (xy 200.249134 -37.540639) (xy 200.279907 -37.587152)
			(xy 200.303579 -37.637649) (xy 200.319647 -37.691056) (xy 200.327767 -37.746232) (xy 200.328276 -37.774118)
			(xy 200.327767 -37.802004) (xy 200.319647 -37.85718) (xy 200.303579 -37.910587) (xy 200.279907 -37.961084)
			(xy 200.249134 -38.007597) (xy 200.211917 -38.049134) (xy 200.169049 -38.084809) (xy 200.121443 -38.113863)
			(xy 200.070114 -38.135675) (xy 200.016157 -38.149781) (xy 199.96072 -38.155881) (xy 199.904986 -38.153844)
			(xy 199.850143 -38.143714) (xy 199.797359 -38.125707) (xy 199.747759 -38.100206) (xy 199.702401 -38.067755)
			(xy 199.662252 -38.029046) (xy 199.628166 -37.984903) (xy 199.60087 -37.936268) (xy 199.580947 -37.884177)
			(xy 199.568821 -37.82974) (xy 199.56475 -37.774118) (xy 188.794653 -37.774118) (xy 188.787219 -37.798827)
			(xy 188.763547 -37.849324) (xy 188.732774 -37.895837) (xy 188.695557 -37.937374) (xy 188.652689 -37.973049)
			(xy 188.605083 -38.002103) (xy 188.553754 -38.023915) (xy 188.499797 -38.038021) (xy 188.44436 -38.044121)
			(xy 188.388626 -38.042084) (xy 188.333783 -38.031954) (xy 188.280999 -38.013947) (xy 188.231399 -37.988446)
			(xy 188.186041 -37.955995) (xy 188.145892 -37.917286) (xy 188.111806 -37.873143) (xy 188.08451 -37.824508)
			(xy 188.064587 -37.772417) (xy 188.052461 -37.71798) (xy 188.04839 -37.662358) (xy 186.57633 -37.662358)
			(xy 186.548678 -37.705384) (xy 186.512788 -37.746801) (xy 186.47137 -37.782689) (xy 186.425265 -37.812316)
			(xy 186.375414 -37.835081) (xy 186.32283 -37.850519) (xy 186.268584 -37.858316) (xy 186.241182 -37.8587)
			(xy 186.216137 -37.858273) (xy 186.166479 -37.851714) (xy 186.118096 -37.838749) (xy 186.071812 -37.819598)
			(xy 186.028413 -37.794587) (xy 186.008264 -37.779706) (xy 186.00801 -37.779452) (xy 186.007502 -37.779198)
			(xy 185.999785 -37.773936) (xy 185.981839 -37.768812) (xy 185.963245 -37.770417) (xy 185.95467 -37.774118)
			(xy 185.951622 -37.775642) (xy 185.927492 -37.78758) (xy 185.926984 -37.78758) (xy 185.873898 -37.813742)
			(xy 185.868427 -37.816743) (xy 185.859052 -37.824971) (xy 185.855356 -37.829998) (xy 185.855356 -38.098984)
			(xy 185.854876 -38.132146) (xy 185.847422 -38.19805) (xy 185.832639 -38.262706) (xy 185.810714 -38.325302)
			(xy 185.781921 -38.38505) (xy 185.746622 -38.441201) (xy 185.705262 -38.493049) (xy 185.682128 -38.516814)
			(xy 185.46901 -38.729948) (xy 191.80102 -38.729948) (xy 191.80102 -38.675452) (xy 191.808775 -38.621512)
			(xy 191.824128 -38.569224) (xy 191.846766 -38.519653) (xy 191.876228 -38.473808) (xy 191.911914 -38.432623)
			(xy 191.953098 -38.396935) (xy 191.998942 -38.367472) (xy 192.048512 -38.344832) (xy 192.1008 -38.329478)
			(xy 192.15474 -38.321721) (xy 192.181988 -38.321234) (xy 192.210293 -38.321717) (xy 192.266282 -38.330068)
			(xy 192.320422 -38.346604) (xy 192.371523 -38.37096) (xy 192.418463 -38.402602) (xy 192.46021 -38.440834)
			(xy 192.495847 -38.484818) (xy 192.510664 -38.50894) (xy 192.518212 -38.521009) (xy 192.538841 -38.540613)
			(xy 192.564084 -38.553754) (xy 192.591975 -38.55941) (xy 192.620342 -38.557139) (xy 192.646979 -38.547119)
			(xy 192.669809 -38.53013) (xy 192.678812 -38.5191) (xy 192.696997 -38.496222) (xy 192.73916 -38.455758)
			(xy 192.786996 -38.422191) (xy 192.839388 -38.396304) (xy 192.895113 -38.378703) (xy 192.952869 -38.369797)
			(xy 192.982088 -38.36924) (xy 193.009345 -38.369606) (xy 193.063304 -38.377363) (xy 193.11561 -38.39272)
			(xy 193.165198 -38.415364) (xy 193.211058 -38.444836) (xy 193.252258 -38.480534) (xy 193.287957 -38.521732)
			(xy 193.31743 -38.567592) (xy 193.340076 -38.617179) (xy 193.355435 -38.669484) (xy 193.363193 -38.723443)
			(xy 193.363193 -38.777957) (xy 193.355435 -38.831916) (xy 193.340076 -38.884221) (xy 193.31743 -38.933808)
			(xy 193.287957 -38.979668) (xy 193.252258 -39.020866) (xy 193.211058 -39.056564) (xy 193.165198 -39.086036)
			(xy 193.11561 -39.10868) (xy 193.063304 -39.124037) (xy 193.009345 -39.131794) (xy 192.982088 -39.132256)
			(xy 192.953785 -39.131718) (xy 192.897798 -39.123377) (xy 192.843659 -39.106852) (xy 192.792558 -39.082505)
			(xy 192.745617 -39.050872) (xy 192.703869 -39.012646) (xy 192.66823 -38.968669) (xy 192.653412 -38.94455)
			(xy 192.645765 -38.93255) (xy 192.625156 -38.912952) (xy 192.599935 -38.89981) (xy 192.572064 -38.894147)
			(xy 192.543714 -38.896404) (xy 192.517091 -38.906405) (xy 192.494266 -38.923372) (xy 192.485264 -38.93439)
			(xy 192.467091 -38.957277) (xy 192.424925 -38.997741) (xy 192.377087 -39.031307) (xy 192.324693 -39.057193)
			(xy 192.268966 -39.074792) (xy 192.211208 -39.083695) (xy 192.181988 -39.08425) (xy 192.15474 -39.083679)
			(xy 192.1008 -39.075922) (xy 192.048512 -39.060568) (xy 191.998942 -39.037928) (xy 191.953098 -39.008465)
			(xy 191.911914 -38.972777) (xy 191.876228 -38.931592) (xy 191.846766 -38.885747) (xy 191.824128 -38.836176)
			(xy 191.808775 -38.783888) (xy 191.80102 -38.729948) (xy 185.46901 -38.729948) (xy 184.227069 -39.97198)
			(xy 193.9958 -39.97198) (xy 193.999871 -39.916358) (xy 194.011997 -39.861921) (xy 194.03192 -39.80983)
			(xy 194.059216 -39.761195) (xy 194.093302 -39.717052) (xy 194.133451 -39.678343) (xy 194.178809 -39.645892)
			(xy 194.228409 -39.620391) (xy 194.281193 -39.602384) (xy 194.336036 -39.592254) (xy 194.39177 -39.590217)
			(xy 194.447207 -39.596317) (xy 194.501164 -39.610423) (xy 194.552493 -39.632235) (xy 194.600099 -39.661289)
			(xy 194.642967 -39.696964) (xy 194.680184 -39.738501) (xy 194.710957 -39.785014) (xy 194.734629 -39.835511)
			(xy 194.750697 -39.888918) (xy 194.758817 -39.944094) (xy 194.759326 -39.97198) (xy 194.758817 -39.999866)
			(xy 194.750697 -40.055042) (xy 194.734629 -40.108449) (xy 194.710957 -40.158946) (xy 194.680184 -40.205459)
			(xy 194.642967 -40.246996) (xy 194.600099 -40.282671) (xy 194.552493 -40.311725) (xy 194.501164 -40.333537)
			(xy 194.447207 -40.347643) (xy 194.39177 -40.353743) (xy 194.336036 -40.351706) (xy 194.281193 -40.341576)
			(xy 194.228409 -40.323569) (xy 194.178809 -40.298068) (xy 194.133451 -40.265617) (xy 194.093302 -40.226908)
			(xy 194.059216 -40.182765) (xy 194.03192 -40.13413) (xy 194.011997 -40.082039) (xy 193.999871 -40.027602)
			(xy 193.9958 -39.97198) (xy 184.227069 -39.97198) (xy 182.93039 -41.268755) (xy 183.943927 -41.268755)
			(xy 183.943927 -41.214245) (xy 183.951685 -41.160289) (xy 183.967042 -41.107987) (xy 183.989687 -41.058403)
			(xy 184.019157 -41.012546) (xy 184.054854 -40.97135) (xy 184.096051 -40.935654) (xy 184.141908 -40.906184)
			(xy 184.191493 -40.88354) (xy 184.243795 -40.868183) (xy 184.297751 -40.860427) (xy 184.325006 -40.859964)
			(xy 184.353745 -40.860494) (xy 184.410571 -40.869116) (xy 184.465462 -40.886166) (xy 184.517173 -40.911255)
			(xy 184.564537 -40.943818) (xy 184.585864 -40.963088) (xy 184.592722 -40.969692) (xy 184.610756 -40.976804)
			(xy 184.699656 -40.976804) (xy 184.71769 -40.969692) (xy 184.724548 -40.963088) (xy 184.74588 -40.943823)
			(xy 184.79324 -40.911254) (xy 184.84495 -40.886159) (xy 184.89984 -40.869108) (xy 184.956667 -40.860485)
			(xy 184.985406 -40.859964) (xy 185.012655 -40.860507) (xy 185.066598 -40.868263) (xy 185.118888 -40.883618)
			(xy 185.168461 -40.906258) (xy 185.214307 -40.935722) (xy 185.255494 -40.971411) (xy 185.291182 -41.012598)
			(xy 185.320645 -41.058444) (xy 185.343284 -41.108017) (xy 185.358638 -41.160308) (xy 185.366394 -41.214251)
			(xy 185.366394 -41.268749) (xy 185.358638 -41.322692) (xy 185.343284 -41.374983) (xy 185.320645 -41.424556)
			(xy 185.291182 -41.470402) (xy 185.255494 -41.511589) (xy 185.214307 -41.547278) (xy 185.168461 -41.576742)
			(xy 185.118888 -41.599382) (xy 185.066598 -41.614737) (xy 185.012655 -41.622493) (xy 184.985406 -41.62298)
			(xy 184.956668 -41.622431) (xy 184.899843 -41.613811) (xy 184.844953 -41.596766) (xy 184.793241 -41.571681)
			(xy 184.745877 -41.539123) (xy 184.724548 -41.519856) (xy 184.71769 -41.513252) (xy 184.699656 -41.50614)
			(xy 184.610756 -41.50614) (xy 184.592722 -41.513252) (xy 184.585864 -41.519856) (xy 184.564534 -41.539123)
			(xy 184.517173 -41.57169) (xy 184.465462 -41.596783) (xy 184.410572 -41.613835) (xy 184.353745 -41.622459)
			(xy 184.325006 -41.62298) (xy 184.297751 -41.622573) (xy 184.243795 -41.614817) (xy 184.191493 -41.59946)
			(xy 184.141908 -41.576816) (xy 184.096051 -41.547346) (xy 184.054854 -41.51165) (xy 184.019157 -41.470454)
			(xy 183.989687 -41.424597) (xy 183.967042 -41.375013) (xy 183.951685 -41.322711) (xy 183.943927 -41.268755)
			(xy 182.93039 -41.268755) (xy 182.233062 -41.966134) (xy 182.223156 -41.975786) (xy 182.22214 -41.976802)
			(xy 180.89372 -43.305222) (xy 186.407298 -43.305222) (xy 186.407777 -43.277852) (xy 186.415592 -43.223674)
			(xy 186.431078 -43.171171) (xy 186.453917 -43.121424) (xy 186.483638 -43.075456) (xy 186.501278 -43.054524)
			(xy 186.501532 -43.05427) (xy 186.507099 -43.04717) (xy 186.513356 -43.030263) (xy 186.513724 -43.02125)
			(xy 186.513724 -42.954194) (xy 186.513364 -42.945178) (xy 186.507118 -42.928261) (xy 186.501532 -42.921174)
			(xy 186.501278 -42.921174) (xy 186.501278 -42.92092) (xy 186.483631 -42.899994) (xy 186.453921 -42.854019)
			(xy 186.431087 -42.80427) (xy 186.415598 -42.751768) (xy 186.407771 -42.697592) (xy 186.407298 -42.670222)
			(xy 186.407836 -42.641484) (xy 186.416455 -42.584657) (xy 186.433502 -42.529766) (xy 186.45859 -42.478054)
			(xy 186.491153 -42.430691) (xy 186.510422 -42.409364) (xy 186.517026 -42.402506) (xy 186.524138 -42.384472)
			(xy 186.524138 -42.295572) (xy 186.517026 -42.277538) (xy 186.510422 -42.27068) (xy 186.491173 -42.249334)
			(xy 186.458607 -42.201975) (xy 186.433515 -42.150266) (xy 186.416463 -42.095378) (xy 186.407838 -42.038554)
			(xy 186.407836 -41.981078) (xy 186.416456 -41.924253) (xy 186.433503 -41.869364) (xy 186.458591 -41.817653)
			(xy 186.491153 -41.770291) (xy 186.510422 -41.748964) (xy 186.517026 -41.742106) (xy 186.524138 -41.724072)
			(xy 186.524138 -41.635172) (xy 186.517026 -41.617138) (xy 186.510422 -41.61028) (xy 186.491159 -41.588946)
			(xy 186.458592 -41.541586) (xy 186.433499 -41.489876) (xy 186.416446 -41.434987) (xy 186.407821 -41.37816)
			(xy 186.407298 -41.349422) (xy 186.407784 -41.322171) (xy 186.41554 -41.268223) (xy 186.430895 -41.215928)
			(xy 186.453537 -41.166351) (xy 186.483003 -41.120501) (xy 186.518694 -41.07931) (xy 186.559885 -41.043619)
			(xy 186.605735 -41.014153) (xy 186.655312 -40.991511) (xy 186.707607 -40.976156) (xy 186.761555 -40.9684)
			(xy 186.816057 -40.9684) (xy 186.839178 -40.971724) (xy 194.694046 -40.971724) (xy 194.698117 -40.916102)
			(xy 194.710243 -40.861665) (xy 194.730166 -40.809574) (xy 194.757462 -40.760939) (xy 194.791548 -40.716796)
			(xy 194.831697 -40.678087) (xy 194.877055 -40.645636) (xy 194.926655 -40.620135) (xy 194.979439 -40.602128)
			(xy 195.034282 -40.591998) (xy 195.090016 -40.589961) (xy 195.145453 -40.596061) (xy 195.19941 -40.610167)
			(xy 195.250739 -40.631979) (xy 195.298345 -40.661033) (xy 195.341213 -40.696708) (xy 195.37843 -40.738245)
			(xy 195.409203 -40.784758) (xy 195.432875 -40.835255) (xy 195.448943 -40.888662) (xy 195.457063 -40.943838)
			(xy 195.457572 -40.971724) (xy 195.457063 -40.99961) (xy 195.448943 -41.054786) (xy 195.432875 -41.108193)
			(xy 195.409203 -41.15869) (xy 195.37843 -41.205203) (xy 195.341213 -41.24674) (xy 195.298345 -41.282415)
			(xy 195.250739 -41.311469) (xy 195.19941 -41.333281) (xy 195.145453 -41.347387) (xy 195.090016 -41.353487)
			(xy 195.034282 -41.35145) (xy 194.979439 -41.34132) (xy 194.926655 -41.323313) (xy 194.877055 -41.297812)
			(xy 194.831697 -41.265361) (xy 194.791548 -41.226652) (xy 194.757462 -41.182509) (xy 194.730166 -41.133874)
			(xy 194.710243 -41.081783) (xy 194.698117 -41.027346) (xy 194.694046 -40.971724) (xy 186.839178 -40.971724)
			(xy 186.870005 -40.976156) (xy 186.9223 -40.991511) (xy 186.971877 -41.014153) (xy 187.017727 -41.043619)
			(xy 187.058918 -41.07931) (xy 187.094609 -41.120501) (xy 187.124075 -41.166351) (xy 187.146717 -41.215928)
			(xy 187.162072 -41.268223) (xy 187.169828 -41.322171) (xy 187.170314 -41.349422) (xy 187.1698 -41.378161)
			(xy 187.161174 -41.434989) (xy 187.144122 -41.48988) (xy 187.119028 -41.541591) (xy 187.086461 -41.588953)
			(xy 187.06719 -41.61028) (xy 187.060586 -41.617138) (xy 187.053474 -41.635172) (xy 187.053474 -41.724072)
			(xy 187.060586 -41.742106) (xy 187.06719 -41.748964) (xy 187.086482 -41.770272) (xy 187.119045 -41.817638)
			(xy 187.144135 -41.869353) (xy 187.161183 -41.924247) (xy 187.169803 -41.981076) (xy 187.1698 -42.038556)
			(xy 187.161175 -42.095385) (xy 187.144123 -42.150277) (xy 187.119029 -42.20199) (xy 187.086462 -42.249353)
			(xy 187.06719 -42.27068) (xy 187.060586 -42.277538) (xy 187.053474 -42.295572) (xy 187.053474 -42.384472)
			(xy 187.060586 -42.402506) (xy 187.06719 -42.409364) (xy 187.086476 -42.430678) (xy 187.119039 -42.478044)
			(xy 187.144128 -42.529759) (xy 187.161175 -42.584653) (xy 187.169795 -42.641482) (xy 187.170314 -42.670222)
			(xy 187.169857 -42.697593) (xy 187.162037 -42.751772) (xy 187.146545 -42.804275) (xy 187.125991 -42.849038)
			(xy 188.992 -42.849038) (xy 188.996071 -42.793416) (xy 189.008197 -42.738979) (xy 189.02812 -42.686888)
			(xy 189.055416 -42.638253) (xy 189.089502 -42.59411) (xy 189.129651 -42.555401) (xy 189.175009 -42.52295)
			(xy 189.224609 -42.497449) (xy 189.277393 -42.479442) (xy 189.332236 -42.469312) (xy 189.38797 -42.467275)
			(xy 189.443407 -42.473375) (xy 189.497364 -42.487481) (xy 189.548693 -42.509293) (xy 189.596299 -42.538347)
			(xy 189.639167 -42.574022) (xy 189.676384 -42.615559) (xy 189.707157 -42.662072) (xy 189.730829 -42.712569)
			(xy 189.746897 -42.765976) (xy 189.755017 -42.821152) (xy 189.755378 -42.84091) (xy 195.033136 -42.84091)
			(xy 195.037207 -42.785288) (xy 195.049333 -42.730851) (xy 195.069256 -42.67876) (xy 195.096552 -42.630125)
			(xy 195.130638 -42.585982) (xy 195.170787 -42.547273) (xy 195.216145 -42.514822) (xy 195.265745 -42.489321)
			(xy 195.318529 -42.471314) (xy 195.373372 -42.461184) (xy 195.429106 -42.459147) (xy 195.484543 -42.465247)
			(xy 195.5385 -42.479353) (xy 195.589829 -42.501165) (xy 195.637435 -42.530219) (xy 195.680303 -42.565894)
			(xy 195.71752 -42.607431) (xy 195.748293 -42.653944) (xy 195.771965 -42.704441) (xy 195.788033 -42.757848)
			(xy 195.796153 -42.813024) (xy 195.796662 -42.84091) (xy 195.796153 -42.868796) (xy 195.788033 -42.923972)
			(xy 195.771965 -42.977379) (xy 195.748293 -43.027876) (xy 195.71752 -43.074389) (xy 195.680303 -43.115926)
			(xy 195.637435 -43.151601) (xy 195.589829 -43.180655) (xy 195.5385 -43.202467) (xy 195.484543 -43.216573)
			(xy 195.429106 -43.222673) (xy 195.373372 -43.220636) (xy 195.318529 -43.210506) (xy 195.265745 -43.192499)
			(xy 195.216145 -43.166998) (xy 195.170787 -43.134547) (xy 195.130638 -43.095838) (xy 195.096552 -43.051695)
			(xy 195.069256 -43.00306) (xy 195.049333 -42.950969) (xy 195.037207 -42.896532) (xy 195.033136 -42.84091)
			(xy 189.755378 -42.84091) (xy 189.755526 -42.849038) (xy 189.755017 -42.876924) (xy 189.746897 -42.9321)
			(xy 189.730829 -42.985507) (xy 189.707157 -43.036004) (xy 189.676384 -43.082517) (xy 189.639167 -43.124054)
			(xy 189.596299 -43.159729) (xy 189.548693 -43.188783) (xy 189.497364 -43.210595) (xy 189.443407 -43.224701)
			(xy 189.38797 -43.230801) (xy 189.332236 -43.228764) (xy 189.277393 -43.218634) (xy 189.224609 -43.200627)
			(xy 189.175009 -43.175126) (xy 189.129651 -43.142675) (xy 189.089502 -43.103966) (xy 189.055416 -43.059823)
			(xy 189.02812 -43.011188) (xy 189.008197 -42.959097) (xy 188.996071 -42.90466) (xy 188.992 -42.849038)
			(xy 187.125991 -42.849038) (xy 187.123702 -42.854022) (xy 187.093976 -42.899988) (xy 187.076334 -42.92092)
			(xy 187.07608 -42.921174) (xy 187.070496 -42.928262) (xy 187.064248 -42.945178) (xy 187.063888 -42.954194)
			(xy 187.063888 -43.02125) (xy 187.064271 -43.030264) (xy 187.070501 -43.047181) (xy 187.07608 -43.05427)
			(xy 187.076334 -43.05427) (xy 187.076334 -43.054524) (xy 187.093956 -43.07547) (xy 187.123669 -43.121439)
			(xy 187.146508 -43.171183) (xy 187.162003 -43.223681) (xy 187.169837 -43.277854) (xy 187.170314 -43.305222)
			(xy 187.169828 -43.332473) (xy 187.162072 -43.386421) (xy 187.146717 -43.438716) (xy 187.124075 -43.488293)
			(xy 187.094609 -43.534143) (xy 187.058918 -43.575334) (xy 187.017727 -43.611025) (xy 186.971877 -43.640491)
			(xy 186.9223 -43.663133) (xy 186.870005 -43.678488) (xy 186.816057 -43.686244) (xy 186.761555 -43.686244)
			(xy 186.707607 -43.678488) (xy 186.655312 -43.663133) (xy 186.605735 -43.640491) (xy 186.559885 -43.611025)
			(xy 186.518694 -43.575334) (xy 186.483003 -43.534143) (xy 186.453537 -43.488293) (xy 186.430895 -43.438716)
			(xy 186.41554 -43.386421) (xy 186.407784 -43.332473) (xy 186.407298 -43.305222) (xy 180.89372 -43.305222)
			(xy 180.6956 -43.503342) (xy 180.69231 -43.50682) (xy 180.686935 -43.514742) (xy 180.684932 -43.51909)
			(xy 180.590582 -43.73626) (xy 188.313058 -43.73626) (xy 188.317129 -43.680638) (xy 188.329255 -43.626201)
			(xy 188.349178 -43.57411) (xy 188.376474 -43.525475) (xy 188.41056 -43.481332) (xy 188.450709 -43.442623)
			(xy 188.496067 -43.410172) (xy 188.545667 -43.384671) (xy 188.598451 -43.366664) (xy 188.653294 -43.356534)
			(xy 188.709028 -43.354497) (xy 188.764465 -43.360597) (xy 188.818422 -43.374703) (xy 188.869751 -43.396515)
			(xy 188.917357 -43.425569) (xy 188.960225 -43.461244) (xy 188.997442 -43.502781) (xy 189.028215 -43.549294)
			(xy 189.051887 -43.599791) (xy 189.067955 -43.653198) (xy 189.076075 -43.708374) (xy 189.076584 -43.73626)
			(xy 189.076075 -43.764146) (xy 189.067955 -43.819322) (xy 189.056646 -43.85691) (xy 192.81978 -43.85691)
			(xy 192.823851 -43.801288) (xy 192.835977 -43.746851) (xy 192.8559 -43.69476) (xy 192.883196 -43.646125)
			(xy 192.917282 -43.601982) (xy 192.957431 -43.563273) (xy 193.002789 -43.530822) (xy 193.052389 -43.505321)
			(xy 193.105173 -43.487314) (xy 193.160016 -43.477184) (xy 193.21575 -43.475147) (xy 193.271187 -43.481247)
			(xy 193.325144 -43.495353) (xy 193.376473 -43.517165) (xy 193.424079 -43.546219) (xy 193.466947 -43.581894)
			(xy 193.504164 -43.623431) (xy 193.534937 -43.669944) (xy 193.558609 -43.720441) (xy 193.574677 -43.773848)
			(xy 193.582797 -43.829024) (xy 193.583306 -43.85691) (xy 193.582797 -43.884796) (xy 193.574677 -43.939972)
			(xy 193.558609 -43.993379) (xy 193.534937 -44.043876) (xy 193.504164 -44.090389) (xy 193.466947 -44.131926)
			(xy 193.424079 -44.167601) (xy 193.376473 -44.196655) (xy 193.325144 -44.218467) (xy 193.271187 -44.232573)
			(xy 193.21575 -44.238673) (xy 193.160016 -44.236636) (xy 193.105173 -44.226506) (xy 193.052389 -44.208499)
			(xy 193.002789 -44.182998) (xy 192.957431 -44.150547) (xy 192.917282 -44.111838) (xy 192.883196 -44.067695)
			(xy 192.8559 -44.01906) (xy 192.835977 -43.966969) (xy 192.823851 -43.912532) (xy 192.81978 -43.85691)
			(xy 189.056646 -43.85691) (xy 189.051887 -43.872729) (xy 189.028215 -43.923226) (xy 188.997442 -43.969739)
			(xy 188.960225 -44.011276) (xy 188.917357 -44.046951) (xy 188.869751 -44.076005) (xy 188.818422 -44.097817)
			(xy 188.764465 -44.111923) (xy 188.709028 -44.118023) (xy 188.653294 -44.115986) (xy 188.598451 -44.105856)
			(xy 188.545667 -44.087849) (xy 188.496067 -44.062348) (xy 188.450709 -44.029897) (xy 188.41056 -43.991188)
			(xy 188.376474 -43.947045) (xy 188.349178 -43.89841) (xy 188.329255 -43.846319) (xy 188.317129 -43.791882)
			(xy 188.313058 -43.73626) (xy 180.590582 -43.73626) (xy 180.424836 -44.117768) (xy 180.423044 -44.122199)
			(xy 180.421 -44.131535) (xy 180.420772 -44.13631) (xy 180.387299 -45.114464) (xy 188.165484 -45.114464)
			(xy 188.169555 -45.058842) (xy 188.181681 -45.004405) (xy 188.201604 -44.952314) (xy 188.2289 -44.903679)
			(xy 188.262986 -44.859536) (xy 188.303135 -44.820827) (xy 188.348493 -44.788376) (xy 188.398093 -44.762875)
			(xy 188.450877 -44.744868) (xy 188.50572 -44.734738) (xy 188.561454 -44.732701) (xy 188.616891 -44.738801)
			(xy 188.670848 -44.752907) (xy 188.722177 -44.774719) (xy 188.769783 -44.803773) (xy 188.812651 -44.839448)
			(xy 188.842633 -44.87291) (xy 195.033136 -44.87291) (xy 195.037207 -44.817288) (xy 195.049333 -44.762851)
			(xy 195.069256 -44.71076) (xy 195.096552 -44.662125) (xy 195.130638 -44.617982) (xy 195.170787 -44.579273)
			(xy 195.216145 -44.546822) (xy 195.265745 -44.521321) (xy 195.318529 -44.503314) (xy 195.373372 -44.493184)
			(xy 195.429106 -44.491147) (xy 195.484543 -44.497247) (xy 195.5385 -44.511353) (xy 195.589829 -44.533165)
			(xy 195.637435 -44.562219) (xy 195.680303 -44.597894) (xy 195.71752 -44.639431) (xy 195.748293 -44.685944)
			(xy 195.771965 -44.736441) (xy 195.788033 -44.789848) (xy 195.796153 -44.845024) (xy 195.796662 -44.87291)
			(xy 195.796153 -44.900796) (xy 195.788033 -44.955972) (xy 195.771965 -45.009379) (xy 195.748293 -45.059876)
			(xy 195.71752 -45.106389) (xy 195.680303 -45.147926) (xy 195.637435 -45.183601) (xy 195.589829 -45.212655)
			(xy 195.5385 -45.234467) (xy 195.484543 -45.248573) (xy 195.429106 -45.254673) (xy 195.373372 -45.252636)
			(xy 195.318529 -45.242506) (xy 195.265745 -45.224499) (xy 195.216145 -45.198998) (xy 195.170787 -45.166547)
			(xy 195.130638 -45.127838) (xy 195.096552 -45.083695) (xy 195.069256 -45.03506) (xy 195.049333 -44.982969)
			(xy 195.037207 -44.928532) (xy 195.033136 -44.87291) (xy 188.842633 -44.87291) (xy 188.849868 -44.880985)
			(xy 188.880641 -44.927498) (xy 188.904313 -44.977995) (xy 188.920381 -45.031402) (xy 188.928501 -45.086578)
			(xy 188.92901 -45.114464) (xy 188.928501 -45.14235) (xy 188.920381 -45.197526) (xy 188.904313 -45.250933)
			(xy 188.880641 -45.30143) (xy 188.849868 -45.347943) (xy 188.844226 -45.35424) (xy 192.803778 -45.35424)
			(xy 192.807849 -45.298618) (xy 192.819975 -45.244181) (xy 192.839898 -45.19209) (xy 192.867194 -45.143455)
			(xy 192.90128 -45.099312) (xy 192.941429 -45.060603) (xy 192.986787 -45.028152) (xy 193.036387 -45.002651)
			(xy 193.089171 -44.984644) (xy 193.144014 -44.974514) (xy 193.199748 -44.972477) (xy 193.255185 -44.978577)
			(xy 193.309142 -44.992683) (xy 193.360471 -45.014495) (xy 193.408077 -45.043549) (xy 193.450945 -45.079224)
			(xy 193.488162 -45.120761) (xy 193.518935 -45.167274) (xy 193.542607 -45.217771) (xy 193.558675 -45.271178)
			(xy 193.566795 -45.326354) (xy 193.567304 -45.35424) (xy 193.566795 -45.382126) (xy 193.558675 -45.437302)
			(xy 193.542607 -45.490709) (xy 193.518935 -45.541206) (xy 193.488162 -45.587719) (xy 193.450945 -45.629256)
			(xy 193.408077 -45.664931) (xy 193.360471 -45.693985) (xy 193.309142 -45.715797) (xy 193.255185 -45.729903)
			(xy 193.199748 -45.736003) (xy 193.144014 -45.733966) (xy 193.089171 -45.723836) (xy 193.036387 -45.705829)
			(xy 192.986787 -45.680328) (xy 192.941429 -45.647877) (xy 192.90128 -45.609168) (xy 192.867194 -45.565025)
			(xy 192.839898 -45.51639) (xy 192.819975 -45.464299) (xy 192.807849 -45.409862) (xy 192.803778 -45.35424)
			(xy 188.844226 -45.35424) (xy 188.812651 -45.38948) (xy 188.769783 -45.425155) (xy 188.722177 -45.454209)
			(xy 188.670848 -45.476021) (xy 188.616891 -45.490127) (xy 188.561454 -45.496227) (xy 188.50572 -45.49419)
			(xy 188.450877 -45.48406) (xy 188.398093 -45.466053) (xy 188.348493 -45.440552) (xy 188.303135 -45.408101)
			(xy 188.262986 -45.369392) (xy 188.2289 -45.325249) (xy 188.201604 -45.276614) (xy 188.181681 -45.224523)
			(xy 188.169555 -45.170086) (xy 188.165484 -45.114464) (xy 180.387299 -45.114464) (xy 180.354182 -46.082204)
			(xy 186.152536 -46.082204) (xy 186.152959 -46.054949) (xy 186.160717 -46.000995) (xy 186.176075 -45.948693)
			(xy 186.19872 -45.89911) (xy 186.228191 -45.853255) (xy 186.263889 -45.812061) (xy 186.305087 -45.776367)
			(xy 186.350945 -45.746901) (xy 186.400531 -45.724261) (xy 186.452834 -45.708908) (xy 186.506789 -45.701156)
			(xy 186.534044 -45.700696) (xy 186.560948 -45.701125) (xy 186.614219 -45.708703) (xy 186.665898 -45.723688)
			(xy 186.71496 -45.745783) (xy 186.760432 -45.774551) (xy 186.801413 -45.80942) (xy 186.837089 -45.8497)
			(xy 186.852306 -45.871892) (xy 186.859418 -45.882814) (xy 186.882278 -45.894752) (xy 186.994546 -45.89272)
			(xy 187.016898 -45.879766) (xy 187.023756 -45.86859) (xy 187.038653 -45.844972) (xy 187.074336 -45.802021)
			(xy 187.115899 -45.764729) (xy 187.162453 -45.733893) (xy 187.213004 -45.710172) (xy 187.266473 -45.694073)
			(xy 187.321718 -45.68594) (xy 187.349638 -45.685456) (xy 187.376632 -45.685895) (xy 187.430081 -45.693506)
			(xy 187.481925 -45.708572) (xy 187.531129 -45.730791) (xy 187.576712 -45.75972) (xy 187.597542 -45.776896)
			(xy 187.60567 -45.784008) (xy 187.626244 -45.790104) (xy 187.711588 -45.779182) (xy 187.722134 -45.777412)
			(xy 187.740416 -45.766355) (xy 187.746894 -45.757846) (xy 187.762258 -45.736623) (xy 187.797843 -45.69817)
			(xy 187.838358 -45.664951) (xy 187.88304 -45.637591) (xy 187.931046 -45.616607) (xy 187.981473 -45.602392)
			(xy 188.033372 -45.595214) (xy 188.059568 -45.594778) (xy 188.086821 -45.595267) (xy 188.140774 -45.60302)
			(xy 188.193074 -45.618373) (xy 188.242656 -45.641013) (xy 188.288511 -45.670479) (xy 188.329706 -45.706171)
			(xy 188.365402 -45.747363) (xy 188.394872 -45.793216) (xy 188.417516 -45.842796) (xy 188.432873 -45.895095)
			(xy 188.440631 -45.949047) (xy 188.440631 -46.003553) (xy 188.432873 -46.057505) (xy 188.417516 -46.109804)
			(xy 188.394872 -46.159384) (xy 188.365402 -46.205237) (xy 188.329706 -46.246429) (xy 188.288511 -46.282121)
			(xy 188.242656 -46.311587) (xy 188.193074 -46.334227) (xy 188.140774 -46.34958) (xy 188.086821 -46.357333)
			(xy 188.059568 -46.357794) (xy 188.032575 -46.35734) (xy 187.979127 -46.34973) (xy 187.927284 -46.334668)
			(xy 187.878079 -46.312453) (xy 187.832495 -46.283528) (xy 187.811664 -46.266354) (xy 187.803536 -46.259242)
			(xy 187.782962 -46.253146) (xy 187.697618 -46.264068) (xy 187.687078 -46.265859) (xy 187.668794 -46.276903)
			(xy 187.662312 -46.285404) (xy 187.644694 -46.309701) (xy 187.603102 -46.352962) (xy 187.579508 -46.37151)
			(xy 187.571634 -46.377352) (xy 187.56122 -46.394878) (xy 187.548012 -46.485302) (xy 187.552838 -46.504606)
			(xy 187.55868 -46.51248) (xy 187.55868 -46.512734) (xy 187.576184 -46.537478) (xy 187.603986 -46.591331)
			(xy 187.622922 -46.648903) (xy 187.630125 -46.693836) (xy 192.776348 -46.693836) (xy 192.776834 -46.666585)
			(xy 192.78459 -46.612637) (xy 192.799945 -46.560342) (xy 192.822587 -46.510765) (xy 192.852053 -46.464915)
			(xy 192.887744 -46.423724) (xy 192.928935 -46.388033) (xy 192.974785 -46.358567) (xy 193.024362 -46.335925)
			(xy 193.076657 -46.32057) (xy 193.130605 -46.312814) (xy 193.185107 -46.312814) (xy 193.239055 -46.32057)
			(xy 193.29135 -46.335925) (xy 193.340927 -46.358567) (xy 193.386777 -46.388033) (xy 193.427968 -46.423724)
			(xy 193.463659 -46.464915) (xy 193.493125 -46.510765) (xy 193.515767 -46.560342) (xy 193.531122 -46.612637)
			(xy 193.538878 -46.666585) (xy 193.539364 -46.693836) (xy 193.538896 -46.720264) (xy 193.531586 -46.772611)
			(xy 193.517111 -46.823446) (xy 193.49575 -46.871793) (xy 193.482214 -46.894496) (xy 193.48196 -46.89475)
			(xy 193.476623 -46.904768) (xy 193.474365 -46.927318) (xy 193.477642 -46.938184) (xy 193.503804 -47.01286)
			(xy 193.508165 -47.023388) (xy 193.524269 -47.039471) (xy 193.534792 -47.043848) (xy 193.535046 -47.043848)
			(xy 193.559555 -47.052918) (xy 193.606007 -47.07686) (xy 193.648759 -47.106916) (xy 193.687011 -47.142523)
			(xy 193.720048 -47.183016) (xy 193.747251 -47.227637) (xy 193.768113 -47.275552) (xy 193.782243 -47.325866)
			(xy 193.789377 -47.377636) (xy 193.789808 -47.403766) (xy 193.789322 -47.431017) (xy 193.787799 -47.441612)
			(xy 195.061838 -47.441612) (xy 195.065909 -47.38599) (xy 195.078035 -47.331553) (xy 195.097958 -47.279462)
			(xy 195.125254 -47.230827) (xy 195.15934 -47.186684) (xy 195.199489 -47.147975) (xy 195.244847 -47.115524)
			(xy 195.294447 -47.090023) (xy 195.347231 -47.072016) (xy 195.402074 -47.061886) (xy 195.457808 -47.059849)
			(xy 195.513245 -47.065949) (xy 195.567202 -47.080055) (xy 195.618531 -47.101867) (xy 195.666137 -47.130921)
			(xy 195.709005 -47.166596) (xy 195.746222 -47.208133) (xy 195.776995 -47.254646) (xy 195.800667 -47.305143)
			(xy 195.816735 -47.35855) (xy 195.824855 -47.413726) (xy 195.825364 -47.441612) (xy 195.824855 -47.469498)
			(xy 195.816735 -47.524674) (xy 195.800667 -47.578081) (xy 195.776995 -47.628578) (xy 195.746222 -47.675091)
			(xy 195.709005 -47.716628) (xy 195.666137 -47.752303) (xy 195.618531 -47.781357) (xy 195.567202 -47.803169)
			(xy 195.513245 -47.817275) (xy 195.457808 -47.823375) (xy 195.402074 -47.821338) (xy 195.347231 -47.811208)
			(xy 195.294447 -47.793201) (xy 195.244847 -47.7677) (xy 195.199489 -47.735249) (xy 195.15934 -47.69654)
			(xy 195.125254 -47.652397) (xy 195.097958 -47.603762) (xy 195.078035 -47.551671) (xy 195.065909 -47.497234)
			(xy 195.061838 -47.441612) (xy 193.787799 -47.441612) (xy 193.781566 -47.484965) (xy 193.766211 -47.53726)
			(xy 193.743569 -47.586837) (xy 193.714103 -47.632687) (xy 193.678412 -47.673878) (xy 193.637221 -47.709569)
			(xy 193.591371 -47.739035) (xy 193.541794 -47.761677) (xy 193.489499 -47.777032) (xy 193.435551 -47.784788)
			(xy 193.381049 -47.784788) (xy 193.327101 -47.777032) (xy 193.274806 -47.761677) (xy 193.225229 -47.739035)
			(xy 193.179379 -47.709569) (xy 193.138188 -47.673878) (xy 193.102497 -47.632687) (xy 193.073031 -47.586837)
			(xy 193.050389 -47.53726) (xy 193.035034 -47.484965) (xy 193.027278 -47.431017) (xy 193.026792 -47.403766)
			(xy 193.027267 -47.377339) (xy 193.034576 -47.324991) (xy 193.049049 -47.274156) (xy 193.070408 -47.225809)
			(xy 193.083942 -47.203106) (xy 193.084196 -47.202852) (xy 193.089531 -47.192834) (xy 193.091788 -47.170284)
			(xy 193.088514 -47.159418) (xy 193.062352 -47.084742) (xy 193.057965 -47.074228) (xy 193.041879 -47.058139)
			(xy 193.031364 -47.053754) (xy 193.03111 -47.053754) (xy 193.006593 -47.044708) (xy 192.960141 -47.02076)
			(xy 192.917391 -46.9907) (xy 192.87914 -46.955089) (xy 192.846105 -46.914594) (xy 192.818903 -46.86997)
			(xy 192.798042 -46.822053) (xy 192.783913 -46.771738) (xy 192.776779 -46.719966) (xy 192.776348 -46.693836)
			(xy 187.630125 -46.693836) (xy 187.632515 -46.708745) (xy 187.633102 -46.739048) (xy 187.632667 -46.766301)
			(xy 187.624904 -46.820251) (xy 187.609542 -46.872547) (xy 187.586895 -46.922124) (xy 187.557423 -46.967975)
			(xy 187.521726 -47.009165) (xy 187.480532 -47.044855) (xy 187.434677 -47.074321) (xy 187.385096 -47.096961)
			(xy 187.332798 -47.112315) (xy 187.278847 -47.120071) (xy 187.251594 -47.120556) (xy 187.225561 -47.120105)
			(xy 187.173978 -47.113018) (xy 187.123836 -47.098989) (xy 187.076065 -47.078279) (xy 187.03155 -47.051272)
			(xy 187.011056 -47.035212) (xy 187.003289 -47.029485) (xy 186.984886 -47.023735) (xy 186.975242 -47.024036)
			(xy 186.895486 -47.030386) (xy 186.877706 -47.039022) (xy 186.871356 -47.046388) (xy 186.85317 -47.066029)
			(xy 186.812263 -47.100551) (xy 186.766935 -47.129021) (xy 186.718075 -47.150879) (xy 186.66664 -47.165698)
			(xy 186.613639 -47.173186) (xy 186.586876 -47.173642) (xy 186.559626 -47.173145) (xy 186.50568 -47.165386)
			(xy 186.453388 -47.150029) (xy 186.403813 -47.127388) (xy 186.357964 -47.097922) (xy 186.316775 -47.062232)
			(xy 186.281084 -47.021044) (xy 186.251617 -46.975196) (xy 186.228974 -46.925622) (xy 186.213616 -46.87333)
			(xy 186.205856 -46.819384) (xy 186.205368 -46.792134) (xy 186.205901 -46.76336) (xy 186.214551 -46.706467)
			(xy 186.231646 -46.651517) (xy 186.256797 -46.599757) (xy 186.289435 -46.55236) (xy 186.308746 -46.531022)
			(xy 186.316112 -46.523148) (xy 186.323224 -46.503336) (xy 186.315858 -46.40707) (xy 186.305952 -46.388274)
			(xy 186.29757 -46.38167) (xy 186.275375 -46.363458) (xy 186.236168 -46.321518) (xy 186.203685 -46.27418)
			(xy 186.178659 -46.222509) (xy 186.161654 -46.167674) (xy 186.153054 -46.11091) (xy 186.152536 -46.082204)
			(xy 180.354182 -46.082204) (xy 180.278048 -48.30699) (xy 192.653918 -48.30699) (xy 192.657989 -48.251368)
			(xy 192.670115 -48.196931) (xy 192.690038 -48.14484) (xy 192.717334 -48.096205) (xy 192.75142 -48.052062)
			(xy 192.791569 -48.013353) (xy 192.836927 -47.980902) (xy 192.886527 -47.955401) (xy 192.939311 -47.937394)
			(xy 192.994154 -47.927264) (xy 193.049888 -47.925227) (xy 193.105325 -47.931327) (xy 193.159282 -47.945433)
			(xy 193.210611 -47.967245) (xy 193.258217 -47.996299) (xy 193.301085 -48.031974) (xy 193.338302 -48.073511)
			(xy 193.369075 -48.120024) (xy 193.392747 -48.170521) (xy 193.408815 -48.223928) (xy 193.416935 -48.279104)
			(xy 193.417444 -48.30699) (xy 193.416935 -48.334876) (xy 193.408815 -48.390052) (xy 193.392747 -48.443459)
			(xy 193.369075 -48.493956) (xy 193.338302 -48.540469) (xy 193.301085 -48.582006) (xy 193.258217 -48.617681)
			(xy 193.210611 -48.646735) (xy 193.159282 -48.668547) (xy 193.105325 -48.682653) (xy 193.049888 -48.688753)
			(xy 192.994154 -48.686716) (xy 192.939311 -48.676586) (xy 192.886527 -48.658579) (xy 192.836927 -48.633078)
			(xy 192.791569 -48.600627) (xy 192.75142 -48.561918) (xy 192.717334 -48.517775) (xy 192.690038 -48.46914)
			(xy 192.670115 -48.417049) (xy 192.657989 -48.362612) (xy 192.653918 -48.30699) (xy 180.278048 -48.30699)
			(xy 180.268626 -48.582326) (xy 180.266086 -48.621442) (xy 180.265578 -48.62576) (xy 180.27321 -48.753014)
			(xy 189.268352 -48.753014) (xy 189.272423 -48.697392) (xy 189.284549 -48.642955) (xy 189.304472 -48.590864)
			(xy 189.331768 -48.542229) (xy 189.365854 -48.498086) (xy 189.406003 -48.459377) (xy 189.451361 -48.426926)
			(xy 189.500961 -48.401425) (xy 189.553745 -48.383418) (xy 189.608588 -48.373288) (xy 189.664322 -48.371251)
			(xy 189.719759 -48.377351) (xy 189.773716 -48.391457) (xy 189.825045 -48.413269) (xy 189.872651 -48.442323)
			(xy 189.915519 -48.477998) (xy 189.952736 -48.519535) (xy 189.983509 -48.566048) (xy 190.007181 -48.616545)
			(xy 190.023249 -48.669952) (xy 190.031369 -48.725128) (xy 190.031878 -48.753014) (xy 190.031369 -48.7809)
			(xy 190.023249 -48.836076) (xy 190.020805 -48.8442) (xy 190.2874 -48.8442) (xy 190.291471 -48.788578)
			(xy 190.303597 -48.734141) (xy 190.32352 -48.68205) (xy 190.350816 -48.633415) (xy 190.384902 -48.589272)
			(xy 190.425051 -48.550563) (xy 190.470409 -48.518112) (xy 190.520009 -48.492611) (xy 190.572793 -48.474604)
			(xy 190.627636 -48.464474) (xy 190.68337 -48.462437) (xy 190.738807 -48.468537) (xy 190.792764 -48.482643)
			(xy 190.844093 -48.504455) (xy 190.891699 -48.533509) (xy 190.934567 -48.569184) (xy 190.971784 -48.610721)
			(xy 191.002557 -48.657234) (xy 191.026229 -48.707731) (xy 191.042297 -48.761138) (xy 191.050417 -48.816314)
			(xy 191.050926 -48.8442) (xy 191.050417 -48.872086) (xy 191.047419 -48.89246) (xy 191.314068 -48.89246)
			(xy 191.318139 -48.836838) (xy 191.330265 -48.782401) (xy 191.350188 -48.73031) (xy 191.377484 -48.681675)
			(xy 191.41157 -48.637532) (xy 191.451719 -48.598823) (xy 191.497077 -48.566372) (xy 191.546677 -48.540871)
			(xy 191.599461 -48.522864) (xy 191.654304 -48.512734) (xy 191.710038 -48.510697) (xy 191.765475 -48.516797)
			(xy 191.819432 -48.530903) (xy 191.870761 -48.552715) (xy 191.918367 -48.581769) (xy 191.961235 -48.617444)
			(xy 191.998452 -48.658981) (xy 192.029225 -48.705494) (xy 192.052897 -48.755991) (xy 192.068965 -48.809398)
			(xy 192.077085 -48.864574) (xy 192.077594 -48.89246) (xy 192.077085 -48.920346) (xy 192.074647 -48.93691)
			(xy 195.033136 -48.93691) (xy 195.037207 -48.881288) (xy 195.049333 -48.826851) (xy 195.069256 -48.77476)
			(xy 195.096552 -48.726125) (xy 195.130638 -48.681982) (xy 195.170787 -48.643273) (xy 195.216145 -48.610822)
			(xy 195.265745 -48.585321) (xy 195.318529 -48.567314) (xy 195.373372 -48.557184) (xy 195.429106 -48.555147)
			(xy 195.484543 -48.561247) (xy 195.5385 -48.575353) (xy 195.589829 -48.597165) (xy 195.637435 -48.626219)
			(xy 195.680303 -48.661894) (xy 195.71752 -48.703431) (xy 195.748293 -48.749944) (xy 195.771965 -48.800441)
			(xy 195.788033 -48.853848) (xy 195.796153 -48.909024) (xy 195.796662 -48.93691) (xy 195.796153 -48.964796)
			(xy 195.788033 -49.019972) (xy 195.771965 -49.073379) (xy 195.748293 -49.123876) (xy 195.71752 -49.170389)
			(xy 195.680303 -49.211926) (xy 195.637435 -49.247601) (xy 195.589829 -49.276655) (xy 195.5385 -49.298467)
			(xy 195.484543 -49.312573) (xy 195.429106 -49.318673) (xy 195.373372 -49.316636) (xy 195.318529 -49.306506)
			(xy 195.265745 -49.288499) (xy 195.216145 -49.262998) (xy 195.170787 -49.230547) (xy 195.130638 -49.191838)
			(xy 195.096552 -49.147695) (xy 195.069256 -49.09906) (xy 195.049333 -49.046969) (xy 195.037207 -48.992532)
			(xy 195.033136 -48.93691) (xy 192.074647 -48.93691) (xy 192.068965 -48.975522) (xy 192.052897 -49.028929)
			(xy 192.029225 -49.079426) (xy 191.998452 -49.125939) (xy 191.961235 -49.167476) (xy 191.918367 -49.203151)
			(xy 191.870761 -49.232205) (xy 191.819432 -49.254017) (xy 191.765475 -49.268123) (xy 191.710038 -49.274223)
			(xy 191.654304 -49.272186) (xy 191.599461 -49.262056) (xy 191.546677 -49.244049) (xy 191.497077 -49.218548)
			(xy 191.451719 -49.186097) (xy 191.41157 -49.147388) (xy 191.377484 -49.103245) (xy 191.350188 -49.05461)
			(xy 191.330265 -49.002519) (xy 191.318139 -48.948082) (xy 191.314068 -48.89246) (xy 191.047419 -48.89246)
			(xy 191.042297 -48.927262) (xy 191.026229 -48.980669) (xy 191.002557 -49.031166) (xy 190.971784 -49.077679)
			(xy 190.934567 -49.119216) (xy 190.891699 -49.154891) (xy 190.844093 -49.183945) (xy 190.792764 -49.205757)
			(xy 190.738807 -49.219863) (xy 190.68337 -49.225963) (xy 190.627636 -49.223926) (xy 190.572793 -49.213796)
			(xy 190.520009 -49.195789) (xy 190.470409 -49.170288) (xy 190.425051 -49.137837) (xy 190.384902 -49.099128)
			(xy 190.350816 -49.054985) (xy 190.32352 -49.00635) (xy 190.303597 -48.954259) (xy 190.291471 -48.899822)
			(xy 190.2874 -48.8442) (xy 190.020805 -48.8442) (xy 190.007181 -48.889483) (xy 189.983509 -48.93998)
			(xy 189.952736 -48.986493) (xy 189.915519 -49.02803) (xy 189.872651 -49.063705) (xy 189.825045 -49.092759)
			(xy 189.773716 -49.114571) (xy 189.719759 -49.128677) (xy 189.664322 -49.134777) (xy 189.608588 -49.13274)
			(xy 189.553745 -49.12261) (xy 189.500961 -49.104603) (xy 189.451361 -49.079102) (xy 189.406003 -49.046651)
			(xy 189.365854 -49.007942) (xy 189.331768 -48.963799) (xy 189.304472 -48.915164) (xy 189.284549 -48.863073)
			(xy 189.272423 -48.808636) (xy 189.268352 -48.753014) (xy 180.27321 -48.753014) (xy 180.324122 -49.601949)
			(xy 200.212982 -49.601949) (xy 200.212982 -49.547451) (xy 200.220737 -49.493507) (xy 200.23609 -49.441216)
			(xy 200.258728 -49.391642) (xy 200.28819 -49.345794) (xy 200.323877 -49.304605) (xy 200.365062 -49.268914)
			(xy 200.410907 -49.239447) (xy 200.460479 -49.216804) (xy 200.512768 -49.201446) (xy 200.566711 -49.193684)
			(xy 200.59396 -49.193196) (xy 200.621329 -49.193686) (xy 200.675507 -49.201499) (xy 200.72801 -49.216982)
			(xy 200.777757 -49.239818) (xy 200.823725 -49.269537) (xy 200.844658 -49.287176) (xy 200.844912 -49.28743)
			(xy 200.851988 -49.293031) (xy 200.868913 -49.299268) (xy 200.877932 -49.299622) (xy 200.944988 -49.299622)
			(xy 200.954004 -49.299254) (xy 200.97092 -49.293014) (xy 200.978008 -49.28743) (xy 200.978008 -49.287176)
			(xy 200.978262 -49.287176) (xy 200.999195 -49.269535) (xy 201.045163 -49.239811) (xy 201.094909 -49.216965)
			(xy 201.147411 -49.201469) (xy 201.201589 -49.19364) (xy 201.256331 -49.19364) (xy 201.310509 -49.201469)
			(xy 201.363011 -49.216965) (xy 201.412757 -49.239811) (xy 201.458725 -49.269535) (xy 201.479658 -49.287176)
			(xy 201.479912 -49.28743) (xy 201.486988 -49.293031) (xy 201.503913 -49.299268) (xy 201.512932 -49.299622)
			(xy 201.579988 -49.299622) (xy 201.589004 -49.299254) (xy 201.60592 -49.293014) (xy 201.613008 -49.28743)
			(xy 201.613008 -49.287176) (xy 201.613262 -49.287176) (xy 201.634195 -49.269535) (xy 201.680163 -49.239811)
			(xy 201.729909 -49.216965) (xy 201.782411 -49.201469) (xy 201.836589 -49.19364) (xy 201.891331 -49.19364)
			(xy 201.945509 -49.201469) (xy 201.998011 -49.216965) (xy 202.047757 -49.239811) (xy 202.093725 -49.269535)
			(xy 202.114658 -49.287176) (xy 202.114912 -49.28743) (xy 202.121988 -49.293031) (xy 202.138913 -49.299268)
			(xy 202.147932 -49.299622) (xy 202.214988 -49.299622) (xy 202.224004 -49.299254) (xy 202.24092 -49.293014)
			(xy 202.248008 -49.28743) (xy 202.248008 -49.287176) (xy 202.248262 -49.287176) (xy 202.269194 -49.269538)
			(xy 202.315168 -49.239826) (xy 202.364915 -49.216991) (xy 202.417415 -49.201499) (xy 202.471591 -49.193671)
			(xy 202.49896 -49.193196) (xy 202.526215 -49.193649) (xy 202.580171 -49.201401) (xy 202.632474 -49.216754)
			(xy 202.68206 -49.239394) (xy 202.727918 -49.268861) (xy 202.769116 -49.304555) (xy 202.804815 -49.34575)
			(xy 202.834287 -49.391605) (xy 202.856932 -49.441188) (xy 202.87229 -49.49349) (xy 202.880049 -49.547445)
			(xy 202.880049 -49.601955) (xy 202.87229 -49.65591) (xy 202.856932 -49.708212) (xy 202.834287 -49.757795)
			(xy 202.804815 -49.80365) (xy 202.769116 -49.844845) (xy 202.727918 -49.880539) (xy 202.68206 -49.910006)
			(xy 202.632474 -49.932646) (xy 202.580171 -49.947999) (xy 202.526215 -49.955751) (xy 202.49896 -49.956212)
			(xy 202.471591 -49.955708) (xy 202.417414 -49.947899) (xy 202.364911 -49.932418) (xy 202.315164 -49.909585)
			(xy 202.269195 -49.879869) (xy 202.248262 -49.862232) (xy 202.248008 -49.861978) (xy 202.240925 -49.856386)
			(xy 202.224005 -49.850143) (xy 202.214988 -49.849786) (xy 202.147932 -49.849786) (xy 202.138917 -49.850161)
			(xy 202.122 -49.856396) (xy 202.114912 -49.861978) (xy 202.114658 -49.862232) (xy 202.093725 -49.879873)
			(xy 202.047757 -49.909597) (xy 201.998011 -49.932443) (xy 201.945509 -49.947939) (xy 201.891331 -49.955768)
			(xy 201.836589 -49.955768) (xy 201.782411 -49.947939) (xy 201.729909 -49.932443) (xy 201.680163 -49.909597)
			(xy 201.634195 -49.879873) (xy 201.613262 -49.862232) (xy 201.613008 -49.861978) (xy 201.605925 -49.856386)
			(xy 201.589005 -49.850143) (xy 201.579988 -49.849786) (xy 201.512932 -49.849786) (xy 201.503917 -49.850161)
			(xy 201.487 -49.856396) (xy 201.479912 -49.861978) (xy 201.479912 -49.862232) (xy 201.479658 -49.862232)
			(xy 201.458725 -49.879873) (xy 201.412757 -49.909597) (xy 201.363011 -49.932443) (xy 201.310509 -49.947939)
			(xy 201.256331 -49.955768) (xy 201.201589 -49.955768) (xy 201.147411 -49.947939) (xy 201.094909 -49.932443)
			(xy 201.045163 -49.909597) (xy 200.999195 -49.879873) (xy 200.978262 -49.862232) (xy 200.978008 -49.861978)
			(xy 200.970925 -49.856386) (xy 200.954005 -49.850143) (xy 200.944988 -49.849786) (xy 200.877932 -49.849786)
			(xy 200.868917 -49.850161) (xy 200.852 -49.856396) (xy 200.844912 -49.861978) (xy 200.844912 -49.862232)
			(xy 200.844658 -49.862232) (xy 200.823719 -49.879862) (xy 200.777748 -49.909574) (xy 200.728002 -49.932412)
			(xy 200.675503 -49.947905) (xy 200.621329 -49.955736) (xy 200.59396 -49.956212) (xy 200.566711 -49.955716)
			(xy 200.512768 -49.947954) (xy 200.460479 -49.932596) (xy 200.410907 -49.909953) (xy 200.365062 -49.880486)
			(xy 200.323877 -49.844795) (xy 200.28819 -49.803606) (xy 200.258728 -49.757758) (xy 200.23609 -49.708184)
			(xy 200.220737 -49.655893) (xy 200.212982 -49.601949) (xy 180.324122 -49.601949) (xy 180.375727 -50.462434)
			(xy 190.92621 -50.462434) (xy 190.930281 -50.406812) (xy 190.942407 -50.352375) (xy 190.96233 -50.300284)
			(xy 190.989626 -50.251649) (xy 191.023712 -50.207506) (xy 191.063861 -50.168797) (xy 191.109219 -50.136346)
			(xy 191.158819 -50.110845) (xy 191.211603 -50.092838) (xy 191.266446 -50.082708) (xy 191.32218 -50.080671)
			(xy 191.377617 -50.086771) (xy 191.431574 -50.100877) (xy 191.482903 -50.122689) (xy 191.530509 -50.151743)
			(xy 191.573377 -50.187418) (xy 191.610594 -50.228955) (xy 191.641367 -50.275468) (xy 191.665039 -50.325965)
			(xy 191.681107 -50.379372) (xy 191.689227 -50.434548) (xy 191.689736 -50.462434) (xy 191.689227 -50.49032)
			(xy 191.681107 -50.545496) (xy 191.665039 -50.598903) (xy 191.641367 -50.6494) (xy 191.610594 -50.695913)
			(xy 191.573377 -50.73745) (xy 191.530509 -50.773125) (xy 191.482903 -50.802179) (xy 191.431574 -50.823991)
			(xy 191.377617 -50.838097) (xy 191.32218 -50.844197) (xy 191.266446 -50.84216) (xy 191.211603 -50.83203)
			(xy 191.158819 -50.814023) (xy 191.109219 -50.788522) (xy 191.063861 -50.756071) (xy 191.023712 -50.717362)
			(xy 190.989626 -50.673219) (xy 190.96233 -50.624584) (xy 190.942407 -50.572493) (xy 190.930281 -50.518056)
			(xy 190.92621 -50.462434) (xy 180.375727 -50.462434) (xy 180.409133 -51.019456) (xy 192.849498 -51.019456)
			(xy 192.853569 -50.963834) (xy 192.865695 -50.909397) (xy 192.885618 -50.857306) (xy 192.912914 -50.808671)
			(xy 192.947 -50.764528) (xy 192.987149 -50.725819) (xy 193.032507 -50.693368) (xy 193.082107 -50.667867)
			(xy 193.134891 -50.64986) (xy 193.189734 -50.63973) (xy 193.245468 -50.637693) (xy 193.300905 -50.643793)
			(xy 193.354862 -50.657899) (xy 193.406191 -50.679711) (xy 193.453797 -50.708765) (xy 193.496665 -50.74444)
			(xy 193.533882 -50.785977) (xy 193.564655 -50.83249) (xy 193.588327 -50.882987) (xy 193.604395 -50.936394)
			(xy 193.612515 -50.99157) (xy 193.613024 -51.019456) (xy 193.612515 -51.047342) (xy 193.604395 -51.102518)
			(xy 193.588327 -51.155925) (xy 193.564655 -51.206422) (xy 193.539799 -51.243992) (xy 201.233024 -51.243992)
			(xy 201.23348 -51.216621) (xy 201.241299 -51.162442) (xy 201.25679 -51.109938) (xy 201.279634 -51.060191)
			(xy 201.309362 -51.014225) (xy 201.327004 -50.993294) (xy 201.327258 -50.99304) (xy 201.332841 -50.985951)
			(xy 201.339088 -50.969036) (xy 201.33945 -50.96002) (xy 201.33945 -50.892964) (xy 201.339121 -50.883944)
			(xy 201.332855 -50.867027) (xy 201.327258 -50.859944) (xy 201.327004 -50.859944) (xy 201.327004 -50.85969)
			(xy 201.309347 -50.838772) (xy 201.279638 -50.792795) (xy 201.256805 -50.743044) (xy 201.241318 -50.690541)
			(xy 201.233495 -50.636362) (xy 201.233024 -50.608992) (xy 201.233448 -50.581737) (xy 201.241207 -50.527784)
			(xy 201.256566 -50.475483) (xy 201.279211 -50.425901) (xy 201.308683 -50.380046) (xy 201.344381 -50.338853)
			(xy 201.385578 -50.303159) (xy 201.431436 -50.273692) (xy 201.481021 -50.251052) (xy 201.533323 -50.235698)
			(xy 201.587277 -50.227945) (xy 201.614532 -50.227484) (xy 201.643449 -50.228019) (xy 201.70062 -50.23674)
			(xy 201.75582 -50.253993) (xy 201.807783 -50.279381) (xy 201.855317 -50.312323) (xy 201.897333 -50.352064)
			(xy 201.915522 -50.37455) (xy 201.923121 -50.383366) (xy 201.944028 -50.393543) (xy 201.955654 -50.394108)
			(xy 202.03541 -50.394108) (xy 202.04704 -50.393557) (xy 202.06795 -50.383376) (xy 202.075542 -50.37455)
			(xy 202.093697 -50.352036) (xy 202.135725 -50.312305) (xy 202.183268 -50.279371) (xy 202.235237 -50.253988)
			(xy 202.29044 -50.236738) (xy 202.347614 -50.228016) (xy 202.376532 -50.227484) (xy 202.403784 -50.227948)
			(xy 202.457732 -50.235709) (xy 202.510026 -50.251067) (xy 202.559603 -50.273712) (xy 202.605453 -50.303181)
			(xy 202.646643 -50.338874) (xy 202.682334 -50.380066) (xy 202.7118 -50.425918) (xy 202.734441 -50.475496)
			(xy 202.749796 -50.527792) (xy 202.757554 -50.58174) (xy 202.75804 -50.608992) (xy 202.757586 -50.635307)
			(xy 202.750351 -50.687437) (xy 202.736031 -50.73808) (xy 202.714896 -50.78628) (xy 202.687347 -50.831123)
			(xy 202.653904 -50.871761) (xy 202.63485 -50.889916) (xy 202.627447 -50.897436) (xy 202.618922 -50.916717)
			(xy 202.61834 -50.927254) (xy 202.61834 -51.00193) (xy 202.618882 -51.012479) (xy 202.627407 -51.031775)
			(xy 202.63485 -51.039268) (xy 202.653941 -51.057388) (xy 202.687393 -51.098026) (xy 202.714946 -51.142874)
			(xy 202.736078 -51.191082) (xy 202.750388 -51.241735) (xy 202.757605 -51.293874) (xy 202.75804 -51.320192)
			(xy 202.757515 -51.347442) (xy 202.74976 -51.401386) (xy 202.734408 -51.453678) (xy 202.71177 -51.503253)
			(xy 202.682307 -51.549102) (xy 202.64662 -51.590292) (xy 202.605434 -51.625983) (xy 202.559589 -51.655451)
			(xy 202.510016 -51.678094) (xy 202.457725 -51.693452) (xy 202.403782 -51.701212) (xy 202.376532 -51.7017)
			(xy 202.348868 -51.701163) (xy 202.29412 -51.693168) (xy 202.241099 -51.677356) (xy 202.190915 -51.654057)
			(xy 202.144619 -51.623759) (xy 202.10318 -51.587098) (xy 202.067466 -51.544839) (xy 202.052428 -51.521614)
			(xy 202.045788 -51.511941) (xy 202.025929 -51.499496) (xy 202.014328 -51.497738) (xy 201.934318 -51.489864)
			(xy 201.92268 -51.489247) (xy 201.900843 -51.497316) (xy 201.892408 -51.505358) (xy 201.892154 -51.505612)
			(xy 201.87408 -51.5242) (xy 201.833746 -51.556777) (xy 201.78937 -51.583589) (xy 201.741771 -51.604141)
			(xy 201.691825 -51.618053) (xy 201.640455 -51.625069) (xy 201.614532 -51.6255) (xy 201.58728 -51.625015)
			(xy 201.533329 -51.617262) (xy 201.481031 -51.60191) (xy 201.431451 -51.57927) (xy 201.385597 -51.549805)
			(xy 201.344404 -51.514113) (xy 201.308709 -51.472922) (xy 201.279241 -51.427071) (xy 201.256599 -51.377491)
			(xy 201.241243 -51.325194) (xy 201.233487 -51.271244) (xy 201.233024 -51.243992) (xy 193.539799 -51.243992)
			(xy 193.533882 -51.252935) (xy 193.496665 -51.294472) (xy 193.453797 -51.330147) (xy 193.406191 -51.359201)
			(xy 193.354862 -51.381013) (xy 193.300905 -51.395119) (xy 193.245468 -51.401219) (xy 193.189734 -51.399182)
			(xy 193.134891 -51.389052) (xy 193.082107 -51.371045) (xy 193.032507 -51.345544) (xy 192.987149 -51.313093)
			(xy 192.947 -51.274384) (xy 192.912914 -51.230241) (xy 192.885618 -51.181606) (xy 192.865695 -51.129515)
			(xy 192.853569 -51.075078) (xy 192.849498 -51.019456) (xy 180.409133 -51.019456) (xy 180.470064 -52.035456)
			(xy 195.041264 -52.035456) (xy 195.045335 -51.979834) (xy 195.057461 -51.925397) (xy 195.077384 -51.873306)
			(xy 195.10468 -51.824671) (xy 195.138766 -51.780528) (xy 195.178915 -51.741819) (xy 195.224273 -51.709368)
			(xy 195.273873 -51.683867) (xy 195.326657 -51.66586) (xy 195.3815 -51.65573) (xy 195.437234 -51.653693)
			(xy 195.492671 -51.659793) (xy 195.546628 -51.673899) (xy 195.597957 -51.695711) (xy 195.645563 -51.724765)
			(xy 195.688431 -51.76044) (xy 195.725648 -51.801977) (xy 195.756421 -51.84849) (xy 195.780093 -51.898987)
			(xy 195.796161 -51.952394) (xy 195.804281 -52.00757) (xy 195.80479 -52.035456) (xy 195.804281 -52.063342)
			(xy 195.796161 -52.118518) (xy 195.780093 -52.171925) (xy 195.756421 -52.222422) (xy 195.725648 -52.268935)
			(xy 195.688431 -52.310472) (xy 195.645563 -52.346147) (xy 195.597957 -52.375201) (xy 195.546628 -52.397013)
			(xy 195.492671 -52.411119) (xy 195.437234 -52.417219) (xy 195.3815 -52.415182) (xy 195.326657 -52.405052)
			(xy 195.273873 -52.387045) (xy 195.224273 -52.361544) (xy 195.178915 -52.329093) (xy 195.138766 -52.290384)
			(xy 195.10468 -52.246241) (xy 195.077384 -52.197606) (xy 195.057461 -52.145515) (xy 195.045335 -52.091078)
			(xy 195.041264 -52.035456) (xy 180.470064 -52.035456) (xy 180.631746 -54.731412) (xy 181.620668 -54.731412)
			(xy 181.621125 -54.704041) (xy 181.628942 -54.649861) (xy 181.644432 -54.597357) (xy 181.667277 -54.54761)
			(xy 181.697005 -54.501645) (xy 181.714648 -54.480714) (xy 181.714902 -54.48046) (xy 181.72047 -54.473361)
			(xy 181.726728 -54.456454) (xy 181.727094 -54.44744) (xy 181.727094 -54.380384) (xy 181.726746 -54.371366)
			(xy 181.720492 -54.354449) (xy 181.714902 -54.347364) (xy 181.714648 -54.347364) (xy 181.714648 -54.34711)
			(xy 181.697018 -54.326168) (xy 181.667291 -54.280202) (xy 181.644444 -54.230458) (xy 181.628946 -54.177957)
			(xy 181.621116 -54.123779) (xy 181.621114 -54.069039) (xy 181.628942 -54.014861) (xy 181.644438 -53.962359)
			(xy 181.667283 -53.912613) (xy 181.697007 -53.866646) (xy 181.714648 -53.845714) (xy 181.714902 -53.84546)
			(xy 181.72047 -53.838361) (xy 181.726728 -53.821454) (xy 181.727094 -53.81244) (xy 181.727094 -53.745384)
			(xy 181.726746 -53.736366) (xy 181.720492 -53.719449) (xy 181.714902 -53.712364) (xy 181.714648 -53.712364)
			(xy 181.714648 -53.71211) (xy 181.697018 -53.691168) (xy 181.667291 -53.645202) (xy 181.644444 -53.595458)
			(xy 181.628946 -53.542957) (xy 181.621116 -53.488779) (xy 181.621114 -53.434039) (xy 181.628942 -53.379861)
			(xy 181.644438 -53.327359) (xy 181.667283 -53.277613) (xy 181.697007 -53.231646) (xy 181.714648 -53.210714)
			(xy 181.714902 -53.21046) (xy 181.72047 -53.203361) (xy 181.726728 -53.186454) (xy 181.727094 -53.17744)
			(xy 181.727094 -53.110384) (xy 181.726746 -53.101366) (xy 181.720492 -53.084449) (xy 181.714902 -53.077364)
			(xy 181.714648 -53.077364) (xy 181.714648 -53.07711) (xy 181.697008 -53.056179) (xy 181.667294 -53.010207)
			(xy 181.644458 -52.960459) (xy 181.628967 -52.907958) (xy 181.621141 -52.853781) (xy 181.620668 -52.826412)
			(xy 181.621154 -52.799161) (xy 181.62891 -52.745213) (xy 181.644265 -52.692918) (xy 181.666907 -52.643341)
			(xy 181.696373 -52.597491) (xy 181.732064 -52.5563) (xy 181.773255 -52.520609) (xy 181.819105 -52.491143)
			(xy 181.868682 -52.468501) (xy 181.920977 -52.453146) (xy 181.974925 -52.44539) (xy 182.029427 -52.44539)
			(xy 182.083375 -52.453146) (xy 182.13567 -52.468501) (xy 182.185247 -52.491143) (xy 182.231097 -52.520609)
			(xy 182.272288 -52.5563) (xy 182.307979 -52.597491) (xy 182.337445 -52.643341) (xy 182.360087 -52.692918)
			(xy 182.375442 -52.745213) (xy 182.383198 -52.799161) (xy 182.383684 -52.826412) (xy 182.383229 -52.853783)
			(xy 182.375409 -52.907962) (xy 182.359918 -52.960466) (xy 182.337073 -53.010212) (xy 182.307346 -53.056179)
			(xy 182.289704 -53.07711) (xy 182.28945 -53.077364) (xy 182.283866 -53.084452) (xy 182.277619 -53.101368)
			(xy 182.277258 -53.110384) (xy 182.277258 -53.17744) (xy 182.277583 -53.18646) (xy 182.283851 -53.203378)
			(xy 182.28945 -53.21046) (xy 182.289704 -53.21046) (xy 182.289704 -53.210714) (xy 182.307355 -53.231638)
			(xy 182.337077 -53.277608) (xy 182.35992 -53.327356) (xy 182.375414 -53.379859) (xy 182.383241 -53.434038)
			(xy 182.383239 -53.48878) (xy 182.37541 -53.542959) (xy 182.359914 -53.595461) (xy 182.337068 -53.645208)
			(xy 182.307344 -53.691177) (xy 182.289704 -53.71211) (xy 182.28945 -53.712364) (xy 182.283866 -53.719452)
			(xy 182.277619 -53.736368) (xy 182.277258 -53.745384) (xy 182.277258 -53.81244) (xy 182.277583 -53.82146)
			(xy 182.283851 -53.838378) (xy 182.28945 -53.84546) (xy 182.289704 -53.84546) (xy 182.289704 -53.845714)
			(xy 182.307355 -53.866638) (xy 182.337077 -53.912608) (xy 182.35992 -53.962356) (xy 182.375414 -54.014859)
			(xy 182.383241 -54.069038) (xy 182.383239 -54.12378) (xy 182.37541 -54.177959) (xy 182.359914 -54.230461)
			(xy 182.337068 -54.280208) (xy 182.307344 -54.326177) (xy 182.289704 -54.34711) (xy 182.28945 -54.347364)
			(xy 182.283866 -54.354452) (xy 182.277619 -54.371368) (xy 182.277258 -54.380384) (xy 182.277258 -54.44744)
			(xy 182.277583 -54.45646) (xy 182.283851 -54.473378) (xy 182.28945 -54.48046) (xy 182.289704 -54.48046)
			(xy 182.289704 -54.480714) (xy 182.307317 -54.501667) (xy 182.337033 -54.547634) (xy 182.359873 -54.597376)
			(xy 182.375371 -54.649872) (xy 182.383206 -54.704044) (xy 182.383684 -54.731412) (xy 182.383198 -54.758663)
			(xy 182.378534 -54.791102) (xy 184.276492 -54.791102) (xy 184.276961 -54.763732) (xy 184.284779 -54.709553)
			(xy 184.300267 -54.65705) (xy 184.323108 -54.607303) (xy 184.352831 -54.561336) (xy 184.370472 -54.540404)
			(xy 184.370726 -54.54015) (xy 184.376301 -54.533055) (xy 184.382554 -54.516145) (xy 184.382918 -54.50713)
			(xy 184.382918 -54.440074) (xy 184.38257 -54.431056) (xy 184.376316 -54.41414) (xy 184.370726 -54.407054)
			(xy 184.370472 -54.407054) (xy 184.370472 -54.4068) (xy 184.352831 -54.385867) (xy 184.323103 -54.3399)
			(xy 184.300255 -54.290154) (xy 184.284757 -54.237652) (xy 184.276927 -54.183473) (xy 184.276927 -54.12873)
			(xy 184.284756 -54.074551) (xy 184.300254 -54.022049) (xy 184.323102 -53.972303) (xy 184.35283 -53.926336)
			(xy 184.370472 -53.905404) (xy 184.370726 -53.90515) (xy 184.376301 -53.898055) (xy 184.382554 -53.881145)
			(xy 184.382918 -53.87213) (xy 184.382918 -53.805074) (xy 184.38257 -53.796056) (xy 184.376316 -53.77914)
			(xy 184.370726 -53.772054) (xy 184.370472 -53.772054) (xy 184.370472 -53.7718) (xy 184.352831 -53.750867)
			(xy 184.323103 -53.7049) (xy 184.300255 -53.655154) (xy 184.284757 -53.602652) (xy 184.276927 -53.548473)
			(xy 184.276927 -53.49373) (xy 184.284756 -53.439551) (xy 184.300254 -53.387049) (xy 184.323102 -53.337303)
			(xy 184.35283 -53.291336) (xy 184.370472 -53.270404) (xy 184.370726 -53.27015) (xy 184.376301 -53.263055)
			(xy 184.382554 -53.246145) (xy 184.382918 -53.23713) (xy 184.382918 -53.170074) (xy 184.38257 -53.161056)
			(xy 184.376316 -53.14414) (xy 184.370726 -53.137054) (xy 184.370472 -53.137054) (xy 184.370472 -53.1368)
			(xy 184.352815 -53.115882) (xy 184.323107 -53.069905) (xy 184.300275 -53.020154) (xy 184.284788 -52.96765)
			(xy 184.276964 -52.913472) (xy 184.276492 -52.886102) (xy 184.276978 -52.858851) (xy 184.284734 -52.804903)
			(xy 184.300089 -52.752608) (xy 184.322731 -52.703031) (xy 184.352197 -52.657181) (xy 184.387888 -52.61599)
			(xy 184.429079 -52.580299) (xy 184.474929 -52.550833) (xy 184.524506 -52.528191) (xy 184.576801 -52.512836)
			(xy 184.630749 -52.50508) (xy 184.685251 -52.50508) (xy 184.739199 -52.512836) (xy 184.791494 -52.528191)
			(xy 184.830594 -52.546048) (xy 189.779696 -52.546048) (xy 189.779696 -52.491552) (xy 189.787451 -52.437611)
			(xy 189.802803 -52.385322) (xy 189.82544 -52.33575) (xy 189.854901 -52.289904) (xy 189.890586 -52.248717)
			(xy 189.931769 -52.213027) (xy 189.977612 -52.183561) (xy 190.027181 -52.160919) (xy 190.079468 -52.14556)
			(xy 190.133408 -52.137799) (xy 190.160656 -52.13731) (xy 190.188025 -52.137799) (xy 190.242204 -52.145611)
			(xy 190.294707 -52.161095) (xy 190.344454 -52.183931) (xy 190.390422 -52.213651) (xy 190.411354 -52.23129)
			(xy 190.411608 -52.231544) (xy 190.418684 -52.237145) (xy 190.435609 -52.243382) (xy 190.444628 -52.243736)
			(xy 190.511684 -52.243736) (xy 190.520699 -52.243363) (xy 190.537616 -52.237126) (xy 190.544704 -52.231544)
			(xy 190.544704 -52.23129) (xy 190.544958 -52.23129) (xy 190.565891 -52.213649) (xy 190.611859 -52.183925)
			(xy 190.661605 -52.161079) (xy 190.714107 -52.145583) (xy 190.768285 -52.137754) (xy 190.823027 -52.137754)
			(xy 190.877205 -52.145583) (xy 190.929707 -52.161079) (xy 190.979453 -52.183925) (xy 191.025421 -52.213649)
			(xy 191.046354 -52.23129) (xy 191.046608 -52.231544) (xy 191.053684 -52.237145) (xy 191.070609 -52.243382)
			(xy 191.079628 -52.243736) (xy 191.146684 -52.243736) (xy 191.155699 -52.243363) (xy 191.172616 -52.237126)
			(xy 191.179704 -52.231544) (xy 191.179704 -52.23129) (xy 191.179958 -52.23129) (xy 191.200894 -52.213656)
			(xy 191.246866 -52.183943) (xy 191.296612 -52.161107) (xy 191.349112 -52.145615) (xy 191.403287 -52.137785)
			(xy 191.430656 -52.13731) (xy 191.457912 -52.137734) (xy 191.511871 -52.145486) (xy 191.564176 -52.160839)
			(xy 191.613764 -52.18348) (xy 191.659625 -52.212948) (xy 191.700825 -52.248644) (xy 191.736525 -52.28984)
			(xy 191.765999 -52.335697) (xy 191.788645 -52.385283) (xy 191.804004 -52.437586) (xy 191.811763 -52.491544)
			(xy 191.811763 -52.546056) (xy 191.805818 -52.587398) (xy 192.85534 -52.587398) (xy 192.859411 -52.531776)
			(xy 192.871537 -52.477339) (xy 192.89146 -52.425248) (xy 192.918756 -52.376613) (xy 192.952842 -52.33247)
			(xy 192.992991 -52.293761) (xy 193.038349 -52.26131) (xy 193.087949 -52.235809) (xy 193.140733 -52.217802)
			(xy 193.195576 -52.207672) (xy 193.25131 -52.205635) (xy 193.306747 -52.211735) (xy 193.360704 -52.225841)
			(xy 193.412033 -52.247653) (xy 193.459639 -52.276707) (xy 193.502507 -52.312382) (xy 193.539724 -52.353919)
			(xy 193.570497 -52.400432) (xy 193.594169 -52.450929) (xy 193.610237 -52.504336) (xy 193.617833 -52.555948)
			(xy 200.683902 -52.555948) (xy 200.683902 -52.501452) (xy 200.691658 -52.447509) (xy 200.70701 -52.39522)
			(xy 200.729648 -52.345647) (xy 200.759111 -52.299801) (xy 200.794797 -52.258614) (xy 200.835982 -52.222925)
			(xy 200.881826 -52.19346) (xy 200.931397 -52.170819) (xy 200.983686 -52.155463) (xy 201.037628 -52.147704)
			(xy 201.064876 -52.147216) (xy 201.092246 -52.147692) (xy 201.146425 -52.155507) (xy 201.198928 -52.170994)
			(xy 201.248675 -52.193833) (xy 201.294642 -52.223556) (xy 201.315574 -52.241196) (xy 201.315828 -52.24145)
			(xy 201.322927 -52.247019) (xy 201.339834 -52.253275) (xy 201.348848 -52.253642) (xy 201.415904 -52.253642)
			(xy 201.424923 -52.253299) (xy 201.44184 -52.247043) (xy 201.448924 -52.24145) (xy 201.448924 -52.241196)
			(xy 201.449178 -52.241196) (xy 201.470107 -52.223553) (xy 201.516081 -52.193842) (xy 201.565829 -52.171007)
			(xy 201.61833 -52.155517) (xy 201.672507 -52.147689) (xy 201.699876 -52.147216) (xy 201.727132 -52.147629)
			(xy 201.781089 -52.155384) (xy 201.833393 -52.170739) (xy 201.882979 -52.193381) (xy 201.928838 -52.222851)
			(xy 201.970036 -52.258547) (xy 202.005735 -52.299743) (xy 202.035207 -52.3456) (xy 202.057853 -52.395185)
			(xy 202.073211 -52.447488) (xy 202.080969 -52.501444) (xy 202.080969 -52.555956) (xy 202.073211 -52.609912)
			(xy 202.057853 -52.662215) (xy 202.035207 -52.7118) (xy 202.005735 -52.757657) (xy 201.970036 -52.798853)
			(xy 201.928838 -52.834549) (xy 201.882979 -52.864019) (xy 201.833393 -52.886661) (xy 201.781089 -52.902016)
			(xy 201.727132 -52.909771) (xy 201.699876 -52.910232) (xy 201.672504 -52.909797) (xy 201.618323 -52.901974)
			(xy 201.565819 -52.886479) (xy 201.516073 -52.86363) (xy 201.470108 -52.833897) (xy 201.449178 -52.816252)
			(xy 201.448924 -52.815998) (xy 201.441835 -52.810415) (xy 201.42492 -52.804166) (xy 201.415904 -52.803806)
			(xy 201.348848 -52.803806) (xy 201.339833 -52.804185) (xy 201.322916 -52.810417) (xy 201.315828 -52.815998)
			(xy 201.315828 -52.816252) (xy 201.315574 -52.816252) (xy 201.294619 -52.833862) (xy 201.248653 -52.86358)
			(xy 201.198912 -52.886422) (xy 201.146416 -52.90192) (xy 201.092244 -52.909755) (xy 201.064876 -52.910232)
			(xy 201.037628 -52.909696) (xy 200.983686 -52.901937) (xy 200.931397 -52.886581) (xy 200.881826 -52.86394)
			(xy 200.835982 -52.834475) (xy 200.794797 -52.798786) (xy 200.759111 -52.757599) (xy 200.729648 -52.711753)
			(xy 200.70701 -52.66218) (xy 200.691658 -52.609891) (xy 200.683902 -52.555948) (xy 193.617833 -52.555948)
			(xy 193.618357 -52.559512) (xy 193.618866 -52.587398) (xy 193.618357 -52.615284) (xy 193.610237 -52.67046)
			(xy 193.594169 -52.723867) (xy 193.570497 -52.774364) (xy 193.539724 -52.820877) (xy 193.502507 -52.862414)
			(xy 193.459639 -52.898089) (xy 193.412033 -52.927143) (xy 193.360704 -52.948955) (xy 193.306747 -52.963061)
			(xy 193.25131 -52.969161) (xy 193.195576 -52.967124) (xy 193.140733 -52.956994) (xy 193.087949 -52.938987)
			(xy 193.038349 -52.913486) (xy 192.992991 -52.881035) (xy 192.952842 -52.842326) (xy 192.918756 -52.798183)
			(xy 192.89146 -52.749548) (xy 192.871537 -52.697457) (xy 192.859411 -52.64302) (xy 192.85534 -52.587398)
			(xy 191.805818 -52.587398) (xy 191.804004 -52.600014) (xy 191.788645 -52.652317) (xy 191.765999 -52.701903)
			(xy 191.736525 -52.74776) (xy 191.700825 -52.788956) (xy 191.659625 -52.824652) (xy 191.613764 -52.85412)
			(xy 191.564176 -52.876761) (xy 191.511871 -52.892114) (xy 191.457912 -52.899866) (xy 191.430656 -52.900326)
			(xy 191.403286 -52.899845) (xy 191.349107 -52.892034) (xy 191.296603 -52.876549) (xy 191.246856 -52.85371)
			(xy 191.200889 -52.823987) (xy 191.179958 -52.806346) (xy 191.179704 -52.806092) (xy 191.172621 -52.8005)
			(xy 191.155701 -52.794257) (xy 191.146684 -52.7939) (xy 191.079628 -52.7939) (xy 191.070612 -52.79427)
			(xy 191.053695 -52.800509) (xy 191.046608 -52.806092) (xy 191.046354 -52.806346) (xy 191.025421 -52.823987)
			(xy 190.979453 -52.853711) (xy 190.929707 -52.876557) (xy 190.877205 -52.892053) (xy 190.823027 -52.899882)
			(xy 190.768285 -52.899882) (xy 190.714107 -52.892053) (xy 190.661605 -52.876557) (xy 190.611859 -52.853711)
			(xy 190.565891 -52.823987) (xy 190.544958 -52.806346) (xy 190.544704 -52.806092) (xy 190.537621 -52.8005)
			(xy 190.520701 -52.794257) (xy 190.511684 -52.7939) (xy 190.444628 -52.7939) (xy 190.435612 -52.79427)
			(xy 190.418695 -52.800509) (xy 190.411608 -52.806092) (xy 190.411608 -52.806346) (xy 190.411354 -52.806346)
			(xy 190.390405 -52.823965) (xy 190.344438 -52.853682) (xy 190.294695 -52.876522) (xy 190.242197 -52.892018)
			(xy 190.188024 -52.89985) (xy 190.160656 -52.900326) (xy 190.133408 -52.899801) (xy 190.079468 -52.89204)
			(xy 190.027181 -52.876681) (xy 189.977612 -52.854039) (xy 189.931769 -52.824573) (xy 189.890586 -52.788883)
			(xy 189.854901 -52.747696) (xy 189.82544 -52.70185) (xy 189.802803 -52.652278) (xy 189.787451 -52.599989)
			(xy 189.779696 -52.546048) (xy 184.830594 -52.546048) (xy 184.841071 -52.550833) (xy 184.886921 -52.580299)
			(xy 184.928112 -52.61599) (xy 184.963803 -52.657181) (xy 184.993269 -52.703031) (xy 185.015911 -52.752608)
			(xy 185.031266 -52.804903) (xy 185.039022 -52.858851) (xy 185.039508 -52.886102) (xy 185.039041 -52.913472)
			(xy 185.031223 -52.967651) (xy 185.015734 -53.020154) (xy 184.992893 -53.069901) (xy 184.963169 -53.115868)
			(xy 184.945528 -53.1368) (xy 184.945274 -53.137054) (xy 184.939698 -53.144147) (xy 184.933446 -53.161059)
			(xy 184.933082 -53.170074) (xy 184.933082 -53.23713) (xy 184.933428 -53.246148) (xy 184.939684 -53.263065)
			(xy 184.945274 -53.27015) (xy 184.945528 -53.27015) (xy 184.945528 -53.270404) (xy 184.963173 -53.291334)
			(xy 184.992901 -53.337301) (xy 185.015749 -53.387048) (xy 185.031247 -53.439551) (xy 185.039076 -53.49373)
			(xy 185.039076 -53.548473) (xy 185.031246 -53.602652) (xy 185.015748 -53.655155) (xy 184.992899 -53.704901)
			(xy 184.963171 -53.750868) (xy 184.946598 -53.77053) (xy 185.31078 -53.77053) (xy 185.311289 -53.741612)
			(xy 185.320016 -53.684439) (xy 185.337274 -53.629239) (xy 185.362667 -53.577277) (xy 185.395613 -53.529743)
			(xy 185.435358 -53.487728) (xy 185.457846 -53.46954) (xy 185.466633 -53.461913) (xy 185.476826 -53.441027)
			(xy 185.477404 -53.429408) (xy 185.477404 -53.349652) (xy 185.476877 -53.338019) (xy 185.466679 -53.317109)
			(xy 185.457846 -53.30952) (xy 185.435361 -53.291331) (xy 185.395628 -53.249309) (xy 185.362691 -53.201774)
			(xy 185.337303 -53.149812) (xy 185.320047 -53.094615) (xy 185.311316 -53.037446) (xy 185.31078 -53.00853)
			(xy 185.311283 -52.981278) (xy 185.319036 -52.92733) (xy 185.334387 -52.875033) (xy 185.357026 -52.825454)
			(xy 185.386489 -52.779601) (xy 185.422179 -52.738409) (xy 185.463368 -52.702714) (xy 185.509217 -52.673246)
			(xy 185.558794 -52.650602) (xy 185.611088 -52.635245) (xy 185.665036 -52.627486) (xy 185.692288 -52.627022)
			(xy 185.718602 -52.62749) (xy 185.770731 -52.634724) (xy 185.821374 -52.649042) (xy 185.869573 -52.670175)
			(xy 185.914416 -52.697721) (xy 185.955056 -52.73116) (xy 185.973212 -52.750212) (xy 185.980726 -52.757623)
			(xy 186.000012 -52.766142) (xy 186.01055 -52.766722) (xy 186.085226 -52.766722) (xy 186.095772 -52.76616)
			(xy 186.115067 -52.757647) (xy 186.122564 -52.750212) (xy 186.140698 -52.731135) (xy 186.181332 -52.697679)
			(xy 186.226177 -52.670123) (xy 186.274382 -52.648988) (xy 186.325033 -52.634676) (xy 186.377171 -52.627457)
			(xy 186.403488 -52.627022) (xy 186.430742 -52.627467) (xy 186.484695 -52.635223) (xy 186.536995 -52.650579)
			(xy 186.586577 -52.673222) (xy 186.632432 -52.702692) (xy 186.673625 -52.738387) (xy 186.709319 -52.779583)
			(xy 186.738787 -52.825439) (xy 186.761428 -52.875022) (xy 186.776781 -52.927323) (xy 186.784535 -52.981276)
			(xy 186.784996 -53.00853) (xy 186.784509 -53.036196) (xy 186.782278 -53.051456) (xy 195.041264 -53.051456)
			(xy 195.045335 -52.995834) (xy 195.057461 -52.941397) (xy 195.077384 -52.889306) (xy 195.10468 -52.840671)
			(xy 195.138766 -52.796528) (xy 195.178915 -52.757819) (xy 195.224273 -52.725368) (xy 195.273873 -52.699867)
			(xy 195.326657 -52.68186) (xy 195.3815 -52.67173) (xy 195.437234 -52.669693) (xy 195.492671 -52.675793)
			(xy 195.546628 -52.689899) (xy 195.597957 -52.711711) (xy 195.645563 -52.740765) (xy 195.688431 -52.77644)
			(xy 195.725648 -52.817977) (xy 195.756421 -52.86449) (xy 195.780093 -52.914987) (xy 195.796161 -52.968394)
			(xy 195.804281 -53.02357) (xy 195.80479 -53.051456) (xy 195.804281 -53.079342) (xy 195.796161 -53.134518)
			(xy 195.780093 -53.187925) (xy 195.756421 -53.238422) (xy 195.725648 -53.284935) (xy 195.688431 -53.326472)
			(xy 195.645563 -53.362147) (xy 195.597957 -53.391201) (xy 195.546628 -53.413013) (xy 195.492671 -53.427119)
			(xy 195.437234 -53.433219) (xy 195.3815 -53.431182) (xy 195.326657 -53.421052) (xy 195.273873 -53.403045)
			(xy 195.224273 -53.377544) (xy 195.178915 -53.345093) (xy 195.138766 -53.306384) (xy 195.10468 -53.262241)
			(xy 195.077384 -53.213606) (xy 195.057461 -53.161515) (xy 195.045335 -53.107078) (xy 195.041264 -53.051456)
			(xy 186.782278 -53.051456) (xy 186.776505 -53.090946) (xy 186.760684 -53.143969) (xy 186.737377 -53.194153)
			(xy 186.707072 -53.240448) (xy 186.670403 -53.281886) (xy 186.628139 -53.317598) (xy 186.60491 -53.332634)
			(xy 186.595211 -53.339244) (xy 186.58278 -53.359125) (xy 186.581034 -53.370734) (xy 186.57316 -53.450744)
			(xy 186.572506 -53.462383) (xy 186.580601 -53.484222) (xy 186.588654 -53.492654) (xy 186.588908 -53.492908)
			(xy 186.607477 -53.511001) (xy 186.640056 -53.551331) (xy 186.666871 -53.595702) (xy 186.687425 -53.643298)
			(xy 186.701342 -53.69324) (xy 186.708362 -53.744608) (xy 186.708796 -53.77053) (xy 186.70835 -53.797783)
			(xy 186.700589 -53.851732) (xy 186.68523 -53.904029) (xy 186.662584 -53.953607) (xy 186.633114 -53.999457)
			(xy 186.597418 -54.040648) (xy 186.556224 -54.076339) (xy 186.51037 -54.105804) (xy 186.460789 -54.128444)
			(xy 186.408491 -54.143798) (xy 186.354541 -54.151553) (xy 186.327288 -54.152038) (xy 186.299917 -54.151594)
			(xy 186.245736 -54.143773) (xy 186.193232 -54.12828) (xy 186.143486 -54.105433) (xy 186.09752 -54.075702)
			(xy 186.07659 -54.058058) (xy 186.076336 -54.057804) (xy 186.069243 -54.052227) (xy 186.052331 -54.045974)
			(xy 186.043316 -54.045612) (xy 185.97626 -54.045612) (xy 185.967241 -54.045947) (xy 185.950324 -54.05221)
			(xy 185.94324 -54.057804) (xy 185.94324 -54.058058) (xy 185.942986 -54.058058) (xy 185.922027 -54.075664)
			(xy 185.876062 -54.105382) (xy 185.826322 -54.128225) (xy 185.773827 -54.143724) (xy 185.719655 -54.15156)
			(xy 185.692288 -54.152038) (xy 185.665038 -54.151533) (xy 185.611092 -54.143776) (xy 185.5588 -54.128421)
			(xy 185.509224 -54.105781) (xy 185.463376 -54.076316) (xy 185.422186 -54.040626) (xy 185.386495 -53.999439)
			(xy 185.357028 -53.953591) (xy 185.334385 -53.904017) (xy 185.319028 -53.851725) (xy 185.311268 -53.79778)
			(xy 185.31078 -53.77053) (xy 184.946598 -53.77053) (xy 184.945528 -53.7718) (xy 184.945274 -53.772054)
			(xy 184.939698 -53.779147) (xy 184.933446 -53.796059) (xy 184.933082 -53.805074) (xy 184.933082 -53.87213)
			(xy 184.933428 -53.881148) (xy 184.939684 -53.898065) (xy 184.945274 -53.90515) (xy 184.945528 -53.90515)
			(xy 184.945528 -53.905404) (xy 184.963173 -53.926334) (xy 184.992901 -53.972301) (xy 185.015749 -54.022048)
			(xy 185.031247 -54.074551) (xy 185.039076 -54.12873) (xy 185.039076 -54.183473) (xy 185.031246 -54.237652)
			(xy 185.015748 -54.290155) (xy 185.001954 -54.320186) (xy 187.230512 -54.320186) (xy 187.230967 -54.292815)
			(xy 187.238787 -54.238636) (xy 187.254279 -54.186132) (xy 187.277123 -54.136386) (xy 187.30685 -54.090419)
			(xy 187.324492 -54.069488) (xy 187.324746 -54.069234) (xy 187.33033 -54.062146) (xy 187.336577 -54.04523)
			(xy 187.336938 -54.036214) (xy 187.336938 -53.969158) (xy 187.336545 -53.960145) (xy 187.330322 -53.943228)
			(xy 187.324746 -53.936138) (xy 187.324492 -53.936138) (xy 187.324492 -53.935884) (xy 187.306878 -53.914932)
			(xy 187.277162 -53.868965) (xy 187.254322 -53.819222) (xy 187.238825 -53.766726) (xy 187.23099 -53.712554)
			(xy 187.230512 -53.685186) (xy 187.230998 -53.657935) (xy 187.238754 -53.603987) (xy 187.254109 -53.551692)
			(xy 187.276751 -53.502115) (xy 187.306217 -53.456265) (xy 187.341908 -53.415074) (xy 187.383099 -53.379383)
			(xy 187.428949 -53.349917) (xy 187.478526 -53.327275) (xy 187.530821 -53.31192) (xy 187.584769 -53.304164)
			(xy 187.639271 -53.304164) (xy 187.693219 -53.31192) (xy 187.745514 -53.327275) (xy 187.795091 -53.349917)
			(xy 187.840941 -53.379383) (xy 187.882132 -53.415074) (xy 187.917823 -53.456265) (xy 187.943716 -53.496555)
			(xy 200.233441 -53.496555) (xy 200.233441 -53.442045) (xy 200.241199 -53.388089) (xy 200.256557 -53.335786)
			(xy 200.279203 -53.286202) (xy 200.308676 -53.240345) (xy 200.344374 -53.19915) (xy 200.385573 -53.163455)
			(xy 200.431432 -53.133987) (xy 200.481018 -53.111346) (xy 200.533322 -53.095992) (xy 200.587279 -53.088239)
			(xy 200.614534 -53.087778) (xy 200.641906 -53.088205) (xy 200.696087 -53.096029) (xy 200.748592 -53.111527)
			(xy 200.798338 -53.134377) (xy 200.844302 -53.164112) (xy 200.865232 -53.181758) (xy 200.865486 -53.182012)
			(xy 200.872571 -53.1876) (xy 200.889489 -53.193846) (xy 200.898506 -53.194204) (xy 200.965562 -53.194204)
			(xy 200.974577 -53.193828) (xy 200.991494 -53.187594) (xy 200.998582 -53.182012) (xy 200.998582 -53.181758)
			(xy 200.998836 -53.181758) (xy 201.019776 -53.164129) (xy 201.065747 -53.134417) (xy 201.115493 -53.111579)
			(xy 201.167991 -53.096086) (xy 201.222165 -53.088254) (xy 201.249534 -53.087778) (xy 201.276783 -53.088295)
			(xy 201.330725 -53.096055) (xy 201.383013 -53.111412) (xy 201.432584 -53.134054) (xy 201.478429 -53.163521)
			(xy 201.519613 -53.199211) (xy 201.5553 -53.240398) (xy 201.584762 -53.286245) (xy 201.6074 -53.335819)
			(xy 201.622753 -53.388109) (xy 201.630508 -53.442051) (xy 201.630508 -53.496549) (xy 201.622753 -53.550491)
			(xy 201.6074 -53.602781) (xy 201.584762 -53.652355) (xy 201.5553 -53.698202) (xy 201.519613 -53.739389)
			(xy 201.478429 -53.775079) (xy 201.432584 -53.804546) (xy 201.383013 -53.827188) (xy 201.330725 -53.842545)
			(xy 201.276783 -53.850305) (xy 201.249534 -53.850794) (xy 201.222164 -53.850309) (xy 201.167986 -53.842496)
			(xy 201.115483 -53.827012) (xy 201.065736 -53.804174) (xy 201.019768 -53.774453) (xy 200.998836 -53.756814)
			(xy 200.998582 -53.75656) (xy 200.991508 -53.750955) (xy 200.974581 -53.74472) (xy 200.965562 -53.744368)
			(xy 200.898506 -53.744368) (xy 200.88949 -53.744735) (xy 200.872574 -53.750976) (xy 200.865486 -53.75656)
			(xy 200.865486 -53.756814) (xy 200.865232 -53.756814) (xy 200.8443 -53.774454) (xy 200.798327 -53.804165)
			(xy 200.74858 -53.827001) (xy 200.696079 -53.842492) (xy 200.641903 -53.85032) (xy 200.614534 -53.850794)
			(xy 200.587279 -53.850361) (xy 200.533322 -53.842608) (xy 200.481018 -53.827254) (xy 200.431432 -53.804613)
			(xy 200.385573 -53.775145) (xy 200.344374 -53.73945) (xy 200.308676 -53.698255) (xy 200.279203 -53.652398)
			(xy 200.256557 -53.602814) (xy 200.241199 -53.550511) (xy 200.233441 -53.496555) (xy 187.943716 -53.496555)
			(xy 187.947289 -53.502115) (xy 187.969931 -53.551692) (xy 187.985286 -53.603987) (xy 187.993042 -53.657935)
			(xy 187.993528 -53.685186) (xy 187.993071 -53.712557) (xy 187.985254 -53.766737) (xy 187.969764 -53.819241)
			(xy 187.946919 -53.868988) (xy 187.917191 -53.914953) (xy 187.899548 -53.935884) (xy 187.899294 -53.936138)
			(xy 187.893727 -53.943238) (xy 187.887469 -53.960144) (xy 187.887102 -53.969158) (xy 187.887102 -54.036214)
			(xy 187.887452 -54.045232) (xy 187.893704 -54.062148) (xy 187.899294 -54.069234) (xy 187.899548 -54.069234)
			(xy 187.899548 -54.069488) (xy 187.917187 -54.09042) (xy 187.946901 -54.136392) (xy 187.969737 -54.18614)
			(xy 187.985228 -54.238641) (xy 187.993055 -54.292817) (xy 187.993528 -54.320186) (xy 187.993042 -54.347437)
			(xy 187.985286 -54.401385) (xy 187.969931 -54.45368) (xy 187.947289 -54.503257) (xy 187.917823 -54.549107)
			(xy 187.882132 -54.590298) (xy 187.840941 -54.625989) (xy 187.795091 -54.655455) (xy 187.745514 -54.678097)
			(xy 187.693219 -54.693452) (xy 187.639271 -54.701208) (xy 187.584769 -54.701208) (xy 187.530821 -54.693452)
			(xy 187.478526 -54.678097) (xy 187.428949 -54.655455) (xy 187.383099 -54.625989) (xy 187.341908 -54.590298)
			(xy 187.306217 -54.549107) (xy 187.276751 -54.503257) (xy 187.254109 -54.45368) (xy 187.238754 -54.401385)
			(xy 187.230998 -54.347437) (xy 187.230512 -54.320186) (xy 185.001954 -54.320186) (xy 184.992899 -54.339901)
			(xy 184.963171 -54.385868) (xy 184.945528 -54.4068) (xy 184.945274 -54.407054) (xy 184.939698 -54.414147)
			(xy 184.933446 -54.431059) (xy 184.933082 -54.440074) (xy 184.933082 -54.50713) (xy 184.933428 -54.516148)
			(xy 184.939684 -54.533065) (xy 184.945274 -54.54015) (xy 184.945528 -54.54015) (xy 184.945528 -54.540404)
			(xy 184.963187 -54.56132) (xy 184.992895 -54.607298) (xy 185.015726 -54.657049) (xy 185.031213 -54.709553)
			(xy 185.039036 -54.763732) (xy 185.039153 -54.770528) (xy 188.171074 -54.770528) (xy 188.171538 -54.743158)
			(xy 188.179354 -54.688978) (xy 188.194842 -54.636474) (xy 188.217685 -54.586727) (xy 188.247411 -54.540761)
			(xy 188.265054 -54.51983) (xy 188.265308 -54.519576) (xy 188.270912 -54.512501) (xy 188.277148 -54.495575)
			(xy 188.2775 -54.486556) (xy 188.2775 -54.4195) (xy 188.277143 -54.410483) (xy 188.270895 -54.393566)
			(xy 188.265308 -54.38648) (xy 188.265054 -54.38648) (xy 188.265054 -54.386226) (xy 188.247422 -54.365288)
			(xy 188.217707 -54.319318) (xy 188.194869 -54.269572) (xy 188.179377 -54.217072) (xy 188.171548 -54.162897)
			(xy 188.171074 -54.135528) (xy 188.17156 -54.108277) (xy 188.179316 -54.054329) (xy 188.194671 -54.002034)
			(xy 188.217313 -53.952457) (xy 188.246779 -53.906607) (xy 188.28247 -53.865416) (xy 188.323661 -53.829725)
			(xy 188.369511 -53.800259) (xy 188.419088 -53.777617) (xy 188.471383 -53.762262) (xy 188.525331 -53.754506)
			(xy 188.579833 -53.754506) (xy 188.633781 -53.762262) (xy 188.686076 -53.777617) (xy 188.735653 -53.800259)
			(xy 188.781503 -53.829725) (xy 188.822694 -53.865416) (xy 188.858385 -53.906607) (xy 188.887851 -53.952457)
			(xy 188.892926 -53.96357) (xy 192.872104 -53.96357) (xy 192.876175 -53.907948) (xy 192.888301 -53.853511)
			(xy 192.908224 -53.80142) (xy 192.93552 -53.752785) (xy 192.969606 -53.708642) (xy 193.009755 -53.669933)
			(xy 193.055113 -53.637482) (xy 193.104713 -53.611981) (xy 193.157497 -53.593974) (xy 193.21234 -53.583844)
			(xy 193.268074 -53.581807) (xy 193.323511 -53.587907) (xy 193.377468 -53.602013) (xy 193.428797 -53.623825)
			(xy 193.476403 -53.652879) (xy 193.519271 -53.688554) (xy 193.556488 -53.730091) (xy 193.587261 -53.776604)
			(xy 193.610933 -53.827101) (xy 193.627001 -53.880508) (xy 193.635121 -53.935684) (xy 193.63563 -53.96357)
			(xy 193.635121 -53.991456) (xy 193.627001 -54.046632) (xy 193.610933 -54.100039) (xy 193.587261 -54.150536)
			(xy 193.556488 -54.197049) (xy 193.519271 -54.238586) (xy 193.476403 -54.274261) (xy 193.428797 -54.303315)
			(xy 193.377468 -54.325127) (xy 193.323511 -54.339233) (xy 193.268074 -54.345333) (xy 193.21234 -54.343296)
			(xy 193.157497 -54.333166) (xy 193.104713 -54.315159) (xy 193.055113 -54.289658) (xy 193.009755 -54.257207)
			(xy 192.969606 -54.218498) (xy 192.93552 -54.174355) (xy 192.908224 -54.12572) (xy 192.888301 -54.073629)
			(xy 192.876175 -54.019192) (xy 192.872104 -53.96357) (xy 188.892926 -53.96357) (xy 188.910493 -54.002034)
			(xy 188.925848 -54.054329) (xy 188.933604 -54.108277) (xy 188.93409 -54.135528) (xy 188.933643 -54.162899)
			(xy 188.925821 -54.217079) (xy 188.910327 -54.269582) (xy 188.887481 -54.319329) (xy 188.857753 -54.365295)
			(xy 188.84011 -54.386226) (xy 188.839856 -54.38648) (xy 188.834266 -54.393564) (xy 188.828023 -54.410483)
			(xy 188.827664 -54.4195) (xy 188.827664 -54.486556) (xy 188.82805 -54.49557) (xy 188.834278 -54.512487)
			(xy 188.839856 -54.519576) (xy 188.84011 -54.519576) (xy 188.84011 -54.51983) (xy 188.857731 -54.540776)
			(xy 188.887445 -54.586745) (xy 188.910285 -54.636489) (xy 188.92578 -54.688987) (xy 188.933613 -54.74316)
			(xy 188.93409 -54.770528) (xy 188.933604 -54.797779) (xy 188.925848 -54.851727) (xy 188.910493 -54.904022)
			(xy 188.887851 -54.953599) (xy 188.865065 -54.989055) (xy 198.001045 -54.989055) (xy 198.001045 -54.934545)
			(xy 198.008803 -54.88059) (xy 198.024161 -54.828289) (xy 198.046806 -54.778705) (xy 198.076277 -54.73285)
			(xy 198.111975 -54.691655) (xy 198.153172 -54.655961) (xy 198.19903 -54.626492) (xy 198.248615 -54.603851)
			(xy 198.300918 -54.588497) (xy 198.354873 -54.580743) (xy 198.382128 -54.580282) (xy 198.41022 -54.580755)
			(xy 198.465799 -54.588986) (xy 198.519568 -54.605281) (xy 198.570366 -54.629287) (xy 198.617092 -54.660485)
			(xy 198.658737 -54.6982) (xy 198.694398 -54.741616) (xy 198.70928 -54.765448) (xy 198.714614 -54.774338)
			(xy 198.731632 -54.78653) (xy 198.82485 -54.80685) (xy 198.845424 -54.802532) (xy 198.85406 -54.79669)
			(xy 198.878132 -54.780704) (xy 198.930061 -54.755358) (xy 198.985216 -54.738129) (xy 199.042338 -54.729409)
			(xy 199.07123 -54.728872) (xy 199.098481 -54.72935) (xy 199.152428 -54.73711) (xy 199.204722 -54.752468)
			(xy 199.254298 -54.775111) (xy 199.300147 -54.804579) (xy 199.341336 -54.840271) (xy 199.377027 -54.881461)
			(xy 199.406494 -54.927311) (xy 199.429136 -54.976888) (xy 199.444492 -55.029182) (xy 199.452251 -55.083129)
			(xy 199.452738 -55.11038) (xy 199.452275 -55.137751) (xy 199.444459 -55.19193) (xy 199.42897 -55.244434)
			(xy 199.406127 -55.294181) (xy 199.3764 -55.340147) (xy 199.358758 -55.361078) (xy 199.358504 -55.361332)
			(xy 199.35294 -55.368434) (xy 199.34668 -55.385339) (xy 199.346312 -55.394352) (xy 199.346312 -55.461408)
			(xy 199.346663 -55.470426) (xy 199.352914 -55.487343) (xy 199.358504 -55.494428) (xy 199.358758 -55.494428)
			(xy 199.358758 -55.494682) (xy 199.37638 -55.51563) (xy 199.406106 -55.561595) (xy 199.428954 -55.611339)
			(xy 199.444452 -55.663838) (xy 199.452283 -55.718015) (xy 199.452285 -55.772755) (xy 199.444459 -55.826932)
			(xy 199.428965 -55.879433) (xy 199.406121 -55.929179) (xy 199.376398 -55.975146) (xy 199.358758 -55.996078)
			(xy 199.358504 -55.996332) (xy 199.35294 -56.003434) (xy 199.34668 -56.020339) (xy 199.346312 -56.029352)
			(xy 199.346312 -56.096408) (xy 199.346663 -56.105426) (xy 199.352914 -56.122343) (xy 199.358504 -56.129428)
			(xy 199.358758 -56.129428) (xy 199.358758 -56.129682) (xy 199.376396 -56.150615) (xy 199.406109 -56.196587)
			(xy 199.428946 -56.246334) (xy 199.444437 -56.298835) (xy 199.452265 -56.353011) (xy 199.452738 -56.38038)
			(xy 199.452252 -56.407631) (xy 199.444496 -56.461579) (xy 199.429141 -56.513874) (xy 199.406499 -56.563451)
			(xy 199.377033 -56.609301) (xy 199.341342 -56.650492) (xy 199.300151 -56.686183) (xy 199.254301 -56.715649)
			(xy 199.204724 -56.738291) (xy 199.152429 -56.753646) (xy 199.098481 -56.761402) (xy 199.043979 -56.761402)
			(xy 198.990031 -56.753646) (xy 198.937736 -56.738291) (xy 198.888159 -56.715649) (xy 198.842309 -56.686183)
			(xy 198.801118 -56.650492) (xy 198.765427 -56.609301) (xy 198.735961 -56.563451) (xy 198.713319 -56.513874)
			(xy 198.697964 -56.461579) (xy 198.690208 -56.407631) (xy 198.689722 -56.38038) (xy 198.690171 -56.353009)
			(xy 198.697992 -56.298829) (xy 198.713485 -56.246326) (xy 198.736331 -56.196579) (xy 198.766059 -56.150613)
			(xy 198.783702 -56.129682) (xy 198.783956 -56.129428) (xy 198.789544 -56.122342) (xy 198.795788 -56.105425)
			(xy 198.796148 -56.096408) (xy 198.796148 -56.029352) (xy 198.795777 -56.020336) (xy 198.789541 -56.003419)
			(xy 198.783956 -55.996332) (xy 198.783702 -55.996332) (xy 198.783702 -55.996078) (xy 198.766043 -55.975161)
			(xy 198.736321 -55.92919) (xy 198.713478 -55.879441) (xy 198.697984 -55.826936) (xy 198.690158 -55.772756)
			(xy 198.69016 -55.718014) (xy 198.697991 -55.663834) (xy 198.713489 -55.611331) (xy 198.736335 -55.561584)
			(xy 198.766061 -55.515615) (xy 198.783702 -55.494682) (xy 198.783956 -55.494428) (xy 198.789544 -55.487342)
			(xy 198.795788 -55.470425) (xy 198.796148 -55.461408) (xy 198.796148 -55.394352) (xy 198.795777 -55.385336)
			(xy 198.789541 -55.368419) (xy 198.783956 -55.361332) (xy 198.783702 -55.360824) (xy 198.772759 -55.348089)
			(xy 198.752917 -55.320998) (xy 198.744078 -55.306722) (xy 198.738744 -55.297832) (xy 198.721726 -55.28564)
			(xy 198.628508 -55.26532) (xy 198.607934 -55.269638) (xy 198.599298 -55.27548) (xy 198.575235 -55.291481)
			(xy 198.523303 -55.316824) (xy 198.468145 -55.334049) (xy 198.411021 -55.342764) (xy 198.382128 -55.343298)
			(xy 198.354873 -55.342857) (xy 198.300918 -55.335103) (xy 198.248615 -55.319749) (xy 198.19903 -55.297108)
			(xy 198.153172 -55.267639) (xy 198.111975 -55.231945) (xy 198.076277 -55.19075) (xy 198.046806 -55.144895)
			(xy 198.024161 -55.095311) (xy 198.008803 -55.04301) (xy 198.001045 -54.989055) (xy 188.865065 -54.989055)
			(xy 188.858385 -54.999449) (xy 188.822694 -55.04064) (xy 188.781503 -55.076331) (xy 188.735653 -55.105797)
			(xy 188.686076 -55.128439) (xy 188.633781 -55.143794) (xy 188.579833 -55.15155) (xy 188.525331 -55.15155)
			(xy 188.471383 -55.143794) (xy 188.419088 -55.128439) (xy 188.369511 -55.105797) (xy 188.323661 -55.076331)
			(xy 188.28247 -55.04064) (xy 188.246779 -54.999449) (xy 188.217313 -54.953599) (xy 188.194671 -54.904022)
			(xy 188.179316 -54.851727) (xy 188.17156 -54.797779) (xy 188.171074 -54.770528) (xy 185.039153 -54.770528)
			(xy 185.039508 -54.791102) (xy 185.039022 -54.818353) (xy 185.031266 -54.872301) (xy 185.015911 -54.924596)
			(xy 184.993269 -54.974173) (xy 184.963803 -55.020023) (xy 184.928112 -55.061214) (xy 184.886921 -55.096905)
			(xy 184.841071 -55.126371) (xy 184.791494 -55.149013) (xy 184.739199 -55.164368) (xy 184.685251 -55.172124)
			(xy 184.630749 -55.172124) (xy 184.576801 -55.164368) (xy 184.524506 -55.149013) (xy 184.474929 -55.126371)
			(xy 184.429079 -55.096905) (xy 184.387888 -55.061214) (xy 184.352197 -55.020023) (xy 184.322731 -54.974173)
			(xy 184.300089 -54.924596) (xy 184.284734 -54.872301) (xy 184.276978 -54.818353) (xy 184.276492 -54.791102)
			(xy 182.378534 -54.791102) (xy 182.375442 -54.812611) (xy 182.360087 -54.864906) (xy 182.337445 -54.914483)
			(xy 182.307979 -54.960333) (xy 182.272288 -55.001524) (xy 182.231097 -55.037215) (xy 182.185247 -55.066681)
			(xy 182.13567 -55.089323) (xy 182.083375 -55.104678) (xy 182.029427 -55.112434) (xy 181.974925 -55.112434)
			(xy 181.920977 -55.104678) (xy 181.868682 -55.089323) (xy 181.819105 -55.066681) (xy 181.773255 -55.037215)
			(xy 181.732064 -55.001524) (xy 181.696373 -54.960333) (xy 181.666907 -54.914483) (xy 181.644265 -54.864906)
			(xy 181.62891 -54.812611) (xy 181.621154 -54.758663) (xy 181.620668 -54.731412) (xy 180.631746 -54.731412)
			(xy 180.69117 -55.722266) (xy 193.934078 -55.722266) (xy 193.938149 -55.666644) (xy 193.950275 -55.612207)
			(xy 193.970198 -55.560116) (xy 193.997494 -55.511481) (xy 194.03158 -55.467338) (xy 194.071729 -55.428629)
			(xy 194.117087 -55.396178) (xy 194.166687 -55.370677) (xy 194.219471 -55.35267) (xy 194.274314 -55.34254)
			(xy 194.330048 -55.340503) (xy 194.385485 -55.346603) (xy 194.439442 -55.360709) (xy 194.490771 -55.382521)
			(xy 194.538377 -55.411575) (xy 194.549528 -55.420855) (xy 196.324645 -55.420855) (xy 196.324645 -55.366345)
			(xy 196.332403 -55.31239) (xy 196.347761 -55.260089) (xy 196.370406 -55.210505) (xy 196.399877 -55.16465)
			(xy 196.435575 -55.123455) (xy 196.476772 -55.087761) (xy 196.52263 -55.058292) (xy 196.572215 -55.035651)
			(xy 196.624518 -55.020297) (xy 196.678473 -55.012543) (xy 196.705728 -55.012082) (xy 196.732042 -55.012537)
			(xy 196.784171 -55.019775) (xy 196.834814 -55.034097) (xy 196.883013 -55.055232) (xy 196.927856 -55.08278)
			(xy 196.968495 -55.11622) (xy 196.986652 -55.135272) (xy 196.994156 -55.142695) (xy 197.013449 -55.151208)
			(xy 197.02399 -55.151782) (xy 197.098666 -55.151782) (xy 197.109216 -55.151253) (xy 197.128512 -55.142719)
			(xy 197.136004 -55.135272) (xy 197.154159 -55.116216) (xy 197.19479 -55.08276) (xy 197.23963 -55.055202)
			(xy 197.287831 -55.034064) (xy 197.338478 -55.019746) (xy 197.390612 -55.012521) (xy 197.416928 -55.012082)
			(xy 197.444177 -55.01259) (xy 197.49812 -55.02035) (xy 197.55041 -55.035707) (xy 197.599983 -55.058349)
			(xy 197.645828 -55.087815) (xy 197.687014 -55.123506) (xy 197.722702 -55.164694) (xy 197.752164 -55.210542)
			(xy 197.774803 -55.260116) (xy 197.790156 -55.312407) (xy 197.797912 -55.366351) (xy 197.797912 -55.420849)
			(xy 197.790156 -55.474793) (xy 197.774803 -55.527084) (xy 197.752164 -55.576658) (xy 197.722702 -55.622506)
			(xy 197.687014 -55.663694) (xy 197.645828 -55.699385) (xy 197.599983 -55.728851) (xy 197.55041 -55.751493)
			(xy 197.49812 -55.76685) (xy 197.444177 -55.77461) (xy 197.416928 -55.775098) (xy 197.390612 -55.774679)
			(xy 197.338482 -55.767435) (xy 197.287838 -55.753106) (xy 197.239639 -55.731964) (xy 197.194797 -55.70441)
			(xy 197.154159 -55.670963) (xy 197.136004 -55.651908) (xy 197.128482 -55.644507) (xy 197.109202 -55.635982)
			(xy 197.098666 -55.635398) (xy 197.02399 -55.635398) (xy 197.013438 -55.635909) (xy 196.994143 -55.644457)
			(xy 196.986652 -55.651908) (xy 196.968514 -55.670981) (xy 196.927881 -55.704437) (xy 196.883037 -55.731993)
			(xy 196.834832 -55.753128) (xy 196.784182 -55.767442) (xy 196.732045 -55.774662) (xy 196.705728 -55.775098)
			(xy 196.678473 -55.774657) (xy 196.624518 -55.766903) (xy 196.572215 -55.751549) (xy 196.52263 -55.728908)
			(xy 196.476772 -55.699439) (xy 196.435575 -55.663745) (xy 196.399877 -55.62255) (xy 196.370406 -55.576695)
			(xy 196.347761 -55.527111) (xy 196.332403 -55.47481) (xy 196.324645 -55.420855) (xy 194.549528 -55.420855)
			(xy 194.581245 -55.44725) (xy 194.618462 -55.488787) (xy 194.649235 -55.5353) (xy 194.672907 -55.585797)
			(xy 194.688975 -55.639204) (xy 194.697095 -55.69438) (xy 194.697604 -55.722266) (xy 194.697095 -55.750152)
			(xy 194.688975 -55.805328) (xy 194.672907 -55.858735) (xy 194.649235 -55.909232) (xy 194.618462 -55.955745)
			(xy 194.581245 -55.997282) (xy 194.538377 -56.032957) (xy 194.490771 -56.062011) (xy 194.439442 -56.083823)
			(xy 194.385485 -56.097929) (xy 194.330048 -56.104029) (xy 194.274314 -56.101992) (xy 194.219471 -56.091862)
			(xy 194.166687 -56.073855) (xy 194.117087 -56.048354) (xy 194.071729 -56.015903) (xy 194.03158 -55.977194)
			(xy 193.997494 -55.933051) (xy 193.970198 -55.884416) (xy 193.950275 -55.832325) (xy 193.938149 -55.777888)
			(xy 193.934078 -55.722266) (xy 180.69117 -55.722266) (xy 180.767974 -57.002934) (xy 189.663578 -57.002934)
			(xy 189.664102 -56.974843) (xy 189.672324 -56.919268) (xy 189.68861 -56.8655) (xy 189.712608 -56.814702)
			(xy 189.743798 -56.767975) (xy 189.781506 -56.726329) (xy 189.824915 -56.690665) (xy 189.848744 -56.675782)
			(xy 189.857634 -56.670448) (xy 189.869826 -56.65343) (xy 189.890146 -56.560212) (xy 189.885828 -56.539638)
			(xy 189.879986 -56.531002) (xy 189.863983 -56.50694) (xy 189.838641 -56.455008) (xy 189.821417 -56.399849)
			(xy 189.812702 -56.342725) (xy 189.812168 -56.313832) (xy 189.812685 -56.286581) (xy 189.820437 -56.232633)
			(xy 189.835788 -56.180338) (xy 189.858425 -56.130759) (xy 189.887887 -56.084907) (xy 189.923575 -56.043715)
			(xy 189.964762 -56.008021) (xy 190.01061 -55.978552) (xy 190.060185 -55.955907) (xy 190.112478 -55.940549)
			(xy 190.166425 -55.932789) (xy 190.193676 -55.932324) (xy 190.221046 -55.932798) (xy 190.275225 -55.940613)
			(xy 190.327728 -55.9561) (xy 190.377475 -55.97894) (xy 190.423442 -56.008663) (xy 190.444374 -56.026304)
			(xy 190.444628 -56.026558) (xy 190.451726 -56.032127) (xy 190.468634 -56.038383) (xy 190.477648 -56.03875)
			(xy 190.544704 -56.03875) (xy 190.553722 -56.038406) (xy 190.57064 -56.03215) (xy 190.577724 -56.026558)
			(xy 190.577724 -56.026304) (xy 190.577978 -56.026304) (xy 190.598911 -56.008663) (xy 190.644879 -55.978939)
			(xy 190.694625 -55.956093) (xy 190.747127 -55.940597) (xy 190.801305 -55.932768) (xy 190.856047 -55.932768)
			(xy 190.910225 -55.940597) (xy 190.962727 -55.956093) (xy 191.012473 -55.978939) (xy 191.058441 -56.008663)
			(xy 191.079374 -56.026304) (xy 191.079628 -56.026558) (xy 191.086726 -56.032127) (xy 191.103634 -56.038383)
			(xy 191.112648 -56.03875) (xy 191.179704 -56.03875) (xy 191.188722 -56.038406) (xy 191.20564 -56.03215)
			(xy 191.212724 -56.026558) (xy 191.212724 -56.026304) (xy 191.212978 -56.026304) (xy 191.233908 -56.008662)
			(xy 191.279881 -55.978951) (xy 191.329629 -55.956115) (xy 191.382131 -55.940625) (xy 191.436307 -55.932797)
			(xy 191.463676 -55.932324) (xy 191.490932 -55.932721) (xy 191.54489 -55.940476) (xy 191.597196 -55.955831)
			(xy 191.646783 -55.978474) (xy 191.692643 -56.007944) (xy 191.733842 -56.043641) (xy 191.769541 -56.084838)
			(xy 191.799014 -56.130696) (xy 191.82166 -56.180282) (xy 191.837019 -56.232586) (xy 191.844777 -56.286544)
			(xy 191.844777 -56.297068) (xy 192.186558 -56.297068) (xy 192.190629 -56.241446) (xy 192.202755 -56.187009)
			(xy 192.222678 -56.134918) (xy 192.249974 -56.086283) (xy 192.28406 -56.04214) (xy 192.324209 -56.003431)
			(xy 192.369567 -55.97098) (xy 192.419167 -55.945479) (xy 192.471951 -55.927472) (xy 192.526794 -55.917342)
			(xy 192.582528 -55.915305) (xy 192.637965 -55.921405) (xy 192.691922 -55.935511) (xy 192.743251 -55.957323)
			(xy 192.790857 -55.986377) (xy 192.833725 -56.022052) (xy 192.870942 -56.063589) (xy 192.901715 -56.110102)
			(xy 192.925387 -56.160599) (xy 192.941455 -56.214006) (xy 192.949575 -56.269182) (xy 192.950084 -56.297068)
			(xy 192.949575 -56.324954) (xy 192.941455 -56.38013) (xy 192.925387 -56.433537) (xy 192.901715 -56.484034)
			(xy 192.870942 -56.530547) (xy 192.833725 -56.572084) (xy 192.790857 -56.607759) (xy 192.743251 -56.636813)
			(xy 192.691922 -56.658625) (xy 192.637965 -56.672731) (xy 192.582528 -56.678831) (xy 192.526794 -56.676794)
			(xy 192.471951 -56.666664) (xy 192.419167 -56.648657) (xy 192.369567 -56.623156) (xy 192.324209 -56.590705)
			(xy 192.28406 -56.551996) (xy 192.249974 -56.507853) (xy 192.222678 -56.459218) (xy 192.202755 -56.407127)
			(xy 192.190629 -56.35269) (xy 192.186558 -56.297068) (xy 191.844777 -56.297068) (xy 191.844777 -56.341056)
			(xy 191.837019 -56.395014) (xy 191.82166 -56.447318) (xy 191.799014 -56.496904) (xy 191.769541 -56.542762)
			(xy 191.733842 -56.583959) (xy 191.692643 -56.619656) (xy 191.646783 -56.649126) (xy 191.597196 -56.671769)
			(xy 191.54489 -56.687124) (xy 191.490932 -56.694879) (xy 191.463676 -56.69534) (xy 191.436305 -56.694903)
			(xy 191.382124 -56.68708) (xy 191.32962 -56.671585) (xy 191.279873 -56.648737) (xy 191.233908 -56.619005)
			(xy 191.212978 -56.60136) (xy 191.212724 -56.601106) (xy 191.205634 -56.595524) (xy 191.18872 -56.589274)
			(xy 191.179704 -56.588914) (xy 191.112648 -56.588914) (xy 191.103633 -56.589291) (xy 191.086716 -56.595524)
			(xy 191.079628 -56.601106) (xy 191.079628 -56.60136) (xy 191.079374 -56.60136) (xy 191.058441 -56.619001)
			(xy 191.012473 -56.648725) (xy 190.962727 -56.671571) (xy 190.910225 -56.687067) (xy 190.856047 -56.694896)
			(xy 190.801305 -56.694896) (xy 190.747127 -56.687067) (xy 190.694625 -56.671571) (xy 190.644879 -56.648725)
			(xy 190.598911 -56.619001) (xy 190.577978 -56.60136) (xy 190.577724 -56.601106) (xy 190.570634 -56.595524)
			(xy 190.55372 -56.589274) (xy 190.544704 -56.588914) (xy 190.477648 -56.588914) (xy 190.468633 -56.589291)
			(xy 190.451716 -56.595524) (xy 190.444628 -56.601106) (xy 190.44412 -56.60136) (xy 190.431388 -56.612307)
			(xy 190.404295 -56.632146) (xy 190.390018 -56.640984) (xy 190.381128 -56.646318) (xy 190.368936 -56.663336)
			(xy 190.348616 -56.756554) (xy 190.352934 -56.777128) (xy 190.358776 -56.785764) (xy 190.37476 -56.809838)
			(xy 190.400107 -56.861766) (xy 190.417337 -56.91692) (xy 190.426057 -56.974042) (xy 190.426594 -57.002934)
			(xy 190.426108 -57.030185) (xy 190.425826 -57.032144) (xy 193.585844 -57.032144) (xy 193.589915 -56.976522)
			(xy 193.602041 -56.922085) (xy 193.621964 -56.869994) (xy 193.64926 -56.821359) (xy 193.683346 -56.777216)
			(xy 193.723495 -56.738507) (xy 193.768853 -56.706056) (xy 193.818453 -56.680555) (xy 193.871237 -56.662548)
			(xy 193.92608 -56.652418) (xy 193.981814 -56.650381) (xy 194.037251 -56.656481) (xy 194.091208 -56.670587)
			(xy 194.142537 -56.692399) (xy 194.190143 -56.721453) (xy 194.233011 -56.757128) (xy 194.270228 -56.798665)
			(xy 194.301001 -56.845178) (xy 194.324673 -56.895675) (xy 194.340741 -56.949082) (xy 194.348861 -57.004258)
			(xy 194.34937 -57.032144) (xy 194.348861 -57.06003) (xy 194.340741 -57.115206) (xy 194.324673 -57.168613)
			(xy 194.301001 -57.21911) (xy 194.270228 -57.265623) (xy 194.233011 -57.30716) (xy 194.190143 -57.342835)
			(xy 194.142537 -57.371889) (xy 194.091208 -57.393701) (xy 194.037251 -57.407807) (xy 193.981814 -57.413907)
			(xy 193.92608 -57.41187) (xy 193.871237 -57.40174) (xy 193.818453 -57.383733) (xy 193.768853 -57.358232)
			(xy 193.723495 -57.325781) (xy 193.683346 -57.287072) (xy 193.64926 -57.242929) (xy 193.621964 -57.194294)
			(xy 193.602041 -57.142203) (xy 193.589915 -57.087766) (xy 193.585844 -57.032144) (xy 190.425826 -57.032144)
			(xy 190.418352 -57.084133) (xy 190.402997 -57.136428) (xy 190.380355 -57.186005) (xy 190.350889 -57.231855)
			(xy 190.315198 -57.273046) (xy 190.274007 -57.308737) (xy 190.228157 -57.338203) (xy 190.17858 -57.360845)
			(xy 190.126285 -57.3762) (xy 190.072337 -57.383956) (xy 190.017835 -57.383956) (xy 189.963887 -57.3762)
			(xy 189.911592 -57.360845) (xy 189.862015 -57.338203) (xy 189.816165 -57.308737) (xy 189.774974 -57.273046)
			(xy 189.739283 -57.231855) (xy 189.709817 -57.186005) (xy 189.687175 -57.136428) (xy 189.67182 -57.084133)
			(xy 189.664064 -57.030185) (xy 189.663578 -57.002934) (xy 180.767974 -57.002934) (xy 180.796901 -57.48528)
			(xy 198.705976 -57.48528) (xy 198.710047 -57.429658) (xy 198.722173 -57.375221) (xy 198.742096 -57.32313)
			(xy 198.769392 -57.274495) (xy 198.803478 -57.230352) (xy 198.843627 -57.191643) (xy 198.888985 -57.159192)
			(xy 198.938585 -57.133691) (xy 198.991369 -57.115684) (xy 199.046212 -57.105554) (xy 199.101946 -57.103517)
			(xy 199.157383 -57.109617) (xy 199.21134 -57.123723) (xy 199.262669 -57.145535) (xy 199.310275 -57.174589)
			(xy 199.353143 -57.210264) (xy 199.39036 -57.251801) (xy 199.421133 -57.298314) (xy 199.444805 -57.348811)
			(xy 199.460873 -57.402218) (xy 199.468993 -57.457394) (xy 199.469502 -57.48528) (xy 199.468993 -57.513166)
			(xy 199.460873 -57.568342) (xy 199.444805 -57.621749) (xy 199.421133 -57.672246) (xy 199.39036 -57.718759)
			(xy 199.353143 -57.760296) (xy 199.310275 -57.795971) (xy 199.262669 -57.825025) (xy 199.21134 -57.846837)
			(xy 199.157383 -57.860943) (xy 199.101946 -57.867043) (xy 199.046212 -57.865006) (xy 198.991369 -57.854876)
			(xy 198.938585 -57.836869) (xy 198.888985 -57.811368) (xy 198.843627 -57.778917) (xy 198.803478 -57.740208)
			(xy 198.769392 -57.696065) (xy 198.742096 -57.64743) (xy 198.722173 -57.595339) (xy 198.710047 -57.540902)
			(xy 198.705976 -57.48528) (xy 180.796901 -57.48528) (xy 180.868511 -58.679334) (xy 190.095378 -58.679334)
			(xy 190.095808 -58.653019) (xy 190.103052 -58.600889) (xy 190.117379 -58.550246) (xy 190.138518 -58.502047)
			(xy 190.16607 -58.457205) (xy 190.199514 -58.416566) (xy 190.218568 -58.39841) (xy 190.225963 -58.390882)
			(xy 190.234492 -58.371607) (xy 190.235078 -58.361072) (xy 190.235078 -58.286396) (xy 190.234571 -58.275844)
			(xy 190.226021 -58.256548) (xy 190.218568 -58.249058) (xy 190.199493 -58.230922) (xy 190.166039 -58.190287)
			(xy 190.138483 -58.145443) (xy 190.117348 -58.097238) (xy 190.103035 -58.046588) (xy 190.095814 -57.994451)
			(xy 190.095378 -57.968134) (xy 190.095864 -57.940883) (xy 190.10362 -57.886935) (xy 190.118975 -57.83464)
			(xy 190.141617 -57.785063) (xy 190.171083 -57.739213) (xy 190.206774 -57.698022) (xy 190.247965 -57.662331)
			(xy 190.293815 -57.632865) (xy 190.343392 -57.610223) (xy 190.395687 -57.594868) (xy 190.449635 -57.587112)
			(xy 190.504137 -57.587112) (xy 190.558085 -57.594868) (xy 190.61038 -57.610223) (xy 190.659957 -57.632865)
			(xy 190.705807 -57.662331) (xy 190.746998 -57.698022) (xy 190.782689 -57.739213) (xy 190.812155 -57.785063)
			(xy 190.834797 -57.83464) (xy 190.850152 -57.886935) (xy 190.857908 -57.940883) (xy 190.858394 -57.968134)
			(xy 190.857951 -57.994449) (xy 190.850712 -58.046578) (xy 190.842367 -58.076084) (xy 199.45807 -58.076084)
			(xy 199.462141 -58.020462) (xy 199.474267 -57.966025) (xy 199.49419 -57.913934) (xy 199.521486 -57.865299)
			(xy 199.555572 -57.821156) (xy 199.595721 -57.782447) (xy 199.641079 -57.749996) (xy 199.690679 -57.724495)
			(xy 199.743463 -57.706488) (xy 199.798306 -57.696358) (xy 199.85404 -57.694321) (xy 199.909477 -57.700421)
			(xy 199.963434 -57.714527) (xy 200.014763 -57.736339) (xy 200.062369 -57.765393) (xy 200.105237 -57.801068)
			(xy 200.142454 -57.842605) (xy 200.15879 -57.867296) (xy 201.743054 -57.867296) (xy 201.747125 -57.811674)
			(xy 201.759251 -57.757237) (xy 201.779174 -57.705146) (xy 201.80647 -57.656511) (xy 201.840556 -57.612368)
			(xy 201.880705 -57.573659) (xy 201.926063 -57.541208) (xy 201.975663 -57.515707) (xy 202.028447 -57.4977)
			(xy 202.08329 -57.48757) (xy 202.139024 -57.485533) (xy 202.194461 -57.491633) (xy 202.248418 -57.505739)
			(xy 202.299747 -57.527551) (xy 202.347353 -57.556605) (xy 202.390221 -57.59228) (xy 202.427438 -57.633817)
			(xy 202.458211 -57.68033) (xy 202.481883 -57.730827) (xy 202.497951 -57.784234) (xy 202.506071 -57.83941)
			(xy 202.50658 -57.867296) (xy 202.506071 -57.895182) (xy 202.497951 -57.950358) (xy 202.481883 -58.003765)
			(xy 202.458211 -58.054262) (xy 202.427438 -58.100775) (xy 202.390221 -58.142312) (xy 202.347353 -58.177987)
			(xy 202.299747 -58.207041) (xy 202.248418 -58.228853) (xy 202.194461 -58.242959) (xy 202.139024 -58.249059)
			(xy 202.08329 -58.247022) (xy 202.028447 -58.236892) (xy 201.975663 -58.218885) (xy 201.926063 -58.193384)
			(xy 201.880705 -58.160933) (xy 201.840556 -58.122224) (xy 201.80647 -58.078081) (xy 201.779174 -58.029446)
			(xy 201.759251 -57.977355) (xy 201.747125 -57.922918) (xy 201.743054 -57.867296) (xy 200.15879 -57.867296)
			(xy 200.173227 -57.889118) (xy 200.196899 -57.939615) (xy 200.212967 -57.993022) (xy 200.221087 -58.048198)
			(xy 200.221596 -58.076084) (xy 200.221087 -58.10397) (xy 200.212967 -58.159146) (xy 200.196899 -58.212553)
			(xy 200.173227 -58.26305) (xy 200.142454 -58.309563) (xy 200.105237 -58.3511) (xy 200.062369 -58.386775)
			(xy 200.014763 -58.415829) (xy 199.963434 -58.437641) (xy 199.909477 -58.451747) (xy 199.85404 -58.457847)
			(xy 199.798306 -58.45581) (xy 199.743463 -58.44568) (xy 199.690679 -58.427673) (xy 199.641079 -58.402172)
			(xy 199.595721 -58.369721) (xy 199.555572 -58.331012) (xy 199.521486 -58.286869) (xy 199.49419 -58.238234)
			(xy 199.474267 -58.186143) (xy 199.462141 -58.131706) (xy 199.45807 -58.076084) (xy 190.842367 -58.076084)
			(xy 190.836388 -58.097222) (xy 190.815251 -58.145421) (xy 190.7877 -58.190264) (xy 190.754257 -58.230902)
			(xy 190.735204 -58.249058) (xy 190.72782 -58.256594) (xy 190.719285 -58.275863) (xy 190.718694 -58.286396)
			(xy 190.718694 -58.361072) (xy 190.719227 -58.371621) (xy 190.72776 -58.390916) (xy 190.735204 -58.39841)
			(xy 190.754258 -58.416567) (xy 190.787715 -58.457196) (xy 190.815274 -58.502036) (xy 190.836413 -58.550237)
			(xy 190.839519 -58.561224) (xy 200.662284 -58.561224) (xy 200.666355 -58.505602) (xy 200.678481 -58.451165)
			(xy 200.698404 -58.399074) (xy 200.7257 -58.350439) (xy 200.759786 -58.306296) (xy 200.799935 -58.267587)
			(xy 200.845293 -58.235136) (xy 200.894893 -58.209635) (xy 200.947677 -58.191628) (xy 201.00252 -58.181498)
			(xy 201.058254 -58.179461) (xy 201.113691 -58.185561) (xy 201.167648 -58.199667) (xy 201.218977 -58.221479)
			(xy 201.266583 -58.250533) (xy 201.309451 -58.286208) (xy 201.346668 -58.327745) (xy 201.377441 -58.374258)
			(xy 201.401113 -58.424755) (xy 201.408623 -58.449718) (xy 202.908914 -58.449718) (xy 202.912985 -58.394096)
			(xy 202.925111 -58.339659) (xy 202.945034 -58.287568) (xy 202.97233 -58.238933) (xy 203.006416 -58.19479)
			(xy 203.046565 -58.156081) (xy 203.091923 -58.12363) (xy 203.141523 -58.098129) (xy 203.194307 -58.080122)
			(xy 203.24915 -58.069992) (xy 203.304884 -58.067955) (xy 203.360321 -58.074055) (xy 203.414278 -58.088161)
			(xy 203.465607 -58.109973) (xy 203.513213 -58.139027) (xy 203.556081 -58.174702) (xy 203.593298 -58.216239)
			(xy 203.624071 -58.262752) (xy 203.647743 -58.313249) (xy 203.663811 -58.366656) (xy 203.671931 -58.421832)
			(xy 203.67244 -58.449718) (xy 203.671931 -58.477604) (xy 203.663811 -58.53278) (xy 203.647743 -58.586187)
			(xy 203.624071 -58.636684) (xy 203.593298 -58.683197) (xy 203.556081 -58.724734) (xy 203.513213 -58.760409)
			(xy 203.465607 -58.789463) (xy 203.414278 -58.811275) (xy 203.360321 -58.825381) (xy 203.304884 -58.831481)
			(xy 203.24915 -58.829444) (xy 203.194307 -58.819314) (xy 203.141523 -58.801307) (xy 203.091923 -58.775806)
			(xy 203.046565 -58.743355) (xy 203.006416 -58.704646) (xy 202.97233 -58.660503) (xy 202.945034 -58.611868)
			(xy 202.925111 -58.559777) (xy 202.912985 -58.50534) (xy 202.908914 -58.449718) (xy 201.408623 -58.449718)
			(xy 201.417181 -58.478162) (xy 201.425301 -58.533338) (xy 201.42581 -58.561224) (xy 201.425301 -58.58911)
			(xy 201.417181 -58.644286) (xy 201.401113 -58.697693) (xy 201.377441 -58.74819) (xy 201.346668 -58.794703)
			(xy 201.309451 -58.83624) (xy 201.266583 -58.871915) (xy 201.218977 -58.900969) (xy 201.167648 -58.922781)
			(xy 201.113691 -58.936887) (xy 201.058254 -58.942987) (xy 201.00252 -58.94095) (xy 200.947677 -58.93082)
			(xy 200.894893 -58.912813) (xy 200.845293 -58.887312) (xy 200.799935 -58.854861) (xy 200.759786 -58.816152)
			(xy 200.7257 -58.772009) (xy 200.698404 -58.723374) (xy 200.678481 -58.671283) (xy 200.666355 -58.616846)
			(xy 200.662284 -58.561224) (xy 190.839519 -58.561224) (xy 190.850731 -58.600884) (xy 190.857955 -58.653018)
			(xy 190.858394 -58.679334) (xy 190.857908 -58.706585) (xy 190.850152 -58.760533) (xy 190.834797 -58.812828)
			(xy 190.812155 -58.862405) (xy 190.782689 -58.908255) (xy 190.746998 -58.949446) (xy 190.705807 -58.985137)
			(xy 190.659957 -59.014603) (xy 190.61038 -59.037245) (xy 190.558085 -59.0526) (xy 190.504137 -59.060356)
			(xy 190.449635 -59.060356) (xy 190.395687 -59.0526) (xy 190.343392 -59.037245) (xy 190.293815 -59.014603)
			(xy 190.247965 -58.985137) (xy 190.206774 -58.949446) (xy 190.171083 -58.908255) (xy 190.141617 -58.862405)
			(xy 190.118975 -58.812828) (xy 190.10362 -58.760533) (xy 190.095864 -58.706585) (xy 190.095378 -58.679334)
			(xy 180.868511 -58.679334) (xy 180.898215 -59.174634) (xy 199.193148 -59.174634) (xy 199.197219 -59.119012)
			(xy 199.209345 -59.064575) (xy 199.229268 -59.012484) (xy 199.256564 -58.963849) (xy 199.29065 -58.919706)
			(xy 199.330799 -58.880997) (xy 199.376157 -58.848546) (xy 199.425757 -58.823045) (xy 199.478541 -58.805038)
			(xy 199.533384 -58.794908) (xy 199.589118 -58.792871) (xy 199.644555 -58.798971) (xy 199.698512 -58.813077)
			(xy 199.749841 -58.834889) (xy 199.797447 -58.863943) (xy 199.840315 -58.899618) (xy 199.877532 -58.941155)
			(xy 199.908305 -58.987668) (xy 199.931977 -59.038165) (xy 199.948045 -59.091572) (xy 199.956165 -59.146748)
			(xy 199.956674 -59.174634) (xy 199.956165 -59.20252) (xy 199.948045 -59.257696) (xy 199.931977 -59.311103)
			(xy 199.908305 -59.3616) (xy 199.877532 -59.408113) (xy 199.840315 -59.44965) (xy 199.797447 -59.485325)
			(xy 199.749841 -59.514379) (xy 199.698512 -59.536191) (xy 199.644555 -59.550297) (xy 199.589118 -59.556397)
			(xy 199.533384 -59.55436) (xy 199.478541 -59.54423) (xy 199.425757 -59.526223) (xy 199.376157 -59.500722)
			(xy 199.330799 -59.468271) (xy 199.29065 -59.429562) (xy 199.256564 -59.385419) (xy 199.229268 -59.336784)
			(xy 199.209345 -59.284693) (xy 199.197219 -59.230256) (xy 199.193148 -59.174634) (xy 180.898215 -59.174634)
			(xy 180.930296 -59.709558) (xy 180.931312 -59.744864) (xy 180.931087 -59.767819) (xy 180.927524 -59.81359)
			(xy 180.9242 -59.836304) (xy 180.895525 -60.019254) (xy 190.235761 -60.019254) (xy 190.235761 -59.964746)
			(xy 190.243519 -59.910792) (xy 190.258877 -59.858492) (xy 190.281522 -59.80891) (xy 190.310993 -59.763056)
			(xy 190.346691 -59.721863) (xy 190.387888 -59.686169) (xy 190.433745 -59.656703) (xy 190.483329 -59.634063)
			(xy 190.535631 -59.618711) (xy 190.589586 -59.610959) (xy 190.61684 -59.610498) (xy 190.644209 -59.611)
			(xy 190.698386 -59.618809) (xy 190.750889 -59.63429) (xy 190.800637 -59.657124) (xy 190.846605 -59.68684)
			(xy 190.867538 -59.704478) (xy 190.867792 -59.704732) (xy 190.874874 -59.710325) (xy 190.891794 -59.716567)
			(xy 190.900812 -59.716924) (xy 190.967868 -59.716924) (xy 190.976883 -59.716546) (xy 190.9938 -59.710313)
			(xy 191.000888 -59.704732) (xy 191.000888 -59.704478) (xy 191.001142 -59.704478) (xy 191.022075 -59.686837)
			(xy 191.068043 -59.657113) (xy 191.117789 -59.634267) (xy 191.170291 -59.618771) (xy 191.224469 -59.610942)
			(xy 191.279211 -59.610942) (xy 191.333389 -59.618771) (xy 191.385891 -59.634267) (xy 191.435637 -59.657113)
			(xy 191.481605 -59.686837) (xy 191.502538 -59.704478) (xy 191.502792 -59.704732) (xy 191.509874 -59.710325)
			(xy 191.526794 -59.716567) (xy 191.535812 -59.716924) (xy 191.602868 -59.716924) (xy 191.611883 -59.716546)
			(xy 191.6288 -59.710313) (xy 191.635888 -59.704732) (xy 191.635888 -59.704478) (xy 191.636142 -59.704478)
			(xy 191.657082 -59.686849) (xy 191.703053 -59.657137) (xy 191.752799 -59.634299) (xy 191.805297 -59.618805)
			(xy 191.859471 -59.610974) (xy 191.88684 -59.610498) (xy 191.91409 -59.610975) (xy 191.968034 -59.618736)
			(xy 192.020325 -59.634095) (xy 192.069898 -59.656738) (xy 192.115744 -59.686206) (xy 192.15693 -59.721898)
			(xy 192.192618 -59.763088) (xy 192.222081 -59.808937) (xy 192.244719 -59.858513) (xy 192.260073 -59.910805)
			(xy 192.267828 -59.96475) (xy 192.267828 -60.01925) (xy 192.260073 -60.073195) (xy 192.244719 -60.125487)
			(xy 192.222081 -60.175063) (xy 192.192618 -60.220912) (xy 192.15693 -60.262102) (xy 192.115744 -60.297794)
			(xy 192.069898 -60.327262) (xy 192.020325 -60.349905) (xy 191.968034 -60.365264) (xy 191.91409 -60.373025)
			(xy 191.88684 -60.373514) (xy 191.859471 -60.373021) (xy 191.805293 -60.365209) (xy 191.75279 -60.349726)
			(xy 191.703043 -60.326891) (xy 191.657075 -60.297172) (xy 191.636142 -60.279534) (xy 191.635888 -60.27928)
			(xy 191.628811 -60.27368) (xy 191.611887 -60.267442) (xy 191.602868 -60.267088) (xy 191.535812 -60.267088)
			(xy 191.526796 -60.267453) (xy 191.509879 -60.273695) (xy 191.502792 -60.27928) (xy 191.502538 -60.279534)
			(xy 191.481605 -60.297175) (xy 191.435637 -60.326899) (xy 191.385891 -60.349745) (xy 191.333389 -60.365241)
			(xy 191.279211 -60.37307) (xy 191.224469 -60.37307) (xy 191.170291 -60.365241) (xy 191.117789 -60.349745)
			(xy 191.068043 -60.326899) (xy 191.022075 -60.297175) (xy 191.001142 -60.279534) (xy 191.000888 -60.27928)
			(xy 190.993811 -60.27368) (xy 190.976887 -60.267442) (xy 190.967868 -60.267088) (xy 190.900812 -60.267088)
			(xy 190.891796 -60.267453) (xy 190.874879 -60.273695) (xy 190.867792 -60.27928) (xy 190.867792 -60.279534)
			(xy 190.867538 -60.279534) (xy 190.846607 -60.297174) (xy 190.800633 -60.326885) (xy 190.750885 -60.34972)
			(xy 190.698385 -60.365211) (xy 190.644209 -60.373039) (xy 190.61684 -60.373514) (xy 190.589586 -60.373041)
			(xy 190.535631 -60.365289) (xy 190.483329 -60.349937) (xy 190.433745 -60.327297) (xy 190.387888 -60.297831)
			(xy 190.346691 -60.262137) (xy 190.310993 -60.220944) (xy 190.281522 -60.17509) (xy 190.258877 -60.125508)
			(xy 190.243519 -60.073208) (xy 190.235761 -60.019254) (xy 180.895525 -60.019254) (xy 180.799274 -60.633356)
			(xy 201.896978 -60.633356) (xy 201.901049 -60.577734) (xy 201.913175 -60.523297) (xy 201.933098 -60.471206)
			(xy 201.960394 -60.422571) (xy 201.99448 -60.378428) (xy 202.034629 -60.339719) (xy 202.079987 -60.307268)
			(xy 202.129587 -60.281767) (xy 202.182371 -60.26376) (xy 202.237214 -60.25363) (xy 202.292948 -60.251593)
			(xy 202.348385 -60.257693) (xy 202.402342 -60.271799) (xy 202.453671 -60.293611) (xy 202.501277 -60.322665)
			(xy 202.544145 -60.35834) (xy 202.581362 -60.399877) (xy 202.612135 -60.44639) (xy 202.635807 -60.496887)
			(xy 202.651875 -60.550294) (xy 202.659995 -60.60547) (xy 202.660504 -60.633356) (xy 202.659995 -60.661242)
			(xy 202.651875 -60.716418) (xy 202.635807 -60.769825) (xy 202.612135 -60.820322) (xy 202.581362 -60.866835)
			(xy 202.544145 -60.908372) (xy 202.501277 -60.944047) (xy 202.453671 -60.973101) (xy 202.402342 -60.994913)
			(xy 202.348385 -61.009019) (xy 202.292948 -61.015119) (xy 202.237214 -61.013082) (xy 202.182371 -61.002952)
			(xy 202.129587 -60.984945) (xy 202.079987 -60.959444) (xy 202.034629 -60.926993) (xy 201.99448 -60.888284)
			(xy 201.960394 -60.844141) (xy 201.933098 -60.795506) (xy 201.913175 -60.743415) (xy 201.901049 -60.688978)
			(xy 201.896978 -60.633356) (xy 180.799274 -60.633356) (xy 180.665351 -61.487812) (xy 200.404474 -61.487812)
			(xy 200.408545 -61.43219) (xy 200.420671 -61.377753) (xy 200.440594 -61.325662) (xy 200.46789 -61.277027)
			(xy 200.501976 -61.232884) (xy 200.542125 -61.194175) (xy 200.587483 -61.161724) (xy 200.637083 -61.136223)
			(xy 200.689867 -61.118216) (xy 200.74471 -61.108086) (xy 200.800444 -61.106049) (xy 200.855881 -61.112149)
			(xy 200.909838 -61.126255) (xy 200.961167 -61.148067) (xy 201.008773 -61.177121) (xy 201.051641 -61.212796)
			(xy 201.088858 -61.254333) (xy 201.119631 -61.300846) (xy 201.143303 -61.351343) (xy 201.159371 -61.40475)
			(xy 201.167491 -61.459926) (xy 201.168 -61.487812) (xy 201.167491 -61.515698) (xy 201.159371 -61.570874)
			(xy 201.143303 -61.624281) (xy 201.119631 -61.674778) (xy 201.088858 -61.721291) (xy 201.051641 -61.762828)
			(xy 201.008773 -61.798503) (xy 200.961167 -61.827557) (xy 200.909838 -61.849369) (xy 200.855881 -61.863475)
			(xy 200.800444 -61.869575) (xy 200.74471 -61.867538) (xy 200.689867 -61.857408) (xy 200.637083 -61.839401)
			(xy 200.587483 -61.8139) (xy 200.542125 -61.781449) (xy 200.501976 -61.74274) (xy 200.46789 -61.698597)
			(xy 200.440594 -61.649962) (xy 200.420671 -61.597871) (xy 200.408545 -61.543434) (xy 200.404474 -61.487812)
			(xy 180.665351 -61.487812) (xy 180.566103 -62.121034) (xy 198.342248 -62.121034) (xy 198.346319 -62.065412)
			(xy 198.358445 -62.010975) (xy 198.378368 -61.958884) (xy 198.405664 -61.910249) (xy 198.43975 -61.866106)
			(xy 198.479899 -61.827397) (xy 198.525257 -61.794946) (xy 198.574857 -61.769445) (xy 198.627641 -61.751438)
			(xy 198.682484 -61.741308) (xy 198.738218 -61.739271) (xy 198.793655 -61.745371) (xy 198.847612 -61.759477)
			(xy 198.898941 -61.781289) (xy 198.946547 -61.810343) (xy 198.989415 -61.846018) (xy 199.026632 -61.887555)
			(xy 199.057405 -61.934068) (xy 199.081077 -61.984565) (xy 199.097145 -62.037972) (xy 199.105265 -62.093148)
			(xy 199.105774 -62.121034) (xy 199.105265 -62.14892) (xy 199.097145 -62.204096) (xy 199.081077 -62.257503)
			(xy 199.057405 -62.308) (xy 199.026632 -62.354513) (xy 198.989415 -62.39605) (xy 198.946547 -62.431725)
			(xy 198.898941 -62.460779) (xy 198.847612 -62.482591) (xy 198.793655 -62.496697) (xy 198.738218 -62.502797)
			(xy 198.682484 -62.50076) (xy 198.627641 -62.49063) (xy 198.574857 -62.472623) (xy 198.525257 -62.447122)
			(xy 198.479899 -62.414671) (xy 198.43975 -62.375962) (xy 198.405664 -62.331819) (xy 198.378368 -62.283184)
			(xy 198.358445 -62.231093) (xy 198.346319 -62.176656) (xy 198.342248 -62.121034) (xy 180.566103 -62.121034)
			(xy 180.55209 -62.210442) (xy 180.545761 -62.24714) (xy 180.525076 -62.318681) (xy 180.495577 -62.387061)
			(xy 180.457732 -62.4512) (xy 180.412138 -62.510083) (xy 180.386228 -62.536832) (xy 180.24429 -62.67877)
			(xy 201.766172 -62.67877) (xy 201.773926 -62.624822) (xy 201.789278 -62.572527) (xy 201.811916 -62.522948)
			(xy 201.841379 -62.477096) (xy 201.877067 -62.435904) (xy 201.918255 -62.40021) (xy 201.964103 -62.37074)
			(xy 202.013679 -62.348095) (xy 202.065972 -62.332737) (xy 202.119919 -62.324976) (xy 202.14717 -62.324488)
			(xy 202.170724 -62.324873) (xy 202.217469 -62.330727) (xy 202.240388 -62.336172) (xy 202.254156 -62.339151)
			(xy 202.282302 -62.338308) (xy 202.309147 -62.329813) (xy 202.332654 -62.314311) (xy 202.351035 -62.29298)
			(xy 202.362894 -62.267441) (xy 202.367329 -62.239634) (xy 202.364005 -62.211673) (xy 202.359006 -62.198504)
			(xy 202.349693 -62.175115) (xy 202.336569 -62.126514) (xy 202.329947 -62.076609) (xy 202.329542 -62.051438)
			(xy 202.330014 -62.024181) (xy 202.337767 -61.970221) (xy 202.353121 -61.917914) (xy 202.375763 -61.868325)
			(xy 202.405232 -61.822463) (xy 202.440929 -61.781262) (xy 202.482126 -61.74556) (xy 202.527984 -61.716086)
			(xy 202.577571 -61.693438) (xy 202.629876 -61.678077) (xy 202.683834 -61.670318) (xy 202.738348 -61.670316)
			(xy 202.792307 -61.678074) (xy 202.844613 -61.693432) (xy 202.894201 -61.716077) (xy 202.940061 -61.74555)
			(xy 202.981259 -61.78125) (xy 203.016957 -61.822449) (xy 203.046428 -61.86831) (xy 203.069073 -61.917898)
			(xy 203.084429 -61.970204) (xy 203.092184 -62.024164) (xy 203.092181 -62.078678) (xy 203.08442 -62.132636)
			(xy 203.069058 -62.184941) (xy 203.046409 -62.234527) (xy 203.016932 -62.280384) (xy 202.98123 -62.32158)
			(xy 202.940027 -62.357275) (xy 202.894164 -62.386742) (xy 202.844574 -62.409383) (xy 202.792267 -62.424735)
			(xy 202.738307 -62.432487) (xy 202.71105 -62.432946) (xy 202.687495 -62.432574) (xy 202.640751 -62.426711)
			(xy 202.617832 -62.421262) (xy 202.604067 -62.418257) (xy 202.575914 -62.419095) (xy 202.549061 -62.427589)
			(xy 202.525549 -62.443094) (xy 202.507164 -62.464432) (xy 202.495306 -62.489978) (xy 202.490876 -62.517792)
			(xy 202.494209 -62.545759) (xy 202.499214 -62.55893) (xy 202.508539 -62.582314) (xy 202.521658 -62.630918)
			(xy 202.528275 -62.680824) (xy 202.528678 -62.705996) (xy 202.528227 -62.733247) (xy 202.520471 -62.787195)
			(xy 202.505116 -62.83949) (xy 202.482476 -62.889067) (xy 202.453011 -62.934918) (xy 202.41732 -62.976109)
			(xy 202.376131 -63.011801) (xy 202.330282 -63.041268) (xy 202.280705 -63.063911) (xy 202.228411 -63.079267)
			(xy 202.174464 -63.087025) (xy 202.119962 -63.087027) (xy 202.066014 -63.079273) (xy 202.013719 -63.063919)
			(xy 201.964141 -63.04128) (xy 201.918289 -63.011816) (xy 201.877098 -62.976126) (xy 201.841404 -62.934938)
			(xy 201.811936 -62.889089) (xy 201.789292 -62.839513) (xy 201.773935 -62.78722) (xy 201.766175 -62.733272)
			(xy 201.766172 -62.67877) (xy 180.24429 -62.67877) (xy 179.709512 -63.213548) (xy 190.220888 -63.213548)
			(xy 190.220888 -63.159052) (xy 190.228643 -63.105109) (xy 190.243996 -63.05282) (xy 190.266633 -63.003247)
			(xy 190.296094 -62.9574) (xy 190.33178 -62.916212) (xy 190.372963 -62.880522) (xy 190.418807 -62.851055)
			(xy 190.468377 -62.828412) (xy 190.520664 -62.813053) (xy 190.574606 -62.805291) (xy 190.601854 -62.804802)
			(xy 190.629223 -62.805295) (xy 190.683401 -62.813106) (xy 190.735904 -62.828589) (xy 190.785651 -62.851425)
			(xy 190.831619 -62.881143) (xy 190.852552 -62.898782) (xy 190.852806 -62.899036) (xy 190.859884 -62.904635)
			(xy 190.876807 -62.910873) (xy 190.885826 -62.911228) (xy 190.952882 -62.911228) (xy 190.961897 -62.910856)
			(xy 190.978814 -62.904618) (xy 190.985902 -62.899036) (xy 190.985902 -62.898782) (xy 190.986156 -62.898782)
			(xy 191.007089 -62.881141) (xy 191.053057 -62.851417) (xy 191.102803 -62.828571) (xy 191.155305 -62.813075)
			(xy 191.209483 -62.805246) (xy 191.264225 -62.805246) (xy 191.318403 -62.813075) (xy 191.370905 -62.828571)
			(xy 191.420651 -62.851417) (xy 191.466619 -62.881141) (xy 191.487552 -62.898782) (xy 191.487806 -62.899036)
			(xy 191.494884 -62.904635) (xy 191.511807 -62.910873) (xy 191.520826 -62.911228) (xy 191.587882 -62.911228)
			(xy 191.596897 -62.910856) (xy 191.613814 -62.904618) (xy 191.620902 -62.899036) (xy 191.620902 -62.898782)
			(xy 191.621156 -62.898782) (xy 191.642092 -62.881147) (xy 191.688064 -62.851435) (xy 191.73781 -62.828599)
			(xy 191.79031 -62.813107) (xy 191.844485 -62.805277) (xy 191.871854 -62.804802) (xy 191.89911 -62.805242)
			(xy 191.953067 -62.812994) (xy 192.005372 -62.828346) (xy 192.054959 -62.850987) (xy 192.100819 -62.880454)
			(xy 192.142019 -62.916149) (xy 192.177718 -62.957344) (xy 192.207191 -63.0032) (xy 192.229838 -63.052785)
			(xy 192.23966 -63.086234) (xy 195.487542 -63.086234) (xy 195.491613 -63.030612) (xy 195.503739 -62.976175)
			(xy 195.523662 -62.924084) (xy 195.550958 -62.875449) (xy 195.585044 -62.831306) (xy 195.625193 -62.792597)
			(xy 195.670551 -62.760146) (xy 195.720151 -62.734645) (xy 195.772935 -62.716638) (xy 195.827778 -62.706508)
			(xy 195.883512 -62.704471) (xy 195.938949 -62.710571) (xy 195.992906 -62.724677) (xy 196.044235 -62.746489)
			(xy 196.091841 -62.775543) (xy 196.134709 -62.811218) (xy 196.171926 -62.852755) (xy 196.202699 -62.899268)
			(xy 196.226371 -62.949765) (xy 196.242439 -63.003172) (xy 196.250559 -63.058348) (xy 196.251068 -63.086234)
			(xy 196.250559 -63.11412) (xy 196.242439 -63.169296) (xy 196.226371 -63.222703) (xy 196.202699 -63.2732)
			(xy 196.202546 -63.273432) (xy 197.676768 -63.273432) (xy 197.680839 -63.21781) (xy 197.692965 -63.163373)
			(xy 197.712888 -63.111282) (xy 197.740184 -63.062647) (xy 197.77427 -63.018504) (xy 197.814419 -62.979795)
			(xy 197.859777 -62.947344) (xy 197.909377 -62.921843) (xy 197.962161 -62.903836) (xy 198.017004 -62.893706)
			(xy 198.072738 -62.891669) (xy 198.128175 -62.897769) (xy 198.182132 -62.911875) (xy 198.233461 -62.933687)
			(xy 198.281067 -62.962741) (xy 198.323935 -62.998416) (xy 198.361152 -63.039953) (xy 198.391925 -63.086466)
			(xy 198.415597 -63.136963) (xy 198.431665 -63.19037) (xy 198.439785 -63.245546) (xy 198.440294 -63.273432)
			(xy 198.439785 -63.301318) (xy 198.431665 -63.356494) (xy 198.415597 -63.409901) (xy 198.391925 -63.460398)
			(xy 198.361152 -63.506911) (xy 198.323935 -63.548448) (xy 198.281067 -63.584123) (xy 198.233461 -63.613177)
			(xy 198.182132 -63.634989) (xy 198.128175 -63.649095) (xy 198.072738 -63.655195) (xy 198.017004 -63.653158)
			(xy 197.962161 -63.643028) (xy 197.909377 -63.625021) (xy 197.859777 -63.59952) (xy 197.814419 -63.567069)
			(xy 197.77427 -63.52836) (xy 197.740184 -63.484217) (xy 197.712888 -63.435582) (xy 197.692965 -63.383491)
			(xy 197.680839 -63.329054) (xy 197.676768 -63.273432) (xy 196.202546 -63.273432) (xy 196.171926 -63.319713)
			(xy 196.134709 -63.36125) (xy 196.091841 -63.396925) (xy 196.044235 -63.425979) (xy 195.992906 -63.447791)
			(xy 195.938949 -63.461897) (xy 195.883512 -63.467997) (xy 195.827778 -63.46596) (xy 195.772935 -63.45583)
			(xy 195.720151 -63.437823) (xy 195.670551 -63.412322) (xy 195.625193 -63.379871) (xy 195.585044 -63.341162)
			(xy 195.550958 -63.297019) (xy 195.523662 -63.248384) (xy 195.503739 -63.196293) (xy 195.491613 -63.141856)
			(xy 195.487542 -63.086234) (xy 192.23966 -63.086234) (xy 192.245197 -63.105088) (xy 192.252955 -63.159044)
			(xy 192.252955 -63.213556) (xy 192.245197 -63.267512) (xy 192.229838 -63.319815) (xy 192.207191 -63.3694)
			(xy 192.177718 -63.415256) (xy 192.142019 -63.456451) (xy 192.100819 -63.492146) (xy 192.054959 -63.521613)
			(xy 192.005372 -63.544254) (xy 191.953067 -63.559606) (xy 191.89911 -63.567358) (xy 191.871854 -63.567818)
			(xy 191.844484 -63.56734) (xy 191.790305 -63.559528) (xy 191.737801 -63.544043) (xy 191.688054 -63.521203)
			(xy 191.642087 -63.491479) (xy 191.621156 -63.473838) (xy 191.620902 -63.473584) (xy 191.61382 -63.46799)
			(xy 191.5969 -63.461748) (xy 191.587882 -63.461392) (xy 191.520826 -63.461392) (xy 191.511811 -63.461763)
			(xy 191.494894 -63.468001) (xy 191.487806 -63.473584) (xy 191.487552 -63.473838) (xy 191.466619 -63.491479)
			(xy 191.420651 -63.521203) (xy 191.370905 -63.544049) (xy 191.318403 -63.559545) (xy 191.264225 -63.567374)
			(xy 191.209483 -63.567374) (xy 191.155305 -63.559545) (xy 191.102803 -63.544049) (xy 191.053057 -63.521203)
			(xy 191.007089 -63.491479) (xy 190.986156 -63.473838) (xy 190.985902 -63.473584) (xy 190.97882 -63.46799)
			(xy 190.9619 -63.461748) (xy 190.952882 -63.461392) (xy 190.885826 -63.461392) (xy 190.876811 -63.461763)
			(xy 190.859894 -63.468001) (xy 190.852806 -63.473584) (xy 190.852806 -63.473838) (xy 190.852552 -63.473838)
			(xy 190.831616 -63.491472) (xy 190.785644 -63.521184) (xy 190.735897 -63.54402) (xy 190.683398 -63.559513)
			(xy 190.629223 -63.567343) (xy 190.601854 -63.567818) (xy 190.574606 -63.567309) (xy 190.520664 -63.559547)
			(xy 190.468377 -63.544188) (xy 190.418807 -63.521545) (xy 190.372963 -63.492078) (xy 190.33178 -63.456388)
			(xy 190.296094 -63.4152) (xy 190.266633 -63.369353) (xy 190.243996 -63.31978) (xy 190.228643 -63.267491)
			(xy 190.220888 -63.213548) (xy 179.709512 -63.213548) (xy 177.822098 -65.100962) (xy 188.23254 -65.100962)
			(xy 188.236611 -65.04534) (xy 188.248737 -64.990903) (xy 188.26866 -64.938812) (xy 188.295956 -64.890177)
			(xy 188.330042 -64.846034) (xy 188.370191 -64.807325) (xy 188.415549 -64.774874) (xy 188.465149 -64.749373)
			(xy 188.517933 -64.731366) (xy 188.572776 -64.721236) (xy 188.62851 -64.719199) (xy 188.683947 -64.725299)
			(xy 188.737904 -64.739405) (xy 188.789233 -64.761217) (xy 188.836839 -64.790271) (xy 188.879707 -64.825946)
			(xy 188.916924 -64.867483) (xy 188.947697 -64.913996) (xy 188.971369 -64.964493) (xy 188.987437 -65.0179)
			(xy 188.995557 -65.073076) (xy 188.996066 -65.100962) (xy 188.995644 -65.124076) (xy 200.20737 -65.124076)
			(xy 200.211441 -65.068454) (xy 200.223567 -65.014017) (xy 200.24349 -64.961926) (xy 200.270786 -64.913291)
			(xy 200.304872 -64.869148) (xy 200.345021 -64.830439) (xy 200.390379 -64.797988) (xy 200.439979 -64.772487)
			(xy 200.492763 -64.75448) (xy 200.547606 -64.74435) (xy 200.60334 -64.742313) (xy 200.658777 -64.748413)
			(xy 200.712734 -64.762519) (xy 200.764063 -64.784331) (xy 200.811669 -64.813385) (xy 200.854537 -64.84906)
			(xy 200.891754 -64.890597) (xy 200.922527 -64.93711) (xy 200.946199 -64.987607) (xy 200.962267 -65.041014)
			(xy 200.970387 -65.09619) (xy 200.970896 -65.124076) (xy 200.970387 -65.151962) (xy 200.962267 -65.207138)
			(xy 200.946199 -65.260545) (xy 200.922527 -65.311042) (xy 200.891754 -65.357555) (xy 200.854537 -65.399092)
			(xy 200.811669 -65.434767) (xy 200.764063 -65.463821) (xy 200.712734 -65.485633) (xy 200.658777 -65.499739)
			(xy 200.60334 -65.505839) (xy 200.547606 -65.503802) (xy 200.492763 -65.493672) (xy 200.439979 -65.475665)
			(xy 200.390379 -65.450164) (xy 200.345021 -65.417713) (xy 200.304872 -65.379004) (xy 200.270786 -65.334861)
			(xy 200.24349 -65.286226) (xy 200.223567 -65.234135) (xy 200.211441 -65.179698) (xy 200.20737 -65.124076)
			(xy 188.995644 -65.124076) (xy 188.995557 -65.128848) (xy 188.987437 -65.184024) (xy 188.971369 -65.237431)
			(xy 188.947697 -65.287928) (xy 188.916924 -65.334441) (xy 188.879707 -65.375978) (xy 188.836839 -65.411653)
			(xy 188.789233 -65.440707) (xy 188.737904 -65.462519) (xy 188.683947 -65.476625) (xy 188.62851 -65.482725)
			(xy 188.572776 -65.480688) (xy 188.517933 -65.470558) (xy 188.465149 -65.452551) (xy 188.415549 -65.42705)
			(xy 188.370191 -65.394599) (xy 188.330042 -65.35589) (xy 188.295956 -65.311747) (xy 188.26866 -65.263112)
			(xy 188.248737 -65.211021) (xy 188.236611 -65.156584) (xy 188.23254 -65.100962) (xy 177.822098 -65.100962)
			(xy 177.16754 -65.75552) (xy 182.446674 -65.75552) (xy 182.450745 -65.699898) (xy 182.462871 -65.645461)
			(xy 182.482794 -65.59337) (xy 182.51009 -65.544735) (xy 182.544176 -65.500592) (xy 182.584325 -65.461883)
			(xy 182.629683 -65.429432) (xy 182.679283 -65.403931) (xy 182.732067 -65.385924) (xy 182.78691 -65.375794)
			(xy 182.842644 -65.373757) (xy 182.898081 -65.379857) (xy 182.952038 -65.393963) (xy 183.003367 -65.415775)
			(xy 183.050973 -65.444829) (xy 183.093841 -65.480504) (xy 183.131058 -65.522041) (xy 183.161831 -65.568554)
			(xy 183.185503 -65.619051) (xy 183.201571 -65.672458) (xy 183.209691 -65.727634) (xy 183.2102 -65.75552)
			(xy 183.209691 -65.783406) (xy 183.201571 -65.838582) (xy 183.185503 -65.891989) (xy 183.161831 -65.942486)
			(xy 183.131058 -65.988999) (xy 183.093841 -66.030536) (xy 183.050973 -66.066211) (xy 183.003367 -66.095265)
			(xy 182.952038 -66.117077) (xy 182.898081 -66.131183) (xy 182.842644 -66.137283) (xy 182.78691 -66.135246)
			(xy 182.732067 -66.125116) (xy 182.679283 -66.107109) (xy 182.629683 -66.081608) (xy 182.584325 -66.049157)
			(xy 182.544176 -66.010448) (xy 182.51009 -65.966305) (xy 182.482794 -65.91767) (xy 182.462871 -65.865579)
			(xy 182.450745 -65.811142) (xy 182.446674 -65.75552) (xy 177.16754 -65.75552) (xy 175.794107 -67.128953)
			(xy 182.466675 -67.128953) (xy 182.466675 -67.074447) (xy 182.474433 -67.020495) (xy 182.48979 -66.968196)
			(xy 182.512435 -66.918616) (xy 182.541905 -66.872763) (xy 182.577601 -66.831572) (xy 182.618797 -66.79588)
			(xy 182.664653 -66.766415) (xy 182.714236 -66.743776) (xy 182.766536 -66.728424) (xy 182.820489 -66.720672)
			(xy 182.847742 -66.720212) (xy 182.875111 -66.720709) (xy 182.929289 -66.728519) (xy 182.981792 -66.744001)
			(xy 183.031539 -66.766836) (xy 183.077507 -66.796554) (xy 183.09844 -66.814192) (xy 183.098694 -66.814446)
			(xy 183.105774 -66.820042) (xy 183.122696 -66.826282) (xy 183.131714 -66.826638) (xy 183.19877 -66.826638)
			(xy 183.207784 -66.826258) (xy 183.224701 -66.820026) (xy 183.23179 -66.814446) (xy 183.23179 -66.814192)
			(xy 183.232044 -66.814192) (xy 183.252985 -66.796564) (xy 183.298956 -66.766851) (xy 183.348701 -66.744013)
			(xy 183.401199 -66.728519) (xy 183.455373 -66.720688) (xy 183.482742 -66.720212) (xy 183.509993 -66.720661)
			(xy 183.563939 -66.728422) (xy 183.616231 -66.743782) (xy 183.665806 -66.766427) (xy 183.711653 -66.795896)
			(xy 183.752841 -66.831589) (xy 183.788529 -66.87278) (xy 183.817993 -66.918631) (xy 183.840633 -66.968208)
			(xy 183.855986 -67.020502) (xy 183.863742 -67.074449) (xy 183.863742 -67.128951) (xy 183.855986 -67.182898)
			(xy 183.840633 -67.235192) (xy 183.817993 -67.284769) (xy 183.788529 -67.33062) (xy 183.752841 -67.371811)
			(xy 183.711653 -67.407504) (xy 183.665806 -67.436973) (xy 183.616231 -67.459618) (xy 183.563939 -67.474978)
			(xy 183.509993 -67.482739) (xy 183.482742 -67.483228) (xy 183.455372 -67.482755) (xy 183.401192 -67.474941)
			(xy 183.348689 -67.459455) (xy 183.298942 -67.436614) (xy 183.252975 -67.40689) (xy 183.232044 -67.389248)
			(xy 183.23179 -67.388994) (xy 183.224711 -67.383396) (xy 183.207788 -67.377157) (xy 183.19877 -67.376802)
			(xy 183.131714 -67.376802) (xy 183.122698 -67.377165) (xy 183.105781 -67.383408) (xy 183.098694 -67.388994)
			(xy 183.098694 -67.389248) (xy 183.09844 -67.389248) (xy 183.077497 -67.406874) (xy 183.031528 -67.436589)
			(xy 182.981783 -67.459429) (xy 182.929285 -67.474923) (xy 182.875111 -67.482753) (xy 182.847742 -67.483228)
			(xy 182.820489 -67.482728) (xy 182.766536 -67.474976) (xy 182.714236 -67.459624) (xy 182.664653 -67.436985)
			(xy 182.618797 -67.40752) (xy 182.577601 -67.371828) (xy 182.541905 -67.330637) (xy 182.512435 -67.284784)
			(xy 182.48979 -67.235204) (xy 182.474433 -67.182905) (xy 182.466675 -67.128953) (xy 175.794107 -67.128953)
			(xy 175.435006 -67.488054) (xy 186.879228 -67.488054) (xy 186.883299 -67.432432) (xy 186.895425 -67.377995)
			(xy 186.915348 -67.325904) (xy 186.942644 -67.277269) (xy 186.97673 -67.233126) (xy 187.016879 -67.194417)
			(xy 187.062237 -67.161966) (xy 187.111837 -67.136465) (xy 187.164621 -67.118458) (xy 187.219464 -67.108328)
			(xy 187.275198 -67.106291) (xy 187.330635 -67.112391) (xy 187.384592 -67.126497) (xy 187.435921 -67.148309)
			(xy 187.483527 -67.177363) (xy 187.526395 -67.213038) (xy 187.563612 -67.254575) (xy 187.594385 -67.301088)
			(xy 187.618057 -67.351585) (xy 187.634125 -67.404992) (xy 187.642245 -67.460168) (xy 187.642754 -67.488054)
			(xy 187.642245 -67.51594) (xy 187.63906 -67.537584) (xy 188.171326 -67.537584) (xy 188.175397 -67.481962)
			(xy 188.187523 -67.427525) (xy 188.207446 -67.375434) (xy 188.234742 -67.326799) (xy 188.268828 -67.282656)
			(xy 188.308977 -67.243947) (xy 188.354335 -67.211496) (xy 188.403935 -67.185995) (xy 188.456719 -67.167988)
			(xy 188.511562 -67.157858) (xy 188.567296 -67.155821) (xy 188.622733 -67.161921) (xy 188.67669 -67.176027)
			(xy 188.728019 -67.197839) (xy 188.775625 -67.226893) (xy 188.818493 -67.262568) (xy 188.85571 -67.304105)
			(xy 188.886483 -67.350618) (xy 188.910155 -67.401115) (xy 188.926223 -67.454522) (xy 188.934343 -67.509698)
			(xy 188.934852 -67.537584) (xy 188.934343 -67.56547) (xy 188.930298 -67.592956) (xy 189.44539 -67.592956)
			(xy 189.449461 -67.537334) (xy 189.461587 -67.482897) (xy 189.48151 -67.430806) (xy 189.508806 -67.382171)
			(xy 189.542892 -67.338028) (xy 189.583041 -67.299319) (xy 189.628399 -67.266868) (xy 189.677999 -67.241367)
			(xy 189.730783 -67.22336) (xy 189.785626 -67.21323) (xy 189.84136 -67.211193) (xy 189.896797 -67.217293)
			(xy 189.950754 -67.231399) (xy 190.002083 -67.253211) (xy 190.049689 -67.282265) (xy 190.092557 -67.31794)
			(xy 190.129774 -67.359477) (xy 190.160547 -67.40599) (xy 190.184219 -67.456487) (xy 190.200287 -67.509894)
			(xy 190.208404 -67.565052) (xy 192.546693 -67.565052) (xy 192.546693 -67.510548) (xy 192.55445 -67.4566)
			(xy 192.569806 -67.404305) (xy 192.592449 -67.354728) (xy 192.621917 -67.308877) (xy 192.657611 -67.267688)
			(xy 192.698803 -67.231998) (xy 192.744656 -67.202534) (xy 192.794235 -67.179895) (xy 192.846531 -67.164544)
			(xy 192.90048 -67.156791) (xy 192.927732 -67.15633) (xy 192.955103 -67.15677) (xy 193.009284 -67.164593)
			(xy 193.061787 -67.180088) (xy 193.111534 -67.202935) (xy 193.157499 -67.232666) (xy 193.17843 -67.25031)
			(xy 193.178684 -67.250564) (xy 193.185765 -67.256158) (xy 193.202686 -67.262398) (xy 193.211704 -67.262756)
			(xy 193.27876 -67.262756) (xy 193.287776 -67.262389) (xy 193.304694 -67.25615) (xy 193.31178 -67.250564)
			(xy 193.31178 -67.25031) (xy 193.312034 -67.25031) (xy 193.332981 -67.23269) (xy 193.37895 -67.202975)
			(xy 193.428693 -67.180135) (xy 193.481191 -67.16464) (xy 193.535364 -67.156807) (xy 193.562732 -67.15633)
			(xy 193.589984 -67.156742) (xy 193.643934 -67.164503) (xy 193.69623 -67.179862) (xy 193.745808 -67.202508)
			(xy 193.791659 -67.231978) (xy 193.83285 -67.267673) (xy 193.868541 -67.308866) (xy 193.898008 -67.35472)
			(xy 193.920649 -67.4043) (xy 193.936004 -67.456597) (xy 193.94376 -67.510547) (xy 193.94376 -67.565053)
			(xy 193.936004 -67.619003) (xy 193.920649 -67.6713) (xy 193.898008 -67.72088) (xy 193.868541 -67.766734)
			(xy 193.83285 -67.807927) (xy 193.791659 -67.843622) (xy 193.745808 -67.873092) (xy 193.69623 -67.895738)
			(xy 193.643934 -67.911097) (xy 193.589984 -67.918858) (xy 193.562732 -67.919346) (xy 193.535362 -67.918874)
			(xy 193.481182 -67.91106) (xy 193.428679 -67.895573) (xy 193.378932 -67.872732) (xy 193.332965 -67.843007)
			(xy 193.312034 -67.825366) (xy 193.31178 -67.825112) (xy 193.304702 -67.819512) (xy 193.287779 -67.813273)
			(xy 193.27876 -67.81292) (xy 193.211704 -67.81292) (xy 193.202687 -67.813274) (xy 193.18577 -67.819523)
			(xy 193.178684 -67.825112) (xy 193.178684 -67.825366) (xy 193.17843 -67.825366) (xy 193.157493 -67.842999)
			(xy 193.111522 -67.872713) (xy 193.061776 -67.895551) (xy 193.009276 -67.911043) (xy 192.955101 -67.918872)
			(xy 192.927732 -67.919346) (xy 192.90048 -67.918809) (xy 192.846531 -67.911056) (xy 192.794235 -67.895705)
			(xy 192.744656 -67.873066) (xy 192.698803 -67.843602) (xy 192.657611 -67.807912) (xy 192.621917 -67.766723)
			(xy 192.592449 -67.720872) (xy 192.569806 -67.671295) (xy 192.55445 -67.619) (xy 192.546693 -67.565052)
			(xy 190.208404 -67.565052) (xy 190.208407 -67.56507) (xy 190.208916 -67.592956) (xy 190.208407 -67.620842)
			(xy 190.200287 -67.676018) (xy 190.184219 -67.729425) (xy 190.160547 -67.779922) (xy 190.129774 -67.826435)
			(xy 190.092557 -67.867972) (xy 190.049689 -67.903647) (xy 190.002083 -67.932701) (xy 189.950754 -67.954513)
			(xy 189.896797 -67.968619) (xy 189.84136 -67.974719) (xy 189.785626 -67.972682) (xy 189.730783 -67.962552)
			(xy 189.677999 -67.944545) (xy 189.628399 -67.919044) (xy 189.583041 -67.886593) (xy 189.542892 -67.847884)
			(xy 189.508806 -67.803741) (xy 189.48151 -67.755106) (xy 189.461587 -67.703015) (xy 189.449461 -67.648578)
			(xy 189.44539 -67.592956) (xy 188.930298 -67.592956) (xy 188.926223 -67.620646) (xy 188.910155 -67.674053)
			(xy 188.886483 -67.72455) (xy 188.85571 -67.771063) (xy 188.818493 -67.8126) (xy 188.775625 -67.848275)
			(xy 188.728019 -67.877329) (xy 188.67669 -67.899141) (xy 188.622733 -67.913247) (xy 188.567296 -67.919347)
			(xy 188.511562 -67.91731) (xy 188.456719 -67.90718) (xy 188.403935 -67.889173) (xy 188.354335 -67.863672)
			(xy 188.308977 -67.831221) (xy 188.268828 -67.792512) (xy 188.234742 -67.748369) (xy 188.207446 -67.699734)
			(xy 188.187523 -67.647643) (xy 188.175397 -67.593206) (xy 188.171326 -67.537584) (xy 187.63906 -67.537584)
			(xy 187.634125 -67.571116) (xy 187.618057 -67.624523) (xy 187.594385 -67.67502) (xy 187.563612 -67.721533)
			(xy 187.526395 -67.76307) (xy 187.483527 -67.798745) (xy 187.435921 -67.827799) (xy 187.384592 -67.849611)
			(xy 187.330635 -67.863717) (xy 187.275198 -67.869817) (xy 187.219464 -67.86778) (xy 187.164621 -67.85765)
			(xy 187.111837 -67.839643) (xy 187.062237 -67.814142) (xy 187.016879 -67.781691) (xy 186.97673 -67.742982)
			(xy 186.942644 -67.698839) (xy 186.915348 -67.650204) (xy 186.895425 -67.598113) (xy 186.883299 -67.543676)
			(xy 186.879228 -67.488054) (xy 175.435006 -67.488054) (xy 174.336456 -68.586604) (xy 184.72531 -68.586604)
			(xy 184.725776 -68.559234) (xy 184.733593 -68.505055) (xy 184.749082 -68.452551) (xy 184.771924 -68.402804)
			(xy 184.801649 -68.356838) (xy 184.81929 -68.335906) (xy 184.819544 -68.335652) (xy 184.82512 -68.328559)
			(xy 184.831372 -68.311647) (xy 184.831736 -68.302632) (xy 184.831736 -68.235576) (xy 184.831383 -68.226559)
			(xy 184.825132 -68.209642) (xy 184.819544 -68.202556) (xy 184.81929 -68.202556) (xy 184.81929 -68.202302)
			(xy 184.801637 -68.181381) (xy 184.771927 -68.135405) (xy 184.749094 -68.085655) (xy 184.733607 -68.033152)
			(xy 184.725782 -67.978974) (xy 184.72531 -67.951604) (xy 184.725759 -67.92435) (xy 184.733516 -67.870398)
			(xy 184.748872 -67.818099) (xy 184.771516 -67.768518) (xy 184.800985 -67.722664) (xy 184.83668 -67.68147)
			(xy 184.877875 -67.645777) (xy 184.92373 -67.616309) (xy 184.973312 -67.593668) (xy 185.025612 -67.578313)
			(xy 185.079564 -67.570558) (xy 185.106818 -67.570096) (xy 185.133132 -67.570553) (xy 185.185261 -67.57779)
			(xy 185.235904 -67.592111) (xy 185.284103 -67.613246) (xy 185.328946 -67.640794) (xy 185.369586 -67.674234)
			(xy 185.387742 -67.693286) (xy 185.395248 -67.700706) (xy 185.41454 -67.70922) (xy 185.42508 -67.709796)
			(xy 185.499756 -67.709796) (xy 185.510305 -67.709258) (xy 185.5296 -67.700729) (xy 185.537094 -67.693286)
			(xy 185.555257 -67.674238) (xy 185.595885 -67.64078) (xy 185.640724 -67.613221) (xy 185.688923 -67.592081)
			(xy 185.739569 -67.577762) (xy 185.791702 -67.570536) (xy 185.818018 -67.570096) (xy 185.845389 -67.570552)
			(xy 185.899568 -67.578373) (xy 185.952071 -67.593864) (xy 186.001818 -67.616708) (xy 186.047784 -67.646434)
			(xy 186.068716 -67.664076) (xy 186.06897 -67.66433) (xy 186.076059 -67.669913) (xy 186.092974 -67.676161)
			(xy 186.10199 -67.676522) (xy 186.169046 -67.676522) (xy 186.17806 -67.676135) (xy 186.194977 -67.669908)
			(xy 186.202066 -67.66433) (xy 186.202066 -67.664076) (xy 186.20232 -67.664076) (xy 186.223268 -67.646457)
			(xy 186.269237 -67.616743) (xy 186.31898 -67.593904) (xy 186.371477 -67.578408) (xy 186.42565 -67.570573)
			(xy 186.453018 -67.570096) (xy 186.48027 -67.570561) (xy 186.534219 -67.57832) (xy 186.586514 -67.593678)
			(xy 186.636091 -67.616321) (xy 186.681942 -67.64579) (xy 186.723132 -67.681483) (xy 186.758823 -67.722676)
			(xy 186.788289 -67.768528) (xy 186.81093 -67.818107) (xy 186.826285 -67.870403) (xy 186.834041 -67.924352)
			(xy 186.834526 -67.951604) (xy 186.83408 -67.978975) (xy 186.82626 -68.033156) (xy 186.810767 -68.08566)
			(xy 186.787921 -68.135406) (xy 186.75819 -68.181372) (xy 186.740546 -68.202302) (xy 186.740292 -68.202556)
			(xy 186.734717 -68.20965) (xy 186.728464 -68.226561) (xy 186.7281 -68.235576) (xy 186.7281 -68.302632)
			(xy 186.728442 -68.31165) (xy 186.7347 -68.328567) (xy 186.740292 -68.335652) (xy 186.740546 -68.335652)
			(xy 186.740546 -68.335906) (xy 186.758193 -68.356832) (xy 186.787905 -68.402806) (xy 186.810741 -68.452555)
			(xy 186.82623 -68.505057) (xy 186.834054 -68.559234) (xy 186.834526 -68.586604) (xy 186.834026 -68.613855)
			(xy 186.826269 -68.667801) (xy 186.810915 -68.720094) (xy 186.794275 -68.75653) (xy 190.270384 -68.75653)
			(xy 190.270847 -68.729159) (xy 190.278663 -68.674979) (xy 190.294151 -68.622475) (xy 190.316994 -68.572729)
			(xy 190.346721 -68.526763) (xy 190.364364 -68.505832) (xy 190.364618 -68.505578) (xy 190.370222 -68.498503)
			(xy 190.376458 -68.481577) (xy 190.37681 -68.472558) (xy 190.37681 -68.405502) (xy 190.37645 -68.396486)
			(xy 190.370204 -68.379569) (xy 190.364618 -68.372482) (xy 190.364364 -68.372482) (xy 190.364364 -68.372228)
			(xy 190.346719 -68.351301) (xy 190.317009 -68.305326) (xy 190.294175 -68.255577) (xy 190.278685 -68.203076)
			(xy 190.270858 -68.148899) (xy 190.270384 -68.12153) (xy 190.270883 -68.094278) (xy 190.278636 -68.040329)
			(xy 190.293988 -67.988032) (xy 190.316626 -67.938453) (xy 190.34609 -67.8926) (xy 190.38178 -67.851407)
			(xy 190.422969 -67.815713) (xy 190.468819 -67.786244) (xy 190.518397 -67.763601) (xy 190.570692 -67.748244)
			(xy 190.62464 -67.740486) (xy 190.651892 -67.740022) (xy 190.679262 -67.740487) (xy 190.733442 -67.748305)
			(xy 190.785945 -67.763794) (xy 190.835692 -67.786636) (xy 190.881658 -67.81636) (xy 190.90259 -67.834002)
			(xy 190.902844 -67.834256) (xy 190.909938 -67.839832) (xy 190.926849 -67.846084) (xy 190.935864 -67.846448)
			(xy 191.00292 -67.846448) (xy 191.011939 -67.846112) (xy 191.028857 -67.839851) (xy 191.03594 -67.834256)
			(xy 191.03594 -67.834002) (xy 191.036194 -67.834002) (xy 191.057118 -67.816353) (xy 191.103093 -67.786642)
			(xy 191.152842 -67.763808) (xy 191.205345 -67.74832) (xy 191.259522 -67.740494) (xy 191.286892 -67.740022)
			(xy 191.313206 -67.740488) (xy 191.365335 -67.747722) (xy 191.415978 -67.762041) (xy 191.464177 -67.783174)
			(xy 191.509021 -67.81072) (xy 191.54966 -67.84416) (xy 191.567816 -67.863212) (xy 191.575328 -67.870625)
			(xy 191.594615 -67.879142) (xy 191.605154 -67.879722) (xy 191.67983 -67.879722) (xy 191.690376 -67.879162)
			(xy 191.709671 -67.870648) (xy 191.717168 -67.863212) (xy 191.7353 -67.844133) (xy 191.775934 -67.810677)
			(xy 191.82078 -67.783121) (xy 191.868985 -67.761987) (xy 191.919637 -67.747675) (xy 191.971774 -67.740457)
			(xy 191.998092 -67.740022) (xy 192.025346 -67.740463) (xy 192.079299 -67.74822) (xy 192.131599 -67.763576)
			(xy 192.181182 -67.78622) (xy 192.227036 -67.81569) (xy 192.26823 -67.851386) (xy 192.303923 -67.892582)
			(xy 192.333391 -67.938438) (xy 192.356032 -67.988021) (xy 192.371385 -68.040322) (xy 192.379139 -68.094276)
			(xy 192.3796 -68.12153) (xy 192.379152 -68.148901) (xy 192.371329 -68.203081) (xy 192.355836 -68.255584)
			(xy 192.332991 -68.305331) (xy 192.303263 -68.351297) (xy 192.28562 -68.372228) (xy 192.285366 -68.372482)
			(xy 192.279777 -68.379567) (xy 192.273533 -68.396485) (xy 192.273174 -68.405502) (xy 192.273174 -68.472558)
			(xy 192.273557 -68.481572) (xy 192.279787 -68.498489) (xy 192.285366 -68.505578) (xy 192.28562 -68.505578)
			(xy 192.28562 -68.505832) (xy 192.303244 -68.526776) (xy 192.332957 -68.572746) (xy 192.355796 -68.622491)
			(xy 192.371291 -68.674988) (xy 192.379123 -68.729162) (xy 192.3796 -68.75653) (xy 192.37915 -68.783782)
			(xy 192.371389 -68.837732) (xy 192.35603 -68.890028) (xy 192.333385 -68.939606) (xy 192.303915 -68.985456)
			(xy 192.268219 -69.026646) (xy 192.227026 -69.062337) (xy 192.181172 -69.091803) (xy 192.131592 -69.114443)
			(xy 192.079295 -69.129797) (xy 192.025344 -69.137553) (xy 191.998092 -69.138038) (xy 191.971777 -69.137596)
			(xy 191.919647 -69.130358) (xy 191.869003 -69.116036) (xy 191.820803 -69.094899) (xy 191.77596 -69.067347)
			(xy 191.735323 -69.033903) (xy 191.717168 -69.014848) (xy 191.709654 -69.007437) (xy 191.690368 -68.998917)
			(xy 191.67983 -68.998338) (xy 191.605154 -68.998338) (xy 191.594605 -68.998872) (xy 191.575308 -69.007402)
			(xy 191.567816 -69.014848) (xy 191.549655 -69.033898) (xy 191.509025 -69.067354) (xy 191.464186 -69.094912)
			(xy 191.415986 -69.116051) (xy 191.36534 -69.13037) (xy 191.313208 -69.137598) (xy 191.286892 -69.138038)
			(xy 191.259521 -69.137592) (xy 191.20534 -69.129771) (xy 191.152836 -69.114279) (xy 191.10309 -69.091432)
			(xy 191.057124 -69.061702) (xy 191.036194 -69.044058) (xy 191.03594 -69.043804) (xy 191.028846 -69.038228)
			(xy 191.011935 -69.031975) (xy 191.00292 -69.031612) (xy 190.935864 -69.031612) (xy 190.926845 -69.031949)
			(xy 190.909928 -69.03821) (xy 190.902844 -69.043804) (xy 190.902844 -69.044058) (xy 190.90259 -69.044058)
			(xy 190.881667 -69.061709) (xy 190.835692 -69.09142) (xy 190.785943 -69.114255) (xy 190.73344 -69.129743)
			(xy 190.679262 -69.137567) (xy 190.651892 -69.138038) (xy 190.624642 -69.13753) (xy 190.570697 -69.129773)
			(xy 190.518404 -69.114418) (xy 190.468829 -69.091778) (xy 190.42298 -69.062314) (xy 190.381791 -69.026625)
			(xy 190.346099 -68.985438) (xy 190.316632 -68.939591) (xy 190.293989 -68.890017) (xy 190.278632 -68.837725)
			(xy 190.270872 -68.78378) (xy 190.270384 -68.75653) (xy 186.794275 -68.75653) (xy 186.788274 -68.76967)
			(xy 186.758809 -68.81552) (xy 186.723119 -68.856709) (xy 186.681931 -68.892401) (xy 186.636083 -68.921868)
			(xy 186.586507 -68.94451) (xy 186.534215 -68.959866) (xy 186.480269 -68.967625) (xy 186.453018 -68.968112)
			(xy 186.425648 -68.967632) (xy 186.37147 -68.959817) (xy 186.318967 -68.944331) (xy 186.26922 -68.921493)
			(xy 186.223252 -68.891772) (xy 186.20232 -68.874132) (xy 186.202066 -68.873878) (xy 186.194966 -68.86831)
			(xy 186.17806 -68.862053) (xy 186.169046 -68.861686) (xy 186.10199 -68.861686) (xy 186.092973 -68.862041)
			(xy 186.076056 -68.868291) (xy 186.06897 -68.873878) (xy 186.06897 -68.874132) (xy 186.068716 -68.874132)
			(xy 186.047793 -68.891782) (xy 186.001817 -68.921491) (xy 185.952067 -68.944324) (xy 185.899565 -68.959813)
			(xy 185.845388 -68.967639) (xy 185.818018 -68.968112) (xy 185.791705 -68.967629) (xy 185.739577 -68.960397)
			(xy 185.688935 -68.94608) (xy 185.640736 -68.924951) (xy 185.595892 -68.897408) (xy 185.555251 -68.863972)
			(xy 185.537094 -68.844922) (xy 185.529574 -68.837519) (xy 185.510293 -68.828995) (xy 185.499756 -68.828412)
			(xy 185.42508 -68.828412) (xy 185.414533 -68.828967) (xy 185.395237 -68.837484) (xy 185.387742 -68.844922)
			(xy 185.369612 -68.864003) (xy 185.328976 -68.897457) (xy 185.28413 -68.925012) (xy 185.235925 -68.946146)
			(xy 185.185273 -68.960458) (xy 185.133136 -68.967677) (xy 185.106818 -68.968112) (xy 185.079566 -68.967628)
			(xy 185.025616 -68.959874) (xy 184.973319 -68.94452) (xy 184.923739 -68.92188) (xy 184.877886 -68.892414)
			(xy 184.836693 -68.856723) (xy 184.800999 -68.815532) (xy 184.771531 -68.769681) (xy 184.748888 -68.720102)
			(xy 184.733531 -68.667806) (xy 184.725774 -68.613856) (xy 184.72531 -68.586604) (xy 174.336456 -68.586604)
			(xy 171.367196 -71.555864) (xy 187.294518 -71.555864) (xy 187.298589 -71.500242) (xy 187.310715 -71.445805)
			(xy 187.330638 -71.393714) (xy 187.357934 -71.345079) (xy 187.39202 -71.300936) (xy 187.432169 -71.262227)
			(xy 187.477527 -71.229776) (xy 187.527127 -71.204275) (xy 187.579911 -71.186268) (xy 187.634754 -71.176138)
			(xy 187.690488 -71.174101) (xy 187.745925 -71.180201) (xy 187.799882 -71.194307) (xy 187.851211 -71.216119)
			(xy 187.898817 -71.245173) (xy 187.941685 -71.280848) (xy 187.978902 -71.322385) (xy 188.009675 -71.368898)
			(xy 188.033347 -71.419395) (xy 188.049415 -71.472802) (xy 188.057535 -71.527978) (xy 188.058044 -71.555864)
			(xy 188.057535 -71.58375) (xy 188.051696 -71.623428) (xy 188.803532 -71.623428) (xy 188.807603 -71.567806)
			(xy 188.819729 -71.513369) (xy 188.839652 -71.461278) (xy 188.866948 -71.412643) (xy 188.901034 -71.3685)
			(xy 188.941183 -71.329791) (xy 188.986541 -71.29734) (xy 189.036141 -71.271839) (xy 189.088925 -71.253832)
			(xy 189.143768 -71.243702) (xy 189.199502 -71.241665) (xy 189.254939 -71.247765) (xy 189.308896 -71.261871)
			(xy 189.360225 -71.283683) (xy 189.407831 -71.312737) (xy 189.450699 -71.348412) (xy 189.487916 -71.389949)
			(xy 189.518689 -71.436462) (xy 189.542361 -71.486959) (xy 189.558429 -71.540366) (xy 189.566549 -71.595542)
			(xy 189.567058 -71.623428) (xy 189.566549 -71.651314) (xy 189.558429 -71.70649) (xy 189.542361 -71.759897)
			(xy 189.518689 -71.810394) (xy 189.487916 -71.856907) (xy 189.450699 -71.898444) (xy 189.407831 -71.934119)
			(xy 189.360225 -71.963173) (xy 189.308896 -71.984985) (xy 189.254939 -71.999091) (xy 189.199502 -72.005191)
			(xy 189.143768 -72.003154) (xy 189.088925 -71.993024) (xy 189.036141 -71.975017) (xy 188.986541 -71.949516)
			(xy 188.941183 -71.917065) (xy 188.901034 -71.878356) (xy 188.866948 -71.834213) (xy 188.839652 -71.785578)
			(xy 188.819729 -71.733487) (xy 188.807603 -71.67905) (xy 188.803532 -71.623428) (xy 188.051696 -71.623428)
			(xy 188.049415 -71.638926) (xy 188.033347 -71.692333) (xy 188.009675 -71.74283) (xy 187.978902 -71.789343)
			(xy 187.941685 -71.83088) (xy 187.898817 -71.866555) (xy 187.851211 -71.895609) (xy 187.799882 -71.917421)
			(xy 187.745925 -71.931527) (xy 187.690488 -71.937627) (xy 187.634754 -71.93559) (xy 187.579911 -71.92546)
			(xy 187.527127 -71.907453) (xy 187.477527 -71.881952) (xy 187.432169 -71.849501) (xy 187.39202 -71.810792)
			(xy 187.357934 -71.766649) (xy 187.330638 -71.718014) (xy 187.310715 -71.665923) (xy 187.298589 -71.611486)
			(xy 187.294518 -71.555864) (xy 171.367196 -71.555864) (xy 166.724838 -76.198222) (xy 166.717991 -76.20562)
			(xy 166.710258 -76.224218) (xy 166.709852 -76.23429) (xy 166.709852 -76.90231) (xy 166.710106 -76.907136)
			(xy 166.710106 -76.90739) (xy 166.711061 -76.914118) (xy 166.716081 -76.926739) (xy 166.720012 -76.932282)
			(xy 166.724584 -76.937616) (xy 167.302688 -77.51572) (xy 167.309029 -77.521615) (xy 167.324609 -77.529146)
			(xy 167.333168 -77.530452) (xy 167.335962 -77.530706) (xy 182.029608 -77.530706) (xy 182.03826 -77.530311)
			(xy 182.054549 -77.524456) (xy 182.067963 -77.513516) (xy 182.072788 -77.506322) (xy 182.078122 -77.497432)
			(xy 182.079646 -77.486764) (xy 182.083859 -77.459708) (xy 182.099024 -77.407094) (xy 182.121551 -77.357187)
			(xy 182.150978 -77.311011) (xy 182.1867 -77.269512) (xy 182.227984 -77.233543) (xy 182.273985 -77.203842)
			(xy 182.323757 -77.181018) (xy 182.376279 -77.165539) (xy 182.430474 -77.157723) (xy 182.457852 -77.157326)
			(xy 182.485496 -77.157819) (xy 182.540206 -77.165798) (xy 182.593193 -77.18158) (xy 182.643352 -77.204837)
			(xy 182.689633 -77.235083) (xy 182.731071 -77.271685) (xy 182.766799 -77.313879) (xy 182.79607 -77.360783)
			(xy 182.818273 -77.411417) (xy 182.832944 -77.464723) (xy 182.83682 -77.492098) (xy 182.83682 -77.493622)
			(xy 182.838852 -77.506068) (xy 182.852568 -77.51826) (xy 182.859749 -77.523963) (xy 182.876933 -77.530323)
			(xy 182.886096 -77.530706) (xy 185.688732 -77.530706) (xy 185.699908 -77.529944) (xy 191.623188 -75.07605)
			(xy 191.631824 -75.071732) (xy 191.639952 -75.064874) (xy 205.309724 -61.395102) (xy 205.315605 -61.388696)
			(xy 205.323023 -61.372982) (xy 205.324202 -61.364368) (xy 205.47838 -59.870594) (xy 205.478634 -59.862466)
			(xy 204.917548 -50.508154) (xy 204.916532 -50.473102) (xy 204.916532 -50.472594) (xy 204.916786 -50.451766)
			(xy 205.190852 -42.769282) (xy 205.19203 -42.743682) (xy 205.198262 -42.69281) (xy 205.203298 -42.667682)
			(xy 205.204314 -42.66057) (xy 205.204314 -42.660316) (xy 205.204822 -42.653966) (xy 205.211426 -42.469054)
			(xy 205.212169 -42.459455) (xy 205.219866 -42.441823) (xy 205.226412 -42.434764) (xy 205.358746 -42.30243)
			(xy 205.359762 -42.301414) (xy 205.373732 -42.286936) (xy 209.472784 -38.187884) (xy 209.476594 -38.177216)
			(xy 209.487944 -38.146966) (xy 209.516328 -38.088923) (xy 209.533236 -38.061392) (xy 209.536864 -38.055191)
			(xy 209.540848 -38.041395) (xy 209.54111 -38.034214) (xy 209.54111 -37.962078) (xy 209.541537 -37.95201)
			(xy 209.549259 -37.933412) (xy 209.556096 -37.92601) (xy 209.691478 -37.790628) (xy 209.69732 -37.784278)
			(xy 209.716878 -37.764466) (xy 209.717386 -37.763958) (xy 210.023964 -37.457634) (xy 210.038696 -37.44341)
			(xy 210.039712 -37.442394) (xy 210.179666 -37.30244) (xy 210.187066 -37.2956) (xy 210.205665 -37.287883)
			(xy 210.215734 -37.287454) (xy 210.308952 -37.287454) (xy 210.319017 -37.28702) (xy 210.337603 -37.279287)
			(xy 210.34502 -37.272468) (xy 210.345528 -37.27196) (xy 210.345528 -37.15766) (xy 210.345959 -37.147594)
			(xy 210.353687 -37.129002) (xy 210.360514 -37.121592) (xy 210.51393 -36.968176) (xy 210.515962 -36.966144)
			(xy 210.828636 -36.65347) (xy 210.830922 -36.651184) (xy 210.984084 -36.498022) (xy 210.991486 -36.491186)
			(xy 211.010085 -36.483479) (xy 211.020152 -36.483036) (xy 211.123022 -36.483036) (xy 211.143596 -36.47313)
			(xy 211.149692 -36.46551) (xy 211.149692 -36.003992) (xy 211.149469 -35.996952) (xy 211.145604 -35.983415)
			(xy 211.142072 -35.977322) (xy 211.124935 -35.949091) (xy 211.096354 -35.889551) (xy 211.0746 -35.827192)
			(xy 211.059948 -35.762794) (xy 211.052578 -35.697162) (xy 211.052156 -35.66414) (xy 211.052156 -35.405568)
			(xy 211.051726 -35.395501) (xy 211.043998 -35.37691) (xy 211.03717 -35.3695) (xy 211.03082 -35.36315)
			(xy 211.0232 -35.344608) (xy 211.0232 -35.17646) (xy 211.022946 -35.170618) (xy 211.022946 -35.035744)
			(xy 211.0232 -35.03295) (xy 211.0232 -34.45256) (xy 211.023631 -34.442493) (xy 211.031355 -34.423899)
			(xy 211.038186 -34.416492) (xy 211.044536 -34.410142) (xy 211.052156 -34.3916) (xy 211.052156 -34.268156)
			(xy 211.051723 -34.25809) (xy 211.043993 -34.239502) (xy 211.03717 -34.232088) (xy 211.03082 -34.225738)
			(xy 211.0232 -34.207196) (xy 211.0232 -33.315148) (xy 211.023633 -33.305082) (xy 211.03136 -33.286491)
			(xy 211.038186 -33.27908) (xy 211.04479 -33.272476) (xy 211.05241 -33.252918) (xy 211.052156 -33.242504)
			(xy 211.052156 -33.130744) (xy 211.051721 -33.120679) (xy 211.043988 -33.102094) (xy 211.03717 -33.094676)
			(xy 211.03082 -33.088326) (xy 211.0232 -33.069784) (xy 211.0232 -32.177736) (xy 211.023635 -32.167671)
			(xy 211.031366 -32.149083) (xy 211.038186 -32.141668) (xy 211.044028 -32.135826) (xy 211.051975 -32.126922)
			(xy 211.0594 -32.104271) (xy 211.058252 -32.092392) (xy 211.055356 -32.070984) (xy 211.052307 -32.027888)
			(xy 211.052156 -32.006286) (xy 211.052156 -31.993332) (xy 211.051719 -31.983268) (xy 211.043982 -31.964686)
			(xy 211.03717 -31.957264) (xy 211.03082 -31.950914) (xy 211.0232 -31.932372) (xy 211.0232 -31.040324)
			(xy 211.023637 -31.03026) (xy 211.031371 -31.011676) (xy 211.038186 -31.004256) (xy 211.057744 -30.984698)
			(xy 211.063712 -30.978176) (xy 211.071189 -30.962171) (xy 211.072789 -30.944579) (xy 211.070952 -30.93593)
			(xy 211.065948 -30.915733) (xy 211.058444 -30.874801) (xy 211.055966 -30.854142) (xy 211.05495 -30.845506)
			(xy 211.047584 -30.830266) (xy 211.038186 -30.820868) (xy 211.031335 -30.813472) (xy 211.023599 -30.794873)
			(xy 211.0232 -30.7848) (xy 211.0232 -29.902912) (xy 211.023621 -29.892841) (xy 211.031332 -29.874233)
			(xy 211.038186 -29.866844) (xy 211.077556 -29.827474) (xy 211.084054 -29.820338) (xy 211.09164 -29.802609)
			(xy 211.092163 -29.783331) (xy 211.08924 -29.774134) (xy 211.08924 -29.77388) (xy 211.074254 -29.728668)
			(xy 211.072476 -29.722318) (xy 211.066126 -29.711396) (xy 211.038186 -29.683456) (xy 211.031337 -29.676059)
			(xy 211.023605 -29.65746) (xy 211.0232 -29.647388) (xy 211.0232 -28.7655) (xy 211.023623 -28.75543)
			(xy 211.031338 -28.736825) (xy 211.038186 -28.729432) (xy 211.122514 -28.645104) (xy 211.122514 -28.630372)
			(xy 211.038186 -28.546044) (xy 211.031339 -28.538647) (xy 211.023612 -28.520047) (xy 211.0232 -28.509976)
			(xy 211.0232 -27.966416) (xy 211.022692 -27.958542) (xy 211.021081 -27.950244) (xy 211.013163 -27.935321)
			(xy 211.007198 -27.929332) (xy 210.98129 -27.925522) (xy 210.972908 -27.92476) (xy 210.861402 -27.92476)
			(xy 210.851333 -27.924336) (xy 210.832731 -27.916618) (xy 210.825334 -27.909774) (xy 210.746594 -27.831034)
			(xy 210.73999 -27.825446) (xy 210.712944 -27.805746) (xy 210.663029 -27.761183) (xy 210.618464 -27.711269)
			(xy 210.598766 -27.684222) (xy 210.593178 -27.677618) (xy 210.514438 -27.598878) (xy 210.507591 -27.59148)
			(xy 210.499858 -27.572882) (xy 210.499452 -27.56281) (xy 210.499452 -27.451304) (xy 210.49869 -27.442922)
			(xy 210.494722 -27.418095) (xy 210.490527 -27.367988) (xy 210.490308 -27.342846) (xy 210.490545 -27.317705)
			(xy 210.494741 -27.2676) (xy 210.49869 -27.24277) (xy 210.499452 -27.234388) (xy 210.499452 -27.122882)
			(xy 210.49988 -27.112814) (xy 210.507605 -27.09422) (xy 210.514438 -27.086814) (xy 210.593178 -27.008074)
			(xy 210.598766 -27.00147) (xy 210.622896 -26.969466) (xy 210.623404 -26.968958) (xy 210.623404 -26.870152)
			(xy 210.623079 -26.861873) (xy 210.617757 -26.846196) (xy 210.61299 -26.839418) (xy 210.59364 -26.813563)
			(xy 210.560068 -26.758393) (xy 210.532705 -26.699895) (xy 210.511877 -26.638764) (xy 210.497832 -26.575728)
			(xy 210.490738 -26.511537) (xy 210.490308 -26.479246) (xy 210.490753 -26.446076) (xy 210.498176 -26.380152)
			(xy 210.512933 -26.315473) (xy 210.534839 -26.252854) (xy 210.563619 -26.193081) (xy 210.598911 -26.136906)
			(xy 210.64027 -26.085036) (xy 210.687176 -26.038123) (xy 210.739041 -25.996757) (xy 210.795211 -25.961458)
			(xy 210.85498 -25.93267) (xy 210.917596 -25.910755) (xy 210.982273 -25.895989) (xy 211.048196 -25.888558)
			(xy 211.081366 -25.888188) (xy 211.114528 -25.888667) (xy 211.180433 -25.89612) (xy 211.245089 -25.910902)
			(xy 211.307685 -25.932827) (xy 211.367434 -25.96162) (xy 211.423584 -25.99692) (xy 211.475432 -26.038282)
			(xy 211.499196 -26.061416) (xy 211.60359 -26.16581) (xy 211.610984 -26.172668) (xy 211.629583 -26.18042)
			(xy 211.639658 -26.180796) (xy 211.683854 -26.180796) (xy 211.717008 -26.181263) (xy 211.782899 -26.188688)
			(xy 211.847545 -26.203439) (xy 211.910134 -26.225332) (xy 211.969881 -26.25409) (xy 212.026035 -26.289352)
			(xy 212.077891 -26.330677) (xy 212.101684 -26.35377) (xy 212.108796 -26.360882) (xy 213.189564 -26.360882)
			(xy 213.193635 -26.30526) (xy 213.205761 -26.250823) (xy 213.225684 -26.198732) (xy 213.25298 -26.150097)
			(xy 213.287066 -26.105954) (xy 213.327215 -26.067245) (xy 213.372573 -26.034794) (xy 213.422173 -26.009293)
			(xy 213.474957 -25.991286) (xy 213.5298 -25.981156) (xy 213.585534 -25.979119) (xy 213.640971 -25.985219)
			(xy 213.694928 -25.999325) (xy 213.746257 -26.021137) (xy 213.793863 -26.050191) (xy 213.836731 -26.085866)
			(xy 213.873948 -26.127403) (xy 213.904721 -26.173916) (xy 213.928393 -26.224413) (xy 213.944461 -26.27782)
			(xy 213.950629 -26.319734) (xy 218.941902 -26.319734) (xy 218.945973 -26.264112) (xy 218.958099 -26.209675)
			(xy 218.978022 -26.157584) (xy 219.005318 -26.108949) (xy 219.039404 -26.064806) (xy 219.079553 -26.026097)
			(xy 219.124911 -25.993646) (xy 219.174511 -25.968145) (xy 219.227295 -25.950138) (xy 219.282138 -25.940008)
			(xy 219.337872 -25.937971) (xy 219.393309 -25.944071) (xy 219.447266 -25.958177) (xy 219.498595 -25.979989)
			(xy 219.546201 -26.009043) (xy 219.575866 -26.03373) (xy 237.4679 -26.03373) (xy 237.471971 -25.978108)
			(xy 237.484097 -25.923671) (xy 237.50402 -25.87158) (xy 237.531316 -25.822945) (xy 237.565402 -25.778802)
			(xy 237.605551 -25.740093) (xy 237.650909 -25.707642) (xy 237.700509 -25.682141) (xy 237.753293 -25.664134)
			(xy 237.808136 -25.654004) (xy 237.86387 -25.651967) (xy 237.919307 -25.658067) (xy 237.973264 -25.672173)
			(xy 238.024593 -25.693985) (xy 238.072199 -25.723039) (xy 238.115067 -25.758714) (xy 238.152284 -25.800251)
			(xy 238.183057 -25.846764) (xy 238.206729 -25.897261) (xy 238.222797 -25.950668) (xy 238.230917 -26.005844)
			(xy 238.231426 -26.03373) (xy 238.230917 -26.061616) (xy 238.222797 -26.116792) (xy 238.206729 -26.170199)
			(xy 238.183057 -26.220696) (xy 238.152823 -26.266394) (xy 240.720626 -26.266394) (xy 240.721112 -26.239143)
			(xy 240.728868 -26.185195) (xy 240.744223 -26.1329) (xy 240.766865 -26.083323) (xy 240.796331 -26.037473)
			(xy 240.832022 -25.996282) (xy 240.873213 -25.960591) (xy 240.919063 -25.931125) (xy 240.96864 -25.908483)
			(xy 241.020935 -25.893128) (xy 241.074883 -25.885372) (xy 241.129385 -25.885372) (xy 241.183333 -25.893128)
			(xy 241.235628 -25.908483) (xy 241.285205 -25.931125) (xy 241.331055 -25.960591) (xy 241.372246 -25.996282)
			(xy 241.407937 -26.037473) (xy 241.437403 -26.083323) (xy 241.460045 -26.1329) (xy 241.4754 -26.185195)
			(xy 241.483156 -26.239143) (xy 241.483642 -26.266394) (xy 241.483073 -26.295881) (xy 241.47398 -26.35415)
			(xy 241.456024 -26.410324) (xy 241.429634 -26.463064) (xy 241.395439 -26.511113) (xy 241.354254 -26.553324)
			(xy 241.330988 -26.571448) (xy 241.319833 -26.580307) (xy 241.302647 -26.603017) (xy 241.2924 -26.629589)
			(xy 241.289887 -26.657958) (xy 241.295303 -26.685917) (xy 241.308228 -26.711295) (xy 241.327657 -26.732118)
			(xy 241.339624 -26.73985) (xy 241.363366 -26.754746) (xy 241.4066 -26.790414) (xy 241.444151 -26.832024)
			(xy 241.475209 -26.878679) (xy 241.499108 -26.929377) (xy 241.515333 -26.983025) (xy 241.523533 -27.03847)
			(xy 241.524028 -27.066494) (xy 241.523542 -27.093745) (xy 241.515786 -27.147693) (xy 241.500431 -27.199988)
			(xy 241.477789 -27.249565) (xy 241.448323 -27.295415) (xy 241.412632 -27.336606) (xy 241.371441 -27.372297)
			(xy 241.325591 -27.401763) (xy 241.276014 -27.424405) (xy 241.223719 -27.43976) (xy 241.169771 -27.447516)
			(xy 241.115269 -27.447516) (xy 241.061321 -27.43976) (xy 241.009026 -27.424405) (xy 240.959449 -27.401763)
			(xy 240.913599 -27.372297) (xy 240.872408 -27.336606) (xy 240.836717 -27.295415) (xy 240.807251 -27.249565)
			(xy 240.784609 -27.199988) (xy 240.769254 -27.147693) (xy 240.761498 -27.093745) (xy 240.761012 -27.066494)
			(xy 240.76155 -27.037006) (xy 240.770647 -26.978734) (xy 240.788608 -26.922559) (xy 240.815004 -26.869818)
			(xy 240.849205 -26.821771) (xy 240.890397 -26.779562) (xy 240.913666 -26.76144) (xy 240.924723 -26.75247)
			(xy 240.941898 -26.729783) (xy 240.952145 -26.703238) (xy 240.954668 -26.674896) (xy 240.949272 -26.646957)
			(xy 240.936376 -26.621593) (xy 240.91698 -26.600773) (xy 240.90503 -26.593038) (xy 240.881295 -26.578131)
			(xy 240.838058 -26.542467) (xy 240.800505 -26.50086) (xy 240.769445 -26.454206) (xy 240.745545 -26.40351)
			(xy 240.72932 -26.349862) (xy 240.72112 -26.294418) (xy 240.720626 -26.266394) (xy 238.152823 -26.266394)
			(xy 238.152284 -26.267209) (xy 238.115067 -26.308746) (xy 238.072199 -26.344421) (xy 238.024593 -26.373475)
			(xy 237.973264 -26.395287) (xy 237.919307 -26.409393) (xy 237.86387 -26.415493) (xy 237.808136 -26.413456)
			(xy 237.753293 -26.403326) (xy 237.700509 -26.385319) (xy 237.650909 -26.359818) (xy 237.605551 -26.327367)
			(xy 237.565402 -26.288658) (xy 237.531316 -26.244515) (xy 237.50402 -26.19588) (xy 237.484097 -26.143789)
			(xy 237.471971 -26.089352) (xy 237.4679 -26.03373) (xy 219.575866 -26.03373) (xy 219.589069 -26.044718)
			(xy 219.626286 -26.086255) (xy 219.657059 -26.132768) (xy 219.680731 -26.183265) (xy 219.696799 -26.236672)
			(xy 219.704919 -26.291848) (xy 219.705428 -26.319734) (xy 219.704919 -26.34762) (xy 219.696799 -26.402796)
			(xy 219.680731 -26.456203) (xy 219.657059 -26.5067) (xy 219.626286 -26.553213) (xy 219.589069 -26.59475)
			(xy 219.546201 -26.630425) (xy 219.498595 -26.659479) (xy 219.447266 -26.681291) (xy 219.393309 -26.695397)
			(xy 219.337872 -26.701497) (xy 219.282138 -26.69946) (xy 219.227295 -26.68933) (xy 219.174511 -26.671323)
			(xy 219.124911 -26.645822) (xy 219.079553 -26.613371) (xy 219.039404 -26.574662) (xy 219.005318 -26.530519)
			(xy 218.978022 -26.481884) (xy 218.958099 -26.429793) (xy 218.945973 -26.375356) (xy 218.941902 -26.319734)
			(xy 213.950629 -26.319734) (xy 213.952581 -26.332996) (xy 213.95309 -26.360882) (xy 213.952581 -26.388768)
			(xy 213.944461 -26.443944) (xy 213.928393 -26.497351) (xy 213.904721 -26.547848) (xy 213.873948 -26.594361)
			(xy 213.836731 -26.635898) (xy 213.793863 -26.671573) (xy 213.746257 -26.700627) (xy 213.694928 -26.722439)
			(xy 213.640971 -26.736545) (xy 213.585534 -26.742645) (xy 213.5298 -26.740608) (xy 213.474957 -26.730478)
			(xy 213.422173 -26.712471) (xy 213.372573 -26.68697) (xy 213.327215 -26.654519) (xy 213.287066 -26.61581)
			(xy 213.25298 -26.571667) (xy 213.225684 -26.523032) (xy 213.205761 -26.470941) (xy 213.193635 -26.416504)
			(xy 213.189564 -26.360882) (xy 212.108796 -26.360882) (xy 212.45703 -26.709116) (xy 212.480142 -26.732894)
			(xy 212.521479 -26.784745) (xy 212.556751 -26.840899) (xy 212.585515 -26.900648) (xy 212.607409 -26.963242)
			(xy 212.609234 -26.971244) (xy 214.951054 -26.971244) (xy 214.955125 -26.915622) (xy 214.967251 -26.861185)
			(xy 214.987174 -26.809094) (xy 215.01447 -26.760459) (xy 215.048556 -26.716316) (xy 215.088705 -26.677607)
			(xy 215.134063 -26.645156) (xy 215.183663 -26.619655) (xy 215.236447 -26.601648) (xy 215.29129 -26.591518)
			(xy 215.347024 -26.589481) (xy 215.402461 -26.595581) (xy 215.456418 -26.609687) (xy 215.507747 -26.631499)
			(xy 215.555353 -26.660553) (xy 215.598221 -26.696228) (xy 215.635438 -26.737765) (xy 215.666211 -26.784278)
			(xy 215.689883 -26.834775) (xy 215.705951 -26.888182) (xy 215.714071 -26.943358) (xy 215.71458 -26.971244)
			(xy 215.714071 -26.99913) (xy 215.705951 -27.054306) (xy 215.689883 -27.107713) (xy 215.666211 -27.15821)
			(xy 215.635438 -27.204723) (xy 215.598221 -27.24626) (xy 215.555353 -27.281935) (xy 215.507747 -27.310989)
			(xy 215.456418 -27.332801) (xy 215.402461 -27.346907) (xy 215.347024 -27.353007) (xy 215.29129 -27.35097)
			(xy 215.236447 -27.34084) (xy 215.183663 -27.322833) (xy 215.134063 -27.297332) (xy 215.088705 -27.264881)
			(xy 215.048556 -27.226172) (xy 215.01447 -27.182029) (xy 214.987174 -27.133394) (xy 214.967251 -27.081303)
			(xy 214.955125 -27.026866) (xy 214.951054 -26.971244) (xy 212.609234 -26.971244) (xy 212.622158 -27.027894)
			(xy 212.629577 -27.09379) (xy 212.630004 -27.126946) (xy 212.630004 -29.114242) (xy 212.947504 -29.114242)
			(xy 212.947504 -28.250642) (xy 212.947994 -28.220674) (xy 212.955817 -28.161252) (xy 212.97133 -28.103359)
			(xy 212.994266 -28.047986) (xy 213.024233 -27.99608) (xy 213.06072 -27.94853) (xy 213.1031 -27.90615)
			(xy 213.15065 -27.869663) (xy 213.202556 -27.839696) (xy 213.257929 -27.81676) (xy 213.315822 -27.801247)
			(xy 213.375244 -27.793424) (xy 213.43518 -27.793424) (xy 213.494602 -27.801247) (xy 213.552495 -27.81676)
			(xy 213.607868 -27.839696) (xy 213.659774 -27.869663) (xy 213.707324 -27.90615) (xy 213.749704 -27.94853)
			(xy 213.786191 -27.99608) (xy 213.816158 -28.047986) (xy 213.839094 -28.103359) (xy 213.854607 -28.161252)
			(xy 213.86243 -28.220674) (xy 213.86292 -28.250642) (xy 213.86292 -28.469082) (xy 217.852496 -28.469082)
			(xy 217.856567 -28.41346) (xy 217.868693 -28.359023) (xy 217.888616 -28.306932) (xy 217.915912 -28.258297)
			(xy 217.949998 -28.214154) (xy 217.990147 -28.175445) (xy 218.035505 -28.142994) (xy 218.085105 -28.117493)
			(xy 218.137889 -28.099486) (xy 218.192732 -28.089356) (xy 218.248466 -28.087319) (xy 218.303903 -28.093419)
			(xy 218.35786 -28.107525) (xy 218.409189 -28.129337) (xy 218.425245 -28.139136) (xy 234.597954 -28.139136)
			(xy 234.602025 -28.083514) (xy 234.614151 -28.029077) (xy 234.634074 -27.976986) (xy 234.66137 -27.928351)
			(xy 234.695456 -27.884208) (xy 234.735605 -27.845499) (xy 234.780963 -27.813048) (xy 234.830563 -27.787547)
			(xy 234.883347 -27.76954) (xy 234.93819 -27.75941) (xy 234.993924 -27.757373) (xy 235.049361 -27.763473)
			(xy 235.103318 -27.777579) (xy 235.154647 -27.799391) (xy 235.202253 -27.828445) (xy 235.245121 -27.86412)
			(xy 235.282338 -27.905657) (xy 235.313111 -27.95217) (xy 235.336783 -28.002667) (xy 235.352851 -28.056074)
			(xy 235.360971 -28.11125) (xy 235.36148 -28.139136) (xy 235.867954 -28.139136) (xy 235.872025 -28.083514)
			(xy 235.884151 -28.029077) (xy 235.904074 -27.976986) (xy 235.93137 -27.928351) (xy 235.965456 -27.884208)
			(xy 236.005605 -27.845499) (xy 236.050963 -27.813048) (xy 236.100563 -27.787547) (xy 236.153347 -27.76954)
			(xy 236.20819 -27.75941) (xy 236.263924 -27.757373) (xy 236.319361 -27.763473) (xy 236.373318 -27.777579)
			(xy 236.424647 -27.799391) (xy 236.472253 -27.828445) (xy 236.515121 -27.86412) (xy 236.552338 -27.905657)
			(xy 236.583111 -27.95217) (xy 236.606783 -28.002667) (xy 236.622851 -28.056074) (xy 236.630971 -28.11125)
			(xy 236.63148 -28.139136) (xy 236.630971 -28.167022) (xy 236.622851 -28.222198) (xy 236.606783 -28.275605)
			(xy 236.583111 -28.326102) (xy 236.552338 -28.372615) (xy 236.515121 -28.414152) (xy 236.472253 -28.449827)
			(xy 236.424647 -28.478881) (xy 236.373318 -28.500693) (xy 236.319361 -28.514799) (xy 236.263924 -28.520899)
			(xy 236.20819 -28.518862) (xy 236.153347 -28.508732) (xy 236.100563 -28.490725) (xy 236.050963 -28.465224)
			(xy 236.005605 -28.432773) (xy 235.965456 -28.394064) (xy 235.93137 -28.349921) (xy 235.904074 -28.301286)
			(xy 235.884151 -28.249195) (xy 235.872025 -28.194758) (xy 235.867954 -28.139136) (xy 235.36148 -28.139136)
			(xy 235.360971 -28.167022) (xy 235.352851 -28.222198) (xy 235.336783 -28.275605) (xy 235.313111 -28.326102)
			(xy 235.282338 -28.372615) (xy 235.245121 -28.414152) (xy 235.202253 -28.449827) (xy 235.154647 -28.478881)
			(xy 235.103318 -28.500693) (xy 235.049361 -28.514799) (xy 234.993924 -28.520899) (xy 234.93819 -28.518862)
			(xy 234.883347 -28.508732) (xy 234.830563 -28.490725) (xy 234.780963 -28.465224) (xy 234.735605 -28.432773)
			(xy 234.695456 -28.394064) (xy 234.66137 -28.349921) (xy 234.634074 -28.301286) (xy 234.614151 -28.249195)
			(xy 234.602025 -28.194758) (xy 234.597954 -28.139136) (xy 218.425245 -28.139136) (xy 218.456795 -28.158391)
			(xy 218.499663 -28.194066) (xy 218.53688 -28.235603) (xy 218.567653 -28.282116) (xy 218.591325 -28.332613)
			(xy 218.607393 -28.38602) (xy 218.615513 -28.441196) (xy 218.616022 -28.469082) (xy 218.615513 -28.496968)
			(xy 218.607393 -28.552144) (xy 218.591325 -28.605551) (xy 218.567653 -28.656048) (xy 218.53688 -28.702561)
			(xy 218.499663 -28.744098) (xy 218.456795 -28.779773) (xy 218.409189 -28.808827) (xy 218.35786 -28.830639)
			(xy 218.303903 -28.844745) (xy 218.248466 -28.850845) (xy 218.192732 -28.848808) (xy 218.137889 -28.838678)
			(xy 218.085105 -28.820671) (xy 218.035505 -28.79517) (xy 217.990147 -28.762719) (xy 217.949998 -28.72401)
			(xy 217.915912 -28.679867) (xy 217.888616 -28.631232) (xy 217.868693 -28.579141) (xy 217.856567 -28.524704)
			(xy 217.852496 -28.469082) (xy 213.86292 -28.469082) (xy 213.86292 -29.114242) (xy 213.862787 -29.12237)
			(xy 240.806732 -29.12237) (xy 240.806732 -28.25877) (xy 240.807222 -28.228786) (xy 240.81505 -28.16933)
			(xy 240.830571 -28.111405) (xy 240.85352 -28.056001) (xy 240.883504 -28.004067) (xy 240.92001 -27.956491)
			(xy 240.962415 -27.914086) (xy 241.009991 -27.87758) (xy 241.061925 -27.847596) (xy 241.117329 -27.824647)
			(xy 241.175254 -27.809126) (xy 241.23471 -27.801298) (xy 241.294678 -27.801298) (xy 241.354134 -27.809126)
			(xy 241.412059 -27.824647) (xy 241.467463 -27.847596) (xy 241.519397 -27.87758) (xy 241.566973 -27.914086)
			(xy 241.609378 -27.956491) (xy 241.645884 -28.004067) (xy 241.675868 -28.056001) (xy 241.698817 -28.111405)
			(xy 241.714338 -28.16933) (xy 241.722166 -28.228786) (xy 241.722656 -28.25877) (xy 241.722656 -29.12237)
			(xy 241.722166 -29.152354) (xy 241.714338 -29.21181) (xy 241.698817 -29.269735) (xy 241.675868 -29.325139)
			(xy 241.645884 -29.377073) (xy 241.609378 -29.424649) (xy 241.566973 -29.467054) (xy 241.519397 -29.50356)
			(xy 241.467463 -29.533544) (xy 241.412059 -29.556493) (xy 241.354134 -29.572014) (xy 241.294678 -29.579842)
			(xy 241.23471 -29.579842) (xy 241.175254 -29.572014) (xy 241.117329 -29.556493) (xy 241.061925 -29.533544)
			(xy 241.009991 -29.50356) (xy 240.962415 -29.467054) (xy 240.92001 -29.424649) (xy 240.883504 -29.377073)
			(xy 240.85352 -29.325139) (xy 240.830571 -29.269735) (xy 240.81505 -29.21181) (xy 240.807222 -29.152354)
			(xy 240.806732 -29.12237) (xy 213.862787 -29.12237) (xy 213.86243 -29.14421) (xy 213.854607 -29.203632)
			(xy 213.839094 -29.261525) (xy 213.816158 -29.316898) (xy 213.786191 -29.368804) (xy 213.749704 -29.416354)
			(xy 213.707324 -29.458734) (xy 213.659774 -29.495221) (xy 213.607868 -29.525188) (xy 213.552495 -29.548124)
			(xy 213.494602 -29.563637) (xy 213.43518 -29.57146) (xy 213.375244 -29.57146) (xy 213.315822 -29.563637)
			(xy 213.257929 -29.548124) (xy 213.202556 -29.525188) (xy 213.15065 -29.495221) (xy 213.1031 -29.458734)
			(xy 213.06072 -29.416354) (xy 213.024233 -29.368804) (xy 212.994266 -29.316898) (xy 212.97133 -29.261525)
			(xy 212.955817 -29.203632) (xy 212.947994 -29.14421) (xy 212.947504 -29.114242) (xy 212.630004 -29.114242)
			(xy 212.630004 -30.92069) (xy 215.589612 -30.92069) (xy 215.589612 -30.05709) (xy 215.590102 -30.027122)
			(xy 215.597925 -29.9677) (xy 215.613438 -29.909807) (xy 215.636374 -29.854434) (xy 215.666341 -29.802528)
			(xy 215.702828 -29.754978) (xy 215.745208 -29.712598) (xy 215.792758 -29.676111) (xy 215.844664 -29.646144)
			(xy 215.900037 -29.623208) (xy 215.95793 -29.607695) (xy 216.017352 -29.599872) (xy 216.077288 -29.599872)
			(xy 216.13671 -29.607695) (xy 216.194603 -29.623208) (xy 216.249976 -29.646144) (xy 216.301882 -29.676111)
			(xy 216.349432 -29.712598) (xy 216.391812 -29.754978) (xy 216.428299 -29.802528) (xy 216.458266 -29.854434)
			(xy 216.481202 -29.909807) (xy 216.496715 -29.9677) (xy 216.504538 -30.027122) (xy 216.505028 -30.05709)
			(xy 216.505028 -30.376876) (xy 233.088942 -30.376876) (xy 233.089499 -30.34796) (xy 233.098218 -30.29079)
			(xy 233.115467 -30.235592) (xy 233.140851 -30.183629) (xy 233.173789 -30.136095) (xy 233.213525 -30.094077)
			(xy 233.236008 -30.075886) (xy 233.244813 -30.068276) (xy 233.254997 -30.047378) (xy 233.255566 -30.035754)
			(xy 233.255566 -29.955998) (xy 233.255026 -29.944366) (xy 233.244839 -29.923456) (xy 233.236008 -29.915866)
			(xy 233.21351 -29.897692) (xy 233.173775 -29.855669) (xy 233.140838 -29.808131) (xy 233.115452 -29.756166)
			(xy 233.098199 -29.700965) (xy 233.089474 -29.643793) (xy 233.088942 -29.614876) (xy 233.089428 -29.587625)
			(xy 233.097184 -29.533677) (xy 233.112539 -29.481382) (xy 233.135181 -29.431805) (xy 233.164647 -29.385955)
			(xy 233.200338 -29.344764) (xy 233.241529 -29.309073) (xy 233.287379 -29.279607) (xy 233.336956 -29.256965)
			(xy 233.389251 -29.24161) (xy 233.443199 -29.233854) (xy 233.497701 -29.233854) (xy 233.551649 -29.24161)
			(xy 233.603944 -29.256965) (xy 233.653521 -29.279607) (xy 233.699371 -29.309073) (xy 233.740562 -29.344764)
			(xy 233.776253 -29.385955) (xy 233.805719 -29.431805) (xy 233.828361 -29.481382) (xy 233.843716 -29.533677)
			(xy 233.851472 -29.587625) (xy 233.851958 -29.614876) (xy 233.851438 -29.643793) (xy 233.842712 -29.700965)
			(xy 233.825455 -29.756164) (xy 233.800064 -29.808126) (xy 233.76712 -29.85566) (xy 233.727378 -29.897676)
			(xy 233.704892 -29.915866) (xy 233.696109 -29.923497) (xy 233.685912 -29.944379) (xy 233.685334 -29.955998)
			(xy 233.685334 -30.035754) (xy 233.685845 -30.04739) (xy 233.696053 -30.0683) (xy 233.704892 -30.075886)
			(xy 233.727367 -30.094087) (xy 233.767103 -30.136104) (xy 233.800043 -30.183637) (xy 233.825433 -30.235597)
			(xy 233.842691 -30.290792) (xy 233.851422 -30.347961) (xy 233.851958 -30.376876) (xy 236.129068 -30.376876)
			(xy 236.129615 -30.34796) (xy 236.138335 -30.290789) (xy 236.155585 -30.23559) (xy 236.180971 -30.183627)
			(xy 236.213911 -30.136093) (xy 236.25365 -30.094076) (xy 236.276134 -30.075886) (xy 236.284943 -30.068281)
			(xy 236.295124 -30.047378) (xy 236.295692 -30.035754) (xy 236.295692 -29.955998) (xy 236.295143 -29.944367)
			(xy 236.284961 -29.923457) (xy 236.276134 -29.915866) (xy 236.253641 -29.897686) (xy 236.213905 -29.855665)
			(xy 236.180966 -29.808128) (xy 236.155579 -29.756164) (xy 236.138325 -29.700964) (xy 236.1296 -29.643793)
			(xy 236.129068 -29.614876) (xy 236.129554 -29.587625) (xy 236.13731 -29.533677) (xy 236.152665 -29.481382)
			(xy 236.175307 -29.431805) (xy 236.204773 -29.385955) (xy 236.240464 -29.344764) (xy 236.281655 -29.309073)
			(xy 236.327505 -29.279607) (xy 236.377082 -29.256965) (xy 236.429377 -29.24161) (xy 236.483325 -29.233854)
			(xy 236.537827 -29.233854) (xy 236.591775 -29.24161) (xy 236.64407 -29.256965) (xy 236.693647 -29.279607)
			(xy 236.739497 -29.309073) (xy 236.780688 -29.344764) (xy 236.816379 -29.385955) (xy 236.845845 -29.431805)
			(xy 236.868487 -29.481382) (xy 236.883842 -29.533677) (xy 236.891598 -29.587625) (xy 236.892084 -29.614876)
			(xy 236.891554 -29.643793) (xy 236.882829 -29.700964) (xy 236.865573 -29.756162) (xy 236.840184 -29.808124)
			(xy 236.807242 -29.855658) (xy 236.767503 -29.897676) (xy 236.745018 -29.915866) (xy 236.736222 -29.923484)
			(xy 236.726036 -29.944377) (xy 236.72546 -29.955998) (xy 236.72546 -30.035754) (xy 236.725961 -30.047391)
			(xy 236.736175 -30.068302) (xy 236.745018 -30.075886) (xy 236.767499 -30.09408) (xy 236.807233 -30.1361)
			(xy 236.840172 -30.183634) (xy 236.865561 -30.235595) (xy 236.882818 -30.290792) (xy 236.891548 -30.34796)
			(xy 236.892084 -30.376876) (xy 236.891598 -30.404127) (xy 236.883842 -30.458075) (xy 236.868487 -30.51037)
			(xy 236.845845 -30.559947) (xy 236.816379 -30.605797) (xy 236.780688 -30.646988) (xy 236.739497 -30.682679)
			(xy 236.693647 -30.712145) (xy 236.64407 -30.734787) (xy 236.591775 -30.750142) (xy 236.537827 -30.757898)
			(xy 236.483325 -30.757898) (xy 236.429377 -30.750142) (xy 236.377082 -30.734787) (xy 236.327505 -30.712145)
			(xy 236.281655 -30.682679) (xy 236.240464 -30.646988) (xy 236.204773 -30.605797) (xy 236.175307 -30.559947)
			(xy 236.152665 -30.51037) (xy 236.13731 -30.458075) (xy 236.129554 -30.404127) (xy 236.129068 -30.376876)
			(xy 233.851958 -30.376876) (xy 233.851472 -30.404127) (xy 233.843716 -30.458075) (xy 233.828361 -30.51037)
			(xy 233.805719 -30.559947) (xy 233.776253 -30.605797) (xy 233.740562 -30.646988) (xy 233.699371 -30.682679)
			(xy 233.653521 -30.712145) (xy 233.603944 -30.734787) (xy 233.551649 -30.750142) (xy 233.497701 -30.757898)
			(xy 233.443199 -30.757898) (xy 233.389251 -30.750142) (xy 233.336956 -30.734787) (xy 233.287379 -30.712145)
			(xy 233.241529 -30.682679) (xy 233.200338 -30.646988) (xy 233.164647 -30.605797) (xy 233.135181 -30.559947)
			(xy 233.112539 -30.51037) (xy 233.097184 -30.458075) (xy 233.089428 -30.404127) (xy 233.088942 -30.376876)
			(xy 216.505028 -30.376876) (xy 216.505028 -30.92069) (xy 216.504999 -30.922468) (xy 238.952532 -30.922468)
			(xy 238.952532 -30.058868) (xy 238.953022 -30.028884) (xy 238.96085 -29.969428) (xy 238.976371 -29.911503)
			(xy 238.99932 -29.856099) (xy 239.029304 -29.804165) (xy 239.06581 -29.756589) (xy 239.108215 -29.714184)
			(xy 239.155791 -29.677678) (xy 239.207725 -29.647694) (xy 239.263129 -29.624745) (xy 239.321054 -29.609224)
			(xy 239.38051 -29.601396) (xy 239.440478 -29.601396) (xy 239.499934 -29.609224) (xy 239.557859 -29.624745)
			(xy 239.613263 -29.647694) (xy 239.665197 -29.677678) (xy 239.712773 -29.714184) (xy 239.755178 -29.756589)
			(xy 239.791684 -29.804165) (xy 239.821668 -29.856099) (xy 239.844617 -29.911503) (xy 239.860138 -29.969428)
			(xy 239.867966 -30.028884) (xy 239.868456 -30.058868) (xy 239.868456 -30.922468) (xy 239.867966 -30.952452)
			(xy 239.860138 -31.011908) (xy 239.844617 -31.069833) (xy 239.821668 -31.125237) (xy 239.791684 -31.177171)
			(xy 239.755178 -31.224747) (xy 239.712773 -31.267152) (xy 239.665197 -31.303658) (xy 239.613263 -31.333642)
			(xy 239.557859 -31.356591) (xy 239.499934 -31.372112) (xy 239.440478 -31.37994) (xy 239.38051 -31.37994)
			(xy 239.321054 -31.372112) (xy 239.263129 -31.356591) (xy 239.207725 -31.333642) (xy 239.155791 -31.303658)
			(xy 239.108215 -31.267152) (xy 239.06581 -31.224747) (xy 239.029304 -31.177171) (xy 238.99932 -31.125237)
			(xy 238.976371 -31.069833) (xy 238.96085 -31.011908) (xy 238.953022 -30.952452) (xy 238.952532 -30.922468)
			(xy 216.504999 -30.922468) (xy 216.504538 -30.950658) (xy 216.496715 -31.01008) (xy 216.481202 -31.067973)
			(xy 216.458266 -31.123346) (xy 216.428299 -31.175252) (xy 216.391812 -31.222802) (xy 216.349432 -31.265182)
			(xy 216.301882 -31.301669) (xy 216.249976 -31.331636) (xy 216.194603 -31.354572) (xy 216.13671 -31.370085)
			(xy 216.077288 -31.377908) (xy 216.017352 -31.377908) (xy 215.95793 -31.370085) (xy 215.900037 -31.354572)
			(xy 215.844664 -31.331636) (xy 215.792758 -31.301669) (xy 215.745208 -31.265182) (xy 215.702828 -31.222802)
			(xy 215.666341 -31.175252) (xy 215.636374 -31.123346) (xy 215.613438 -31.067973) (xy 215.597925 -31.01008)
			(xy 215.590102 -30.950658) (xy 215.589612 -30.92069) (xy 212.630004 -30.92069) (xy 212.630004 -32.714184)
			(xy 212.947504 -32.714184) (xy 212.947504 -31.850584) (xy 212.947994 -31.820616) (xy 212.955817 -31.761194)
			(xy 212.97133 -31.703301) (xy 212.994266 -31.647928) (xy 213.024233 -31.596022) (xy 213.06072 -31.548472)
			(xy 213.1031 -31.506092) (xy 213.15065 -31.469605) (xy 213.202556 -31.439638) (xy 213.257929 -31.416702)
			(xy 213.315822 -31.401189) (xy 213.375244 -31.393366) (xy 213.43518 -31.393366) (xy 213.494602 -31.401189)
			(xy 213.552495 -31.416702) (xy 213.607868 -31.439638) (xy 213.659774 -31.469605) (xy 213.707324 -31.506092)
			(xy 213.749704 -31.548472) (xy 213.764598 -31.567882) (xy 233.198668 -31.567882) (xy 233.202739 -31.51226)
			(xy 233.214865 -31.457823) (xy 233.234788 -31.405732) (xy 233.262084 -31.357097) (xy 233.29617 -31.312954)
			(xy 233.336319 -31.274245) (xy 233.381677 -31.241794) (xy 233.431277 -31.216293) (xy 233.484061 -31.198286)
			(xy 233.538904 -31.188156) (xy 233.594638 -31.186119) (xy 233.650075 -31.192219) (xy 233.704032 -31.206325)
			(xy 233.755361 -31.228137) (xy 233.802967 -31.257191) (xy 233.845835 -31.292866) (xy 233.883052 -31.334403)
			(xy 233.913825 -31.380916) (xy 233.937497 -31.431413) (xy 233.953565 -31.48482) (xy 233.961685 -31.539996)
			(xy 233.962194 -31.567882) (xy 233.961685 -31.595768) (xy 233.953565 -31.650944) (xy 233.937497 -31.704351)
			(xy 233.930505 -31.719266) (xy 234.485432 -31.719266) (xy 234.489503 -31.663644) (xy 234.501629 -31.609207)
			(xy 234.521552 -31.557116) (xy 234.548848 -31.508481) (xy 234.582934 -31.464338) (xy 234.623083 -31.425629)
			(xy 234.668441 -31.393178) (xy 234.718041 -31.367677) (xy 234.770825 -31.34967) (xy 234.825668 -31.33954)
			(xy 234.881402 -31.337503) (xy 234.936839 -31.343603) (xy 234.990796 -31.357709) (xy 235.042125 -31.379521)
			(xy 235.089731 -31.408575) (xy 235.132599 -31.44425) (xy 235.169816 -31.485787) (xy 235.200589 -31.5323)
			(xy 235.224261 -31.582797) (xy 235.240329 -31.636204) (xy 235.244479 -31.664402) (xy 235.76102 -31.664402)
			(xy 235.765091 -31.60878) (xy 235.777217 -31.554343) (xy 235.79714 -31.502252) (xy 235.824436 -31.453617)
			(xy 235.858522 -31.409474) (xy 235.898671 -31.370765) (xy 235.944029 -31.338314) (xy 235.993629 -31.312813)
			(xy 236.046413 -31.294806) (xy 236.101256 -31.284676) (xy 236.15699 -31.282639) (xy 236.212427 -31.288739)
			(xy 236.266384 -31.302845) (xy 236.317713 -31.324657) (xy 236.365319 -31.353711) (xy 236.408187 -31.389386)
			(xy 236.445404 -31.430923) (xy 236.476177 -31.477436) (xy 236.499849 -31.527933) (xy 236.515917 -31.58134)
			(xy 236.524037 -31.636516) (xy 236.524546 -31.664402) (xy 236.524037 -31.692288) (xy 236.515917 -31.747464)
			(xy 236.506977 -31.777178) (xy 237.026194 -31.777178) (xy 237.030265 -31.721556) (xy 237.042391 -31.667119)
			(xy 237.062314 -31.615028) (xy 237.08961 -31.566393) (xy 237.123696 -31.52225) (xy 237.163845 -31.483541)
			(xy 237.209203 -31.45109) (xy 237.258803 -31.425589) (xy 237.311587 -31.407582) (xy 237.36643 -31.397452)
			(xy 237.422164 -31.395415) (xy 237.477601 -31.401515) (xy 237.531558 -31.415621) (xy 237.582887 -31.437433)
			(xy 237.630493 -31.466487) (xy 237.673361 -31.502162) (xy 237.710578 -31.543699) (xy 237.741351 -31.590212)
			(xy 237.765023 -31.640709) (xy 237.781091 -31.694116) (xy 237.789211 -31.749292) (xy 237.78972 -31.777178)
			(xy 237.789211 -31.805064) (xy 237.781091 -31.86024) (xy 237.765023 -31.913647) (xy 237.741351 -31.964144)
			(xy 237.710578 -32.010657) (xy 237.673361 -32.052194) (xy 237.630493 -32.087869) (xy 237.582887 -32.116923)
			(xy 237.531558 -32.138735) (xy 237.477601 -32.152841) (xy 237.422164 -32.158941) (xy 237.36643 -32.156904)
			(xy 237.311587 -32.146774) (xy 237.258803 -32.128767) (xy 237.209203 -32.103266) (xy 237.163845 -32.070815)
			(xy 237.123696 -32.032106) (xy 237.08961 -31.987963) (xy 237.062314 -31.939328) (xy 237.042391 -31.887237)
			(xy 237.030265 -31.8328) (xy 237.026194 -31.777178) (xy 236.506977 -31.777178) (xy 236.499849 -31.800871)
			(xy 236.476177 -31.851368) (xy 236.445404 -31.897881) (xy 236.408187 -31.939418) (xy 236.365319 -31.975093)
			(xy 236.317713 -32.004147) (xy 236.266384 -32.025959) (xy 236.212427 -32.040065) (xy 236.15699 -32.046165)
			(xy 236.101256 -32.044128) (xy 236.046413 -32.033998) (xy 235.993629 -32.015991) (xy 235.944029 -31.99049)
			(xy 235.898671 -31.958039) (xy 235.858522 -31.91933) (xy 235.824436 -31.875187) (xy 235.79714 -31.826552)
			(xy 235.777217 -31.774461) (xy 235.765091 -31.720024) (xy 235.76102 -31.664402) (xy 235.244479 -31.664402)
			(xy 235.248449 -31.69138) (xy 235.248958 -31.719266) (xy 235.248449 -31.747152) (xy 235.240329 -31.802328)
			(xy 235.224261 -31.855735) (xy 235.200589 -31.906232) (xy 235.169816 -31.952745) (xy 235.132599 -31.994282)
			(xy 235.089731 -32.029957) (xy 235.042125 -32.059011) (xy 234.990796 -32.080823) (xy 234.936839 -32.094929)
			(xy 234.881402 -32.101029) (xy 234.825668 -32.098992) (xy 234.770825 -32.088862) (xy 234.718041 -32.070855)
			(xy 234.668441 -32.045354) (xy 234.623083 -32.012903) (xy 234.582934 -31.974194) (xy 234.548848 -31.930051)
			(xy 234.521552 -31.881416) (xy 234.501629 -31.829325) (xy 234.489503 -31.774888) (xy 234.485432 -31.719266)
			(xy 233.930505 -31.719266) (xy 233.913825 -31.754848) (xy 233.883052 -31.801361) (xy 233.845835 -31.842898)
			(xy 233.802967 -31.878573) (xy 233.755361 -31.907627) (xy 233.704032 -31.929439) (xy 233.650075 -31.943545)
			(xy 233.594638 -31.949645) (xy 233.538904 -31.947608) (xy 233.484061 -31.937478) (xy 233.431277 -31.919471)
			(xy 233.381677 -31.89397) (xy 233.336319 -31.861519) (xy 233.29617 -31.82281) (xy 233.262084 -31.778667)
			(xy 233.234788 -31.730032) (xy 233.214865 -31.677941) (xy 233.202739 -31.623504) (xy 233.198668 -31.567882)
			(xy 213.764598 -31.567882) (xy 213.786191 -31.596022) (xy 213.816158 -31.647928) (xy 213.839094 -31.703301)
			(xy 213.854607 -31.761194) (xy 213.86243 -31.820616) (xy 213.86292 -31.850584) (xy 213.86292 -32.714184)
			(xy 213.862787 -32.722312) (xy 240.806732 -32.722312) (xy 240.806732 -31.858712) (xy 240.807222 -31.828728)
			(xy 240.81505 -31.769272) (xy 240.830571 -31.711347) (xy 240.85352 -31.655943) (xy 240.883504 -31.604009)
			(xy 240.92001 -31.556433) (xy 240.962415 -31.514028) (xy 241.009991 -31.477522) (xy 241.061925 -31.447538)
			(xy 241.117329 -31.424589) (xy 241.175254 -31.409068) (xy 241.23471 -31.40124) (xy 241.294678 -31.40124)
			(xy 241.354134 -31.409068) (xy 241.412059 -31.424589) (xy 241.467463 -31.447538) (xy 241.519397 -31.477522)
			(xy 241.566973 -31.514028) (xy 241.609378 -31.556433) (xy 241.645884 -31.604009) (xy 241.675868 -31.655943)
			(xy 241.698817 -31.711347) (xy 241.714338 -31.769272) (xy 241.722166 -31.828728) (xy 241.722656 -31.858712)
			(xy 241.722656 -32.714184) (xy 251.047504 -32.714184) (xy 251.047504 -31.850584) (xy 251.047994 -31.820616)
			(xy 251.055817 -31.761194) (xy 251.07133 -31.703301) (xy 251.094266 -31.647928) (xy 251.124233 -31.596022)
			(xy 251.16072 -31.548472) (xy 251.2031 -31.506092) (xy 251.25065 -31.469605) (xy 251.302556 -31.439638)
			(xy 251.357929 -31.416702) (xy 251.415822 -31.401189) (xy 251.475244 -31.393366) (xy 251.53518 -31.393366)
			(xy 251.594602 -31.401189) (xy 251.652495 -31.416702) (xy 251.707868 -31.439638) (xy 251.759774 -31.469605)
			(xy 251.807324 -31.506092) (xy 251.849704 -31.548472) (xy 251.886191 -31.596022) (xy 251.916158 -31.647928)
			(xy 251.939094 -31.703301) (xy 251.954607 -31.761194) (xy 251.96243 -31.820616) (xy 251.96292 -31.850584)
			(xy 251.96292 -32.714184) (xy 251.96243 -32.744152) (xy 251.954607 -32.803574) (xy 251.939094 -32.861467)
			(xy 251.916158 -32.91684) (xy 251.886191 -32.968746) (xy 251.849704 -33.016296) (xy 251.807324 -33.058676)
			(xy 251.759774 -33.095163) (xy 251.707868 -33.12513) (xy 251.652495 -33.148066) (xy 251.594602 -33.163579)
			(xy 251.53518 -33.171402) (xy 251.475244 -33.171402) (xy 251.415822 -33.163579) (xy 251.357929 -33.148066)
			(xy 251.302556 -33.12513) (xy 251.25065 -33.095163) (xy 251.2031 -33.058676) (xy 251.16072 -33.016296)
			(xy 251.124233 -32.968746) (xy 251.094266 -32.91684) (xy 251.07133 -32.861467) (xy 251.055817 -32.803574)
			(xy 251.047994 -32.744152) (xy 251.047504 -32.714184) (xy 241.722656 -32.714184) (xy 241.722656 -32.722312)
			(xy 241.722166 -32.752296) (xy 241.714338 -32.811752) (xy 241.698817 -32.869677) (xy 241.675868 -32.925081)
			(xy 241.645884 -32.977015) (xy 241.609378 -33.024591) (xy 241.566973 -33.066996) (xy 241.519397 -33.103502)
			(xy 241.467463 -33.133486) (xy 241.412059 -33.156435) (xy 241.354134 -33.171956) (xy 241.294678 -33.179784)
			(xy 241.23471 -33.179784) (xy 241.175254 -33.171956) (xy 241.117329 -33.156435) (xy 241.061925 -33.133486)
			(xy 241.009991 -33.103502) (xy 240.962415 -33.066996) (xy 240.92001 -33.024591) (xy 240.883504 -32.977015)
			(xy 240.85352 -32.925081) (xy 240.830571 -32.869677) (xy 240.81505 -32.811752) (xy 240.807222 -32.752296)
			(xy 240.806732 -32.722312) (xy 213.862787 -32.722312) (xy 213.86243 -32.744152) (xy 213.854607 -32.803574)
			(xy 213.839094 -32.861467) (xy 213.816158 -32.91684) (xy 213.786191 -32.968746) (xy 213.749704 -33.016296)
			(xy 213.707324 -33.058676) (xy 213.659774 -33.095163) (xy 213.607868 -33.12513) (xy 213.552495 -33.148066)
			(xy 213.494602 -33.163579) (xy 213.43518 -33.171402) (xy 213.375244 -33.171402) (xy 213.315822 -33.163579)
			(xy 213.257929 -33.148066) (xy 213.202556 -33.12513) (xy 213.15065 -33.095163) (xy 213.1031 -33.058676)
			(xy 213.06072 -33.016296) (xy 213.024233 -32.968746) (xy 212.994266 -32.91684) (xy 212.97133 -32.861467)
			(xy 212.955817 -32.803574) (xy 212.947994 -32.744152) (xy 212.947504 -32.714184) (xy 212.630004 -32.714184)
			(xy 212.630004 -34.520886) (xy 215.589612 -34.520886) (xy 215.589612 -33.657286) (xy 215.590102 -33.627318)
			(xy 215.597925 -33.567896) (xy 215.613438 -33.510003) (xy 215.636374 -33.45463) (xy 215.666341 -33.402724)
			(xy 215.702828 -33.355174) (xy 215.745208 -33.312794) (xy 215.792758 -33.276307) (xy 215.844664 -33.24634)
			(xy 215.900037 -33.223404) (xy 215.95793 -33.207891) (xy 216.017352 -33.200068) (xy 216.077288 -33.200068)
			(xy 216.13671 -33.207891) (xy 216.194603 -33.223404) (xy 216.249976 -33.24634) (xy 216.301882 -33.276307)
			(xy 216.349432 -33.312794) (xy 216.391812 -33.355174) (xy 216.428299 -33.402724) (xy 216.458266 -33.45463)
			(xy 216.481202 -33.510003) (xy 216.496715 -33.567896) (xy 216.504538 -33.627318) (xy 216.505028 -33.657286)
			(xy 216.505028 -34.520886) (xy 216.505003 -34.52241) (xy 238.952532 -34.52241) (xy 238.952532 -33.65881)
			(xy 238.953022 -33.628826) (xy 238.96085 -33.56937) (xy 238.976371 -33.511445) (xy 238.99932 -33.456041)
			(xy 239.029304 -33.404107) (xy 239.06581 -33.356531) (xy 239.108215 -33.314126) (xy 239.155791 -33.27762)
			(xy 239.207725 -33.247636) (xy 239.263129 -33.224687) (xy 239.321054 -33.209166) (xy 239.38051 -33.201338)
			(xy 239.440478 -33.201338) (xy 239.499934 -33.209166) (xy 239.557859 -33.224687) (xy 239.613263 -33.247636)
			(xy 239.665197 -33.27762) (xy 239.712773 -33.314126) (xy 239.755178 -33.356531) (xy 239.791684 -33.404107)
			(xy 239.821668 -33.456041) (xy 239.844617 -33.511445) (xy 239.860138 -33.56937) (xy 239.867966 -33.628826)
			(xy 239.868456 -33.65881) (xy 239.868456 -34.520886) (xy 253.689612 -34.520886) (xy 253.689612 -33.657286)
			(xy 253.690102 -33.627318) (xy 253.697925 -33.567896) (xy 253.713438 -33.510003) (xy 253.736374 -33.45463)
			(xy 253.766341 -33.402724) (xy 253.802828 -33.355174) (xy 253.845208 -33.312794) (xy 253.892758 -33.276307)
			(xy 253.944664 -33.24634) (xy 254.000037 -33.223404) (xy 254.05793 -33.207891) (xy 254.117352 -33.200068)
			(xy 254.177288 -33.200068) (xy 254.23671 -33.207891) (xy 254.294603 -33.223404) (xy 254.349976 -33.24634)
			(xy 254.401882 -33.276307) (xy 254.449432 -33.312794) (xy 254.491812 -33.355174) (xy 254.528299 -33.402724)
			(xy 254.558266 -33.45463) (xy 254.581202 -33.510003) (xy 254.596715 -33.567896) (xy 254.604538 -33.627318)
			(xy 254.605028 -33.657286) (xy 254.605028 -34.520886) (xy 254.604538 -34.550854) (xy 254.596715 -34.610276)
			(xy 254.581202 -34.668169) (xy 254.558266 -34.723542) (xy 254.528299 -34.775448) (xy 254.491812 -34.822998)
			(xy 254.449432 -34.865378) (xy 254.401882 -34.901865) (xy 254.349976 -34.931832) (xy 254.294603 -34.954768)
			(xy 254.23671 -34.970281) (xy 254.177288 -34.978104) (xy 254.117352 -34.978104) (xy 254.05793 -34.970281)
			(xy 254.000037 -34.954768) (xy 253.944664 -34.931832) (xy 253.892758 -34.901865) (xy 253.845208 -34.865378)
			(xy 253.802828 -34.822998) (xy 253.766341 -34.775448) (xy 253.736374 -34.723542) (xy 253.713438 -34.668169)
			(xy 253.697925 -34.610276) (xy 253.690102 -34.550854) (xy 253.689612 -34.520886) (xy 239.868456 -34.520886)
			(xy 239.868456 -34.52241) (xy 239.867966 -34.552394) (xy 239.860138 -34.61185) (xy 239.844617 -34.669775)
			(xy 239.821668 -34.725179) (xy 239.791684 -34.777113) (xy 239.755178 -34.824689) (xy 239.712773 -34.867094)
			(xy 239.665197 -34.9036) (xy 239.613263 -34.933584) (xy 239.557859 -34.956533) (xy 239.499934 -34.972054)
			(xy 239.440478 -34.979882) (xy 239.38051 -34.979882) (xy 239.321054 -34.972054) (xy 239.263129 -34.956533)
			(xy 239.207725 -34.933584) (xy 239.155791 -34.9036) (xy 239.108215 -34.867094) (xy 239.06581 -34.824689)
			(xy 239.029304 -34.777113) (xy 238.99932 -34.725179) (xy 238.976371 -34.669775) (xy 238.96085 -34.61185)
			(xy 238.953022 -34.552394) (xy 238.952532 -34.52241) (xy 216.505003 -34.52241) (xy 216.504538 -34.550854)
			(xy 216.496715 -34.610276) (xy 216.481202 -34.668169) (xy 216.458266 -34.723542) (xy 216.428299 -34.775448)
			(xy 216.391812 -34.822998) (xy 216.349432 -34.865378) (xy 216.301882 -34.901865) (xy 216.249976 -34.931832)
			(xy 216.194603 -34.954768) (xy 216.13671 -34.970281) (xy 216.077288 -34.978104) (xy 216.017352 -34.978104)
			(xy 215.95793 -34.970281) (xy 215.900037 -34.954768) (xy 215.844664 -34.931832) (xy 215.792758 -34.901865)
			(xy 215.745208 -34.865378) (xy 215.702828 -34.822998) (xy 215.666341 -34.775448) (xy 215.636374 -34.723542)
			(xy 215.613438 -34.668169) (xy 215.597925 -34.610276) (xy 215.590102 -34.550854) (xy 215.589612 -34.520886)
			(xy 212.630004 -34.520886) (xy 212.630004 -35.264852) (xy 236.102396 -35.264852) (xy 236.106467 -35.20923)
			(xy 236.118593 -35.154793) (xy 236.138516 -35.102702) (xy 236.165812 -35.054067) (xy 236.199898 -35.009924)
			(xy 236.240047 -34.971215) (xy 236.285405 -34.938764) (xy 236.335005 -34.913263) (xy 236.387789 -34.895256)
			(xy 236.442632 -34.885126) (xy 236.498366 -34.883089) (xy 236.553803 -34.889189) (xy 236.60776 -34.903295)
			(xy 236.659089 -34.925107) (xy 236.706695 -34.954161) (xy 236.749563 -34.989836) (xy 236.78678 -35.031373)
			(xy 236.817553 -35.077886) (xy 236.841225 -35.128383) (xy 236.857293 -35.18179) (xy 236.865413 -35.236966)
			(xy 236.865922 -35.264852) (xy 236.865413 -35.292738) (xy 236.857293 -35.347914) (xy 236.841225 -35.401321)
			(xy 236.817553 -35.451818) (xy 236.78678 -35.498331) (xy 236.749563 -35.539868) (xy 236.706695 -35.575543)
			(xy 236.659089 -35.604597) (xy 236.60776 -35.626409) (xy 236.553803 -35.640515) (xy 236.498366 -35.646615)
			(xy 236.442632 -35.644578) (xy 236.387789 -35.634448) (xy 236.335005 -35.616441) (xy 236.285405 -35.59094)
			(xy 236.240047 -35.558489) (xy 236.199898 -35.51978) (xy 236.165812 -35.475637) (xy 236.138516 -35.427002)
			(xy 236.118593 -35.374911) (xy 236.106467 -35.320474) (xy 236.102396 -35.264852) (xy 212.630004 -35.264852)
			(xy 212.630004 -35.876738) (xy 224.917252 -35.876738) (xy 224.921323 -35.821116) (xy 224.933449 -35.766679)
			(xy 224.953372 -35.714588) (xy 224.980668 -35.665953) (xy 225.014754 -35.62181) (xy 225.054903 -35.583101)
			(xy 225.100261 -35.55065) (xy 225.149861 -35.525149) (xy 225.202645 -35.507142) (xy 225.257488 -35.497012)
			(xy 225.313222 -35.494975) (xy 225.368659 -35.501075) (xy 225.422616 -35.515181) (xy 225.473945 -35.536993)
			(xy 225.521551 -35.566047) (xy 225.564419 -35.601722) (xy 225.601636 -35.643259) (xy 225.632409 -35.689772)
			(xy 225.656081 -35.740269) (xy 225.672149 -35.793676) (xy 225.680269 -35.848852) (xy 225.680778 -35.876738)
			(xy 228.988872 -35.876738) (xy 228.992943 -35.821116) (xy 229.005069 -35.766679) (xy 229.024992 -35.714588)
			(xy 229.052288 -35.665953) (xy 229.086374 -35.62181) (xy 229.126523 -35.583101) (xy 229.171881 -35.55065)
			(xy 229.221481 -35.525149) (xy 229.274265 -35.507142) (xy 229.329108 -35.497012) (xy 229.384842 -35.494975)
			(xy 229.440279 -35.501075) (xy 229.494236 -35.515181) (xy 229.545565 -35.536993) (xy 229.593171 -35.566047)
			(xy 229.636039 -35.601722) (xy 229.673256 -35.643259) (xy 229.704029 -35.689772) (xy 229.727701 -35.740269)
			(xy 229.743769 -35.793676) (xy 229.751889 -35.848852) (xy 229.752398 -35.876738) (xy 229.751889 -35.904624)
			(xy 229.743769 -35.9598) (xy 229.727701 -36.013207) (xy 229.704029 -36.063704) (xy 229.673256 -36.110217)
			(xy 229.636039 -36.151754) (xy 229.593171 -36.187429) (xy 229.545565 -36.216483) (xy 229.494236 -36.238295)
			(xy 229.440279 -36.252401) (xy 229.384842 -36.258501) (xy 229.329108 -36.256464) (xy 229.274265 -36.246334)
			(xy 229.221481 -36.228327) (xy 229.171881 -36.202826) (xy 229.126523 -36.170375) (xy 229.086374 -36.131666)
			(xy 229.052288 -36.087523) (xy 229.024992 -36.038888) (xy 229.005069 -35.986797) (xy 228.992943 -35.93236)
			(xy 228.988872 -35.876738) (xy 225.680778 -35.876738) (xy 225.680269 -35.904624) (xy 225.672149 -35.9598)
			(xy 225.656081 -36.013207) (xy 225.632409 -36.063704) (xy 225.601636 -36.110217) (xy 225.564419 -36.151754)
			(xy 225.521551 -36.187429) (xy 225.473945 -36.216483) (xy 225.422616 -36.238295) (xy 225.368659 -36.252401)
			(xy 225.313222 -36.258501) (xy 225.257488 -36.256464) (xy 225.202645 -36.246334) (xy 225.149861 -36.228327)
			(xy 225.100261 -36.202826) (xy 225.054903 -36.170375) (xy 225.014754 -36.131666) (xy 224.980668 -36.087523)
			(xy 224.953372 -36.038888) (xy 224.933449 -35.986797) (xy 224.921323 -35.93236) (xy 224.917252 -35.876738)
			(xy 212.630004 -35.876738) (xy 212.630004 -36.50996) (xy 226.81387 -36.50996) (xy 226.817941 -36.454338)
			(xy 226.830067 -36.399901) (xy 226.84999 -36.34781) (xy 226.877286 -36.299175) (xy 226.911372 -36.255032)
			(xy 226.951521 -36.216323) (xy 226.996879 -36.183872) (xy 227.046479 -36.158371) (xy 227.099263 -36.140364)
			(xy 227.154106 -36.130234) (xy 227.20984 -36.128197) (xy 227.265277 -36.134297) (xy 227.319234 -36.148403)
			(xy 227.370563 -36.170215) (xy 227.418169 -36.199269) (xy 227.461037 -36.234944) (xy 227.498254 -36.276481)
			(xy 227.529027 -36.322994) (xy 227.552699 -36.373491) (xy 227.568767 -36.426898) (xy 227.572692 -36.453572)
			(xy 230.12857 -36.453572) (xy 230.132641 -36.39795) (xy 230.144767 -36.343513) (xy 230.16469 -36.291422)
			(xy 230.191986 -36.242787) (xy 230.226072 -36.198644) (xy 230.266221 -36.159935) (xy 230.311579 -36.127484)
			(xy 230.361179 -36.101983) (xy 230.413963 -36.083976) (xy 230.468806 -36.073846) (xy 230.52454 -36.071809)
			(xy 230.579977 -36.077909) (xy 230.633934 -36.092015) (xy 230.685263 -36.113827) (xy 230.732869 -36.142881)
			(xy 230.775737 -36.178556) (xy 230.812954 -36.220093) (xy 230.843727 -36.266606) (xy 230.853263 -36.286948)
			(xy 237.400336 -36.286948) (xy 237.404407 -36.231326) (xy 237.416533 -36.176889) (xy 237.436456 -36.124798)
			(xy 237.463752 -36.076163) (xy 237.497838 -36.03202) (xy 237.537987 -35.993311) (xy 237.583345 -35.96086)
			(xy 237.632945 -35.935359) (xy 237.685729 -35.917352) (xy 237.740572 -35.907222) (xy 237.796306 -35.905185)
			(xy 237.851743 -35.911285) (xy 237.9057 -35.925391) (xy 237.957029 -35.947203) (xy 238.004635 -35.976257)
			(xy 238.047503 -36.011932) (xy 238.08472 -36.053469) (xy 238.115493 -36.099982) (xy 238.139165 -36.150479)
			(xy 238.155233 -36.203886) (xy 238.163353 -36.259062) (xy 238.163862 -36.286948) (xy 238.163353 -36.314834)
			(xy 238.155233 -36.37001) (xy 238.139165 -36.423417) (xy 238.115493 -36.473914) (xy 238.087948 -36.515548)
			(xy 239.21415 -36.515548) (xy 239.218221 -36.459926) (xy 239.230347 -36.405489) (xy 239.25027 -36.353398)
			(xy 239.277566 -36.304763) (xy 239.311652 -36.26062) (xy 239.351801 -36.221911) (xy 239.397159 -36.18946)
			(xy 239.446759 -36.163959) (xy 239.499543 -36.145952) (xy 239.554386 -36.135822) (xy 239.61012 -36.133785)
			(xy 239.665557 -36.139885) (xy 239.719514 -36.153991) (xy 239.770843 -36.175803) (xy 239.818449 -36.204857)
			(xy 239.861317 -36.240532) (xy 239.898534 -36.282069) (xy 239.929307 -36.328582) (xy 239.952979 -36.379079)
			(xy 239.969047 -36.432486) (xy 239.977167 -36.487662) (xy 239.977676 -36.515548) (xy 239.977167 -36.543434)
			(xy 239.969047 -36.59861) (xy 239.96859 -36.60013) (xy 244.198655 -36.60013) (xy 244.202659 -36.512245)
			(xy 244.214639 -36.425088) (xy 244.234494 -36.339381) (xy 244.262061 -36.255836) (xy 244.297111 -36.175143)
			(xy 244.339353 -36.097971) (xy 244.388438 -36.024961) (xy 244.443959 -35.956717) (xy 244.505456 -35.893804)
			(xy 244.572418 -35.836744) (xy 244.644292 -35.78601) (xy 244.720482 -35.742022) (xy 244.800356 -35.705144)
			(xy 244.883253 -35.675683) (xy 244.968485 -35.653881) (xy 245.055347 -35.639921) (xy 245.143118 -35.633917)
			(xy 245.231072 -35.63592) (xy 245.318479 -35.645912) (xy 245.404615 -35.663812) (xy 245.488767 -35.68947)
			(xy 245.570237 -35.722674) (xy 245.64835 -35.763148) (xy 245.722458 -35.810559) (xy 245.791949 -35.864512)
			(xy 245.80504 -35.876738) (xy 250.9172 -35.876738) (xy 250.921271 -35.821116) (xy 250.933397 -35.766679)
			(xy 250.95332 -35.714588) (xy 250.980616 -35.665953) (xy 251.014702 -35.62181) (xy 251.054851 -35.583101)
			(xy 251.100209 -35.55065) (xy 251.149809 -35.525149) (xy 251.202593 -35.507142) (xy 251.257436 -35.497012)
			(xy 251.31317 -35.494975) (xy 251.368607 -35.501075) (xy 251.422564 -35.515181) (xy 251.473893 -35.536993)
			(xy 251.521499 -35.566047) (xy 251.564367 -35.601722) (xy 251.601584 -35.643259) (xy 251.632357 -35.689772)
			(xy 251.656029 -35.740269) (xy 251.672097 -35.793676) (xy 251.680217 -35.848852) (xy 251.680726 -35.876738)
			(xy 254.98882 -35.876738) (xy 254.992891 -35.821116) (xy 255.005017 -35.766679) (xy 255.02494 -35.714588)
			(xy 255.052236 -35.665953) (xy 255.086322 -35.62181) (xy 255.126471 -35.583101) (xy 255.171829 -35.55065)
			(xy 255.221429 -35.525149) (xy 255.274213 -35.507142) (xy 255.329056 -35.497012) (xy 255.38479 -35.494975)
			(xy 255.440227 -35.501075) (xy 255.494184 -35.515181) (xy 255.545513 -35.536993) (xy 255.593119 -35.566047)
			(xy 255.635987 -35.601722) (xy 255.673204 -35.643259) (xy 255.703977 -35.689772) (xy 255.727649 -35.740269)
			(xy 255.743717 -35.793676) (xy 255.751837 -35.848852) (xy 255.752346 -35.876738) (xy 255.751837 -35.904624)
			(xy 255.743717 -35.9598) (xy 255.727649 -36.013207) (xy 255.703977 -36.063704) (xy 255.673204 -36.110217)
			(xy 255.635987 -36.151754) (xy 255.593119 -36.187429) (xy 255.545513 -36.216483) (xy 255.494184 -36.238295)
			(xy 255.440227 -36.252401) (xy 255.38479 -36.258501) (xy 255.329056 -36.256464) (xy 255.274213 -36.246334)
			(xy 255.221429 -36.228327) (xy 255.171829 -36.202826) (xy 255.126471 -36.170375) (xy 255.086322 -36.131666)
			(xy 255.052236 -36.087523) (xy 255.02494 -36.038888) (xy 255.005017 -35.986797) (xy 254.992891 -35.93236)
			(xy 254.98882 -35.876738) (xy 251.680726 -35.876738) (xy 251.680217 -35.904624) (xy 251.672097 -35.9598)
			(xy 251.656029 -36.013207) (xy 251.632357 -36.063704) (xy 251.601584 -36.110217) (xy 251.564367 -36.151754)
			(xy 251.521499 -36.187429) (xy 251.473893 -36.216483) (xy 251.422564 -36.238295) (xy 251.368607 -36.252401)
			(xy 251.31317 -36.258501) (xy 251.257436 -36.256464) (xy 251.202593 -36.246334) (xy 251.149809 -36.228327)
			(xy 251.100209 -36.202826) (xy 251.054851 -36.170375) (xy 251.014702 -36.131666) (xy 250.980616 -36.087523)
			(xy 250.95332 -36.038888) (xy 250.933397 -35.986797) (xy 250.921271 -35.93236) (xy 250.9172 -35.876738)
			(xy 245.80504 -35.876738) (xy 245.856245 -35.92456) (xy 245.914814 -35.990207) (xy 245.967171 -36.060907)
			(xy 246.012883 -36.136076) (xy 246.051569 -36.21509) (xy 246.08291 -36.297295) (xy 246.106645 -36.382009)
			(xy 246.122579 -36.46853) (xy 246.126362 -36.50996) (xy 252.813818 -36.50996) (xy 252.817889 -36.454338)
			(xy 252.830015 -36.399901) (xy 252.849938 -36.34781) (xy 252.877234 -36.299175) (xy 252.91132 -36.255032)
			(xy 252.951469 -36.216323) (xy 252.996827 -36.183872) (xy 253.046427 -36.158371) (xy 253.099211 -36.140364)
			(xy 253.154054 -36.130234) (xy 253.209788 -36.128197) (xy 253.265225 -36.134297) (xy 253.319182 -36.148403)
			(xy 253.370511 -36.170215) (xy 253.418117 -36.199269) (xy 253.460985 -36.234944) (xy 253.498202 -36.276481)
			(xy 253.528975 -36.322994) (xy 253.552647 -36.373491) (xy 253.568715 -36.426898) (xy 253.57264 -36.453572)
			(xy 256.128518 -36.453572) (xy 256.132589 -36.39795) (xy 256.144715 -36.343513) (xy 256.164638 -36.291422)
			(xy 256.191934 -36.242787) (xy 256.22602 -36.198644) (xy 256.266169 -36.159935) (xy 256.311527 -36.127484)
			(xy 256.361127 -36.101983) (xy 256.413911 -36.083976) (xy 256.468754 -36.073846) (xy 256.524488 -36.071809)
			(xy 256.579925 -36.077909) (xy 256.633882 -36.092015) (xy 256.685211 -36.113827) (xy 256.732817 -36.142881)
			(xy 256.775685 -36.178556) (xy 256.812902 -36.220093) (xy 256.843675 -36.266606) (xy 256.867347 -36.317103)
			(xy 256.883415 -36.37051) (xy 256.891535 -36.425686) (xy 256.892044 -36.453572) (xy 256.891535 -36.481458)
			(xy 256.883415 -36.536634) (xy 256.867347 -36.590041) (xy 256.843675 -36.640538) (xy 256.812902 -36.687051)
			(xy 256.775685 -36.728588) (xy 256.732817 -36.764263) (xy 256.685211 -36.793317) (xy 256.633882 -36.815129)
			(xy 256.579925 -36.829235) (xy 256.524488 -36.835335) (xy 256.468754 -36.833298) (xy 256.413911 -36.823168)
			(xy 256.361127 -36.805161) (xy 256.311527 -36.77966) (xy 256.266169 -36.747209) (xy 256.22602 -36.7085)
			(xy 256.191934 -36.664357) (xy 256.164638 -36.615722) (xy 256.144715 -36.563631) (xy 256.132589 -36.509194)
			(xy 256.128518 -36.453572) (xy 253.57264 -36.453572) (xy 253.576835 -36.482074) (xy 253.577344 -36.50996)
			(xy 253.576835 -36.537846) (xy 253.568715 -36.593022) (xy 253.552647 -36.646429) (xy 253.528975 -36.696926)
			(xy 253.498202 -36.743439) (xy 253.460985 -36.784976) (xy 253.418117 -36.820651) (xy 253.370511 -36.849705)
			(xy 253.319182 -36.871517) (xy 253.265225 -36.885623) (xy 253.209788 -36.891723) (xy 253.154054 -36.889686)
			(xy 253.099211 -36.879556) (xy 253.046427 -36.861549) (xy 252.996827 -36.836048) (xy 252.951469 -36.803597)
			(xy 252.91132 -36.764888) (xy 252.877234 -36.720745) (xy 252.849938 -36.67211) (xy 252.830015 -36.620019)
			(xy 252.817889 -36.565582) (xy 252.813818 -36.50996) (xy 246.126362 -36.50996) (xy 246.130579 -36.556142)
			(xy 246.13108 -36.60013) (xy 246.130579 -36.644118) (xy 246.122579 -36.73173) (xy 246.106645 -36.818251)
			(xy 246.08291 -36.902965) (xy 246.051569 -36.98517) (xy 246.012883 -37.064184) (xy 245.967171 -37.139353)
			(xy 245.914814 -37.210053) (xy 245.856245 -37.2757) (xy 245.791949 -37.335748) (xy 245.722458 -37.389701)
			(xy 245.64835 -37.437112) (xy 245.574919 -37.47516) (xy 249.959112 -37.47516) (xy 249.963183 -37.419538)
			(xy 249.975309 -37.365101) (xy 249.995232 -37.31301) (xy 250.022528 -37.264375) (xy 250.056614 -37.220232)
			(xy 250.096763 -37.181523) (xy 250.142121 -37.149072) (xy 250.191721 -37.123571) (xy 250.244505 -37.105564)
			(xy 250.299348 -37.095434) (xy 250.355082 -37.093397) (xy 250.410519 -37.099497) (xy 250.464476 -37.113603)
			(xy 250.515805 -37.135415) (xy 250.563411 -37.164469) (xy 250.606279 -37.200144) (xy 250.643496 -37.241681)
			(xy 250.674269 -37.288194) (xy 250.697941 -37.338691) (xy 250.714009 -37.392098) (xy 250.722129 -37.447274)
			(xy 250.722638 -37.47516) (xy 250.722129 -37.503046) (xy 250.714009 -37.558222) (xy 250.697941 -37.611629)
			(xy 250.674269 -37.662126) (xy 250.674116 -37.662358) (xy 252.148338 -37.662358) (xy 252.152409 -37.606736)
			(xy 252.164535 -37.552299) (xy 252.184458 -37.500208) (xy 252.211754 -37.451573) (xy 252.24584 -37.40743)
			(xy 252.285989 -37.368721) (xy 252.331347 -37.33627) (xy 252.380947 -37.310769) (xy 252.433731 -37.292762)
			(xy 252.488574 -37.282632) (xy 252.544308 -37.280595) (xy 252.599745 -37.286695) (xy 252.653702 -37.300801)
			(xy 252.705031 -37.322613) (xy 252.752637 -37.351667) (xy 252.795505 -37.387342) (xy 252.832722 -37.428879)
			(xy 252.863495 -37.475392) (xy 252.887167 -37.525889) (xy 252.903235 -37.579296) (xy 252.911355 -37.634472)
			(xy 252.911864 -37.662358) (xy 252.911355 -37.690244) (xy 252.903235 -37.74542) (xy 252.887167 -37.798827)
			(xy 252.863495 -37.849324) (xy 252.832722 -37.895837) (xy 252.795505 -37.937374) (xy 252.752637 -37.973049)
			(xy 252.705031 -38.002103) (xy 252.653702 -38.023915) (xy 252.599745 -38.038021) (xy 252.544308 -38.044121)
			(xy 252.488574 -38.042084) (xy 252.433731 -38.031954) (xy 252.380947 -38.013947) (xy 252.331347 -37.988446)
			(xy 252.285989 -37.955995) (xy 252.24584 -37.917286) (xy 252.211754 -37.873143) (xy 252.184458 -37.824508)
			(xy 252.164535 -37.772417) (xy 252.152409 -37.71798) (xy 252.148338 -37.662358) (xy 250.674116 -37.662358)
			(xy 250.643496 -37.708639) (xy 250.606279 -37.750176) (xy 250.563411 -37.785851) (xy 250.515805 -37.814905)
			(xy 250.464476 -37.836717) (xy 250.410519 -37.850823) (xy 250.355082 -37.856923) (xy 250.299348 -37.854886)
			(xy 250.244505 -37.844756) (xy 250.191721 -37.826749) (xy 250.142121 -37.801248) (xy 250.096763 -37.768797)
			(xy 250.056614 -37.730088) (xy 250.022528 -37.685945) (xy 249.995232 -37.63731) (xy 249.975309 -37.585219)
			(xy 249.963183 -37.530782) (xy 249.959112 -37.47516) (xy 245.574919 -37.47516) (xy 245.570237 -37.477586)
			(xy 245.488767 -37.51079) (xy 245.404615 -37.536448) (xy 245.318479 -37.554348) (xy 245.231072 -37.56434)
			(xy 245.143118 -37.566343) (xy 245.055347 -37.560339) (xy 244.968485 -37.546379) (xy 244.883253 -37.524577)
			(xy 244.800356 -37.495116) (xy 244.720482 -37.458238) (xy 244.644292 -37.41425) (xy 244.572418 -37.363516)
			(xy 244.505456 -37.306456) (xy 244.443959 -37.243543) (xy 244.388438 -37.175299) (xy 244.339353 -37.102289)
			(xy 244.297111 -37.025117) (xy 244.262061 -36.944424) (xy 244.234494 -36.860879) (xy 244.214639 -36.775172)
			(xy 244.202659 -36.688015) (xy 244.198655 -36.60013) (xy 239.96859 -36.60013) (xy 239.952979 -36.652017)
			(xy 239.929307 -36.702514) (xy 239.898534 -36.749027) (xy 239.861317 -36.790564) (xy 239.818449 -36.826239)
			(xy 239.770843 -36.855293) (xy 239.719514 -36.877105) (xy 239.665557 -36.891211) (xy 239.61012 -36.897311)
			(xy 239.554386 -36.895274) (xy 239.499543 -36.885144) (xy 239.446759 -36.867137) (xy 239.397159 -36.841636)
			(xy 239.351801 -36.809185) (xy 239.311652 -36.770476) (xy 239.277566 -36.726333) (xy 239.25027 -36.677698)
			(xy 239.230347 -36.625607) (xy 239.218221 -36.57117) (xy 239.21415 -36.515548) (xy 238.087948 -36.515548)
			(xy 238.08472 -36.520427) (xy 238.047503 -36.561964) (xy 238.004635 -36.597639) (xy 237.957029 -36.626693)
			(xy 237.9057 -36.648505) (xy 237.851743 -36.662611) (xy 237.796306 -36.668711) (xy 237.740572 -36.666674)
			(xy 237.685729 -36.656544) (xy 237.632945 -36.638537) (xy 237.583345 -36.613036) (xy 237.537987 -36.580585)
			(xy 237.497838 -36.541876) (xy 237.463752 -36.497733) (xy 237.436456 -36.449098) (xy 237.416533 -36.397007)
			(xy 237.404407 -36.34257) (xy 237.400336 -36.286948) (xy 230.853263 -36.286948) (xy 230.867399 -36.317103)
			(xy 230.883467 -36.37051) (xy 230.891587 -36.425686) (xy 230.892096 -36.453572) (xy 230.891587 -36.481458)
			(xy 230.883467 -36.536634) (xy 230.867399 -36.590041) (xy 230.843727 -36.640538) (xy 230.812954 -36.687051)
			(xy 230.775737 -36.728588) (xy 230.732869 -36.764263) (xy 230.685263 -36.793317) (xy 230.633934 -36.815129)
			(xy 230.579977 -36.829235) (xy 230.52454 -36.835335) (xy 230.468806 -36.833298) (xy 230.413963 -36.823168)
			(xy 230.361179 -36.805161) (xy 230.311579 -36.77966) (xy 230.266221 -36.747209) (xy 230.226072 -36.7085)
			(xy 230.191986 -36.664357) (xy 230.16469 -36.615722) (xy 230.144767 -36.563631) (xy 230.132641 -36.509194)
			(xy 230.12857 -36.453572) (xy 227.572692 -36.453572) (xy 227.576887 -36.482074) (xy 227.577396 -36.50996)
			(xy 227.576887 -36.537846) (xy 227.568767 -36.593022) (xy 227.552699 -36.646429) (xy 227.529027 -36.696926)
			(xy 227.498254 -36.743439) (xy 227.461037 -36.784976) (xy 227.418169 -36.820651) (xy 227.370563 -36.849705)
			(xy 227.319234 -36.871517) (xy 227.265277 -36.885623) (xy 227.20984 -36.891723) (xy 227.154106 -36.889686)
			(xy 227.099263 -36.879556) (xy 227.046479 -36.861549) (xy 226.996879 -36.836048) (xy 226.951521 -36.803597)
			(xy 226.911372 -36.764888) (xy 226.877286 -36.720745) (xy 226.84999 -36.67211) (xy 226.830067 -36.620019)
			(xy 226.817941 -36.565582) (xy 226.81387 -36.50996) (xy 212.630004 -36.50996) (xy 212.630004 -36.931346)
			(xy 212.629538 -36.9645) (xy 212.622113 -37.030391) (xy 212.607363 -37.095038) (xy 212.585471 -37.157628)
			(xy 212.556713 -37.217375) (xy 212.521451 -37.27353) (xy 212.480127 -37.325386) (xy 212.45703 -37.349176)
			(xy 212.331046 -37.47516) (xy 223.959164 -37.47516) (xy 223.963235 -37.419538) (xy 223.975361 -37.365101)
			(xy 223.995284 -37.31301) (xy 224.02258 -37.264375) (xy 224.056666 -37.220232) (xy 224.096815 -37.181523)
			(xy 224.142173 -37.149072) (xy 224.191773 -37.123571) (xy 224.244557 -37.105564) (xy 224.2994 -37.095434)
			(xy 224.355134 -37.093397) (xy 224.410571 -37.099497) (xy 224.464528 -37.113603) (xy 224.515857 -37.135415)
			(xy 224.563463 -37.164469) (xy 224.606331 -37.200144) (xy 224.643548 -37.241681) (xy 224.674321 -37.288194)
			(xy 224.697993 -37.338691) (xy 224.714061 -37.392098) (xy 224.722181 -37.447274) (xy 224.72269 -37.47516)
			(xy 224.722181 -37.503046) (xy 224.714061 -37.558222) (xy 224.697993 -37.611629) (xy 224.674321 -37.662126)
			(xy 224.674168 -37.662358) (xy 226.14839 -37.662358) (xy 226.152461 -37.606736) (xy 226.164587 -37.552299)
			(xy 226.18451 -37.500208) (xy 226.211806 -37.451573) (xy 226.245892 -37.40743) (xy 226.286041 -37.368721)
			(xy 226.331399 -37.33627) (xy 226.380999 -37.310769) (xy 226.433783 -37.292762) (xy 226.488626 -37.282632)
			(xy 226.54436 -37.280595) (xy 226.599797 -37.286695) (xy 226.653754 -37.300801) (xy 226.705083 -37.322613)
			(xy 226.752689 -37.351667) (xy 226.795557 -37.387342) (xy 226.832774 -37.428879) (xy 226.863547 -37.475392)
			(xy 226.887219 -37.525889) (xy 226.903287 -37.579296) (xy 226.911407 -37.634472) (xy 226.911916 -37.662358)
			(xy 226.911407 -37.690244) (xy 226.903287 -37.74542) (xy 226.894653 -37.774118) (xy 237.66475 -37.774118)
			(xy 237.668821 -37.718496) (xy 237.680947 -37.664059) (xy 237.70087 -37.611968) (xy 237.728166 -37.563333)
			(xy 237.762252 -37.51919) (xy 237.802401 -37.480481) (xy 237.847759 -37.44803) (xy 237.897359 -37.422529)
			(xy 237.950143 -37.404522) (xy 238.004986 -37.394392) (xy 238.06072 -37.392355) (xy 238.116157 -37.398455)
			(xy 238.170114 -37.412561) (xy 238.221443 -37.434373) (xy 238.269049 -37.463427) (xy 238.311917 -37.499102)
			(xy 238.349134 -37.540639) (xy 238.379907 -37.587152) (xy 238.403579 -37.637649) (xy 238.419647 -37.691056)
			(xy 238.427767 -37.746232) (xy 238.428276 -37.774118) (xy 238.427767 -37.802004) (xy 238.419647 -37.85718)
			(xy 238.403579 -37.910587) (xy 238.379907 -37.961084) (xy 238.349134 -38.007597) (xy 238.311917 -38.049134)
			(xy 238.269049 -38.084809) (xy 238.221443 -38.113863) (xy 238.170114 -38.135675) (xy 238.116157 -38.149781)
			(xy 238.06072 -38.155881) (xy 238.004986 -38.153844) (xy 237.950143 -38.143714) (xy 237.897359 -38.125707)
			(xy 237.847759 -38.100206) (xy 237.802401 -38.067755) (xy 237.762252 -38.029046) (xy 237.728166 -37.984903)
			(xy 237.70087 -37.936268) (xy 237.680947 -37.884177) (xy 237.668821 -37.82974) (xy 237.66475 -37.774118)
			(xy 226.894653 -37.774118) (xy 226.887219 -37.798827) (xy 226.863547 -37.849324) (xy 226.832774 -37.895837)
			(xy 226.795557 -37.937374) (xy 226.752689 -37.973049) (xy 226.705083 -38.002103) (xy 226.653754 -38.023915)
			(xy 226.599797 -38.038021) (xy 226.54436 -38.044121) (xy 226.488626 -38.042084) (xy 226.433783 -38.031954)
			(xy 226.380999 -38.013947) (xy 226.331399 -37.988446) (xy 226.286041 -37.955995) (xy 226.245892 -37.917286)
			(xy 226.211806 -37.873143) (xy 226.18451 -37.824508) (xy 226.164587 -37.772417) (xy 226.152461 -37.71798)
			(xy 226.14839 -37.662358) (xy 224.674168 -37.662358) (xy 224.643548 -37.708639) (xy 224.606331 -37.750176)
			(xy 224.563463 -37.785851) (xy 224.515857 -37.814905) (xy 224.464528 -37.836717) (xy 224.410571 -37.850823)
			(xy 224.355134 -37.856923) (xy 224.2994 -37.854886) (xy 224.244557 -37.844756) (xy 224.191773 -37.826749)
			(xy 224.142173 -37.801248) (xy 224.096815 -37.768797) (xy 224.056666 -37.730088) (xy 224.02258 -37.685945)
			(xy 223.995284 -37.63731) (xy 223.975361 -37.585219) (xy 223.963235 -37.530782) (xy 223.959164 -37.47516)
			(xy 212.331046 -37.47516) (xy 211.076258 -38.729948) (xy 229.90102 -38.729948) (xy 229.90102 -38.675452)
			(xy 229.908775 -38.621512) (xy 229.924128 -38.569224) (xy 229.946766 -38.519653) (xy 229.976228 -38.473808)
			(xy 230.011914 -38.432623) (xy 230.053098 -38.396935) (xy 230.098942 -38.367472) (xy 230.148512 -38.344832)
			(xy 230.2008 -38.329478) (xy 230.25474 -38.321721) (xy 230.281988 -38.321234) (xy 230.310293 -38.321717)
			(xy 230.366282 -38.330068) (xy 230.420422 -38.346604) (xy 230.471523 -38.37096) (xy 230.518463 -38.402602)
			(xy 230.56021 -38.440834) (xy 230.595847 -38.484818) (xy 230.610664 -38.50894) (xy 230.618212 -38.521009)
			(xy 230.638841 -38.540613) (xy 230.664084 -38.553754) (xy 230.691975 -38.55941) (xy 230.720342 -38.557139)
			(xy 230.746979 -38.547119) (xy 230.769809 -38.53013) (xy 230.778812 -38.5191) (xy 230.796997 -38.496222)
			(xy 230.83916 -38.455758) (xy 230.886996 -38.422191) (xy 230.939388 -38.396304) (xy 230.995113 -38.378703)
			(xy 231.052869 -38.369797) (xy 231.082088 -38.36924) (xy 231.109345 -38.369606) (xy 231.163304 -38.377363)
			(xy 231.21561 -38.39272) (xy 231.265198 -38.415364) (xy 231.311058 -38.444836) (xy 231.352258 -38.480534)
			(xy 231.387957 -38.521732) (xy 231.41743 -38.567592) (xy 231.440076 -38.617179) (xy 231.455435 -38.669484)
			(xy 231.463193 -38.723443) (xy 231.463193 -38.729951) (xy 255.900897 -38.729951) (xy 255.900897 -38.675449)
			(xy 255.908654 -38.6215) (xy 255.924011 -38.569205) (xy 255.946653 -38.519628) (xy 255.976121 -38.473779)
			(xy 256.011815 -38.432589) (xy 256.053007 -38.3969) (xy 256.09886 -38.367436) (xy 256.148439 -38.344798)
			(xy 256.200736 -38.329447) (xy 256.254684 -38.321695) (xy 256.281936 -38.321234) (xy 256.310239 -38.321758)
			(xy 256.366227 -38.330102) (xy 256.420366 -38.34663) (xy 256.471467 -38.370979) (xy 256.518407 -38.402615)
			(xy 256.560156 -38.440842) (xy 256.595795 -38.48482) (xy 256.610612 -38.50894) (xy 256.618228 -38.520962)
			(xy 256.638843 -38.540563) (xy 256.664071 -38.553706) (xy 256.691948 -38.559367) (xy 256.720304 -38.557105)
			(xy 256.746932 -38.547097) (xy 256.769758 -38.530122) (xy 256.77876 -38.5191) (xy 256.796974 -38.496247)
			(xy 256.839131 -38.455782) (xy 256.886961 -38.422212) (xy 256.939348 -38.396321) (xy 256.995067 -38.378713)
			(xy 257.052819 -38.369801) (xy 257.082036 -38.36924) (xy 257.109289 -38.369632) (xy 257.16324 -38.377394)
			(xy 257.215537 -38.392754) (xy 257.265116 -38.4154) (xy 257.310967 -38.444871) (xy 257.352158 -38.480567)
			(xy 257.38785 -38.521762) (xy 257.417317 -38.567616) (xy 257.439958 -38.617197) (xy 257.455314 -38.669496)
			(xy 257.46307 -38.723447) (xy 257.46307 -38.777953) (xy 257.455314 -38.831904) (xy 257.439958 -38.884203)
			(xy 257.417317 -38.933784) (xy 257.38785 -38.979638) (xy 257.352158 -39.020833) (xy 257.310967 -39.056529)
			(xy 257.265116 -39.086) (xy 257.215537 -39.108646) (xy 257.16324 -39.124006) (xy 257.109289 -39.131768)
			(xy 257.082036 -39.132256) (xy 257.053732 -39.131759) (xy 256.997743 -39.123411) (xy 256.943603 -39.106879)
			(xy 256.892501 -39.082525) (xy 256.845561 -39.050885) (xy 256.803814 -39.012654) (xy 256.768177 -38.968672)
			(xy 256.75336 -38.94455) (xy 256.745781 -38.932503) (xy 256.725157 -38.912902) (xy 256.699922 -38.899761)
			(xy 256.672038 -38.894104) (xy 256.643676 -38.89637) (xy 256.617044 -38.906383) (xy 256.594215 -38.923365)
			(xy 256.585212 -38.93439) (xy 256.567011 -38.957254) (xy 256.524852 -38.997719) (xy 256.477019 -39.031288)
			(xy 256.42463 -39.057178) (xy 256.368908 -39.074782) (xy 256.311154 -39.083691) (xy 256.281936 -39.08425)
			(xy 256.254684 -39.083705) (xy 256.200736 -39.075953) (xy 256.148439 -39.060602) (xy 256.09886 -39.037964)
			(xy 256.053007 -39.0085) (xy 256.011815 -38.972811) (xy 255.976121 -38.931621) (xy 255.946653 -38.885772)
			(xy 255.924011 -38.836195) (xy 255.908654 -38.7839) (xy 255.900897 -38.729951) (xy 231.463193 -38.729951)
			(xy 231.463193 -38.777957) (xy 231.455435 -38.831916) (xy 231.440076 -38.884221) (xy 231.41743 -38.933808)
			(xy 231.387957 -38.979668) (xy 231.352258 -39.020866) (xy 231.311058 -39.056564) (xy 231.265198 -39.086036)
			(xy 231.21561 -39.10868) (xy 231.163304 -39.124037) (xy 231.109345 -39.131794) (xy 231.082088 -39.132256)
			(xy 231.053785 -39.131718) (xy 230.997798 -39.123377) (xy 230.943659 -39.106852) (xy 230.892558 -39.082505)
			(xy 230.845617 -39.050872) (xy 230.803869 -39.012646) (xy 230.76823 -38.968669) (xy 230.753412 -38.94455)
			(xy 230.745765 -38.93255) (xy 230.725156 -38.912952) (xy 230.699935 -38.89981) (xy 230.672064 -38.894147)
			(xy 230.643714 -38.896404) (xy 230.617091 -38.906405) (xy 230.594266 -38.923372) (xy 230.585264 -38.93439)
			(xy 230.567091 -38.957277) (xy 230.524925 -38.997741) (xy 230.477087 -39.031307) (xy 230.424693 -39.057193)
			(xy 230.368966 -39.074792) (xy 230.311208 -39.083695) (xy 230.281988 -39.08425) (xy 230.25474 -39.083679)
			(xy 230.2008 -39.075922) (xy 230.148512 -39.060568) (xy 230.098942 -39.037928) (xy 230.053098 -39.008465)
			(xy 230.011914 -38.972777) (xy 229.976228 -38.931592) (xy 229.946766 -38.885747) (xy 229.924128 -38.836176)
			(xy 229.908775 -38.783888) (xy 229.90102 -38.729948) (xy 211.076258 -38.729948) (xy 209.624676 -40.18153)
			(xy 228.109524 -40.18153) (xy 228.113595 -40.125908) (xy 228.125721 -40.071471) (xy 228.145644 -40.01938)
			(xy 228.17294 -39.970745) (xy 228.207026 -39.926602) (xy 228.247175 -39.887893) (xy 228.292533 -39.855442)
			(xy 228.342133 -39.829941) (xy 228.394917 -39.811934) (xy 228.44976 -39.801804) (xy 228.505494 -39.799767)
			(xy 228.560931 -39.805867) (xy 228.614888 -39.819973) (xy 228.666217 -39.841785) (xy 228.713823 -39.870839)
			(xy 228.756691 -39.906514) (xy 228.793908 -39.948051) (xy 228.809739 -39.97198) (xy 232.0958 -39.97198)
			(xy 232.099871 -39.916358) (xy 232.111997 -39.861921) (xy 232.13192 -39.80983) (xy 232.159216 -39.761195)
			(xy 232.193302 -39.717052) (xy 232.233451 -39.678343) (xy 232.278809 -39.645892) (xy 232.328409 -39.620391)
			(xy 232.381193 -39.602384) (xy 232.436036 -39.592254) (xy 232.49177 -39.590217) (xy 232.547207 -39.596317)
			(xy 232.601164 -39.610423) (xy 232.652493 -39.632235) (xy 232.700099 -39.661289) (xy 232.742967 -39.696964)
			(xy 232.780184 -39.738501) (xy 232.810957 -39.785014) (xy 232.834629 -39.835511) (xy 232.850697 -39.888918)
			(xy 232.858817 -39.944094) (xy 232.859326 -39.97198) (xy 258.095748 -39.97198) (xy 258.099819 -39.916358)
			(xy 258.111945 -39.861921) (xy 258.131868 -39.80983) (xy 258.159164 -39.761195) (xy 258.19325 -39.717052)
			(xy 258.233399 -39.678343) (xy 258.278757 -39.645892) (xy 258.328357 -39.620391) (xy 258.381141 -39.602384)
			(xy 258.435984 -39.592254) (xy 258.491718 -39.590217) (xy 258.547155 -39.596317) (xy 258.601112 -39.610423)
			(xy 258.652441 -39.632235) (xy 258.700047 -39.661289) (xy 258.742915 -39.696964) (xy 258.780132 -39.738501)
			(xy 258.810905 -39.785014) (xy 258.834577 -39.835511) (xy 258.850645 -39.888918) (xy 258.858765 -39.944094)
			(xy 258.859274 -39.97198) (xy 258.858765 -39.999866) (xy 258.850645 -40.055042) (xy 258.834577 -40.108449)
			(xy 258.810905 -40.158946) (xy 258.780132 -40.205459) (xy 258.742915 -40.246996) (xy 258.700047 -40.282671)
			(xy 258.652441 -40.311725) (xy 258.601112 -40.333537) (xy 258.547155 -40.347643) (xy 258.491718 -40.353743)
			(xy 258.435984 -40.351706) (xy 258.381141 -40.341576) (xy 258.328357 -40.323569) (xy 258.278757 -40.298068)
			(xy 258.233399 -40.265617) (xy 258.19325 -40.226908) (xy 258.159164 -40.182765) (xy 258.131868 -40.13413)
			(xy 258.111945 -40.082039) (xy 258.099819 -40.027602) (xy 258.095748 -39.97198) (xy 232.859326 -39.97198)
			(xy 232.858817 -39.999866) (xy 232.850697 -40.055042) (xy 232.834629 -40.108449) (xy 232.810957 -40.158946)
			(xy 232.780184 -40.205459) (xy 232.742967 -40.246996) (xy 232.700099 -40.282671) (xy 232.652493 -40.311725)
			(xy 232.601164 -40.333537) (xy 232.547207 -40.347643) (xy 232.49177 -40.353743) (xy 232.436036 -40.351706)
			(xy 232.381193 -40.341576) (xy 232.328409 -40.323569) (xy 232.278809 -40.298068) (xy 232.233451 -40.265617)
			(xy 232.193302 -40.226908) (xy 232.159216 -40.182765) (xy 232.13192 -40.13413) (xy 232.111997 -40.082039)
			(xy 232.099871 -40.027602) (xy 232.0958 -39.97198) (xy 228.809739 -39.97198) (xy 228.824681 -39.994564)
			(xy 228.848353 -40.045061) (xy 228.864421 -40.098468) (xy 228.872541 -40.153644) (xy 228.87305 -40.18153)
			(xy 228.872541 -40.209416) (xy 228.864421 -40.264592) (xy 228.848353 -40.317999) (xy 228.824681 -40.368496)
			(xy 228.793908 -40.415009) (xy 228.756691 -40.456546) (xy 228.713823 -40.492221) (xy 228.666217 -40.521275)
			(xy 228.614888 -40.543087) (xy 228.560931 -40.557193) (xy 228.505494 -40.563293) (xy 228.44976 -40.561256)
			(xy 228.394917 -40.551126) (xy 228.342133 -40.533119) (xy 228.292533 -40.507618) (xy 228.247175 -40.475167)
			(xy 228.207026 -40.436458) (xy 228.17294 -40.392315) (xy 228.145644 -40.34368) (xy 228.125721 -40.291589)
			(xy 228.113595 -40.237152) (xy 228.109524 -40.18153) (xy 209.624676 -40.18153) (xy 208.537455 -41.268751)
			(xy 209.94395 -41.268751) (xy 209.94395 -41.214249) (xy 209.951706 -41.160301) (xy 209.96706 -41.108006)
			(xy 209.989699 -41.058428) (xy 210.019163 -41.012577) (xy 210.054852 -40.971385) (xy 210.09604 -40.935691)
			(xy 210.141888 -40.906221) (xy 210.191463 -40.883576) (xy 210.243756 -40.868215) (xy 210.297703 -40.860453)
			(xy 210.324954 -40.859964) (xy 210.353694 -40.860465) (xy 210.410522 -40.869094) (xy 210.465412 -40.88615)
			(xy 210.517124 -40.911247) (xy 210.564485 -40.943816) (xy 210.585812 -40.963088) (xy 210.59267 -40.969692)
			(xy 210.610704 -40.976804) (xy 210.699604 -40.976804) (xy 210.717638 -40.969692) (xy 210.724496 -40.963088)
			(xy 210.745808 -40.9438) (xy 210.793173 -40.911234) (xy 210.844889 -40.886144) (xy 210.899783 -40.869098)
			(xy 210.956614 -40.860481) (xy 210.985354 -40.859964) (xy 211.012607 -40.86048) (xy 211.066559 -40.868231)
			(xy 211.118858 -40.883582) (xy 211.168441 -40.90622) (xy 211.214296 -40.935685) (xy 211.255491 -40.971376)
			(xy 211.291187 -41.012567) (xy 211.320658 -41.058419) (xy 211.343302 -41.107998) (xy 211.358659 -41.160296)
			(xy 211.366417 -41.214247) (xy 211.366417 -41.268753) (xy 211.358659 -41.322704) (xy 211.343302 -41.375002)
			(xy 211.320658 -41.424581) (xy 211.291187 -41.470433) (xy 211.255491 -41.511624) (xy 211.214296 -41.547315)
			(xy 211.168441 -41.57678) (xy 211.118858 -41.599418) (xy 211.066559 -41.614769) (xy 211.012607 -41.62252)
			(xy 210.985354 -41.62298) (xy 210.956615 -41.622463) (xy 210.899788 -41.613835) (xy 210.844898 -41.596783)
			(xy 210.793187 -41.57169) (xy 210.745824 -41.539126) (xy 210.724496 -41.519856) (xy 210.717638 -41.513252)
			(xy 210.699604 -41.50614) (xy 210.610704 -41.50614) (xy 210.59267 -41.513252) (xy 210.585812 -41.519856)
			(xy 210.564503 -41.539148) (xy 210.517136 -41.571711) (xy 210.46542 -41.5968) (xy 210.410525 -41.613845)
			(xy 210.353694 -41.622462) (xy 210.324954 -41.62298) (xy 210.297703 -41.622547) (xy 210.243756 -41.614785)
			(xy 210.191463 -41.599424) (xy 210.141888 -41.576779) (xy 210.09604 -41.547309) (xy 210.054852 -41.511615)
			(xy 210.019163 -41.470423) (xy 209.989699 -41.424572) (xy 209.96706 -41.374994) (xy 209.951706 -41.322699)
			(xy 209.94395 -41.268751) (xy 208.537455 -41.268751) (xy 206.65567 -43.150536) (xy 206.649138 -43.157605)
			(xy 206.64144 -43.17523) (xy 206.640684 -43.184826) (xy 206.636392 -43.305222) (xy 212.407246 -43.305222)
			(xy 212.407714 -43.277852) (xy 212.415529 -43.223672) (xy 212.431018 -43.171169) (xy 212.453859 -43.121422)
			(xy 212.483584 -43.075455) (xy 212.501226 -43.054524) (xy 212.50148 -43.05427) (xy 212.507053 -43.047174)
			(xy 212.513306 -43.030264) (xy 212.513672 -43.02125) (xy 212.513672 -42.954194) (xy 212.513324 -42.945176)
			(xy 212.507071 -42.928259) (xy 212.50148 -42.921174) (xy 212.501226 -42.921174) (xy 212.501226 -42.92092)
			(xy 212.483587 -42.899988) (xy 212.453874 -42.854015) (xy 212.431038 -42.804268) (xy 212.415547 -42.751767)
			(xy 212.407719 -42.697591) (xy 212.407246 -42.670222) (xy 212.407798 -42.641484) (xy 212.416416 -42.584659)
			(xy 212.43346 -42.529769) (xy 212.458545 -42.478057) (xy 212.491103 -42.430692) (xy 212.51037 -42.409364)
			(xy 212.516974 -42.402506) (xy 212.524086 -42.384472) (xy 212.524086 -42.295572) (xy 212.516974 -42.277538)
			(xy 212.51037 -42.27068) (xy 212.491123 -42.249333) (xy 212.458562 -42.201973) (xy 212.433473 -42.150264)
			(xy 212.416424 -42.095377) (xy 212.4078 -42.038553) (xy 212.407798 -41.981079) (xy 212.416417 -41.924255)
			(xy 212.433461 -41.869366) (xy 212.458546 -41.817655) (xy 212.491103 -41.770292) (xy 212.51037 -41.748964)
			(xy 212.516974 -41.742106) (xy 212.524086 -41.724072) (xy 212.524086 -41.635172) (xy 212.516974 -41.617138)
			(xy 212.51037 -41.61028) (xy 212.491115 -41.588939) (xy 212.458545 -41.541582) (xy 212.433449 -41.489873)
			(xy 212.416395 -41.434986) (xy 212.407769 -41.37816) (xy 212.407246 -41.349422) (xy 212.407732 -41.322171)
			(xy 212.415488 -41.268223) (xy 212.430843 -41.215928) (xy 212.453485 -41.166351) (xy 212.482951 -41.120501)
			(xy 212.518642 -41.07931) (xy 212.559833 -41.043619) (xy 212.605683 -41.014153) (xy 212.65526 -40.991511)
			(xy 212.707555 -40.976156) (xy 212.761503 -40.9684) (xy 212.816005 -40.9684) (xy 212.839126 -40.971724)
			(xy 232.794046 -40.971724) (xy 232.798117 -40.916102) (xy 232.810243 -40.861665) (xy 232.830166 -40.809574)
			(xy 232.857462 -40.760939) (xy 232.891548 -40.716796) (xy 232.931697 -40.678087) (xy 232.977055 -40.645636)
			(xy 233.026655 -40.620135) (xy 233.079439 -40.602128) (xy 233.134282 -40.591998) (xy 233.190016 -40.589961)
			(xy 233.245453 -40.596061) (xy 233.29941 -40.610167) (xy 233.350739 -40.631979) (xy 233.398345 -40.661033)
			(xy 233.441213 -40.696708) (xy 233.47843 -40.738245) (xy 233.509203 -40.784758) (xy 233.532875 -40.835255)
			(xy 233.548943 -40.888662) (xy 233.557063 -40.943838) (xy 233.557572 -40.971724) (xy 233.557063 -40.99961)
			(xy 233.548943 -41.054786) (xy 233.532875 -41.108193) (xy 233.509203 -41.15869) (xy 233.47843 -41.205203)
			(xy 233.441213 -41.24674) (xy 233.414764 -41.268751) (xy 248.04395 -41.268751) (xy 248.04395 -41.214249)
			(xy 248.051706 -41.160301) (xy 248.06706 -41.108006) (xy 248.089699 -41.058428) (xy 248.119163 -41.012577)
			(xy 248.154852 -40.971385) (xy 248.19604 -40.935691) (xy 248.241888 -40.906221) (xy 248.291463 -40.883576)
			(xy 248.343756 -40.868215) (xy 248.397703 -40.860453) (xy 248.424954 -40.859964) (xy 248.453694 -40.860465)
			(xy 248.510522 -40.869094) (xy 248.565412 -40.88615) (xy 248.617124 -40.911247) (xy 248.664485 -40.943816)
			(xy 248.685812 -40.963088) (xy 248.69267 -40.969692) (xy 248.710704 -40.976804) (xy 248.799604 -40.976804)
			(xy 248.817638 -40.969692) (xy 248.824496 -40.963088) (xy 248.845808 -40.9438) (xy 248.893173 -40.911234)
			(xy 248.944889 -40.886144) (xy 248.999783 -40.869098) (xy 249.056614 -40.860481) (xy 249.085354 -40.859964)
			(xy 249.112607 -40.86048) (xy 249.166559 -40.868231) (xy 249.218858 -40.883582) (xy 249.268441 -40.90622)
			(xy 249.314296 -40.935685) (xy 249.355491 -40.971376) (xy 249.391187 -41.012567) (xy 249.420658 -41.058419)
			(xy 249.443302 -41.107998) (xy 249.458659 -41.160296) (xy 249.466417 -41.214247) (xy 249.466417 -41.268753)
			(xy 249.458659 -41.322704) (xy 249.443302 -41.375002) (xy 249.420658 -41.424581) (xy 249.391187 -41.470433)
			(xy 249.355491 -41.511624) (xy 249.314296 -41.547315) (xy 249.268441 -41.57678) (xy 249.218858 -41.599418)
			(xy 249.166559 -41.614769) (xy 249.112607 -41.62252) (xy 249.085354 -41.62298) (xy 249.056615 -41.622463)
			(xy 248.999788 -41.613835) (xy 248.944898 -41.596783) (xy 248.893187 -41.57169) (xy 248.845824 -41.539126)
			(xy 248.824496 -41.519856) (xy 248.817638 -41.513252) (xy 248.799604 -41.50614) (xy 248.710704 -41.50614)
			(xy 248.69267 -41.513252) (xy 248.685812 -41.519856) (xy 248.664503 -41.539148) (xy 248.617136 -41.571711)
			(xy 248.56542 -41.5968) (xy 248.510525 -41.613845) (xy 248.453694 -41.622462) (xy 248.424954 -41.62298)
			(xy 248.397703 -41.622547) (xy 248.343756 -41.614785) (xy 248.291463 -41.599424) (xy 248.241888 -41.576779)
			(xy 248.19604 -41.547309) (xy 248.154852 -41.511615) (xy 248.119163 -41.470423) (xy 248.089699 -41.424572)
			(xy 248.06706 -41.374994) (xy 248.051706 -41.322699) (xy 248.04395 -41.268751) (xy 233.414764 -41.268751)
			(xy 233.398345 -41.282415) (xy 233.350739 -41.311469) (xy 233.29941 -41.333281) (xy 233.245453 -41.347387)
			(xy 233.190016 -41.353487) (xy 233.134282 -41.35145) (xy 233.079439 -41.34132) (xy 233.026655 -41.323313)
			(xy 232.977055 -41.297812) (xy 232.931697 -41.265361) (xy 232.891548 -41.226652) (xy 232.857462 -41.182509)
			(xy 232.830166 -41.133874) (xy 232.810243 -41.081783) (xy 232.798117 -41.027346) (xy 232.794046 -40.971724)
			(xy 212.839126 -40.971724) (xy 212.869953 -40.976156) (xy 212.922248 -40.991511) (xy 212.971825 -41.014153)
			(xy 213.017675 -41.043619) (xy 213.058866 -41.07931) (xy 213.094557 -41.120501) (xy 213.124023 -41.166351)
			(xy 213.146665 -41.215928) (xy 213.16202 -41.268223) (xy 213.169776 -41.322171) (xy 213.170262 -41.349422)
			(xy 213.169735 -41.378161) (xy 213.161111 -41.434987) (xy 213.14406 -41.489877) (xy 213.11897 -41.541589)
			(xy 213.086407 -41.588952) (xy 213.067138 -41.61028) (xy 213.060534 -41.617138) (xy 213.053422 -41.635172)
			(xy 213.053422 -41.724072) (xy 213.060534 -41.742106) (xy 213.067138 -41.748964) (xy 213.086432 -41.770271)
			(xy 213.119 -41.817636) (xy 213.144093 -41.869351) (xy 213.161143 -41.924245) (xy 213.169765 -41.981075)
			(xy 213.169762 -42.038557) (xy 213.161136 -42.095387) (xy 213.144081 -42.150279) (xy 213.118984 -42.201992)
			(xy 213.086412 -42.249354) (xy 213.067138 -42.27068) (xy 213.060534 -42.277538) (xy 213.053422 -42.295572)
			(xy 213.053422 -42.384472) (xy 213.060534 -42.402506) (xy 213.067138 -42.409364) (xy 213.086415 -42.430686)
			(xy 213.118981 -42.478049) (xy 213.144073 -42.529762) (xy 213.161122 -42.584654) (xy 213.169743 -42.641483)
			(xy 213.170262 -42.670222) (xy 213.169818 -42.697593) (xy 213.161996 -42.751774) (xy 213.146503 -42.804277)
			(xy 213.125946 -42.849038) (xy 214.991948 -42.849038) (xy 214.996019 -42.793416) (xy 215.008145 -42.738979)
			(xy 215.028068 -42.686888) (xy 215.055364 -42.638253) (xy 215.08945 -42.59411) (xy 215.129599 -42.555401)
			(xy 215.174957 -42.52295) (xy 215.224557 -42.497449) (xy 215.277341 -42.479442) (xy 215.332184 -42.469312)
			(xy 215.387918 -42.467275) (xy 215.443355 -42.473375) (xy 215.497312 -42.487481) (xy 215.548641 -42.509293)
			(xy 215.596247 -42.538347) (xy 215.639115 -42.574022) (xy 215.676332 -42.615559) (xy 215.707105 -42.662072)
			(xy 215.730777 -42.712569) (xy 215.746845 -42.765976) (xy 215.754965 -42.821152) (xy 215.755326 -42.84091)
			(xy 221.033084 -42.84091) (xy 221.037155 -42.785288) (xy 221.049281 -42.730851) (xy 221.069204 -42.67876)
			(xy 221.0965 -42.630125) (xy 221.130586 -42.585982) (xy 221.170735 -42.547273) (xy 221.216093 -42.514822)
			(xy 221.265693 -42.489321) (xy 221.318477 -42.471314) (xy 221.37332 -42.461184) (xy 221.429054 -42.459147)
			(xy 221.484491 -42.465247) (xy 221.538448 -42.479353) (xy 221.589777 -42.501165) (xy 221.637383 -42.530219)
			(xy 221.680251 -42.565894) (xy 221.717468 -42.607431) (xy 221.748241 -42.653944) (xy 221.753729 -42.66565)
			(xy 232.397044 -42.66565) (xy 232.401115 -42.610028) (xy 232.413241 -42.555591) (xy 232.433164 -42.5035)
			(xy 232.46046 -42.454865) (xy 232.494546 -42.410722) (xy 232.534695 -42.372013) (xy 232.580053 -42.339562)
			(xy 232.629653 -42.314061) (xy 232.682437 -42.296054) (xy 232.73728 -42.285924) (xy 232.793014 -42.283887)
			(xy 232.848451 -42.289987) (xy 232.902408 -42.304093) (xy 232.953737 -42.325905) (xy 233.001343 -42.354959)
			(xy 233.044211 -42.390634) (xy 233.081428 -42.432171) (xy 233.112201 -42.478684) (xy 233.135873 -42.529181)
			(xy 233.151941 -42.582588) (xy 233.160061 -42.637764) (xy 233.16057 -42.66565) (xy 233.160061 -42.693536)
			(xy 233.151941 -42.748712) (xy 233.135873 -42.802119) (xy 233.112201 -42.852616) (xy 233.081428 -42.899129)
			(xy 233.044211 -42.940666) (xy 233.001343 -42.976341) (xy 232.953737 -43.005395) (xy 232.902408 -43.027207)
			(xy 232.848451 -43.041313) (xy 232.793014 -43.047413) (xy 232.73728 -43.045376) (xy 232.682437 -43.035246)
			(xy 232.629653 -43.017239) (xy 232.580053 -42.991738) (xy 232.534695 -42.959287) (xy 232.494546 -42.920578)
			(xy 232.46046 -42.876435) (xy 232.433164 -42.8278) (xy 232.413241 -42.775709) (xy 232.401115 -42.721272)
			(xy 232.397044 -42.66565) (xy 221.753729 -42.66565) (xy 221.771913 -42.704441) (xy 221.787981 -42.757848)
			(xy 221.796101 -42.813024) (xy 221.79661 -42.84091) (xy 221.796101 -42.868796) (xy 221.787981 -42.923972)
			(xy 221.771913 -42.977379) (xy 221.748241 -43.027876) (xy 221.717468 -43.074389) (xy 221.680251 -43.115926)
			(xy 221.637383 -43.151601) (xy 221.589777 -43.180655) (xy 221.538448 -43.202467) (xy 221.484491 -43.216573)
			(xy 221.429054 -43.222673) (xy 221.37332 -43.220636) (xy 221.318477 -43.210506) (xy 221.265693 -43.192499)
			(xy 221.216093 -43.166998) (xy 221.170735 -43.134547) (xy 221.130586 -43.095838) (xy 221.0965 -43.051695)
			(xy 221.069204 -43.00306) (xy 221.049281 -42.950969) (xy 221.037155 -42.896532) (xy 221.033084 -42.84091)
			(xy 215.755326 -42.84091) (xy 215.755474 -42.849038) (xy 215.754965 -42.876924) (xy 215.746845 -42.9321)
			(xy 215.730777 -42.985507) (xy 215.707105 -43.036004) (xy 215.676332 -43.082517) (xy 215.639115 -43.124054)
			(xy 215.596247 -43.159729) (xy 215.548641 -43.188783) (xy 215.497312 -43.210595) (xy 215.443355 -43.224701)
			(xy 215.387918 -43.230801) (xy 215.332184 -43.228764) (xy 215.277341 -43.218634) (xy 215.224557 -43.200627)
			(xy 215.174957 -43.175126) (xy 215.129599 -43.142675) (xy 215.08945 -43.103966) (xy 215.055364 -43.059823)
			(xy 215.028068 -43.011188) (xy 215.008145 -42.959097) (xy 214.996019 -42.90466) (xy 214.991948 -42.849038)
			(xy 213.125946 -42.849038) (xy 213.123656 -42.854024) (xy 213.093926 -42.899989) (xy 213.076282 -42.92092)
			(xy 213.076028 -42.921174) (xy 213.070438 -42.928258) (xy 213.064195 -42.945177) (xy 213.063836 -42.954194)
			(xy 213.063836 -43.02125) (xy 213.064209 -43.030265) (xy 213.070445 -43.047183) (xy 213.076028 -43.05427)
			(xy 213.076282 -43.05427) (xy 213.076282 -43.054524) (xy 213.093896 -43.075476) (xy 213.123612 -43.121443)
			(xy 213.146453 -43.171186) (xy 213.16195 -43.223682) (xy 213.169785 -43.277854) (xy 213.170262 -43.305222)
			(xy 250.507246 -43.305222) (xy 250.507714 -43.277852) (xy 250.515529 -43.223672) (xy 250.531018 -43.171169)
			(xy 250.553859 -43.121422) (xy 250.583584 -43.075455) (xy 250.601226 -43.054524) (xy 250.60148 -43.05427)
			(xy 250.607053 -43.047174) (xy 250.613306 -43.030264) (xy 250.613672 -43.02125) (xy 250.613672 -42.954194)
			(xy 250.613324 -42.945176) (xy 250.607071 -42.928259) (xy 250.60148 -42.921174) (xy 250.601226 -42.921174)
			(xy 250.601226 -42.92092) (xy 250.583587 -42.899988) (xy 250.553874 -42.854015) (xy 250.531038 -42.804268)
			(xy 250.515547 -42.751767) (xy 250.507719 -42.697591) (xy 250.507246 -42.670222) (xy 250.507798 -42.641484)
			(xy 250.516416 -42.584659) (xy 250.53346 -42.529769) (xy 250.558545 -42.478057) (xy 250.591103 -42.430692)
			(xy 250.61037 -42.409364) (xy 250.616974 -42.402506) (xy 250.624086 -42.384472) (xy 250.624086 -42.295572)
			(xy 250.616974 -42.277538) (xy 250.61037 -42.27068) (xy 250.591123 -42.249333) (xy 250.558562 -42.201973)
			(xy 250.533473 -42.150264) (xy 250.516424 -42.095377) (xy 250.5078 -42.038553) (xy 250.507798 -41.981079)
			(xy 250.516417 -41.924255) (xy 250.533461 -41.869366) (xy 250.558546 -41.817655) (xy 250.591103 -41.770292)
			(xy 250.61037 -41.748964) (xy 250.616974 -41.742106) (xy 250.624086 -41.724072) (xy 250.624086 -41.635172)
			(xy 250.616974 -41.617138) (xy 250.61037 -41.61028) (xy 250.591115 -41.588939) (xy 250.558545 -41.541582)
			(xy 250.533449 -41.489873) (xy 250.516395 -41.434986) (xy 250.507769 -41.37816) (xy 250.507246 -41.349422)
			(xy 250.507732 -41.322171) (xy 250.515488 -41.268223) (xy 250.530843 -41.215928) (xy 250.553485 -41.166351)
			(xy 250.582951 -41.120501) (xy 250.618642 -41.07931) (xy 250.659833 -41.043619) (xy 250.705683 -41.014153)
			(xy 250.75526 -40.991511) (xy 250.807555 -40.976156) (xy 250.861503 -40.9684) (xy 250.916005 -40.9684)
			(xy 250.939126 -40.971724) (xy 258.793994 -40.971724) (xy 258.798065 -40.916102) (xy 258.810191 -40.861665)
			(xy 258.830114 -40.809574) (xy 258.85741 -40.760939) (xy 258.891496 -40.716796) (xy 258.931645 -40.678087)
			(xy 258.977003 -40.645636) (xy 259.026603 -40.620135) (xy 259.079387 -40.602128) (xy 259.13423 -40.591998)
			(xy 259.189964 -40.589961) (xy 259.245401 -40.596061) (xy 259.299358 -40.610167) (xy 259.350687 -40.631979)
			(xy 259.398293 -40.661033) (xy 259.441161 -40.696708) (xy 259.478378 -40.738245) (xy 259.509151 -40.784758)
			(xy 259.532823 -40.835255) (xy 259.548891 -40.888662) (xy 259.557011 -40.943838) (xy 259.55752 -40.971724)
			(xy 259.557011 -40.99961) (xy 259.548891 -41.054786) (xy 259.532823 -41.108193) (xy 259.509151 -41.15869)
			(xy 259.478378 -41.205203) (xy 259.441161 -41.24674) (xy 259.398293 -41.282415) (xy 259.350687 -41.311469)
			(xy 259.299358 -41.333281) (xy 259.245401 -41.347387) (xy 259.189964 -41.353487) (xy 259.13423 -41.35145)
			(xy 259.079387 -41.34132) (xy 259.026603 -41.323313) (xy 258.977003 -41.297812) (xy 258.931645 -41.265361)
			(xy 258.891496 -41.226652) (xy 258.85741 -41.182509) (xy 258.830114 -41.133874) (xy 258.810191 -41.081783)
			(xy 258.798065 -41.027346) (xy 258.793994 -40.971724) (xy 250.939126 -40.971724) (xy 250.969953 -40.976156)
			(xy 251.022248 -40.991511) (xy 251.071825 -41.014153) (xy 251.117675 -41.043619) (xy 251.158866 -41.07931)
			(xy 251.194557 -41.120501) (xy 251.224023 -41.166351) (xy 251.246665 -41.215928) (xy 251.26202 -41.268223)
			(xy 251.269776 -41.322171) (xy 251.270262 -41.349422) (xy 251.269735 -41.378161) (xy 251.261111 -41.434987)
			(xy 251.24406 -41.489877) (xy 251.21897 -41.541589) (xy 251.186407 -41.588952) (xy 251.167138 -41.61028)
			(xy 251.160534 -41.617138) (xy 251.153422 -41.635172) (xy 251.153422 -41.724072) (xy 251.160534 -41.742106)
			(xy 251.167138 -41.748964) (xy 251.186432 -41.770271) (xy 251.219 -41.817636) (xy 251.244093 -41.869351)
			(xy 251.261143 -41.924245) (xy 251.269765 -41.981075) (xy 251.269762 -42.038557) (xy 251.261136 -42.095387)
			(xy 251.244081 -42.150279) (xy 251.218984 -42.201992) (xy 251.186412 -42.249354) (xy 251.167138 -42.27068)
			(xy 251.160534 -42.277538) (xy 251.153422 -42.295572) (xy 251.153422 -42.384472) (xy 251.160534 -42.402506)
			(xy 251.167138 -42.409364) (xy 251.186415 -42.430686) (xy 251.218981 -42.478049) (xy 251.244073 -42.529762)
			(xy 251.261122 -42.584654) (xy 251.269743 -42.641483) (xy 251.270262 -42.670222) (xy 251.269818 -42.697593)
			(xy 251.261996 -42.751774) (xy 251.246503 -42.804277) (xy 251.225946 -42.849038) (xy 253.091948 -42.849038)
			(xy 253.096019 -42.793416) (xy 253.108145 -42.738979) (xy 253.128068 -42.686888) (xy 253.155364 -42.638253)
			(xy 253.18945 -42.59411) (xy 253.229599 -42.555401) (xy 253.274957 -42.52295) (xy 253.324557 -42.497449)
			(xy 253.377341 -42.479442) (xy 253.432184 -42.469312) (xy 253.487918 -42.467275) (xy 253.543355 -42.473375)
			(xy 253.597312 -42.487481) (xy 253.648641 -42.509293) (xy 253.696247 -42.538347) (xy 253.739115 -42.574022)
			(xy 253.776332 -42.615559) (xy 253.807105 -42.662072) (xy 253.830777 -42.712569) (xy 253.846845 -42.765976)
			(xy 253.854965 -42.821152) (xy 253.855326 -42.84091) (xy 259.133084 -42.84091) (xy 259.137155 -42.785288)
			(xy 259.149281 -42.730851) (xy 259.169204 -42.67876) (xy 259.1965 -42.630125) (xy 259.230586 -42.585982)
			(xy 259.270735 -42.547273) (xy 259.316093 -42.514822) (xy 259.365693 -42.489321) (xy 259.418477 -42.471314)
			(xy 259.47332 -42.461184) (xy 259.529054 -42.459147) (xy 259.584491 -42.465247) (xy 259.638448 -42.479353)
			(xy 259.689777 -42.501165) (xy 259.737383 -42.530219) (xy 259.780251 -42.565894) (xy 259.817468 -42.607431)
			(xy 259.848241 -42.653944) (xy 259.871913 -42.704441) (xy 259.887981 -42.757848) (xy 259.896101 -42.813024)
			(xy 259.89661 -42.84091) (xy 259.896101 -42.868796) (xy 259.887981 -42.923972) (xy 259.871913 -42.977379)
			(xy 259.848241 -43.027876) (xy 259.817468 -43.074389) (xy 259.780251 -43.115926) (xy 259.737383 -43.151601)
			(xy 259.689777 -43.180655) (xy 259.638448 -43.202467) (xy 259.584491 -43.216573) (xy 259.529054 -43.222673)
			(xy 259.47332 -43.220636) (xy 259.418477 -43.210506) (xy 259.365693 -43.192499) (xy 259.316093 -43.166998)
			(xy 259.270735 -43.134547) (xy 259.230586 -43.095838) (xy 259.1965 -43.051695) (xy 259.169204 -43.00306)
			(xy 259.149281 -42.950969) (xy 259.137155 -42.896532) (xy 259.133084 -42.84091) (xy 253.855326 -42.84091)
			(xy 253.855474 -42.849038) (xy 253.854965 -42.876924) (xy 253.846845 -42.9321) (xy 253.830777 -42.985507)
			(xy 253.807105 -43.036004) (xy 253.776332 -43.082517) (xy 253.739115 -43.124054) (xy 253.696247 -43.159729)
			(xy 253.648641 -43.188783) (xy 253.597312 -43.210595) (xy 253.543355 -43.224701) (xy 253.487918 -43.230801)
			(xy 253.432184 -43.228764) (xy 253.377341 -43.218634) (xy 253.324557 -43.200627) (xy 253.274957 -43.175126)
			(xy 253.229599 -43.142675) (xy 253.18945 -43.103966) (xy 253.155364 -43.059823) (xy 253.128068 -43.011188)
			(xy 253.108145 -42.959097) (xy 253.096019 -42.90466) (xy 253.091948 -42.849038) (xy 251.225946 -42.849038)
			(xy 251.223656 -42.854024) (xy 251.193926 -42.899989) (xy 251.176282 -42.92092) (xy 251.176028 -42.921174)
			(xy 251.170438 -42.928258) (xy 251.164195 -42.945177) (xy 251.163836 -42.954194) (xy 251.163836 -43.02125)
			(xy 251.164209 -43.030265) (xy 251.170445 -43.047183) (xy 251.176028 -43.05427) (xy 251.176282 -43.05427)
			(xy 251.176282 -43.054524) (xy 251.193896 -43.075476) (xy 251.223612 -43.121443) (xy 251.246453 -43.171186)
			(xy 251.26195 -43.223682) (xy 251.269785 -43.277854) (xy 251.270262 -43.305222) (xy 251.269776 -43.332473)
			(xy 251.26202 -43.386421) (xy 251.246665 -43.438716) (xy 251.224023 -43.488293) (xy 251.194557 -43.534143)
			(xy 251.158866 -43.575334) (xy 251.117675 -43.611025) (xy 251.071825 -43.640491) (xy 251.022248 -43.663133)
			(xy 250.969953 -43.678488) (xy 250.916005 -43.686244) (xy 250.861503 -43.686244) (xy 250.807555 -43.678488)
			(xy 250.75526 -43.663133) (xy 250.705683 -43.640491) (xy 250.659833 -43.611025) (xy 250.618642 -43.575334)
			(xy 250.582951 -43.534143) (xy 250.553485 -43.488293) (xy 250.530843 -43.438716) (xy 250.515488 -43.386421)
			(xy 250.507732 -43.332473) (xy 250.507246 -43.305222) (xy 213.170262 -43.305222) (xy 213.169776 -43.332473)
			(xy 213.16202 -43.386421) (xy 213.146665 -43.438716) (xy 213.124023 -43.488293) (xy 213.094557 -43.534143)
			(xy 213.058866 -43.575334) (xy 213.017675 -43.611025) (xy 212.971825 -43.640491) (xy 212.922248 -43.663133)
			(xy 212.869953 -43.678488) (xy 212.816005 -43.686244) (xy 212.761503 -43.686244) (xy 212.707555 -43.678488)
			(xy 212.65526 -43.663133) (xy 212.605683 -43.640491) (xy 212.559833 -43.611025) (xy 212.518642 -43.575334)
			(xy 212.482951 -43.534143) (xy 212.453485 -43.488293) (xy 212.430843 -43.438716) (xy 212.415488 -43.386421)
			(xy 212.407732 -43.332473) (xy 212.407246 -43.305222) (xy 206.636392 -43.305222) (xy 206.621026 -43.73626)
			(xy 214.313006 -43.73626) (xy 214.317077 -43.680638) (xy 214.329203 -43.626201) (xy 214.349126 -43.57411)
			(xy 214.376422 -43.525475) (xy 214.410508 -43.481332) (xy 214.450657 -43.442623) (xy 214.496015 -43.410172)
			(xy 214.545615 -43.384671) (xy 214.598399 -43.366664) (xy 214.653242 -43.356534) (xy 214.708976 -43.354497)
			(xy 214.764413 -43.360597) (xy 214.81837 -43.374703) (xy 214.869699 -43.396515) (xy 214.917305 -43.425569)
			(xy 214.960173 -43.461244) (xy 214.99739 -43.502781) (xy 215.028163 -43.549294) (xy 215.051835 -43.599791)
			(xy 215.067903 -43.653198) (xy 215.076023 -43.708374) (xy 215.076532 -43.73626) (xy 215.076023 -43.764146)
			(xy 215.067903 -43.819322) (xy 215.056594 -43.85691) (xy 218.819728 -43.85691) (xy 218.823799 -43.801288)
			(xy 218.835925 -43.746851) (xy 218.855848 -43.69476) (xy 218.883144 -43.646125) (xy 218.91723 -43.601982)
			(xy 218.957379 -43.563273) (xy 219.002737 -43.530822) (xy 219.052337 -43.505321) (xy 219.105121 -43.487314)
			(xy 219.159964 -43.477184) (xy 219.215698 -43.475147) (xy 219.271135 -43.481247) (xy 219.325092 -43.495353)
			(xy 219.376421 -43.517165) (xy 219.424027 -43.546219) (xy 219.466895 -43.581894) (xy 219.504112 -43.623431)
			(xy 219.534885 -43.669944) (xy 219.558557 -43.720441) (xy 219.563316 -43.73626) (xy 252.413006 -43.73626)
			(xy 252.417077 -43.680638) (xy 252.429203 -43.626201) (xy 252.449126 -43.57411) (xy 252.476422 -43.525475)
			(xy 252.510508 -43.481332) (xy 252.550657 -43.442623) (xy 252.596015 -43.410172) (xy 252.645615 -43.384671)
			(xy 252.698399 -43.366664) (xy 252.753242 -43.356534) (xy 252.808976 -43.354497) (xy 252.864413 -43.360597)
			(xy 252.91837 -43.374703) (xy 252.969699 -43.396515) (xy 253.017305 -43.425569) (xy 253.060173 -43.461244)
			(xy 253.09739 -43.502781) (xy 253.128163 -43.549294) (xy 253.151835 -43.599791) (xy 253.167903 -43.653198)
			(xy 253.176023 -43.708374) (xy 253.176532 -43.73626) (xy 253.176023 -43.764146) (xy 253.167903 -43.819322)
			(xy 253.156594 -43.85691) (xy 256.919728 -43.85691) (xy 256.923799 -43.801288) (xy 256.935925 -43.746851)
			(xy 256.955848 -43.69476) (xy 256.983144 -43.646125) (xy 257.01723 -43.601982) (xy 257.057379 -43.563273)
			(xy 257.102737 -43.530822) (xy 257.152337 -43.505321) (xy 257.205121 -43.487314) (xy 257.259964 -43.477184)
			(xy 257.315698 -43.475147) (xy 257.371135 -43.481247) (xy 257.425092 -43.495353) (xy 257.476421 -43.517165)
			(xy 257.524027 -43.546219) (xy 257.566895 -43.581894) (xy 257.604112 -43.623431) (xy 257.634885 -43.669944)
			(xy 257.658557 -43.720441) (xy 257.674625 -43.773848) (xy 257.682745 -43.829024) (xy 257.683254 -43.85691)
			(xy 257.682745 -43.884796) (xy 257.674625 -43.939972) (xy 257.658557 -43.993379) (xy 257.634885 -44.043876)
			(xy 257.604112 -44.090389) (xy 257.566895 -44.131926) (xy 257.524027 -44.167601) (xy 257.476421 -44.196655)
			(xy 257.425092 -44.218467) (xy 257.371135 -44.232573) (xy 257.315698 -44.238673) (xy 257.259964 -44.236636)
			(xy 257.205121 -44.226506) (xy 257.152337 -44.208499) (xy 257.102737 -44.182998) (xy 257.057379 -44.150547)
			(xy 257.01723 -44.111838) (xy 256.983144 -44.067695) (xy 256.955848 -44.01906) (xy 256.935925 -43.966969)
			(xy 256.923799 -43.912532) (xy 256.919728 -43.85691) (xy 253.156594 -43.85691) (xy 253.151835 -43.872729)
			(xy 253.128163 -43.923226) (xy 253.09739 -43.969739) (xy 253.060173 -44.011276) (xy 253.017305 -44.046951)
			(xy 252.969699 -44.076005) (xy 252.91837 -44.097817) (xy 252.864413 -44.111923) (xy 252.808976 -44.118023)
			(xy 252.753242 -44.115986) (xy 252.698399 -44.105856) (xy 252.645615 -44.087849) (xy 252.596015 -44.062348)
			(xy 252.550657 -44.029897) (xy 252.510508 -43.991188) (xy 252.476422 -43.947045) (xy 252.449126 -43.89841)
			(xy 252.429203 -43.846319) (xy 252.417077 -43.791882) (xy 252.413006 -43.73626) (xy 219.563316 -43.73626)
			(xy 219.574625 -43.773848) (xy 219.582745 -43.829024) (xy 219.583254 -43.85691) (xy 219.582745 -43.884796)
			(xy 219.574625 -43.939972) (xy 219.558557 -43.993379) (xy 219.534885 -44.043876) (xy 219.504112 -44.090389)
			(xy 219.466895 -44.131926) (xy 219.424027 -44.167601) (xy 219.376421 -44.196655) (xy 219.325092 -44.218467)
			(xy 219.271135 -44.232573) (xy 219.215698 -44.238673) (xy 219.159964 -44.236636) (xy 219.105121 -44.226506)
			(xy 219.052337 -44.208499) (xy 219.002737 -44.182998) (xy 218.957379 -44.150547) (xy 218.91723 -44.111838)
			(xy 218.883144 -44.067695) (xy 218.855848 -44.01906) (xy 218.835925 -43.966969) (xy 218.823799 -43.912532)
			(xy 218.819728 -43.85691) (xy 215.056594 -43.85691) (xy 215.051835 -43.872729) (xy 215.028163 -43.923226)
			(xy 214.99739 -43.969739) (xy 214.960173 -44.011276) (xy 214.917305 -44.046951) (xy 214.869699 -44.076005)
			(xy 214.81837 -44.097817) (xy 214.764413 -44.111923) (xy 214.708976 -44.118023) (xy 214.653242 -44.115986)
			(xy 214.598399 -44.105856) (xy 214.545615 -44.087849) (xy 214.496015 -44.062348) (xy 214.450657 -44.029897)
			(xy 214.410508 -43.991188) (xy 214.376422 -43.947045) (xy 214.349126 -43.89841) (xy 214.329203 -43.846319)
			(xy 214.317077 -43.791882) (xy 214.313006 -43.73626) (xy 206.621026 -43.73626) (xy 206.571895 -45.114464)
			(xy 214.165432 -45.114464) (xy 214.169503 -45.058842) (xy 214.181629 -45.004405) (xy 214.201552 -44.952314)
			(xy 214.228848 -44.903679) (xy 214.262934 -44.859536) (xy 214.303083 -44.820827) (xy 214.348441 -44.788376)
			(xy 214.398041 -44.762875) (xy 214.450825 -44.744868) (xy 214.505668 -44.734738) (xy 214.561402 -44.732701)
			(xy 214.616839 -44.738801) (xy 214.670796 -44.752907) (xy 214.722125 -44.774719) (xy 214.769731 -44.803773)
			(xy 214.812599 -44.839448) (xy 214.849816 -44.880985) (xy 214.865383 -44.904515) (xy 220.93275 -44.904515)
			(xy 220.93275 -44.841285) (xy 220.941004 -44.778596) (xy 220.957369 -44.717521) (xy 220.981566 -44.659104)
			(xy 221.013181 -44.604345) (xy 221.051673 -44.554182) (xy 221.096383 -44.509472) (xy 221.146547 -44.47098)
			(xy 221.201306 -44.439365) (xy 221.259723 -44.415168) (xy 221.320798 -44.398803) (xy 221.383487 -44.39055)
			(xy 221.415102 -44.390056) (xy 223.641412 -44.390056) (xy 223.672972 -44.390586) (xy 223.735548 -44.398863)
			(xy 223.796512 -44.415221) (xy 223.854825 -44.439383) (xy 223.909494 -44.470935) (xy 223.959586 -44.509341)
			(xy 223.98228 -44.53128) (xy 224.50933 -45.05833) (xy 224.531326 -45.081067) (xy 224.556943 -45.114464)
			(xy 252.265432 -45.114464) (xy 252.269503 -45.058842) (xy 252.281629 -45.004405) (xy 252.301552 -44.952314)
			(xy 252.328848 -44.903679) (xy 252.362934 -44.859536) (xy 252.403083 -44.820827) (xy 252.448441 -44.788376)
			(xy 252.498041 -44.762875) (xy 252.550825 -44.744868) (xy 252.605668 -44.734738) (xy 252.661402 -44.732701)
			(xy 252.716839 -44.738801) (xy 252.770796 -44.752907) (xy 252.822125 -44.774719) (xy 252.869731 -44.803773)
			(xy 252.912599 -44.839448) (xy 252.942581 -44.87291) (xy 259.133084 -44.87291) (xy 259.137155 -44.817288)
			(xy 259.149281 -44.762851) (xy 259.169204 -44.71076) (xy 259.1965 -44.662125) (xy 259.230586 -44.617982)
			(xy 259.270735 -44.579273) (xy 259.316093 -44.546822) (xy 259.365693 -44.521321) (xy 259.418477 -44.503314)
			(xy 259.47332 -44.493184) (xy 259.529054 -44.491147) (xy 259.584491 -44.497247) (xy 259.638448 -44.511353)
			(xy 259.689777 -44.533165) (xy 259.737383 -44.562219) (xy 259.780251 -44.597894) (xy 259.817468 -44.639431)
			(xy 259.848241 -44.685944) (xy 259.871913 -44.736441) (xy 259.887981 -44.789848) (xy 259.896101 -44.845024)
			(xy 259.89661 -44.87291) (xy 259.896101 -44.900796) (xy 259.887981 -44.955972) (xy 259.871913 -45.009379)
			(xy 259.848241 -45.059876) (xy 259.817468 -45.106389) (xy 259.780251 -45.147926) (xy 259.737383 -45.183601)
			(xy 259.689777 -45.212655) (xy 259.638448 -45.234467) (xy 259.584491 -45.248573) (xy 259.529054 -45.254673)
			(xy 259.47332 -45.252636) (xy 259.418477 -45.242506) (xy 259.365693 -45.224499) (xy 259.316093 -45.198998)
			(xy 259.270735 -45.166547) (xy 259.230586 -45.127838) (xy 259.1965 -45.083695) (xy 259.169204 -45.03506)
			(xy 259.149281 -44.982969) (xy 259.137155 -44.928532) (xy 259.133084 -44.87291) (xy 252.942581 -44.87291)
			(xy 252.949816 -44.880985) (xy 252.980589 -44.927498) (xy 253.004261 -44.977995) (xy 253.020329 -45.031402)
			(xy 253.028449 -45.086578) (xy 253.028958 -45.114464) (xy 253.028449 -45.14235) (xy 253.020329 -45.197526)
			(xy 253.004261 -45.250933) (xy 252.980589 -45.30143) (xy 252.949816 -45.347943) (xy 252.944174 -45.35424)
			(xy 256.903726 -45.35424) (xy 256.907797 -45.298618) (xy 256.919923 -45.244181) (xy 256.939846 -45.19209)
			(xy 256.967142 -45.143455) (xy 257.001228 -45.099312) (xy 257.041377 -45.060603) (xy 257.086735 -45.028152)
			(xy 257.136335 -45.002651) (xy 257.189119 -44.984644) (xy 257.243962 -44.974514) (xy 257.299696 -44.972477)
			(xy 257.355133 -44.978577) (xy 257.40909 -44.992683) (xy 257.460419 -45.014495) (xy 257.508025 -45.043549)
			(xy 257.550893 -45.079224) (xy 257.58811 -45.120761) (xy 257.618883 -45.167274) (xy 257.642555 -45.217771)
			(xy 257.658623 -45.271178) (xy 257.666743 -45.326354) (xy 257.667252 -45.35424) (xy 257.666743 -45.382126)
			(xy 257.658623 -45.437302) (xy 257.642555 -45.490709) (xy 257.618883 -45.541206) (xy 257.58811 -45.587719)
			(xy 257.550893 -45.629256) (xy 257.508025 -45.664931) (xy 257.460419 -45.693985) (xy 257.40909 -45.715797)
			(xy 257.355133 -45.729903) (xy 257.299696 -45.736003) (xy 257.243962 -45.733966) (xy 257.189119 -45.723836)
			(xy 257.136335 -45.705829) (xy 257.086735 -45.680328) (xy 257.041377 -45.647877) (xy 257.001228 -45.609168)
			(xy 256.967142 -45.565025) (xy 256.939846 -45.51639) (xy 256.919923 -45.464299) (xy 256.907797 -45.409862)
			(xy 256.903726 -45.35424) (xy 252.944174 -45.35424) (xy 252.912599 -45.38948) (xy 252.869731 -45.425155)
			(xy 252.822125 -45.454209) (xy 252.770796 -45.476021) (xy 252.716839 -45.490127) (xy 252.661402 -45.496227)
			(xy 252.605668 -45.49419) (xy 252.550825 -45.48406) (xy 252.498041 -45.466053) (xy 252.448441 -45.440552)
			(xy 252.403083 -45.408101) (xy 252.362934 -45.369392) (xy 252.328848 -45.325249) (xy 252.301552 -45.276614)
			(xy 252.281629 -45.224523) (xy 252.269503 -45.170086) (xy 252.265432 -45.114464) (xy 224.556943 -45.114464)
			(xy 224.569829 -45.131263) (xy 224.601453 -45.186053) (xy 224.625658 -45.244502) (xy 224.64203 -45.305608)
			(xy 224.650289 -45.368329) (xy 224.650808 -45.39996) (xy 224.650808 -45.835351) (xy 238.482093 -45.835351)
			(xy 238.482093 -45.780849) (xy 238.48985 -45.726901) (xy 238.505206 -45.674607) (xy 238.527848 -45.62503)
			(xy 238.557315 -45.57918) (xy 238.593008 -45.537991) (xy 238.634199 -45.502301) (xy 238.680051 -45.472836)
			(xy 238.729629 -45.450197) (xy 238.781925 -45.434845) (xy 238.835873 -45.427092) (xy 238.863124 -45.42663)
			(xy 238.890495 -45.427075) (xy 238.944675 -45.434897) (xy 238.997179 -45.45039) (xy 239.046926 -45.473237)
			(xy 239.092891 -45.502966) (xy 239.113822 -45.52061) (xy 239.114076 -45.520864) (xy 239.12116 -45.526454)
			(xy 239.138079 -45.532697) (xy 239.147096 -45.533056) (xy 239.214152 -45.533056) (xy 239.223168 -45.532686)
			(xy 239.240085 -45.526448) (xy 239.247172 -45.520864) (xy 239.247172 -45.52061) (xy 239.247426 -45.52061)
			(xy 239.268359 -45.502969) (xy 239.314327 -45.473245) (xy 239.364073 -45.450399) (xy 239.416575 -45.434903)
			(xy 239.470753 -45.427074) (xy 239.525495 -45.427074) (xy 239.579673 -45.434903) (xy 239.632175 -45.450399)
			(xy 239.681921 -45.473245) (xy 239.727889 -45.502969) (xy 239.748822 -45.52061) (xy 239.749076 -45.520864)
			(xy 239.75616 -45.526454) (xy 239.773079 -45.532697) (xy 239.782096 -45.533056) (xy 239.849152 -45.533056)
			(xy 239.858168 -45.532686) (xy 239.875085 -45.526448) (xy 239.882172 -45.520864) (xy 239.882172 -45.52061)
			(xy 239.882426 -45.52061) (xy 239.903359 -45.502969) (xy 239.949327 -45.473245) (xy 239.999073 -45.450399)
			(xy 240.051575 -45.434903) (xy 240.105753 -45.427074) (xy 240.160495 -45.427074) (xy 240.214673 -45.434903)
			(xy 240.267175 -45.450399) (xy 240.316921 -45.473245) (xy 240.362889 -45.502969) (xy 240.383822 -45.52061)
			(xy 240.384076 -45.520864) (xy 240.39116 -45.526454) (xy 240.408079 -45.532697) (xy 240.417096 -45.533056)
			(xy 240.484152 -45.533056) (xy 240.493168 -45.532686) (xy 240.510085 -45.526448) (xy 240.517172 -45.520864)
			(xy 240.517172 -45.52061) (xy 240.517426 -45.52061) (xy 240.538376 -45.502994) (xy 240.584344 -45.473278)
			(xy 240.634087 -45.450438) (xy 240.686584 -45.434941) (xy 240.740756 -45.427107) (xy 240.768124 -45.42663)
			(xy 240.795377 -45.427042) (xy 240.849327 -45.434802) (xy 240.901624 -45.45016) (xy 240.951204 -45.472805)
			(xy 240.997056 -45.502275) (xy 241.038247 -45.53797) (xy 241.073939 -45.579164) (xy 241.103406 -45.625018)
			(xy 241.126048 -45.674598) (xy 241.141404 -45.726896) (xy 241.14916 -45.780847) (xy 241.14916 -45.835353)
			(xy 241.141404 -45.889304) (xy 241.126048 -45.941602) (xy 241.103406 -45.991182) (xy 241.073939 -46.037036)
			(xy 241.038247 -46.07823) (xy 241.033661 -46.082204) (xy 250.252484 -46.082204) (xy 250.252981 -46.054953)
			(xy 250.260737 -46.001006) (xy 250.276091 -45.948712) (xy 250.298732 -45.899136) (xy 250.328197 -45.853286)
			(xy 250.363887 -45.812095) (xy 250.405076 -45.776404) (xy 250.450925 -45.746937) (xy 250.500501 -45.724296)
			(xy 250.552795 -45.70894) (xy 250.606741 -45.701182) (xy 250.633992 -45.700696) (xy 250.660894 -45.701164)
			(xy 250.714164 -45.708735) (xy 250.765842 -45.723713) (xy 250.814904 -45.745802) (xy 250.860376 -45.774564)
			(xy 250.901358 -45.809428) (xy 250.937036 -45.849703) (xy 250.952254 -45.871892) (xy 250.959366 -45.882814)
			(xy 250.982226 -45.894752) (xy 251.094494 -45.89272) (xy 251.116846 -45.879766) (xy 251.123704 -45.86859)
			(xy 251.138636 -45.844996) (xy 251.174314 -45.802044) (xy 251.21587 -45.764751) (xy 251.262418 -45.733912)
			(xy 251.312964 -45.710188) (xy 251.366428 -45.694083) (xy 251.421668 -45.685943) (xy 251.449586 -45.685456)
			(xy 251.476579 -45.685925) (xy 251.530027 -45.693529) (xy 251.58187 -45.708588) (xy 251.631075 -45.7308)
			(xy 251.676659 -45.759723) (xy 251.69749 -45.776896) (xy 251.705618 -45.784008) (xy 251.726192 -45.790104)
			(xy 251.811536 -45.779182) (xy 251.822087 -45.777435) (xy 251.840367 -45.766361) (xy 251.846842 -45.757846)
			(xy 251.862176 -45.736601) (xy 251.897766 -45.698148) (xy 251.938287 -45.664931) (xy 251.982973 -45.637574)
			(xy 252.030984 -45.616593) (xy 252.081416 -45.602383) (xy 252.133318 -45.595211) (xy 252.159516 -45.594778)
			(xy 252.186765 -45.595293) (xy 252.240709 -45.603051) (xy 252.293 -45.618407) (xy 252.342574 -45.641049)
			(xy 252.38842 -45.670514) (xy 252.429607 -45.706204) (xy 252.465295 -45.747393) (xy 252.494759 -45.79324)
			(xy 252.517398 -45.842815) (xy 252.532752 -45.895106) (xy 252.540508 -45.949051) (xy 252.540508 -46.003549)
			(xy 252.532752 -46.057494) (xy 252.517398 -46.109785) (xy 252.494759 -46.15936) (xy 252.465295 -46.205207)
			(xy 252.429607 -46.246396) (xy 252.38842 -46.282086) (xy 252.342574 -46.311551) (xy 252.293 -46.334193)
			(xy 252.240709 -46.349549) (xy 252.186765 -46.357307) (xy 252.159516 -46.357794) (xy 252.132524 -46.357312)
			(xy 252.079077 -46.349709) (xy 252.027234 -46.334653) (xy 251.978029 -46.312444) (xy 251.932444 -46.283525)
			(xy 251.911612 -46.266354) (xy 251.903484 -46.259242) (xy 251.88291 -46.253146) (xy 251.797566 -46.264068)
			(xy 251.78702 -46.265833) (xy 251.768739 -46.276896) (xy 251.76226 -46.285404) (xy 251.744649 -46.309706)
			(xy 251.703052 -46.352965) (xy 251.679456 -46.37151) (xy 251.671582 -46.377352) (xy 251.661168 -46.394878)
			(xy 251.64796 -46.485302) (xy 251.652786 -46.504606) (xy 251.658628 -46.51248) (xy 251.658628 -46.512734)
			(xy 251.676125 -46.537482) (xy 251.703931 -46.591333) (xy 251.722869 -46.648904) (xy 251.730072 -46.693836)
			(xy 256.876296 -46.693836) (xy 256.876782 -46.666585) (xy 256.884538 -46.612637) (xy 256.899893 -46.560342)
			(xy 256.922535 -46.510765) (xy 256.952001 -46.464915) (xy 256.987692 -46.423724) (xy 257.028883 -46.388033)
			(xy 257.074733 -46.358567) (xy 257.12431 -46.335925) (xy 257.176605 -46.32057) (xy 257.230553 -46.312814)
			(xy 257.285055 -46.312814) (xy 257.339003 -46.32057) (xy 257.391298 -46.335925) (xy 257.440875 -46.358567)
			(xy 257.486725 -46.388033) (xy 257.527916 -46.423724) (xy 257.563607 -46.464915) (xy 257.593073 -46.510765)
			(xy 257.615715 -46.560342) (xy 257.63107 -46.612637) (xy 257.638826 -46.666585) (xy 257.639312 -46.693836)
			(xy 257.638838 -46.720263) (xy 257.631528 -46.772611) (xy 257.617056 -46.823446) (xy 257.595696 -46.871793)
			(xy 257.582162 -46.894496) (xy 257.581908 -46.89475) (xy 257.576571 -46.904768) (xy 257.574316 -46.927318)
			(xy 257.57759 -46.938184) (xy 257.603752 -47.01286) (xy 257.608136 -47.023375) (xy 257.624225 -47.039464)
			(xy 257.63474 -47.043848) (xy 257.634994 -47.043848) (xy 257.659513 -47.052891) (xy 257.705964 -47.076839)
			(xy 257.748715 -47.106899) (xy 257.786965 -47.142511) (xy 257.82 -47.183007) (xy 257.847202 -47.227631)
			(xy 257.868063 -47.275548) (xy 257.882192 -47.325863) (xy 257.889325 -47.377635) (xy 257.889756 -47.403766)
			(xy 257.88927 -47.431017) (xy 257.887747 -47.441612) (xy 259.161786 -47.441612) (xy 259.165857 -47.38599)
			(xy 259.177983 -47.331553) (xy 259.197906 -47.279462) (xy 259.225202 -47.230827) (xy 259.259288 -47.186684)
			(xy 259.299437 -47.147975) (xy 259.344795 -47.115524) (xy 259.394395 -47.090023) (xy 259.447179 -47.072016)
			(xy 259.502022 -47.061886) (xy 259.557756 -47.059849) (xy 259.613193 -47.065949) (xy 259.66715 -47.080055)
			(xy 259.718479 -47.101867) (xy 259.766085 -47.130921) (xy 259.808953 -47.166596) (xy 259.84617 -47.208133)
			(xy 259.876943 -47.254646) (xy 259.900615 -47.305143) (xy 259.916683 -47.35855) (xy 259.924803 -47.413726)
			(xy 259.925312 -47.441612) (xy 259.924803 -47.469498) (xy 259.916683 -47.524674) (xy 259.900615 -47.578081)
			(xy 259.876943 -47.628578) (xy 259.84617 -47.675091) (xy 259.808953 -47.716628) (xy 259.766085 -47.752303)
			(xy 259.718479 -47.781357) (xy 259.66715 -47.803169) (xy 259.613193 -47.817275) (xy 259.557756 -47.823375)
			(xy 259.502022 -47.821338) (xy 259.447179 -47.811208) (xy 259.394395 -47.793201) (xy 259.344795 -47.7677)
			(xy 259.299437 -47.735249) (xy 259.259288 -47.69654) (xy 259.225202 -47.652397) (xy 259.197906 -47.603762)
			(xy 259.177983 -47.551671) (xy 259.165857 -47.497234) (xy 259.161786 -47.441612) (xy 257.887747 -47.441612)
			(xy 257.881514 -47.484965) (xy 257.866159 -47.53726) (xy 257.843517 -47.586837) (xy 257.814051 -47.632687)
			(xy 257.77836 -47.673878) (xy 257.737169 -47.709569) (xy 257.691319 -47.739035) (xy 257.641742 -47.761677)
			(xy 257.589447 -47.777032) (xy 257.535499 -47.784788) (xy 257.480997 -47.784788) (xy 257.427049 -47.777032)
			(xy 257.374754 -47.761677) (xy 257.325177 -47.739035) (xy 257.279327 -47.709569) (xy 257.238136 -47.673878)
			(xy 257.202445 -47.632687) (xy 257.172979 -47.586837) (xy 257.150337 -47.53726) (xy 257.134982 -47.484965)
			(xy 257.127226 -47.431017) (xy 257.12674 -47.403766) (xy 257.127208 -47.377338) (xy 257.134518 -47.324991)
			(xy 257.148993 -47.274155) (xy 257.170354 -47.225809) (xy 257.18389 -47.203106) (xy 257.184144 -47.202852)
			(xy 257.189479 -47.192833) (xy 257.191738 -47.170284) (xy 257.188462 -47.159418) (xy 257.1623 -47.084742)
			(xy 257.157937 -47.074216) (xy 257.141834 -47.058131) (xy 257.131312 -47.053754) (xy 257.131058 -47.053754)
			(xy 257.106551 -47.04468) (xy 257.060098 -47.020739) (xy 257.017346 -46.990683) (xy 256.979094 -46.955077)
			(xy 256.946057 -46.914584) (xy 256.918854 -46.869964) (xy 256.897991 -46.822049) (xy 256.883861 -46.771736)
			(xy 256.876727 -46.719966) (xy 256.876296 -46.693836) (xy 251.730072 -46.693836) (xy 251.732462 -46.708745)
			(xy 251.73305 -46.739048) (xy 251.732567 -46.766299) (xy 251.724805 -46.820244) (xy 251.709446 -46.872536)
			(xy 251.686802 -46.922111) (xy 251.657335 -46.967959) (xy 251.621643 -47.009148) (xy 251.580454 -47.044838)
			(xy 251.534606 -47.074305) (xy 251.485031 -47.096948) (xy 251.432738 -47.112306) (xy 251.378793 -47.120067)
			(xy 251.351542 -47.120556) (xy 251.325508 -47.120134) (xy 251.273924 -47.11304) (xy 251.223782 -47.099005)
			(xy 251.176011 -47.078288) (xy 251.131498 -47.051275) (xy 251.111004 -47.035212) (xy 251.103253 -47.029461)
			(xy 251.084838 -47.023726) (xy 251.07519 -47.024036) (xy 250.995434 -47.030386) (xy 250.977654 -47.039022)
			(xy 250.971304 -47.046388) (xy 250.953144 -47.066054) (xy 250.912232 -47.100574) (xy 250.866898 -47.129041)
			(xy 250.818033 -47.150895) (xy 250.766593 -47.165708) (xy 250.713589 -47.17319) (xy 250.686824 -47.173642)
			(xy 250.659575 -47.1731) (xy 250.605631 -47.165347) (xy 250.553339 -47.149997) (xy 250.503765 -47.127361)
			(xy 250.457916 -47.0979) (xy 250.416726 -47.062215) (xy 250.381034 -47.021031) (xy 250.351567 -46.975186)
			(xy 250.328923 -46.925615) (xy 250.313565 -46.873326) (xy 250.305805 -46.819383) (xy 250.305316 -46.792134)
			(xy 250.305836 -46.76336) (xy 250.314488 -46.706465) (xy 250.331585 -46.651515) (xy 250.356739 -46.599754)
			(xy 250.389381 -46.552359) (xy 250.408694 -46.531022) (xy 250.41606 -46.523148) (xy 250.423172 -46.503336)
			(xy 250.415806 -46.40707) (xy 250.4059 -46.388274) (xy 250.397518 -46.38167) (xy 250.375333 -46.363446)
			(xy 250.336123 -46.32151) (xy 250.303638 -46.274174) (xy 250.278609 -46.222506) (xy 250.261603 -46.167672)
			(xy 250.253002 -46.110909) (xy 250.252484 -46.082204) (xy 241.033661 -46.082204) (xy 240.997056 -46.113925)
			(xy 240.951204 -46.143395) (xy 240.901624 -46.16604) (xy 240.849327 -46.181398) (xy 240.795377 -46.189158)
			(xy 240.768124 -46.189646) (xy 240.740754 -46.189179) (xy 240.686574 -46.181363) (xy 240.63407 -46.165875)
			(xy 240.584324 -46.143033) (xy 240.538357 -46.113308) (xy 240.517426 -46.095666) (xy 240.517172 -46.095412)
			(xy 240.510068 -46.089851) (xy 240.493165 -46.083588) (xy 240.484152 -46.08322) (xy 240.417096 -46.08322)
			(xy 240.408078 -46.083571) (xy 240.391161 -46.089822) (xy 240.384076 -46.095412) (xy 240.383822 -46.095666)
			(xy 240.362889 -46.113307) (xy 240.316921 -46.143031) (xy 240.267175 -46.165877) (xy 240.214673 -46.181373)
			(xy 240.160495 -46.189202) (xy 240.105753 -46.189202) (xy 240.051575 -46.181373) (xy 239.999073 -46.165877)
			(xy 239.949327 -46.143031) (xy 239.903359 -46.113307) (xy 239.882426 -46.095666) (xy 239.882172 -46.095412)
			(xy 239.875068 -46.089851) (xy 239.858165 -46.083588) (xy 239.849152 -46.08322) (xy 239.782096 -46.08322)
			(xy 239.773078 -46.083571) (xy 239.756161 -46.089822) (xy 239.749076 -46.095412) (xy 239.749076 -46.095666)
			(xy 239.748822 -46.095666) (xy 239.727889 -46.113307) (xy 239.681921 -46.143031) (xy 239.632175 -46.165877)
			(xy 239.579673 -46.181373) (xy 239.525495 -46.189202) (xy 239.470753 -46.189202) (xy 239.416575 -46.181373)
			(xy 239.364073 -46.165877) (xy 239.314327 -46.143031) (xy 239.268359 -46.113307) (xy 239.247426 -46.095666)
			(xy 239.247172 -46.095412) (xy 239.240068 -46.089851) (xy 239.223165 -46.083588) (xy 239.214152 -46.08322)
			(xy 239.147096 -46.08322) (xy 239.138078 -46.083571) (xy 239.121161 -46.089822) (xy 239.114076 -46.095412)
			(xy 239.114076 -46.095666) (xy 239.113822 -46.095666) (xy 239.092888 -46.113303) (xy 239.046916 -46.143016)
			(xy 238.997169 -46.165853) (xy 238.944669 -46.181345) (xy 238.890493 -46.189172) (xy 238.863124 -46.189646)
			(xy 238.835873 -46.189108) (xy 238.781925 -46.181355) (xy 238.729629 -46.166003) (xy 238.680051 -46.143364)
			(xy 238.634199 -46.113899) (xy 238.593008 -46.078209) (xy 238.557315 -46.03702) (xy 238.527848 -45.99117)
			(xy 238.505206 -45.941593) (xy 238.48985 -45.889299) (xy 238.482093 -45.835351) (xy 224.650808 -45.835351)
			(xy 224.650808 -47.477426) (xy 239.502188 -47.477426) (xy 239.502672 -47.450056) (xy 239.510486 -47.395878)
			(xy 239.525971 -47.343375) (xy 239.548809 -47.293628) (xy 239.578529 -47.247661) (xy 239.596168 -47.226728)
			(xy 239.596422 -47.226474) (xy 239.601986 -47.219372) (xy 239.608246 -47.202467) (xy 239.608614 -47.193454)
			(xy 239.608614 -47.126398) (xy 239.608255 -47.117381) (xy 239.602008 -47.100465) (xy 239.596422 -47.093378)
			(xy 239.596168 -47.093378) (xy 239.596168 -47.093124) (xy 239.578522 -47.072198) (xy 239.548812 -47.026223)
			(xy 239.525978 -46.976474) (xy 239.510489 -46.923972) (xy 239.502662 -46.869795) (xy 239.502188 -46.842426)
			(xy 239.502679 -46.815174) (xy 239.510433 -46.761224) (xy 239.525785 -46.708927) (xy 239.548425 -46.659347)
			(xy 239.577889 -46.613494) (xy 239.61358 -46.572301) (xy 239.65477 -46.536607) (xy 239.700621 -46.507139)
			(xy 239.750199 -46.484496) (xy 239.802495 -46.469139) (xy 239.856444 -46.461382) (xy 239.883696 -46.460918)
			(xy 239.912613 -46.461433) (xy 239.969785 -46.470161) (xy 240.024984 -46.48742) (xy 240.076946 -46.512812)
			(xy 240.12448 -46.545756) (xy 240.166496 -46.585498) (xy 240.184686 -46.607984) (xy 240.192294 -46.616789)
			(xy 240.213195 -46.626971) (xy 240.224818 -46.627542) (xy 240.304574 -46.627542) (xy 240.316205 -46.626994)
			(xy 240.337116 -46.616813) (xy 240.344706 -46.607984) (xy 240.36289 -46.585494) (xy 240.404911 -46.54576)
			(xy 240.452448 -46.512822) (xy 240.504411 -46.487435) (xy 240.559609 -46.47018) (xy 240.61678 -46.461452)
			(xy 240.645696 -46.460918) (xy 240.67295 -46.461359) (xy 240.726903 -46.469116) (xy 240.779203 -46.484473)
			(xy 240.828785 -46.507117) (xy 240.874639 -46.536587) (xy 240.915832 -46.572283) (xy 240.951526 -46.613479)
			(xy 240.980994 -46.659335) (xy 241.003635 -46.708918) (xy 241.018988 -46.761219) (xy 241.026742 -46.815172)
			(xy 241.027204 -46.842426) (xy 241.026753 -46.86874) (xy 241.019514 -46.92087) (xy 241.005192 -46.971513)
			(xy 240.984057 -47.019712) (xy 240.956508 -47.064555) (xy 240.923067 -47.105194) (xy 240.904014 -47.12335)
			(xy 240.89659 -47.130853) (xy 240.888078 -47.150147) (xy 240.887504 -47.160688) (xy 240.887504 -47.235364)
			(xy 240.888038 -47.245913) (xy 240.89657 -47.265209) (xy 240.904014 -47.272702) (xy 240.923066 -47.290861)
			(xy 240.956523 -47.33149) (xy 240.984082 -47.37633) (xy 241.005221 -47.42453) (xy 241.019539 -47.475177)
			(xy 241.026765 -47.52731) (xy 241.027204 -47.553626) (xy 241.026746 -47.580878) (xy 241.018986 -47.634827)
			(xy 241.003628 -47.687123) (xy 240.980983 -47.7367) (xy 240.951514 -47.782551) (xy 240.915819 -47.823741)
			(xy 240.874627 -47.859432) (xy 240.828774 -47.888898) (xy 240.779194 -47.911538) (xy 240.726898 -47.926893)
			(xy 240.672948 -47.934649) (xy 240.645696 -47.935134) (xy 240.618029 -47.934655) (xy 240.563277 -47.926654)
			(xy 240.510254 -47.910834) (xy 240.460068 -47.887526) (xy 240.413773 -47.857219) (xy 240.372336 -47.820547)
			(xy 240.336627 -47.778278) (xy 240.321592 -47.755048) (xy 240.314961 -47.745367) (xy 240.295096 -47.732925)
			(xy 240.283492 -47.731172) (xy 240.203482 -47.723298) (xy 240.191844 -47.722678) (xy 240.170009 -47.730752)
			(xy 240.161572 -47.738792) (xy 240.161318 -47.739046) (xy 240.143201 -47.757591) (xy 240.102878 -47.790175)
			(xy 240.058511 -47.816994) (xy 240.01092 -47.837553) (xy 239.960982 -47.851474) (xy 239.909617 -47.858499)
			(xy 239.883696 -47.858934) (xy 239.856446 -47.858426) (xy 239.8025 -47.85067) (xy 239.750208 -47.835315)
			(xy 239.700632 -47.812676) (xy 239.654783 -47.783211) (xy 239.613593 -47.747522) (xy 239.577902 -47.706335)
			(xy 239.548435 -47.660487) (xy 239.525792 -47.610913) (xy 239.510435 -47.558621) (xy 239.502676 -47.504676)
			(xy 239.502188 -47.477426) (xy 224.650808 -47.477426) (xy 224.650808 -48.30699) (xy 256.753866 -48.30699)
			(xy 256.757937 -48.251368) (xy 256.770063 -48.196931) (xy 256.789986 -48.14484) (xy 256.817282 -48.096205)
			(xy 256.851368 -48.052062) (xy 256.891517 -48.013353) (xy 256.936875 -47.980902) (xy 256.986475 -47.955401)
			(xy 257.039259 -47.937394) (xy 257.094102 -47.927264) (xy 257.149836 -47.925227) (xy 257.205273 -47.931327)
			(xy 257.25923 -47.945433) (xy 257.310559 -47.967245) (xy 257.358165 -47.996299) (xy 257.401033 -48.031974)
			(xy 257.43825 -48.073511) (xy 257.469023 -48.120024) (xy 257.492695 -48.170521) (xy 257.508763 -48.223928)
			(xy 257.516883 -48.279104) (xy 257.517392 -48.30699) (xy 257.516883 -48.334876) (xy 257.508763 -48.390052)
			(xy 257.492695 -48.443459) (xy 257.469023 -48.493956) (xy 257.43825 -48.540469) (xy 257.401033 -48.582006)
			(xy 257.358165 -48.617681) (xy 257.310559 -48.646735) (xy 257.25923 -48.668547) (xy 257.205273 -48.682653)
			(xy 257.149836 -48.688753) (xy 257.094102 -48.686716) (xy 257.039259 -48.676586) (xy 256.986475 -48.658579)
			(xy 256.936875 -48.633078) (xy 256.891517 -48.600627) (xy 256.851368 -48.561918) (xy 256.817282 -48.517775)
			(xy 256.789986 -48.46914) (xy 256.770063 -48.417049) (xy 256.757937 -48.362612) (xy 256.753866 -48.30699)
			(xy 224.650808 -48.30699) (xy 224.650808 -48.789458) (xy 238.952913 -48.789458) (xy 238.952913 -48.734942)
			(xy 238.960672 -48.680982) (xy 238.976032 -48.628675) (xy 238.99868 -48.579087) (xy 239.028155 -48.533227)
			(xy 239.063857 -48.492028) (xy 239.105059 -48.456331) (xy 239.150922 -48.42686) (xy 239.200513 -48.404218)
			(xy 239.252821 -48.388863) (xy 239.306782 -48.38111) (xy 239.33404 -48.38065) (xy 239.36141 -48.381139)
			(xy 239.415588 -48.388949) (xy 239.468091 -48.404432) (xy 239.517839 -48.427269) (xy 239.563806 -48.45699)
			(xy 239.584738 -48.47463) (xy 239.584992 -48.474884) (xy 239.592078 -48.480472) (xy 239.608995 -48.486718)
			(xy 239.618012 -48.487076) (xy 239.685068 -48.487076) (xy 239.694084 -48.486709) (xy 239.711001 -48.480469)
			(xy 239.718088 -48.474884) (xy 239.718088 -48.47463) (xy 239.718342 -48.47463) (xy 239.739289 -48.457009)
			(xy 239.785257 -48.427294) (xy 239.835001 -48.404454) (xy 239.887498 -48.388958) (xy 239.941672 -48.381126)
			(xy 239.96904 -48.38065) (xy 239.996286 -48.381223) (xy 240.050224 -48.388983) (xy 240.102508 -48.40434)
			(xy 240.152075 -48.426981) (xy 240.197915 -48.456445) (xy 240.239096 -48.492133) (xy 240.274779 -48.533317)
			(xy 240.304238 -48.579161) (xy 240.326874 -48.62873) (xy 240.342225 -48.681015) (xy 240.34998 -48.734954)
			(xy 240.34998 -48.753014) (xy 253.3683 -48.753014) (xy 253.372371 -48.697392) (xy 253.384497 -48.642955)
			(xy 253.40442 -48.590864) (xy 253.431716 -48.542229) (xy 253.465802 -48.498086) (xy 253.505951 -48.459377)
			(xy 253.551309 -48.426926) (xy 253.600909 -48.401425) (xy 253.653693 -48.383418) (xy 253.708536 -48.373288)
			(xy 253.76427 -48.371251) (xy 253.819707 -48.377351) (xy 253.873664 -48.391457) (xy 253.924993 -48.413269)
			(xy 253.972599 -48.442323) (xy 254.015467 -48.477998) (xy 254.052684 -48.519535) (xy 254.083457 -48.566048)
			(xy 254.107129 -48.616545) (xy 254.123197 -48.669952) (xy 254.131317 -48.725128) (xy 254.131826 -48.753014)
			(xy 254.131317 -48.7809) (xy 254.123197 -48.836076) (xy 254.120753 -48.8442) (xy 254.387348 -48.8442)
			(xy 254.391419 -48.788578) (xy 254.403545 -48.734141) (xy 254.423468 -48.68205) (xy 254.450764 -48.633415)
			(xy 254.48485 -48.589272) (xy 254.524999 -48.550563) (xy 254.570357 -48.518112) (xy 254.619957 -48.492611)
			(xy 254.672741 -48.474604) (xy 254.727584 -48.464474) (xy 254.783318 -48.462437) (xy 254.838755 -48.468537)
			(xy 254.892712 -48.482643) (xy 254.944041 -48.504455) (xy 254.991647 -48.533509) (xy 255.034515 -48.569184)
			(xy 255.071732 -48.610721) (xy 255.102505 -48.657234) (xy 255.126177 -48.707731) (xy 255.142245 -48.761138)
			(xy 255.150365 -48.816314) (xy 255.150874 -48.8442) (xy 255.150365 -48.872086) (xy 255.147367 -48.89246)
			(xy 255.414016 -48.89246) (xy 255.418087 -48.836838) (xy 255.430213 -48.782401) (xy 255.450136 -48.73031)
			(xy 255.477432 -48.681675) (xy 255.511518 -48.637532) (xy 255.551667 -48.598823) (xy 255.597025 -48.566372)
			(xy 255.646625 -48.540871) (xy 255.699409 -48.522864) (xy 255.754252 -48.512734) (xy 255.809986 -48.510697)
			(xy 255.865423 -48.516797) (xy 255.91938 -48.530903) (xy 255.970709 -48.552715) (xy 256.018315 -48.581769)
			(xy 256.061183 -48.617444) (xy 256.0984 -48.658981) (xy 256.129173 -48.705494) (xy 256.152845 -48.755991)
			(xy 256.168913 -48.809398) (xy 256.177033 -48.864574) (xy 256.177542 -48.89246) (xy 256.177033 -48.920346)
			(xy 256.174595 -48.93691) (xy 259.133084 -48.93691) (xy 259.137155 -48.881288) (xy 259.149281 -48.826851)
			(xy 259.169204 -48.77476) (xy 259.1965 -48.726125) (xy 259.230586 -48.681982) (xy 259.270735 -48.643273)
			(xy 259.316093 -48.610822) (xy 259.365693 -48.585321) (xy 259.418477 -48.567314) (xy 259.47332 -48.557184)
			(xy 259.529054 -48.555147) (xy 259.584491 -48.561247) (xy 259.638448 -48.575353) (xy 259.689777 -48.597165)
			(xy 259.737383 -48.626219) (xy 259.780251 -48.661894) (xy 259.817468 -48.703431) (xy 259.848241 -48.749944)
			(xy 259.871913 -48.800441) (xy 259.887981 -48.853848) (xy 259.896101 -48.909024) (xy 259.89661 -48.93691)
			(xy 259.896101 -48.964796) (xy 259.887981 -49.019972) (xy 259.871913 -49.073379) (xy 259.848241 -49.123876)
			(xy 259.817468 -49.170389) (xy 259.780251 -49.211926) (xy 259.737383 -49.247601) (xy 259.689777 -49.276655)
			(xy 259.638448 -49.298467) (xy 259.584491 -49.312573) (xy 259.529054 -49.318673) (xy 259.47332 -49.316636)
			(xy 259.418477 -49.306506) (xy 259.365693 -49.288499) (xy 259.316093 -49.262998) (xy 259.270735 -49.230547)
			(xy 259.230586 -49.191838) (xy 259.1965 -49.147695) (xy 259.169204 -49.09906) (xy 259.149281 -49.046969)
			(xy 259.137155 -48.992532) (xy 259.133084 -48.93691) (xy 256.174595 -48.93691) (xy 256.168913 -48.975522)
			(xy 256.152845 -49.028929) (xy 256.129173 -49.079426) (xy 256.0984 -49.125939) (xy 256.061183 -49.167476)
			(xy 256.018315 -49.203151) (xy 255.970709 -49.232205) (xy 255.91938 -49.254017) (xy 255.865423 -49.268123)
			(xy 255.809986 -49.274223) (xy 255.754252 -49.272186) (xy 255.699409 -49.262056) (xy 255.646625 -49.244049)
			(xy 255.597025 -49.218548) (xy 255.551667 -49.186097) (xy 255.511518 -49.147388) (xy 255.477432 -49.103245)
			(xy 255.450136 -49.05461) (xy 255.430213 -49.002519) (xy 255.418087 -48.948082) (xy 255.414016 -48.89246)
			(xy 255.147367 -48.89246) (xy 255.142245 -48.927262) (xy 255.126177 -48.980669) (xy 255.102505 -49.031166)
			(xy 255.071732 -49.077679) (xy 255.034515 -49.119216) (xy 254.991647 -49.154891) (xy 254.944041 -49.183945)
			(xy 254.892712 -49.205757) (xy 254.838755 -49.219863) (xy 254.783318 -49.225963) (xy 254.727584 -49.223926)
			(xy 254.672741 -49.213796) (xy 254.619957 -49.195789) (xy 254.570357 -49.170288) (xy 254.524999 -49.137837)
			(xy 254.48485 -49.099128) (xy 254.450764 -49.054985) (xy 254.423468 -49.00635) (xy 254.403545 -48.954259)
			(xy 254.391419 -48.899822) (xy 254.387348 -48.8442) (xy 254.120753 -48.8442) (xy 254.107129 -48.889483)
			(xy 254.083457 -48.93998) (xy 254.052684 -48.986493) (xy 254.015467 -49.02803) (xy 253.972599 -49.063705)
			(xy 253.924993 -49.092759) (xy 253.873664 -49.114571) (xy 253.819707 -49.128677) (xy 253.76427 -49.134777)
			(xy 253.708536 -49.13274) (xy 253.653693 -49.12261) (xy 253.600909 -49.104603) (xy 253.551309 -49.079102)
			(xy 253.505951 -49.046651) (xy 253.465802 -49.007942) (xy 253.431716 -48.963799) (xy 253.40442 -48.915164)
			(xy 253.384497 -48.863073) (xy 253.372371 -48.808636) (xy 253.3683 -48.753014) (xy 240.34998 -48.753014)
			(xy 240.34998 -48.789446) (xy 240.342225 -48.843385) (xy 240.326874 -48.89567) (xy 240.304238 -48.945239)
			(xy 240.274779 -48.991083) (xy 240.239096 -49.032267) (xy 240.197915 -49.067955) (xy 240.152075 -49.097419)
			(xy 240.102508 -49.12006) (xy 240.050224 -49.135417) (xy 239.996286 -49.143177) (xy 239.96904 -49.143666)
			(xy 239.94167 -49.143185) (xy 239.887491 -49.135372) (xy 239.834988 -49.119887) (xy 239.785241 -49.097048)
			(xy 239.739274 -49.067326) (xy 239.718342 -49.049686) (xy 239.718088 -49.049432) (xy 239.711015 -49.043826)
			(xy 239.694088 -49.037593) (xy 239.685068 -49.03724) (xy 239.618012 -49.03724) (xy 239.608995 -49.037594)
			(xy 239.592077 -49.043843) (xy 239.584992 -49.049432) (xy 239.584992 -49.049686) (xy 239.584738 -49.049686)
			(xy 239.563801 -49.067319) (xy 239.51783 -49.097032) (xy 239.468083 -49.119869) (xy 239.415584 -49.135362)
			(xy 239.361409 -49.143191) (xy 239.33404 -49.143666) (xy 239.306782 -49.14329) (xy 239.252821 -49.135537)
			(xy 239.200513 -49.120182) (xy 239.150922 -49.09754) (xy 239.105059 -49.068069) (xy 239.063857 -49.032372)
			(xy 239.028155 -48.991173) (xy 238.99868 -48.945313) (xy 238.976032 -48.895725) (xy 238.960672 -48.843418)
			(xy 238.952913 -48.789458) (xy 224.650808 -48.789458) (xy 224.650808 -49.72995) (xy 238.502698 -49.72995)
			(xy 238.502698 -49.67545) (xy 238.510454 -49.621506) (xy 238.525808 -49.569214) (xy 238.548448 -49.519639)
			(xy 238.577913 -49.473792) (xy 238.613602 -49.432604) (xy 238.65479 -49.396914) (xy 238.700638 -49.367449)
			(xy 238.750212 -49.344809) (xy 238.802504 -49.329455) (xy 238.856448 -49.321698) (xy 238.883698 -49.321212)
			(xy 238.911068 -49.321676) (xy 238.965248 -49.329494) (xy 239.017751 -49.344983) (xy 239.067498 -49.367826)
			(xy 239.113464 -49.397551) (xy 239.134396 -49.415192) (xy 239.13465 -49.415446) (xy 239.141743 -49.421023)
			(xy 239.158655 -49.427274) (xy 239.16767 -49.427638) (xy 239.234726 -49.427638) (xy 239.243743 -49.427285)
			(xy 239.26066 -49.421034) (xy 239.267746 -49.415446) (xy 239.267746 -49.415192) (xy 239.268 -49.415192)
			(xy 239.28892 -49.397538) (xy 239.334896 -49.367829) (xy 239.384647 -49.344996) (xy 239.43715 -49.329508)
			(xy 239.491328 -49.321684) (xy 239.518698 -49.321212) (xy 239.545952 -49.321635) (xy 239.599906 -49.329392)
			(xy 239.652207 -49.344749) (xy 239.70179 -49.367392) (xy 239.747646 -49.396862) (xy 239.788841 -49.432557)
			(xy 239.824537 -49.473752) (xy 239.854007 -49.519608) (xy 239.876651 -49.569191) (xy 239.892008 -49.621492)
			(xy 239.899765 -49.675446) (xy 239.899765 -49.729954) (xy 239.892008 -49.783908) (xy 239.876651 -49.836209)
			(xy 239.854007 -49.885792) (xy 239.824537 -49.931648) (xy 239.806113 -49.95291) (xy 259.133084 -49.95291)
			(xy 259.137155 -49.897288) (xy 259.149281 -49.842851) (xy 259.169204 -49.79076) (xy 259.1965 -49.742125)
			(xy 259.230586 -49.697982) (xy 259.270735 -49.659273) (xy 259.316093 -49.626822) (xy 259.365693 -49.601321)
			(xy 259.418477 -49.583314) (xy 259.47332 -49.573184) (xy 259.529054 -49.571147) (xy 259.584491 -49.577247)
			(xy 259.638448 -49.591353) (xy 259.663392 -49.601953) (xy 264.312859 -49.601953) (xy 264.312859 -49.547447)
			(xy 264.320616 -49.493496) (xy 264.335973 -49.441198) (xy 264.358616 -49.391618) (xy 264.388084 -49.345765)
			(xy 264.423778 -49.304572) (xy 264.464971 -49.268879) (xy 264.510825 -49.239412) (xy 264.560406 -49.21677)
			(xy 264.612704 -49.201415) (xy 264.666655 -49.193659) (xy 264.693908 -49.193196) (xy 264.721278 -49.193658)
			(xy 264.775458 -49.201477) (xy 264.827961 -49.216967) (xy 264.877707 -49.23981) (xy 264.923674 -49.269535)
			(xy 264.944606 -49.287176) (xy 264.94486 -49.28743) (xy 264.951951 -49.293009) (xy 264.968865 -49.299259)
			(xy 264.97788 -49.299622) (xy 265.044936 -49.299622) (xy 265.053954 -49.299278) (xy 265.070871 -49.293021)
			(xy 265.077956 -49.28743) (xy 265.077956 -49.287176) (xy 265.07821 -49.287176) (xy 265.099143 -49.269535)
			(xy 265.145111 -49.239811) (xy 265.194857 -49.216965) (xy 265.247359 -49.201469) (xy 265.301537 -49.19364)
			(xy 265.356279 -49.19364) (xy 265.410457 -49.201469) (xy 265.462959 -49.216965) (xy 265.512705 -49.239811)
			(xy 265.558673 -49.269535) (xy 265.579606 -49.287176) (xy 265.57986 -49.28743) (xy 265.586951 -49.293009)
			(xy 265.603865 -49.299259) (xy 265.61288 -49.299622) (xy 265.679936 -49.299622) (xy 265.688954 -49.299278)
			(xy 265.705871 -49.293021) (xy 265.712956 -49.28743) (xy 265.712956 -49.287176) (xy 265.71321 -49.287176)
			(xy 265.734143 -49.269535) (xy 265.780111 -49.239811) (xy 265.829857 -49.216965) (xy 265.882359 -49.201469)
			(xy 265.936537 -49.19364) (xy 265.991279 -49.19364) (xy 266.045457 -49.201469) (xy 266.097959 -49.216965)
			(xy 266.147705 -49.239811) (xy 266.193673 -49.269535) (xy 266.214606 -49.287176) (xy 266.21486 -49.28743)
			(xy 266.221951 -49.293009) (xy 266.238865 -49.299259) (xy 266.24788 -49.299622) (xy 266.314936 -49.299622)
			(xy 266.323954 -49.299278) (xy 266.340871 -49.293021) (xy 266.347956 -49.28743) (xy 266.347956 -49.287176)
			(xy 266.34821 -49.287176) (xy 266.369124 -49.269515) (xy 266.415102 -49.239807) (xy 266.464854 -49.216976)
			(xy 266.517359 -49.20149) (xy 266.571538 -49.193667) (xy 266.598908 -49.193196) (xy 266.626159 -49.193674)
			(xy 266.680107 -49.201432) (xy 266.732401 -49.216788) (xy 266.781978 -49.23943) (xy 266.827828 -49.268896)
			(xy 266.869017 -49.304588) (xy 266.904708 -49.345779) (xy 266.934174 -49.391629) (xy 266.956815 -49.441207)
			(xy 266.97217 -49.493501) (xy 266.979926 -49.547449) (xy 266.979926 -49.601951) (xy 266.97217 -49.655899)
			(xy 266.956815 -49.708193) (xy 266.934174 -49.757771) (xy 266.904708 -49.803621) (xy 266.869017 -49.844812)
			(xy 266.827828 -49.880504) (xy 266.781978 -49.90997) (xy 266.732401 -49.932612) (xy 266.680107 -49.947968)
			(xy 266.626159 -49.955726) (xy 266.598908 -49.956212) (xy 266.571538 -49.955738) (xy 266.517359 -49.947922)
			(xy 266.464857 -49.932434) (xy 266.41511 -49.909594) (xy 266.369142 -49.879872) (xy 266.34821 -49.862232)
			(xy 266.347956 -49.861978) (xy 266.340859 -49.856406) (xy 266.32395 -49.850151) (xy 266.314936 -49.849786)
			(xy 266.24788 -49.849786) (xy 266.238863 -49.850137) (xy 266.221946 -49.856389) (xy 266.21486 -49.861978)
			(xy 266.214606 -49.862232) (xy 266.193673 -49.879873) (xy 266.147705 -49.909597) (xy 266.097959 -49.932443)
			(xy 266.045457 -49.947939) (xy 265.991279 -49.955768) (xy 265.936537 -49.955768) (xy 265.882359 -49.947939)
			(xy 265.829857 -49.932443) (xy 265.780111 -49.909597) (xy 265.734143 -49.879873) (xy 265.71321 -49.862232)
			(xy 265.712956 -49.861978) (xy 265.705859 -49.856406) (xy 265.68895 -49.850151) (xy 265.679936 -49.849786)
			(xy 265.61288 -49.849786) (xy 265.603863 -49.850137) (xy 265.586946 -49.856389) (xy 265.57986 -49.861978)
			(xy 265.57986 -49.862232) (xy 265.579606 -49.862232) (xy 265.558673 -49.879873) (xy 265.512705 -49.909597)
			(xy 265.462959 -49.932443) (xy 265.410457 -49.947939) (xy 265.356279 -49.955768) (xy 265.301537 -49.955768)
			(xy 265.247359 -49.947939) (xy 265.194857 -49.932443) (xy 265.145111 -49.909597) (xy 265.099143 -49.879873)
			(xy 265.07821 -49.862232) (xy 265.077956 -49.861978) (xy 265.070859 -49.856406) (xy 265.05395 -49.850151)
			(xy 265.044936 -49.849786) (xy 264.97788 -49.849786) (xy 264.968863 -49.850137) (xy 264.951946 -49.856389)
			(xy 264.94486 -49.861978) (xy 264.94486 -49.862232) (xy 264.944606 -49.862232) (xy 264.923687 -49.879887)
			(xy 264.87771 -49.909595) (xy 264.827959 -49.932428) (xy 264.775456 -49.947915) (xy 264.721278 -49.95574)
			(xy 264.693908 -49.956212) (xy 264.666655 -49.955741) (xy 264.612704 -49.947985) (xy 264.560406 -49.93263)
			(xy 264.510825 -49.909988) (xy 264.464971 -49.880521) (xy 264.423778 -49.844828) (xy 264.388084 -49.803635)
			(xy 264.358616 -49.757782) (xy 264.335973 -49.708202) (xy 264.320616 -49.655904) (xy 264.312859 -49.601953)
			(xy 259.663392 -49.601953) (xy 259.689777 -49.613165) (xy 259.737383 -49.642219) (xy 259.780251 -49.677894)
			(xy 259.817468 -49.719431) (xy 259.848241 -49.765944) (xy 259.871913 -49.816441) (xy 259.887981 -49.869848)
			(xy 259.896101 -49.925024) (xy 259.89661 -49.95291) (xy 259.896101 -49.980796) (xy 259.887981 -50.035972)
			(xy 259.871913 -50.089379) (xy 259.848241 -50.139876) (xy 259.817468 -50.186389) (xy 259.780251 -50.227926)
			(xy 259.737383 -50.263601) (xy 259.689777 -50.292655) (xy 259.638448 -50.314467) (xy 259.584491 -50.328573)
			(xy 259.529054 -50.334673) (xy 259.47332 -50.332636) (xy 259.418477 -50.322506) (xy 259.365693 -50.304499)
			(xy 259.316093 -50.278998) (xy 259.270735 -50.246547) (xy 259.230586 -50.207838) (xy 259.1965 -50.163695)
			(xy 259.169204 -50.11506) (xy 259.149281 -50.062969) (xy 259.137155 -50.008532) (xy 259.133084 -49.95291)
			(xy 239.806113 -49.95291) (xy 239.788841 -49.972843) (xy 239.747646 -50.008538) (xy 239.70179 -50.038008)
			(xy 239.652207 -50.060651) (xy 239.599906 -50.076008) (xy 239.545952 -50.083765) (xy 239.518698 -50.084228)
			(xy 239.491327 -50.083781) (xy 239.437146 -50.075961) (xy 239.384642 -50.060469) (xy 239.334896 -50.037622)
			(xy 239.28893 -50.007892) (xy 239.268 -49.990248) (xy 239.267746 -49.989994) (xy 239.260651 -49.98442)
			(xy 239.243741 -49.978166) (xy 239.234726 -49.977802) (xy 239.16767 -49.977802) (xy 239.158652 -49.978144)
			(xy 239.141735 -49.984402) (xy 239.13465 -49.989994) (xy 239.13465 -49.990248) (xy 239.134396 -49.990248)
			(xy 239.11347 -50.007894) (xy 239.067496 -50.037607) (xy 239.017747 -50.060442) (xy 238.965245 -50.075931)
			(xy 238.911068 -50.083756) (xy 238.883698 -50.084228) (xy 238.856448 -50.083702) (xy 238.802504 -50.075945)
			(xy 238.750212 -50.060591) (xy 238.700638 -50.037951) (xy 238.65479 -50.008486) (xy 238.613602 -49.972796)
			(xy 238.577913 -49.931608) (xy 238.548448 -49.885761) (xy 238.525808 -49.836186) (xy 238.510454 -49.783894)
			(xy 238.502698 -49.72995) (xy 224.650808 -49.72995) (xy 224.650808 -50.701956) (xy 224.650506 -50.721051)
			(xy 256.232883 -50.721051) (xy 256.232883 -50.666549) (xy 256.24064 -50.6126) (xy 256.255996 -50.560305)
			(xy 256.278638 -50.510728) (xy 256.308105 -50.464877) (xy 256.343797 -50.423687) (xy 256.384989 -50.387996)
			(xy 256.43084 -50.358531) (xy 256.480418 -50.335891) (xy 256.532714 -50.320537) (xy 256.586662 -50.312782)
			(xy 256.613914 -50.31232) (xy 256.640253 -50.312759) (xy 256.692432 -50.319983) (xy 256.74312 -50.33432)
			(xy 256.791353 -50.355496) (xy 256.836212 -50.383109) (xy 256.876844 -50.416633) (xy 256.912476 -50.45543)
			(xy 256.942429 -50.498762) (xy 256.966133 -50.545804) (xy 256.983138 -50.595661) (xy 256.988564 -50.621438)
			(xy 256.991588 -50.634981) (xy 257.003979 -50.6598) (xy 257.022604 -50.680357) (xy 257.046084 -50.695129)
			(xy 257.072678 -50.703021) (xy 257.100415 -50.703448) (xy 257.127239 -50.696378) (xy 257.13944 -50.689764)
			(xy 257.161399 -50.677474) (xy 257.207836 -50.658087) (xy 257.256419 -50.644971) (xy 257.306303 -50.638353)
			(xy 257.331464 -50.637948) (xy 257.358715 -50.638497) (xy 257.412664 -50.646249) (xy 257.46496 -50.6616)
			(xy 257.514539 -50.684238) (xy 257.560391 -50.713701) (xy 257.601584 -50.749391) (xy 257.637277 -50.79058)
			(xy 257.666745 -50.836429) (xy 257.689388 -50.886006) (xy 257.704744 -50.938301) (xy 257.712501 -50.992249)
			(xy 257.712501 -51.046751) (xy 257.704744 -51.100699) (xy 257.689388 -51.152994) (xy 257.666745 -51.202571)
			(xy 257.640123 -51.243992) (xy 265.332972 -51.243992) (xy 265.333416 -51.216621) (xy 265.341236 -51.16244)
			(xy 265.35673 -51.109936) (xy 265.379577 -51.060189) (xy 265.409308 -51.014224) (xy 265.426952 -50.993294)
			(xy 265.427206 -50.99304) (xy 265.432783 -50.985947) (xy 265.439035 -50.969035) (xy 265.439398 -50.96002)
			(xy 265.439398 -50.892964) (xy 265.439058 -50.883945) (xy 265.432799 -50.867029) (xy 265.427206 -50.859944)
			(xy 265.426952 -50.859944) (xy 265.426952 -50.85969) (xy 265.409303 -50.838766) (xy 265.379591 -50.792792)
			(xy 265.356756 -50.743042) (xy 265.341267 -50.69054) (xy 265.333443 -50.636362) (xy 265.332972 -50.608992)
			(xy 265.33347 -50.581741) (xy 265.341227 -50.527795) (xy 265.356582 -50.475502) (xy 265.379223 -50.425926)
			(xy 265.408688 -50.380077) (xy 265.444378 -50.338887) (xy 265.485567 -50.303196) (xy 265.531415 -50.273729)
			(xy 265.580991 -50.251087) (xy 265.633283 -50.23573) (xy 265.687229 -50.227971) (xy 265.71448 -50.227484)
			(xy 265.743398 -50.227985) (xy 265.800571 -50.236713) (xy 265.855772 -50.253972) (xy 265.907734 -50.279367)
			(xy 265.955268 -50.312315) (xy 265.997282 -50.352062) (xy 266.01547 -50.37455) (xy 266.023091 -50.383342)
			(xy 266.043982 -50.393532) (xy 266.055602 -50.394108) (xy 266.135358 -50.394108) (xy 266.146992 -50.393585)
			(xy 266.167901 -50.383384) (xy 266.17549 -50.37455) (xy 266.193674 -50.352061) (xy 266.235697 -50.312328)
			(xy 266.283234 -50.279391) (xy 266.335196 -50.254005) (xy 266.390394 -50.236749) (xy 266.447564 -50.22802)
			(xy 266.47648 -50.227484) (xy 266.503732 -50.227974) (xy 266.557682 -50.235728) (xy 266.609978 -50.251081)
			(xy 266.659558 -50.273721) (xy 266.705411 -50.303186) (xy 266.746603 -50.338877) (xy 266.782297 -50.380067)
			(xy 266.811766 -50.425917) (xy 266.834409 -50.475495) (xy 266.849766 -50.527791) (xy 266.857524 -50.58174)
			(xy 266.857988 -50.608992) (xy 266.857519 -50.635306) (xy 266.850285 -50.687435) (xy 266.835967 -50.738077)
			(xy 266.814834 -50.786276) (xy 266.787288 -50.83112) (xy 266.75385 -50.87176) (xy 266.734798 -50.889916)
			(xy 266.727387 -50.89743) (xy 266.718868 -50.916716) (xy 266.718288 -50.927254) (xy 266.718288 -51.00193)
			(xy 266.718845 -51.012476) (xy 266.727361 -51.031772) (xy 266.734798 -51.039268) (xy 266.753879 -51.057398)
			(xy 266.787334 -51.098033) (xy 266.81489 -51.142879) (xy 266.836024 -51.191085) (xy 266.850335 -51.241737)
			(xy 266.857553 -51.293874) (xy 266.857988 -51.320192) (xy 266.857537 -51.347446) (xy 266.849781 -51.401398)
			(xy 266.834425 -51.453697) (xy 266.811782 -51.503279) (xy 266.782313 -51.549133) (xy 266.746618 -51.590326)
			(xy 266.705423 -51.62602) (xy 266.659568 -51.655487) (xy 266.609986 -51.678129) (xy 266.557686 -51.693483)
			(xy 266.503734 -51.701238) (xy 266.47648 -51.7017) (xy 266.448814 -51.701203) (xy 266.394064 -51.693201)
			(xy 266.341042 -51.677382) (xy 266.290858 -51.654076) (xy 266.244563 -51.623773) (xy 266.203125 -51.587105)
			(xy 266.167413 -51.544842) (xy 266.152376 -51.521614) (xy 266.14576 -51.51192) (xy 266.125883 -51.499486)
			(xy 266.114276 -51.497738) (xy 266.034266 -51.489864) (xy 266.022627 -51.489215) (xy 266.000789 -51.497307)
			(xy 265.992356 -51.505358) (xy 265.992102 -51.505612) (xy 265.974005 -51.524177) (xy 265.933676 -51.556756)
			(xy 265.889305 -51.583571) (xy 265.84171 -51.604127) (xy 265.791769 -51.618044) (xy 265.740402 -51.625066)
			(xy 265.71448 -51.6255) (xy 265.687228 -51.625041) (xy 265.633279 -51.617281) (xy 265.580983 -51.601923)
			(xy 265.531405 -51.579279) (xy 265.485555 -51.54981) (xy 265.444364 -51.514116) (xy 265.408673 -51.472923)
			(xy 265.379207 -51.42707) (xy 265.356567 -51.377491) (xy 265.341213 -51.325194) (xy 265.333457 -51.271244)
			(xy 265.332972 -51.243992) (xy 257.640123 -51.243992) (xy 257.637277 -51.24842) (xy 257.601584 -51.289609)
			(xy 257.560391 -51.325299) (xy 257.514539 -51.354762) (xy 257.46496 -51.3774) (xy 257.412664 -51.392751)
			(xy 257.358715 -51.400503) (xy 257.331464 -51.400964) (xy 257.305128 -51.400478) (xy 257.252954 -51.393252)
			(xy 257.20227 -51.378917) (xy 257.154042 -51.357743) (xy 257.109185 -51.330135) (xy 257.068554 -51.296617)
			(xy 257.032922 -51.257827) (xy 257.002966 -51.214503) (xy 256.979257 -51.167469) (xy 256.962245 -51.11762)
			(xy 256.956814 -51.091846) (xy 256.953689 -51.078332) (xy 256.941309 -51.053527) (xy 256.922699 -51.032979)
			(xy 256.899239 -51.018209) (xy 256.872666 -51.010311) (xy 256.844947 -51.00987) (xy 256.818135 -51.016918)
			(xy 256.805938 -51.02352) (xy 256.783983 -51.035817) (xy 256.737544 -51.055203) (xy 256.688961 -51.068317)
			(xy 256.639075 -51.074933) (xy 256.613914 -51.075336) (xy 256.586662 -51.074818) (xy 256.532714 -51.067063)
			(xy 256.480418 -51.051709) (xy 256.43084 -51.029069) (xy 256.384989 -50.999604) (xy 256.343797 -50.963913)
			(xy 256.308105 -50.922723) (xy 256.278638 -50.876872) (xy 256.255996 -50.827295) (xy 256.24064 -50.775)
			(xy 256.232883 -50.721051) (xy 224.650506 -50.721051) (xy 224.650308 -50.73359) (xy 224.642065 -50.796317)
			(xy 224.625701 -50.857431) (xy 224.601496 -50.915885) (xy 224.569865 -50.970677) (xy 224.53135 -51.020869)
			(xy 224.50933 -51.043586) (xy 224.330467 -51.222449) (xy 236.270302 -51.222449) (xy 236.270302 -51.167951)
			(xy 236.278058 -51.114007) (xy 236.293412 -51.061717) (xy 236.316051 -51.012143) (xy 236.345514 -50.966296)
			(xy 236.381203 -50.925109) (xy 236.42239 -50.889419) (xy 236.468236 -50.859955) (xy 236.517809 -50.837315)
			(xy 236.570099 -50.82196) (xy 236.624043 -50.814203) (xy 236.651292 -50.813716) (xy 236.679384 -50.814201)
			(xy 236.734962 -50.822428) (xy 236.788732 -50.838719) (xy 236.83953 -50.862723) (xy 236.886257 -50.89392)
			(xy 236.927902 -50.931634) (xy 236.963562 -50.97505) (xy 236.978444 -50.998882) (xy 236.983778 -51.007772)
			(xy 237.000796 -51.019964) (xy 237.094014 -51.040284) (xy 237.114588 -51.035966) (xy 237.123224 -51.030124)
			(xy 237.147282 -51.014114) (xy 237.199215 -50.988773) (xy 237.254375 -50.97155) (xy 237.311501 -50.962838)
			(xy 237.340394 -50.962306) (xy 237.367647 -50.962761) (xy 237.421599 -50.970517) (xy 237.473898 -50.985873)
			(xy 237.523479 -51.008516) (xy 237.569333 -51.037985) (xy 237.610526 -51.07368) (xy 237.64622 -51.114873)
			(xy 237.675688 -51.160728) (xy 237.698329 -51.210309) (xy 237.713684 -51.262609) (xy 237.72144 -51.316561)
			(xy 237.721902 -51.343814) (xy 237.721444 -51.371185) (xy 237.713624 -51.425364) (xy 237.698133 -51.477867)
			(xy 237.67529 -51.527614) (xy 237.645564 -51.57358) (xy 237.627922 -51.594512) (xy 237.627668 -51.594766)
			(xy 237.622086 -51.601856) (xy 237.615838 -51.61877) (xy 237.615476 -51.627786) (xy 237.615476 -51.694842)
			(xy 237.615866 -51.703855) (xy 237.622091 -51.720772) (xy 237.627668 -51.727862) (xy 237.627922 -51.727862)
			(xy 237.627922 -51.728116) (xy 237.645574 -51.749039) (xy 237.675295 -51.795009) (xy 237.698136 -51.844758)
			(xy 237.713629 -51.897261) (xy 237.721456 -51.95144) (xy 237.721454 -52.006181) (xy 237.717224 -52.035456)
			(xy 259.141212 -52.035456) (xy 259.145283 -51.979834) (xy 259.157409 -51.925397) (xy 259.177332 -51.873306)
			(xy 259.204628 -51.824671) (xy 259.238714 -51.780528) (xy 259.278863 -51.741819) (xy 259.324221 -51.709368)
			(xy 259.373821 -51.683867) (xy 259.426605 -51.66586) (xy 259.481448 -51.65573) (xy 259.537182 -51.653693)
			(xy 259.592619 -51.659793) (xy 259.646576 -51.673899) (xy 259.697905 -51.695711) (xy 259.745511 -51.724765)
			(xy 259.788379 -51.76044) (xy 259.825596 -51.801977) (xy 259.856369 -51.84849) (xy 259.880041 -51.898987)
			(xy 259.896109 -51.952394) (xy 259.904229 -52.00757) (xy 259.904738 -52.035456) (xy 259.904229 -52.063342)
			(xy 259.896109 -52.118518) (xy 259.880041 -52.171925) (xy 259.856369 -52.222422) (xy 259.825596 -52.268935)
			(xy 259.788379 -52.310472) (xy 259.745511 -52.346147) (xy 259.697905 -52.375201) (xy 259.646576 -52.397013)
			(xy 259.592619 -52.411119) (xy 259.537182 -52.417219) (xy 259.481448 -52.415182) (xy 259.426605 -52.405052)
			(xy 259.373821 -52.387045) (xy 259.324221 -52.361544) (xy 259.278863 -52.329093) (xy 259.238714 -52.290384)
			(xy 259.204628 -52.246241) (xy 259.177332 -52.197606) (xy 259.157409 -52.145515) (xy 259.145283 -52.091078)
			(xy 259.141212 -52.035456) (xy 237.717224 -52.035456) (xy 237.713625 -52.06036) (xy 237.698129 -52.112862)
			(xy 237.675285 -52.162609) (xy 237.645562 -52.208578) (xy 237.627922 -52.229512) (xy 237.627668 -52.229766)
			(xy 237.622086 -52.236856) (xy 237.615838 -52.25377) (xy 237.615476 -52.262786) (xy 237.615476 -52.329842)
			(xy 237.615866 -52.338855) (xy 237.622091 -52.355772) (xy 237.627668 -52.362862) (xy 237.627922 -52.362862)
			(xy 237.627922 -52.363116) (xy 237.645539 -52.384066) (xy 237.675253 -52.430034) (xy 237.698093 -52.479777)
			(xy 237.713589 -52.532274) (xy 237.721424 -52.586446) (xy 237.721902 -52.613814) (xy 237.721416 -52.641065)
			(xy 237.71366 -52.695013) (xy 237.698305 -52.747308) (xy 237.675663 -52.796885) (xy 237.646197 -52.842735)
			(xy 237.610506 -52.883926) (xy 237.569315 -52.919617) (xy 237.523465 -52.949083) (xy 237.473888 -52.971725)
			(xy 237.421593 -52.98708) (xy 237.367645 -52.994836) (xy 237.313143 -52.994836) (xy 237.259195 -52.98708)
			(xy 237.2069 -52.971725) (xy 237.157323 -52.949083) (xy 237.111473 -52.919617) (xy 237.070282 -52.883926)
			(xy 237.034591 -52.842735) (xy 237.005125 -52.796885) (xy 236.982483 -52.747308) (xy 236.967128 -52.695013)
			(xy 236.959372 -52.641065) (xy 236.958886 -52.613814) (xy 236.959364 -52.586444) (xy 236.967179 -52.532266)
			(xy 236.982666 -52.479763) (xy 237.005505 -52.430016) (xy 237.035226 -52.384048) (xy 237.052866 -52.363116)
			(xy 237.05312 -52.362862) (xy 237.058689 -52.355763) (xy 237.064946 -52.338856) (xy 237.065312 -52.329842)
			(xy 237.065312 -52.262786) (xy 237.064959 -52.253769) (xy 237.058708 -52.236852) (xy 237.05312 -52.229766)
			(xy 237.052866 -52.229766) (xy 237.052866 -52.229512) (xy 237.035237 -52.208569) (xy 237.005509 -52.162604)
			(xy 236.98266 -52.11286) (xy 236.967161 -52.060359) (xy 236.959331 -52.006181) (xy 236.959329 -51.95144)
			(xy 236.967157 -51.897262) (xy 236.982653 -51.84476) (xy 237.005499 -51.795015) (xy 237.035225 -51.749048)
			(xy 237.052866 -51.728116) (xy 237.05312 -51.727862) (xy 237.058689 -51.720763) (xy 237.064946 -51.703856)
			(xy 237.065312 -51.694842) (xy 237.065312 -51.627786) (xy 237.064959 -51.618769) (xy 237.058708 -51.601852)
			(xy 237.05312 -51.594766) (xy 237.052866 -51.594258) (xy 237.041923 -51.581523) (xy 237.022081 -51.554432)
			(xy 237.013242 -51.540156) (xy 237.007908 -51.531266) (xy 236.99089 -51.519074) (xy 236.897672 -51.498754)
			(xy 236.877098 -51.503072) (xy 236.868462 -51.508914) (xy 236.844411 -51.524934) (xy 236.792475 -51.550272)
			(xy 236.737313 -51.567492) (xy 236.680186 -51.576201) (xy 236.651292 -51.576732) (xy 236.624043 -51.576197)
			(xy 236.570099 -51.56844) (xy 236.517809 -51.553085) (xy 236.468236 -51.530445) (xy 236.42239 -51.500981)
			(xy 236.381203 -51.465291) (xy 236.345514 -51.424104) (xy 236.316051 -51.378257) (xy 236.293412 -51.328683)
			(xy 236.278058 -51.276393) (xy 236.270302 -51.222449) (xy 224.330467 -51.222449) (xy 223.898667 -51.654249)
			(xy 234.593902 -51.654249) (xy 234.593902 -51.599751) (xy 234.601658 -51.545807) (xy 234.617012 -51.493517)
			(xy 234.639651 -51.443943) (xy 234.669114 -51.398096) (xy 234.704803 -51.356909) (xy 234.74599 -51.321219)
			(xy 234.791836 -51.291755) (xy 234.841409 -51.269115) (xy 234.893699 -51.25376) (xy 234.947643 -51.246003)
			(xy 234.974892 -51.245516) (xy 235.001206 -51.245984) (xy 235.053335 -51.253218) (xy 235.103978 -51.267536)
			(xy 235.152177 -51.288669) (xy 235.19702 -51.316215) (xy 235.23766 -51.349654) (xy 235.255816 -51.368706)
			(xy 235.263329 -51.376117) (xy 235.282616 -51.384636) (xy 235.293154 -51.385216) (xy 235.36783 -51.385216)
			(xy 235.378376 -51.384658) (xy 235.397672 -51.376143) (xy 235.405168 -51.368706) (xy 235.423299 -51.349626)
			(xy 235.463934 -51.31617) (xy 235.508779 -51.288615) (xy 235.556985 -51.26748) (xy 235.607637 -51.253169)
			(xy 235.659774 -51.245951) (xy 235.686092 -51.245516) (xy 235.713347 -51.24593) (xy 235.767302 -51.253687)
			(xy 235.819604 -51.269043) (xy 235.869189 -51.291687) (xy 235.915046 -51.321156) (xy 235.956242 -51.356852)
			(xy 235.991939 -51.398048) (xy 236.021409 -51.443904) (xy 236.044054 -51.493488) (xy 236.059411 -51.54579)
			(xy 236.067169 -51.599745) (xy 236.067169 -51.654255) (xy 236.059411 -51.70821) (xy 236.044054 -51.760512)
			(xy 236.021409 -51.810096) (xy 235.991939 -51.855952) (xy 235.956242 -51.897148) (xy 235.915046 -51.932844)
			(xy 235.869189 -51.962313) (xy 235.819604 -51.984957) (xy 235.767302 -52.000313) (xy 235.713347 -52.00807)
			(xy 235.686092 -52.008532) (xy 235.659778 -52.00806) (xy 235.60765 -52.000824) (xy 235.557008 -51.986506)
			(xy 235.508809 -51.965374) (xy 235.463966 -51.937829) (xy 235.423325 -51.904393) (xy 235.405168 -51.885342)
			(xy 235.397654 -51.877931) (xy 235.378369 -51.869411) (xy 235.36783 -51.868832) (xy 235.293154 -51.868832)
			(xy 235.282605 -51.869367) (xy 235.263309 -51.877897) (xy 235.255816 -51.885342) (xy 235.237654 -51.904391)
			(xy 235.197025 -51.937847) (xy 235.152185 -51.965406) (xy 235.103986 -51.986545) (xy 235.05334 -52.000864)
			(xy 235.001208 -52.008092) (xy 234.974892 -52.008532) (xy 234.947643 -52.007997) (xy 234.893699 -52.00024)
			(xy 234.841409 -51.984885) (xy 234.791836 -51.962245) (xy 234.74599 -51.932781) (xy 234.704803 -51.897091)
			(xy 234.669114 -51.855904) (xy 234.639651 -51.810057) (xy 234.617012 -51.760483) (xy 234.601658 -51.708193)
			(xy 234.593902 -51.654249) (xy 223.898667 -51.654249) (xy 223.17583 -52.377086) (xy 223.153104 -52.399094)
			(xy 223.102906 -52.437596) (xy 223.048114 -52.46922) (xy 222.989663 -52.493423) (xy 222.928554 -52.509792)
			(xy 222.865832 -52.518047) (xy 222.8342 -52.518564) (xy 221.42323 -52.518564) (xy 221.391594 -52.518159)
			(xy 221.328862 -52.509904) (xy 221.267745 -52.493531) (xy 221.209287 -52.46932) (xy 221.15449 -52.437686)
			(xy 221.104292 -52.39917) (xy 221.05955 -52.354431) (xy 221.021031 -52.304235) (xy 220.989393 -52.24944)
			(xy 220.965179 -52.190984) (xy 220.948802 -52.129867) (xy 220.940543 -52.067136) (xy 220.940543 -52.003864)
			(xy 220.948802 -51.941133) (xy 220.965179 -51.880016) (xy 220.989393 -51.82156) (xy 221.021031 -51.766765)
			(xy 221.05955 -51.716569) (xy 221.104292 -51.67183) (xy 221.15449 -51.633314) (xy 221.209287 -51.60168)
			(xy 221.267745 -51.577469) (xy 221.328862 -51.561096) (xy 221.391594 -51.552841) (xy 221.42323 -51.552348)
			(xy 222.612966 -51.552348) (xy 222.623035 -51.551919) (xy 222.641634 -51.544202) (xy 222.649034 -51.537362)
			(xy 223.669606 -50.51679) (xy 223.676444 -50.509388) (xy 223.684165 -50.49079) (xy 223.684592 -50.480722)
			(xy 223.684592 -45.621194) (xy 223.684172 -45.611124) (xy 223.676448 -45.592526) (xy 223.669606 -45.585126)
			(xy 223.455484 -45.37075) (xy 223.448078 -45.363917) (xy 223.429484 -45.356192) (xy 223.419416 -45.355764)
			(xy 221.415102 -45.355764) (xy 221.383487 -45.35525) (xy 221.320798 -45.346997) (xy 221.259723 -45.330632)
			(xy 221.201306 -45.306435) (xy 221.146547 -45.27482) (xy 221.096383 -45.236328) (xy 221.051673 -45.191618)
			(xy 221.013181 -45.141455) (xy 220.981566 -45.086696) (xy 220.957369 -45.028279) (xy 220.941004 -44.967204)
			(xy 220.93275 -44.904515) (xy 214.865383 -44.904515) (xy 214.880589 -44.927498) (xy 214.904261 -44.977995)
			(xy 214.920329 -45.031402) (xy 214.928449 -45.086578) (xy 214.928958 -45.114464) (xy 214.928449 -45.14235)
			(xy 214.920329 -45.197526) (xy 214.904261 -45.250933) (xy 214.880589 -45.30143) (xy 214.849816 -45.347943)
			(xy 214.844174 -45.35424) (xy 218.803726 -45.35424) (xy 218.807797 -45.298618) (xy 218.819923 -45.244181)
			(xy 218.839846 -45.19209) (xy 218.867142 -45.143455) (xy 218.901228 -45.099312) (xy 218.941377 -45.060603)
			(xy 218.986735 -45.028152) (xy 219.036335 -45.002651) (xy 219.089119 -44.984644) (xy 219.143962 -44.974514)
			(xy 219.199696 -44.972477) (xy 219.255133 -44.978577) (xy 219.30909 -44.992683) (xy 219.360419 -45.014495)
			(xy 219.408025 -45.043549) (xy 219.450893 -45.079224) (xy 219.48811 -45.120761) (xy 219.518883 -45.167274)
			(xy 219.542555 -45.217771) (xy 219.558623 -45.271178) (xy 219.566743 -45.326354) (xy 219.567252 -45.35424)
			(xy 219.566743 -45.382126) (xy 219.558623 -45.437302) (xy 219.542555 -45.490709) (xy 219.518883 -45.541206)
			(xy 219.48811 -45.587719) (xy 219.450893 -45.629256) (xy 219.408025 -45.664931) (xy 219.360419 -45.693985)
			(xy 219.30909 -45.715797) (xy 219.255133 -45.729903) (xy 219.199696 -45.736003) (xy 219.143962 -45.733966)
			(xy 219.089119 -45.723836) (xy 219.036335 -45.705829) (xy 218.986735 -45.680328) (xy 218.941377 -45.647877)
			(xy 218.901228 -45.609168) (xy 218.867142 -45.565025) (xy 218.839846 -45.51639) (xy 218.819923 -45.464299)
			(xy 218.807797 -45.409862) (xy 218.803726 -45.35424) (xy 214.844174 -45.35424) (xy 214.812599 -45.38948)
			(xy 214.769731 -45.425155) (xy 214.722125 -45.454209) (xy 214.670796 -45.476021) (xy 214.616839 -45.490127)
			(xy 214.561402 -45.496227) (xy 214.505668 -45.49419) (xy 214.450825 -45.48406) (xy 214.398041 -45.466053)
			(xy 214.348441 -45.440552) (xy 214.303083 -45.408101) (xy 214.262934 -45.369392) (xy 214.228848 -45.325249)
			(xy 214.201552 -45.276614) (xy 214.181629 -45.224523) (xy 214.169503 -45.170086) (xy 214.165432 -45.114464)
			(xy 206.571895 -45.114464) (xy 206.537397 -46.082204) (xy 212.152484 -46.082204) (xy 212.152981 -46.054953)
			(xy 212.160737 -46.001006) (xy 212.176091 -45.948712) (xy 212.198732 -45.899136) (xy 212.228197 -45.853286)
			(xy 212.263887 -45.812095) (xy 212.305076 -45.776404) (xy 212.350925 -45.746937) (xy 212.400501 -45.724296)
			(xy 212.452795 -45.70894) (xy 212.506741 -45.701182) (xy 212.533992 -45.700696) (xy 212.560894 -45.701164)
			(xy 212.614164 -45.708735) (xy 212.665842 -45.723713) (xy 212.714904 -45.745802) (xy 212.760376 -45.774564)
			(xy 212.801358 -45.809428) (xy 212.837036 -45.849703) (xy 212.852254 -45.871892) (xy 212.859366 -45.882814)
			(xy 212.882226 -45.894752) (xy 212.994494 -45.89272) (xy 213.016846 -45.879766) (xy 213.023704 -45.86859)
			(xy 213.038636 -45.844996) (xy 213.074314 -45.802044) (xy 213.11587 -45.764751) (xy 213.162418 -45.733912)
			(xy 213.212964 -45.710188) (xy 213.266428 -45.694083) (xy 213.321668 -45.685943) (xy 213.349586 -45.685456)
			(xy 213.376579 -45.685925) (xy 213.430027 -45.693529) (xy 213.48187 -45.708588) (xy 213.531075 -45.7308)
			(xy 213.576659 -45.759723) (xy 213.59749 -45.776896) (xy 213.605618 -45.784008) (xy 213.626192 -45.790104)
			(xy 213.711536 -45.779182) (xy 213.722087 -45.777435) (xy 213.740367 -45.766361) (xy 213.746842 -45.757846)
			(xy 213.762176 -45.736601) (xy 213.797766 -45.698148) (xy 213.838287 -45.664931) (xy 213.882973 -45.637574)
			(xy 213.930984 -45.616593) (xy 213.981416 -45.602383) (xy 214.033318 -45.595211) (xy 214.059516 -45.594778)
			(xy 214.086765 -45.595293) (xy 214.140709 -45.603051) (xy 214.193 -45.618407) (xy 214.242574 -45.641049)
			(xy 214.28842 -45.670514) (xy 214.329607 -45.706204) (xy 214.365295 -45.747393) (xy 214.394759 -45.79324)
			(xy 214.417398 -45.842815) (xy 214.432752 -45.895106) (xy 214.440508 -45.949051) (xy 214.440508 -46.003549)
			(xy 214.432752 -46.057494) (xy 214.417398 -46.109785) (xy 214.394759 -46.15936) (xy 214.365295 -46.205207)
			(xy 214.329607 -46.246396) (xy 214.28842 -46.282086) (xy 214.242574 -46.311551) (xy 214.193 -46.334193)
			(xy 214.140709 -46.349549) (xy 214.086765 -46.357307) (xy 214.059516 -46.357794) (xy 214.032524 -46.357312)
			(xy 213.979077 -46.349709) (xy 213.927234 -46.334653) (xy 213.878029 -46.312444) (xy 213.832444 -46.283525)
			(xy 213.811612 -46.266354) (xy 213.803484 -46.259242) (xy 213.78291 -46.253146) (xy 213.697566 -46.264068)
			(xy 213.68702 -46.265833) (xy 213.668739 -46.276896) (xy 213.66226 -46.285404) (xy 213.644649 -46.309706)
			(xy 213.603052 -46.352965) (xy 213.579456 -46.37151) (xy 213.571582 -46.377352) (xy 213.561168 -46.394878)
			(xy 213.54796 -46.485302) (xy 213.552786 -46.504606) (xy 213.558628 -46.51248) (xy 213.558628 -46.512734)
			(xy 213.576125 -46.537482) (xy 213.603931 -46.591333) (xy 213.622869 -46.648904) (xy 213.630072 -46.693836)
			(xy 218.776296 -46.693836) (xy 218.776782 -46.666585) (xy 218.784538 -46.612637) (xy 218.799893 -46.560342)
			(xy 218.822535 -46.510765) (xy 218.852001 -46.464915) (xy 218.887692 -46.423724) (xy 218.928883 -46.388033)
			(xy 218.974733 -46.358567) (xy 219.02431 -46.335925) (xy 219.076605 -46.32057) (xy 219.130553 -46.312814)
			(xy 219.185055 -46.312814) (xy 219.239003 -46.32057) (xy 219.291298 -46.335925) (xy 219.340875 -46.358567)
			(xy 219.386725 -46.388033) (xy 219.427916 -46.423724) (xy 219.463607 -46.464915) (xy 219.493073 -46.510765)
			(xy 219.515715 -46.560342) (xy 219.53107 -46.612637) (xy 219.538826 -46.666585) (xy 219.539312 -46.693836)
			(xy 219.538838 -46.720263) (xy 219.531528 -46.772611) (xy 219.517056 -46.823446) (xy 219.495696 -46.871793)
			(xy 219.482162 -46.894496) (xy 219.481908 -46.89475) (xy 219.476571 -46.904768) (xy 219.474316 -46.927318)
			(xy 219.47759 -46.938184) (xy 219.503752 -47.01286) (xy 219.508136 -47.023375) (xy 219.524225 -47.039464)
			(xy 219.53474 -47.043848) (xy 219.534994 -47.043848) (xy 219.559513 -47.052891) (xy 219.605964 -47.076839)
			(xy 219.648715 -47.106899) (xy 219.686965 -47.142511) (xy 219.72 -47.183007) (xy 219.747202 -47.227631)
			(xy 219.768063 -47.275548) (xy 219.782192 -47.325863) (xy 219.789325 -47.377635) (xy 219.789756 -47.403766)
			(xy 219.78927 -47.431017) (xy 219.787747 -47.441612) (xy 221.061786 -47.441612) (xy 221.065857 -47.38599)
			(xy 221.077983 -47.331553) (xy 221.097906 -47.279462) (xy 221.125202 -47.230827) (xy 221.159288 -47.186684)
			(xy 221.199437 -47.147975) (xy 221.244795 -47.115524) (xy 221.294395 -47.090023) (xy 221.347179 -47.072016)
			(xy 221.402022 -47.061886) (xy 221.457756 -47.059849) (xy 221.513193 -47.065949) (xy 221.56715 -47.080055)
			(xy 221.618479 -47.101867) (xy 221.666085 -47.130921) (xy 221.708953 -47.166596) (xy 221.74617 -47.208133)
			(xy 221.776943 -47.254646) (xy 221.800615 -47.305143) (xy 221.816683 -47.35855) (xy 221.824803 -47.413726)
			(xy 221.825312 -47.441612) (xy 221.824803 -47.469498) (xy 221.816683 -47.524674) (xy 221.800615 -47.578081)
			(xy 221.776943 -47.628578) (xy 221.74617 -47.675091) (xy 221.708953 -47.716628) (xy 221.666085 -47.752303)
			(xy 221.618479 -47.781357) (xy 221.56715 -47.803169) (xy 221.513193 -47.817275) (xy 221.457756 -47.823375)
			(xy 221.402022 -47.821338) (xy 221.347179 -47.811208) (xy 221.294395 -47.793201) (xy 221.244795 -47.7677)
			(xy 221.199437 -47.735249) (xy 221.159288 -47.69654) (xy 221.125202 -47.652397) (xy 221.097906 -47.603762)
			(xy 221.077983 -47.551671) (xy 221.065857 -47.497234) (xy 221.061786 -47.441612) (xy 219.787747 -47.441612)
			(xy 219.781514 -47.484965) (xy 219.766159 -47.53726) (xy 219.743517 -47.586837) (xy 219.714051 -47.632687)
			(xy 219.67836 -47.673878) (xy 219.637169 -47.709569) (xy 219.591319 -47.739035) (xy 219.541742 -47.761677)
			(xy 219.489447 -47.777032) (xy 219.435499 -47.784788) (xy 219.380997 -47.784788) (xy 219.327049 -47.777032)
			(xy 219.274754 -47.761677) (xy 219.225177 -47.739035) (xy 219.179327 -47.709569) (xy 219.138136 -47.673878)
			(xy 219.102445 -47.632687) (xy 219.072979 -47.586837) (xy 219.050337 -47.53726) (xy 219.034982 -47.484965)
			(xy 219.027226 -47.431017) (xy 219.02674 -47.403766) (xy 219.027208 -47.377338) (xy 219.034518 -47.324991)
			(xy 219.048993 -47.274155) (xy 219.070354 -47.225809) (xy 219.08389 -47.203106) (xy 219.084144 -47.202852)
			(xy 219.089479 -47.192833) (xy 219.091738 -47.170284) (xy 219.088462 -47.159418) (xy 219.0623 -47.084742)
			(xy 219.057937 -47.074216) (xy 219.041834 -47.058131) (xy 219.031312 -47.053754) (xy 219.031058 -47.053754)
			(xy 219.006551 -47.04468) (xy 218.960098 -47.020739) (xy 218.917346 -46.990683) (xy 218.879094 -46.955077)
			(xy 218.846057 -46.914584) (xy 218.818854 -46.869964) (xy 218.797991 -46.822049) (xy 218.783861 -46.771736)
			(xy 218.776727 -46.719966) (xy 218.776296 -46.693836) (xy 213.630072 -46.693836) (xy 213.632462 -46.708745)
			(xy 213.63305 -46.739048) (xy 213.632567 -46.766299) (xy 213.624805 -46.820244) (xy 213.609446 -46.872536)
			(xy 213.586802 -46.922111) (xy 213.557335 -46.967959) (xy 213.521643 -47.009148) (xy 213.480454 -47.044838)
			(xy 213.434606 -47.074305) (xy 213.385031 -47.096948) (xy 213.332738 -47.112306) (xy 213.278793 -47.120067)
			(xy 213.251542 -47.120556) (xy 213.225508 -47.120134) (xy 213.173924 -47.11304) (xy 213.123782 -47.099005)
			(xy 213.076011 -47.078288) (xy 213.031498 -47.051275) (xy 213.011004 -47.035212) (xy 213.003253 -47.029461)
			(xy 212.984838 -47.023726) (xy 212.97519 -47.024036) (xy 212.895434 -47.030386) (xy 212.877654 -47.039022)
			(xy 212.871304 -47.046388) (xy 212.853144 -47.066054) (xy 212.812232 -47.100574) (xy 212.766898 -47.129041)
			(xy 212.718033 -47.150895) (xy 212.666593 -47.165708) (xy 212.613589 -47.17319) (xy 212.586824 -47.173642)
			(xy 212.559575 -47.1731) (xy 212.505631 -47.165347) (xy 212.453339 -47.149997) (xy 212.403765 -47.127361)
			(xy 212.357916 -47.0979) (xy 212.316726 -47.062215) (xy 212.281034 -47.021031) (xy 212.251567 -46.975186)
			(xy 212.228923 -46.925615) (xy 212.213565 -46.873326) (xy 212.205805 -46.819383) (xy 212.205316 -46.792134)
			(xy 212.205836 -46.76336) (xy 212.214488 -46.706465) (xy 212.231585 -46.651515) (xy 212.256739 -46.599754)
			(xy 212.289381 -46.552359) (xy 212.308694 -46.531022) (xy 212.31606 -46.523148) (xy 212.323172 -46.503336)
			(xy 212.315806 -46.40707) (xy 212.3059 -46.388274) (xy 212.297518 -46.38167) (xy 212.275333 -46.363446)
			(xy 212.236123 -46.32151) (xy 212.203638 -46.274174) (xy 212.178609 -46.222506) (xy 212.161603 -46.167672)
			(xy 212.153002 -46.110909) (xy 212.152484 -46.082204) (xy 206.537397 -46.082204) (xy 206.458086 -48.30699)
			(xy 218.653866 -48.30699) (xy 218.657937 -48.251368) (xy 218.670063 -48.196931) (xy 218.689986 -48.14484)
			(xy 218.717282 -48.096205) (xy 218.751368 -48.052062) (xy 218.791517 -48.013353) (xy 218.836875 -47.980902)
			(xy 218.886475 -47.955401) (xy 218.939259 -47.937394) (xy 218.994102 -47.927264) (xy 219.049836 -47.925227)
			(xy 219.105273 -47.931327) (xy 219.15923 -47.945433) (xy 219.210559 -47.967245) (xy 219.258165 -47.996299)
			(xy 219.301033 -48.031974) (xy 219.33825 -48.073511) (xy 219.369023 -48.120024) (xy 219.392695 -48.170521)
			(xy 219.408763 -48.223928) (xy 219.416883 -48.279104) (xy 219.417392 -48.30699) (xy 219.416883 -48.334876)
			(xy 219.408763 -48.390052) (xy 219.392695 -48.443459) (xy 219.369023 -48.493956) (xy 219.33825 -48.540469)
			(xy 219.301033 -48.582006) (xy 219.258165 -48.617681) (xy 219.210559 -48.646735) (xy 219.15923 -48.668547)
			(xy 219.105273 -48.682653) (xy 219.049836 -48.688753) (xy 218.994102 -48.686716) (xy 218.939259 -48.676586)
			(xy 218.886475 -48.658579) (xy 218.836875 -48.633078) (xy 218.791517 -48.600627) (xy 218.751368 -48.561918)
			(xy 218.717282 -48.517775) (xy 218.689986 -48.46914) (xy 218.670063 -48.417049) (xy 218.657937 -48.362612)
			(xy 218.653866 -48.30699) (xy 206.458086 -48.30699) (xy 206.442186 -48.753014) (xy 215.2683 -48.753014)
			(xy 215.272371 -48.697392) (xy 215.284497 -48.642955) (xy 215.30442 -48.590864) (xy 215.331716 -48.542229)
			(xy 215.365802 -48.498086) (xy 215.405951 -48.459377) (xy 215.451309 -48.426926) (xy 215.500909 -48.401425)
			(xy 215.553693 -48.383418) (xy 215.608536 -48.373288) (xy 215.66427 -48.371251) (xy 215.719707 -48.377351)
			(xy 215.773664 -48.391457) (xy 215.824993 -48.413269) (xy 215.872599 -48.442323) (xy 215.915467 -48.477998)
			(xy 215.952684 -48.519535) (xy 215.983457 -48.566048) (xy 216.007129 -48.616545) (xy 216.023197 -48.669952)
			(xy 216.031317 -48.725128) (xy 216.031826 -48.753014) (xy 216.031317 -48.7809) (xy 216.023197 -48.836076)
			(xy 216.020753 -48.8442) (xy 216.287348 -48.8442) (xy 216.291419 -48.788578) (xy 216.303545 -48.734141)
			(xy 216.323468 -48.68205) (xy 216.350764 -48.633415) (xy 216.38485 -48.589272) (xy 216.424999 -48.550563)
			(xy 216.470357 -48.518112) (xy 216.519957 -48.492611) (xy 216.572741 -48.474604) (xy 216.627584 -48.464474)
			(xy 216.683318 -48.462437) (xy 216.738755 -48.468537) (xy 216.792712 -48.482643) (xy 216.844041 -48.504455)
			(xy 216.891647 -48.533509) (xy 216.934515 -48.569184) (xy 216.971732 -48.610721) (xy 217.002505 -48.657234)
			(xy 217.026177 -48.707731) (xy 217.042245 -48.761138) (xy 217.050365 -48.816314) (xy 217.050874 -48.8442)
			(xy 217.050365 -48.872086) (xy 217.047367 -48.89246) (xy 217.314016 -48.89246) (xy 217.318087 -48.836838)
			(xy 217.330213 -48.782401) (xy 217.350136 -48.73031) (xy 217.377432 -48.681675) (xy 217.411518 -48.637532)
			(xy 217.451667 -48.598823) (xy 217.497025 -48.566372) (xy 217.546625 -48.540871) (xy 217.599409 -48.522864)
			(xy 217.654252 -48.512734) (xy 217.709986 -48.510697) (xy 217.765423 -48.516797) (xy 217.81938 -48.530903)
			(xy 217.870709 -48.552715) (xy 217.918315 -48.581769) (xy 217.961183 -48.617444) (xy 217.9984 -48.658981)
			(xy 218.029173 -48.705494) (xy 218.052845 -48.755991) (xy 218.068913 -48.809398) (xy 218.077033 -48.864574)
			(xy 218.077542 -48.89246) (xy 218.077033 -48.920346) (xy 218.074595 -48.93691) (xy 221.033084 -48.93691)
			(xy 221.037155 -48.881288) (xy 221.049281 -48.826851) (xy 221.069204 -48.77476) (xy 221.0965 -48.726125)
			(xy 221.130586 -48.681982) (xy 221.170735 -48.643273) (xy 221.216093 -48.610822) (xy 221.265693 -48.585321)
			(xy 221.318477 -48.567314) (xy 221.37332 -48.557184) (xy 221.429054 -48.555147) (xy 221.484491 -48.561247)
			(xy 221.538448 -48.575353) (xy 221.589777 -48.597165) (xy 221.637383 -48.626219) (xy 221.680251 -48.661894)
			(xy 221.717468 -48.703431) (xy 221.748241 -48.749944) (xy 221.771913 -48.800441) (xy 221.787981 -48.853848)
			(xy 221.796101 -48.909024) (xy 221.79661 -48.93691) (xy 221.796101 -48.964796) (xy 221.787981 -49.019972)
			(xy 221.771913 -49.073379) (xy 221.748241 -49.123876) (xy 221.717468 -49.170389) (xy 221.680251 -49.211926)
			(xy 221.637383 -49.247601) (xy 221.589777 -49.276655) (xy 221.538448 -49.298467) (xy 221.484491 -49.312573)
			(xy 221.429054 -49.318673) (xy 221.37332 -49.316636) (xy 221.318477 -49.306506) (xy 221.265693 -49.288499)
			(xy 221.216093 -49.262998) (xy 221.170735 -49.230547) (xy 221.130586 -49.191838) (xy 221.0965 -49.147695)
			(xy 221.069204 -49.09906) (xy 221.049281 -49.046969) (xy 221.037155 -48.992532) (xy 221.033084 -48.93691)
			(xy 218.074595 -48.93691) (xy 218.068913 -48.975522) (xy 218.052845 -49.028929) (xy 218.029173 -49.079426)
			(xy 217.9984 -49.125939) (xy 217.961183 -49.167476) (xy 217.918315 -49.203151) (xy 217.870709 -49.232205)
			(xy 217.81938 -49.254017) (xy 217.765423 -49.268123) (xy 217.709986 -49.274223) (xy 217.654252 -49.272186)
			(xy 217.599409 -49.262056) (xy 217.546625 -49.244049) (xy 217.497025 -49.218548) (xy 217.451667 -49.186097)
			(xy 217.411518 -49.147388) (xy 217.377432 -49.103245) (xy 217.350136 -49.05461) (xy 217.330213 -49.002519)
			(xy 217.318087 -48.948082) (xy 217.314016 -48.89246) (xy 217.047367 -48.89246) (xy 217.042245 -48.927262)
			(xy 217.026177 -48.980669) (xy 217.002505 -49.031166) (xy 216.971732 -49.077679) (xy 216.934515 -49.119216)
			(xy 216.891647 -49.154891) (xy 216.844041 -49.183945) (xy 216.792712 -49.205757) (xy 216.738755 -49.219863)
			(xy 216.683318 -49.225963) (xy 216.627584 -49.223926) (xy 216.572741 -49.213796) (xy 216.519957 -49.195789)
			(xy 216.470357 -49.170288) (xy 216.424999 -49.137837) (xy 216.38485 -49.099128) (xy 216.350764 -49.054985)
			(xy 216.323468 -49.00635) (xy 216.303545 -48.954259) (xy 216.291419 -48.899822) (xy 216.287348 -48.8442)
			(xy 216.020753 -48.8442) (xy 216.007129 -48.889483) (xy 215.983457 -48.93998) (xy 215.952684 -48.986493)
			(xy 215.915467 -49.02803) (xy 215.872599 -49.063705) (xy 215.824993 -49.092759) (xy 215.773664 -49.114571)
			(xy 215.719707 -49.128677) (xy 215.66427 -49.134777) (xy 215.608536 -49.13274) (xy 215.553693 -49.12261)
			(xy 215.500909 -49.104603) (xy 215.451309 -49.079102) (xy 215.405951 -49.046651) (xy 215.365802 -49.007942)
			(xy 215.331716 -48.963799) (xy 215.30442 -48.915164) (xy 215.284497 -48.863073) (xy 215.272371 -48.808636)
			(xy 215.2683 -48.753014) (xy 206.442186 -48.753014) (xy 206.399412 -49.95291) (xy 221.033084 -49.95291)
			(xy 221.037155 -49.897288) (xy 221.049281 -49.842851) (xy 221.069204 -49.79076) (xy 221.0965 -49.742125)
			(xy 221.130586 -49.697982) (xy 221.170735 -49.659273) (xy 221.216093 -49.626822) (xy 221.265693 -49.601321)
			(xy 221.318477 -49.583314) (xy 221.37332 -49.573184) (xy 221.429054 -49.571147) (xy 221.484491 -49.577247)
			(xy 221.538448 -49.591353) (xy 221.589777 -49.613165) (xy 221.637383 -49.642219) (xy 221.680251 -49.677894)
			(xy 221.717468 -49.719431) (xy 221.748241 -49.765944) (xy 221.771913 -49.816441) (xy 221.787981 -49.869848)
			(xy 221.796101 -49.925024) (xy 221.79661 -49.95291) (xy 221.796101 -49.980796) (xy 221.787981 -50.035972)
			(xy 221.771913 -50.089379) (xy 221.748241 -50.139876) (xy 221.717468 -50.186389) (xy 221.680251 -50.227926)
			(xy 221.637383 -50.263601) (xy 221.589777 -50.292655) (xy 221.538448 -50.314467) (xy 221.484491 -50.328573)
			(xy 221.429054 -50.334673) (xy 221.37332 -50.332636) (xy 221.318477 -50.322506) (xy 221.265693 -50.304499)
			(xy 221.216093 -50.278998) (xy 221.170735 -50.246547) (xy 221.130586 -50.207838) (xy 221.0965 -50.163695)
			(xy 221.069204 -50.11506) (xy 221.049281 -50.062969) (xy 221.037155 -50.008532) (xy 221.033084 -49.95291)
			(xy 206.399412 -49.95291) (xy 206.384906 -50.359818) (xy 206.38516 -50.364898) (xy 206.424395 -51.019456)
			(xy 218.849446 -51.019456) (xy 218.853517 -50.963834) (xy 218.865643 -50.909397) (xy 218.885566 -50.857306)
			(xy 218.912862 -50.808671) (xy 218.946948 -50.764528) (xy 218.987097 -50.725819) (xy 219.032455 -50.693368)
			(xy 219.082055 -50.667867) (xy 219.134839 -50.64986) (xy 219.189682 -50.63973) (xy 219.245416 -50.637693)
			(xy 219.300853 -50.643793) (xy 219.35481 -50.657899) (xy 219.406139 -50.679711) (xy 219.453745 -50.708765)
			(xy 219.496613 -50.74444) (xy 219.53383 -50.785977) (xy 219.564603 -50.83249) (xy 219.588275 -50.882987)
			(xy 219.604343 -50.936394) (xy 219.612463 -50.99157) (xy 219.612972 -51.019456) (xy 219.612463 -51.047342)
			(xy 219.604343 -51.102518) (xy 219.588275 -51.155925) (xy 219.564603 -51.206422) (xy 219.53383 -51.252935)
			(xy 219.496613 -51.294472) (xy 219.453745 -51.330147) (xy 219.406139 -51.359201) (xy 219.35481 -51.381013)
			(xy 219.300853 -51.395119) (xy 219.245416 -51.401219) (xy 219.189682 -51.399182) (xy 219.134839 -51.389052)
			(xy 219.082055 -51.371045) (xy 219.032455 -51.345544) (xy 218.987097 -51.313093) (xy 218.946948 -51.274384)
			(xy 218.912862 -51.230241) (xy 218.885566 -51.181606) (xy 218.865643 -51.129515) (xy 218.853517 -51.075078)
			(xy 218.849446 -51.019456) (xy 206.424395 -51.019456) (xy 206.646892 -54.731412) (xy 207.620616 -54.731412)
			(xy 207.621085 -54.704042) (xy 207.628902 -54.649863) (xy 207.64439 -54.597359) (xy 207.667231 -54.547613)
			(xy 207.696955 -54.501646) (xy 207.714596 -54.480714) (xy 207.71485 -54.48046) (xy 207.720424 -54.473365)
			(xy 207.726677 -54.456454) (xy 207.727042 -54.44744) (xy 207.727042 -54.380384) (xy 207.726705 -54.371365)
			(xy 207.720445 -54.354447) (xy 207.71485 -54.347364) (xy 207.714596 -54.347364) (xy 207.714596 -54.34711)
			(xy 207.696968 -54.326167) (xy 207.667245 -54.2802) (xy 207.644401 -54.230456) (xy 207.628905 -54.177955)
			(xy 207.621076 -54.123779) (xy 207.621075 -54.069039) (xy 207.628902 -54.014862) (xy 207.644395 -53.962361)
			(xy 207.667237 -53.912616) (xy 207.696957 -53.866647) (xy 207.714596 -53.845714) (xy 207.71485 -53.84546)
			(xy 207.720424 -53.838365) (xy 207.726677 -53.821454) (xy 207.727042 -53.81244) (xy 207.727042 -53.745384)
			(xy 207.726705 -53.736365) (xy 207.720445 -53.719447) (xy 207.71485 -53.712364) (xy 207.714596 -53.712364)
			(xy 207.714596 -53.71211) (xy 207.696968 -53.691167) (xy 207.667245 -53.6452) (xy 207.644401 -53.595456)
			(xy 207.628905 -53.542955) (xy 207.621076 -53.488779) (xy 207.621075 -53.434039) (xy 207.628902 -53.379862)
			(xy 207.644395 -53.327361) (xy 207.667237 -53.277616) (xy 207.696957 -53.231647) (xy 207.714596 -53.210714)
			(xy 207.71485 -53.21046) (xy 207.720424 -53.203365) (xy 207.726677 -53.186454) (xy 207.727042 -53.17744)
			(xy 207.727042 -53.110384) (xy 207.726705 -53.101365) (xy 207.720445 -53.084447) (xy 207.71485 -53.077364)
			(xy 207.714596 -53.077364) (xy 207.714596 -53.07711) (xy 207.696948 -53.056186) (xy 207.667237 -53.010211)
			(xy 207.644403 -52.960461) (xy 207.628914 -52.907959) (xy 207.621089 -52.853782) (xy 207.620616 -52.826412)
			(xy 207.621102 -52.799161) (xy 207.628858 -52.745213) (xy 207.644213 -52.692918) (xy 207.666855 -52.643341)
			(xy 207.696321 -52.597491) (xy 207.732012 -52.5563) (xy 207.773203 -52.520609) (xy 207.819053 -52.491143)
			(xy 207.86863 -52.468501) (xy 207.920925 -52.453146) (xy 207.974873 -52.44539) (xy 208.029375 -52.44539)
			(xy 208.083323 -52.453146) (xy 208.135618 -52.468501) (xy 208.185195 -52.491143) (xy 208.231045 -52.520609)
			(xy 208.272236 -52.5563) (xy 208.307927 -52.597491) (xy 208.337393 -52.643341) (xy 208.360035 -52.692918)
			(xy 208.37539 -52.745213) (xy 208.383146 -52.799161) (xy 208.383632 -52.826412) (xy 208.38319 -52.853783)
			(xy 208.375369 -52.907964) (xy 208.359875 -52.960468) (xy 208.337027 -53.010215) (xy 208.307297 -53.05618)
			(xy 208.289652 -53.07711) (xy 208.289398 -53.077364) (xy 208.28382 -53.084457) (xy 208.277568 -53.101369)
			(xy 208.277206 -53.110384) (xy 208.277206 -53.17744) (xy 208.277543 -53.186459) (xy 208.283804 -53.203376)
			(xy 208.289398 -53.21046) (xy 208.289652 -53.21046) (xy 208.289652 -53.210714) (xy 208.307305 -53.231637)
			(xy 208.337031 -53.277606) (xy 208.359877 -53.327354) (xy 208.375373 -53.379857) (xy 208.383201 -53.434038)
			(xy 208.3832 -53.48878) (xy 208.37537 -53.54296) (xy 208.359871 -53.595463) (xy 208.337023 -53.64521)
			(xy 208.307294 -53.691178) (xy 208.289652 -53.71211) (xy 208.289398 -53.712364) (xy 208.28382 -53.719457)
			(xy 208.277568 -53.736369) (xy 208.277206 -53.745384) (xy 208.277206 -53.81244) (xy 208.277543 -53.821459)
			(xy 208.283804 -53.838376) (xy 208.289398 -53.84546) (xy 208.289652 -53.84546) (xy 208.289652 -53.845714)
			(xy 208.307305 -53.866637) (xy 208.337031 -53.912606) (xy 208.359877 -53.962354) (xy 208.375373 -54.014857)
			(xy 208.383201 -54.069038) (xy 208.3832 -54.12378) (xy 208.37537 -54.17796) (xy 208.359871 -54.230463)
			(xy 208.337023 -54.28021) (xy 208.307294 -54.326178) (xy 208.289652 -54.34711) (xy 208.289398 -54.347364)
			(xy 208.28382 -54.354457) (xy 208.277568 -54.371369) (xy 208.277206 -54.380384) (xy 208.277206 -54.44744)
			(xy 208.277543 -54.456459) (xy 208.283804 -54.473376) (xy 208.289398 -54.48046) (xy 208.289652 -54.48046)
			(xy 208.289652 -54.480714) (xy 208.307257 -54.501674) (xy 208.336975 -54.547638) (xy 208.359819 -54.597379)
			(xy 208.375318 -54.649873) (xy 208.383154 -54.704045) (xy 208.383632 -54.731412) (xy 208.383146 -54.758663)
			(xy 208.378482 -54.791102) (xy 210.27644 -54.791102) (xy 210.276897 -54.763731) (xy 210.284716 -54.709552)
			(xy 210.300206 -54.657048) (xy 210.32305 -54.607301) (xy 210.352777 -54.561335) (xy 210.37042 -54.540404)
			(xy 210.370674 -54.54015) (xy 210.376254 -54.53306) (xy 210.382503 -54.516145) (xy 210.382866 -54.50713)
			(xy 210.382866 -54.440074) (xy 210.382529 -54.431055) (xy 210.376268 -54.414138) (xy 210.370674 -54.407054)
			(xy 210.37042 -54.407054) (xy 210.37042 -54.4068) (xy 210.352782 -54.385866) (xy 210.323057 -54.339898)
			(xy 210.300212 -54.290152) (xy 210.284716 -54.23765) (xy 210.276887 -54.183472) (xy 210.276887 -54.128731)
			(xy 210.284715 -54.074553) (xy 210.300211 -54.022051) (xy 210.323056 -53.972305) (xy 210.35278 -53.926337)
			(xy 210.37042 -53.905404) (xy 210.370674 -53.90515) (xy 210.376254 -53.89806) (xy 210.382503 -53.881145)
			(xy 210.382866 -53.87213) (xy 210.382866 -53.805074) (xy 210.382529 -53.796055) (xy 210.376268 -53.779138)
			(xy 210.370674 -53.772054) (xy 210.37042 -53.772054) (xy 210.37042 -53.7718) (xy 210.352782 -53.750866)
			(xy 210.323057 -53.704898) (xy 210.300212 -53.655152) (xy 210.284716 -53.60265) (xy 210.276887 -53.548472)
			(xy 210.276887 -53.493731) (xy 210.284715 -53.439553) (xy 210.300211 -53.387051) (xy 210.323056 -53.337305)
			(xy 210.35278 -53.291337) (xy 210.37042 -53.270404) (xy 210.370674 -53.27015) (xy 210.376254 -53.26306)
			(xy 210.382503 -53.246145) (xy 210.382866 -53.23713) (xy 210.382866 -53.170074) (xy 210.382529 -53.161055)
			(xy 210.376268 -53.144138) (xy 210.370674 -53.137054) (xy 210.37042 -53.137054) (xy 210.37042 -53.1368)
			(xy 210.352771 -53.115876) (xy 210.32306 -53.069901) (xy 210.300225 -53.020152) (xy 210.284737 -52.967649)
			(xy 210.276912 -52.913472) (xy 210.27644 -52.886102) (xy 210.276926 -52.858851) (xy 210.284682 -52.804903)
			(xy 210.300037 -52.752608) (xy 210.322679 -52.703031) (xy 210.352145 -52.657181) (xy 210.387836 -52.61599)
			(xy 210.429027 -52.580299) (xy 210.474877 -52.550833) (xy 210.524454 -52.528191) (xy 210.576749 -52.512836)
			(xy 210.630697 -52.50508) (xy 210.685199 -52.50508) (xy 210.739147 -52.512836) (xy 210.791442 -52.528191)
			(xy 210.830551 -52.546052) (xy 215.779573 -52.546052) (xy 215.779573 -52.491548) (xy 215.78733 -52.4376)
			(xy 215.802686 -52.385304) (xy 215.825327 -52.335726) (xy 215.854794 -52.289875) (xy 215.890487 -52.248684)
			(xy 215.931678 -52.212992) (xy 215.977529 -52.183525) (xy 216.027108 -52.160884) (xy 216.079403 -52.145529)
			(xy 216.133352 -52.137773) (xy 216.160604 -52.13731) (xy 216.187974 -52.137771) (xy 216.242154 -52.14559)
			(xy 216.294657 -52.16108) (xy 216.344404 -52.183923) (xy 216.39037 -52.213648) (xy 216.411302 -52.23129)
			(xy 216.411556 -52.231544) (xy 216.418647 -52.237124) (xy 216.435561 -52.243373) (xy 216.444576 -52.243736)
			(xy 216.511632 -52.243736) (xy 216.520649 -52.243387) (xy 216.537566 -52.237133) (xy 216.544652 -52.231544)
			(xy 216.544652 -52.23129) (xy 216.544906 -52.23129) (xy 216.565839 -52.213649) (xy 216.611807 -52.183925)
			(xy 216.661553 -52.161079) (xy 216.714055 -52.145583) (xy 216.768233 -52.137754) (xy 216.822975 -52.137754)
			(xy 216.877153 -52.145583) (xy 216.929655 -52.161079) (xy 216.979401 -52.183925) (xy 217.025369 -52.213649)
			(xy 217.046302 -52.23129) (xy 217.046556 -52.231544) (xy 217.053647 -52.237124) (xy 217.070561 -52.243373)
			(xy 217.079576 -52.243736) (xy 217.146632 -52.243736) (xy 217.155649 -52.243387) (xy 217.172566 -52.237133)
			(xy 217.179652 -52.231544) (xy 217.179652 -52.23129) (xy 217.179906 -52.23129) (xy 217.200824 -52.213633)
			(xy 217.246801 -52.183924) (xy 217.296552 -52.161092) (xy 217.349056 -52.145605) (xy 217.403234 -52.137782)
			(xy 217.430604 -52.13731) (xy 217.457856 -52.13776) (xy 217.511806 -52.145517) (xy 217.564103 -52.160874)
			(xy 217.613682 -52.183516) (xy 217.659534 -52.212984) (xy 217.700726 -52.248677) (xy 217.736419 -52.289869)
			(xy 217.765886 -52.335722) (xy 217.788528 -52.385301) (xy 217.803883 -52.437598) (xy 217.81164 -52.491548)
			(xy 217.81164 -52.546052) (xy 217.805695 -52.587398) (xy 218.855288 -52.587398) (xy 218.859359 -52.531776)
			(xy 218.871485 -52.477339) (xy 218.891408 -52.425248) (xy 218.918704 -52.376613) (xy 218.95279 -52.33247)
			(xy 218.992939 -52.293761) (xy 219.038297 -52.26131) (xy 219.087897 -52.235809) (xy 219.140681 -52.217802)
			(xy 219.195524 -52.207672) (xy 219.251258 -52.205635) (xy 219.306695 -52.211735) (xy 219.360652 -52.225841)
			(xy 219.411981 -52.247653) (xy 219.459587 -52.276707) (xy 219.502455 -52.312382) (xy 219.539672 -52.353919)
			(xy 219.570445 -52.400432) (xy 219.594117 -52.450929) (xy 219.610185 -52.504336) (xy 219.618305 -52.559512)
			(xy 219.618814 -52.587398) (xy 219.618305 -52.615284) (xy 219.610185 -52.67046) (xy 219.594117 -52.723867)
			(xy 219.570445 -52.774364) (xy 219.539672 -52.820877) (xy 219.502455 -52.862414) (xy 219.459587 -52.898089)
			(xy 219.411981 -52.927143) (xy 219.360652 -52.948955) (xy 219.306695 -52.963061) (xy 219.251258 -52.969161)
			(xy 219.195524 -52.967124) (xy 219.140681 -52.956994) (xy 219.087897 -52.938987) (xy 219.038297 -52.913486)
			(xy 218.992939 -52.881035) (xy 218.95279 -52.842326) (xy 218.918704 -52.798183) (xy 218.891408 -52.749548)
			(xy 218.871485 -52.697457) (xy 218.859359 -52.64302) (xy 218.855288 -52.587398) (xy 217.805695 -52.587398)
			(xy 217.803883 -52.600002) (xy 217.788528 -52.652299) (xy 217.765886 -52.701878) (xy 217.736419 -52.747731)
			(xy 217.700726 -52.788923) (xy 217.659534 -52.824616) (xy 217.613682 -52.854084) (xy 217.564103 -52.876726)
			(xy 217.511806 -52.892083) (xy 217.457856 -52.89984) (xy 217.430604 -52.900326) (xy 217.403233 -52.899876)
			(xy 217.349053 -52.892057) (xy 217.296549 -52.876565) (xy 217.246802 -52.853719) (xy 217.200836 -52.82399)
			(xy 217.179906 -52.806346) (xy 217.179652 -52.806092) (xy 217.172555 -52.80052) (xy 217.155646 -52.794265)
			(xy 217.146632 -52.7939) (xy 217.079576 -52.7939) (xy 217.070558 -52.794246) (xy 217.053641 -52.800501)
			(xy 217.046556 -52.806092) (xy 217.046302 -52.806346) (xy 217.025369 -52.823987) (xy 216.979401 -52.853711)
			(xy 216.929655 -52.876557) (xy 216.877153 -52.892053) (xy 216.822975 -52.899882) (xy 216.768233 -52.899882)
			(xy 216.714055 -52.892053) (xy 216.661553 -52.876557) (xy 216.611807 -52.853711) (xy 216.565839 -52.823987)
			(xy 216.544906 -52.806346) (xy 216.544652 -52.806092) (xy 216.537555 -52.80052) (xy 216.520646 -52.794265)
			(xy 216.511632 -52.7939) (xy 216.444576 -52.7939) (xy 216.435558 -52.794246) (xy 216.418641 -52.800501)
			(xy 216.411556 -52.806092) (xy 216.411556 -52.806346) (xy 216.411302 -52.806346) (xy 216.390373 -52.823989)
			(xy 216.3444 -52.853702) (xy 216.294652 -52.876538) (xy 216.24215 -52.892028) (xy 216.187974 -52.899854)
			(xy 216.160604 -52.900326) (xy 216.133352 -52.899827) (xy 216.079403 -52.892071) (xy 216.027108 -52.876716)
			(xy 215.977529 -52.854075) (xy 215.931678 -52.824608) (xy 215.890487 -52.788916) (xy 215.854794 -52.747725)
			(xy 215.825327 -52.701874) (xy 215.802686 -52.652296) (xy 215.78733 -52.6) (xy 215.779573 -52.546052)
			(xy 210.830551 -52.546052) (xy 210.841019 -52.550833) (xy 210.886869 -52.580299) (xy 210.92806 -52.61599)
			(xy 210.963751 -52.657181) (xy 210.993217 -52.703031) (xy 211.015859 -52.752608) (xy 211.031214 -52.804903)
			(xy 211.03897 -52.858851) (xy 211.039456 -52.886102) (xy 211.039002 -52.913473) (xy 211.031183 -52.967653)
			(xy 211.015692 -53.020156) (xy 210.992847 -53.069903) (xy 210.963119 -53.115869) (xy 210.945476 -53.1368)
			(xy 210.945222 -53.137054) (xy 210.939639 -53.144143) (xy 210.933392 -53.161058) (xy 210.93303 -53.170074)
			(xy 210.93303 -53.23713) (xy 210.933366 -53.246149) (xy 210.939627 -53.263066) (xy 210.945222 -53.27015)
			(xy 210.945476 -53.27015) (xy 210.945476 -53.270404) (xy 210.963119 -53.291335) (xy 210.992843 -53.337303)
			(xy 211.015688 -53.38705) (xy 211.031184 -53.439552) (xy 211.039012 -53.493731) (xy 211.039012 -53.548472)
			(xy 211.031183 -53.602651) (xy 211.015687 -53.655153) (xy 210.992842 -53.704899) (xy 210.963117 -53.750867)
			(xy 210.946546 -53.77053) (xy 211.310728 -53.77053) (xy 211.311257 -53.741613) (xy 211.319983 -53.684442)
			(xy 211.337238 -53.629243) (xy 211.362627 -53.577281) (xy 211.395569 -53.529747) (xy 211.435309 -53.48773)
			(xy 211.457794 -53.46954) (xy 211.466572 -53.461905) (xy 211.476772 -53.441025) (xy 211.477352 -53.429408)
			(xy 211.477352 -53.349652) (xy 211.476843 -53.338016) (xy 211.466635 -53.317106) (xy 211.457794 -53.30952)
			(xy 211.435319 -53.291319) (xy 211.395583 -53.249301) (xy 211.362644 -53.201768) (xy 211.337254 -53.149809)
			(xy 211.319996 -53.094613) (xy 211.311264 -53.037445) (xy 211.310728 -53.00853) (xy 211.311183 -52.981276)
			(xy 211.318937 -52.927323) (xy 211.334291 -52.875023) (xy 211.356933 -52.825441) (xy 211.386401 -52.779586)
			(xy 211.422096 -52.738392) (xy 211.46329 -52.702697) (xy 211.509146 -52.67323) (xy 211.558729 -52.650589)
			(xy 211.611029 -52.635236) (xy 211.664982 -52.627483) (xy 211.692236 -52.627022) (xy 211.718551 -52.627458)
			(xy 211.770681 -52.634699) (xy 211.821325 -52.649023) (xy 211.869524 -52.670162) (xy 211.914367 -52.697713)
			(xy 211.955005 -52.731158) (xy 211.97316 -52.750212) (xy 211.980693 -52.7576) (xy 211.999964 -52.766132)
			(xy 212.010498 -52.766722) (xy 212.085174 -52.766722) (xy 212.095723 -52.766186) (xy 212.115018 -52.757655)
			(xy 212.122512 -52.750212) (xy 212.140671 -52.73116) (xy 212.1813 -52.697702) (xy 212.226139 -52.670142)
			(xy 212.274339 -52.649003) (xy 212.324986 -52.634685) (xy 212.37712 -52.62746) (xy 212.403436 -52.627022)
			(xy 212.43069 -52.627444) (xy 212.484641 -52.635207) (xy 212.536939 -52.650568) (xy 212.586518 -52.673215)
			(xy 212.63237 -52.702688) (xy 212.67356 -52.738386) (xy 212.709251 -52.779583) (xy 212.738716 -52.82544)
			(xy 212.761355 -52.875023) (xy 212.776707 -52.927324) (xy 212.78446 -52.981276) (xy 212.784944 -53.00853)
			(xy 212.784481 -53.036197) (xy 212.78225 -53.051456) (xy 221.041212 -53.051456) (xy 221.045283 -52.995834)
			(xy 221.057409 -52.941397) (xy 221.077332 -52.889306) (xy 221.104628 -52.840671) (xy 221.138714 -52.796528)
			(xy 221.178863 -52.757819) (xy 221.224221 -52.725368) (xy 221.273821 -52.699867) (xy 221.326605 -52.68186)
			(xy 221.381448 -52.67173) (xy 221.437182 -52.669693) (xy 221.492619 -52.675793) (xy 221.546576 -52.689899)
			(xy 221.597905 -52.711711) (xy 221.645511 -52.740765) (xy 221.688379 -52.77644) (xy 221.725596 -52.817977)
			(xy 221.756369 -52.86449) (xy 221.780041 -52.914987) (xy 221.796109 -52.968394) (xy 221.804229 -53.02357)
			(xy 221.804738 -53.051456) (xy 221.804229 -53.079342) (xy 221.796109 -53.134518) (xy 221.780041 -53.187925)
			(xy 221.756369 -53.238422) (xy 221.725596 -53.284935) (xy 221.688379 -53.326472) (xy 221.645511 -53.362147)
			(xy 221.597905 -53.391201) (xy 221.546576 -53.413013) (xy 221.492619 -53.427119) (xy 221.437182 -53.433219)
			(xy 221.381448 -53.431182) (xy 221.326605 -53.421052) (xy 221.273821 -53.403045) (xy 221.224221 -53.377544)
			(xy 221.178863 -53.345093) (xy 221.138714 -53.306384) (xy 221.104628 -53.262241) (xy 221.077332 -53.213606)
			(xy 221.057409 -53.161515) (xy 221.045283 -53.107078) (xy 221.041212 -53.051456) (xy 212.78225 -53.051456)
			(xy 212.776476 -53.09095) (xy 212.760653 -53.143974) (xy 212.737342 -53.194159) (xy 212.707033 -53.240454)
			(xy 212.670359 -53.28189) (xy 212.628089 -53.317599) (xy 212.604858 -53.332634) (xy 212.595169 -53.339256)
			(xy 212.58273 -53.359128) (xy 212.580982 -53.370734) (xy 212.573108 -53.450744) (xy 212.572469 -53.462382)
			(xy 212.580556 -53.484219) (xy 212.588602 -53.492654) (xy 212.588856 -53.492908) (xy 212.607415 -53.511011)
			(xy 212.639997 -53.551337) (xy 212.666814 -53.595707) (xy 212.687371 -53.643301) (xy 212.701289 -53.693242)
			(xy 212.70831 -53.744608) (xy 212.708744 -53.77053) (xy 212.70825 -53.79778) (xy 212.700491 -53.851726)
			(xy 212.685133 -53.904018) (xy 212.662491 -53.953593) (xy 212.633025 -53.999442) (xy 212.597335 -54.040631)
			(xy 212.556147 -54.076322) (xy 212.510299 -54.105789) (xy 212.460724 -54.128431) (xy 212.408432 -54.143789)
			(xy 212.354486 -54.15155) (xy 212.327236 -54.152038) (xy 212.299866 -54.151566) (xy 212.245686 -54.143752)
			(xy 212.193183 -54.128265) (xy 212.143436 -54.105424) (xy 212.097469 -54.0757) (xy 212.076538 -54.058058)
			(xy 212.076284 -54.057804) (xy 212.069206 -54.052205) (xy 212.052283 -54.045966) (xy 212.043264 -54.045612)
			(xy 211.976208 -54.045612) (xy 211.967191 -54.04597) (xy 211.950274 -54.052217) (xy 211.943188 -54.057804)
			(xy 211.943188 -54.058058) (xy 211.942934 -54.058058) (xy 211.921995 -54.075688) (xy 211.876024 -54.105403)
			(xy 211.826279 -54.128241) (xy 211.77378 -54.143734) (xy 211.719605 -54.151564) (xy 211.692236 -54.152038)
			(xy 211.664985 -54.151511) (xy 211.611038 -54.14376) (xy 211.558743 -54.12841) (xy 211.509165 -54.105774)
			(xy 211.463314 -54.076312) (xy 211.422121 -54.040625) (xy 211.386427 -53.999439) (xy 211.356958 -53.953593)
			(xy 211.334313 -53.904018) (xy 211.318954 -53.851726) (xy 211.311193 -53.797781) (xy 211.310728 -53.77053)
			(xy 210.946546 -53.77053) (xy 210.945476 -53.7718) (xy 210.945222 -53.772054) (xy 210.939639 -53.779143)
			(xy 210.933392 -53.796058) (xy 210.93303 -53.805074) (xy 210.93303 -53.87213) (xy 210.933366 -53.881149)
			(xy 210.939627 -53.898066) (xy 210.945222 -53.90515) (xy 210.945476 -53.90515) (xy 210.945476 -53.905404)
			(xy 210.963119 -53.926335) (xy 210.992843 -53.972303) (xy 211.015688 -54.02205) (xy 211.031184 -54.074552)
			(xy 211.039012 -54.128731) (xy 211.039012 -54.183472) (xy 211.031183 -54.237651) (xy 211.015687 -54.290153)
			(xy 211.001895 -54.320186) (xy 213.23046 -54.320186) (xy 213.230903 -54.292815) (xy 213.238724 -54.238634)
			(xy 213.254218 -54.18613) (xy 213.277065 -54.136384) (xy 213.306796 -54.090418) (xy 213.32444 -54.069488)
			(xy 213.324694 -54.069234) (xy 213.330272 -54.062141) (xy 213.336524 -54.045229) (xy 213.336886 -54.036214)
			(xy 213.336886 -53.969158) (xy 213.336504 -53.960144) (xy 213.330274 -53.943226) (xy 213.324694 -53.936138)
			(xy 213.32444 -53.936138) (xy 213.32444 -53.935884) (xy 213.306833 -53.914926) (xy 213.277115 -53.868961)
			(xy 213.254272 -53.81922) (xy 213.238774 -53.766725) (xy 213.230938 -53.712553) (xy 213.23046 -53.685186)
			(xy 213.230946 -53.657935) (xy 213.238702 -53.603987) (xy 213.254057 -53.551692) (xy 213.276699 -53.502115)
			(xy 213.306165 -53.456265) (xy 213.341856 -53.415074) (xy 213.383047 -53.379383) (xy 213.428897 -53.349917)
			(xy 213.478474 -53.327275) (xy 213.530769 -53.31192) (xy 213.584717 -53.304164) (xy 213.639219 -53.304164)
			(xy 213.693167 -53.31192) (xy 213.745462 -53.327275) (xy 213.795039 -53.349917) (xy 213.840889 -53.379383)
			(xy 213.88208 -53.415074) (xy 213.917771 -53.456265) (xy 213.947237 -53.502115) (xy 213.969879 -53.551692)
			(xy 213.985234 -53.603987) (xy 213.99299 -53.657935) (xy 213.993476 -53.685186) (xy 213.993008 -53.712556)
			(xy 213.985191 -53.766735) (xy 213.969703 -53.819239) (xy 213.946862 -53.868986) (xy 213.917137 -53.914952)
			(xy 213.899496 -53.935884) (xy 213.899242 -53.936138) (xy 213.893668 -53.943233) (xy 213.887415 -53.960144)
			(xy 213.88705 -53.969158) (xy 213.88705 -54.036214) (xy 213.88739 -54.045233) (xy 213.893648 -54.06215)
			(xy 213.899242 -54.069234) (xy 213.899496 -54.069234) (xy 213.899496 -54.069488) (xy 213.917142 -54.090414)
			(xy 213.946853 -54.136389) (xy 213.969688 -54.186138) (xy 213.985177 -54.23864) (xy 213.993003 -54.292816)
			(xy 213.993476 -54.320186) (xy 213.99299 -54.347437) (xy 213.985234 -54.401385) (xy 213.969879 -54.45368)
			(xy 213.947237 -54.503257) (xy 213.917771 -54.549107) (xy 213.88208 -54.590298) (xy 213.840889 -54.625989)
			(xy 213.795039 -54.655455) (xy 213.745462 -54.678097) (xy 213.693167 -54.693452) (xy 213.639219 -54.701208)
			(xy 213.584717 -54.701208) (xy 213.530769 -54.693452) (xy 213.478474 -54.678097) (xy 213.428897 -54.655455)
			(xy 213.383047 -54.625989) (xy 213.341856 -54.590298) (xy 213.306165 -54.549107) (xy 213.276699 -54.503257)
			(xy 213.254057 -54.45368) (xy 213.238702 -54.401385) (xy 213.230946 -54.347437) (xy 213.23046 -54.320186)
			(xy 211.001895 -54.320186) (xy 210.992842 -54.339899) (xy 210.963117 -54.385867) (xy 210.945476 -54.4068)
			(xy 210.945222 -54.407054) (xy 210.939639 -54.414143) (xy 210.933392 -54.431058) (xy 210.93303 -54.440074)
			(xy 210.93303 -54.50713) (xy 210.933366 -54.516149) (xy 210.939627 -54.533066) (xy 210.945222 -54.54015)
			(xy 210.945476 -54.54015) (xy 210.945476 -54.540404) (xy 210.963127 -54.561327) (xy 210.992838 -54.607302)
			(xy 211.015672 -54.657052) (xy 211.03116 -54.709554) (xy 211.038984 -54.763732) (xy 211.039101 -54.770528)
			(xy 214.171022 -54.770528) (xy 214.171499 -54.743158) (xy 214.179313 -54.688979) (xy 214.1948 -54.636476)
			(xy 214.217639 -54.586729) (xy 214.247362 -54.540762) (xy 214.265002 -54.51983) (xy 214.265256 -54.519576)
			(xy 214.270865 -54.512505) (xy 214.277097 -54.495576) (xy 214.277448 -54.486556) (xy 214.277448 -54.4195)
			(xy 214.277102 -54.410482) (xy 214.270848 -54.393564) (xy 214.265256 -54.38648) (xy 214.265002 -54.38648)
			(xy 214.265002 -54.386226) (xy 214.247362 -54.365295) (xy 214.21765 -54.319322) (xy 214.194814 -54.269574)
			(xy 214.179324 -54.217073) (xy 214.171496 -54.162897) (xy 214.171022 -54.135528) (xy 214.171508 -54.108277)
			(xy 214.179264 -54.054329) (xy 214.194619 -54.002034) (xy 214.217261 -53.952457) (xy 214.246727 -53.906607)
			(xy 214.282418 -53.865416) (xy 214.323609 -53.829725) (xy 214.369459 -53.800259) (xy 214.419036 -53.777617)
			(xy 214.471331 -53.762262) (xy 214.525279 -53.754506) (xy 214.579781 -53.754506) (xy 214.633729 -53.762262)
			(xy 214.686024 -53.777617) (xy 214.735601 -53.800259) (xy 214.781451 -53.829725) (xy 214.822642 -53.865416)
			(xy 214.858333 -53.906607) (xy 214.887799 -53.952457) (xy 214.892874 -53.96357) (xy 218.872052 -53.96357)
			(xy 218.876123 -53.907948) (xy 218.888249 -53.853511) (xy 218.908172 -53.80142) (xy 218.935468 -53.752785)
			(xy 218.969554 -53.708642) (xy 219.009703 -53.669933) (xy 219.055061 -53.637482) (xy 219.104661 -53.611981)
			(xy 219.157445 -53.593974) (xy 219.212288 -53.583844) (xy 219.268022 -53.581807) (xy 219.323459 -53.587907)
			(xy 219.377416 -53.602013) (xy 219.428745 -53.623825) (xy 219.476351 -53.652879) (xy 219.519219 -53.688554)
			(xy 219.546242 -53.718714) (xy 236.97514 -53.718714) (xy 236.979211 -53.663092) (xy 236.991337 -53.608655)
			(xy 237.01126 -53.556564) (xy 237.038556 -53.507929) (xy 237.072642 -53.463786) (xy 237.112791 -53.425077)
			(xy 237.158149 -53.392626) (xy 237.207749 -53.367125) (xy 237.260533 -53.349118) (xy 237.315376 -53.338988)
			(xy 237.37111 -53.336951) (xy 237.426547 -53.343051) (xy 237.480504 -53.357157) (xy 237.531833 -53.378969)
			(xy 237.579439 -53.408023) (xy 237.622307 -53.443698) (xy 237.659524 -53.485235) (xy 237.690297 -53.531748)
			(xy 237.713969 -53.582245) (xy 237.730037 -53.635652) (xy 237.738157 -53.690828) (xy 237.738666 -53.718714)
			(xy 237.738157 -53.7466) (xy 237.730037 -53.801776) (xy 237.713969 -53.855183) (xy 237.690297 -53.90568)
			(xy 237.659524 -53.952193) (xy 237.622307 -53.99373) (xy 237.579439 -54.029405) (xy 237.531833 -54.058459)
			(xy 237.480504 -54.080271) (xy 237.426547 -54.094377) (xy 237.37111 -54.100477) (xy 237.315376 -54.09844)
			(xy 237.260533 -54.08831) (xy 237.207749 -54.070303) (xy 237.158149 -54.044802) (xy 237.112791 -54.012351)
			(xy 237.072642 -53.973642) (xy 237.038556 -53.929499) (xy 237.01126 -53.880864) (xy 236.991337 -53.828773)
			(xy 236.979211 -53.774336) (xy 236.97514 -53.718714) (xy 219.546242 -53.718714) (xy 219.556436 -53.730091)
			(xy 219.587209 -53.776604) (xy 219.610881 -53.827101) (xy 219.626949 -53.880508) (xy 219.635069 -53.935684)
			(xy 219.635578 -53.96357) (xy 219.635069 -53.991456) (xy 219.626949 -54.046632) (xy 219.610881 -54.100039)
			(xy 219.587209 -54.150536) (xy 219.556436 -54.197049) (xy 219.519219 -54.238586) (xy 219.476351 -54.274261)
			(xy 219.428745 -54.303315) (xy 219.414148 -54.309518) (xy 237.727234 -54.309518) (xy 237.731305 -54.253896)
			(xy 237.743431 -54.199459) (xy 237.763354 -54.147368) (xy 237.79065 -54.098733) (xy 237.824736 -54.05459)
			(xy 237.864885 -54.015881) (xy 237.910243 -53.98343) (xy 237.959843 -53.957929) (xy 238.012627 -53.939922)
			(xy 238.06747 -53.929792) (xy 238.123204 -53.927755) (xy 238.178641 -53.933855) (xy 238.232598 -53.947961)
			(xy 238.283927 -53.969773) (xy 238.331533 -53.998827) (xy 238.374401 -54.034502) (xy 238.411618 -54.076039)
			(xy 238.442391 -54.122552) (xy 238.466063 -54.173049) (xy 238.47449 -54.20106) (xy 239.961418 -54.20106)
			(xy 239.965489 -54.145438) (xy 239.977615 -54.091001) (xy 239.997538 -54.03891) (xy 240.024834 -53.990275)
			(xy 240.05892 -53.946132) (xy 240.099069 -53.907423) (xy 240.144427 -53.874972) (xy 240.194027 -53.849471)
			(xy 240.246811 -53.831464) (xy 240.301654 -53.821334) (xy 240.357388 -53.819297) (xy 240.412825 -53.825397)
			(xy 240.466782 -53.839503) (xy 240.518111 -53.861315) (xy 240.565717 -53.890369) (xy 240.608585 -53.926044)
			(xy 240.645802 -53.967581) (xy 240.676575 -54.014094) (xy 240.700247 -54.064591) (xy 240.716315 -54.117998)
			(xy 240.724435 -54.173174) (xy 240.724944 -54.20106) (xy 240.724435 -54.228946) (xy 240.716315 -54.284122)
			(xy 240.700247 -54.337529) (xy 240.676575 -54.388026) (xy 240.645802 -54.434539) (xy 240.608585 -54.476076)
			(xy 240.565717 -54.511751) (xy 240.518111 -54.540805) (xy 240.466782 -54.562617) (xy 240.412825 -54.576723)
			(xy 240.357388 -54.582823) (xy 240.301654 -54.580786) (xy 240.246811 -54.570656) (xy 240.194027 -54.552649)
			(xy 240.144427 -54.527148) (xy 240.099069 -54.494697) (xy 240.05892 -54.455988) (xy 240.024834 -54.411845)
			(xy 239.997538 -54.36321) (xy 239.977615 -54.311119) (xy 239.965489 -54.256682) (xy 239.961418 -54.20106)
			(xy 238.47449 -54.20106) (xy 238.482131 -54.226456) (xy 238.490251 -54.281632) (xy 238.49076 -54.309518)
			(xy 238.490251 -54.337404) (xy 238.482131 -54.39258) (xy 238.466063 -54.445987) (xy 238.442391 -54.496484)
			(xy 238.411618 -54.542997) (xy 238.374401 -54.584534) (xy 238.331533 -54.620209) (xy 238.283927 -54.649263)
			(xy 238.232598 -54.671075) (xy 238.178641 -54.685181) (xy 238.123204 -54.691281) (xy 238.06747 -54.689244)
			(xy 238.012627 -54.679114) (xy 237.959843 -54.661107) (xy 237.910243 -54.635606) (xy 237.864885 -54.603155)
			(xy 237.824736 -54.564446) (xy 237.79065 -54.520303) (xy 237.763354 -54.471668) (xy 237.743431 -54.419577)
			(xy 237.731305 -54.36514) (xy 237.727234 -54.309518) (xy 219.414148 -54.309518) (xy 219.377416 -54.325127)
			(xy 219.323459 -54.339233) (xy 219.268022 -54.345333) (xy 219.212288 -54.343296) (xy 219.157445 -54.333166)
			(xy 219.104661 -54.315159) (xy 219.055061 -54.289658) (xy 219.009703 -54.257207) (xy 218.969554 -54.218498)
			(xy 218.935468 -54.174355) (xy 218.908172 -54.12572) (xy 218.888249 -54.073629) (xy 218.876123 -54.019192)
			(xy 218.872052 -53.96357) (xy 214.892874 -53.96357) (xy 214.910441 -54.002034) (xy 214.925796 -54.054329)
			(xy 214.933552 -54.108277) (xy 214.934038 -54.135528) (xy 214.933603 -54.1629) (xy 214.92578 -54.217081)
			(xy 214.910285 -54.269585) (xy 214.887436 -54.319331) (xy 214.857703 -54.365296) (xy 214.840058 -54.386226)
			(xy 214.839804 -54.38648) (xy 214.83422 -54.393568) (xy 214.827972 -54.410484) (xy 214.827612 -54.4195)
			(xy 214.827612 -54.486556) (xy 214.827988 -54.495571) (xy 214.834222 -54.512488) (xy 214.839804 -54.519576)
			(xy 214.840058 -54.519576) (xy 214.840058 -54.51983) (xy 214.857671 -54.540783) (xy 214.887388 -54.586749)
			(xy 214.91023 -54.636492) (xy 214.925727 -54.688988) (xy 214.933561 -54.74316) (xy 214.934038 -54.770528)
			(xy 214.933608 -54.794658) (xy 238.931448 -54.794658) (xy 238.935519 -54.739036) (xy 238.947645 -54.684599)
			(xy 238.967568 -54.632508) (xy 238.994864 -54.583873) (xy 239.02895 -54.53973) (xy 239.069099 -54.501021)
			(xy 239.114457 -54.46857) (xy 239.164057 -54.443069) (xy 239.216841 -54.425062) (xy 239.271684 -54.414932)
			(xy 239.327418 -54.412895) (xy 239.382855 -54.418995) (xy 239.436812 -54.433101) (xy 239.488141 -54.454913)
			(xy 239.535747 -54.483967) (xy 239.578615 -54.519642) (xy 239.615832 -54.561179) (xy 239.646605 -54.607692)
			(xy 239.670277 -54.658189) (xy 239.686345 -54.711596) (xy 239.694465 -54.766772) (xy 239.694974 -54.794658)
			(xy 239.69496 -54.79542) (xy 240.96294 -54.79542) (xy 240.967011 -54.739798) (xy 240.979137 -54.685361)
			(xy 240.99906 -54.63327) (xy 241.026356 -54.584635) (xy 241.060442 -54.540492) (xy 241.100591 -54.501783)
			(xy 241.145949 -54.469332) (xy 241.195549 -54.443831) (xy 241.248333 -54.425824) (xy 241.303176 -54.415694)
			(xy 241.35891 -54.413657) (xy 241.414347 -54.419757) (xy 241.468304 -54.433863) (xy 241.519633 -54.455675)
			(xy 241.567239 -54.484729) (xy 241.610107 -54.520404) (xy 241.647324 -54.561941) (xy 241.678097 -54.608454)
			(xy 241.701769 -54.658951) (xy 241.717837 -54.712358) (xy 241.720641 -54.731412) (xy 245.720616 -54.731412)
			(xy 245.721085 -54.704042) (xy 245.728902 -54.649863) (xy 245.74439 -54.597359) (xy 245.767231 -54.547613)
			(xy 245.796955 -54.501646) (xy 245.814596 -54.480714) (xy 245.81485 -54.48046) (xy 245.820424 -54.473365)
			(xy 245.826677 -54.456454) (xy 245.827042 -54.44744) (xy 245.827042 -54.380384) (xy 245.826705 -54.371365)
			(xy 245.820445 -54.354447) (xy 245.81485 -54.347364) (xy 245.814596 -54.347364) (xy 245.814596 -54.34711)
			(xy 245.796968 -54.326167) (xy 245.767245 -54.2802) (xy 245.744401 -54.230456) (xy 245.728905 -54.177955)
			(xy 245.721076 -54.123779) (xy 245.721075 -54.069039) (xy 245.728902 -54.014862) (xy 245.744395 -53.962361)
			(xy 245.767237 -53.912616) (xy 245.796957 -53.866647) (xy 245.814596 -53.845714) (xy 245.81485 -53.84546)
			(xy 245.820424 -53.838365) (xy 245.826677 -53.821454) (xy 245.827042 -53.81244) (xy 245.827042 -53.745384)
			(xy 245.826705 -53.736365) (xy 245.820445 -53.719447) (xy 245.81485 -53.712364) (xy 245.814596 -53.712364)
			(xy 245.814596 -53.71211) (xy 245.796968 -53.691167) (xy 245.767245 -53.6452) (xy 245.744401 -53.595456)
			(xy 245.728905 -53.542955) (xy 245.721076 -53.488779) (xy 245.721075 -53.434039) (xy 245.728902 -53.379862)
			(xy 245.744395 -53.327361) (xy 245.767237 -53.277616) (xy 245.796957 -53.231647) (xy 245.814596 -53.210714)
			(xy 245.81485 -53.21046) (xy 245.820424 -53.203365) (xy 245.826677 -53.186454) (xy 245.827042 -53.17744)
			(xy 245.827042 -53.110384) (xy 245.826705 -53.101365) (xy 245.820445 -53.084447) (xy 245.81485 -53.077364)
			(xy 245.814596 -53.077364) (xy 245.814596 -53.07711) (xy 245.796948 -53.056186) (xy 245.767237 -53.010211)
			(xy 245.744403 -52.960461) (xy 245.728914 -52.907959) (xy 245.721089 -52.853782) (xy 245.720616 -52.826412)
			(xy 245.721102 -52.799161) (xy 245.728858 -52.745213) (xy 245.744213 -52.692918) (xy 245.766855 -52.643341)
			(xy 245.796321 -52.597491) (xy 245.832012 -52.5563) (xy 245.873203 -52.520609) (xy 245.919053 -52.491143)
			(xy 245.96863 -52.468501) (xy 246.020925 -52.453146) (xy 246.074873 -52.44539) (xy 246.129375 -52.44539)
			(xy 246.183323 -52.453146) (xy 246.235618 -52.468501) (xy 246.285195 -52.491143) (xy 246.331045 -52.520609)
			(xy 246.372236 -52.5563) (xy 246.407927 -52.597491) (xy 246.437393 -52.643341) (xy 246.460035 -52.692918)
			(xy 246.47539 -52.745213) (xy 246.483146 -52.799161) (xy 246.483632 -52.826412) (xy 246.48319 -52.853783)
			(xy 246.475369 -52.907964) (xy 246.459875 -52.960468) (xy 246.437027 -53.010215) (xy 246.407297 -53.05618)
			(xy 246.389652 -53.07711) (xy 246.389398 -53.077364) (xy 246.38382 -53.084457) (xy 246.377568 -53.101369)
			(xy 246.377206 -53.110384) (xy 246.377206 -53.17744) (xy 246.377543 -53.186459) (xy 246.383804 -53.203376)
			(xy 246.389398 -53.21046) (xy 246.389652 -53.21046) (xy 246.389652 -53.210714) (xy 246.407305 -53.231637)
			(xy 246.437031 -53.277606) (xy 246.459877 -53.327354) (xy 246.475373 -53.379857) (xy 246.483201 -53.434038)
			(xy 246.4832 -53.48878) (xy 246.47537 -53.54296) (xy 246.459871 -53.595463) (xy 246.437023 -53.64521)
			(xy 246.407294 -53.691178) (xy 246.389652 -53.71211) (xy 246.389398 -53.712364) (xy 246.38382 -53.719457)
			(xy 246.377568 -53.736369) (xy 246.377206 -53.745384) (xy 246.377206 -53.81244) (xy 246.377543 -53.821459)
			(xy 246.383804 -53.838376) (xy 246.389398 -53.84546) (xy 246.389652 -53.84546) (xy 246.389652 -53.845714)
			(xy 246.407305 -53.866637) (xy 246.437031 -53.912606) (xy 246.459877 -53.962354) (xy 246.475373 -54.014857)
			(xy 246.483201 -54.069038) (xy 246.4832 -54.12378) (xy 246.47537 -54.17796) (xy 246.459871 -54.230463)
			(xy 246.437023 -54.28021) (xy 246.407294 -54.326178) (xy 246.389652 -54.34711) (xy 246.389398 -54.347364)
			(xy 246.38382 -54.354457) (xy 246.377568 -54.371369) (xy 246.377206 -54.380384) (xy 246.377206 -54.44744)
			(xy 246.377543 -54.456459) (xy 246.383804 -54.473376) (xy 246.389398 -54.48046) (xy 246.389652 -54.48046)
			(xy 246.389652 -54.480714) (xy 246.407257 -54.501674) (xy 246.436975 -54.547638) (xy 246.459819 -54.597379)
			(xy 246.475318 -54.649873) (xy 246.483154 -54.704045) (xy 246.483632 -54.731412) (xy 246.483146 -54.758663)
			(xy 246.478482 -54.791102) (xy 248.37644 -54.791102) (xy 248.376897 -54.763731) (xy 248.384716 -54.709552)
			(xy 248.400206 -54.657048) (xy 248.42305 -54.607301) (xy 248.452777 -54.561335) (xy 248.47042 -54.540404)
			(xy 248.470674 -54.54015) (xy 248.476254 -54.53306) (xy 248.482503 -54.516145) (xy 248.482866 -54.50713)
			(xy 248.482866 -54.440074) (xy 248.482529 -54.431055) (xy 248.476268 -54.414138) (xy 248.470674 -54.407054)
			(xy 248.47042 -54.407054) (xy 248.47042 -54.4068) (xy 248.452782 -54.385866) (xy 248.423057 -54.339898)
			(xy 248.400212 -54.290152) (xy 248.384716 -54.23765) (xy 248.376887 -54.183472) (xy 248.376887 -54.128731)
			(xy 248.384715 -54.074553) (xy 248.400211 -54.022051) (xy 248.423056 -53.972305) (xy 248.45278 -53.926337)
			(xy 248.47042 -53.905404) (xy 248.470674 -53.90515) (xy 248.476254 -53.89806) (xy 248.482503 -53.881145)
			(xy 248.482866 -53.87213) (xy 248.482866 -53.805074) (xy 248.482529 -53.796055) (xy 248.476268 -53.779138)
			(xy 248.470674 -53.772054) (xy 248.47042 -53.772054) (xy 248.47042 -53.7718) (xy 248.452782 -53.750866)
			(xy 248.423057 -53.704898) (xy 248.400212 -53.655152) (xy 248.384716 -53.60265) (xy 248.376887 -53.548472)
			(xy 248.376887 -53.493731) (xy 248.384715 -53.439553) (xy 248.400211 -53.387051) (xy 248.423056 -53.337305)
			(xy 248.45278 -53.291337) (xy 248.47042 -53.270404) (xy 248.470674 -53.27015) (xy 248.476254 -53.26306)
			(xy 248.482503 -53.246145) (xy 248.482866 -53.23713) (xy 248.482866 -53.170074) (xy 248.482529 -53.161055)
			(xy 248.476268 -53.144138) (xy 248.470674 -53.137054) (xy 248.47042 -53.137054) (xy 248.47042 -53.1368)
			(xy 248.452771 -53.115876) (xy 248.42306 -53.069901) (xy 248.400225 -53.020152) (xy 248.384737 -52.967649)
			(xy 248.376912 -52.913472) (xy 248.37644 -52.886102) (xy 248.376926 -52.858851) (xy 248.384682 -52.804903)
			(xy 248.400037 -52.752608) (xy 248.422679 -52.703031) (xy 248.452145 -52.657181) (xy 248.487836 -52.61599)
			(xy 248.529027 -52.580299) (xy 248.574877 -52.550833) (xy 248.624454 -52.528191) (xy 248.676749 -52.512836)
			(xy 248.730697 -52.50508) (xy 248.785199 -52.50508) (xy 248.839147 -52.512836) (xy 248.891442 -52.528191)
			(xy 248.930551 -52.546052) (xy 253.879573 -52.546052) (xy 253.879573 -52.491548) (xy 253.88733 -52.4376)
			(xy 253.902686 -52.385304) (xy 253.925327 -52.335726) (xy 253.954794 -52.289875) (xy 253.990487 -52.248684)
			(xy 254.031678 -52.212992) (xy 254.077529 -52.183525) (xy 254.127108 -52.160884) (xy 254.179403 -52.145529)
			(xy 254.233352 -52.137773) (xy 254.260604 -52.13731) (xy 254.287974 -52.137771) (xy 254.342154 -52.14559)
			(xy 254.394657 -52.16108) (xy 254.444404 -52.183923) (xy 254.49037 -52.213648) (xy 254.511302 -52.23129)
			(xy 254.511556 -52.231544) (xy 254.518647 -52.237124) (xy 254.535561 -52.243373) (xy 254.544576 -52.243736)
			(xy 254.611632 -52.243736) (xy 254.620649 -52.243387) (xy 254.637566 -52.237133) (xy 254.644652 -52.231544)
			(xy 254.644652 -52.23129) (xy 254.644906 -52.23129) (xy 254.665839 -52.213649) (xy 254.711807 -52.183925)
			(xy 254.761553 -52.161079) (xy 254.814055 -52.145583) (xy 254.868233 -52.137754) (xy 254.922975 -52.137754)
			(xy 254.977153 -52.145583) (xy 255.029655 -52.161079) (xy 255.079401 -52.183925) (xy 255.125369 -52.213649)
			(xy 255.146302 -52.23129) (xy 255.146556 -52.231544) (xy 255.153647 -52.237124) (xy 255.170561 -52.243373)
			(xy 255.179576 -52.243736) (xy 255.246632 -52.243736) (xy 255.255649 -52.243387) (xy 255.272566 -52.237133)
			(xy 255.279652 -52.231544) (xy 255.279652 -52.23129) (xy 255.279906 -52.23129) (xy 255.300824 -52.213633)
			(xy 255.346801 -52.183924) (xy 255.396552 -52.161092) (xy 255.449056 -52.145605) (xy 255.503234 -52.137782)
			(xy 255.530604 -52.13731) (xy 255.557856 -52.13776) (xy 255.611806 -52.145517) (xy 255.664103 -52.160874)
			(xy 255.713682 -52.183516) (xy 255.759534 -52.212984) (xy 255.800726 -52.248677) (xy 255.836419 -52.289869)
			(xy 255.865886 -52.335722) (xy 255.888528 -52.385301) (xy 255.903883 -52.437598) (xy 255.91164 -52.491548)
			(xy 255.91164 -52.546052) (xy 255.905695 -52.587398) (xy 256.955288 -52.587398) (xy 256.959359 -52.531776)
			(xy 256.971485 -52.477339) (xy 256.991408 -52.425248) (xy 257.018704 -52.376613) (xy 257.05279 -52.33247)
			(xy 257.092939 -52.293761) (xy 257.138297 -52.26131) (xy 257.187897 -52.235809) (xy 257.240681 -52.217802)
			(xy 257.295524 -52.207672) (xy 257.351258 -52.205635) (xy 257.406695 -52.211735) (xy 257.460652 -52.225841)
			(xy 257.511981 -52.247653) (xy 257.559587 -52.276707) (xy 257.602455 -52.312382) (xy 257.639672 -52.353919)
			(xy 257.670445 -52.400432) (xy 257.694117 -52.450929) (xy 257.710185 -52.504336) (xy 257.717781 -52.555952)
			(xy 264.783779 -52.555952) (xy 264.783779 -52.501448) (xy 264.791536 -52.447498) (xy 264.806893 -52.395202)
			(xy 264.829536 -52.345623) (xy 264.859004 -52.299772) (xy 264.894698 -52.258581) (xy 264.935891 -52.22289)
			(xy 264.981744 -52.193424) (xy 265.031324 -52.170784) (xy 265.083622 -52.155431) (xy 265.137572 -52.147678)
			(xy 265.164824 -52.147216) (xy 265.192195 -52.147664) (xy 265.246375 -52.155486) (xy 265.298878 -52.170979)
			(xy 265.348625 -52.193825) (xy 265.394591 -52.223553) (xy 265.415522 -52.241196) (xy 265.415776 -52.24145)
			(xy 265.422861 -52.247039) (xy 265.439779 -52.253283) (xy 265.448796 -52.253642) (xy 265.515852 -52.253642)
			(xy 265.524868 -52.253275) (xy 265.541786 -52.247036) (xy 265.548872 -52.24145) (xy 265.548872 -52.241196)
			(xy 265.549126 -52.241196) (xy 265.570075 -52.223578) (xy 265.616043 -52.193863) (xy 265.665786 -52.171023)
			(xy 265.718283 -52.155527) (xy 265.772456 -52.147693) (xy 265.799824 -52.147216) (xy 265.827076 -52.147655)
			(xy 265.881024 -52.155415) (xy 265.93332 -52.170773) (xy 265.982897 -52.193417) (xy 266.028747 -52.222886)
			(xy 266.069937 -52.25858) (xy 266.105628 -52.299772) (xy 266.135094 -52.345624) (xy 266.157735 -52.395203)
			(xy 266.17309 -52.447499) (xy 266.180846 -52.501448) (xy 266.180846 -52.555952) (xy 266.17309 -52.609901)
			(xy 266.157735 -52.662197) (xy 266.135094 -52.711776) (xy 266.105628 -52.757628) (xy 266.069937 -52.79882)
			(xy 266.028747 -52.834514) (xy 265.982897 -52.863983) (xy 265.93332 -52.886627) (xy 265.881024 -52.901985)
			(xy 265.827076 -52.909745) (xy 265.799824 -52.910232) (xy 265.772453 -52.909768) (xy 265.718274 -52.901953)
			(xy 265.66577 -52.886464) (xy 265.616023 -52.863621) (xy 265.570057 -52.833895) (xy 265.549126 -52.816252)
			(xy 265.548872 -52.815998) (xy 265.541769 -52.810435) (xy 265.524865 -52.804174) (xy 265.515852 -52.803806)
			(xy 265.448796 -52.803806) (xy 265.439779 -52.80416) (xy 265.422862 -52.810409) (xy 265.415776 -52.815998)
			(xy 265.415776 -52.816252) (xy 265.415522 -52.816252) (xy 265.394586 -52.833887) (xy 265.348615 -52.863601)
			(xy 265.298869 -52.886438) (xy 265.246369 -52.90193) (xy 265.192193 -52.909758) (xy 265.164824 -52.910232)
			(xy 265.137572 -52.909722) (xy 265.083622 -52.901969) (xy 265.031324 -52.886616) (xy 264.981744 -52.863976)
			(xy 264.935891 -52.83451) (xy 264.894698 -52.798819) (xy 264.859004 -52.757628) (xy 264.829536 -52.711777)
			(xy 264.806893 -52.662198) (xy 264.791536 -52.609902) (xy 264.783779 -52.555952) (xy 257.717781 -52.555952)
			(xy 257.718305 -52.559512) (xy 257.718814 -52.587398) (xy 257.718305 -52.615284) (xy 257.710185 -52.67046)
			(xy 257.694117 -52.723867) (xy 257.670445 -52.774364) (xy 257.639672 -52.820877) (xy 257.602455 -52.862414)
			(xy 257.559587 -52.898089) (xy 257.511981 -52.927143) (xy 257.460652 -52.948955) (xy 257.406695 -52.963061)
			(xy 257.351258 -52.969161) (xy 257.295524 -52.967124) (xy 257.240681 -52.956994) (xy 257.187897 -52.938987)
			(xy 257.138297 -52.913486) (xy 257.092939 -52.881035) (xy 257.05279 -52.842326) (xy 257.018704 -52.798183)
			(xy 256.991408 -52.749548) (xy 256.971485 -52.697457) (xy 256.959359 -52.64302) (xy 256.955288 -52.587398)
			(xy 255.905695 -52.587398) (xy 255.903883 -52.600002) (xy 255.888528 -52.652299) (xy 255.865886 -52.701878)
			(xy 255.836419 -52.747731) (xy 255.800726 -52.788923) (xy 255.759534 -52.824616) (xy 255.713682 -52.854084)
			(xy 255.664103 -52.876726) (xy 255.611806 -52.892083) (xy 255.557856 -52.89984) (xy 255.530604 -52.900326)
			(xy 255.503233 -52.899876) (xy 255.449053 -52.892057) (xy 255.396549 -52.876565) (xy 255.346802 -52.853719)
			(xy 255.300836 -52.82399) (xy 255.279906 -52.806346) (xy 255.279652 -52.806092) (xy 255.272555 -52.80052)
			(xy 255.255646 -52.794265) (xy 255.246632 -52.7939) (xy 255.179576 -52.7939) (xy 255.170558 -52.794246)
			(xy 255.153641 -52.800501) (xy 255.146556 -52.806092) (xy 255.146302 -52.806346) (xy 255.125369 -52.823987)
			(xy 255.079401 -52.853711) (xy 255.029655 -52.876557) (xy 254.977153 -52.892053) (xy 254.922975 -52.899882)
			(xy 254.868233 -52.899882) (xy 254.814055 -52.892053) (xy 254.761553 -52.876557) (xy 254.711807 -52.853711)
			(xy 254.665839 -52.823987) (xy 254.644906 -52.806346) (xy 254.644652 -52.806092) (xy 254.637555 -52.80052)
			(xy 254.620646 -52.794265) (xy 254.611632 -52.7939) (xy 254.544576 -52.7939) (xy 254.535558 -52.794246)
			(xy 254.518641 -52.800501) (xy 254.511556 -52.806092) (xy 254.511556 -52.806346) (xy 254.511302 -52.806346)
			(xy 254.490373 -52.823989) (xy 254.4444 -52.853702) (xy 254.394652 -52.876538) (xy 254.34215 -52.892028)
			(xy 254.287974 -52.899854) (xy 254.260604 -52.900326) (xy 254.233352 -52.899827) (xy 254.179403 -52.892071)
			(xy 254.127108 -52.876716) (xy 254.077529 -52.854075) (xy 254.031678 -52.824608) (xy 253.990487 -52.788916)
			(xy 253.954794 -52.747725) (xy 253.925327 -52.701874) (xy 253.902686 -52.652296) (xy 253.88733 -52.6)
			(xy 253.879573 -52.546052) (xy 248.930551 -52.546052) (xy 248.941019 -52.550833) (xy 248.986869 -52.580299)
			(xy 249.02806 -52.61599) (xy 249.063751 -52.657181) (xy 249.093217 -52.703031) (xy 249.115859 -52.752608)
			(xy 249.131214 -52.804903) (xy 249.13897 -52.858851) (xy 249.139456 -52.886102) (xy 249.139002 -52.913473)
			(xy 249.131183 -52.967653) (xy 249.115692 -53.020156) (xy 249.092847 -53.069903) (xy 249.063119 -53.115869)
			(xy 249.045476 -53.1368) (xy 249.045222 -53.137054) (xy 249.039639 -53.144143) (xy 249.033392 -53.161058)
			(xy 249.03303 -53.170074) (xy 249.03303 -53.23713) (xy 249.033366 -53.246149) (xy 249.039627 -53.263066)
			(xy 249.045222 -53.27015) (xy 249.045476 -53.27015) (xy 249.045476 -53.270404) (xy 249.063119 -53.291335)
			(xy 249.092843 -53.337303) (xy 249.115688 -53.38705) (xy 249.131184 -53.439552) (xy 249.139012 -53.493731)
			(xy 249.139012 -53.548472) (xy 249.131183 -53.602651) (xy 249.115687 -53.655153) (xy 249.092842 -53.704899)
			(xy 249.063117 -53.750867) (xy 249.046546 -53.77053) (xy 249.410728 -53.77053) (xy 249.411257 -53.741613)
			(xy 249.419983 -53.684442) (xy 249.437238 -53.629243) (xy 249.462627 -53.577281) (xy 249.495569 -53.529747)
			(xy 249.535309 -53.48773) (xy 249.557794 -53.46954) (xy 249.566572 -53.461905) (xy 249.576772 -53.441025)
			(xy 249.577352 -53.429408) (xy 249.577352 -53.349652) (xy 249.576843 -53.338016) (xy 249.566635 -53.317106)
			(xy 249.557794 -53.30952) (xy 249.535319 -53.291319) (xy 249.495583 -53.249301) (xy 249.462644 -53.201768)
			(xy 249.437254 -53.149809) (xy 249.419996 -53.094613) (xy 249.411264 -53.037445) (xy 249.410728 -53.00853)
			(xy 249.411183 -52.981276) (xy 249.418937 -52.927323) (xy 249.434291 -52.875023) (xy 249.456933 -52.825441)
			(xy 249.486401 -52.779586) (xy 249.522096 -52.738392) (xy 249.56329 -52.702697) (xy 249.609146 -52.67323)
			(xy 249.658729 -52.650589) (xy 249.711029 -52.635236) (xy 249.764982 -52.627483) (xy 249.792236 -52.627022)
			(xy 249.818551 -52.627458) (xy 249.870681 -52.634699) (xy 249.921325 -52.649023) (xy 249.969524 -52.670162)
			(xy 250.014367 -52.697713) (xy 250.055005 -52.731158) (xy 250.07316 -52.750212) (xy 250.080693 -52.7576)
			(xy 250.099964 -52.766132) (xy 250.110498 -52.766722) (xy 250.185174 -52.766722) (xy 250.195723 -52.766186)
			(xy 250.215018 -52.757655) (xy 250.222512 -52.750212) (xy 250.240671 -52.73116) (xy 250.2813 -52.697702)
			(xy 250.326139 -52.670142) (xy 250.374339 -52.649003) (xy 250.424986 -52.634685) (xy 250.47712 -52.62746)
			(xy 250.503436 -52.627022) (xy 250.53069 -52.627444) (xy 250.584641 -52.635207) (xy 250.636939 -52.650568)
			(xy 250.686518 -52.673215) (xy 250.73237 -52.702688) (xy 250.77356 -52.738386) (xy 250.809251 -52.779583)
			(xy 250.838716 -52.82544) (xy 250.861355 -52.875023) (xy 250.876707 -52.927324) (xy 250.88446 -52.981276)
			(xy 250.884944 -53.00853) (xy 250.884481 -53.036197) (xy 250.88225 -53.051456) (xy 259.141212 -53.051456)
			(xy 259.145283 -52.995834) (xy 259.157409 -52.941397) (xy 259.177332 -52.889306) (xy 259.204628 -52.840671)
			(xy 259.238714 -52.796528) (xy 259.278863 -52.757819) (xy 259.324221 -52.725368) (xy 259.373821 -52.699867)
			(xy 259.426605 -52.68186) (xy 259.481448 -52.67173) (xy 259.537182 -52.669693) (xy 259.592619 -52.675793)
			(xy 259.646576 -52.689899) (xy 259.697905 -52.711711) (xy 259.745511 -52.740765) (xy 259.788379 -52.77644)
			(xy 259.825596 -52.817977) (xy 259.856369 -52.86449) (xy 259.880041 -52.914987) (xy 259.896109 -52.968394)
			(xy 259.904229 -53.02357) (xy 259.904738 -53.051456) (xy 259.904229 -53.079342) (xy 259.896109 -53.134518)
			(xy 259.880041 -53.187925) (xy 259.856369 -53.238422) (xy 259.825596 -53.284935) (xy 259.788379 -53.326472)
			(xy 259.745511 -53.362147) (xy 259.697905 -53.391201) (xy 259.646576 -53.413013) (xy 259.592619 -53.427119)
			(xy 259.537182 -53.433219) (xy 259.481448 -53.431182) (xy 259.426605 -53.421052) (xy 259.373821 -53.403045)
			(xy 259.324221 -53.377544) (xy 259.278863 -53.345093) (xy 259.238714 -53.306384) (xy 259.204628 -53.262241)
			(xy 259.177332 -53.213606) (xy 259.157409 -53.161515) (xy 259.145283 -53.107078) (xy 259.141212 -53.051456)
			(xy 250.88225 -53.051456) (xy 250.876476 -53.09095) (xy 250.860653 -53.143974) (xy 250.837342 -53.194159)
			(xy 250.807033 -53.240454) (xy 250.770359 -53.28189) (xy 250.728089 -53.317599) (xy 250.704858 -53.332634)
			(xy 250.695169 -53.339256) (xy 250.68273 -53.359128) (xy 250.680982 -53.370734) (xy 250.673108 -53.450744)
			(xy 250.672469 -53.462382) (xy 250.680556 -53.484219) (xy 250.688602 -53.492654) (xy 250.688856 -53.492908)
			(xy 250.707415 -53.511011) (xy 250.739997 -53.551337) (xy 250.766814 -53.595707) (xy 250.787371 -53.643301)
			(xy 250.801289 -53.693242) (xy 250.80831 -53.744608) (xy 250.808744 -53.77053) (xy 250.80825 -53.79778)
			(xy 250.800491 -53.851726) (xy 250.785133 -53.904018) (xy 250.762491 -53.953593) (xy 250.733025 -53.999442)
			(xy 250.697335 -54.040631) (xy 250.656147 -54.076322) (xy 250.610299 -54.105789) (xy 250.560724 -54.128431)
			(xy 250.508432 -54.143789) (xy 250.454486 -54.15155) (xy 250.427236 -54.152038) (xy 250.399866 -54.151566)
			(xy 250.345686 -54.143752) (xy 250.293183 -54.128265) (xy 250.243436 -54.105424) (xy 250.197469 -54.0757)
			(xy 250.176538 -54.058058) (xy 250.176284 -54.057804) (xy 250.169206 -54.052205) (xy 250.152283 -54.045966)
			(xy 250.143264 -54.045612) (xy 250.076208 -54.045612) (xy 250.067191 -54.04597) (xy 250.050274 -54.052217)
			(xy 250.043188 -54.057804) (xy 250.043188 -54.058058) (xy 250.042934 -54.058058) (xy 250.021995 -54.075688)
			(xy 249.976024 -54.105403) (xy 249.926279 -54.128241) (xy 249.87378 -54.143734) (xy 249.819605 -54.151564)
			(xy 249.792236 -54.152038) (xy 249.764985 -54.151511) (xy 249.711038 -54.14376) (xy 249.658743 -54.12841)
			(xy 249.609165 -54.105774) (xy 249.563314 -54.076312) (xy 249.522121 -54.040625) (xy 249.486427 -53.999439)
			(xy 249.456958 -53.953593) (xy 249.434313 -53.904018) (xy 249.418954 -53.851726) (xy 249.411193 -53.797781)
			(xy 249.410728 -53.77053) (xy 249.046546 -53.77053) (xy 249.045476 -53.7718) (xy 249.045222 -53.772054)
			(xy 249.039639 -53.779143) (xy 249.033392 -53.796058) (xy 249.03303 -53.805074) (xy 249.03303 -53.87213)
			(xy 249.033366 -53.881149) (xy 249.039627 -53.898066) (xy 249.045222 -53.90515) (xy 249.045476 -53.90515)
			(xy 249.045476 -53.905404) (xy 249.063119 -53.926335) (xy 249.092843 -53.972303) (xy 249.115688 -54.02205)
			(xy 249.131184 -54.074552) (xy 249.139012 -54.128731) (xy 249.139012 -54.183472) (xy 249.131183 -54.237651)
			(xy 249.115687 -54.290153) (xy 249.101895 -54.320186) (xy 251.33046 -54.320186) (xy 251.330903 -54.292815)
			(xy 251.338724 -54.238634) (xy 251.354218 -54.18613) (xy 251.377065 -54.136384) (xy 251.406796 -54.090418)
			(xy 251.42444 -54.069488) (xy 251.424694 -54.069234) (xy 251.430272 -54.062141) (xy 251.436524 -54.045229)
			(xy 251.436886 -54.036214) (xy 251.436886 -53.969158) (xy 251.436504 -53.960144) (xy 251.430274 -53.943226)
			(xy 251.424694 -53.936138) (xy 251.42444 -53.936138) (xy 251.42444 -53.935884) (xy 251.406833 -53.914926)
			(xy 251.377115 -53.868961) (xy 251.354272 -53.81922) (xy 251.338774 -53.766725) (xy 251.330938 -53.712553)
			(xy 251.33046 -53.685186) (xy 251.330946 -53.657935) (xy 251.338702 -53.603987) (xy 251.354057 -53.551692)
			(xy 251.376699 -53.502115) (xy 251.406165 -53.456265) (xy 251.441856 -53.415074) (xy 251.483047 -53.379383)
			(xy 251.528897 -53.349917) (xy 251.578474 -53.327275) (xy 251.630769 -53.31192) (xy 251.684717 -53.304164)
			(xy 251.739219 -53.304164) (xy 251.793167 -53.31192) (xy 251.845462 -53.327275) (xy 251.895039 -53.349917)
			(xy 251.940889 -53.379383) (xy 251.98208 -53.415074) (xy 252.017771 -53.456265) (xy 252.043661 -53.496551)
			(xy 264.333464 -53.496551) (xy 264.333464 -53.442049) (xy 264.34122 -53.3881) (xy 264.356575 -53.335805)
			(xy 264.379216 -53.286227) (xy 264.408681 -53.240376) (xy 264.444372 -53.199185) (xy 264.485562 -53.163492)
			(xy 264.531412 -53.134024) (xy 264.580988 -53.111381) (xy 264.633283 -53.096024) (xy 264.687231 -53.088265)
			(xy 264.714482 -53.087778) (xy 264.741853 -53.088236) (xy 264.796033 -53.096053) (xy 264.848537 -53.111543)
			(xy 264.898284 -53.134387) (xy 264.944249 -53.164115) (xy 264.96518 -53.181758) (xy 264.965434 -53.182012)
			(xy 264.972534 -53.187578) (xy 264.989441 -53.193837) (xy 264.998454 -53.194204) (xy 265.06551 -53.194204)
			(xy 265.074527 -53.193851) (xy 265.091444 -53.1876) (xy 265.09853 -53.182012) (xy 265.09853 -53.181758)
			(xy 265.098784 -53.181758) (xy 265.119706 -53.164106) (xy 265.165682 -53.134397) (xy 265.215432 -53.111565)
			(xy 265.267935 -53.096076) (xy 265.322112 -53.08825) (xy 265.349482 -53.087778) (xy 265.376735 -53.088268)
			(xy 265.430686 -53.096023) (xy 265.482984 -53.111377) (xy 265.532564 -53.134017) (xy 265.578418 -53.163484)
			(xy 265.619611 -53.199176) (xy 265.655306 -53.240368) (xy 265.684774 -53.28622) (xy 265.707417 -53.335799)
			(xy 265.722773 -53.388097) (xy 265.730531 -53.442047) (xy 265.730531 -53.496553) (xy 265.722773 -53.550503)
			(xy 265.707417 -53.602801) (xy 265.684774 -53.65238) (xy 265.655306 -53.698232) (xy 265.619611 -53.739424)
			(xy 265.578418 -53.775116) (xy 265.532564 -53.804583) (xy 265.482984 -53.827223) (xy 265.430686 -53.842577)
			(xy 265.376735 -53.850332) (xy 265.349482 -53.850794) (xy 265.322111 -53.85034) (xy 265.267932 -53.842519)
			(xy 265.215428 -53.827028) (xy 265.165682 -53.804183) (xy 265.119715 -53.774456) (xy 265.098784 -53.756814)
			(xy 265.09853 -53.75656) (xy 265.091443 -53.750975) (xy 265.074526 -53.744728) (xy 265.06551 -53.744368)
			(xy 264.998454 -53.744368) (xy 264.989441 -53.744758) (xy 264.972524 -53.750983) (xy 264.965434 -53.75656)
			(xy 264.965434 -53.756814) (xy 264.96518 -53.756814) (xy 264.94423 -53.774431) (xy 264.898262 -53.804146)
			(xy 264.848519 -53.826986) (xy 264.796022 -53.842482) (xy 264.74185 -53.850316) (xy 264.714482 -53.850794)
			(xy 264.687231 -53.850335) (xy 264.633283 -53.842576) (xy 264.580988 -53.827219) (xy 264.531412 -53.804576)
			(xy 264.485562 -53.775108) (xy 264.444372 -53.739415) (xy 264.408681 -53.698224) (xy 264.379216 -53.652373)
			(xy 264.356575 -53.602795) (xy 264.34122 -53.5505) (xy 264.333464 -53.496551) (xy 252.043661 -53.496551)
			(xy 252.047237 -53.502115) (xy 252.069879 -53.551692) (xy 252.085234 -53.603987) (xy 252.09299 -53.657935)
			(xy 252.093476 -53.685186) (xy 252.093008 -53.712556) (xy 252.085191 -53.766735) (xy 252.069703 -53.819239)
			(xy 252.046862 -53.868986) (xy 252.017137 -53.914952) (xy 251.999496 -53.935884) (xy 251.999242 -53.936138)
			(xy 251.993668 -53.943233) (xy 251.987415 -53.960144) (xy 251.98705 -53.969158) (xy 251.98705 -54.036214)
			(xy 251.98739 -54.045233) (xy 251.993648 -54.06215) (xy 251.999242 -54.069234) (xy 251.999496 -54.069234)
			(xy 251.999496 -54.069488) (xy 252.017142 -54.090414) (xy 252.046853 -54.136389) (xy 252.069688 -54.186138)
			(xy 252.085177 -54.23864) (xy 252.093003 -54.292816) (xy 252.093476 -54.320186) (xy 252.09299 -54.347437)
			(xy 252.085234 -54.401385) (xy 252.069879 -54.45368) (xy 252.047237 -54.503257) (xy 252.017771 -54.549107)
			(xy 251.98208 -54.590298) (xy 251.940889 -54.625989) (xy 251.895039 -54.655455) (xy 251.845462 -54.678097)
			(xy 251.793167 -54.693452) (xy 251.739219 -54.701208) (xy 251.684717 -54.701208) (xy 251.630769 -54.693452)
			(xy 251.578474 -54.678097) (xy 251.528897 -54.655455) (xy 251.483047 -54.625989) (xy 251.441856 -54.590298)
			(xy 251.406165 -54.549107) (xy 251.376699 -54.503257) (xy 251.354057 -54.45368) (xy 251.338702 -54.401385)
			(xy 251.330946 -54.347437) (xy 251.33046 -54.320186) (xy 249.101895 -54.320186) (xy 249.092842 -54.339899)
			(xy 249.063117 -54.385867) (xy 249.045476 -54.4068) (xy 249.045222 -54.407054) (xy 249.039639 -54.414143)
			(xy 249.033392 -54.431058) (xy 249.03303 -54.440074) (xy 249.03303 -54.50713) (xy 249.033366 -54.516149)
			(xy 249.039627 -54.533066) (xy 249.045222 -54.54015) (xy 249.045476 -54.54015) (xy 249.045476 -54.540404)
			(xy 249.063127 -54.561327) (xy 249.092838 -54.607302) (xy 249.115672 -54.657052) (xy 249.13116 -54.709554)
			(xy 249.138984 -54.763732) (xy 249.139101 -54.770528) (xy 252.271022 -54.770528) (xy 252.271499 -54.743158)
			(xy 252.279313 -54.688979) (xy 252.2948 -54.636476) (xy 252.317639 -54.586729) (xy 252.347362 -54.540762)
			(xy 252.365002 -54.51983) (xy 252.365256 -54.519576) (xy 252.370865 -54.512505) (xy 252.377097 -54.495576)
			(xy 252.377448 -54.486556) (xy 252.377448 -54.4195) (xy 252.377102 -54.410482) (xy 252.370848 -54.393564)
			(xy 252.365256 -54.38648) (xy 252.365002 -54.38648) (xy 252.365002 -54.386226) (xy 252.347362 -54.365295)
			(xy 252.31765 -54.319322) (xy 252.294814 -54.269574) (xy 252.279324 -54.217073) (xy 252.271496 -54.162897)
			(xy 252.271022 -54.135528) (xy 252.271508 -54.108277) (xy 252.279264 -54.054329) (xy 252.294619 -54.002034)
			(xy 252.317261 -53.952457) (xy 252.346727 -53.906607) (xy 252.382418 -53.865416) (xy 252.423609 -53.829725)
			(xy 252.469459 -53.800259) (xy 252.519036 -53.777617) (xy 252.571331 -53.762262) (xy 252.625279 -53.754506)
			(xy 252.679781 -53.754506) (xy 252.733729 -53.762262) (xy 252.786024 -53.777617) (xy 252.835601 -53.800259)
			(xy 252.881451 -53.829725) (xy 252.922642 -53.865416) (xy 252.958333 -53.906607) (xy 252.987799 -53.952457)
			(xy 252.992874 -53.96357) (xy 256.972052 -53.96357) (xy 256.976123 -53.907948) (xy 256.988249 -53.853511)
			(xy 257.008172 -53.80142) (xy 257.035468 -53.752785) (xy 257.069554 -53.708642) (xy 257.109703 -53.669933)
			(xy 257.155061 -53.637482) (xy 257.204661 -53.611981) (xy 257.257445 -53.593974) (xy 257.312288 -53.583844)
			(xy 257.368022 -53.581807) (xy 257.423459 -53.587907) (xy 257.477416 -53.602013) (xy 257.528745 -53.623825)
			(xy 257.576351 -53.652879) (xy 257.619219 -53.688554) (xy 257.656436 -53.730091) (xy 257.687209 -53.776604)
			(xy 257.710881 -53.827101) (xy 257.726949 -53.880508) (xy 257.735069 -53.935684) (xy 257.735578 -53.96357)
			(xy 257.735069 -53.991456) (xy 257.726949 -54.046632) (xy 257.710881 -54.100039) (xy 257.687209 -54.150536)
			(xy 257.656436 -54.197049) (xy 257.619219 -54.238586) (xy 257.576351 -54.274261) (xy 257.528745 -54.303315)
			(xy 257.477416 -54.325127) (xy 257.423459 -54.339233) (xy 257.368022 -54.345333) (xy 257.312288 -54.343296)
			(xy 257.257445 -54.333166) (xy 257.204661 -54.315159) (xy 257.155061 -54.289658) (xy 257.109703 -54.257207)
			(xy 257.069554 -54.218498) (xy 257.035468 -54.174355) (xy 257.008172 -54.12572) (xy 256.988249 -54.073629)
			(xy 256.976123 -54.019192) (xy 256.972052 -53.96357) (xy 252.992874 -53.96357) (xy 253.010441 -54.002034)
			(xy 253.025796 -54.054329) (xy 253.033552 -54.108277) (xy 253.034038 -54.135528) (xy 253.033603 -54.1629)
			(xy 253.02578 -54.217081) (xy 253.010285 -54.269585) (xy 252.987436 -54.319331) (xy 252.957703 -54.365296)
			(xy 252.940058 -54.386226) (xy 252.939804 -54.38648) (xy 252.93422 -54.393568) (xy 252.927972 -54.410484)
			(xy 252.927612 -54.4195) (xy 252.927612 -54.486556) (xy 252.927988 -54.495571) (xy 252.934222 -54.512488)
			(xy 252.939804 -54.519576) (xy 252.940058 -54.519576) (xy 252.940058 -54.51983) (xy 252.957671 -54.540783)
			(xy 252.987388 -54.586749) (xy 253.01023 -54.636492) (xy 253.025727 -54.688988) (xy 253.033561 -54.74316)
			(xy 253.034038 -54.770528) (xy 253.033552 -54.797779) (xy 253.025796 -54.851727) (xy 253.010441 -54.904022)
			(xy 252.987799 -54.953599) (xy 252.965015 -54.989051) (xy 262.101068 -54.989051) (xy 262.101068 -54.934549)
			(xy 262.108824 -54.880602) (xy 262.124178 -54.828308) (xy 262.146818 -54.778731) (xy 262.176283 -54.732881)
			(xy 262.211973 -54.69169) (xy 262.253161 -54.655997) (xy 262.29901 -54.62653) (xy 262.348585 -54.603887)
			(xy 262.400879 -54.588529) (xy 262.454825 -54.580769) (xy 262.482076 -54.580282) (xy 262.510167 -54.580796)
			(xy 262.565743 -54.58902) (xy 262.619512 -54.605307) (xy 262.670309 -54.629307) (xy 262.717036 -54.660499)
			(xy 262.758682 -54.698208) (xy 262.794345 -54.741619) (xy 262.809228 -54.765448) (xy 262.814562 -54.774338)
			(xy 262.83158 -54.78653) (xy 262.924798 -54.80685) (xy 262.945372 -54.802532) (xy 262.954008 -54.79669)
			(xy 262.978068 -54.780683) (xy 263.030001 -54.755342) (xy 263.08516 -54.738119) (xy 263.142285 -54.729406)
			(xy 263.171178 -54.728872) (xy 263.198429 -54.729376) (xy 263.252378 -54.737129) (xy 263.304674 -54.752481)
			(xy 263.354252 -54.77512) (xy 263.400105 -54.804584) (xy 263.441297 -54.840273) (xy 263.476991 -54.881462)
			(xy 263.50646 -54.927311) (xy 263.529104 -54.976887) (xy 263.544462 -55.029181) (xy 263.552221 -55.083129)
			(xy 263.552686 -55.11038) (xy 263.552212 -55.13775) (xy 263.544396 -55.191929) (xy 263.528909 -55.244432)
			(xy 263.506069 -55.294179) (xy 263.476346 -55.340146) (xy 263.458706 -55.361078) (xy 263.458452 -55.361332)
			(xy 263.452882 -55.36843) (xy 263.446627 -55.385338) (xy 263.44626 -55.394352) (xy 263.44626 -55.461408)
			(xy 263.4466 -55.470427) (xy 263.452858 -55.487344) (xy 263.458452 -55.494428) (xy 263.458706 -55.494428)
			(xy 263.458706 -55.494682) (xy 263.476326 -55.515631) (xy 263.506049 -55.561597) (xy 263.528893 -55.611341)
			(xy 263.54439 -55.66384) (xy 263.552219 -55.718016) (xy 263.552222 -55.772754) (xy 263.544396 -55.826931)
			(xy 263.528904 -55.879431) (xy 263.506063 -55.929177) (xy 263.476344 -55.975145) (xy 263.458706 -55.996078)
			(xy 263.458452 -55.996332) (xy 263.452882 -56.00343) (xy 263.446627 -56.020338) (xy 263.44626 -56.029352)
			(xy 263.44626 -56.096408) (xy 263.4466 -56.105427) (xy 263.452858 -56.122344) (xy 263.458452 -56.129428)
			(xy 263.458706 -56.129428) (xy 263.458706 -56.129682) (xy 263.476351 -56.150609) (xy 263.506062 -56.196583)
			(xy 263.528896 -56.246332) (xy 263.544386 -56.298834) (xy 263.552213 -56.353011) (xy 263.552686 -56.38038)
			(xy 263.5522 -56.407631) (xy 263.544444 -56.461579) (xy 263.529089 -56.513874) (xy 263.506447 -56.563451)
			(xy 263.476981 -56.609301) (xy 263.44129 -56.650492) (xy 263.400099 -56.686183) (xy 263.354249 -56.715649)
			(xy 263.304672 -56.738291) (xy 263.252377 -56.753646) (xy 263.198429 -56.761402) (xy 263.143927 -56.761402)
			(xy 263.089979 -56.753646) (xy 263.037684 -56.738291) (xy 262.988107 -56.715649) (xy 262.942257 -56.686183)
			(xy 262.901066 -56.650492) (xy 262.865375 -56.609301) (xy 262.835909 -56.563451) (xy 262.813267 -56.513874)
			(xy 262.797912 -56.461579) (xy 262.790156 -56.407631) (xy 262.78967 -56.38038) (xy 262.790107 -56.353009)
			(xy 262.797929 -56.298828) (xy 262.813424 -56.246323) (xy 262.836273 -56.196577) (xy 262.866005 -56.150612)
			(xy 262.88365 -56.129682) (xy 262.883904 -56.129428) (xy 262.889485 -56.122338) (xy 262.895735 -56.105424)
			(xy 262.896096 -56.096408) (xy 262.896096 -56.029352) (xy 262.895715 -56.020338) (xy 262.889484 -56.00342)
			(xy 262.883904 -55.996332) (xy 262.88365 -55.996332) (xy 262.88365 -55.996078) (xy 262.865989 -55.975162)
			(xy 262.836263 -55.929192) (xy 262.813417 -55.879443) (xy 262.797922 -55.826938) (xy 262.790094 -55.772757)
			(xy 262.790097 -55.718013) (xy 262.797928 -55.663833) (xy 262.813428 -55.611329) (xy 262.836278 -55.561582)
			(xy 262.866007 -55.515614) (xy 262.88365 -55.494682) (xy 262.883904 -55.494428) (xy 262.889485 -55.487338)
			(xy 262.895735 -55.470424) (xy 262.896096 -55.461408) (xy 262.896096 -55.394352) (xy 262.895715 -55.385338)
			(xy 262.889484 -55.36842) (xy 262.883904 -55.361332) (xy 262.88365 -55.360824) (xy 262.872704 -55.348092)
			(xy 262.852864 -55.320999) (xy 262.844026 -55.306722) (xy 262.838692 -55.297832) (xy 262.821674 -55.28564)
			(xy 262.728456 -55.26532) (xy 262.707882 -55.269638) (xy 262.699246 -55.27548) (xy 262.67517 -55.29146)
			(xy 262.623243 -55.316808) (xy 262.568089 -55.334039) (xy 262.510967 -55.34276) (xy 262.482076 -55.343298)
			(xy 262.454825 -55.342831) (xy 262.400879 -55.335071) (xy 262.348585 -55.319713) (xy 262.29901 -55.29707)
			(xy 262.253161 -55.267603) (xy 262.211973 -55.23191) (xy 262.176283 -55.190719) (xy 262.146818 -55.144869)
			(xy 262.124178 -55.095292) (xy 262.108824 -55.042998) (xy 262.101068 -54.989051) (xy 252.965015 -54.989051)
			(xy 252.958333 -54.999449) (xy 252.922642 -55.04064) (xy 252.881451 -55.076331) (xy 252.835601 -55.105797)
			(xy 252.786024 -55.128439) (xy 252.733729 -55.143794) (xy 252.679781 -55.15155) (xy 252.625279 -55.15155)
			(xy 252.571331 -55.143794) (xy 252.519036 -55.128439) (xy 252.469459 -55.105797) (xy 252.423609 -55.076331)
			(xy 252.382418 -55.04064) (xy 252.346727 -54.999449) (xy 252.317261 -54.953599) (xy 252.294619 -54.904022)
			(xy 252.279264 -54.851727) (xy 252.271508 -54.797779) (xy 252.271022 -54.770528) (xy 249.139101 -54.770528)
			(xy 249.139456 -54.791102) (xy 249.13897 -54.818353) (xy 249.131214 -54.872301) (xy 249.115859 -54.924596)
			(xy 249.093217 -54.974173) (xy 249.063751 -55.020023) (xy 249.02806 -55.061214) (xy 248.986869 -55.096905)
			(xy 248.941019 -55.126371) (xy 248.891442 -55.149013) (xy 248.839147 -55.164368) (xy 248.785199 -55.172124)
			(xy 248.730697 -55.172124) (xy 248.676749 -55.164368) (xy 248.624454 -55.149013) (xy 248.574877 -55.126371)
			(xy 248.529027 -55.096905) (xy 248.487836 -55.061214) (xy 248.452145 -55.020023) (xy 248.422679 -54.974173)
			(xy 248.400037 -54.924596) (xy 248.384682 -54.872301) (xy 248.376926 -54.818353) (xy 248.37644 -54.791102)
			(xy 246.478482 -54.791102) (xy 246.47539 -54.812611) (xy 246.460035 -54.864906) (xy 246.437393 -54.914483)
			(xy 246.407927 -54.960333) (xy 246.372236 -55.001524) (xy 246.331045 -55.037215) (xy 246.285195 -55.066681)
			(xy 246.235618 -55.089323) (xy 246.183323 -55.104678) (xy 246.129375 -55.112434) (xy 246.074873 -55.112434)
			(xy 246.020925 -55.104678) (xy 245.96863 -55.089323) (xy 245.919053 -55.066681) (xy 245.873203 -55.037215)
			(xy 245.832012 -55.001524) (xy 245.796321 -54.960333) (xy 245.766855 -54.914483) (xy 245.744213 -54.864906)
			(xy 245.728858 -54.812611) (xy 245.721102 -54.758663) (xy 245.720616 -54.731412) (xy 241.720641 -54.731412)
			(xy 241.725957 -54.767534) (xy 241.726466 -54.79542) (xy 241.725957 -54.823306) (xy 241.717837 -54.878482)
			(xy 241.701769 -54.931889) (xy 241.678097 -54.982386) (xy 241.647324 -55.028899) (xy 241.610107 -55.070436)
			(xy 241.567239 -55.106111) (xy 241.519633 -55.135165) (xy 241.468304 -55.156977) (xy 241.414347 -55.171083)
			(xy 241.35891 -55.177183) (xy 241.303176 -55.175146) (xy 241.248333 -55.165016) (xy 241.195549 -55.147009)
			(xy 241.145949 -55.121508) (xy 241.100591 -55.089057) (xy 241.060442 -55.050348) (xy 241.026356 -55.006205)
			(xy 240.99906 -54.95757) (xy 240.979137 -54.905479) (xy 240.967011 -54.851042) (xy 240.96294 -54.79542)
			(xy 239.69496 -54.79542) (xy 239.694465 -54.822544) (xy 239.686345 -54.87772) (xy 239.670277 -54.931127)
			(xy 239.646605 -54.981624) (xy 239.615832 -55.028137) (xy 239.578615 -55.069674) (xy 239.535747 -55.105349)
			(xy 239.488141 -55.134403) (xy 239.436812 -55.156215) (xy 239.382855 -55.170321) (xy 239.327418 -55.176421)
			(xy 239.271684 -55.174384) (xy 239.216841 -55.164254) (xy 239.164057 -55.146247) (xy 239.114457 -55.120746)
			(xy 239.069099 -55.088295) (xy 239.02895 -55.049586) (xy 238.994864 -55.005443) (xy 238.967568 -54.956808)
			(xy 238.947645 -54.904717) (xy 238.935519 -54.85028) (xy 238.931448 -54.794658) (xy 214.933608 -54.794658)
			(xy 214.933552 -54.797779) (xy 214.925796 -54.851727) (xy 214.910441 -54.904022) (xy 214.887799 -54.953599)
			(xy 214.858333 -54.999449) (xy 214.822642 -55.04064) (xy 214.781451 -55.076331) (xy 214.735601 -55.105797)
			(xy 214.686024 -55.128439) (xy 214.633729 -55.143794) (xy 214.579781 -55.15155) (xy 214.525279 -55.15155)
			(xy 214.471331 -55.143794) (xy 214.419036 -55.128439) (xy 214.369459 -55.105797) (xy 214.323609 -55.076331)
			(xy 214.282418 -55.04064) (xy 214.246727 -54.999449) (xy 214.217261 -54.953599) (xy 214.194619 -54.904022)
			(xy 214.179264 -54.851727) (xy 214.171508 -54.797779) (xy 214.171022 -54.770528) (xy 211.039101 -54.770528)
			(xy 211.039456 -54.791102) (xy 211.03897 -54.818353) (xy 211.031214 -54.872301) (xy 211.015859 -54.924596)
			(xy 210.993217 -54.974173) (xy 210.963751 -55.020023) (xy 210.92806 -55.061214) (xy 210.886869 -55.096905)
			(xy 210.841019 -55.126371) (xy 210.791442 -55.149013) (xy 210.739147 -55.164368) (xy 210.685199 -55.172124)
			(xy 210.630697 -55.172124) (xy 210.576749 -55.164368) (xy 210.524454 -55.149013) (xy 210.474877 -55.126371)
			(xy 210.429027 -55.096905) (xy 210.387836 -55.061214) (xy 210.352145 -55.020023) (xy 210.322679 -54.974173)
			(xy 210.300037 -54.924596) (xy 210.284682 -54.872301) (xy 210.276926 -54.818353) (xy 210.27644 -54.791102)
			(xy 208.378482 -54.791102) (xy 208.37539 -54.812611) (xy 208.360035 -54.864906) (xy 208.337393 -54.914483)
			(xy 208.307927 -54.960333) (xy 208.272236 -55.001524) (xy 208.231045 -55.037215) (xy 208.185195 -55.066681)
			(xy 208.135618 -55.089323) (xy 208.083323 -55.104678) (xy 208.029375 -55.112434) (xy 207.974873 -55.112434)
			(xy 207.920925 -55.104678) (xy 207.86863 -55.089323) (xy 207.819053 -55.066681) (xy 207.773203 -55.037215)
			(xy 207.732012 -55.001524) (xy 207.696321 -54.960333) (xy 207.666855 -54.914483) (xy 207.644213 -54.864906)
			(xy 207.628858 -54.812611) (xy 207.621102 -54.758663) (xy 207.620616 -54.731412) (xy 206.646892 -54.731412)
			(xy 206.706285 -55.722266) (xy 219.934026 -55.722266) (xy 219.938097 -55.666644) (xy 219.950223 -55.612207)
			(xy 219.970146 -55.560116) (xy 219.997442 -55.511481) (xy 220.031528 -55.467338) (xy 220.071677 -55.428629)
			(xy 220.117035 -55.396178) (xy 220.166635 -55.370677) (xy 220.219419 -55.35267) (xy 220.274262 -55.34254)
			(xy 220.329996 -55.340503) (xy 220.385433 -55.346603) (xy 220.43939 -55.360709) (xy 220.490719 -55.382521)
			(xy 220.532579 -55.408068) (xy 237.462312 -55.408068) (xy 237.466383 -55.352446) (xy 237.478509 -55.298009)
			(xy 237.498432 -55.245918) (xy 237.525728 -55.197283) (xy 237.559814 -55.15314) (xy 237.599963 -55.114431)
			(xy 237.645321 -55.08198) (xy 237.694921 -55.056479) (xy 237.747705 -55.038472) (xy 237.802548 -55.028342)
			(xy 237.858282 -55.026305) (xy 237.913719 -55.032405) (xy 237.967676 -55.046511) (xy 238.019005 -55.068323)
			(xy 238.066611 -55.097377) (xy 238.109479 -55.133052) (xy 238.146696 -55.174589) (xy 238.177469 -55.221102)
			(xy 238.201141 -55.271599) (xy 238.217209 -55.325006) (xy 238.225329 -55.380182) (xy 238.225838 -55.408068)
			(xy 238.225329 -55.435954) (xy 238.217209 -55.49113) (xy 238.201141 -55.544537) (xy 238.177469 -55.595034)
			(xy 238.146696 -55.641547) (xy 238.109479 -55.683084) (xy 238.066611 -55.718759) (xy 238.060865 -55.722266)
			(xy 258.034026 -55.722266) (xy 258.038097 -55.666644) (xy 258.050223 -55.612207) (xy 258.070146 -55.560116)
			(xy 258.097442 -55.511481) (xy 258.131528 -55.467338) (xy 258.171677 -55.428629) (xy 258.217035 -55.396178)
			(xy 258.266635 -55.370677) (xy 258.319419 -55.35267) (xy 258.374262 -55.34254) (xy 258.429996 -55.340503)
			(xy 258.485433 -55.346603) (xy 258.53939 -55.360709) (xy 258.590719 -55.382521) (xy 258.638325 -55.411575)
			(xy 258.649471 -55.420851) (xy 260.424668 -55.420851) (xy 260.424668 -55.366349) (xy 260.432424 -55.312402)
			(xy 260.447778 -55.260108) (xy 260.470418 -55.210531) (xy 260.499883 -55.164681) (xy 260.535573 -55.12349)
			(xy 260.576761 -55.087797) (xy 260.62261 -55.05833) (xy 260.672185 -55.035687) (xy 260.724479 -55.020329)
			(xy 260.778425 -55.012569) (xy 260.805676 -55.012082) (xy 260.831989 -55.012571) (xy 260.884116 -55.019802)
			(xy 260.934759 -55.034118) (xy 260.982958 -55.055246) (xy 261.027802 -55.082788) (xy 261.068442 -55.116222)
			(xy 261.0866 -55.135272) (xy 261.094123 -55.142672) (xy 261.113402 -55.151198) (xy 261.123938 -55.151782)
			(xy 261.198614 -55.151782) (xy 261.209167 -55.151279) (xy 261.228462 -55.142726) (xy 261.235952 -55.135272)
			(xy 261.254084 -55.116193) (xy 261.294719 -55.082739) (xy 261.339565 -55.055184) (xy 261.38777 -55.03405)
			(xy 261.438421 -55.019737) (xy 261.490559 -55.012518) (xy 261.516876 -55.012082) (xy 261.544129 -55.012564)
			(xy 261.598081 -55.020318) (xy 261.650381 -55.035671) (xy 261.699963 -55.058312) (xy 261.745817 -55.087778)
			(xy 261.787012 -55.123471) (xy 261.822707 -55.164663) (xy 261.852177 -55.210516) (xy 261.87482 -55.260097)
			(xy 261.890177 -55.312395) (xy 261.897935 -55.366347) (xy 261.897935 -55.420853) (xy 261.890177 -55.474805)
			(xy 261.87482 -55.527103) (xy 261.852177 -55.576684) (xy 261.822707 -55.622537) (xy 261.787012 -55.663729)
			(xy 261.745817 -55.699422) (xy 261.699963 -55.728888) (xy 261.650381 -55.751529) (xy 261.598081 -55.766882)
			(xy 261.544129 -55.774636) (xy 261.516876 -55.775098) (xy 261.490561 -55.774647) (xy 261.438432 -55.767409)
			(xy 261.387789 -55.753087) (xy 261.33959 -55.731951) (xy 261.294747 -55.704402) (xy 261.254108 -55.670961)
			(xy 261.235952 -55.651908) (xy 261.228449 -55.644484) (xy 261.209155 -55.635972) (xy 261.198614 -55.635398)
			(xy 261.123938 -55.635398) (xy 261.113389 -55.635935) (xy 261.094094 -55.644465) (xy 261.0866 -55.651908)
			(xy 261.068439 -55.670958) (xy 261.02781 -55.704415) (xy 260.982971 -55.731975) (xy 260.934771 -55.753114)
			(xy 260.884125 -55.767433) (xy 260.831992 -55.774659) (xy 260.805676 -55.775098) (xy 260.778425 -55.774631)
			(xy 260.724479 -55.766871) (xy 260.672185 -55.751513) (xy 260.62261 -55.72887) (xy 260.576761 -55.699403)
			(xy 260.535573 -55.66371) (xy 260.499883 -55.622519) (xy 260.470418 -55.576669) (xy 260.447778 -55.527092)
			(xy 260.432424 -55.474798) (xy 260.424668 -55.420851) (xy 258.649471 -55.420851) (xy 258.681193 -55.44725)
			(xy 258.71841 -55.488787) (xy 258.749183 -55.5353) (xy 258.772855 -55.585797) (xy 258.788923 -55.639204)
			(xy 258.797043 -55.69438) (xy 258.797552 -55.722266) (xy 258.797043 -55.750152) (xy 258.788923 -55.805328)
			(xy 258.772855 -55.858735) (xy 258.749183 -55.909232) (xy 258.71841 -55.955745) (xy 258.681193 -55.997282)
			(xy 258.638325 -56.032957) (xy 258.590719 -56.062011) (xy 258.53939 -56.083823) (xy 258.485433 -56.097929)
			(xy 258.429996 -56.104029) (xy 258.374262 -56.101992) (xy 258.319419 -56.091862) (xy 258.266635 -56.073855)
			(xy 258.217035 -56.048354) (xy 258.171677 -56.015903) (xy 258.131528 -55.977194) (xy 258.097442 -55.933051)
			(xy 258.070146 -55.884416) (xy 258.050223 -55.832325) (xy 258.038097 -55.777888) (xy 258.034026 -55.722266)
			(xy 238.060865 -55.722266) (xy 238.019005 -55.747813) (xy 237.967676 -55.769625) (xy 237.913719 -55.783731)
			(xy 237.858282 -55.789831) (xy 237.802548 -55.787794) (xy 237.747705 -55.777664) (xy 237.694921 -55.759657)
			(xy 237.645321 -55.734156) (xy 237.599963 -55.701705) (xy 237.559814 -55.662996) (xy 237.525728 -55.618853)
			(xy 237.498432 -55.570218) (xy 237.478509 -55.518127) (xy 237.466383 -55.46369) (xy 237.462312 -55.408068)
			(xy 220.532579 -55.408068) (xy 220.538325 -55.411575) (xy 220.581193 -55.44725) (xy 220.61841 -55.488787)
			(xy 220.649183 -55.5353) (xy 220.672855 -55.585797) (xy 220.688923 -55.639204) (xy 220.697043 -55.69438)
			(xy 220.697552 -55.722266) (xy 220.697043 -55.750152) (xy 220.688923 -55.805328) (xy 220.672855 -55.858735)
			(xy 220.649183 -55.909232) (xy 220.61841 -55.955745) (xy 220.581193 -55.997282) (xy 220.538325 -56.032957)
			(xy 220.490719 -56.062011) (xy 220.43939 -56.083823) (xy 220.385433 -56.097929) (xy 220.329996 -56.104029)
			(xy 220.274262 -56.101992) (xy 220.219419 -56.091862) (xy 220.166635 -56.073855) (xy 220.117035 -56.048354)
			(xy 220.071677 -56.015903) (xy 220.031528 -55.977194) (xy 219.997442 -55.933051) (xy 219.970146 -55.884416)
			(xy 219.950223 -55.832325) (xy 219.938097 -55.777888) (xy 219.934026 -55.722266) (xy 206.706285 -55.722266)
			(xy 206.745078 -56.369458) (xy 206.783048 -57.002934) (xy 215.663526 -57.002934) (xy 215.664026 -56.974842)
			(xy 215.67225 -56.919265) (xy 215.688538 -56.865495) (xy 215.71254 -56.814696) (xy 215.743734 -56.767969)
			(xy 215.781447 -56.726325) (xy 215.824861 -56.690664) (xy 215.848692 -56.675782) (xy 215.857582 -56.670448)
			(xy 215.869774 -56.65343) (xy 215.890094 -56.560212) (xy 215.885776 -56.539638) (xy 215.879934 -56.531002)
			(xy 215.863937 -56.506936) (xy 215.838592 -56.455006) (xy 215.821366 -56.399848) (xy 215.81265 -56.342724)
			(xy 215.812116 -56.313832) (xy 215.812585 -56.286579) (xy 215.820338 -56.232627) (xy 215.835692 -56.180328)
			(xy 215.858332 -56.130746) (xy 215.887799 -56.084892) (xy 215.923492 -56.043698) (xy 215.964685 -56.008004)
			(xy 216.010539 -55.978536) (xy 216.06012 -55.955894) (xy 216.112419 -55.94054) (xy 216.166371 -55.932786)
			(xy 216.193624 -55.932324) (xy 216.220995 -55.93277) (xy 216.275175 -55.940592) (xy 216.327679 -55.956085)
			(xy 216.377425 -55.978932) (xy 216.423391 -56.008661) (xy 216.444322 -56.026304) (xy 216.444576 -56.026558)
			(xy 216.45166 -56.032148) (xy 216.468579 -56.038391) (xy 216.477596 -56.03875) (xy 216.544652 -56.03875)
			(xy 216.553668 -56.038381) (xy 216.570586 -56.032143) (xy 216.577672 -56.026558) (xy 216.577672 -56.026304)
			(xy 216.577926 -56.026304) (xy 216.598859 -56.008663) (xy 216.644827 -55.978939) (xy 216.694573 -55.956093)
			(xy 216.747075 -55.940597) (xy 216.801253 -55.932768) (xy 216.855995 -55.932768) (xy 216.910173 -55.940597)
			(xy 216.962675 -55.956093) (xy 217.012421 -55.978939) (xy 217.058389 -56.008663) (xy 217.079322 -56.026304)
			(xy 217.079576 -56.026558) (xy 217.08666 -56.032148) (xy 217.103579 -56.038391) (xy 217.112596 -56.03875)
			(xy 217.179652 -56.03875) (xy 217.188668 -56.038381) (xy 217.205586 -56.032143) (xy 217.212672 -56.026558)
			(xy 217.212672 -56.026304) (xy 217.212926 -56.026304) (xy 217.233876 -56.008687) (xy 217.279844 -55.978971)
			(xy 217.329587 -55.956131) (xy 217.382083 -55.940635) (xy 217.436256 -55.932801) (xy 217.463624 -55.932324)
			(xy 217.490876 -55.932747) (xy 217.544826 -55.940507) (xy 217.597122 -55.955866) (xy 217.646701 -55.97851)
			(xy 217.692552 -56.00798) (xy 217.733743 -56.043674) (xy 217.769435 -56.084867) (xy 217.798901 -56.13072)
			(xy 217.821542 -56.1803) (xy 217.836898 -56.232597) (xy 217.844654 -56.286548) (xy 217.844654 -56.297068)
			(xy 218.186506 -56.297068) (xy 218.190577 -56.241446) (xy 218.202703 -56.187009) (xy 218.222626 -56.134918)
			(xy 218.249922 -56.086283) (xy 218.284008 -56.04214) (xy 218.324157 -56.003431) (xy 218.369515 -55.97098)
			(xy 218.419115 -55.945479) (xy 218.471899 -55.927472) (xy 218.526742 -55.917342) (xy 218.582476 -55.915305)
			(xy 218.637913 -55.921405) (xy 218.69187 -55.935511) (xy 218.743199 -55.957323) (xy 218.790805 -55.986377)
			(xy 218.833673 -56.022052) (xy 218.87089 -56.063589) (xy 218.901663 -56.110102) (xy 218.925335 -56.160599)
			(xy 218.941403 -56.214006) (xy 218.949523 -56.269182) (xy 218.950032 -56.297068) (xy 218.949523 -56.324954)
			(xy 218.941403 -56.38013) (xy 218.925335 -56.433537) (xy 218.901663 -56.484034) (xy 218.87089 -56.530547)
			(xy 218.833673 -56.572084) (xy 218.790805 -56.607759) (xy 218.743199 -56.636813) (xy 218.69187 -56.658625)
			(xy 218.637913 -56.672731) (xy 218.582476 -56.678831) (xy 218.526742 -56.676794) (xy 218.471899 -56.666664)
			(xy 218.419115 -56.648657) (xy 218.369515 -56.623156) (xy 218.324157 -56.590705) (xy 218.284008 -56.551996)
			(xy 218.249922 -56.507853) (xy 218.222626 -56.459218) (xy 218.202703 -56.407127) (xy 218.190577 -56.35269)
			(xy 218.186506 -56.297068) (xy 217.844654 -56.297068) (xy 217.844654 -56.341052) (xy 217.836898 -56.395003)
			(xy 217.821542 -56.4473) (xy 217.798901 -56.49688) (xy 217.769435 -56.542733) (xy 217.733743 -56.583926)
			(xy 217.692552 -56.61962) (xy 217.646701 -56.64909) (xy 217.597122 -56.671734) (xy 217.544826 -56.687093)
			(xy 217.490876 -56.694853) (xy 217.463624 -56.69534) (xy 217.436254 -56.694874) (xy 217.382074 -56.687059)
			(xy 217.32957 -56.67157) (xy 217.279823 -56.648728) (xy 217.233857 -56.619002) (xy 217.212926 -56.60136)
			(xy 217.212672 -56.601106) (xy 217.205568 -56.595544) (xy 217.188665 -56.589282) (xy 217.179652 -56.588914)
			(xy 217.112596 -56.588914) (xy 217.103579 -56.589266) (xy 217.086661 -56.595517) (xy 217.079576 -56.601106)
			(xy 217.079576 -56.60136) (xy 217.079322 -56.60136) (xy 217.058389 -56.619001) (xy 217.012421 -56.648725)
			(xy 216.962675 -56.671571) (xy 216.910173 -56.687067) (xy 216.855995 -56.694896) (xy 216.801253 -56.694896)
			(xy 216.747075 -56.687067) (xy 216.694573 -56.671571) (xy 216.644827 -56.648725) (xy 216.598859 -56.619001)
			(xy 216.577926 -56.60136) (xy 216.577672 -56.601106) (xy 216.570568 -56.595544) (xy 216.553665 -56.589282)
			(xy 216.544652 -56.588914) (xy 216.477596 -56.588914) (xy 216.468579 -56.589266) (xy 216.451661 -56.595517)
			(xy 216.444576 -56.601106) (xy 216.444068 -56.60136) (xy 216.431333 -56.612303) (xy 216.404242 -56.632145)
			(xy 216.389966 -56.640984) (xy 216.381076 -56.646318) (xy 216.368884 -56.663336) (xy 216.348564 -56.756554)
			(xy 216.352882 -56.777128) (xy 216.358724 -56.785764) (xy 216.374714 -56.809834) (xy 216.400058 -56.861764)
			(xy 216.417286 -56.91692) (xy 216.426005 -56.974042) (xy 216.426542 -57.002934) (xy 216.426056 -57.030185)
			(xy 216.425774 -57.032144) (xy 219.585792 -57.032144) (xy 219.589863 -56.976522) (xy 219.601989 -56.922085)
			(xy 219.621912 -56.869994) (xy 219.649208 -56.821359) (xy 219.683294 -56.777216) (xy 219.723443 -56.738507)
			(xy 219.768801 -56.706056) (xy 219.818401 -56.680555) (xy 219.871185 -56.662548) (xy 219.926028 -56.652418)
			(xy 219.981762 -56.650381) (xy 220.037199 -56.656481) (xy 220.091156 -56.670587) (xy 220.142485 -56.692399)
			(xy 220.190091 -56.721453) (xy 220.232959 -56.757128) (xy 220.270176 -56.798665) (xy 220.300949 -56.845178)
			(xy 220.31108 -56.86679) (xy 240.166142 -56.86679) (xy 240.170213 -56.811168) (xy 240.182339 -56.756731)
			(xy 240.202262 -56.70464) (xy 240.229558 -56.656005) (xy 240.263644 -56.611862) (xy 240.303793 -56.573153)
			(xy 240.349151 -56.540702) (xy 240.398751 -56.515201) (xy 240.451535 -56.497194) (xy 240.506378 -56.487064)
			(xy 240.562112 -56.485027) (xy 240.617549 -56.491127) (xy 240.671506 -56.505233) (xy 240.722835 -56.527045)
			(xy 240.770441 -56.556099) (xy 240.813309 -56.591774) (xy 240.850526 -56.633311) (xy 240.881299 -56.679824)
			(xy 240.904971 -56.730321) (xy 240.921039 -56.783728) (xy 240.929159 -56.838904) (xy 240.929668 -56.86679)
			(xy 240.929159 -56.894676) (xy 240.921039 -56.949852) (xy 240.905069 -57.002934) (xy 253.763526 -57.002934)
			(xy 253.764026 -56.974842) (xy 253.77225 -56.919265) (xy 253.788538 -56.865495) (xy 253.81254 -56.814696)
			(xy 253.843734 -56.767969) (xy 253.881447 -56.726325) (xy 253.924861 -56.690664) (xy 253.948692 -56.675782)
			(xy 253.957582 -56.670448) (xy 253.969774 -56.65343) (xy 253.990094 -56.560212) (xy 253.985776 -56.539638)
			(xy 253.979934 -56.531002) (xy 253.963937 -56.506936) (xy 253.938592 -56.455006) (xy 253.921366 -56.399848)
			(xy 253.91265 -56.342724) (xy 253.912116 -56.313832) (xy 253.912585 -56.286579) (xy 253.920338 -56.232627)
			(xy 253.935692 -56.180328) (xy 253.958332 -56.130746) (xy 253.987799 -56.084892) (xy 254.023492 -56.043698)
			(xy 254.064685 -56.008004) (xy 254.110539 -55.978536) (xy 254.16012 -55.955894) (xy 254.212419 -55.94054)
			(xy 254.266371 -55.932786) (xy 254.293624 -55.932324) (xy 254.320995 -55.93277) (xy 254.375175 -55.940592)
			(xy 254.427679 -55.956085) (xy 254.477425 -55.978932) (xy 254.523391 -56.008661) (xy 254.544322 -56.026304)
			(xy 254.544576 -56.026558) (xy 254.55166 -56.032148) (xy 254.568579 -56.038391) (xy 254.577596 -56.03875)
			(xy 254.644652 -56.03875) (xy 254.653668 -56.038381) (xy 254.670586 -56.032143) (xy 254.677672 -56.026558)
			(xy 254.677672 -56.026304) (xy 254.677926 -56.026304) (xy 254.698859 -56.008663) (xy 254.744827 -55.978939)
			(xy 254.794573 -55.956093) (xy 254.847075 -55.940597) (xy 254.901253 -55.932768) (xy 254.955995 -55.932768)
			(xy 255.010173 -55.940597) (xy 255.062675 -55.956093) (xy 255.112421 -55.978939) (xy 255.158389 -56.008663)
			(xy 255.179322 -56.026304) (xy 255.179576 -56.026558) (xy 255.18666 -56.032148) (xy 255.203579 -56.038391)
			(xy 255.212596 -56.03875) (xy 255.279652 -56.03875) (xy 255.288668 -56.038381) (xy 255.305586 -56.032143)
			(xy 255.312672 -56.026558) (xy 255.312672 -56.026304) (xy 255.312926 -56.026304) (xy 255.333876 -56.008687)
			(xy 255.379844 -55.978971) (xy 255.429587 -55.956131) (xy 255.482083 -55.940635) (xy 255.536256 -55.932801)
			(xy 255.563624 -55.932324) (xy 255.590876 -55.932747) (xy 255.644826 -55.940507) (xy 255.697122 -55.955866)
			(xy 255.746701 -55.97851) (xy 255.792552 -56.00798) (xy 255.833743 -56.043674) (xy 255.869435 -56.084867)
			(xy 255.898901 -56.13072) (xy 255.921542 -56.1803) (xy 255.936898 -56.232597) (xy 255.944654 -56.286548)
			(xy 255.944654 -56.297068) (xy 256.286506 -56.297068) (xy 256.290577 -56.241446) (xy 256.302703 -56.187009)
			(xy 256.322626 -56.134918) (xy 256.349922 -56.086283) (xy 256.384008 -56.04214) (xy 256.424157 -56.003431)
			(xy 256.469515 -55.97098) (xy 256.519115 -55.945479) (xy 256.571899 -55.927472) (xy 256.626742 -55.917342)
			(xy 256.682476 -55.915305) (xy 256.737913 -55.921405) (xy 256.79187 -55.935511) (xy 256.843199 -55.957323)
			(xy 256.890805 -55.986377) (xy 256.933673 -56.022052) (xy 256.97089 -56.063589) (xy 257.001663 -56.110102)
			(xy 257.025335 -56.160599) (xy 257.041403 -56.214006) (xy 257.049523 -56.269182) (xy 257.050032 -56.297068)
			(xy 257.049523 -56.324954) (xy 257.041403 -56.38013) (xy 257.025335 -56.433537) (xy 257.001663 -56.484034)
			(xy 256.97089 -56.530547) (xy 256.933673 -56.572084) (xy 256.890805 -56.607759) (xy 256.843199 -56.636813)
			(xy 256.79187 -56.658625) (xy 256.737913 -56.672731) (xy 256.682476 -56.678831) (xy 256.626742 -56.676794)
			(xy 256.571899 -56.666664) (xy 256.519115 -56.648657) (xy 256.469515 -56.623156) (xy 256.424157 -56.590705)
			(xy 256.384008 -56.551996) (xy 256.349922 -56.507853) (xy 256.322626 -56.459218) (xy 256.302703 -56.407127)
			(xy 256.290577 -56.35269) (xy 256.286506 -56.297068) (xy 255.944654 -56.297068) (xy 255.944654 -56.341052)
			(xy 255.936898 -56.395003) (xy 255.921542 -56.4473) (xy 255.898901 -56.49688) (xy 255.869435 -56.542733)
			(xy 255.833743 -56.583926) (xy 255.792552 -56.61962) (xy 255.746701 -56.64909) (xy 255.697122 -56.671734)
			(xy 255.644826 -56.687093) (xy 255.590876 -56.694853) (xy 255.563624 -56.69534) (xy 255.536254 -56.694874)
			(xy 255.482074 -56.687059) (xy 255.42957 -56.67157) (xy 255.379823 -56.648728) (xy 255.333857 -56.619002)
			(xy 255.312926 -56.60136) (xy 255.312672 -56.601106) (xy 255.305568 -56.595544) (xy 255.288665 -56.589282)
			(xy 255.279652 -56.588914) (xy 255.212596 -56.588914) (xy 255.203579 -56.589266) (xy 255.186661 -56.595517)
			(xy 255.179576 -56.601106) (xy 255.179576 -56.60136) (xy 255.179322 -56.60136) (xy 255.158389 -56.619001)
			(xy 255.112421 -56.648725) (xy 255.062675 -56.671571) (xy 255.010173 -56.687067) (xy 254.955995 -56.694896)
			(xy 254.901253 -56.694896) (xy 254.847075 -56.687067) (xy 254.794573 -56.671571) (xy 254.744827 -56.648725)
			(xy 254.698859 -56.619001) (xy 254.677926 -56.60136) (xy 254.677672 -56.601106) (xy 254.670568 -56.595544)
			(xy 254.653665 -56.589282) (xy 254.644652 -56.588914) (xy 254.577596 -56.588914) (xy 254.568579 -56.589266)
			(xy 254.551661 -56.595517) (xy 254.544576 -56.601106) (xy 254.544068 -56.60136) (xy 254.531333 -56.612303)
			(xy 254.504242 -56.632145) (xy 254.489966 -56.640984) (xy 254.481076 -56.646318) (xy 254.468884 -56.663336)
			(xy 254.448564 -56.756554) (xy 254.452882 -56.777128) (xy 254.458724 -56.785764) (xy 254.474714 -56.809834)
			(xy 254.500058 -56.861764) (xy 254.517286 -56.91692) (xy 254.526005 -56.974042) (xy 254.526542 -57.002934)
			(xy 254.526056 -57.030185) (xy 254.5183 -57.084133) (xy 254.502945 -57.136428) (xy 254.480303 -57.186005)
			(xy 254.450837 -57.231855) (xy 254.415146 -57.273046) (xy 254.373955 -57.308737) (xy 254.328105 -57.338203)
			(xy 254.278528 -57.360845) (xy 254.226233 -57.3762) (xy 254.172285 -57.383956) (xy 254.117783 -57.383956)
			(xy 254.063835 -57.3762) (xy 254.01154 -57.360845) (xy 253.961963 -57.338203) (xy 253.916113 -57.308737)
			(xy 253.874922 -57.273046) (xy 253.839231 -57.231855) (xy 253.809765 -57.186005) (xy 253.787123 -57.136428)
			(xy 253.771768 -57.084133) (xy 253.764012 -57.030185) (xy 253.763526 -57.002934) (xy 240.905069 -57.002934)
			(xy 240.904971 -57.003259) (xy 240.881299 -57.053756) (xy 240.850526 -57.100269) (xy 240.813309 -57.141806)
			(xy 240.770441 -57.177481) (xy 240.722835 -57.206535) (xy 240.671506 -57.228347) (xy 240.617549 -57.242453)
			(xy 240.562112 -57.248553) (xy 240.506378 -57.246516) (xy 240.451535 -57.236386) (xy 240.398751 -57.218379)
			(xy 240.349151 -57.192878) (xy 240.303793 -57.160427) (xy 240.263644 -57.121718) (xy 240.229558 -57.077575)
			(xy 240.202262 -57.02894) (xy 240.182339 -56.976849) (xy 240.170213 -56.922412) (xy 240.166142 -56.86679)
			(xy 220.31108 -56.86679) (xy 220.324621 -56.895675) (xy 220.340689 -56.949082) (xy 220.348809 -57.004258)
			(xy 220.349318 -57.032144) (xy 220.348809 -57.06003) (xy 220.340689 -57.115206) (xy 220.324621 -57.168613)
			(xy 220.300949 -57.21911) (xy 220.270176 -57.265623) (xy 220.232959 -57.30716) (xy 220.190091 -57.342835)
			(xy 220.142485 -57.371889) (xy 220.091156 -57.393701) (xy 220.037199 -57.407807) (xy 219.981762 -57.413907)
			(xy 219.926028 -57.41187) (xy 219.871185 -57.40174) (xy 219.818401 -57.383733) (xy 219.768801 -57.358232)
			(xy 219.723443 -57.325781) (xy 219.683294 -57.287072) (xy 219.649208 -57.242929) (xy 219.621912 -57.194294)
			(xy 219.601989 -57.142203) (xy 219.589863 -57.087766) (xy 219.585792 -57.032144) (xy 216.425774 -57.032144)
			(xy 216.4183 -57.084133) (xy 216.402945 -57.136428) (xy 216.380303 -57.186005) (xy 216.350837 -57.231855)
			(xy 216.315146 -57.273046) (xy 216.273955 -57.308737) (xy 216.228105 -57.338203) (xy 216.178528 -57.360845)
			(xy 216.126233 -57.3762) (xy 216.072285 -57.383956) (xy 216.017783 -57.383956) (xy 215.963835 -57.3762)
			(xy 215.91154 -57.360845) (xy 215.861963 -57.338203) (xy 215.816113 -57.308737) (xy 215.774922 -57.273046)
			(xy 215.739231 -57.231855) (xy 215.709765 -57.186005) (xy 215.687123 -57.136428) (xy 215.671768 -57.084133)
			(xy 215.664012 -57.030185) (xy 215.663526 -57.002934) (xy 206.783048 -57.002934) (xy 206.88353 -58.679334)
			(xy 216.095326 -58.679334) (xy 216.095741 -58.653018) (xy 216.102985 -58.600887) (xy 216.117314 -58.550243)
			(xy 216.138456 -58.502044) (xy 216.166012 -58.457202) (xy 216.19946 -58.416565) (xy 216.218516 -58.39841)
			(xy 216.225918 -58.390889) (xy 216.234442 -58.371608) (xy 216.235026 -58.361072) (xy 216.235026 -58.286396)
			(xy 216.234505 -58.275846) (xy 216.225963 -58.256551) (xy 216.218516 -58.249058) (xy 216.19945 -58.230913)
			(xy 216.165993 -58.190281) (xy 216.138435 -58.145439) (xy 216.117298 -58.097236) (xy 216.102984 -58.046587)
			(xy 216.095762 -57.994451) (xy 216.095326 -57.968134) (xy 216.095812 -57.940883) (xy 216.103568 -57.886935)
			(xy 216.118923 -57.83464) (xy 216.141565 -57.785063) (xy 216.171031 -57.739213) (xy 216.206722 -57.698022)
			(xy 216.247913 -57.662331) (xy 216.293763 -57.632865) (xy 216.34334 -57.610223) (xy 216.395635 -57.594868)
			(xy 216.449583 -57.587112) (xy 216.504085 -57.587112) (xy 216.558033 -57.594868) (xy 216.610328 -57.610223)
			(xy 216.659905 -57.632865) (xy 216.705755 -57.662331) (xy 216.746946 -57.698022) (xy 216.782637 -57.739213)
			(xy 216.812103 -57.785063) (xy 216.834745 -57.83464) (xy 216.8501 -57.886935) (xy 216.857856 -57.940883)
			(xy 216.858342 -57.968134) (xy 216.857916 -57.99445) (xy 216.850675 -58.046581) (xy 216.836349 -58.097225)
			(xy 216.815209 -58.145424) (xy 216.787655 -58.190266) (xy 216.754208 -58.230903) (xy 216.735152 -58.249058)
			(xy 216.727775 -58.2566) (xy 216.719235 -58.275864) (xy 216.718642 -58.286396) (xy 216.718642 -58.361072)
			(xy 216.719161 -58.371623) (xy 216.727702 -58.390919) (xy 216.735152 -58.39841) (xy 216.754215 -58.416558)
			(xy 216.78767 -58.45719) (xy 216.815226 -58.502032) (xy 216.836363 -58.550235) (xy 216.850679 -58.600883)
			(xy 216.857904 -58.653018) (xy 216.858342 -58.679334) (xy 216.858001 -58.698471) (xy 229.808523 -58.698471)
			(xy 229.808523 -58.601777) (xy 229.816508 -58.505414) (xy 229.832424 -58.410039) (xy 229.85616 -58.316305)
			(xy 229.887557 -58.22485) (xy 229.926398 -58.136301) (xy 229.972419 -58.051261) (xy 230.025305 -57.970313)
			(xy 230.084696 -57.894008) (xy 230.150184 -57.822868) (xy 230.221324 -57.75738) (xy 230.297629 -57.697989)
			(xy 230.378577 -57.645103) (xy 230.463617 -57.599082) (xy 230.552166 -57.560241) (xy 230.643621 -57.528844)
			(xy 230.737355 -57.505108) (xy 230.83273 -57.489192) (xy 230.929093 -57.481207) (xy 231.025787 -57.481207)
			(xy 231.07494 -57.48528) (xy 262.805924 -57.48528) (xy 262.809995 -57.429658) (xy 262.822121 -57.375221)
			(xy 262.842044 -57.32313) (xy 262.86934 -57.274495) (xy 262.903426 -57.230352) (xy 262.943575 -57.191643)
			(xy 262.988933 -57.159192) (xy 263.038533 -57.133691) (xy 263.091317 -57.115684) (xy 263.14616 -57.105554)
			(xy 263.201894 -57.103517) (xy 263.257331 -57.109617) (xy 263.311288 -57.123723) (xy 263.362617 -57.145535)
			(xy 263.410223 -57.174589) (xy 263.453091 -57.210264) (xy 263.490308 -57.251801) (xy 263.521081 -57.298314)
			(xy 263.544753 -57.348811) (xy 263.560821 -57.402218) (xy 263.568941 -57.457394) (xy 263.56945 -57.48528)
			(xy 263.568941 -57.513166) (xy 263.560821 -57.568342) (xy 263.544753 -57.621749) (xy 263.521081 -57.672246)
			(xy 263.490308 -57.718759) (xy 263.453091 -57.760296) (xy 263.410223 -57.795971) (xy 263.362617 -57.825025)
			(xy 263.311288 -57.846837) (xy 263.257331 -57.860943) (xy 263.201894 -57.867043) (xy 263.14616 -57.865006)
			(xy 263.091317 -57.854876) (xy 263.038533 -57.836869) (xy 262.988933 -57.811368) (xy 262.943575 -57.778917)
			(xy 262.903426 -57.740208) (xy 262.86934 -57.696065) (xy 262.842044 -57.64743) (xy 262.822121 -57.595339)
			(xy 262.809995 -57.540902) (xy 262.805924 -57.48528) (xy 231.07494 -57.48528) (xy 231.12215 -57.489192)
			(xy 231.217525 -57.505108) (xy 231.311259 -57.528844) (xy 231.402714 -57.560241) (xy 231.491263 -57.599082)
			(xy 231.576303 -57.645103) (xy 231.657251 -57.697989) (xy 231.733556 -57.75738) (xy 231.804696 -57.822868)
			(xy 231.870184 -57.894008) (xy 231.929575 -57.970313) (xy 231.982461 -58.051261) (xy 232.028482 -58.136301)
			(xy 232.067323 -58.22485) (xy 232.087929 -58.284872) (xy 240.598196 -58.284872) (xy 240.602267 -58.22925)
			(xy 240.614393 -58.174813) (xy 240.634316 -58.122722) (xy 240.661612 -58.074087) (xy 240.695698 -58.029944)
			(xy 240.735847 -57.991235) (xy 240.781205 -57.958784) (xy 240.830805 -57.933283) (xy 240.883589 -57.915276)
			(xy 240.938432 -57.905146) (xy 240.994166 -57.903109) (xy 241.049603 -57.909209) (xy 241.10356 -57.923315)
			(xy 241.154889 -57.945127) (xy 241.202495 -57.974181) (xy 241.245363 -58.009856) (xy 241.28258 -58.051393)
			(xy 241.313353 -58.097906) (xy 241.337025 -58.148403) (xy 241.353093 -58.20181) (xy 241.361213 -58.256986)
			(xy 241.361722 -58.284872) (xy 241.361213 -58.312758) (xy 241.353093 -58.367934) (xy 241.337025 -58.421341)
			(xy 241.313353 -58.471838) (xy 241.28258 -58.518351) (xy 241.245363 -58.559888) (xy 241.202495 -58.595563)
			(xy 241.154889 -58.624617) (xy 241.10356 -58.646429) (xy 241.049603 -58.660535) (xy 240.994166 -58.666635)
			(xy 240.938432 -58.664598) (xy 240.883589 -58.654468) (xy 240.830805 -58.636461) (xy 240.781205 -58.61096)
			(xy 240.735847 -58.578509) (xy 240.695698 -58.5398) (xy 240.661612 -58.495657) (xy 240.634316 -58.447022)
			(xy 240.614393 -58.394931) (xy 240.602267 -58.340494) (xy 240.598196 -58.284872) (xy 232.087929 -58.284872)
			(xy 232.09872 -58.316305) (xy 232.122456 -58.410039) (xy 232.138372 -58.505414) (xy 232.146357 -58.601777)
			(xy 232.146856 -58.650124) (xy 232.146555 -58.679334) (xy 254.195326 -58.679334) (xy 254.195741 -58.653018)
			(xy 254.202985 -58.600887) (xy 254.217314 -58.550243) (xy 254.238456 -58.502044) (xy 254.266012 -58.457202)
			(xy 254.29946 -58.416565) (xy 254.318516 -58.39841) (xy 254.325918 -58.390889) (xy 254.334442 -58.371608)
			(xy 254.335026 -58.361072) (xy 254.335026 -58.286396) (xy 254.334505 -58.275846) (xy 254.325963 -58.256551)
			(xy 254.318516 -58.249058) (xy 254.29945 -58.230913) (xy 254.265993 -58.190281) (xy 254.238435 -58.145439)
			(xy 254.217298 -58.097236) (xy 254.202984 -58.046587) (xy 254.195762 -57.994451) (xy 254.195326 -57.968134)
			(xy 254.195812 -57.940883) (xy 254.203568 -57.886935) (xy 254.218923 -57.83464) (xy 254.241565 -57.785063)
			(xy 254.271031 -57.739213) (xy 254.306722 -57.698022) (xy 254.347913 -57.662331) (xy 254.393763 -57.632865)
			(xy 254.44334 -57.610223) (xy 254.495635 -57.594868) (xy 254.549583 -57.587112) (xy 254.604085 -57.587112)
			(xy 254.658033 -57.594868) (xy 254.710328 -57.610223) (xy 254.759905 -57.632865) (xy 254.805755 -57.662331)
			(xy 254.846946 -57.698022) (xy 254.882637 -57.739213) (xy 254.912103 -57.785063) (xy 254.934745 -57.83464)
			(xy 254.9501 -57.886935) (xy 254.957856 -57.940883) (xy 254.958342 -57.968134) (xy 254.957916 -57.99445)
			(xy 254.950675 -58.046581) (xy 254.943407 -58.072274) (xy 258.193538 -58.072274) (xy 258.197609 -58.016652)
			(xy 258.209735 -57.962215) (xy 258.229658 -57.910124) (xy 258.256954 -57.861489) (xy 258.29104 -57.817346)
			(xy 258.331189 -57.778637) (xy 258.376547 -57.746186) (xy 258.426147 -57.720685) (xy 258.478931 -57.702678)
			(xy 258.533774 -57.692548) (xy 258.589508 -57.690511) (xy 258.644945 -57.696611) (xy 258.698902 -57.710717)
			(xy 258.750231 -57.732529) (xy 258.797837 -57.761583) (xy 258.840705 -57.797258) (xy 258.877922 -57.838795)
			(xy 258.908695 -57.885308) (xy 258.932367 -57.935805) (xy 258.948435 -57.989212) (xy 258.956555 -58.044388)
			(xy 258.957064 -58.072274) (xy 258.956994 -58.076084) (xy 263.558018 -58.076084) (xy 263.562089 -58.020462)
			(xy 263.574215 -57.966025) (xy 263.594138 -57.913934) (xy 263.621434 -57.865299) (xy 263.65552 -57.821156)
			(xy 263.695669 -57.782447) (xy 263.741027 -57.749996) (xy 263.790627 -57.724495) (xy 263.843411 -57.706488)
			(xy 263.898254 -57.696358) (xy 263.953988 -57.694321) (xy 264.009425 -57.700421) (xy 264.063382 -57.714527)
			(xy 264.114711 -57.736339) (xy 264.162317 -57.765393) (xy 264.205185 -57.801068) (xy 264.242402 -57.842605)
			(xy 264.258738 -57.867296) (xy 265.843002 -57.867296) (xy 265.847073 -57.811674) (xy 265.859199 -57.757237)
			(xy 265.879122 -57.705146) (xy 265.906418 -57.656511) (xy 265.940504 -57.612368) (xy 265.980653 -57.573659)
			(xy 266.026011 -57.541208) (xy 266.075611 -57.515707) (xy 266.128395 -57.4977) (xy 266.183238 -57.48757)
			(xy 266.238972 -57.485533) (xy 266.294409 -57.491633) (xy 266.348366 -57.505739) (xy 266.399695 -57.527551)
			(xy 266.447301 -57.556605) (xy 266.490169 -57.59228) (xy 266.527386 -57.633817) (xy 266.558159 -57.68033)
			(xy 266.581831 -57.730827) (xy 266.597899 -57.784234) (xy 266.606019 -57.83941) (xy 266.606528 -57.867296)
			(xy 266.606019 -57.895182) (xy 266.597899 -57.950358) (xy 266.581831 -58.003765) (xy 266.558159 -58.054262)
			(xy 266.527386 -58.100775) (xy 266.490169 -58.142312) (xy 266.447301 -58.177987) (xy 266.399695 -58.207041)
			(xy 266.348366 -58.228853) (xy 266.294409 -58.242959) (xy 266.238972 -58.249059) (xy 266.183238 -58.247022)
			(xy 266.128395 -58.236892) (xy 266.075611 -58.218885) (xy 266.026011 -58.193384) (xy 265.980653 -58.160933)
			(xy 265.940504 -58.122224) (xy 265.906418 -58.078081) (xy 265.879122 -58.029446) (xy 265.859199 -57.977355)
			(xy 265.847073 -57.922918) (xy 265.843002 -57.867296) (xy 264.258738 -57.867296) (xy 264.273175 -57.889118)
			(xy 264.296847 -57.939615) (xy 264.312915 -57.993022) (xy 264.321035 -58.048198) (xy 264.321544 -58.076084)
			(xy 264.321035 -58.10397) (xy 264.312915 -58.159146) (xy 264.296847 -58.212553) (xy 264.273175 -58.26305)
			(xy 264.242402 -58.309563) (xy 264.205185 -58.3511) (xy 264.162317 -58.386775) (xy 264.114711 -58.415829)
			(xy 264.063382 -58.437641) (xy 264.009425 -58.451747) (xy 263.953988 -58.457847) (xy 263.898254 -58.45581)
			(xy 263.843411 -58.44568) (xy 263.790627 -58.427673) (xy 263.741027 -58.402172) (xy 263.695669 -58.369721)
			(xy 263.65552 -58.331012) (xy 263.621434 -58.286869) (xy 263.594138 -58.238234) (xy 263.574215 -58.186143)
			(xy 263.562089 -58.131706) (xy 263.558018 -58.076084) (xy 258.956994 -58.076084) (xy 258.956555 -58.10016)
			(xy 258.948435 -58.155336) (xy 258.932367 -58.208743) (xy 258.908695 -58.25924) (xy 258.877922 -58.305753)
			(xy 258.840705 -58.34729) (xy 258.797837 -58.382965) (xy 258.750231 -58.412019) (xy 258.698902 -58.433831)
			(xy 258.644945 -58.447937) (xy 258.589508 -58.454037) (xy 258.533774 -58.452) (xy 258.478931 -58.44187)
			(xy 258.426147 -58.423863) (xy 258.376547 -58.398362) (xy 258.331189 -58.365911) (xy 258.29104 -58.327202)
			(xy 258.256954 -58.283059) (xy 258.229658 -58.234424) (xy 258.209735 -58.182333) (xy 258.197609 -58.127896)
			(xy 258.193538 -58.072274) (xy 254.943407 -58.072274) (xy 254.936349 -58.097225) (xy 254.915209 -58.145424)
			(xy 254.887655 -58.190266) (xy 254.854208 -58.230903) (xy 254.835152 -58.249058) (xy 254.827775 -58.2566)
			(xy 254.819235 -58.275864) (xy 254.818642 -58.286396) (xy 254.818642 -58.361072) (xy 254.819161 -58.371623)
			(xy 254.827702 -58.390919) (xy 254.835152 -58.39841) (xy 254.854215 -58.416558) (xy 254.88767 -58.45719)
			(xy 254.915226 -58.502032) (xy 254.936363 -58.550235) (xy 254.939469 -58.561224) (xy 264.762232 -58.561224)
			(xy 264.766303 -58.505602) (xy 264.778429 -58.451165) (xy 264.798352 -58.399074) (xy 264.825648 -58.350439)
			(xy 264.859734 -58.306296) (xy 264.899883 -58.267587) (xy 264.945241 -58.235136) (xy 264.994841 -58.209635)
			(xy 265.047625 -58.191628) (xy 265.102468 -58.181498) (xy 265.158202 -58.179461) (xy 265.213639 -58.185561)
			(xy 265.267596 -58.199667) (xy 265.318925 -58.221479) (xy 265.366531 -58.250533) (xy 265.409399 -58.286208)
			(xy 265.446616 -58.327745) (xy 265.477389 -58.374258) (xy 265.501061 -58.424755) (xy 265.508571 -58.449718)
			(xy 267.008862 -58.449718) (xy 267.012933 -58.394096) (xy 267.025059 -58.339659) (xy 267.044982 -58.287568)
			(xy 267.072278 -58.238933) (xy 267.106364 -58.19479) (xy 267.146513 -58.156081) (xy 267.191871 -58.12363)
			(xy 267.241471 -58.098129) (xy 267.294255 -58.080122) (xy 267.349098 -58.069992) (xy 267.404832 -58.067955)
			(xy 267.460269 -58.074055) (xy 267.514226 -58.088161) (xy 267.565555 -58.109973) (xy 267.613161 -58.139027)
			(xy 267.656029 -58.174702) (xy 267.693246 -58.216239) (xy 267.724019 -58.262752) (xy 267.747691 -58.313249)
			(xy 267.763759 -58.366656) (xy 267.771879 -58.421832) (xy 267.772388 -58.449718) (xy 267.771879 -58.477604)
			(xy 267.763759 -58.53278) (xy 267.747691 -58.586187) (xy 267.724019 -58.636684) (xy 267.693246 -58.683197)
			(xy 267.656029 -58.724734) (xy 267.613161 -58.760409) (xy 267.565555 -58.789463) (xy 267.514226 -58.811275)
			(xy 267.460269 -58.825381) (xy 267.404832 -58.831481) (xy 267.349098 -58.829444) (xy 267.294255 -58.819314)
			(xy 267.241471 -58.801307) (xy 267.191871 -58.775806) (xy 267.146513 -58.743355) (xy 267.106364 -58.704646)
			(xy 267.072278 -58.660503) (xy 267.044982 -58.611868) (xy 267.025059 -58.559777) (xy 267.012933 -58.50534)
			(xy 267.008862 -58.449718) (xy 265.508571 -58.449718) (xy 265.517129 -58.478162) (xy 265.525249 -58.533338)
			(xy 265.525758 -58.561224) (xy 265.525249 -58.58911) (xy 265.517129 -58.644286) (xy 265.501061 -58.697693)
			(xy 265.477389 -58.74819) (xy 265.446616 -58.794703) (xy 265.409399 -58.83624) (xy 265.366531 -58.871915)
			(xy 265.318925 -58.900969) (xy 265.267596 -58.922781) (xy 265.213639 -58.936887) (xy 265.158202 -58.942987)
			(xy 265.102468 -58.94095) (xy 265.047625 -58.93082) (xy 264.994841 -58.912813) (xy 264.945241 -58.887312)
			(xy 264.899883 -58.854861) (xy 264.859734 -58.816152) (xy 264.825648 -58.772009) (xy 264.798352 -58.723374)
			(xy 264.778429 -58.671283) (xy 264.766303 -58.616846) (xy 264.762232 -58.561224) (xy 254.939469 -58.561224)
			(xy 254.950679 -58.600883) (xy 254.957904 -58.653018) (xy 254.958342 -58.679334) (xy 254.957856 -58.706585)
			(xy 254.9501 -58.760533) (xy 254.934745 -58.812828) (xy 254.912103 -58.862405) (xy 254.882637 -58.908255)
			(xy 254.846946 -58.949446) (xy 254.805755 -58.985137) (xy 254.759905 -59.014603) (xy 254.710328 -59.037245)
			(xy 254.658033 -59.0526) (xy 254.604085 -59.060356) (xy 254.549583 -59.060356) (xy 254.495635 -59.0526)
			(xy 254.44334 -59.037245) (xy 254.393763 -59.014603) (xy 254.347913 -58.985137) (xy 254.306722 -58.949446)
			(xy 254.271031 -58.908255) (xy 254.241565 -58.862405) (xy 254.218923 -58.812828) (xy 254.203568 -58.760533)
			(xy 254.195812 -58.706585) (xy 254.195326 -58.679334) (xy 232.146555 -58.679334) (xy 232.146357 -58.698471)
			(xy 232.138372 -58.794834) (xy 232.122456 -58.890209) (xy 232.09872 -58.983943) (xy 232.067323 -59.075398)
			(xy 232.028482 -59.163947) (xy 232.022699 -59.174634) (xy 263.293096 -59.174634) (xy 263.297167 -59.119012)
			(xy 263.309293 -59.064575) (xy 263.329216 -59.012484) (xy 263.356512 -58.963849) (xy 263.390598 -58.919706)
			(xy 263.430747 -58.880997) (xy 263.476105 -58.848546) (xy 263.525705 -58.823045) (xy 263.578489 -58.805038)
			(xy 263.633332 -58.794908) (xy 263.689066 -58.792871) (xy 263.744503 -58.798971) (xy 263.79846 -58.813077)
			(xy 263.849789 -58.834889) (xy 263.897395 -58.863943) (xy 263.940263 -58.899618) (xy 263.97748 -58.941155)
			(xy 264.008253 -58.987668) (xy 264.031925 -59.038165) (xy 264.047993 -59.091572) (xy 264.056113 -59.146748)
			(xy 264.056622 -59.174634) (xy 264.056113 -59.20252) (xy 264.047993 -59.257696) (xy 264.031925 -59.311103)
			(xy 264.008253 -59.3616) (xy 263.97748 -59.408113) (xy 263.940263 -59.44965) (xy 263.897395 -59.485325)
			(xy 263.849789 -59.514379) (xy 263.79846 -59.536191) (xy 263.744503 -59.550297) (xy 263.689066 -59.556397)
			(xy 263.633332 -59.55436) (xy 263.578489 -59.54423) (xy 263.525705 -59.526223) (xy 263.476105 -59.500722)
			(xy 263.430747 -59.468271) (xy 263.390598 -59.429562) (xy 263.356512 -59.385419) (xy 263.329216 -59.336784)
			(xy 263.309293 -59.284693) (xy 263.297167 -59.230256) (xy 263.293096 -59.174634) (xy 232.022699 -59.174634)
			(xy 231.982461 -59.248987) (xy 231.929575 -59.329935) (xy 231.870184 -59.40624) (xy 231.804696 -59.47738)
			(xy 231.733556 -59.542868) (xy 231.657251 -59.602259) (xy 231.576303 -59.655145) (xy 231.491263 -59.701166)
			(xy 231.402714 -59.740007) (xy 231.311259 -59.771404) (xy 231.217525 -59.79514) (xy 231.12215 -59.811056)
			(xy 231.025787 -59.819041) (xy 230.929093 -59.819041) (xy 230.83273 -59.811056) (xy 230.737355 -59.79514)
			(xy 230.643621 -59.771404) (xy 230.552166 -59.740007) (xy 230.463617 -59.701166) (xy 230.378577 -59.655145)
			(xy 230.297629 -59.602259) (xy 230.221324 -59.542868) (xy 230.150184 -59.47738) (xy 230.084696 -59.40624)
			(xy 230.025305 -59.329935) (xy 229.972419 -59.248987) (xy 229.926398 -59.163947) (xy 229.887557 -59.075398)
			(xy 229.85616 -58.983943) (xy 229.832424 -58.890209) (xy 229.816508 -58.794834) (xy 229.808523 -58.698471)
			(xy 216.858001 -58.698471) (xy 216.857856 -58.706585) (xy 216.8501 -58.760533) (xy 216.834745 -58.812828)
			(xy 216.812103 -58.862405) (xy 216.782637 -58.908255) (xy 216.746946 -58.949446) (xy 216.705755 -58.985137)
			(xy 216.659905 -59.014603) (xy 216.610328 -59.037245) (xy 216.558033 -59.0526) (xy 216.504085 -59.060356)
			(xy 216.449583 -59.060356) (xy 216.395635 -59.0526) (xy 216.34334 -59.037245) (xy 216.293763 -59.014603)
			(xy 216.247913 -58.985137) (xy 216.206722 -58.949446) (xy 216.171031 -58.908255) (xy 216.141565 -58.862405)
			(xy 216.118923 -58.812828) (xy 216.103568 -58.760533) (xy 216.095812 -58.706585) (xy 216.095326 -58.679334)
			(xy 206.88353 -58.679334) (xy 206.959454 -59.946032) (xy 206.959708 -59.94654) (xy 206.959708 -59.949588)
			(xy 206.959962 -59.952128) (xy 206.959962 -59.955176) (xy 206.960216 -59.958224) (xy 206.960216 -59.961272)
			(xy 206.96047 -59.966606) (xy 206.96047 -59.970416) (xy 206.960724 -59.981338) (xy 206.960724 -59.981846)
			(xy 206.959708 -60.014358) (xy 206.959454 -60.018168) (xy 206.95936 -60.01925) (xy 216.235784 -60.01925)
			(xy 216.235784 -59.96475) (xy 216.24354 -59.910804) (xy 216.258894 -59.858511) (xy 216.281534 -59.808935)
			(xy 216.310999 -59.763086) (xy 216.346688 -59.721897) (xy 216.387877 -59.686206) (xy 216.433725 -59.65674)
			(xy 216.4833 -59.634098) (xy 216.535592 -59.618742) (xy 216.589538 -59.610985) (xy 216.616788 -59.610498)
			(xy 216.644158 -59.610972) (xy 216.698337 -59.618788) (xy 216.75084 -59.634275) (xy 216.800587 -59.657115)
			(xy 216.846554 -59.686838) (xy 216.867486 -59.704478) (xy 216.86774 -59.704732) (xy 216.874837 -59.710303)
			(xy 216.891746 -59.716558) (xy 216.90076 -59.716924) (xy 216.967816 -59.716924) (xy 216.976833 -59.716569)
			(xy 216.99375 -59.710319) (xy 217.000836 -59.704732) (xy 217.000836 -59.704478) (xy 217.00109 -59.704478)
			(xy 217.022023 -59.686837) (xy 217.067991 -59.657113) (xy 217.117737 -59.634267) (xy 217.170239 -59.618771)
			(xy 217.224417 -59.610942) (xy 217.279159 -59.610942) (xy 217.333337 -59.618771) (xy 217.385839 -59.634267)
			(xy 217.435585 -59.657113) (xy 217.481553 -59.686837) (xy 217.502486 -59.704478) (xy 217.50274 -59.704732)
			(xy 217.509837 -59.710303) (xy 217.526746 -59.716558) (xy 217.53576 -59.716924) (xy 217.602816 -59.716924)
			(xy 217.611833 -59.716569) (xy 217.62875 -59.710319) (xy 217.635836 -59.704732) (xy 217.635836 -59.704478)
			(xy 217.63609 -59.704478) (xy 217.657012 -59.686827) (xy 217.702988 -59.657117) (xy 217.752738 -59.634284)
			(xy 217.805241 -59.618796) (xy 217.859418 -59.610971) (xy 217.886788 -59.610498) (xy 217.914042 -59.610949)
			(xy 217.967995 -59.618704) (xy 218.020295 -59.634059) (xy 218.069877 -59.656702) (xy 218.115733 -59.68617)
			(xy 218.156928 -59.721864) (xy 218.192623 -59.763058) (xy 218.222093 -59.808912) (xy 218.244736 -59.858494)
			(xy 218.260093 -59.910793) (xy 218.267851 -59.964746) (xy 218.267851 -60.019254) (xy 218.260093 -60.073207)
			(xy 218.244736 -60.125506) (xy 218.241789 -60.13196) (xy 226.436428 -60.13196) (xy 226.436428 -59.26836)
			(xy 226.436918 -59.238392) (xy 226.444741 -59.17897) (xy 226.460254 -59.121077) (xy 226.48319 -59.065704)
			(xy 226.513157 -59.013798) (xy 226.549644 -58.966248) (xy 226.592024 -58.923868) (xy 226.639574 -58.887381)
			(xy 226.69148 -58.857414) (xy 226.746853 -58.834478) (xy 226.804746 -58.818965) (xy 226.864168 -58.811142)
			(xy 226.924104 -58.811142) (xy 226.983526 -58.818965) (xy 227.041419 -58.834478) (xy 227.096792 -58.857414)
			(xy 227.148698 -58.887381) (xy 227.196248 -58.923868) (xy 227.238628 -58.966248) (xy 227.275115 -59.013798)
			(xy 227.305082 -59.065704) (xy 227.328018 -59.121077) (xy 227.343531 -59.17897) (xy 227.351354 -59.238392)
			(xy 227.351844 -59.26836) (xy 227.351844 -60.01925) (xy 254.335784 -60.01925) (xy 254.335784 -59.96475)
			(xy 254.34354 -59.910804) (xy 254.358894 -59.858511) (xy 254.381534 -59.808935) (xy 254.410999 -59.763086)
			(xy 254.446688 -59.721897) (xy 254.487877 -59.686206) (xy 254.533725 -59.65674) (xy 254.5833 -59.634098)
			(xy 254.635592 -59.618742) (xy 254.689538 -59.610985) (xy 254.716788 -59.610498) (xy 254.744158 -59.610972)
			(xy 254.798337 -59.618788) (xy 254.85084 -59.634275) (xy 254.900587 -59.657115) (xy 254.946554 -59.686838)
			(xy 254.967486 -59.704478) (xy 254.96774 -59.704732) (xy 254.974837 -59.710303) (xy 254.991746 -59.716558)
			(xy 255.00076 -59.716924) (xy 255.067816 -59.716924) (xy 255.076833 -59.716569) (xy 255.09375 -59.710319)
			(xy 255.100836 -59.704732) (xy 255.100836 -59.704478) (xy 255.10109 -59.704478) (xy 255.122023 -59.686837)
			(xy 255.167991 -59.657113) (xy 255.217737 -59.634267) (xy 255.270239 -59.618771) (xy 255.324417 -59.610942)
			(xy 255.379159 -59.610942) (xy 255.433337 -59.618771) (xy 255.485839 -59.634267) (xy 255.535585 -59.657113)
			(xy 255.581553 -59.686837) (xy 255.602486 -59.704478) (xy 255.60274 -59.704732) (xy 255.609837 -59.710303)
			(xy 255.626746 -59.716558) (xy 255.63576 -59.716924) (xy 255.702816 -59.716924) (xy 255.711833 -59.716569)
			(xy 255.72875 -59.710319) (xy 255.735836 -59.704732) (xy 255.735836 -59.704478) (xy 255.73609 -59.704478)
			(xy 255.757012 -59.686827) (xy 255.802988 -59.657117) (xy 255.852738 -59.634284) (xy 255.905241 -59.618796)
			(xy 255.959418 -59.610971) (xy 255.986788 -59.610498) (xy 256.014042 -59.610949) (xy 256.067995 -59.618704)
			(xy 256.120295 -59.634059) (xy 256.169877 -59.656702) (xy 256.215733 -59.68617) (xy 256.256928 -59.721864)
			(xy 256.292623 -59.763058) (xy 256.322093 -59.808912) (xy 256.344736 -59.858494) (xy 256.360093 -59.910793)
			(xy 256.367851 -59.964746) (xy 256.367851 -60.019254) (xy 256.360093 -60.073207) (xy 256.344736 -60.125506)
			(xy 256.322093 -60.175088) (xy 256.292623 -60.220942) (xy 256.256928 -60.262136) (xy 256.215733 -60.29783)
			(xy 256.169877 -60.327298) (xy 256.120295 -60.349941) (xy 256.067995 -60.365296) (xy 256.014042 -60.373051)
			(xy 255.986788 -60.373514) (xy 255.959418 -60.373052) (xy 255.905239 -60.365232) (xy 255.852736 -60.349742)
			(xy 255.802989 -60.3269) (xy 255.757022 -60.297175) (xy 255.73609 -60.279534) (xy 255.735836 -60.27928)
			(xy 255.728745 -60.2737) (xy 255.711832 -60.26745) (xy 255.702816 -60.267088) (xy 255.63576 -60.267088)
			(xy 255.626741 -60.267428) (xy 255.609825 -60.273688) (xy 255.60274 -60.27928) (xy 255.602486 -60.279534)
			(xy 255.581553 -60.297175) (xy 255.535585 -60.326899) (xy 255.485839 -60.349745) (xy 255.433337 -60.365241)
			(xy 255.379159 -60.37307) (xy 255.324417 -60.37307) (xy 255.270239 -60.365241) (xy 255.217737 -60.349745)
			(xy 255.167991 -60.326899) (xy 255.122023 -60.297175) (xy 255.10109 -60.279534) (xy 255.100836 -60.27928)
			(xy 255.093745 -60.2737) (xy 255.076832 -60.26745) (xy 255.067816 -60.267088) (xy 255.00076 -60.267088)
			(xy 254.991741 -60.267428) (xy 254.974825 -60.273688) (xy 254.96774 -60.27928) (xy 254.96774 -60.279534)
			(xy 254.967486 -60.279534) (xy 254.946537 -60.297152) (xy 254.900568 -60.326865) (xy 254.850825 -60.349705)
			(xy 254.798328 -60.365201) (xy 254.744156 -60.373036) (xy 254.716788 -60.373514) (xy 254.689538 -60.373015)
			(xy 254.635592 -60.365258) (xy 254.5833 -60.349902) (xy 254.533725 -60.32726) (xy 254.487877 -60.297794)
			(xy 254.446688 -60.262103) (xy 254.410999 -60.220914) (xy 254.381534 -60.175065) (xy 254.358894 -60.125489)
			(xy 254.34354 -60.073196) (xy 254.335784 -60.01925) (xy 227.351844 -60.01925) (xy 227.351844 -60.13196)
			(xy 227.351354 -60.161928) (xy 227.343531 -60.22135) (xy 227.328018 -60.279243) (xy 227.305082 -60.334616)
			(xy 227.275115 -60.386522) (xy 227.238628 -60.434072) (xy 227.196248 -60.476452) (xy 227.148698 -60.512939)
			(xy 227.096792 -60.542906) (xy 227.041419 -60.565842) (xy 226.983526 -60.581355) (xy 226.924104 -60.589178)
			(xy 226.864168 -60.589178) (xy 226.804746 -60.581355) (xy 226.746853 -60.565842) (xy 226.69148 -60.542906)
			(xy 226.639574 -60.512939) (xy 226.592024 -60.476452) (xy 226.549644 -60.434072) (xy 226.513157 -60.386522)
			(xy 226.48319 -60.334616) (xy 226.460254 -60.279243) (xy 226.444741 -60.22135) (xy 226.436918 -60.161928)
			(xy 226.436428 -60.13196) (xy 218.241789 -60.13196) (xy 218.222093 -60.175088) (xy 218.192623 -60.220942)
			(xy 218.156928 -60.262136) (xy 218.115733 -60.29783) (xy 218.069877 -60.327298) (xy 218.020295 -60.349941)
			(xy 217.967995 -60.365296) (xy 217.914042 -60.373051) (xy 217.886788 -60.373514) (xy 217.859418 -60.373052)
			(xy 217.805239 -60.365232) (xy 217.752736 -60.349742) (xy 217.702989 -60.3269) (xy 217.657022 -60.297175)
			(xy 217.63609 -60.279534) (xy 217.635836 -60.27928) (xy 217.628745 -60.2737) (xy 217.611832 -60.26745)
			(xy 217.602816 -60.267088) (xy 217.53576 -60.267088) (xy 217.526741 -60.267428) (xy 217.509825 -60.273688)
			(xy 217.50274 -60.27928) (xy 217.502486 -60.279534) (xy 217.481553 -60.297175) (xy 217.435585 -60.326899)
			(xy 217.385839 -60.349745) (xy 217.333337 -60.365241) (xy 217.279159 -60.37307) (xy 217.224417 -60.37307)
			(xy 217.170239 -60.365241) (xy 217.117737 -60.349745) (xy 217.067991 -60.326899) (xy 217.022023 -60.297175)
			(xy 217.00109 -60.279534) (xy 217.000836 -60.27928) (xy 216.993745 -60.2737) (xy 216.976832 -60.26745)
			(xy 216.967816 -60.267088) (xy 216.90076 -60.267088) (xy 216.891741 -60.267428) (xy 216.874825 -60.273688)
			(xy 216.86774 -60.27928) (xy 216.86774 -60.279534) (xy 216.867486 -60.279534) (xy 216.846537 -60.297152)
			(xy 216.800568 -60.326865) (xy 216.750825 -60.349705) (xy 216.698328 -60.365201) (xy 216.644156 -60.373036)
			(xy 216.616788 -60.373514) (xy 216.589538 -60.373015) (xy 216.535592 -60.365258) (xy 216.4833 -60.349902)
			(xy 216.433725 -60.32726) (xy 216.387877 -60.297794) (xy 216.346688 -60.262103) (xy 216.310999 -60.220914)
			(xy 216.281534 -60.175065) (xy 216.258894 -60.125489) (xy 216.24354 -60.073196) (xy 216.235784 -60.01925)
			(xy 206.95936 -60.01925) (xy 206.957676 -60.038742) (xy 206.957676 -60.03925) (xy 206.957422 -60.042298)
			(xy 206.838037 -61.20003) (xy 233.19054 -61.20003) (xy 233.194611 -61.144408) (xy 233.206737 -61.089971)
			(xy 233.22666 -61.03788) (xy 233.253956 -60.989245) (xy 233.288042 -60.945102) (xy 233.328191 -60.906393)
			(xy 233.373549 -60.873942) (xy 233.423149 -60.848441) (xy 233.475933 -60.830434) (xy 233.530776 -60.820304)
			(xy 233.58651 -60.818267) (xy 233.641947 -60.824367) (xy 233.695904 -60.838473) (xy 233.747233 -60.860285)
			(xy 233.794839 -60.889339) (xy 233.832134 -60.920376) (xy 239.456974 -60.920376) (xy 239.461045 -60.864754)
			(xy 239.473171 -60.810317) (xy 239.493094 -60.758226) (xy 239.52039 -60.709591) (xy 239.554476 -60.665448)
			(xy 239.594625 -60.626739) (xy 239.639983 -60.594288) (xy 239.689583 -60.568787) (xy 239.742367 -60.55078)
			(xy 239.79721 -60.54065) (xy 239.852944 -60.538613) (xy 239.908381 -60.544713) (xy 239.962338 -60.558819)
			(xy 240.013667 -60.580631) (xy 240.061273 -60.609685) (xy 240.089717 -60.633356) (xy 265.996926 -60.633356)
			(xy 266.000997 -60.577734) (xy 266.013123 -60.523297) (xy 266.033046 -60.471206) (xy 266.060342 -60.422571)
			(xy 266.094428 -60.378428) (xy 266.134577 -60.339719) (xy 266.179935 -60.307268) (xy 266.229535 -60.281767)
			(xy 266.282319 -60.26376) (xy 266.337162 -60.25363) (xy 266.392896 -60.251593) (xy 266.448333 -60.257693)
			(xy 266.50229 -60.271799) (xy 266.553619 -60.293611) (xy 266.601225 -60.322665) (xy 266.644093 -60.35834)
			(xy 266.68131 -60.399877) (xy 266.712083 -60.44639) (xy 266.735755 -60.496887) (xy 266.751823 -60.550294)
			(xy 266.759943 -60.60547) (xy 266.760452 -60.633356) (xy 266.759943 -60.661242) (xy 266.751823 -60.716418)
			(xy 266.735755 -60.769825) (xy 266.712083 -60.820322) (xy 266.68131 -60.866835) (xy 266.644093 -60.908372)
			(xy 266.601225 -60.944047) (xy 266.553619 -60.973101) (xy 266.50229 -60.994913) (xy 266.448333 -61.009019)
			(xy 266.392896 -61.015119) (xy 266.337162 -61.013082) (xy 266.282319 -61.002952) (xy 266.229535 -60.984945)
			(xy 266.179935 -60.959444) (xy 266.134577 -60.926993) (xy 266.094428 -60.888284) (xy 266.060342 -60.844141)
			(xy 266.033046 -60.795506) (xy 266.013123 -60.743415) (xy 266.000997 -60.688978) (xy 265.996926 -60.633356)
			(xy 240.089717 -60.633356) (xy 240.104141 -60.64536) (xy 240.141358 -60.686897) (xy 240.172131 -60.73341)
			(xy 240.195803 -60.783907) (xy 240.211871 -60.837314) (xy 240.219991 -60.89249) (xy 240.2205 -60.920376)
			(xy 240.219991 -60.948262) (xy 240.211871 -61.003438) (xy 240.195803 -61.056845) (xy 240.172131 -61.107342)
			(xy 240.141358 -61.153855) (xy 240.104141 -61.195392) (xy 240.061273 -61.231067) (xy 240.013667 -61.260121)
			(xy 239.962338 -61.281933) (xy 239.908381 -61.296039) (xy 239.852944 -61.302139) (xy 239.79721 -61.300102)
			(xy 239.742367 -61.289972) (xy 239.689583 -61.271965) (xy 239.639983 -61.246464) (xy 239.594625 -61.214013)
			(xy 239.554476 -61.175304) (xy 239.52039 -61.131161) (xy 239.493094 -61.082526) (xy 239.473171 -61.030435)
			(xy 239.461045 -60.975998) (xy 239.456974 -60.920376) (xy 233.832134 -60.920376) (xy 233.837707 -60.925014)
			(xy 233.874924 -60.966551) (xy 233.905697 -61.013064) (xy 233.929369 -61.063561) (xy 233.945437 -61.116968)
			(xy 233.953557 -61.172144) (xy 233.954066 -61.20003) (xy 233.953557 -61.227916) (xy 233.945437 -61.283092)
			(xy 233.929369 -61.336499) (xy 233.905697 -61.386996) (xy 233.874924 -61.433509) (xy 233.837707 -61.475046)
			(xy 233.794839 -61.510721) (xy 233.747233 -61.539775) (xy 233.695904 -61.561587) (xy 233.641947 -61.575693)
			(xy 233.58651 -61.581793) (xy 233.530776 -61.579756) (xy 233.475933 -61.569626) (xy 233.423149 -61.551619)
			(xy 233.373549 -61.526118) (xy 233.328191 -61.493667) (xy 233.288042 -61.454958) (xy 233.253956 -61.410815)
			(xy 233.22666 -61.36218) (xy 233.206737 -61.310089) (xy 233.194611 -61.255652) (xy 233.19054 -61.20003)
			(xy 206.838037 -61.20003) (xy 206.778894 -61.773562) (xy 226.029264 -61.773562) (xy 226.033335 -61.71794)
			(xy 226.045461 -61.663503) (xy 226.065384 -61.611412) (xy 226.09268 -61.562777) (xy 226.126766 -61.518634)
			(xy 226.166915 -61.479925) (xy 226.212273 -61.447474) (xy 226.261873 -61.421973) (xy 226.314657 -61.403966)
			(xy 226.3695 -61.393836) (xy 226.425234 -61.391799) (xy 226.480671 -61.397899) (xy 226.534628 -61.412005)
			(xy 226.585957 -61.433817) (xy 226.633563 -61.462871) (xy 226.676431 -61.498546) (xy 226.713648 -61.540083)
			(xy 226.744421 -61.586596) (xy 226.768093 -61.637093) (xy 226.784161 -61.6905) (xy 226.792281 -61.745676)
			(xy 226.79279 -61.773562) (xy 226.792308 -61.799978) (xy 227.210618 -61.799978) (xy 227.214689 -61.744356)
			(xy 227.226815 -61.689919) (xy 227.246738 -61.637828) (xy 227.274034 -61.589193) (xy 227.30812 -61.54505)
			(xy 227.348269 -61.506341) (xy 227.393627 -61.47389) (xy 227.443227 -61.448389) (xy 227.496011 -61.430382)
			(xy 227.550854 -61.420252) (xy 227.606588 -61.418215) (xy 227.662025 -61.424315) (xy 227.715982 -61.438421)
			(xy 227.767311 -61.460233) (xy 227.814917 -61.489287) (xy 227.857785 -61.524962) (xy 227.895002 -61.566499)
			(xy 227.925775 -61.613012) (xy 227.949447 -61.663509) (xy 227.965515 -61.716916) (xy 227.973635 -61.772092)
			(xy 227.974144 -61.799978) (xy 231.00614 -61.799978) (xy 231.010211 -61.744356) (xy 231.022337 -61.689919)
			(xy 231.04226 -61.637828) (xy 231.069556 -61.589193) (xy 231.103642 -61.54505) (xy 231.143791 -61.506341)
			(xy 231.189149 -61.47389) (xy 231.238749 -61.448389) (xy 231.291533 -61.430382) (xy 231.346376 -61.420252)
			(xy 231.40211 -61.418215) (xy 231.457547 -61.424315) (xy 231.511504 -61.438421) (xy 231.562833 -61.460233)
			(xy 231.610439 -61.489287) (xy 231.653307 -61.524962) (xy 231.690524 -61.566499) (xy 231.703331 -61.585856)
			(xy 240.609372 -61.585856) (xy 240.613443 -61.530234) (xy 240.625569 -61.475797) (xy 240.645492 -61.423706)
			(xy 240.672788 -61.375071) (xy 240.706874 -61.330928) (xy 240.747023 -61.292219) (xy 240.792381 -61.259768)
			(xy 240.841981 -61.234267) (xy 240.894765 -61.21626) (xy 240.949608 -61.20613) (xy 241.005342 -61.204093)
			(xy 241.060779 -61.210193) (xy 241.114736 -61.224299) (xy 241.166065 -61.246111) (xy 241.213671 -61.275165)
			(xy 241.256539 -61.31084) (xy 241.293756 -61.352377) (xy 241.324529 -61.39889) (xy 241.348201 -61.449387)
			(xy 241.359762 -61.487812) (xy 264.504422 -61.487812) (xy 264.508493 -61.43219) (xy 264.520619 -61.377753)
			(xy 264.540542 -61.325662) (xy 264.567838 -61.277027) (xy 264.601924 -61.232884) (xy 264.642073 -61.194175)
			(xy 264.687431 -61.161724) (xy 264.737031 -61.136223) (xy 264.789815 -61.118216) (xy 264.844658 -61.108086)
			(xy 264.900392 -61.106049) (xy 264.955829 -61.112149) (xy 265.009786 -61.126255) (xy 265.061115 -61.148067)
			(xy 265.108721 -61.177121) (xy 265.151589 -61.212796) (xy 265.188806 -61.254333) (xy 265.219579 -61.300846)
			(xy 265.243251 -61.351343) (xy 265.259319 -61.40475) (xy 265.267439 -61.459926) (xy 265.267948 -61.487812)
			(xy 265.267439 -61.515698) (xy 265.259319 -61.570874) (xy 265.243251 -61.624281) (xy 265.219579 -61.674778)
			(xy 265.188806 -61.721291) (xy 265.151589 -61.762828) (xy 265.108721 -61.798503) (xy 265.061115 -61.827557)
			(xy 265.009786 -61.849369) (xy 264.955829 -61.863475) (xy 264.900392 -61.869575) (xy 264.844658 -61.867538)
			(xy 264.789815 -61.857408) (xy 264.737031 -61.839401) (xy 264.687431 -61.8139) (xy 264.642073 -61.781449)
			(xy 264.601924 -61.74274) (xy 264.567838 -61.698597) (xy 264.540542 -61.649962) (xy 264.520619 -61.597871)
			(xy 264.508493 -61.543434) (xy 264.504422 -61.487812) (xy 241.359762 -61.487812) (xy 241.364269 -61.502794)
			(xy 241.372389 -61.55797) (xy 241.372898 -61.585856) (xy 241.372389 -61.613742) (xy 241.364269 -61.668918)
			(xy 241.348201 -61.722325) (xy 241.324529 -61.772822) (xy 241.293756 -61.819335) (xy 241.256539 -61.860872)
			(xy 241.213671 -61.896547) (xy 241.166065 -61.925601) (xy 241.114736 -61.947413) (xy 241.060779 -61.961519)
			(xy 241.005342 -61.967619) (xy 240.949608 -61.965582) (xy 240.894765 -61.955452) (xy 240.841981 -61.937445)
			(xy 240.792381 -61.911944) (xy 240.747023 -61.879493) (xy 240.706874 -61.840784) (xy 240.672788 -61.796641)
			(xy 240.645492 -61.748006) (xy 240.625569 -61.695915) (xy 240.613443 -61.641478) (xy 240.609372 -61.585856)
			(xy 231.703331 -61.585856) (xy 231.721297 -61.613012) (xy 231.744969 -61.663509) (xy 231.761037 -61.716916)
			(xy 231.769157 -61.772092) (xy 231.769666 -61.799978) (xy 231.769157 -61.827864) (xy 231.761037 -61.88304)
			(xy 231.744969 -61.936447) (xy 231.721297 -61.986944) (xy 231.690524 -62.033457) (xy 231.653307 -62.074994)
			(xy 231.610439 -62.110669) (xy 231.562833 -62.139723) (xy 231.511504 -62.161535) (xy 231.457547 -62.175641)
			(xy 231.40211 -62.181741) (xy 231.346376 -62.179704) (xy 231.291533 -62.169574) (xy 231.238749 -62.151567)
			(xy 231.189149 -62.126066) (xy 231.143791 -62.093615) (xy 231.103642 -62.054906) (xy 231.069556 -62.010763)
			(xy 231.04226 -61.962128) (xy 231.022337 -61.910037) (xy 231.010211 -61.8556) (xy 231.00614 -61.799978)
			(xy 227.974144 -61.799978) (xy 227.973635 -61.827864) (xy 227.965515 -61.88304) (xy 227.949447 -61.936447)
			(xy 227.925775 -61.986944) (xy 227.895002 -62.033457) (xy 227.857785 -62.074994) (xy 227.814917 -62.110669)
			(xy 227.767311 -62.139723) (xy 227.715982 -62.161535) (xy 227.662025 -62.175641) (xy 227.606588 -62.181741)
			(xy 227.550854 -62.179704) (xy 227.496011 -62.169574) (xy 227.443227 -62.151567) (xy 227.393627 -62.126066)
			(xy 227.348269 -62.093615) (xy 227.30812 -62.054906) (xy 227.274034 -62.010763) (xy 227.246738 -61.962128)
			(xy 227.226815 -61.910037) (xy 227.214689 -61.8556) (xy 227.210618 -61.799978) (xy 226.792308 -61.799978)
			(xy 226.792281 -61.801448) (xy 226.784161 -61.856624) (xy 226.768093 -61.910031) (xy 226.744421 -61.960528)
			(xy 226.713648 -62.007041) (xy 226.676431 -62.048578) (xy 226.633563 -62.084253) (xy 226.585957 -62.113307)
			(xy 226.534628 -62.135119) (xy 226.480671 -62.149225) (xy 226.425234 -62.155325) (xy 226.3695 -62.153288)
			(xy 226.314657 -62.143158) (xy 226.261873 -62.125151) (xy 226.212273 -62.09965) (xy 226.166915 -62.067199)
			(xy 226.126766 -62.02849) (xy 226.09268 -61.984347) (xy 226.065384 -61.935712) (xy 226.045461 -61.883621)
			(xy 226.033335 -61.829184) (xy 226.029264 -61.773562) (xy 206.778894 -61.773562) (xy 206.778606 -61.776356)
			(xy 206.774983 -61.807565) (xy 206.761871 -61.869012) (xy 206.742206 -61.928687) (xy 206.729584 -61.957458)
			(xy 206.72679 -61.965332) (xy 206.71844 -61.995389) (xy 206.696255 -62.053697) (xy 206.668051 -62.109344)
			(xy 206.634144 -62.161711) (xy 206.594909 -62.210216) (xy 206.57312 -62.23254) (xy 206.446882 -62.358778)
			(xy 236.702344 -62.358778) (xy 236.706415 -62.303156) (xy 236.718541 -62.248719) (xy 236.738464 -62.196628)
			(xy 236.76576 -62.147993) (xy 236.799846 -62.10385) (xy 236.839995 -62.065141) (xy 236.885353 -62.03269)
			(xy 236.934953 -62.007189) (xy 236.987737 -61.989182) (xy 237.04258 -61.979052) (xy 237.098314 -61.977015)
			(xy 237.153751 -61.983115) (xy 237.207708 -61.997221) (xy 237.259037 -62.019033) (xy 237.306643 -62.048087)
			(xy 237.349511 -62.083762) (xy 237.382907 -62.121034) (xy 262.442196 -62.121034) (xy 262.446267 -62.065412)
			(xy 262.458393 -62.010975) (xy 262.478316 -61.958884) (xy 262.505612 -61.910249) (xy 262.539698 -61.866106)
			(xy 262.579847 -61.827397) (xy 262.625205 -61.794946) (xy 262.674805 -61.769445) (xy 262.727589 -61.751438)
			(xy 262.782432 -61.741308) (xy 262.838166 -61.739271) (xy 262.893603 -61.745371) (xy 262.94756 -61.759477)
			(xy 262.998889 -61.781289) (xy 263.046495 -61.810343) (xy 263.089363 -61.846018) (xy 263.12658 -61.887555)
			(xy 263.157353 -61.934068) (xy 263.181025 -61.984565) (xy 263.197093 -62.037972) (xy 263.205213 -62.093148)
			(xy 263.205722 -62.121034) (xy 263.205213 -62.14892) (xy 263.197093 -62.204096) (xy 263.181025 -62.257503)
			(xy 263.157353 -62.308) (xy 263.12658 -62.354513) (xy 263.089363 -62.39605) (xy 263.046495 -62.431725)
			(xy 262.998889 -62.460779) (xy 262.94756 -62.482591) (xy 262.893603 -62.496697) (xy 262.838166 -62.502797)
			(xy 262.782432 -62.50076) (xy 262.727589 -62.49063) (xy 262.674805 -62.472623) (xy 262.625205 -62.447122)
			(xy 262.579847 -62.414671) (xy 262.539698 -62.375962) (xy 262.505612 -62.331819) (xy 262.478316 -62.283184)
			(xy 262.458393 -62.231093) (xy 262.446267 -62.176656) (xy 262.442196 -62.121034) (xy 237.382907 -62.121034)
			(xy 237.386728 -62.125299) (xy 237.417501 -62.171812) (xy 237.441173 -62.222309) (xy 237.457241 -62.275716)
			(xy 237.465361 -62.330892) (xy 237.46587 -62.358778) (xy 237.465361 -62.386664) (xy 237.457241 -62.44184)
			(xy 237.441173 -62.495247) (xy 237.417501 -62.545744) (xy 237.386728 -62.592257) (xy 237.349511 -62.633794)
			(xy 237.306643 -62.669469) (xy 237.259037 -62.698523) (xy 237.207708 -62.720335) (xy 237.153751 -62.734441)
			(xy 237.098314 -62.740541) (xy 237.04258 -62.738504) (xy 236.987737 -62.728374) (xy 236.934953 -62.710367)
			(xy 236.885353 -62.684866) (xy 236.839995 -62.652415) (xy 236.799846 -62.613706) (xy 236.76576 -62.569563)
			(xy 236.738464 -62.520928) (xy 236.718541 -62.468837) (xy 236.706415 -62.4144) (xy 236.702344 -62.358778)
			(xy 206.446882 -62.358778) (xy 205.592108 -63.213552) (xy 216.220765 -63.213552) (xy 216.220765 -63.159048)
			(xy 216.228522 -63.105098) (xy 216.243878 -63.052801) (xy 216.26652 -63.003222) (xy 216.295987 -62.95737)
			(xy 216.33168 -62.916179) (xy 216.372872 -62.880486) (xy 216.418724 -62.851019) (xy 216.468303 -62.828377)
			(xy 216.5206 -62.813022) (xy 216.57455 -62.805265) (xy 216.601802 -62.804802) (xy 216.629172 -62.805266)
			(xy 216.683351 -62.813085) (xy 216.735855 -62.828574) (xy 216.785601 -62.851416) (xy 216.831568 -62.881141)
			(xy 216.8525 -62.898782) (xy 216.852754 -62.899036) (xy 216.859847 -62.904613) (xy 216.876759 -62.910865)
			(xy 216.885774 -62.911228) (xy 216.95283 -62.911228) (xy 216.961848 -62.910879) (xy 216.978764 -62.904625)
			(xy 216.98585 -62.899036) (xy 216.98585 -62.898782) (xy 216.986104 -62.898782) (xy 217.007037 -62.881141)
			(xy 217.053005 -62.851417) (xy 217.102751 -62.828571) (xy 217.155253 -62.813075) (xy 217.209431 -62.805246)
			(xy 217.264173 -62.805246) (xy 217.318351 -62.813075) (xy 217.370853 -62.828571) (xy 217.420599 -62.851417)
			(xy 217.466567 -62.881141) (xy 217.4875 -62.898782) (xy 217.487754 -62.899036) (xy 217.494847 -62.904613)
			(xy 217.511759 -62.910865) (xy 217.520774 -62.911228) (xy 217.58783 -62.911228) (xy 217.596848 -62.910879)
			(xy 217.613764 -62.904625) (xy 217.62085 -62.899036) (xy 217.62085 -62.898782) (xy 217.621104 -62.898782)
			(xy 217.642021 -62.881125) (xy 217.687999 -62.851416) (xy 217.73775 -62.828584) (xy 217.790254 -62.813097)
			(xy 217.844432 -62.805274) (xy 217.871802 -62.804802) (xy 217.899054 -62.805268) (xy 217.953003 -62.813025)
			(xy 218.005299 -62.828381) (xy 218.054877 -62.851022) (xy 218.100728 -62.88049) (xy 218.141919 -62.916182)
			(xy 218.177612 -62.957373) (xy 218.205089 -63.000128) (xy 231.00614 -63.000128) (xy 231.010211 -62.944506)
			(xy 231.022337 -62.890069) (xy 231.04226 -62.837978) (xy 231.069556 -62.789343) (xy 231.103642 -62.7452)
			(xy 231.143791 -62.706491) (xy 231.189149 -62.67404) (xy 231.238749 -62.648539) (xy 231.291533 -62.630532)
			(xy 231.346376 -62.620402) (xy 231.40211 -62.618365) (xy 231.457547 -62.624465) (xy 231.511504 -62.638571)
			(xy 231.562833 -62.660383) (xy 231.610439 -62.689437) (xy 231.653307 -62.725112) (xy 231.690524 -62.766649)
			(xy 231.721297 -62.813162) (xy 231.744969 -62.863659) (xy 231.761037 -62.917066) (xy 231.769157 -62.972242)
			(xy 231.769666 -63.000128) (xy 231.769157 -63.028014) (xy 231.761037 -63.08319) (xy 231.744969 -63.136597)
			(xy 231.721297 -63.187094) (xy 231.690524 -63.233607) (xy 231.653307 -63.275144) (xy 231.610439 -63.310819)
			(xy 231.562833 -63.339873) (xy 231.511504 -63.361685) (xy 231.457547 -63.375791) (xy 231.40211 -63.381891)
			(xy 231.346376 -63.379854) (xy 231.291533 -63.369724) (xy 231.238749 -63.351717) (xy 231.189149 -63.326216)
			(xy 231.143791 -63.293765) (xy 231.103642 -63.255056) (xy 231.069556 -63.210913) (xy 231.04226 -63.162278)
			(xy 231.022337 -63.110187) (xy 231.010211 -63.05575) (xy 231.00614 -63.000128) (xy 218.205089 -63.000128)
			(xy 218.207079 -63.003225) (xy 218.22972 -63.052803) (xy 218.245076 -63.105099) (xy 218.252832 -63.159048)
			(xy 218.252832 -63.213552) (xy 218.245076 -63.267501) (xy 218.22972 -63.319797) (xy 218.207079 -63.369375)
			(xy 218.177612 -63.415227) (xy 218.176786 -63.41618) (xy 224.953574 -63.41618) (xy 224.957645 -63.360558)
			(xy 224.969771 -63.306121) (xy 224.989694 -63.25403) (xy 225.01699 -63.205395) (xy 225.051076 -63.161252)
			(xy 225.091225 -63.122543) (xy 225.136583 -63.090092) (xy 225.186183 -63.064591) (xy 225.238967 -63.046584)
			(xy 225.29381 -63.036454) (xy 225.349544 -63.034417) (xy 225.404981 -63.040517) (xy 225.458938 -63.054623)
			(xy 225.510267 -63.076435) (xy 225.557873 -63.105489) (xy 225.600741 -63.141164) (xy 225.637958 -63.182701)
			(xy 225.668731 -63.229214) (xy 225.692403 -63.279711) (xy 225.708471 -63.333118) (xy 225.716591 -63.388294)
			(xy 225.7171 -63.41618) (xy 225.716591 -63.444066) (xy 225.708471 -63.499242) (xy 225.694029 -63.547244)
			(xy 226.964238 -63.547244) (xy 226.968309 -63.491622) (xy 226.980435 -63.437185) (xy 227.000358 -63.385094)
			(xy 227.027654 -63.336459) (xy 227.06174 -63.292316) (xy 227.101889 -63.253607) (xy 227.147247 -63.221156)
			(xy 227.196847 -63.195655) (xy 227.249631 -63.177648) (xy 227.304474 -63.167518) (xy 227.360208 -63.165481)
			(xy 227.415645 -63.171581) (xy 227.469602 -63.185687) (xy 227.520931 -63.207499) (xy 227.568537 -63.236553)
			(xy 227.611405 -63.272228) (xy 227.648622 -63.313765) (xy 227.679395 -63.360278) (xy 227.703067 -63.410775)
			(xy 227.719135 -63.464182) (xy 227.727255 -63.519358) (xy 227.727764 -63.547244) (xy 227.727255 -63.57513)
			(xy 227.723584 -63.600076) (xy 233.19054 -63.600076) (xy 233.194611 -63.544454) (xy 233.206737 -63.490017)
			(xy 233.22666 -63.437926) (xy 233.253956 -63.389291) (xy 233.288042 -63.345148) (xy 233.328191 -63.306439)
			(xy 233.373549 -63.273988) (xy 233.423149 -63.248487) (xy 233.475933 -63.23048) (xy 233.530776 -63.22035)
			(xy 233.58651 -63.218313) (xy 233.641947 -63.224413) (xy 233.695904 -63.238519) (xy 233.747233 -63.260331)
			(xy 233.794839 -63.289385) (xy 233.837707 -63.32506) (xy 233.874924 -63.366597) (xy 233.905697 -63.41311)
			(xy 233.923449 -63.450978) (xy 237.60633 -63.450978) (xy 237.610401 -63.395356) (xy 237.622527 -63.340919)
			(xy 237.64245 -63.288828) (xy 237.669746 -63.240193) (xy 237.703832 -63.19605) (xy 237.743981 -63.157341)
			(xy 237.789339 -63.12489) (xy 237.838939 -63.099389) (xy 237.891723 -63.081382) (xy 237.946566 -63.071252)
			(xy 238.0023 -63.069215) (xy 238.057737 -63.075315) (xy 238.111694 -63.089421) (xy 238.163023 -63.111233)
			(xy 238.210629 -63.140287) (xy 238.253497 -63.175962) (xy 238.287178 -63.213552) (xy 254.320765 -63.213552)
			(xy 254.320765 -63.159048) (xy 254.328522 -63.105098) (xy 254.343878 -63.052801) (xy 254.36652 -63.003222)
			(xy 254.395987 -62.95737) (xy 254.43168 -62.916179) (xy 254.472872 -62.880486) (xy 254.518724 -62.851019)
			(xy 254.568303 -62.828377) (xy 254.6206 -62.813022) (xy 254.67455 -62.805265) (xy 254.701802 -62.804802)
			(xy 254.729172 -62.805266) (xy 254.783351 -62.813085) (xy 254.835855 -62.828574) (xy 254.885601 -62.851416)
			(xy 254.931568 -62.881141) (xy 254.9525 -62.898782) (xy 254.952754 -62.899036) (xy 254.959847 -62.904613)
			(xy 254.976759 -62.910865) (xy 254.985774 -62.911228) (xy 255.05283 -62.911228) (xy 255.061848 -62.910879)
			(xy 255.078764 -62.904625) (xy 255.08585 -62.899036) (xy 255.08585 -62.898782) (xy 255.086104 -62.898782)
			(xy 255.107037 -62.881141) (xy 255.153005 -62.851417) (xy 255.202751 -62.828571) (xy 255.255253 -62.813075)
			(xy 255.309431 -62.805246) (xy 255.364173 -62.805246) (xy 255.418351 -62.813075) (xy 255.470853 -62.828571)
			(xy 255.520599 -62.851417) (xy 255.566567 -62.881141) (xy 255.5875 -62.898782) (xy 255.587754 -62.899036)
			(xy 255.594847 -62.904613) (xy 255.611759 -62.910865) (xy 255.620774 -62.911228) (xy 255.68783 -62.911228)
			(xy 255.696848 -62.910879) (xy 255.713764 -62.904625) (xy 255.72085 -62.899036) (xy 255.72085 -62.898782)
			(xy 255.721104 -62.898782) (xy 255.742021 -62.881125) (xy 255.787999 -62.851416) (xy 255.83775 -62.828584)
			(xy 255.890254 -62.813097) (xy 255.944432 -62.805274) (xy 255.971802 -62.804802) (xy 255.999054 -62.805268)
			(xy 256.053003 -62.813025) (xy 256.105299 -62.828381) (xy 256.154877 -62.851022) (xy 256.200728 -62.88049)
			(xy 256.241919 -62.916182) (xy 256.277612 -62.957373) (xy 256.307079 -63.003225) (xy 256.32972 -63.052803)
			(xy 256.339537 -63.086234) (xy 259.58749 -63.086234) (xy 259.591561 -63.030612) (xy 259.603687 -62.976175)
			(xy 259.62361 -62.924084) (xy 259.650906 -62.875449) (xy 259.684992 -62.831306) (xy 259.725141 -62.792597)
			(xy 259.770499 -62.760146) (xy 259.820099 -62.734645) (xy 259.872883 -62.716638) (xy 259.927726 -62.706508)
			(xy 259.98346 -62.704471) (xy 260.038897 -62.710571) (xy 260.092854 -62.724677) (xy 260.113012 -62.733243)
			(xy 265.866051 -62.733243) (xy 265.866052 -62.678736) (xy 265.873811 -62.624784) (xy 265.889169 -62.572485)
			(xy 265.911814 -62.522905) (xy 265.941284 -62.477052) (xy 265.97698 -62.43586) (xy 266.018175 -62.400167)
			(xy 266.06403 -62.3707) (xy 266.113612 -62.348059) (xy 266.165912 -62.332705) (xy 266.219865 -62.32495)
			(xy 266.247118 -62.324488) (xy 266.270673 -62.324865) (xy 266.317417 -62.330724) (xy 266.340336 -62.336172)
			(xy 266.354094 -62.3392) (xy 266.382243 -62.338346) (xy 266.40909 -62.329842) (xy 266.432597 -62.314332)
			(xy 266.450978 -62.292996) (xy 266.462837 -62.267452) (xy 266.467274 -62.239642) (xy 266.463952 -62.211676)
			(xy 266.458954 -62.198504) (xy 266.449643 -62.175115) (xy 266.436518 -62.126514) (xy 266.429895 -62.076609)
			(xy 266.42949 -62.051438) (xy 266.429914 -62.024182) (xy 266.437667 -61.970223) (xy 266.45302 -61.917918)
			(xy 266.475661 -61.868329) (xy 266.505128 -61.822468) (xy 266.540823 -61.781267) (xy 266.582018 -61.745566)
			(xy 266.627874 -61.716091) (xy 266.677459 -61.693442) (xy 266.729762 -61.67808) (xy 266.783719 -61.670319)
			(xy 266.838232 -61.670315) (xy 266.89219 -61.67807) (xy 266.944495 -61.693425) (xy 266.994082 -61.716067)
			(xy 267.039943 -61.745536) (xy 267.081142 -61.781233) (xy 267.116842 -61.822429) (xy 267.146315 -61.868286)
			(xy 267.168963 -61.917871) (xy 267.184323 -61.970175) (xy 267.192082 -62.024132) (xy 267.192084 -62.078645)
			(xy 267.184327 -62.132603) (xy 267.168971 -62.184907) (xy 267.146326 -62.234494) (xy 267.116856 -62.280353)
			(xy 267.081158 -62.321551) (xy 267.039961 -62.35725) (xy 266.994102 -62.386722) (xy 266.944516 -62.409367)
			(xy 266.892212 -62.424725) (xy 266.838254 -62.432483) (xy 266.810998 -62.432946) (xy 266.787444 -62.432565)
			(xy 266.740699 -62.426709) (xy 266.71778 -62.421262) (xy 266.704026 -62.418204) (xy 266.675869 -62.419054)
			(xy 266.649015 -62.427558) (xy 266.625502 -62.443071) (xy 266.607118 -62.464415) (xy 266.59526 -62.489966)
			(xy 266.590828 -62.517785) (xy 266.594159 -62.545756) (xy 266.599162 -62.55893) (xy 266.608484 -62.582315)
			(xy 266.621605 -62.630918) (xy 266.628223 -62.680825) (xy 266.628626 -62.705996) (xy 266.628149 -62.733249)
			(xy 266.620392 -62.787202) (xy 266.605036 -62.839501) (xy 266.582393 -62.889082) (xy 266.552925 -62.934936)
			(xy 266.517231 -62.97613) (xy 266.476037 -63.011825) (xy 266.430183 -63.041293) (xy 266.380601 -63.063936)
			(xy 266.328302 -63.079292) (xy 266.27435 -63.087049) (xy 266.219843 -63.087048) (xy 266.165891 -63.079291)
			(xy 266.113592 -63.063934) (xy 266.064011 -63.04129) (xy 266.018158 -63.011821) (xy 265.976965 -62.976125)
			(xy 265.941271 -62.934931) (xy 265.911803 -62.889076) (xy 265.889161 -62.839495) (xy 265.873806 -62.787195)
			(xy 265.866051 -62.733243) (xy 260.113012 -62.733243) (xy 260.144183 -62.746489) (xy 260.191789 -62.775543)
			(xy 260.234657 -62.811218) (xy 260.271874 -62.852755) (xy 260.302647 -62.899268) (xy 260.326319 -62.949765)
			(xy 260.342387 -63.003172) (xy 260.350507 -63.058348) (xy 260.351016 -63.086234) (xy 260.350507 -63.11412)
			(xy 260.342387 -63.169296) (xy 260.326319 -63.222703) (xy 260.302647 -63.2732) (xy 260.302494 -63.273432)
			(xy 261.776716 -63.273432) (xy 261.780787 -63.21781) (xy 261.792913 -63.163373) (xy 261.812836 -63.111282)
			(xy 261.840132 -63.062647) (xy 261.874218 -63.018504) (xy 261.914367 -62.979795) (xy 261.959725 -62.947344)
			(xy 262.009325 -62.921843) (xy 262.062109 -62.903836) (xy 262.116952 -62.893706) (xy 262.172686 -62.891669)
			(xy 262.228123 -62.897769) (xy 262.28208 -62.911875) (xy 262.333409 -62.933687) (xy 262.381015 -62.962741)
			(xy 262.423883 -62.998416) (xy 262.4611 -63.039953) (xy 262.491873 -63.086466) (xy 262.515545 -63.136963)
			(xy 262.531613 -63.19037) (xy 262.539733 -63.245546) (xy 262.540242 -63.273432) (xy 262.539733 -63.301318)
			(xy 262.531613 -63.356494) (xy 262.515545 -63.409901) (xy 262.491873 -63.460398) (xy 262.4611 -63.506911)
			(xy 262.423883 -63.548448) (xy 262.381015 -63.584123) (xy 262.333409 -63.613177) (xy 262.28208 -63.634989)
			(xy 262.228123 -63.649095) (xy 262.172686 -63.655195) (xy 262.116952 -63.653158) (xy 262.062109 -63.643028)
			(xy 262.009325 -63.625021) (xy 261.959725 -63.59952) (xy 261.914367 -63.567069) (xy 261.874218 -63.52836)
			(xy 261.840132 -63.484217) (xy 261.812836 -63.435582) (xy 261.792913 -63.383491) (xy 261.780787 -63.329054)
			(xy 261.776716 -63.273432) (xy 260.302494 -63.273432) (xy 260.271874 -63.319713) (xy 260.234657 -63.36125)
			(xy 260.191789 -63.396925) (xy 260.144183 -63.425979) (xy 260.092854 -63.447791) (xy 260.038897 -63.461897)
			(xy 259.98346 -63.467997) (xy 259.927726 -63.46596) (xy 259.872883 -63.45583) (xy 259.820099 -63.437823)
			(xy 259.770499 -63.412322) (xy 259.725141 -63.379871) (xy 259.684992 -63.341162) (xy 259.650906 -63.297019)
			(xy 259.62361 -63.248384) (xy 259.603687 -63.196293) (xy 259.591561 -63.141856) (xy 259.58749 -63.086234)
			(xy 256.339537 -63.086234) (xy 256.345076 -63.105099) (xy 256.352832 -63.159048) (xy 256.352832 -63.213552)
			(xy 256.345076 -63.267501) (xy 256.32972 -63.319797) (xy 256.307079 -63.369375) (xy 256.277612 -63.415227)
			(xy 256.241919 -63.456418) (xy 256.200728 -63.49211) (xy 256.154877 -63.521578) (xy 256.105299 -63.544219)
			(xy 256.053003 -63.559575) (xy 255.999054 -63.567332) (xy 255.971802 -63.567818) (xy 255.944431 -63.567371)
			(xy 255.89025 -63.559551) (xy 255.837746 -63.544059) (xy 255.787999 -63.521213) (xy 255.742034 -63.491482)
			(xy 255.721104 -63.473838) (xy 255.72085 -63.473584) (xy 255.713755 -63.46801) (xy 255.696845 -63.461756)
			(xy 255.68783 -63.461392) (xy 255.620774 -63.461392) (xy 255.611756 -63.461739) (xy 255.594839 -63.467994)
			(xy 255.587754 -63.473584) (xy 255.5875 -63.473838) (xy 255.566567 -63.491479) (xy 255.520599 -63.521203)
			(xy 255.470853 -63.544049) (xy 255.418351 -63.559545) (xy 255.364173 -63.567374) (xy 255.309431 -63.567374)
			(xy 255.255253 -63.559545) (xy 255.202751 -63.544049) (xy 255.153005 -63.521203) (xy 255.107037 -63.491479)
			(xy 255.086104 -63.473838) (xy 255.08585 -63.473584) (xy 255.078755 -63.46801) (xy 255.061845 -63.461756)
			(xy 255.05283 -63.461392) (xy 254.985774 -63.461392) (xy 254.976756 -63.461739) (xy 254.959839 -63.467994)
			(xy 254.952754 -63.473584) (xy 254.952754 -63.473838) (xy 254.9525 -63.473838) (xy 254.931584 -63.491497)
			(xy 254.885606 -63.521205) (xy 254.835855 -63.544036) (xy 254.783351 -63.559523) (xy 254.729172 -63.567347)
			(xy 254.701802 -63.567818) (xy 254.67455 -63.567335) (xy 254.6206 -63.559578) (xy 254.568303 -63.544223)
			(xy 254.518724 -63.521581) (xy 254.472872 -63.492114) (xy 254.43168 -63.456421) (xy 254.395987 -63.41523)
			(xy 254.36652 -63.369378) (xy 254.343878 -63.319799) (xy 254.328522 -63.267502) (xy 254.320765 -63.213552)
			(xy 238.287178 -63.213552) (xy 238.290714 -63.217499) (xy 238.321487 -63.264012) (xy 238.345159 -63.314509)
			(xy 238.361227 -63.367916) (xy 238.369347 -63.423092) (xy 238.369856 -63.450978) (xy 238.369347 -63.478864)
			(xy 238.361227 -63.53404) (xy 238.345159 -63.587447) (xy 238.321487 -63.637944) (xy 238.31478 -63.648082)
			(xy 241.242594 -63.648082) (xy 241.246665 -63.59246) (xy 241.258791 -63.538023) (xy 241.278714 -63.485932)
			(xy 241.30601 -63.437297) (xy 241.340096 -63.393154) (xy 241.380245 -63.354445) (xy 241.425603 -63.321994)
			(xy 241.475203 -63.296493) (xy 241.527987 -63.278486) (xy 241.58283 -63.268356) (xy 241.638564 -63.266319)
			(xy 241.694001 -63.272419) (xy 241.747958 -63.286525) (xy 241.799287 -63.308337) (xy 241.846893 -63.337391)
			(xy 241.889761 -63.373066) (xy 241.926978 -63.414603) (xy 241.957751 -63.461116) (xy 241.981423 -63.511613)
			(xy 241.997491 -63.56502) (xy 242.005611 -63.620196) (xy 242.00612 -63.648082) (xy 242.005611 -63.675968)
			(xy 241.997491 -63.731144) (xy 241.981423 -63.784551) (xy 241.957751 -63.835048) (xy 241.926978 -63.881561)
			(xy 241.889761 -63.923098) (xy 241.846893 -63.958773) (xy 241.799287 -63.987827) (xy 241.747958 -64.009639)
			(xy 241.694001 -64.023745) (xy 241.638564 -64.029845) (xy 241.58283 -64.027808) (xy 241.527987 -64.017678)
			(xy 241.475203 -63.999671) (xy 241.425603 -63.97417) (xy 241.380245 -63.941719) (xy 241.340096 -63.90301)
			(xy 241.30601 -63.858867) (xy 241.278714 -63.810232) (xy 241.258791 -63.758141) (xy 241.246665 -63.703704)
			(xy 241.242594 -63.648082) (xy 238.31478 -63.648082) (xy 238.290714 -63.684457) (xy 238.253497 -63.725994)
			(xy 238.210629 -63.761669) (xy 238.163023 -63.790723) (xy 238.111694 -63.812535) (xy 238.057737 -63.826641)
			(xy 238.0023 -63.832741) (xy 237.946566 -63.830704) (xy 237.891723 -63.820574) (xy 237.838939 -63.802567)
			(xy 237.789339 -63.777066) (xy 237.743981 -63.744615) (xy 237.703832 -63.705906) (xy 237.669746 -63.661763)
			(xy 237.64245 -63.613128) (xy 237.622527 -63.561037) (xy 237.610401 -63.5066) (xy 237.60633 -63.450978)
			(xy 233.923449 -63.450978) (xy 233.929369 -63.463607) (xy 233.945437 -63.517014) (xy 233.953557 -63.57219)
			(xy 233.954066 -63.600076) (xy 233.953557 -63.627962) (xy 233.945437 -63.683138) (xy 233.929369 -63.736545)
			(xy 233.905697 -63.787042) (xy 233.874924 -63.833555) (xy 233.837707 -63.875092) (xy 233.794839 -63.910767)
			(xy 233.747233 -63.939821) (xy 233.695904 -63.961633) (xy 233.641947 -63.975739) (xy 233.58651 -63.981839)
			(xy 233.530776 -63.979802) (xy 233.475933 -63.969672) (xy 233.423149 -63.951665) (xy 233.373549 -63.926164)
			(xy 233.328191 -63.893713) (xy 233.288042 -63.855004) (xy 233.253956 -63.810861) (xy 233.22666 -63.762226)
			(xy 233.206737 -63.710135) (xy 233.194611 -63.655698) (xy 233.19054 -63.600076) (xy 227.723584 -63.600076)
			(xy 227.719135 -63.630306) (xy 227.703067 -63.683713) (xy 227.679395 -63.73421) (xy 227.648622 -63.780723)
			(xy 227.611405 -63.82226) (xy 227.568537 -63.857935) (xy 227.520931 -63.886989) (xy 227.469602 -63.908801)
			(xy 227.415645 -63.922907) (xy 227.360208 -63.929007) (xy 227.304474 -63.92697) (xy 227.249631 -63.91684)
			(xy 227.196847 -63.898833) (xy 227.147247 -63.873332) (xy 227.101889 -63.840881) (xy 227.06174 -63.802172)
			(xy 227.027654 -63.758029) (xy 227.000358 -63.709394) (xy 226.980435 -63.657303) (xy 226.968309 -63.602866)
			(xy 226.964238 -63.547244) (xy 225.694029 -63.547244) (xy 225.692403 -63.552649) (xy 225.668731 -63.603146)
			(xy 225.637958 -63.649659) (xy 225.600741 -63.691196) (xy 225.557873 -63.726871) (xy 225.510267 -63.755925)
			(xy 225.458938 -63.777737) (xy 225.404981 -63.791843) (xy 225.349544 -63.797943) (xy 225.29381 -63.795906)
			(xy 225.238967 -63.785776) (xy 225.186183 -63.767769) (xy 225.136583 -63.742268) (xy 225.091225 -63.709817)
			(xy 225.051076 -63.671108) (xy 225.01699 -63.626965) (xy 224.989694 -63.57833) (xy 224.969771 -63.526239)
			(xy 224.957645 -63.471802) (xy 224.953574 -63.41618) (xy 218.176786 -63.41618) (xy 218.141919 -63.456418)
			(xy 218.100728 -63.49211) (xy 218.054877 -63.521578) (xy 218.005299 -63.544219) (xy 217.953003 -63.559575)
			(xy 217.899054 -63.567332) (xy 217.871802 -63.567818) (xy 217.844431 -63.567371) (xy 217.79025 -63.559551)
			(xy 217.737746 -63.544059) (xy 217.687999 -63.521213) (xy 217.642034 -63.491482) (xy 217.621104 -63.473838)
			(xy 217.62085 -63.473584) (xy 217.613755 -63.46801) (xy 217.596845 -63.461756) (xy 217.58783 -63.461392)
			(xy 217.520774 -63.461392) (xy 217.511756 -63.461739) (xy 217.494839 -63.467994) (xy 217.487754 -63.473584)
			(xy 217.4875 -63.473838) (xy 217.466567 -63.491479) (xy 217.420599 -63.521203) (xy 217.370853 -63.544049)
			(xy 217.318351 -63.559545) (xy 217.264173 -63.567374) (xy 217.209431 -63.567374) (xy 217.155253 -63.559545)
			(xy 217.102751 -63.544049) (xy 217.053005 -63.521203) (xy 217.007037 -63.491479) (xy 216.986104 -63.473838)
			(xy 216.98585 -63.473584) (xy 216.978755 -63.46801) (xy 216.961845 -63.461756) (xy 216.95283 -63.461392)
			(xy 216.885774 -63.461392) (xy 216.876756 -63.461739) (xy 216.859839 -63.467994) (xy 216.852754 -63.473584)
			(xy 216.852754 -63.473838) (xy 216.8525 -63.473838) (xy 216.831584 -63.491497) (xy 216.785606 -63.521205)
			(xy 216.735855 -63.544036) (xy 216.683351 -63.559523) (xy 216.629172 -63.567347) (xy 216.601802 -63.567818)
			(xy 216.57455 -63.567335) (xy 216.5206 -63.559578) (xy 216.468303 -63.544223) (xy 216.418724 -63.521581)
			(xy 216.372872 -63.492114) (xy 216.33168 -63.456421) (xy 216.295987 -63.41523) (xy 216.26652 -63.369378)
			(xy 216.243878 -63.319799) (xy 216.228522 -63.267502) (xy 216.220765 -63.213552) (xy 205.592108 -63.213552)
			(xy 203.704698 -65.100962) (xy 214.232488 -65.100962) (xy 214.236559 -65.04534) (xy 214.248685 -64.990903)
			(xy 214.268608 -64.938812) (xy 214.295904 -64.890177) (xy 214.32999 -64.846034) (xy 214.370139 -64.807325)
			(xy 214.415497 -64.774874) (xy 214.465097 -64.749373) (xy 214.517881 -64.731366) (xy 214.572724 -64.721236)
			(xy 214.628458 -64.719199) (xy 214.683895 -64.725299) (xy 214.737852 -64.739405) (xy 214.789181 -64.761217)
			(xy 214.836787 -64.790271) (xy 214.848444 -64.799972) (xy 224.632518 -64.799972) (xy 224.636589 -64.74435)
			(xy 224.648715 -64.689913) (xy 224.668638 -64.637822) (xy 224.695934 -64.589187) (xy 224.73002 -64.545044)
			(xy 224.770169 -64.506335) (xy 224.815527 -64.473884) (xy 224.865127 -64.448383) (xy 224.917911 -64.430376)
			(xy 224.972754 -64.420246) (xy 225.028488 -64.418209) (xy 225.083925 -64.424309) (xy 225.137882 -64.438415)
			(xy 225.189211 -64.460227) (xy 225.236817 -64.489281) (xy 225.279685 -64.524956) (xy 225.316902 -64.566493)
			(xy 225.347675 -64.613006) (xy 225.371347 -64.663503) (xy 225.387415 -64.71691) (xy 225.395535 -64.772086)
			(xy 225.396044 -64.799972) (xy 225.395535 -64.827858) (xy 225.387415 -64.883034) (xy 225.371347 -64.936441)
			(xy 225.347675 -64.986938) (xy 225.333238 -65.00876) (xy 240.02441 -65.00876) (xy 240.028481 -64.953138)
			(xy 240.040607 -64.898701) (xy 240.06053 -64.84661) (xy 240.087826 -64.797975) (xy 240.121912 -64.753832)
			(xy 240.162061 -64.715123) (xy 240.207419 -64.682672) (xy 240.257019 -64.657171) (xy 240.309803 -64.639164)
			(xy 240.364646 -64.629034) (xy 240.42038 -64.626997) (xy 240.475817 -64.633097) (xy 240.529774 -64.647203)
			(xy 240.581103 -64.669015) (xy 240.628709 -64.698069) (xy 240.671577 -64.733744) (xy 240.708794 -64.775281)
			(xy 240.739567 -64.821794) (xy 240.763239 -64.872291) (xy 240.779307 -64.925698) (xy 240.787427 -64.980874)
			(xy 240.787936 -65.00876) (xy 240.787427 -65.036646) (xy 240.779307 -65.091822) (xy 240.776557 -65.100962)
			(xy 252.332488 -65.100962) (xy 252.336559 -65.04534) (xy 252.348685 -64.990903) (xy 252.368608 -64.938812)
			(xy 252.395904 -64.890177) (xy 252.42999 -64.846034) (xy 252.470139 -64.807325) (xy 252.515497 -64.774874)
			(xy 252.565097 -64.749373) (xy 252.617881 -64.731366) (xy 252.672724 -64.721236) (xy 252.728458 -64.719199)
			(xy 252.783895 -64.725299) (xy 252.837852 -64.739405) (xy 252.889181 -64.761217) (xy 252.936787 -64.790271)
			(xy 252.979655 -64.825946) (xy 253.016872 -64.867483) (xy 253.047645 -64.913996) (xy 253.071317 -64.964493)
			(xy 253.087385 -65.0179) (xy 253.095505 -65.073076) (xy 253.096014 -65.100962) (xy 253.095592 -65.124076)
			(xy 264.307318 -65.124076) (xy 264.311389 -65.068454) (xy 264.323515 -65.014017) (xy 264.343438 -64.961926)
			(xy 264.370734 -64.913291) (xy 264.40482 -64.869148) (xy 264.444969 -64.830439) (xy 264.490327 -64.797988)
			(xy 264.539927 -64.772487) (xy 264.592711 -64.75448) (xy 264.647554 -64.74435) (xy 264.703288 -64.742313)
			(xy 264.758725 -64.748413) (xy 264.812682 -64.762519) (xy 264.864011 -64.784331) (xy 264.911617 -64.813385)
			(xy 264.954485 -64.84906) (xy 264.991702 -64.890597) (xy 265.022475 -64.93711) (xy 265.046147 -64.987607)
			(xy 265.062215 -65.041014) (xy 265.070335 -65.09619) (xy 265.070844 -65.124076) (xy 265.070335 -65.151962)
			(xy 265.062215 -65.207138) (xy 265.046147 -65.260545) (xy 265.022475 -65.311042) (xy 264.991702 -65.357555)
			(xy 264.954485 -65.399092) (xy 264.911617 -65.434767) (xy 264.864011 -65.463821) (xy 264.812682 -65.485633)
			(xy 264.758725 -65.499739) (xy 264.703288 -65.505839) (xy 264.647554 -65.503802) (xy 264.592711 -65.493672)
			(xy 264.539927 -65.475665) (xy 264.490327 -65.450164) (xy 264.444969 -65.417713) (xy 264.40482 -65.379004)
			(xy 264.370734 -65.334861) (xy 264.343438 -65.286226) (xy 264.323515 -65.234135) (xy 264.311389 -65.179698)
			(xy 264.307318 -65.124076) (xy 253.095592 -65.124076) (xy 253.095505 -65.128848) (xy 253.087385 -65.184024)
			(xy 253.071317 -65.237431) (xy 253.047645 -65.287928) (xy 253.016872 -65.334441) (xy 252.979655 -65.375978)
			(xy 252.936787 -65.411653) (xy 252.889181 -65.440707) (xy 252.837852 -65.462519) (xy 252.783895 -65.476625)
			(xy 252.728458 -65.482725) (xy 252.672724 -65.480688) (xy 252.617881 -65.470558) (xy 252.565097 -65.452551)
			(xy 252.515497 -65.42705) (xy 252.470139 -65.394599) (xy 252.42999 -65.35589) (xy 252.395904 -65.311747)
			(xy 252.368608 -65.263112) (xy 252.348685 -65.211021) (xy 252.336559 -65.156584) (xy 252.332488 -65.100962)
			(xy 240.776557 -65.100962) (xy 240.763239 -65.145229) (xy 240.739567 -65.195726) (xy 240.708794 -65.242239)
			(xy 240.671577 -65.283776) (xy 240.628709 -65.319451) (xy 240.581103 -65.348505) (xy 240.529774 -65.370317)
			(xy 240.475817 -65.384423) (xy 240.42038 -65.390523) (xy 240.364646 -65.388486) (xy 240.309803 -65.378356)
			(xy 240.257019 -65.360349) (xy 240.207419 -65.334848) (xy 240.162061 -65.302397) (xy 240.121912 -65.263688)
			(xy 240.087826 -65.219545) (xy 240.06053 -65.17091) (xy 240.040607 -65.118819) (xy 240.028481 -65.064382)
			(xy 240.02441 -65.00876) (xy 225.333238 -65.00876) (xy 225.316902 -65.033451) (xy 225.279685 -65.074988)
			(xy 225.236817 -65.110663) (xy 225.189211 -65.139717) (xy 225.137882 -65.161529) (xy 225.083925 -65.175635)
			(xy 225.028488 -65.181735) (xy 224.972754 -65.179698) (xy 224.917911 -65.169568) (xy 224.865127 -65.151561)
			(xy 224.815527 -65.12606) (xy 224.770169 -65.093609) (xy 224.73002 -65.0549) (xy 224.695934 -65.010757)
			(xy 224.668638 -64.962122) (xy 224.648715 -64.910031) (xy 224.636589 -64.855594) (xy 224.632518 -64.799972)
			(xy 214.848444 -64.799972) (xy 214.879655 -64.825946) (xy 214.916872 -64.867483) (xy 214.947645 -64.913996)
			(xy 214.971317 -64.964493) (xy 214.987385 -65.0179) (xy 214.995505 -65.073076) (xy 214.996014 -65.100962)
			(xy 214.995505 -65.128848) (xy 214.987385 -65.184024) (xy 214.971317 -65.237431) (xy 214.947645 -65.287928)
			(xy 214.916872 -65.334441) (xy 214.879655 -65.375978) (xy 214.850886 -65.39992) (xy 227.456998 -65.39992)
			(xy 227.461069 -65.344298) (xy 227.473195 -65.289861) (xy 227.493118 -65.23777) (xy 227.520414 -65.189135)
			(xy 227.5545 -65.144992) (xy 227.594649 -65.106283) (xy 227.640007 -65.073832) (xy 227.689607 -65.048331)
			(xy 227.742391 -65.030324) (xy 227.797234 -65.020194) (xy 227.852968 -65.018157) (xy 227.908405 -65.024257)
			(xy 227.962362 -65.038363) (xy 228.013691 -65.060175) (xy 228.061297 -65.089229) (xy 228.104165 -65.124904)
			(xy 228.141382 -65.166441) (xy 228.172155 -65.212954) (xy 228.195827 -65.263451) (xy 228.211895 -65.316858)
			(xy 228.220015 -65.372034) (xy 228.220524 -65.39992) (xy 228.220015 -65.427806) (xy 228.211895 -65.482982)
			(xy 228.195827 -65.536389) (xy 228.172155 -65.586886) (xy 228.141382 -65.633399) (xy 228.104165 -65.674936)
			(xy 228.061297 -65.710611) (xy 228.013691 -65.739665) (xy 227.97638 -65.75552) (xy 246.546622 -65.75552)
			(xy 246.550693 -65.699898) (xy 246.562819 -65.645461) (xy 246.582742 -65.59337) (xy 246.610038 -65.544735)
			(xy 246.644124 -65.500592) (xy 246.684273 -65.461883) (xy 246.729631 -65.429432) (xy 246.779231 -65.403931)
			(xy 246.832015 -65.385924) (xy 246.886858 -65.375794) (xy 246.942592 -65.373757) (xy 246.998029 -65.379857)
			(xy 247.051986 -65.393963) (xy 247.103315 -65.415775) (xy 247.150921 -65.444829) (xy 247.193789 -65.480504)
			(xy 247.231006 -65.522041) (xy 247.261779 -65.568554) (xy 247.285451 -65.619051) (xy 247.301519 -65.672458)
			(xy 247.309639 -65.727634) (xy 247.310148 -65.75552) (xy 272.54657 -65.75552) (xy 272.550641 -65.699898)
			(xy 272.562767 -65.645461) (xy 272.58269 -65.59337) (xy 272.609986 -65.544735) (xy 272.644072 -65.500592)
			(xy 272.684221 -65.461883) (xy 272.729579 -65.429432) (xy 272.779179 -65.403931) (xy 272.831963 -65.385924)
			(xy 272.886806 -65.375794) (xy 272.94254 -65.373757) (xy 272.997977 -65.379857) (xy 273.051934 -65.393963)
			(xy 273.103263 -65.415775) (xy 273.150869 -65.444829) (xy 273.193737 -65.480504) (xy 273.230954 -65.522041)
			(xy 273.261727 -65.568554) (xy 273.285399 -65.619051) (xy 273.301467 -65.672458) (xy 273.309587 -65.727634)
			(xy 273.310096 -65.75552) (xy 273.309587 -65.783406) (xy 273.301467 -65.838582) (xy 273.285399 -65.891989)
			(xy 273.261727 -65.942486) (xy 273.230954 -65.988999) (xy 273.193737 -66.030536) (xy 273.150869 -66.066211)
			(xy 273.103263 -66.095265) (xy 273.051934 -66.117077) (xy 272.997977 -66.131183) (xy 272.94254 -66.137283)
			(xy 272.886806 -66.135246) (xy 272.831963 -66.125116) (xy 272.779179 -66.107109) (xy 272.729579 -66.081608)
			(xy 272.684221 -66.049157) (xy 272.644072 -66.010448) (xy 272.609986 -65.966305) (xy 272.58269 -65.91767)
			(xy 272.562767 -65.865579) (xy 272.550641 -65.811142) (xy 272.54657 -65.75552) (xy 247.310148 -65.75552)
			(xy 247.309639 -65.783406) (xy 247.301519 -65.838582) (xy 247.285451 -65.891989) (xy 247.261779 -65.942486)
			(xy 247.231006 -65.988999) (xy 247.193789 -66.030536) (xy 247.150921 -66.066211) (xy 247.103315 -66.095265)
			(xy 247.051986 -66.117077) (xy 246.998029 -66.131183) (xy 246.942592 -66.137283) (xy 246.886858 -66.135246)
			(xy 246.832015 -66.125116) (xy 246.779231 -66.107109) (xy 246.729631 -66.081608) (xy 246.684273 -66.049157)
			(xy 246.644124 -66.010448) (xy 246.610038 -65.966305) (xy 246.582742 -65.91767) (xy 246.562819 -65.865579)
			(xy 246.550693 -65.811142) (xy 246.546622 -65.75552) (xy 227.97638 -65.75552) (xy 227.962362 -65.761477)
			(xy 227.908405 -65.775583) (xy 227.852968 -65.781683) (xy 227.797234 -65.779646) (xy 227.742391 -65.769516)
			(xy 227.689607 -65.751509) (xy 227.640007 -65.726008) (xy 227.594649 -65.693557) (xy 227.5545 -65.654848)
			(xy 227.520414 -65.610705) (xy 227.493118 -65.56207) (xy 227.473195 -65.509979) (xy 227.461069 -65.455542)
			(xy 227.456998 -65.39992) (xy 214.850886 -65.39992) (xy 214.836787 -65.411653) (xy 214.789181 -65.440707)
			(xy 214.737852 -65.462519) (xy 214.683895 -65.476625) (xy 214.628458 -65.482725) (xy 214.572724 -65.480688)
			(xy 214.517881 -65.470558) (xy 214.465097 -65.452551) (xy 214.415497 -65.42705) (xy 214.370139 -65.394599)
			(xy 214.32999 -65.35589) (xy 214.295904 -65.311747) (xy 214.268608 -65.263112) (xy 214.248685 -65.211021)
			(xy 214.236559 -65.156584) (xy 214.232488 -65.100962) (xy 203.704698 -65.100962) (xy 203.05014 -65.75552)
			(xy 208.446622 -65.75552) (xy 208.450693 -65.699898) (xy 208.462819 -65.645461) (xy 208.482742 -65.59337)
			(xy 208.510038 -65.544735) (xy 208.544124 -65.500592) (xy 208.584273 -65.461883) (xy 208.629631 -65.429432)
			(xy 208.679231 -65.403931) (xy 208.732015 -65.385924) (xy 208.786858 -65.375794) (xy 208.842592 -65.373757)
			(xy 208.898029 -65.379857) (xy 208.951986 -65.393963) (xy 209.003315 -65.415775) (xy 209.050921 -65.444829)
			(xy 209.093789 -65.480504) (xy 209.131006 -65.522041) (xy 209.161779 -65.568554) (xy 209.185451 -65.619051)
			(xy 209.201519 -65.672458) (xy 209.209639 -65.727634) (xy 209.210148 -65.75552) (xy 209.209639 -65.783406)
			(xy 209.201519 -65.838582) (xy 209.185451 -65.891989) (xy 209.161779 -65.942486) (xy 209.131006 -65.988999)
			(xy 209.093789 -66.030536) (xy 209.050921 -66.066211) (xy 209.003315 -66.095265) (xy 208.951986 -66.117077)
			(xy 208.898029 -66.131183) (xy 208.842592 -66.137283) (xy 208.786858 -66.135246) (xy 208.732015 -66.125116)
			(xy 208.679231 -66.107109) (xy 208.629631 -66.081608) (xy 208.584273 -66.049157) (xy 208.544124 -66.010448)
			(xy 208.510038 -65.966305) (xy 208.482742 -65.91767) (xy 208.462819 -65.865579) (xy 208.450693 -65.811142)
			(xy 208.446622 -65.75552) (xy 203.05014 -65.75552) (xy 202.54722 -66.25844) (xy 226.308918 -66.25844)
			(xy 226.312989 -66.202818) (xy 226.325115 -66.148381) (xy 226.345038 -66.09629) (xy 226.372334 -66.047655)
			(xy 226.40642 -66.003512) (xy 226.446569 -65.964803) (xy 226.491927 -65.932352) (xy 226.541527 -65.906851)
			(xy 226.594311 -65.888844) (xy 226.649154 -65.878714) (xy 226.704888 -65.876677) (xy 226.760325 -65.882777)
			(xy 226.814282 -65.896883) (xy 226.865611 -65.918695) (xy 226.913217 -65.947749) (xy 226.956085 -65.983424)
			(xy 226.993302 -66.024961) (xy 227.024075 -66.071474) (xy 227.047747 -66.121971) (xy 227.063815 -66.175378)
			(xy 227.071935 -66.230554) (xy 227.072444 -66.25844) (xy 227.071935 -66.286326) (xy 227.063815 -66.341502)
			(xy 227.047747 -66.394909) (xy 227.024075 -66.445406) (xy 226.993302 -66.491919) (xy 226.956085 -66.533456)
			(xy 226.913217 -66.569131) (xy 226.865611 -66.598185) (xy 226.861175 -66.60007) (xy 231.00614 -66.60007)
			(xy 231.010211 -66.544448) (xy 231.022337 -66.490011) (xy 231.04226 -66.43792) (xy 231.069556 -66.389285)
			(xy 231.103642 -66.345142) (xy 231.143791 -66.306433) (xy 231.189149 -66.273982) (xy 231.238749 -66.248481)
			(xy 231.291533 -66.230474) (xy 231.346376 -66.220344) (xy 231.40211 -66.218307) (xy 231.457547 -66.224407)
			(xy 231.511504 -66.238513) (xy 231.562833 -66.260325) (xy 231.610439 -66.289379) (xy 231.653307 -66.325054)
			(xy 231.690524 -66.366591) (xy 231.721297 -66.413104) (xy 231.744969 -66.463601) (xy 231.761037 -66.517008)
			(xy 231.769157 -66.572184) (xy 231.769666 -66.60007) (xy 231.769157 -66.627956) (xy 231.761037 -66.683132)
			(xy 231.744969 -66.736539) (xy 231.721297 -66.787036) (xy 231.690524 -66.833549) (xy 231.653307 -66.875086)
			(xy 231.610439 -66.910761) (xy 231.562833 -66.939815) (xy 231.511504 -66.961627) (xy 231.457547 -66.975733)
			(xy 231.40211 -66.981833) (xy 231.346376 -66.979796) (xy 231.291533 -66.969666) (xy 231.238749 -66.951659)
			(xy 231.189149 -66.926158) (xy 231.143791 -66.893707) (xy 231.103642 -66.854998) (xy 231.069556 -66.810855)
			(xy 231.04226 -66.76222) (xy 231.022337 -66.710129) (xy 231.010211 -66.655692) (xy 231.00614 -66.60007)
			(xy 226.861175 -66.60007) (xy 226.814282 -66.619997) (xy 226.760325 -66.634103) (xy 226.704888 -66.640203)
			(xy 226.649154 -66.638166) (xy 226.594311 -66.628036) (xy 226.541527 -66.610029) (xy 226.491927 -66.584528)
			(xy 226.446569 -66.552077) (xy 226.40642 -66.513368) (xy 226.372334 -66.469225) (xy 226.345038 -66.42059)
			(xy 226.325115 -66.368499) (xy 226.312989 -66.314062) (xy 226.308918 -66.25844) (xy 202.54722 -66.25844)
			(xy 201.676711 -67.128949) (xy 208.466698 -67.128949) (xy 208.466698 -67.074451) (xy 208.474454 -67.020507)
			(xy 208.489808 -66.968216) (xy 208.512447 -66.918642) (xy 208.541911 -66.872794) (xy 208.577599 -66.831606)
			(xy 208.618786 -66.795917) (xy 208.664633 -66.766452) (xy 208.714206 -66.743811) (xy 208.766497 -66.728456)
			(xy 208.820441 -66.720699) (xy 208.84769 -66.720212) (xy 208.87506 -66.720681) (xy 208.929239 -66.728498)
			(xy 208.981742 -66.743986) (xy 209.031489 -66.766827) (xy 209.077456 -66.796551) (xy 209.098388 -66.814192)
			(xy 209.098642 -66.814446) (xy 209.105737 -66.82002) (xy 209.122647 -66.826273) (xy 209.131662 -66.826638)
			(xy 209.198718 -66.826638) (xy 209.207735 -66.826282) (xy 209.224651 -66.820033) (xy 209.231738 -66.814446)
			(xy 209.231738 -66.814192) (xy 209.231992 -66.814192) (xy 209.252915 -66.796542) (xy 209.298891 -66.766832)
			(xy 209.34864 -66.743998) (xy 209.401143 -66.72851) (xy 209.45532 -66.720684) (xy 209.48269 -66.720212)
			(xy 209.509945 -66.720634) (xy 209.522912 -66.722498) (xy 223.929954 -66.722498) (xy 223.934025 -66.666876)
			(xy 223.946151 -66.612439) (xy 223.966074 -66.560348) (xy 223.99337 -66.511713) (xy 224.027456 -66.46757)
			(xy 224.067605 -66.428861) (xy 224.112963 -66.39641) (xy 224.162563 -66.370909) (xy 224.215347 -66.352902)
			(xy 224.27019 -66.342772) (xy 224.325924 -66.340735) (xy 224.381361 -66.346835) (xy 224.435318 -66.360941)
			(xy 224.486647 -66.382753) (xy 224.534253 -66.411807) (xy 224.577121 -66.447482) (xy 224.614338 -66.489019)
			(xy 224.645111 -66.535532) (xy 224.668783 -66.586029) (xy 224.684851 -66.639436) (xy 224.692971 -66.694612)
			(xy 224.69348 -66.722498) (xy 224.692971 -66.750384) (xy 224.684851 -66.80556) (xy 224.668783 -66.858967)
			(xy 224.645111 -66.909464) (xy 224.614338 -66.955977) (xy 224.577121 -66.997514) (xy 224.534253 -67.033189)
			(xy 224.486647 -67.062243) (xy 224.435318 -67.084055) (xy 224.381361 -67.098161) (xy 224.325924 -67.104261)
			(xy 224.27019 -67.102224) (xy 224.215347 -67.092094) (xy 224.162563 -67.074087) (xy 224.112963 -67.048586)
			(xy 224.067605 -67.016135) (xy 224.027456 -66.977426) (xy 223.99337 -66.933283) (xy 223.966074 -66.884648)
			(xy 223.946151 -66.832557) (xy 223.934025 -66.77812) (xy 223.929954 -66.722498) (xy 209.522912 -66.722498)
			(xy 209.5639 -66.72839) (xy 209.616202 -66.743746) (xy 209.665786 -66.76639) (xy 209.711642 -66.795859)
			(xy 209.752838 -66.831554) (xy 209.788535 -66.87275) (xy 209.818006 -66.918606) (xy 209.84065 -66.968189)
			(xy 209.856007 -67.020491) (xy 209.863765 -67.074445) (xy 209.863765 -67.128955) (xy 209.856007 -67.182909)
			(xy 209.84065 -67.235211) (xy 209.818006 -67.284794) (xy 209.788535 -67.33065) (xy 209.752838 -67.371846)
			(xy 209.711642 -67.407541) (xy 209.665786 -67.43701) (xy 209.616202 -67.459654) (xy 209.5639 -67.47501)
			(xy 209.509945 -67.482766) (xy 209.48269 -67.483228) (xy 209.455319 -67.482785) (xy 209.401138 -67.474965)
			(xy 209.348634 -67.459471) (xy 209.298887 -67.436624) (xy 209.252922 -67.406893) (xy 209.231992 -67.389248)
			(xy 209.231738 -67.388994) (xy 209.224645 -67.383417) (xy 209.207733 -67.377165) (xy 209.198718 -67.376802)
			(xy 209.131662 -67.376802) (xy 209.122643 -67.377141) (xy 209.105726 -67.383401) (xy 209.098642 -67.388994)
			(xy 209.098642 -67.389248) (xy 209.098388 -67.389248) (xy 209.077427 -67.406851) (xy 209.031463 -67.43657)
			(xy 208.981723 -67.459414) (xy 208.929228 -67.474913) (xy 208.875057 -67.48275) (xy 208.84769 -67.483228)
			(xy 208.820441 -67.482701) (xy 208.766497 -67.474944) (xy 208.714206 -67.459589) (xy 208.664633 -67.436948)
			(xy 208.618786 -67.407483) (xy 208.577599 -67.371794) (xy 208.541911 -67.330606) (xy 208.512447 -67.284758)
			(xy 208.489808 -67.235184) (xy 208.474454 -67.182893) (xy 208.466698 -67.128949) (xy 201.676711 -67.128949)
			(xy 201.317606 -67.488054) (xy 212.879176 -67.488054) (xy 212.883247 -67.432432) (xy 212.895373 -67.377995)
			(xy 212.915296 -67.325904) (xy 212.942592 -67.277269) (xy 212.976678 -67.233126) (xy 213.016827 -67.194417)
			(xy 213.062185 -67.161966) (xy 213.111785 -67.136465) (xy 213.164569 -67.118458) (xy 213.219412 -67.108328)
			(xy 213.275146 -67.106291) (xy 213.330583 -67.112391) (xy 213.38454 -67.126497) (xy 213.435869 -67.148309)
			(xy 213.483475 -67.177363) (xy 213.526343 -67.213038) (xy 213.56356 -67.254575) (xy 213.594333 -67.301088)
			(xy 213.618005 -67.351585) (xy 213.634073 -67.404992) (xy 213.642193 -67.460168) (xy 213.642702 -67.488054)
			(xy 213.642193 -67.51594) (xy 213.639008 -67.537584) (xy 214.171274 -67.537584) (xy 214.175345 -67.481962)
			(xy 214.187471 -67.427525) (xy 214.207394 -67.375434) (xy 214.23469 -67.326799) (xy 214.268776 -67.282656)
			(xy 214.308925 -67.243947) (xy 214.354283 -67.211496) (xy 214.403883 -67.185995) (xy 214.456667 -67.167988)
			(xy 214.51151 -67.157858) (xy 214.567244 -67.155821) (xy 214.622681 -67.161921) (xy 214.676638 -67.176027)
			(xy 214.727967 -67.197839) (xy 214.775573 -67.226893) (xy 214.818441 -67.262568) (xy 214.855658 -67.304105)
			(xy 214.886431 -67.350618) (xy 214.910103 -67.401115) (xy 214.926171 -67.454522) (xy 214.934291 -67.509698)
			(xy 214.9348 -67.537584) (xy 214.934291 -67.56547) (xy 214.930246 -67.592956) (xy 215.445338 -67.592956)
			(xy 215.449409 -67.537334) (xy 215.461535 -67.482897) (xy 215.481458 -67.430806) (xy 215.508754 -67.382171)
			(xy 215.54284 -67.338028) (xy 215.582989 -67.299319) (xy 215.628347 -67.266868) (xy 215.677947 -67.241367)
			(xy 215.730731 -67.22336) (xy 215.785574 -67.21323) (xy 215.841308 -67.211193) (xy 215.896745 -67.217293)
			(xy 215.950702 -67.231399) (xy 216.002031 -67.253211) (xy 216.049637 -67.282265) (xy 216.092505 -67.31794)
			(xy 216.129722 -67.359477) (xy 216.160495 -67.40599) (xy 216.184167 -67.456487) (xy 216.200235 -67.509894)
			(xy 216.208352 -67.565048) (xy 218.546716 -67.565048) (xy 218.546716 -67.510552) (xy 218.554471 -67.456612)
			(xy 218.569824 -67.404324) (xy 218.592461 -67.354753) (xy 218.621923 -67.308908) (xy 218.657609 -67.267723)
			(xy 218.698792 -67.232035) (xy 218.744636 -67.202571) (xy 218.794205 -67.179931) (xy 218.846492 -67.164576)
			(xy 218.900432 -67.156818) (xy 218.92768 -67.15633) (xy 218.95505 -67.1568) (xy 219.009229 -67.164616)
			(xy 219.061733 -67.180104) (xy 219.11148 -67.202945) (xy 219.157446 -67.232669) (xy 219.178378 -67.25031)
			(xy 219.178632 -67.250564) (xy 219.185728 -67.256136) (xy 219.202638 -67.26239) (xy 219.211652 -67.262756)
			(xy 219.278708 -67.262756) (xy 219.287726 -67.262412) (xy 219.304644 -67.256156) (xy 219.311728 -67.250564)
			(xy 219.311728 -67.25031) (xy 219.311982 -67.25031) (xy 219.332911 -67.232667) (xy 219.378885 -67.202956)
			(xy 219.428633 -67.18012) (xy 219.481134 -67.16463) (xy 219.535311 -67.156803) (xy 219.56268 -67.15633)
			(xy 219.589937 -67.156716) (xy 219.643895 -67.164471) (xy 219.696201 -67.179827) (xy 219.745788 -67.20247)
			(xy 219.791648 -67.231941) (xy 219.832848 -67.267638) (xy 219.868547 -67.308836) (xy 219.89802 -67.354694)
			(xy 219.904985 -67.369944) (xy 226.983542 -67.369944) (xy 226.987613 -67.314322) (xy 226.999739 -67.259885)
			(xy 227.019662 -67.207794) (xy 227.046958 -67.159159) (xy 227.081044 -67.115016) (xy 227.121193 -67.076307)
			(xy 227.166551 -67.043856) (xy 227.216151 -67.018355) (xy 227.268935 -67.000348) (xy 227.323778 -66.990218)
			(xy 227.379512 -66.988181) (xy 227.434949 -66.994281) (xy 227.488906 -67.008387) (xy 227.540235 -67.030199)
			(xy 227.587841 -67.059253) (xy 227.630709 -67.094928) (xy 227.667926 -67.136465) (xy 227.698699 -67.182978)
			(xy 227.706687 -67.200018) (xy 233.19054 -67.200018) (xy 233.194611 -67.144396) (xy 233.206737 -67.089959)
			(xy 233.22666 -67.037868) (xy 233.253956 -66.989233) (xy 233.288042 -66.94509) (xy 233.328191 -66.906381)
			(xy 233.373549 -66.87393) (xy 233.423149 -66.848429) (xy 233.475933 -66.830422) (xy 233.530776 -66.820292)
			(xy 233.58651 -66.818255) (xy 233.641947 -66.824355) (xy 233.695904 -66.838461) (xy 233.747233 -66.860273)
			(xy 233.794839 -66.889327) (xy 233.837707 -66.925002) (xy 233.874924 -66.966539) (xy 233.905697 -67.013052)
			(xy 233.929369 -67.063549) (xy 233.940503 -67.100555) (xy 246.218627 -67.100555) (xy 246.218627 -67.046045)
			(xy 246.226385 -66.992089) (xy 246.241742 -66.939786) (xy 246.264387 -66.890202) (xy 246.293858 -66.844345)
			(xy 246.329556 -66.803149) (xy 246.370753 -66.767452) (xy 246.416611 -66.737983) (xy 246.466196 -66.715339)
			(xy 246.518499 -66.699983) (xy 246.572455 -66.692226) (xy 246.59971 -66.691764) (xy 246.627081 -66.692209)
			(xy 246.681262 -66.700029) (xy 246.733766 -66.715522) (xy 246.783512 -66.738369) (xy 246.829478 -66.7681)
			(xy 246.850408 -66.785744) (xy 246.850662 -66.785998) (xy 246.857755 -66.791575) (xy 246.874667 -66.797827)
			(xy 246.883682 -66.79819) (xy 246.950738 -66.79819) (xy 246.959757 -66.797853) (xy 246.976674 -66.791592)
			(xy 246.983758 -66.785998) (xy 246.983758 -66.785744) (xy 246.984012 -66.785744) (xy 247.004972 -66.76814)
			(xy 247.050937 -66.738421) (xy 247.100677 -66.715578) (xy 247.153172 -66.700079) (xy 247.207343 -66.692242)
			(xy 247.23471 -66.691764) (xy 247.261959 -66.692307) (xy 247.315901 -66.700064) (xy 247.368191 -66.715419)
			(xy 247.417763 -66.738059) (xy 247.463609 -66.767523) (xy 247.504795 -66.803212) (xy 247.540483 -66.844399)
			(xy 247.569946 -66.890245) (xy 247.592585 -66.939818) (xy 247.607938 -66.992108) (xy 247.615694 -67.046051)
			(xy 247.615694 -67.100549) (xy 247.607938 -67.154492) (xy 247.592585 -67.206782) (xy 247.569946 -67.256355)
			(xy 247.540483 -67.302201) (xy 247.504795 -67.343388) (xy 247.463609 -67.379077) (xy 247.417763 -67.408541)
			(xy 247.368191 -67.431181) (xy 247.315901 -67.446536) (xy 247.261959 -67.454293) (xy 247.23471 -67.45478)
			(xy 247.20734 -67.454313) (xy 247.153161 -67.446496) (xy 247.100657 -67.431008) (xy 247.05091 -67.408166)
			(xy 247.004944 -67.378441) (xy 246.984012 -67.3608) (xy 246.983758 -67.360546) (xy 246.976664 -67.354971)
			(xy 246.959753 -67.348719) (xy 246.950738 -67.348354) (xy 246.883682 -67.348354) (xy 246.874663 -67.348691)
			(xy 246.857746 -67.354951) (xy 246.850662 -67.360546) (xy 246.850662 -67.3608) (xy 246.850408 -67.3608)
			(xy 246.829484 -67.378449) (xy 246.783509 -67.408159) (xy 246.733759 -67.430993) (xy 246.681257 -67.446482)
			(xy 246.62708 -67.454307) (xy 246.59971 -67.45478) (xy 246.572455 -67.454374) (xy 246.518499 -67.446617)
			(xy 246.466196 -67.431261) (xy 246.416611 -67.408617) (xy 246.370753 -67.379148) (xy 246.329556 -67.343451)
			(xy 246.293858 -67.302255) (xy 246.264387 -67.256398) (xy 246.241742 -67.206814) (xy 246.226385 -67.154511)
			(xy 246.218627 -67.100555) (xy 233.940503 -67.100555) (xy 233.945437 -67.116956) (xy 233.953557 -67.172132)
			(xy 233.954066 -67.200018) (xy 233.953557 -67.227904) (xy 233.945437 -67.28308) (xy 233.929369 -67.336487)
			(xy 233.905697 -67.386984) (xy 233.874924 -67.433497) (xy 233.837707 -67.475034) (xy 233.822062 -67.488054)
			(xy 250.979176 -67.488054) (xy 250.983247 -67.432432) (xy 250.995373 -67.377995) (xy 251.015296 -67.325904)
			(xy 251.042592 -67.277269) (xy 251.076678 -67.233126) (xy 251.116827 -67.194417) (xy 251.162185 -67.161966)
			(xy 251.211785 -67.136465) (xy 251.264569 -67.118458) (xy 251.319412 -67.108328) (xy 251.375146 -67.106291)
			(xy 251.430583 -67.112391) (xy 251.48454 -67.126497) (xy 251.49032 -67.128953) (xy 272.566575 -67.128953)
			(xy 272.566575 -67.074447) (xy 272.574333 -67.020495) (xy 272.58969 -66.968197) (xy 272.612334 -66.918617)
			(xy 272.641804 -66.872765) (xy 272.6775 -66.831573) (xy 272.718695 -66.795881) (xy 272.764551 -66.766416)
			(xy 272.814133 -66.743777) (xy 272.866433 -66.728425) (xy 272.920385 -66.720673) (xy 272.947638 -66.720212)
			(xy 272.975007 -66.720711) (xy 273.029185 -66.728521) (xy 273.081688 -66.744002) (xy 273.131435 -66.766836)
			(xy 273.177403 -66.796554) (xy 273.198336 -66.814192) (xy 273.19859 -66.814446) (xy 273.205671 -66.82004)
			(xy 273.222592 -66.826281) (xy 273.23161 -66.826638) (xy 273.298666 -66.826638) (xy 273.30768 -66.826256)
			(xy 273.324597 -66.820025) (xy 273.331686 -66.814446) (xy 273.331686 -66.814192) (xy 273.33194 -66.814192)
			(xy 273.352883 -66.796566) (xy 273.398853 -66.766853) (xy 273.448598 -66.744014) (xy 273.501096 -66.72852)
			(xy 273.55527 -66.720688) (xy 273.582638 -66.720212) (xy 273.609889 -66.72066) (xy 273.663835 -66.728422)
			(xy 273.716128 -66.743781) (xy 273.765703 -66.766425) (xy 273.811551 -66.795894) (xy 273.852739 -66.831588)
			(xy 273.888428 -66.872779) (xy 273.917893 -66.91863) (xy 273.940532 -66.968207) (xy 273.955886 -67.020502)
			(xy 273.963642 -67.074449) (xy 273.963642 -67.128951) (xy 273.955886 -67.182898) (xy 273.940532 -67.235193)
			(xy 273.917893 -67.28477) (xy 273.888428 -67.330621) (xy 273.852739 -67.371812) (xy 273.811551 -67.407506)
			(xy 273.765703 -67.436975) (xy 273.716128 -67.459619) (xy 273.663835 -67.474978) (xy 273.609889 -67.48274)
			(xy 273.582638 -67.483228) (xy 273.555268 -67.482757) (xy 273.501088 -67.474943) (xy 273.448584 -67.459456)
			(xy 273.398837 -67.436615) (xy 273.352871 -67.40689) (xy 273.33194 -67.389248) (xy 273.331686 -67.388994)
			(xy 273.324608 -67.383395) (xy 273.307685 -67.377156) (xy 273.298666 -67.376802) (xy 273.23161 -67.376802)
			(xy 273.222594 -67.377163) (xy 273.205677 -67.383408) (xy 273.19859 -67.388994) (xy 273.19859 -67.389248)
			(xy 273.198336 -67.389248) (xy 273.177395 -67.406876) (xy 273.131425 -67.436591) (xy 273.08168 -67.45943)
			(xy 273.029181 -67.474924) (xy 272.975007 -67.482753) (xy 272.947638 -67.483228) (xy 272.920385 -67.482727)
			(xy 272.866433 -67.474975) (xy 272.814133 -67.459623) (xy 272.764551 -67.436984) (xy 272.718695 -67.407519)
			(xy 272.6775 -67.371827) (xy 272.641804 -67.330635) (xy 272.612334 -67.284783) (xy 272.58969 -67.235203)
			(xy 272.574333 -67.182905) (xy 272.566575 -67.128953) (xy 251.49032 -67.128953) (xy 251.535869 -67.148309)
			(xy 251.583475 -67.177363) (xy 251.626343 -67.213038) (xy 251.66356 -67.254575) (xy 251.694333 -67.301088)
			(xy 251.718005 -67.351585) (xy 251.734073 -67.404992) (xy 251.742193 -67.460168) (xy 251.742702 -67.488054)
			(xy 251.742193 -67.51594) (xy 251.739008 -67.537584) (xy 252.271274 -67.537584) (xy 252.275345 -67.481962)
			(xy 252.287471 -67.427525) (xy 252.307394 -67.375434) (xy 252.33469 -67.326799) (xy 252.368776 -67.282656)
			(xy 252.408925 -67.243947) (xy 252.454283 -67.211496) (xy 252.503883 -67.185995) (xy 252.556667 -67.167988)
			(xy 252.61151 -67.157858) (xy 252.667244 -67.155821) (xy 252.722681 -67.161921) (xy 252.776638 -67.176027)
			(xy 252.827967 -67.197839) (xy 252.875573 -67.226893) (xy 252.918441 -67.262568) (xy 252.955658 -67.304105)
			(xy 252.986431 -67.350618) (xy 253.010103 -67.401115) (xy 253.026171 -67.454522) (xy 253.034291 -67.509698)
			(xy 253.0348 -67.537584) (xy 253.034291 -67.56547) (xy 253.030246 -67.592956) (xy 253.545338 -67.592956)
			(xy 253.549409 -67.537334) (xy 253.561535 -67.482897) (xy 253.581458 -67.430806) (xy 253.608754 -67.382171)
			(xy 253.64284 -67.338028) (xy 253.682989 -67.299319) (xy 253.728347 -67.266868) (xy 253.777947 -67.241367)
			(xy 253.830731 -67.22336) (xy 253.885574 -67.21323) (xy 253.941308 -67.211193) (xy 253.996745 -67.217293)
			(xy 254.050702 -67.231399) (xy 254.102031 -67.253211) (xy 254.149637 -67.282265) (xy 254.192505 -67.31794)
			(xy 254.229722 -67.359477) (xy 254.260495 -67.40599) (xy 254.284167 -67.456487) (xy 254.300235 -67.509894)
			(xy 254.308352 -67.565048) (xy 256.646716 -67.565048) (xy 256.646716 -67.510552) (xy 256.654471 -67.456612)
			(xy 256.669824 -67.404324) (xy 256.692461 -67.354753) (xy 256.721923 -67.308908) (xy 256.757609 -67.267723)
			(xy 256.798792 -67.232035) (xy 256.844636 -67.202571) (xy 256.894205 -67.179931) (xy 256.946492 -67.164576)
			(xy 257.000432 -67.156818) (xy 257.02768 -67.15633) (xy 257.05505 -67.1568) (xy 257.109229 -67.164616)
			(xy 257.161733 -67.180104) (xy 257.21148 -67.202945) (xy 257.257446 -67.232669) (xy 257.278378 -67.25031)
			(xy 257.278632 -67.250564) (xy 257.285728 -67.256136) (xy 257.302638 -67.26239) (xy 257.311652 -67.262756)
			(xy 257.378708 -67.262756) (xy 257.387726 -67.262412) (xy 257.404644 -67.256156) (xy 257.411728 -67.250564)
			(xy 257.411728 -67.25031) (xy 257.411982 -67.25031) (xy 257.432911 -67.232667) (xy 257.478885 -67.202956)
			(xy 257.528633 -67.18012) (xy 257.581134 -67.16463) (xy 257.635311 -67.156803) (xy 257.66268 -67.15633)
			(xy 257.689937 -67.156716) (xy 257.743895 -67.164471) (xy 257.796201 -67.179827) (xy 257.845788 -67.20247)
			(xy 257.891648 -67.231941) (xy 257.932848 -67.267638) (xy 257.968547 -67.308836) (xy 257.99802 -67.354694)
			(xy 258.020666 -67.404281) (xy 258.036025 -67.456585) (xy 258.043783 -67.510543) (xy 258.043783 -67.565057)
			(xy 258.036025 -67.619015) (xy 258.020666 -67.671319) (xy 257.99802 -67.720906) (xy 257.968547 -67.766764)
			(xy 257.932848 -67.807962) (xy 257.891648 -67.843659) (xy 257.845788 -67.87313) (xy 257.796201 -67.895773)
			(xy 257.743895 -67.911129) (xy 257.689937 -67.918884) (xy 257.66268 -67.919346) (xy 257.635309 -67.918905)
			(xy 257.581128 -67.911083) (xy 257.528624 -67.895589) (xy 257.478878 -67.872741) (xy 257.432912 -67.84301)
			(xy 257.411982 -67.825366) (xy 257.411728 -67.825112) (xy 257.404637 -67.819532) (xy 257.387724 -67.813281)
			(xy 257.378708 -67.81292) (xy 257.311652 -67.81292) (xy 257.302637 -67.813298) (xy 257.28572 -67.81953)
			(xy 257.278632 -67.825112) (xy 257.278632 -67.825366) (xy 257.278378 -67.825366) (xy 257.257423 -67.842977)
			(xy 257.211457 -67.872694) (xy 257.161715 -67.895536) (xy 257.10922 -67.911034) (xy 257.055048 -67.918869)
			(xy 257.02768 -67.919346) (xy 257.000432 -67.918782) (xy 256.946492 -67.911024) (xy 256.894205 -67.895669)
			(xy 256.844636 -67.873029) (xy 256.798792 -67.843565) (xy 256.757609 -67.807877) (xy 256.721923 -67.766692)
			(xy 256.692461 -67.720847) (xy 256.669824 -67.671276) (xy 256.654471 -67.618988) (xy 256.646716 -67.565048)
			(xy 254.308352 -67.565048) (xy 254.308355 -67.56507) (xy 254.308864 -67.592956) (xy 254.308355 -67.620842)
			(xy 254.300235 -67.676018) (xy 254.284167 -67.729425) (xy 254.260495 -67.779922) (xy 254.229722 -67.826435)
			(xy 254.192505 -67.867972) (xy 254.149637 -67.903647) (xy 254.102031 -67.932701) (xy 254.050702 -67.954513)
			(xy 253.996745 -67.968619) (xy 253.941308 -67.974719) (xy 253.885574 -67.972682) (xy 253.830731 -67.962552)
			(xy 253.777947 -67.944545) (xy 253.728347 -67.919044) (xy 253.682989 -67.886593) (xy 253.64284 -67.847884)
			(xy 253.608754 -67.803741) (xy 253.581458 -67.755106) (xy 253.561535 -67.703015) (xy 253.549409 -67.648578)
			(xy 253.545338 -67.592956) (xy 253.030246 -67.592956) (xy 253.026171 -67.620646) (xy 253.010103 -67.674053)
			(xy 252.986431 -67.72455) (xy 252.955658 -67.771063) (xy 252.918441 -67.8126) (xy 252.875573 -67.848275)
			(xy 252.827967 -67.877329) (xy 252.776638 -67.899141) (xy 252.722681 -67.913247) (xy 252.667244 -67.919347)
			(xy 252.61151 -67.91731) (xy 252.556667 -67.90718) (xy 252.503883 -67.889173) (xy 252.454283 -67.863672)
			(xy 252.408925 -67.831221) (xy 252.368776 -67.792512) (xy 252.33469 -67.748369) (xy 252.307394 -67.699734)
			(xy 252.287471 -67.647643) (xy 252.275345 -67.593206) (xy 252.271274 -67.537584) (xy 251.739008 -67.537584)
			(xy 251.734073 -67.571116) (xy 251.718005 -67.624523) (xy 251.694333 -67.67502) (xy 251.66356 -67.721533)
			(xy 251.626343 -67.76307) (xy 251.583475 -67.798745) (xy 251.535869 -67.827799) (xy 251.48454 -67.849611)
			(xy 251.430583 -67.863717) (xy 251.375146 -67.869817) (xy 251.319412 -67.86778) (xy 251.264569 -67.85765)
			(xy 251.211785 -67.839643) (xy 251.162185 -67.814142) (xy 251.116827 -67.781691) (xy 251.076678 -67.742982)
			(xy 251.042592 -67.698839) (xy 251.015296 -67.650204) (xy 250.995373 -67.598113) (xy 250.983247 -67.543676)
			(xy 250.979176 -67.488054) (xy 233.822062 -67.488054) (xy 233.794839 -67.510709) (xy 233.747233 -67.539763)
			(xy 233.695904 -67.561575) (xy 233.641947 -67.575681) (xy 233.58651 -67.581781) (xy 233.530776 -67.579744)
			(xy 233.475933 -67.569614) (xy 233.423149 -67.551607) (xy 233.373549 -67.526106) (xy 233.328191 -67.493655)
			(xy 233.288042 -67.454946) (xy 233.253956 -67.410803) (xy 233.22666 -67.362168) (xy 233.206737 -67.310077)
			(xy 233.194611 -67.25564) (xy 233.19054 -67.200018) (xy 227.706687 -67.200018) (xy 227.722371 -67.233475)
			(xy 227.738439 -67.286882) (xy 227.746559 -67.342058) (xy 227.747068 -67.369944) (xy 227.746559 -67.39783)
			(xy 227.738439 -67.453006) (xy 227.722371 -67.506413) (xy 227.698699 -67.55691) (xy 227.667926 -67.603423)
			(xy 227.630709 -67.64496) (xy 227.587841 -67.680635) (xy 227.540235 -67.709689) (xy 227.488906 -67.731501)
			(xy 227.434949 -67.745607) (xy 227.379512 -67.751707) (xy 227.323778 -67.74967) (xy 227.268935 -67.73954)
			(xy 227.216151 -67.721533) (xy 227.166551 -67.696032) (xy 227.121193 -67.663581) (xy 227.081044 -67.624872)
			(xy 227.046958 -67.580729) (xy 227.019662 -67.532094) (xy 226.999739 -67.480003) (xy 226.987613 -67.425566)
			(xy 226.983542 -67.369944) (xy 219.904985 -67.369944) (xy 219.920666 -67.404281) (xy 219.936025 -67.456585)
			(xy 219.943783 -67.510543) (xy 219.943783 -67.565057) (xy 219.936025 -67.619015) (xy 219.920666 -67.671319)
			(xy 219.89802 -67.720906) (xy 219.868547 -67.766764) (xy 219.832848 -67.807962) (xy 219.791648 -67.843659)
			(xy 219.745788 -67.87313) (xy 219.696201 -67.895773) (xy 219.643895 -67.911129) (xy 219.589937 -67.918884)
			(xy 219.56268 -67.919346) (xy 219.535309 -67.918905) (xy 219.481128 -67.911083) (xy 219.428624 -67.895589)
			(xy 219.378878 -67.872741) (xy 219.332912 -67.84301) (xy 219.311982 -67.825366) (xy 219.311728 -67.825112)
			(xy 219.304637 -67.819532) (xy 219.287724 -67.813281) (xy 219.278708 -67.81292) (xy 219.211652 -67.81292)
			(xy 219.202637 -67.813298) (xy 219.18572 -67.81953) (xy 219.178632 -67.825112) (xy 219.178632 -67.825366)
			(xy 219.178378 -67.825366) (xy 219.157423 -67.842977) (xy 219.111457 -67.872694) (xy 219.061715 -67.895536)
			(xy 219.00922 -67.911034) (xy 218.955048 -67.918869) (xy 218.92768 -67.919346) (xy 218.900432 -67.918782)
			(xy 218.846492 -67.911024) (xy 218.794205 -67.895669) (xy 218.744636 -67.873029) (xy 218.698792 -67.843565)
			(xy 218.657609 -67.807877) (xy 218.621923 -67.766692) (xy 218.592461 -67.720847) (xy 218.569824 -67.671276)
			(xy 218.554471 -67.618988) (xy 218.546716 -67.565048) (xy 216.208352 -67.565048) (xy 216.208355 -67.56507)
			(xy 216.208864 -67.592956) (xy 216.208355 -67.620842) (xy 216.200235 -67.676018) (xy 216.184167 -67.729425)
			(xy 216.160495 -67.779922) (xy 216.129722 -67.826435) (xy 216.092505 -67.867972) (xy 216.049637 -67.903647)
			(xy 216.002031 -67.932701) (xy 215.950702 -67.954513) (xy 215.896745 -67.968619) (xy 215.841308 -67.974719)
			(xy 215.785574 -67.972682) (xy 215.730731 -67.962552) (xy 215.677947 -67.944545) (xy 215.628347 -67.919044)
			(xy 215.582989 -67.886593) (xy 215.54284 -67.847884) (xy 215.508754 -67.803741) (xy 215.481458 -67.755106)
			(xy 215.461535 -67.703015) (xy 215.449409 -67.648578) (xy 215.445338 -67.592956) (xy 214.930246 -67.592956)
			(xy 214.926171 -67.620646) (xy 214.910103 -67.674053) (xy 214.886431 -67.72455) (xy 214.855658 -67.771063)
			(xy 214.818441 -67.8126) (xy 214.775573 -67.848275) (xy 214.727967 -67.877329) (xy 214.676638 -67.899141)
			(xy 214.622681 -67.913247) (xy 214.567244 -67.919347) (xy 214.51151 -67.91731) (xy 214.456667 -67.90718)
			(xy 214.403883 -67.889173) (xy 214.354283 -67.863672) (xy 214.308925 -67.831221) (xy 214.268776 -67.792512)
			(xy 214.23469 -67.748369) (xy 214.207394 -67.699734) (xy 214.187471 -67.647643) (xy 214.175345 -67.593206)
			(xy 214.171274 -67.537584) (xy 213.639008 -67.537584) (xy 213.634073 -67.571116) (xy 213.618005 -67.624523)
			(xy 213.594333 -67.67502) (xy 213.56356 -67.721533) (xy 213.526343 -67.76307) (xy 213.483475 -67.798745)
			(xy 213.435869 -67.827799) (xy 213.38454 -67.849611) (xy 213.330583 -67.863717) (xy 213.275146 -67.869817)
			(xy 213.219412 -67.86778) (xy 213.164569 -67.85765) (xy 213.111785 -67.839643) (xy 213.062185 -67.814142)
			(xy 213.016827 -67.781691) (xy 212.976678 -67.742982) (xy 212.942592 -67.698839) (xy 212.915296 -67.650204)
			(xy 212.895373 -67.598113) (xy 212.883247 -67.543676) (xy 212.879176 -67.488054) (xy 201.317606 -67.488054)
			(xy 200.219056 -68.586604) (xy 210.725258 -68.586604) (xy 210.725712 -68.559233) (xy 210.733531 -68.505053)
			(xy 210.749022 -68.452549) (xy 210.771867 -68.402803) (xy 210.801595 -68.356837) (xy 210.819238 -68.335906)
			(xy 210.819492 -68.335652) (xy 210.825062 -68.328554) (xy 210.831319 -68.311646) (xy 210.831684 -68.302632)
			(xy 210.831684 -68.235576) (xy 210.831342 -68.226558) (xy 210.825084 -68.209641) (xy 210.819492 -68.202556)
			(xy 210.819238 -68.202556) (xy 210.819238 -68.202302) (xy 210.801592 -68.181375) (xy 210.77188 -68.135401)
			(xy 210.749045 -68.085653) (xy 210.733555 -68.033151) (xy 210.72573 -67.978974) (xy 210.725258 -67.951604)
			(xy 210.725781 -67.924354) (xy 210.733536 -67.87041) (xy 210.748889 -67.818118) (xy 210.771528 -67.768543)
			(xy 210.80099 -67.722694) (xy 210.836678 -67.681505) (xy 210.877864 -67.645813) (xy 210.923709 -67.616346)
			(xy 210.973282 -67.593703) (xy 211.025573 -67.578345) (xy 211.079516 -67.570584) (xy 211.106766 -67.570096)
			(xy 211.133081 -67.570521) (xy 211.185212 -67.577764) (xy 211.235855 -67.592092) (xy 211.284054 -67.613233)
			(xy 211.328896 -67.640786) (xy 211.369534 -67.674231) (xy 211.38769 -67.693286) (xy 211.395215 -67.700683)
			(xy 211.414492 -67.709211) (xy 211.425028 -67.709796) (xy 211.499704 -67.709796) (xy 211.510256 -67.709284)
			(xy 211.529551 -67.700737) (xy 211.537042 -67.693286) (xy 211.555181 -67.674214) (xy 211.595815 -67.640759)
			(xy 211.640659 -67.613203) (xy 211.688863 -67.592067) (xy 211.739513 -67.577753) (xy 211.791649 -67.570532)
			(xy 211.817966 -67.570096) (xy 211.845335 -67.570583) (xy 211.899514 -67.578396) (xy 211.952016 -67.59388)
			(xy 212.001764 -67.616717) (xy 212.047732 -67.646437) (xy 212.068664 -67.664076) (xy 212.068918 -67.66433)
			(xy 212.075993 -67.669934) (xy 212.092919 -67.676169) (xy 212.101938 -67.676522) (xy 212.168994 -67.676522)
			(xy 212.17801 -67.676157) (xy 212.194927 -67.669914) (xy 212.202014 -67.66433) (xy 212.202014 -67.664076)
			(xy 212.202268 -67.664076) (xy 212.223198 -67.646435) (xy 212.269172 -67.616724) (xy 212.31892 -67.593889)
			(xy 212.371421 -67.578398) (xy 212.425597 -67.57057) (xy 212.452966 -67.570096) (xy 212.480218 -67.570587)
			(xy 212.534168 -67.578339) (xy 212.586466 -67.593691) (xy 212.636046 -67.61633) (xy 212.6819 -67.645795)
			(xy 212.723093 -67.681486) (xy 212.758787 -67.722676) (xy 212.788255 -67.768527) (xy 212.810898 -67.818106)
			(xy 212.826254 -67.870402) (xy 212.834011 -67.924352) (xy 212.834474 -67.951604) (xy 212.834017 -67.978975)
			(xy 212.826198 -68.033154) (xy 212.810707 -68.085658) (xy 212.787863 -68.135405) (xy 212.758136 -68.181371)
			(xy 212.740494 -68.202302) (xy 212.74024 -68.202556) (xy 212.734659 -68.209646) (xy 212.72841 -68.22656)
			(xy 212.728048 -68.235576) (xy 212.728048 -68.302632) (xy 212.728379 -68.311652) (xy 212.734643 -68.328569)
			(xy 212.74024 -68.335652) (xy 212.740494 -68.335652) (xy 212.740494 -68.335906) (xy 212.758148 -68.356826)
			(xy 212.787858 -68.402802) (xy 212.810691 -68.452552) (xy 212.826179 -68.505056) (xy 212.834002 -68.559234)
			(xy 212.834474 -68.586604) (xy 212.834048 -68.613858) (xy 212.82629 -68.667813) (xy 212.810932 -68.720113)
			(xy 212.794299 -68.75653) (xy 216.270332 -68.75653) (xy 216.270808 -68.72916) (xy 216.278622 -68.674981)
			(xy 216.294108 -68.622478) (xy 216.316948 -68.572731) (xy 216.346671 -68.526764) (xy 216.364312 -68.505832)
			(xy 216.364566 -68.505578) (xy 216.370176 -68.498508) (xy 216.376407 -68.481578) (xy 216.376758 -68.472558)
			(xy 216.376758 -68.405502) (xy 216.376409 -68.396484) (xy 216.370157 -68.379567) (xy 216.364566 -68.372482)
			(xy 216.364312 -68.372482) (xy 216.364312 -68.372228) (xy 216.346674 -68.351295) (xy 216.316962 -68.305322)
			(xy 216.294126 -68.255575) (xy 216.278634 -68.203075) (xy 216.270806 -68.148899) (xy 216.270332 -68.12153)
			(xy 216.270783 -68.094276) (xy 216.278537 -68.040323) (xy 216.293892 -67.988022) (xy 216.316533 -67.938439)
			(xy 216.346002 -67.892584) (xy 216.381697 -67.85139) (xy 216.422892 -67.815696) (xy 216.468748 -67.786229)
			(xy 216.518331 -67.763588) (xy 216.570632 -67.748235) (xy 216.624586 -67.740483) (xy 216.65184 -67.740022)
			(xy 216.679209 -67.740518) (xy 216.733387 -67.748328) (xy 216.78589 -67.76381) (xy 216.835638 -67.786645)
			(xy 216.881606 -67.816363) (xy 216.902538 -67.834002) (xy 216.902792 -67.834256) (xy 216.909872 -67.839852)
			(xy 216.926794 -67.846092) (xy 216.935812 -67.846448) (xy 217.002868 -67.846448) (xy 217.011885 -67.846087)
			(xy 217.028802 -67.839843) (xy 217.035888 -67.834256) (xy 217.035888 -67.834002) (xy 217.036142 -67.834002)
			(xy 217.057085 -67.816377) (xy 217.103055 -67.786663) (xy 217.1528 -67.763824) (xy 217.205298 -67.74833)
			(xy 217.259472 -67.740498) (xy 217.28684 -67.740022) (xy 217.313155 -67.740456) (xy 217.365285 -67.747696)
			(xy 217.415929 -67.762022) (xy 217.464128 -67.78316) (xy 217.508971 -67.810713) (xy 217.549609 -67.844158)
			(xy 217.567764 -67.863212) (xy 217.575295 -67.870602) (xy 217.594568 -67.879133) (xy 217.605102 -67.879722)
			(xy 217.679778 -67.879722) (xy 217.690327 -67.879188) (xy 217.709622 -67.870655) (xy 217.717116 -67.863212)
			(xy 217.735273 -67.844158) (xy 217.775902 -67.8107) (xy 217.820742 -67.783141) (xy 217.868943 -67.762002)
			(xy 217.91959 -67.747685) (xy 217.971724 -67.74046) (xy 217.99804 -67.740022) (xy 218.025294 -67.740441)
			(xy 218.079245 -67.748203) (xy 218.131543 -67.763565) (xy 218.181122 -67.786213) (xy 218.226974 -67.815686)
			(xy 218.268165 -67.851385) (xy 218.303856 -67.892582) (xy 218.33332 -67.938439) (xy 218.355959 -67.988023)
			(xy 218.371311 -68.040323) (xy 218.379064 -68.094276) (xy 218.379548 -68.12153) (xy 218.379112 -68.148901)
			(xy 218.371289 -68.203082) (xy 218.355794 -68.255586) (xy 218.332945 -68.305333) (xy 218.324834 -68.317872)
			(xy 224.787966 -68.317872) (xy 224.792037 -68.26225) (xy 224.804163 -68.207813) (xy 224.824086 -68.155722)
			(xy 224.851382 -68.107087) (xy 224.885468 -68.062944) (xy 224.925617 -68.024235) (xy 224.970975 -67.991784)
			(xy 225.020575 -67.966283) (xy 225.073359 -67.948276) (xy 225.128202 -67.938146) (xy 225.183936 -67.936109)
			(xy 225.239373 -67.942209) (xy 225.29333 -67.956315) (xy 225.344659 -67.978127) (xy 225.392265 -68.007181)
			(xy 225.435133 -68.042856) (xy 225.47235 -68.084393) (xy 225.503123 -68.130906) (xy 225.526795 -68.181403)
			(xy 225.542863 -68.23481) (xy 225.550983 -68.289986) (xy 225.551492 -68.317872) (xy 225.550983 -68.345758)
			(xy 225.542863 -68.400934) (xy 225.526795 -68.454341) (xy 225.503123 -68.504838) (xy 225.47235 -68.551351)
			(xy 225.435133 -68.592888) (xy 225.392265 -68.628563) (xy 225.344659 -68.657617) (xy 225.29333 -68.679429)
			(xy 225.239373 -68.693535) (xy 225.183936 -68.699635) (xy 225.128202 -68.697598) (xy 225.073359 -68.687468)
			(xy 225.020575 -68.669461) (xy 224.970975 -68.64396) (xy 224.925617 -68.611509) (xy 224.885468 -68.5728)
			(xy 224.851382 -68.528657) (xy 224.824086 -68.480022) (xy 224.804163 -68.427931) (xy 224.792037 -68.373494)
			(xy 224.787966 -68.317872) (xy 218.324834 -68.317872) (xy 218.303213 -68.351298) (xy 218.285568 -68.372228)
			(xy 218.285314 -68.372482) (xy 218.27973 -68.379571) (xy 218.273481 -68.396486) (xy 218.273122 -68.405502)
			(xy 218.273122 -68.472558) (xy 218.273494 -68.481573) (xy 218.279731 -68.498491) (xy 218.285314 -68.505578)
			(xy 218.285568 -68.505578) (xy 218.285568 -68.505832) (xy 218.303184 -68.526783) (xy 218.3329 -68.57275)
			(xy 218.355741 -68.622493) (xy 218.371238 -68.674989) (xy 218.379071 -68.729162) (xy 218.379548 -68.75653)
			(xy 218.37905 -68.78378) (xy 218.371291 -68.837725) (xy 218.355934 -68.890017) (xy 218.333292 -68.939592)
			(xy 218.303826 -68.98544) (xy 218.268136 -69.026629) (xy 218.226948 -69.06232) (xy 218.182251 -69.091048)
			(xy 227.444554 -69.091048) (xy 227.445004 -69.064761) (xy 227.452209 -69.012684) (xy 227.466505 -68.962092)
			(xy 227.487618 -68.913945) (xy 227.515148 -68.869156) (xy 227.548573 -68.828577) (xy 227.587259 -68.792976)
			(xy 227.63047 -68.763031) (xy 227.677387 -68.739309) (xy 227.70211 -68.730368) (xy 227.702364 -68.730368)
			(xy 227.712221 -68.726236) (xy 227.727715 -68.711555) (xy 227.732336 -68.70192) (xy 227.765864 -68.621402)
			(xy 227.765102 -68.599812) (xy 227.76053 -68.59016) (xy 227.748579 -68.564207) (xy 227.731715 -68.509616)
			(xy 227.723191 -68.45312) (xy 227.722684 -68.424552) (xy 227.722684 -68.424298) (xy 227.72317 -68.397047)
			(xy 227.730926 -68.343099) (xy 227.746281 -68.290804) (xy 227.768923 -68.241227) (xy 227.798389 -68.195377)
			(xy 227.83408 -68.154186) (xy 227.875271 -68.118495) (xy 227.921121 -68.089029) (xy 227.970698 -68.066387)
			(xy 228.022993 -68.051032) (xy 228.076941 -68.043276) (xy 228.131443 -68.043276) (xy 228.185391 -68.051032)
			(xy 228.237686 -68.066387) (xy 228.287263 -68.089029) (xy 228.333113 -68.118495) (xy 228.374304 -68.154186)
			(xy 228.409995 -68.195377) (xy 228.439461 -68.241227) (xy 228.462103 -68.290804) (xy 228.477458 -68.343099)
			(xy 228.485214 -68.397047) (xy 228.4857 -68.424298) (xy 228.485254 -68.450584) (xy 228.478044 -68.50266)
			(xy 228.463745 -68.553251) (xy 228.44263 -68.601396) (xy 228.415099 -68.646183) (xy 228.381674 -68.686762)
			(xy 228.34299 -68.722363) (xy 228.299781 -68.75231) (xy 228.252866 -68.776035) (xy 228.228144 -68.784978)
			(xy 228.22789 -68.784978) (xy 228.218015 -68.789074) (xy 228.202529 -68.80378) (xy 228.197918 -68.813426)
			(xy 228.16439 -68.893944) (xy 228.165152 -68.915534) (xy 228.169724 -68.925186) (xy 228.181687 -68.951134)
			(xy 228.198548 -69.005727) (xy 228.207066 -69.062225) (xy 228.20757 -69.090794) (xy 228.20757 -69.091048)
			(xy 228.207084 -69.118299) (xy 228.199328 -69.172247) (xy 228.183973 -69.224542) (xy 228.161331 -69.274119)
			(xy 228.131865 -69.319969) (xy 228.096174 -69.36116) (xy 228.054983 -69.396851) (xy 228.009133 -69.426317)
			(xy 227.959556 -69.448959) (xy 227.907261 -69.464314) (xy 227.853313 -69.47207) (xy 227.798811 -69.47207)
			(xy 227.744863 -69.464314) (xy 227.692568 -69.448959) (xy 227.642991 -69.426317) (xy 227.597141 -69.396851)
			(xy 227.55595 -69.36116) (xy 227.520259 -69.319969) (xy 227.490793 -69.274119) (xy 227.468151 -69.224542)
			(xy 227.452796 -69.172247) (xy 227.44504 -69.118299) (xy 227.444554 -69.091048) (xy 218.182251 -69.091048)
			(xy 218.181101 -69.091787) (xy 218.131527 -69.11443) (xy 218.079235 -69.129789) (xy 218.02529 -69.13755)
			(xy 217.99804 -69.138038) (xy 217.971724 -69.13763) (xy 217.919592 -69.130386) (xy 217.868947 -69.116057)
			(xy 217.820748 -69.094913) (xy 217.775906 -69.067355) (xy 217.73527 -69.033905) (xy 217.717116 -69.014848)
			(xy 217.709584 -69.007459) (xy 217.690312 -68.998926) (xy 217.679778 -68.998338) (xy 217.605102 -68.998338)
			(xy 217.594549 -68.998843) (xy 217.575253 -69.007394) (xy 217.567764 -69.014848) (xy 217.549628 -69.033923)
			(xy 217.508993 -69.067377) (xy 217.464148 -69.094932) (xy 217.415944 -69.116067) (xy 217.365294 -69.13038)
			(xy 217.313157 -69.137601) (xy 217.28684 -69.138038) (xy 217.25947 -69.137564) (xy 217.205291 -69.12975)
			(xy 217.152787 -69.114264) (xy 217.10304 -69.091424) (xy 217.057073 -69.061699) (xy 217.036142 -69.044058)
			(xy 217.035888 -69.043804) (xy 217.028809 -69.038207) (xy 217.011886 -69.031966) (xy 217.002868 -69.031612)
			(xy 216.935812 -69.031612) (xy 216.926795 -69.031972) (xy 216.909878 -69.038217) (xy 216.902792 -69.043804)
			(xy 216.902792 -69.044058) (xy 216.902538 -69.044058) (xy 216.881597 -69.061686) (xy 216.835627 -69.091401)
			(xy 216.785882 -69.11424) (xy 216.733383 -69.129733) (xy 216.679209 -69.137563) (xy 216.65184 -69.138038)
			(xy 216.624589 -69.137508) (xy 216.570643 -69.129757) (xy 216.518348 -69.114407) (xy 216.46877 -69.091772)
			(xy 216.422918 -69.062311) (xy 216.381726 -69.026624) (xy 216.346031 -68.985438) (xy 216.316562 -68.939592)
			(xy 216.293917 -68.890018) (xy 216.278558 -68.837726) (xy 216.270797 -68.78378) (xy 216.270332 -68.75653)
			(xy 212.794299 -68.75653) (xy 212.788286 -68.769696) (xy 212.758815 -68.81555) (xy 212.723117 -68.856744)
			(xy 212.68192 -68.892437) (xy 212.636062 -68.921904) (xy 212.586478 -68.944545) (xy 212.534175 -68.959898)
			(xy 212.480221 -68.967651) (xy 212.452966 -68.968112) (xy 212.425595 -68.967663) (xy 212.371416 -68.959841)
			(xy 212.318912 -68.944347) (xy 212.269166 -68.921502) (xy 212.223199 -68.891774) (xy 212.202268 -68.874132)
			(xy 212.202014 -68.873878) (xy 212.194929 -68.868289) (xy 212.178011 -68.862044) (xy 212.168994 -68.861686)
			(xy 212.101938 -68.861686) (xy 212.092923 -68.862064) (xy 212.076006 -68.868297) (xy 212.068918 -68.873878)
			(xy 212.068918 -68.874132) (xy 212.068664 -68.874132) (xy 212.047723 -68.89176) (xy 212.001752 -68.921472)
			(xy 211.952007 -68.94431) (xy 211.899508 -68.959804) (xy 211.845334 -68.967636) (xy 211.817966 -68.968112)
			(xy 211.791651 -68.967663) (xy 211.739522 -68.960424) (xy 211.688879 -68.946101) (xy 211.640681 -68.924965)
			(xy 211.595837 -68.897416) (xy 211.555198 -68.863975) (xy 211.537042 -68.844922) (xy 211.529504 -68.83754)
			(xy 211.510236 -68.829004) (xy 211.499704 -68.828412) (xy 211.425028 -68.828412) (xy 211.414478 -68.828939)
			(xy 211.395182 -68.837475) (xy 211.38769 -68.844922) (xy 211.369537 -68.86398) (xy 211.328906 -68.897436)
			(xy 211.284065 -68.924994) (xy 211.235864 -68.946132) (xy 211.185216 -68.960449) (xy 211.133082 -68.967673)
			(xy 211.106766 -68.968112) (xy 211.079514 -68.967654) (xy 211.025566 -68.959893) (xy 210.973271 -68.944534)
			(xy 210.923693 -68.921889) (xy 210.877843 -68.892419) (xy 210.836654 -68.856725) (xy 210.800963 -68.815532)
			(xy 210.771497 -68.76968) (xy 210.748856 -68.720101) (xy 210.733501 -68.667805) (xy 210.725744 -68.613856)
			(xy 210.725258 -68.586604) (xy 200.219056 -68.586604) (xy 199.439022 -69.366638) (xy 199.432179 -69.374037)
			(xy 199.424455 -69.392636) (xy 199.424036 -69.402706) (xy 199.424036 -70.271894) (xy 199.42429 -70.27672)
			(xy 199.42429 -70.276974) (xy 199.425242 -70.283703) (xy 199.430258 -70.296328) (xy 199.434196 -70.301866)
			(xy 199.438768 -70.3072) (xy 199.808846 -70.677278) (xy 199.815188 -70.68317) (xy 199.830769 -70.690689)
			(xy 199.839326 -70.69201) (xy 199.84212 -70.692264) (xy 215.548972 -70.692264) (xy 215.554489 -70.692093)
			(xy 215.56525 -70.689649) (xy 215.570308 -70.687438) (xy 215.59901 -70.67423) (xy 215.606122 -70.666356)
			(xy 215.606376 -70.666102) (xy 215.624562 -70.646239) (xy 215.665559 -70.611319) (xy 215.711059 -70.582511)
			(xy 215.760158 -70.560388) (xy 215.811881 -70.545391) (xy 215.865199 -70.537817) (xy 215.919053 -70.537817)
			(xy 215.972371 -70.545391) (xy 216.024094 -70.560388) (xy 216.073193 -70.582511) (xy 216.118693 -70.611319)
			(xy 216.15969 -70.646239) (xy 216.177876 -70.666102) (xy 216.17813 -70.666356) (xy 216.185242 -70.67423)
			(xy 216.213944 -70.687438) (xy 216.219001 -70.689648) (xy 216.229764 -70.692084) (xy 216.23528 -70.692264)
			(xy 230.024686 -70.692264) (xy 230.034435 -70.691839) (xy 230.052521 -70.684559) (xy 230.066549 -70.67102)
			(xy 230.070914 -70.662292) (xy 230.109014 -70.57771) (xy 230.111123 -70.572762) (xy 230.113427 -70.562258)
			(xy 230.113586 -70.556882) (xy 230.100886 -70.523354) (xy 230.069158 -70.486652) (xy 230.011213 -70.408832)
			(xy 229.959919 -70.326476) (xy 229.915627 -70.240151) (xy 229.878644 -70.150452) (xy 229.849223 -70.057996)
			(xy 229.827567 -69.96342) (xy 229.813825 -69.867374) (xy 229.808092 -69.770519) (xy 229.810406 -69.673523)
			(xy 229.820753 -69.577052) (xy 229.839062 -69.481771) (xy 229.865205 -69.388336) (xy 229.899003 -69.297388)
			(xy 229.940223 -69.209556) (xy 229.988582 -69.125443) (xy 230.043747 -69.045627) (xy 230.105338 -68.970659)
			(xy 230.172932 -68.901055) (xy 230.246062 -68.837292) (xy 230.324226 -68.779812) (xy 230.406886 -68.729008)
			(xy 230.493472 -68.68523) (xy 230.58339 -68.648781) (xy 230.676019 -68.61991) (xy 230.770722 -68.598817)
			(xy 230.866848 -68.585647) (xy 230.963735 -68.58049) (xy 231.012238 -68.581524) (xy 231.015286 -68.581524)
			(xy 231.063665 -68.58048) (xy 231.160315 -68.585423) (xy 231.256225 -68.59834) (xy 231.350738 -68.619142)
			(xy 231.443209 -68.647686) (xy 231.533003 -68.683777) (xy 231.619506 -68.727169) (xy 231.702125 -68.777563)
			(xy 231.780295 -68.834615) (xy 231.853481 -68.897935) (xy 231.921182 -68.967088) (xy 231.948553 -69.000116)
			(xy 233.19105 -69.000116) (xy 233.191549 -68.972636) (xy 233.19944 -68.918244) (xy 233.215059 -68.865549)
			(xy 233.238083 -68.815644) (xy 233.268035 -68.769561) (xy 233.304294 -68.728258) (xy 233.346108 -68.69259)
			(xy 233.369104 -68.677536) (xy 233.381055 -68.669324) (xy 233.400234 -68.647601) (xy 233.412546 -68.621369)
			(xy 233.417 -68.592735) (xy 233.413239 -68.564002) (xy 233.401565 -68.537479) (xy 233.382916 -68.515299)
			(xy 233.371136 -68.506848) (xy 233.349088 -68.491587) (xy 233.309032 -68.455942) (xy 233.274366 -68.415036)
			(xy 233.245774 -68.369677) (xy 233.223819 -68.320759) (xy 233.208935 -68.269247) (xy 233.201415 -68.216158)
			(xy 233.200956 -68.189348) (xy 233.201442 -68.162097) (xy 233.209198 -68.108149) (xy 233.224553 -68.055854)
			(xy 233.247195 -68.006277) (xy 233.276661 -67.960427) (xy 233.312352 -67.919236) (xy 233.353543 -67.883545)
			(xy 233.399393 -67.854079) (xy 233.44897 -67.831437) (xy 233.501265 -67.816082) (xy 233.555213 -67.808326)
			(xy 233.609715 -67.808326) (xy 233.663663 -67.816082) (xy 233.715958 -67.831437) (xy 233.765535 -67.854079)
			(xy 233.811385 -67.883545) (xy 233.852576 -67.919236) (xy 233.888267 -67.960427) (xy 233.917733 -68.006277)
			(xy 233.940375 -68.055854) (xy 233.95573 -68.108149) (xy 233.963486 -68.162097) (xy 233.963972 -68.189348)
			(xy 233.963512 -68.21683) (xy 233.955613 -68.271223) (xy 233.939987 -68.323918) (xy 233.916956 -68.373823)
			(xy 233.886998 -68.419905) (xy 233.850734 -68.461207) (xy 233.808915 -68.496875) (xy 233.785918 -68.511928)
			(xy 233.773905 -68.520056) (xy 233.754719 -68.541796) (xy 233.742407 -68.568047) (xy 233.739526 -68.586604)
			(xy 248.825258 -68.586604) (xy 248.825712 -68.559233) (xy 248.833531 -68.505053) (xy 248.849022 -68.452549)
			(xy 248.871867 -68.402803) (xy 248.901595 -68.356837) (xy 248.919238 -68.335906) (xy 248.919492 -68.335652)
			(xy 248.925062 -68.328554) (xy 248.931319 -68.311646) (xy 248.931684 -68.302632) (xy 248.931684 -68.235576)
			(xy 248.931342 -68.226558) (xy 248.925084 -68.209641) (xy 248.919492 -68.202556) (xy 248.919238 -68.202556)
			(xy 248.919238 -68.202302) (xy 248.901592 -68.181375) (xy 248.87188 -68.135401) (xy 248.849045 -68.085653)
			(xy 248.833555 -68.033151) (xy 248.82573 -67.978974) (xy 248.825258 -67.951604) (xy 248.825781 -67.924354)
			(xy 248.833536 -67.87041) (xy 248.848889 -67.818118) (xy 248.871528 -67.768543) (xy 248.90099 -67.722694)
			(xy 248.936678 -67.681505) (xy 248.977864 -67.645813) (xy 249.023709 -67.616346) (xy 249.073282 -67.593703)
			(xy 249.125573 -67.578345) (xy 249.179516 -67.570584) (xy 249.206766 -67.570096) (xy 249.233081 -67.570521)
			(xy 249.285212 -67.577764) (xy 249.335855 -67.592092) (xy 249.384054 -67.613233) (xy 249.428896 -67.640786)
			(xy 249.469534 -67.674231) (xy 249.48769 -67.693286) (xy 249.495215 -67.700683) (xy 249.514492 -67.709211)
			(xy 249.525028 -67.709796) (xy 249.599704 -67.709796) (xy 249.610256 -67.709284) (xy 249.629551 -67.700737)
			(xy 249.637042 -67.693286) (xy 249.655181 -67.674214) (xy 249.695815 -67.640759) (xy 249.740659 -67.613203)
			(xy 249.788863 -67.592067) (xy 249.839513 -67.577753) (xy 249.891649 -67.570532) (xy 249.917966 -67.570096)
			(xy 249.945335 -67.570583) (xy 249.999514 -67.578396) (xy 250.052016 -67.59388) (xy 250.101764 -67.616717)
			(xy 250.147732 -67.646437) (xy 250.168664 -67.664076) (xy 250.168918 -67.66433) (xy 250.175993 -67.669934)
			(xy 250.192919 -67.676169) (xy 250.201938 -67.676522) (xy 250.268994 -67.676522) (xy 250.27801 -67.676157)
			(xy 250.294927 -67.669914) (xy 250.302014 -67.66433) (xy 250.302014 -67.664076) (xy 250.302268 -67.664076)
			(xy 250.323198 -67.646435) (xy 250.369172 -67.616724) (xy 250.41892 -67.593889) (xy 250.471421 -67.578398)
			(xy 250.525597 -67.57057) (xy 250.552966 -67.570096) (xy 250.580218 -67.570587) (xy 250.634168 -67.578339)
			(xy 250.686466 -67.593691) (xy 250.736046 -67.61633) (xy 250.7819 -67.645795) (xy 250.823093 -67.681486)
			(xy 250.858787 -67.722676) (xy 250.888255 -67.768527) (xy 250.910898 -67.818106) (xy 250.926254 -67.870402)
			(xy 250.934011 -67.924352) (xy 250.934474 -67.951604) (xy 250.934017 -67.978975) (xy 250.926198 -68.033154)
			(xy 250.910707 -68.085658) (xy 250.887863 -68.135405) (xy 250.858136 -68.181371) (xy 250.840494 -68.202302)
			(xy 250.84024 -68.202556) (xy 250.834659 -68.209646) (xy 250.82841 -68.22656) (xy 250.828048 -68.235576)
			(xy 250.828048 -68.302632) (xy 250.828379 -68.311652) (xy 250.834643 -68.328569) (xy 250.84024 -68.335652)
			(xy 250.840494 -68.335652) (xy 250.840494 -68.335906) (xy 250.858148 -68.356826) (xy 250.887858 -68.402802)
			(xy 250.910691 -68.452552) (xy 250.926179 -68.505056) (xy 250.934002 -68.559234) (xy 250.934474 -68.586604)
			(xy 250.934048 -68.613858) (xy 250.92629 -68.667813) (xy 250.910932 -68.720113) (xy 250.894299 -68.75653)
			(xy 254.370332 -68.75653) (xy 254.370808 -68.72916) (xy 254.378622 -68.674981) (xy 254.394108 -68.622478)
			(xy 254.416948 -68.572731) (xy 254.446671 -68.526764) (xy 254.464312 -68.505832) (xy 254.464566 -68.505578)
			(xy 254.470176 -68.498508) (xy 254.476407 -68.481578) (xy 254.476758 -68.472558) (xy 254.476758 -68.405502)
			(xy 254.476409 -68.396484) (xy 254.470157 -68.379567) (xy 254.464566 -68.372482) (xy 254.464312 -68.372482)
			(xy 254.464312 -68.372228) (xy 254.446674 -68.351295) (xy 254.416962 -68.305322) (xy 254.394126 -68.255575)
			(xy 254.378634 -68.203075) (xy 254.370806 -68.148899) (xy 254.370332 -68.12153) (xy 254.370783 -68.094276)
			(xy 254.378537 -68.040323) (xy 254.393892 -67.988022) (xy 254.416533 -67.938439) (xy 254.446002 -67.892584)
			(xy 254.481697 -67.85139) (xy 254.522892 -67.815696) (xy 254.568748 -67.786229) (xy 254.618331 -67.763588)
			(xy 254.670632 -67.748235) (xy 254.724586 -67.740483) (xy 254.75184 -67.740022) (xy 254.779209 -67.740518)
			(xy 254.833387 -67.748328) (xy 254.88589 -67.76381) (xy 254.935638 -67.786645) (xy 254.981606 -67.816363)
			(xy 255.002538 -67.834002) (xy 255.002792 -67.834256) (xy 255.009872 -67.839852) (xy 255.026794 -67.846092)
			(xy 255.035812 -67.846448) (xy 255.102868 -67.846448) (xy 255.111885 -67.846087) (xy 255.128802 -67.839843)
			(xy 255.135888 -67.834256) (xy 255.135888 -67.834002) (xy 255.136142 -67.834002) (xy 255.157085 -67.816377)
			(xy 255.203055 -67.786663) (xy 255.2528 -67.763824) (xy 255.305298 -67.74833) (xy 255.359472 -67.740498)
			(xy 255.38684 -67.740022) (xy 255.413155 -67.740456) (xy 255.465285 -67.747696) (xy 255.515929 -67.762022)
			(xy 255.564128 -67.78316) (xy 255.608971 -67.810713) (xy 255.649609 -67.844158) (xy 255.667764 -67.863212)
			(xy 255.675295 -67.870602) (xy 255.694568 -67.879133) (xy 255.705102 -67.879722) (xy 255.779778 -67.879722)
			(xy 255.790327 -67.879188) (xy 255.809622 -67.870655) (xy 255.817116 -67.863212) (xy 255.835273 -67.844158)
			(xy 255.875902 -67.8107) (xy 255.920742 -67.783141) (xy 255.968943 -67.762002) (xy 256.01959 -67.747685)
			(xy 256.071724 -67.74046) (xy 256.09804 -67.740022) (xy 256.125294 -67.740441) (xy 256.179245 -67.748203)
			(xy 256.231543 -67.763565) (xy 256.281122 -67.786213) (xy 256.326974 -67.815686) (xy 256.368165 -67.851385)
			(xy 256.403856 -67.892582) (xy 256.43332 -67.938439) (xy 256.455959 -67.988023) (xy 256.471311 -68.040323)
			(xy 256.479064 -68.094276) (xy 256.479548 -68.12153) (xy 256.479112 -68.148901) (xy 256.471289 -68.203082)
			(xy 256.455794 -68.255586) (xy 256.432945 -68.305333) (xy 256.403213 -68.351298) (xy 256.385568 -68.372228)
			(xy 256.385314 -68.372482) (xy 256.37973 -68.379571) (xy 256.373481 -68.396486) (xy 256.373122 -68.405502)
			(xy 256.373122 -68.472558) (xy 256.373494 -68.481573) (xy 256.379731 -68.498491) (xy 256.385314 -68.505578)
			(xy 256.385568 -68.505578) (xy 256.385568 -68.505832) (xy 256.403184 -68.526783) (xy 256.4329 -68.57275)
			(xy 256.439261 -68.586604) (xy 274.825206 -68.586604) (xy 274.825673 -68.559234) (xy 274.83349 -68.505055)
			(xy 274.848979 -68.452552) (xy 274.871821 -68.402805) (xy 274.901545 -68.356838) (xy 274.919186 -68.335906)
			(xy 274.91944 -68.335652) (xy 274.925016 -68.328558) (xy 274.931268 -68.311647) (xy 274.931632 -68.302632)
			(xy 274.931632 -68.235576) (xy 274.93128 -68.226559) (xy 274.925028 -68.209642) (xy 274.91944 -68.202556)
			(xy 274.919186 -68.202556) (xy 274.919186 -68.202302) (xy 274.901532 -68.181382) (xy 274.871823 -68.135406)
			(xy 274.84899 -68.085655) (xy 274.833503 -68.033152) (xy 274.825678 -67.978974) (xy 274.825206 -67.951604)
			(xy 274.825659 -67.924351) (xy 274.833416 -67.870399) (xy 274.848772 -67.8181) (xy 274.871415 -67.768519)
			(xy 274.900884 -67.722665) (xy 274.936579 -67.681472) (xy 274.977773 -67.645778) (xy 275.023627 -67.61631)
			(xy 275.073209 -67.593669) (xy 275.125508 -67.578314) (xy 275.179461 -67.570558) (xy 275.206714 -67.570096)
			(xy 275.233028 -67.570555) (xy 275.285157 -67.577792) (xy 275.3358 -67.592113) (xy 275.383999 -67.613247)
			(xy 275.428842 -67.640794) (xy 275.469482 -67.674234) (xy 275.487638 -67.693286) (xy 275.495145 -67.700704)
			(xy 275.514436 -67.70922) (xy 275.524976 -67.709796) (xy 275.599652 -67.709796) (xy 275.6102 -67.709256)
			(xy 275.629496 -67.700729) (xy 275.63699 -67.693286) (xy 275.655155 -67.67424) (xy 275.695783 -67.640782)
			(xy 275.740621 -67.613222) (xy 275.78882 -67.592082) (xy 275.839466 -67.577763) (xy 275.891598 -67.570536)
			(xy 275.917914 -67.570096) (xy 275.945284 -67.570555) (xy 275.999464 -67.578375) (xy 276.051967 -67.593865)
			(xy 276.101714 -67.616709) (xy 276.14768 -67.646434) (xy 276.168612 -67.664076) (xy 276.168866 -67.66433)
			(xy 276.175956 -67.669912) (xy 276.19287 -67.67616) (xy 276.201886 -67.676522) (xy 276.268942 -67.676522)
			(xy 276.277956 -67.676133) (xy 276.294873 -67.669907) (xy 276.301962 -67.66433) (xy 276.301962 -67.664076)
			(xy 276.302216 -67.664076) (xy 276.323166 -67.646459) (xy 276.369134 -67.616745) (xy 276.418877 -67.593905)
			(xy 276.471374 -67.578409) (xy 276.525546 -67.570574) (xy 276.552914 -67.570096) (xy 276.580166 -67.570565)
			(xy 276.634114 -67.578323) (xy 276.68641 -67.59368) (xy 276.735987 -67.616323) (xy 276.781838 -67.645792)
			(xy 276.823028 -67.681485) (xy 276.858719 -67.722677) (xy 276.888185 -67.768529) (xy 276.910826 -67.818107)
			(xy 276.926181 -67.870403) (xy 276.933937 -67.924352) (xy 276.934422 -67.951604) (xy 276.933977 -67.978975)
			(xy 276.926157 -68.033156) (xy 276.910664 -68.08566) (xy 276.887817 -68.135407) (xy 276.858087 -68.181372)
			(xy 276.840442 -68.202302) (xy 276.840188 -68.202556) (xy 276.834612 -68.20965) (xy 276.828359 -68.226561)
			(xy 276.827996 -68.235576) (xy 276.827996 -68.302632) (xy 276.828339 -68.31165) (xy 276.834596 -68.328567)
			(xy 276.840188 -68.335652) (xy 276.840442 -68.335652) (xy 276.840442 -68.335906) (xy 276.858104 -68.356819)
			(xy 276.887811 -68.402798) (xy 276.910642 -68.45255) (xy 276.926128 -68.505055) (xy 276.933951 -68.559234)
			(xy 276.934422 -68.586604) (xy 276.933926 -68.613855) (xy 276.926169 -68.667801) (xy 276.910814 -68.720095)
			(xy 276.894175 -68.75653) (xy 280.37028 -68.75653) (xy 280.370744 -68.729159) (xy 280.378559 -68.67498)
			(xy 280.394048 -68.622476) (xy 280.416891 -68.572729) (xy 280.446617 -68.526763) (xy 280.46426 -68.505832)
			(xy 280.464514 -68.505578) (xy 280.470117 -68.498503) (xy 280.476354 -68.481577) (xy 280.476706 -68.472558)
			(xy 280.476706 -68.405502) (xy 280.476347 -68.396485) (xy 280.470101 -68.379568) (xy 280.464514 -68.372482)
			(xy 280.46426 -68.372482) (xy 280.46426 -68.372228) (xy 280.446614 -68.351302) (xy 280.416904 -68.305327)
			(xy 280.39407 -68.255578) (xy 280.378581 -68.203076) (xy 280.370753 -68.148899) (xy 280.37028 -68.12153)
			(xy 280.370783 -68.094278) (xy 280.378536 -68.04033) (xy 280.393887 -67.988033) (xy 280.416526 -67.938454)
			(xy 280.445989 -67.892601) (xy 280.481679 -67.851409) (xy 280.522868 -67.815714) (xy 280.568717 -67.786246)
			(xy 280.618294 -67.763602) (xy 280.670588 -67.748245) (xy 280.724536 -67.740486) (xy 280.751788 -67.740022)
			(xy 280.779158 -67.74049) (xy 280.833337 -67.748306) (xy 280.885841 -67.763795) (xy 280.935588 -67.786636)
			(xy 280.981554 -67.816361) (xy 281.002486 -67.834002) (xy 281.00274 -67.834256) (xy 281.009835 -67.83983)
			(xy 281.026745 -67.846083) (xy 281.03576 -67.846448) (xy 281.102816 -67.846448) (xy 281.111835 -67.84611)
			(xy 281.128752 -67.83985) (xy 281.135836 -67.834256) (xy 281.135836 -67.834002) (xy 281.13609 -67.834002)
			(xy 281.157015 -67.816354) (xy 281.20299 -67.786644) (xy 281.252739 -67.763809) (xy 281.305241 -67.74832)
			(xy 281.359418 -67.740495) (xy 281.386788 -67.740022) (xy 281.413102 -67.74049) (xy 281.465231 -67.747724)
			(xy 281.515874 -67.762042) (xy 281.564073 -67.783175) (xy 281.608916 -67.810721) (xy 281.649556 -67.84416)
			(xy 281.667712 -67.863212) (xy 281.675226 -67.870623) (xy 281.694512 -67.879142) (xy 281.70505 -67.879722)
			(xy 281.779726 -67.879722) (xy 281.790272 -67.87916) (xy 281.809567 -67.870647) (xy 281.817064 -67.863212)
			(xy 281.835198 -67.844135) (xy 281.875832 -67.810679) (xy 281.920677 -67.783123) (xy 281.968882 -67.761988)
			(xy 282.019533 -67.747676) (xy 282.071671 -67.740457) (xy 282.097988 -67.740022) (xy 282.125242 -67.740467)
			(xy 282.179195 -67.748223) (xy 282.231495 -67.763579) (xy 282.281077 -67.786222) (xy 282.326932 -67.815692)
			(xy 282.368125 -67.851387) (xy 282.403819 -67.892583) (xy 282.433287 -67.938439) (xy 282.455928 -67.988022)
			(xy 282.471281 -68.040323) (xy 282.479035 -68.094276) (xy 282.479496 -68.12153) (xy 282.479048 -68.148901)
			(xy 282.471226 -68.203081) (xy 282.455733 -68.255584) (xy 282.432887 -68.305331) (xy 282.403159 -68.351297)
			(xy 282.385516 -68.372228) (xy 282.385262 -68.372482) (xy 282.379673 -68.379566) (xy 282.373429 -68.396485)
			(xy 282.37307 -68.405502) (xy 282.37307 -68.472558) (xy 282.373454 -68.481572) (xy 282.379683 -68.498489)
			(xy 282.385262 -68.505578) (xy 282.385516 -68.505578) (xy 282.385516 -68.505832) (xy 282.403139 -68.526777)
			(xy 282.432853 -68.572746) (xy 282.439216 -68.586604) (xy 300.825154 -68.586604) (xy 300.825609 -68.559233)
			(xy 300.833428 -68.505053) (xy 300.848919 -68.452549) (xy 300.871763 -68.402803) (xy 300.901491 -68.356837)
			(xy 300.919134 -68.335906) (xy 300.919388 -68.335652) (xy 300.924958 -68.328554) (xy 300.931215 -68.311646)
			(xy 300.93158 -68.302632) (xy 300.93158 -68.235576) (xy 300.931239 -68.226557) (xy 300.924981 -68.20964)
			(xy 300.919388 -68.202556) (xy 300.919134 -68.202556) (xy 300.919134 -68.202302) (xy 300.901488 -68.181376)
			(xy 300.871776 -68.135402) (xy 300.848941 -68.085653) (xy 300.833451 -68.033151) (xy 300.825626 -67.978974)
			(xy 300.825154 -67.951604) (xy 300.825681 -67.924355) (xy 300.833436 -67.87041) (xy 300.848789 -67.818119)
			(xy 300.871427 -67.768544) (xy 300.900889 -67.722695) (xy 300.936576 -67.681506) (xy 300.977762 -67.645815)
			(xy 301.023607 -67.616347) (xy 301.073179 -67.593704) (xy 301.125469 -67.578345) (xy 301.179413 -67.570584)
			(xy 301.206662 -67.570096) (xy 301.232977 -67.570523) (xy 301.285108 -67.577767) (xy 301.335751 -67.592094)
			(xy 301.38395 -67.613234) (xy 301.428792 -67.640787) (xy 301.46943 -67.674232) (xy 301.487586 -67.693286)
			(xy 301.495113 -67.700681) (xy 301.514389 -67.70921) (xy 301.524924 -67.709796) (xy 301.5996 -67.709796)
			(xy 301.610151 -67.709281) (xy 301.629447 -67.700736) (xy 301.636938 -67.693286) (xy 301.655079 -67.674216)
			(xy 301.695712 -67.640761) (xy 301.740556 -67.613204) (xy 301.788759 -67.592068) (xy 301.839409 -67.577754)
			(xy 301.891545 -67.570533) (xy 301.917862 -67.570096) (xy 301.945231 -67.570585) (xy 301.999409 -67.578398)
			(xy 302.051912 -67.593881) (xy 302.101659 -67.616718) (xy 302.147627 -67.646437) (xy 302.16856 -67.664076)
			(xy 302.168814 -67.66433) (xy 302.17589 -67.669932) (xy 302.192815 -67.676168) (xy 302.201834 -67.676522)
			(xy 302.26889 -67.676522) (xy 302.277906 -67.676155) (xy 302.294823 -67.669914) (xy 302.30191 -67.66433)
			(xy 302.30191 -67.664076) (xy 302.302164 -67.664076) (xy 302.323096 -67.646437) (xy 302.369069 -67.616726)
			(xy 302.418817 -67.59389) (xy 302.471317 -67.578399) (xy 302.525493 -67.57057) (xy 302.552862 -67.570096)
			(xy 302.580114 -67.570591) (xy 302.634064 -67.578343) (xy 302.686362 -67.593694) (xy 302.735942 -67.616332)
			(xy 302.781795 -67.645797) (xy 302.822989 -67.681487) (xy 302.858683 -67.722677) (xy 302.888151 -67.768528)
			(xy 302.910794 -67.818106) (xy 302.92615 -67.870403) (xy 302.933907 -67.924352) (xy 302.93437 -67.951604)
			(xy 302.933914 -67.978975) (xy 302.926095 -68.033154) (xy 302.910604 -68.085658) (xy 302.88776 -68.135405)
			(xy 302.858033 -68.181371) (xy 302.84039 -68.202302) (xy 302.840136 -68.202556) (xy 302.834554 -68.209645)
			(xy 302.828306 -68.22656) (xy 302.827944 -68.235576) (xy 302.827944 -68.302632) (xy 302.828276 -68.311652)
			(xy 302.83454 -68.328569) (xy 302.840136 -68.335652) (xy 302.84039 -68.335652) (xy 302.84039 -68.335906)
			(xy 302.858044 -68.356826) (xy 302.887754 -68.402802) (xy 302.910587 -68.452553) (xy 302.926075 -68.505056)
			(xy 302.933898 -68.559234) (xy 302.93437 -68.586604) (xy 302.933948 -68.613859) (xy 302.92619 -68.667813)
			(xy 302.910831 -68.720114) (xy 302.894199 -68.75653) (xy 306.370228 -68.75653) (xy 306.370705 -68.72916)
			(xy 306.378519 -68.674981) (xy 306.394005 -68.622478) (xy 306.416845 -68.572731) (xy 306.446567 -68.526764)
			(xy 306.464208 -68.505832) (xy 306.464462 -68.505578) (xy 306.470071 -68.498507) (xy 306.476303 -68.481578)
			(xy 306.476654 -68.472558) (xy 306.476654 -68.405502) (xy 306.476306 -68.396484) (xy 306.470053 -68.379567)
			(xy 306.464462 -68.372482) (xy 306.464208 -68.372482) (xy 306.464208 -68.372228) (xy 306.44657 -68.351295)
			(xy 306.416858 -68.305323) (xy 306.394021 -68.255575) (xy 306.37853 -68.203075) (xy 306.370702 -68.148899)
			(xy 306.370228 -68.12153) (xy 306.370683 -68.094276) (xy 306.378437 -68.040323) (xy 306.393791 -67.988023)
			(xy 306.416433 -67.938441) (xy 306.445901 -67.892586) (xy 306.481596 -67.851392) (xy 306.52279 -67.815697)
			(xy 306.568646 -67.78623) (xy 306.618229 -67.763589) (xy 306.670529 -67.748236) (xy 306.724482 -67.740483)
			(xy 306.751736 -67.740022) (xy 306.779107 -67.740462) (xy 306.833288 -67.748285) (xy 306.885791 -67.76378)
			(xy 306.935538 -67.786628) (xy 306.981503 -67.816358) (xy 307.002434 -67.834002) (xy 307.002688 -67.834256)
			(xy 307.009769 -67.83985) (xy 307.02669 -67.846091) (xy 307.035708 -67.846448) (xy 307.102764 -67.846448)
			(xy 307.11178 -67.846085) (xy 307.128698 -67.839843) (xy 307.135784 -67.834256) (xy 307.135784 -67.834002)
			(xy 307.136038 -67.834002) (xy 307.156983 -67.816379) (xy 307.202952 -67.786665) (xy 307.252696 -67.763825)
			(xy 307.305194 -67.748331) (xy 307.359368 -67.740498) (xy 307.386736 -67.740022) (xy 307.413051 -67.740458)
			(xy 307.465181 -67.747699) (xy 307.515825 -67.762023) (xy 307.564024 -67.783162) (xy 307.608867 -67.810713)
			(xy 307.649505 -67.844158) (xy 307.66766 -67.863212) (xy 307.675193 -67.8706) (xy 307.694464 -67.879132)
			(xy 307.704998 -67.879722) (xy 307.779674 -67.879722) (xy 307.790223 -67.879186) (xy 307.809518 -67.870655)
			(xy 307.817012 -67.863212) (xy 307.835171 -67.84416) (xy 307.8758 -67.810702) (xy 307.920639 -67.783142)
			(xy 307.968839 -67.762003) (xy 308.019486 -67.747685) (xy 308.07162 -67.74046) (xy 308.097936 -67.740022)
			(xy 308.12519 -67.740444) (xy 308.179141 -67.748207) (xy 308.231439 -67.763568) (xy 308.281018 -67.786215)
			(xy 308.32687 -67.815688) (xy 308.36806 -67.851386) (xy 308.403751 -67.892583) (xy 308.433216 -67.93844)
			(xy 308.455855 -67.988023) (xy 308.471207 -68.040324) (xy 308.47896 -68.094276) (xy 308.479444 -68.12153)
			(xy 308.479009 -68.148902) (xy 308.471186 -68.203082) (xy 308.45569 -68.255586) (xy 308.432841 -68.305333)
			(xy 308.403109 -68.351298) (xy 308.385464 -68.372228) (xy 308.38521 -68.372482) (xy 308.379626 -68.37957)
			(xy 308.373377 -68.396486) (xy 308.373018 -68.405502) (xy 308.373018 -68.472558) (xy 308.373391 -68.481573)
			(xy 308.379627 -68.498491) (xy 308.38521 -68.505578) (xy 308.385464 -68.505578) (xy 308.385464 -68.505832)
			(xy 308.403079 -68.526784) (xy 308.432796 -68.57275) (xy 308.455637 -68.622493) (xy 308.471133 -68.674989)
			(xy 308.478967 -68.729162) (xy 308.479444 -68.75653) (xy 308.47895 -68.78378) (xy 308.471191 -68.837726)
			(xy 308.455833 -68.890018) (xy 308.433191 -68.939593) (xy 308.403725 -68.985442) (xy 308.368035 -69.026631)
			(xy 308.326847 -69.062322) (xy 308.280999 -69.091789) (xy 308.231424 -69.114431) (xy 308.179132 -69.129789)
			(xy 308.125186 -69.13755) (xy 308.097936 -69.138038) (xy 308.07162 -69.137633) (xy 308.019488 -69.130388)
			(xy 307.968843 -69.116058) (xy 307.920644 -69.094914) (xy 307.875802 -69.067356) (xy 307.835166 -69.033905)
			(xy 307.817012 -69.014848) (xy 307.809481 -69.007457) (xy 307.790208 -68.998925) (xy 307.779674 -68.998338)
			(xy 307.704998 -68.998338) (xy 307.694445 -68.998841) (xy 307.675149 -69.007393) (xy 307.66766 -69.014848)
			(xy 307.649526 -69.033925) (xy 307.608891 -69.067378) (xy 307.564046 -69.094933) (xy 307.515841 -69.116068)
			(xy 307.46519 -69.130381) (xy 307.413053 -69.137602) (xy 307.386736 -69.138038) (xy 307.359366 -69.137566)
			(xy 307.305186 -69.129752) (xy 307.252683 -69.114265) (xy 307.202936 -69.091424) (xy 307.156969 -69.0617)
			(xy 307.136038 -69.044058) (xy 307.135784 -69.043804) (xy 307.128706 -69.038205) (xy 307.111783 -69.031966)
			(xy 307.102764 -69.031612) (xy 307.035708 -69.031612) (xy 307.026691 -69.03197) (xy 307.009774 -69.038217)
			(xy 307.002688 -69.043804) (xy 307.002688 -69.044058) (xy 307.002434 -69.044058) (xy 306.981495 -69.061688)
			(xy 306.935524 -69.091403) (xy 306.885779 -69.114241) (xy 306.83328 -69.129734) (xy 306.779105 -69.137564)
			(xy 306.751736 -69.138038) (xy 306.724485 -69.137511) (xy 306.670538 -69.12976) (xy 306.618243 -69.11441)
			(xy 306.568665 -69.091774) (xy 306.522814 -69.062312) (xy 306.481621 -69.026625) (xy 306.445927 -68.985439)
			(xy 306.416458 -68.939593) (xy 306.393813 -68.890018) (xy 306.378454 -68.837726) (xy 306.370693 -68.783781)
			(xy 306.370228 -68.75653) (xy 302.894199 -68.75653) (xy 302.888186 -68.769697) (xy 302.858714 -68.815552)
			(xy 302.823015 -68.856745) (xy 302.781818 -68.892439) (xy 302.73596 -68.921906) (xy 302.686375 -68.944546)
			(xy 302.634072 -68.959899) (xy 302.580117 -68.967651) (xy 302.552862 -68.968112) (xy 302.525493 -68.967607)
			(xy 302.471316 -68.959798) (xy 302.418813 -68.944318) (xy 302.369066 -68.921485) (xy 302.323097 -68.891769)
			(xy 302.302164 -68.874132) (xy 302.30191 -68.873878) (xy 302.294827 -68.868287) (xy 302.277907 -68.862044)
			(xy 302.26889 -68.861686) (xy 302.201834 -68.861686) (xy 302.192819 -68.862062) (xy 302.175902 -68.868297)
			(xy 302.168814 -68.873878) (xy 302.168814 -68.874132) (xy 302.16856 -68.874132) (xy 302.14762 -68.891761)
			(xy 302.101649 -68.921474) (xy 302.051903 -68.944311) (xy 301.999405 -68.959804) (xy 301.945231 -68.967636)
			(xy 301.917862 -68.968112) (xy 301.891547 -68.967666) (xy 301.839418 -68.960426) (xy 301.788775 -68.946103)
			(xy 301.740576 -68.924966) (xy 301.695733 -68.897417) (xy 301.655094 -68.863975) (xy 301.636938 -68.844922)
			(xy 301.629401 -68.837538) (xy 301.610133 -68.829003) (xy 301.5996 -68.828412) (xy 301.524924 -68.828412)
			(xy 301.514374 -68.828937) (xy 301.495078 -68.837475) (xy 301.487586 -68.844922) (xy 301.469435 -68.863982)
			(xy 301.428803 -68.897437) (xy 301.383962 -68.924995) (xy 301.335761 -68.946133) (xy 301.285113 -68.96045)
			(xy 301.232978 -68.967674) (xy 301.206662 -68.968112) (xy 301.17941 -68.967658) (xy 301.125461 -68.959896)
			(xy 301.073166 -68.944536) (xy 301.023589 -68.921891) (xy 300.977739 -68.892421) (xy 300.936549 -68.856726)
			(xy 300.900859 -68.815534) (xy 300.871393 -68.769681) (xy 300.848752 -68.720102) (xy 300.833397 -68.667805)
			(xy 300.82564 -68.613856) (xy 300.825154 -68.586604) (xy 282.439216 -68.586604) (xy 282.455692 -68.622491)
			(xy 282.471186 -68.674988) (xy 282.479019 -68.729162) (xy 282.479496 -68.75653) (xy 282.47905 -68.783783)
			(xy 282.471289 -68.837732) (xy 282.45593 -68.890029) (xy 282.433284 -68.939607) (xy 282.403814 -68.985457)
			(xy 282.368118 -69.026648) (xy 282.326924 -69.062339) (xy 282.28107 -69.091804) (xy 282.231489 -69.114444)
			(xy 282.179191 -69.129798) (xy 282.125241 -69.137553) (xy 282.097988 -69.138038) (xy 282.071673 -69.137598)
			(xy 282.019542 -69.130361) (xy 281.968898 -69.116037) (xy 281.920699 -69.0949) (xy 281.875856 -69.067348)
			(xy 281.835219 -69.033903) (xy 281.817064 -69.014848) (xy 281.809551 -69.007436) (xy 281.790265 -68.998916)
			(xy 281.779726 -68.998338) (xy 281.70505 -68.998338) (xy 281.6945 -68.998869) (xy 281.675204 -69.007402)
			(xy 281.667712 -69.014848) (xy 281.649553 -69.0339) (xy 281.608923 -69.067356) (xy 281.564083 -69.094914)
			(xy 281.515883 -69.116053) (xy 281.465237 -69.130371) (xy 281.413104 -69.137598) (xy 281.386788 -69.138038)
			(xy 281.359417 -69.137594) (xy 281.305236 -69.129773) (xy 281.252732 -69.11428) (xy 281.202986 -69.091433)
			(xy 281.15702 -69.061702) (xy 281.13609 -69.044058) (xy 281.135836 -69.043804) (xy 281.128743 -69.038227)
			(xy 281.111831 -69.031974) (xy 281.102816 -69.031612) (xy 281.03576 -69.031612) (xy 281.026741 -69.031947)
			(xy 281.009824 -69.03821) (xy 281.00274 -69.043804) (xy 281.00274 -69.044058) (xy 281.002486 -69.044058)
			(xy 280.981527 -69.061664) (xy 280.935562 -69.091382) (xy 280.885822 -69.114225) (xy 280.833327 -69.129724)
			(xy 280.779155 -69.13756) (xy 280.751788 -69.138038) (xy 280.724538 -69.137533) (xy 280.670592 -69.129776)
			(xy 280.6183 -69.114421) (xy 280.568724 -69.091781) (xy 280.522876 -69.062316) (xy 280.481686 -69.026626)
			(xy 280.445995 -68.985439) (xy 280.416528 -68.939591) (xy 280.393885 -68.890017) (xy 280.378528 -68.837725)
			(xy 280.370768 -68.78378) (xy 280.37028 -68.75653) (xy 276.894175 -68.75653) (xy 276.888174 -68.769671)
			(xy 276.858708 -68.815521) (xy 276.823018 -68.856711) (xy 276.781829 -68.892402) (xy 276.73598 -68.921869)
			(xy 276.686404 -68.944511) (xy 276.634111 -68.959867) (xy 276.580165 -68.967625) (xy 276.552914 -68.968112)
			(xy 276.525544 -68.967635) (xy 276.471366 -68.959819) (xy 276.418863 -68.944333) (xy 276.369116 -68.921493)
			(xy 276.323148 -68.891772) (xy 276.302216 -68.874132) (xy 276.301962 -68.873878) (xy 276.294864 -68.868309)
			(xy 276.277956 -68.862052) (xy 276.268942 -68.861686) (xy 276.201886 -68.861686) (xy 276.192869 -68.86204)
			(xy 276.175952 -68.86829) (xy 276.168866 -68.873878) (xy 276.168866 -68.874132) (xy 276.168612 -68.874132)
			(xy 276.14769 -68.891784) (xy 276.101714 -68.921493) (xy 276.051964 -68.944326) (xy 275.999461 -68.959814)
			(xy 275.945284 -68.967639) (xy 275.917914 -68.968112) (xy 275.891601 -68.967631) (xy 275.839473 -68.960399)
			(xy 275.78883 -68.946082) (xy 275.740631 -68.924952) (xy 275.695788 -68.897408) (xy 275.655147 -68.863972)
			(xy 275.63699 -68.844922) (xy 275.629471 -68.837517) (xy 275.610189 -68.828994) (xy 275.599652 -68.828412)
			(xy 275.524976 -68.828412) (xy 275.514429 -68.828965) (xy 275.495133 -68.837483) (xy 275.487638 -68.844922)
			(xy 275.46951 -68.864005) (xy 275.428874 -68.897459) (xy 275.384028 -68.925014) (xy 275.335822 -68.946147)
			(xy 275.285169 -68.960459) (xy 275.233032 -68.967677) (xy 275.206714 -68.968112) (xy 275.179462 -68.967632)
			(xy 275.125512 -68.959877) (xy 275.073214 -68.944523) (xy 275.023634 -68.921882) (xy 274.977781 -68.892416)
			(xy 274.936589 -68.856724) (xy 274.900895 -68.815533) (xy 274.871427 -68.769681) (xy 274.848784 -68.720103)
			(xy 274.833427 -68.667806) (xy 274.82567 -68.613856) (xy 274.825206 -68.586604) (xy 256.439261 -68.586604)
			(xy 256.455741 -68.622493) (xy 256.471238 -68.674989) (xy 256.479071 -68.729162) (xy 256.479548 -68.75653)
			(xy 256.47905 -68.78378) (xy 256.471291 -68.837725) (xy 256.455934 -68.890017) (xy 256.433292 -68.939592)
			(xy 256.403826 -68.98544) (xy 256.368136 -69.026629) (xy 256.326948 -69.06232) (xy 256.281101 -69.091787)
			(xy 256.231527 -69.11443) (xy 256.179235 -69.129789) (xy 256.12529 -69.13755) (xy 256.09804 -69.138038)
			(xy 256.071724 -69.13763) (xy 256.019592 -69.130386) (xy 255.968947 -69.116057) (xy 255.920748 -69.094913)
			(xy 255.875906 -69.067355) (xy 255.83527 -69.033905) (xy 255.817116 -69.014848) (xy 255.809584 -69.007459)
			(xy 255.790312 -68.998926) (xy 255.779778 -68.998338) (xy 255.705102 -68.998338) (xy 255.694549 -68.998843)
			(xy 255.675253 -69.007394) (xy 255.667764 -69.014848) (xy 255.649628 -69.033923) (xy 255.608993 -69.067377)
			(xy 255.564148 -69.094932) (xy 255.515944 -69.116067) (xy 255.465294 -69.13038) (xy 255.413157 -69.137601)
			(xy 255.38684 -69.138038) (xy 255.35947 -69.137564) (xy 255.305291 -69.12975) (xy 255.252787 -69.114264)
			(xy 255.20304 -69.091424) (xy 255.157073 -69.061699) (xy 255.136142 -69.044058) (xy 255.135888 -69.043804)
			(xy 255.128809 -69.038207) (xy 255.111886 -69.031966) (xy 255.102868 -69.031612) (xy 255.035812 -69.031612)
			(xy 255.026795 -69.031972) (xy 255.009878 -69.038217) (xy 255.002792 -69.043804) (xy 255.002792 -69.044058)
			(xy 255.002538 -69.044058) (xy 254.981597 -69.061686) (xy 254.935627 -69.091401) (xy 254.885882 -69.11424)
			(xy 254.833383 -69.129733) (xy 254.779209 -69.137563) (xy 254.75184 -69.138038) (xy 254.724589 -69.137508)
			(xy 254.670643 -69.129757) (xy 254.618348 -69.114407) (xy 254.56877 -69.091772) (xy 254.522918 -69.062311)
			(xy 254.481726 -69.026624) (xy 254.446031 -68.985438) (xy 254.416562 -68.939592) (xy 254.393917 -68.890018)
			(xy 254.378558 -68.837726) (xy 254.370797 -68.78378) (xy 254.370332 -68.75653) (xy 250.894299 -68.75653)
			(xy 250.888286 -68.769696) (xy 250.858815 -68.81555) (xy 250.823117 -68.856744) (xy 250.78192 -68.892437)
			(xy 250.736062 -68.921904) (xy 250.686478 -68.944545) (xy 250.634175 -68.959898) (xy 250.580221 -68.967651)
			(xy 250.552966 -68.968112) (xy 250.525595 -68.967663) (xy 250.471416 -68.959841) (xy 250.418912 -68.944347)
			(xy 250.369166 -68.921502) (xy 250.323199 -68.891774) (xy 250.302268 -68.874132) (xy 250.302014 -68.873878)
			(xy 250.294929 -68.868289) (xy 250.278011 -68.862044) (xy 250.268994 -68.861686) (xy 250.201938 -68.861686)
			(xy 250.192923 -68.862064) (xy 250.176006 -68.868297) (xy 250.168918 -68.873878) (xy 250.168918 -68.874132)
			(xy 250.168664 -68.874132) (xy 250.147723 -68.89176) (xy 250.101752 -68.921472) (xy 250.052007 -68.94431)
			(xy 249.999508 -68.959804) (xy 249.945334 -68.967636) (xy 249.917966 -68.968112) (xy 249.891651 -68.967663)
			(xy 249.839522 -68.960424) (xy 249.788879 -68.946101) (xy 249.740681 -68.924965) (xy 249.695837 -68.897416)
			(xy 249.655198 -68.863975) (xy 249.637042 -68.844922) (xy 249.629504 -68.83754) (xy 249.610236 -68.829004)
			(xy 249.599704 -68.828412) (xy 249.525028 -68.828412) (xy 249.514478 -68.828939) (xy 249.495182 -68.837475)
			(xy 249.48769 -68.844922) (xy 249.469537 -68.86398) (xy 249.428906 -68.897436) (xy 249.384065 -68.924994)
			(xy 249.335864 -68.946132) (xy 249.285216 -68.960449) (xy 249.233082 -68.967673) (xy 249.206766 -68.968112)
			(xy 249.179514 -68.967654) (xy 249.125566 -68.959893) (xy 249.073271 -68.944534) (xy 249.023693 -68.921889)
			(xy 248.977843 -68.892419) (xy 248.936654 -68.856725) (xy 248.900963 -68.815532) (xy 248.871497 -68.76968)
			(xy 248.848856 -68.720101) (xy 248.833501 -68.667805) (xy 248.825744 -68.613856) (xy 248.825258 -68.586604)
			(xy 233.739526 -68.586604) (xy 233.737959 -68.596699) (xy 233.741732 -68.625448) (xy 233.753425 -68.651981)
			(xy 233.772095 -68.674166) (xy 233.783886 -68.682616) (xy 233.805969 -68.697829) (xy 233.846022 -68.733483)
			(xy 233.880685 -68.774397) (xy 233.909274 -68.819765) (xy 233.931223 -68.86869) (xy 233.9461 -68.920209)
			(xy 233.953611 -68.973304) (xy 233.954066 -69.000116) (xy 233.95358 -69.027367) (xy 233.945824 -69.081315)
			(xy 233.930469 -69.13361) (xy 233.907827 -69.183187) (xy 233.878361 -69.229037) (xy 233.84267 -69.270228)
			(xy 233.801479 -69.305919) (xy 233.755629 -69.335385) (xy 233.706052 -69.358027) (xy 233.653757 -69.373382)
			(xy 233.599809 -69.381138) (xy 233.545307 -69.381138) (xy 233.491359 -69.373382) (xy 233.439064 -69.358027)
			(xy 233.389487 -69.335385) (xy 233.343637 -69.305919) (xy 233.302446 -69.270228) (xy 233.266755 -69.229037)
			(xy 233.237289 -69.183187) (xy 233.214647 -69.13361) (xy 233.199292 -69.081315) (xy 233.191536 -69.027367)
			(xy 233.19105 -69.000116) (xy 231.948553 -69.000116) (xy 231.982933 -69.041602) (xy 232.038313 -69.120966)
			(xy 232.086942 -69.204637) (xy 232.128488 -69.292041) (xy 232.162665 -69.382581) (xy 232.189239 -69.475637)
			(xy 232.20803 -69.570571) (xy 232.218907 -69.666733) (xy 232.221798 -69.763466) (xy 232.216681 -69.860106)
			(xy 232.203592 -69.955993) (xy 232.18262 -70.050469) (xy 232.15391 -70.142888) (xy 232.117657 -70.232617)
			(xy 232.074111 -70.319042) (xy 232.023568 -70.401571) (xy 231.966375 -70.479638) (xy 231.93502 -70.516496)
			(xy 231.934004 -70.517512) (xy 231.928924 -70.523608) (xy 231.921812 -70.542404) (xy 231.921558 -70.542912)
			(xy 231.918002 -70.55231) (xy 231.918002 -70.561962) (xy 231.918211 -70.567209) (xy 231.920513 -70.577452)
			(xy 231.922574 -70.582282) (xy 231.958896 -70.662292) (xy 231.959404 -70.663562) (xy 231.959912 -70.66407)
			(xy 231.964471 -70.672268) (xy 231.978302 -70.684917) (xy 231.995755 -70.691749) (xy 232.005124 -70.692264)
			(xy 233.704384 -70.692264) (xy 233.732578 -70.668896) (xy 233.73588 -70.650862) (xy 233.743739 -70.611828)
			(xy 233.76616 -70.53542) (xy 233.796014 -70.461599) (xy 233.833009 -70.391085) (xy 233.876784 -70.324567)
			(xy 233.926911 -70.262696) (xy 233.982901 -70.206074) (xy 234.044207 -70.155257) (xy 234.110229 -70.110739)
			(xy 234.180324 -70.072956) (xy 234.253806 -70.042276) (xy 234.329958 -70.019) (xy 234.408035 -70.003355)
			(xy 234.487275 -69.995494) (xy 234.52709 -69.995034) (xy 234.568879 -69.995566) (xy 234.652007 -70.004225)
			(xy 234.73379 -70.021451) (xy 234.813348 -70.047058) (xy 234.889825 -70.080771) (xy 234.953167 -70.116954)
			(xy 239.652554 -70.116954) (xy 239.656625 -70.061332) (xy 239.668751 -70.006895) (xy 239.688674 -69.954804)
			(xy 239.71597 -69.906169) (xy 239.750056 -69.862026) (xy 239.790205 -69.823317) (xy 239.835563 -69.790866)
			(xy 239.885163 -69.765365) (xy 239.937947 -69.747358) (xy 239.99279 -69.737228) (xy 240.048524 -69.735191)
			(xy 240.103961 -69.741291) (xy 240.157918 -69.755397) (xy 240.209247 -69.777209) (xy 240.256853 -69.806263)
			(xy 240.299721 -69.841938) (xy 240.336938 -69.883475) (xy 240.367711 -69.929988) (xy 240.391383 -69.980485)
			(xy 240.407451 -70.033892) (xy 240.415571 -70.089068) (xy 240.41608 -70.116954) (xy 240.415571 -70.14484)
			(xy 240.407451 -70.200016) (xy 240.391383 -70.253423) (xy 240.367711 -70.30392) (xy 240.336938 -70.350433)
			(xy 240.299721 -70.39197) (xy 240.256853 -70.427645) (xy 240.209247 -70.456699) (xy 240.157918 -70.478511)
			(xy 240.103961 -70.492617) (xy 240.048524 -70.498717) (xy 239.99279 -70.49668) (xy 239.937947 -70.48655)
			(xy 239.885163 -70.468543) (xy 239.835563 -70.443042) (xy 239.790205 -70.410591) (xy 239.750056 -70.371882)
			(xy 239.71597 -70.327739) (xy 239.688674 -70.279104) (xy 239.668751 -70.227013) (xy 239.656625 -70.172576)
			(xy 239.652554 -70.116954) (xy 234.953167 -70.116954) (xy 234.962396 -70.122226) (xy 235.030282 -70.170979)
			(xy 235.092751 -70.226502) (xy 235.14913 -70.2882) (xy 235.198813 -70.355408) (xy 235.241264 -70.427402)
			(xy 235.259118 -70.465188) (xy 235.260134 -70.46722) (xy 235.274527 -70.496481) (xy 235.298706 -70.557047)
			(xy 235.317454 -70.619508) (xy 235.324396 -70.65137) (xy 235.324396 -70.652132) (xy 235.326559 -70.660549)
			(xy 235.335652 -70.675345) (xy 235.342176 -70.681088) (xy 235.34878 -70.686422) (xy 235.365036 -70.692264)
			(xy 238.844328 -70.692264) (xy 238.850146 -70.691696) (xy 238.861308 -70.688231) (xy 238.866426 -70.685406)
			(xy 238.887508 -70.672706) (xy 238.896398 -70.666102) (xy 238.901224 -70.66153) (xy 238.904526 -70.655942)
			(xy 238.919569 -70.632726) (xy 238.955291 -70.590486) (xy 238.996735 -70.553842) (xy 239.043032 -70.523563)
			(xy 239.093213 -70.50028) (xy 239.146229 -70.484482) (xy 239.20097 -70.4765) (xy 239.25629 -70.4765)
			(xy 239.311031 -70.484482) (xy 239.364047 -70.50028) (xy 239.414228 -70.523563) (xy 239.460525 -70.553842)
			(xy 239.501969 -70.590486) (xy 239.537691 -70.632726) (xy 239.552734 -70.655942) (xy 239.556036 -70.66153)
			(xy 239.560862 -70.666102) (xy 239.569752 -70.672706) (xy 239.590326 -70.685152) (xy 239.595548 -70.688085)
			(xy 239.606971 -70.691675) (xy 239.612932 -70.692264) (xy 253.553976 -70.692264) (xy 253.563651 -70.691694)
			(xy 253.581529 -70.68425) (xy 253.595381 -70.670717) (xy 253.599696 -70.662038) (xy 253.600458 -70.660006)
			(xy 253.61065 -70.635086) (xy 253.637034 -70.588156) (xy 253.669756 -70.545402) (xy 253.708165 -70.507674)
			(xy 253.751498 -70.475723) (xy 253.798894 -70.450184) (xy 253.84941 -70.431563) (xy 253.902043 -70.420232)
			(xy 253.955747 -70.416415) (xy 254.009453 -70.420189) (xy 254.062095 -70.431478) (xy 254.112626 -70.450058)
			(xy 254.160043 -70.475559) (xy 254.203401 -70.507475) (xy 254.241841 -70.545172) (xy 254.274597 -70.587899)
			(xy 254.301018 -70.634809) (xy 254.31115 -70.659752) (xy 254.31115 -70.66026) (xy 254.314228 -70.667243)
			(xy 254.323777 -70.679137) (xy 254.329946 -70.683628) (xy 254.336042 -70.687946) (xy 254.35052 -70.692264)
			(xy 270.183356 -70.692264) (xy 270.19342 -70.692699) (xy 270.212004 -70.700435) (xy 270.219424 -70.70725)
			(xy 271.068038 -71.555864) (xy 277.394414 -71.555864) (xy 277.398485 -71.500242) (xy 277.410611 -71.445805)
			(xy 277.430534 -71.393714) (xy 277.45783 -71.345079) (xy 277.491916 -71.300936) (xy 277.532065 -71.262227)
			(xy 277.577423 -71.229776) (xy 277.627023 -71.204275) (xy 277.679807 -71.186268) (xy 277.73465 -71.176138)
			(xy 277.790384 -71.174101) (xy 277.845821 -71.180201) (xy 277.899778 -71.194307) (xy 277.951107 -71.216119)
			(xy 277.998713 -71.245173) (xy 278.041581 -71.280848) (xy 278.078798 -71.322385) (xy 278.109571 -71.368898)
			(xy 278.133243 -71.419395) (xy 278.149311 -71.472802) (xy 278.157431 -71.527978) (xy 278.15794 -71.555864)
			(xy 278.157431 -71.58375) (xy 278.151592 -71.623428) (xy 278.903428 -71.623428) (xy 278.907499 -71.567806)
			(xy 278.919625 -71.513369) (xy 278.939548 -71.461278) (xy 278.966844 -71.412643) (xy 279.00093 -71.3685)
			(xy 279.041079 -71.329791) (xy 279.086437 -71.29734) (xy 279.136037 -71.271839) (xy 279.188821 -71.253832)
			(xy 279.243664 -71.243702) (xy 279.299398 -71.241665) (xy 279.354835 -71.247765) (xy 279.408792 -71.261871)
			(xy 279.460121 -71.283683) (xy 279.507727 -71.312737) (xy 279.550595 -71.348412) (xy 279.587812 -71.389949)
			(xy 279.618585 -71.436462) (xy 279.642257 -71.486959) (xy 279.658325 -71.540366) (xy 279.660606 -71.555864)
			(xy 303.394362 -71.555864) (xy 303.398433 -71.500242) (xy 303.410559 -71.445805) (xy 303.430482 -71.393714)
			(xy 303.457778 -71.345079) (xy 303.491864 -71.300936) (xy 303.532013 -71.262227) (xy 303.577371 -71.229776)
			(xy 303.626971 -71.204275) (xy 303.679755 -71.186268) (xy 303.734598 -71.176138) (xy 303.790332 -71.174101)
			(xy 303.845769 -71.180201) (xy 303.899726 -71.194307) (xy 303.951055 -71.216119) (xy 303.998661 -71.245173)
			(xy 304.041529 -71.280848) (xy 304.078746 -71.322385) (xy 304.109519 -71.368898) (xy 304.133191 -71.419395)
			(xy 304.149259 -71.472802) (xy 304.157379 -71.527978) (xy 304.157888 -71.555864) (xy 304.157379 -71.58375)
			(xy 304.15154 -71.623428) (xy 304.903376 -71.623428) (xy 304.907447 -71.567806) (xy 304.919573 -71.513369)
			(xy 304.939496 -71.461278) (xy 304.966792 -71.412643) (xy 305.000878 -71.3685) (xy 305.041027 -71.329791)
			(xy 305.086385 -71.29734) (xy 305.135985 -71.271839) (xy 305.188769 -71.253832) (xy 305.243612 -71.243702)
			(xy 305.299346 -71.241665) (xy 305.354783 -71.247765) (xy 305.40874 -71.261871) (xy 305.460069 -71.283683)
			(xy 305.507675 -71.312737) (xy 305.550543 -71.348412) (xy 305.58776 -71.389949) (xy 305.618533 -71.436462)
			(xy 305.642205 -71.486959) (xy 305.658273 -71.540366) (xy 305.666393 -71.595542) (xy 305.666902 -71.623428)
			(xy 305.666393 -71.651314) (xy 305.658273 -71.70649) (xy 305.642205 -71.759897) (xy 305.618533 -71.810394)
			(xy 305.58776 -71.856907) (xy 305.550543 -71.898444) (xy 305.507675 -71.934119) (xy 305.460069 -71.963173)
			(xy 305.40874 -71.984985) (xy 305.354783 -71.999091) (xy 305.299346 -72.005191) (xy 305.243612 -72.003154)
			(xy 305.188769 -71.993024) (xy 305.135985 -71.975017) (xy 305.086385 -71.949516) (xy 305.041027 -71.917065)
			(xy 305.000878 -71.878356) (xy 304.966792 -71.834213) (xy 304.939496 -71.785578) (xy 304.919573 -71.733487)
			(xy 304.907447 -71.67905) (xy 304.903376 -71.623428) (xy 304.15154 -71.623428) (xy 304.149259 -71.638926)
			(xy 304.133191 -71.692333) (xy 304.109519 -71.74283) (xy 304.078746 -71.789343) (xy 304.041529 -71.83088)
			(xy 303.998661 -71.866555) (xy 303.951055 -71.895609) (xy 303.899726 -71.917421) (xy 303.845769 -71.931527)
			(xy 303.790332 -71.937627) (xy 303.734598 -71.93559) (xy 303.679755 -71.92546) (xy 303.626971 -71.907453)
			(xy 303.577371 -71.881952) (xy 303.532013 -71.849501) (xy 303.491864 -71.810792) (xy 303.457778 -71.766649)
			(xy 303.430482 -71.718014) (xy 303.410559 -71.665923) (xy 303.398433 -71.611486) (xy 303.394362 -71.555864)
			(xy 279.660606 -71.555864) (xy 279.666445 -71.595542) (xy 279.666954 -71.623428) (xy 279.666445 -71.651314)
			(xy 279.658325 -71.70649) (xy 279.642257 -71.759897) (xy 279.618585 -71.810394) (xy 279.587812 -71.856907)
			(xy 279.550595 -71.898444) (xy 279.507727 -71.934119) (xy 279.460121 -71.963173) (xy 279.408792 -71.984985)
			(xy 279.354835 -71.999091) (xy 279.299398 -72.005191) (xy 279.243664 -72.003154) (xy 279.188821 -71.993024)
			(xy 279.136037 -71.975017) (xy 279.086437 -71.949516) (xy 279.041079 -71.917065) (xy 279.00093 -71.878356)
			(xy 278.966844 -71.834213) (xy 278.939548 -71.785578) (xy 278.919625 -71.733487) (xy 278.907499 -71.67905)
			(xy 278.903428 -71.623428) (xy 278.151592 -71.623428) (xy 278.149311 -71.638926) (xy 278.133243 -71.692333)
			(xy 278.109571 -71.74283) (xy 278.078798 -71.789343) (xy 278.041581 -71.83088) (xy 277.998713 -71.866555)
			(xy 277.951107 -71.895609) (xy 277.899778 -71.917421) (xy 277.845821 -71.931527) (xy 277.790384 -71.937627)
			(xy 277.73465 -71.93559) (xy 277.679807 -71.92546) (xy 277.627023 -71.907453) (xy 277.577423 -71.881952)
			(xy 277.532065 -71.849501) (xy 277.491916 -71.810792) (xy 277.45783 -71.766649) (xy 277.430534 -71.718014)
			(xy 277.410611 -71.665923) (xy 277.398485 -71.611486) (xy 277.394414 -71.555864) (xy 271.068038 -71.555864)
			(xy 273.783806 -74.271632) (xy 273.792442 -74.275442) (xy 273.817917 -74.287283) (xy 273.865376 -74.317339)
			(xy 273.907915 -74.354029) (xy 273.944614 -74.39656) (xy 273.974679 -74.444013) (xy 273.986498 -74.469498)
			(xy 273.990308 -74.478134) (xy 274.675854 -75.163426) (xy 274.679622 -75.16704) (xy 274.688325 -75.172804)
			(xy 274.693126 -75.174856) (xy 310.816498 -75.174856) (xy 310.821301 -75.172808) (xy 310.830007 -75.167046)
			(xy 310.83377 -75.163426) (xy 311.025794 -74.971402) (xy 311.033192 -74.964554) (xy 311.05179 -74.956817)
			(xy 311.061862 -74.956416) (xy 317.559944 -74.956416) (xy 317.57001 -74.956848) (xy 317.588602 -74.964575)
			(xy 317.596012 -74.971402) (xy 319.51803 -76.89342) (xy 320.334892 -76.89342) (xy 320.338963 -76.837798)
			(xy 320.351089 -76.783361) (xy 320.371012 -76.73127) (xy 320.398308 -76.682635) (xy 320.432394 -76.638492)
			(xy 320.472543 -76.599783) (xy 320.517901 -76.567332) (xy 320.567501 -76.541831) (xy 320.620285 -76.523824)
			(xy 320.675128 -76.513694) (xy 320.730862 -76.511657) (xy 320.786299 -76.517757) (xy 320.840256 -76.531863)
			(xy 320.891585 -76.553675) (xy 320.939191 -76.582729) (xy 320.982059 -76.618404) (xy 321.019276 -76.659941)
			(xy 321.050049 -76.706454) (xy 321.073721 -76.756951) (xy 321.089789 -76.810358) (xy 321.097909 -76.865534)
			(xy 321.098418 -76.89342) (xy 321.097909 -76.921306) (xy 321.089789 -76.976482) (xy 321.073721 -77.029889)
			(xy 321.050049 -77.080386) (xy 321.019276 -77.126899) (xy 320.982059 -77.168436) (xy 320.939191 -77.204111)
			(xy 320.891585 -77.233165) (xy 320.840256 -77.254977) (xy 320.786299 -77.269083) (xy 320.730862 -77.275183)
			(xy 320.675128 -77.273146) (xy 320.620285 -77.263016) (xy 320.567501 -77.245009) (xy 320.517901 -77.219508)
			(xy 320.472543 -77.187057) (xy 320.432394 -77.148348) (xy 320.398308 -77.104205) (xy 320.371012 -77.05557)
			(xy 320.351089 -77.003479) (xy 320.338963 -76.949042) (xy 320.334892 -76.89342) (xy 319.51803 -76.89342)
			(xy 320.14033 -77.51572) (xy 320.146674 -77.52161) (xy 320.162254 -77.529128) (xy 320.17081 -77.530452)
			(xy 320.173604 -77.530706) (xy 321.086734 -77.530706) (xy 321.09156 -77.530452) (xy 321.091814 -77.530452)
			(xy 321.098541 -77.529496) (xy 321.111162 -77.524475) (xy 321.116706 -77.520546) (xy 321.12204 -77.515974)
			(xy 321.44335 -77.194664) (xy 321.449246 -77.188323) (xy 321.456773 -77.172743) (xy 321.458082 -77.164184)
			(xy 321.458336 -77.16139) (xy 321.458336 -76.918312) (xy 321.457828 -76.9112) (xy 321.455288 -76.897738)
			(xy 321.454018 -76.892658) (xy 321.453002 -76.890372) (xy 321.452494 -76.889356) (xy 321.452494 -76.889102)
			(xy 321.440733 -76.85662) (xy 321.427824 -76.78876) (xy 321.42684 -76.754228) (xy 321.42684 -76.743814)
			(xy 321.427972 -76.71287) (xy 321.439022 -76.651947) (xy 321.459778 -76.593612) (xy 321.489693 -76.5394)
			(xy 321.508374 -76.514706) (xy 321.513708 -76.507848) (xy 321.516502 -76.499974) (xy 321.51779 -76.495967)
			(xy 321.519203 -76.487671) (xy 321.519296 -76.483464) (xy 321.519296 -76.458318) (xy 321.519388 -76.454375)
			(xy 321.520673 -76.446593) (xy 321.521836 -76.442824) (xy 321.526662 -76.42733) (xy 321.527967 -76.423136)
			(xy 321.529251 -76.414449) (xy 321.529202 -76.410058) (xy 321.528694 -76.397104) (xy 321.527932 -76.389992)
			(xy 314.031884 -68.893944) (xy 314.02827 -68.890505) (xy 314.019956 -68.884994) (xy 314.015374 -68.883022)
			(xy 310.115458 -67.267328) (xy 310.110723 -67.269083) (xy 310.102022 -67.274204) (xy 310.098186 -67.277488)
			(xy 310.096408 -67.279012) (xy 310.065928 -67.30873) (xy 310.0578 -67.316858) (xy 310.050855 -67.32415)
			(xy 310.042866 -67.342617) (xy 310.042306 -67.352672) (xy 310.042306 -67.366134) (xy 310.047132 -67.378834)
			(xy 310.050434 -67.387724) (xy 310.059272 -67.411666) (xy 310.071707 -67.461164) (xy 310.077988 -67.511812)
			(xy 310.078374 -67.53733) (xy 310.078374 -67.537838) (xy 310.077842 -67.567536) (xy 310.069383 -67.626327)
			(xy 310.052645 -67.683316) (xy 310.027966 -67.737343) (xy 309.99585 -67.787308) (xy 309.95695 -67.832194)
			(xy 309.912058 -67.871087) (xy 309.862089 -67.903196) (xy 309.808058 -67.927866) (xy 309.751067 -67.944597)
			(xy 309.692274 -67.953046) (xy 309.662576 -67.953636) (xy 309.634112 -67.95317) (xy 309.577715 -67.945414)
			(xy 309.522899 -67.93005) (xy 309.470686 -67.907364) (xy 309.42205 -67.877778) (xy 309.399686 -67.860164)
			(xy 309.393082 -67.85483) (xy 309.36819 -67.845432) (xy 309.364121 -67.844136) (xy 309.355696 -67.842738)
			(xy 309.351426 -67.842638) (xy 309.338726 -67.842638) (xy 309.334453 -67.8427) (xy 309.326026 -67.844109)
			(xy 309.321962 -67.845432) (xy 309.29707 -67.85483) (xy 309.290466 -67.860164) (xy 309.268125 -67.87777)
			(xy 309.219544 -67.907359) (xy 309.167385 -67.930052) (xy 309.11262 -67.945426) (xy 309.056271 -67.953194)
			(xy 309.02783 -67.953636) (xy 309.027576 -67.953636) (xy 308.997876 -67.953105) (xy 308.93908 -67.944648)
			(xy 308.882085 -67.927911) (xy 308.828053 -67.903235) (xy 308.778082 -67.87112) (xy 308.733189 -67.832221)
			(xy 308.694289 -67.78733) (xy 308.662172 -67.73736) (xy 308.637493 -67.683328) (xy 308.620755 -67.626334)
			(xy 308.612296 -67.567538) (xy 308.611778 -67.537838) (xy 308.61221 -67.510485) (xy 308.619378 -67.45625)
			(xy 308.633597 -67.403424) (xy 308.65462 -67.352919) (xy 308.682084 -67.305606) (xy 308.715515 -67.262303)
			(xy 308.754336 -67.223758) (xy 308.775862 -67.206876) (xy 308.78018 -67.203574) (xy 308.78526 -67.197478)
			(xy 308.791995 -67.187683) (xy 308.796496 -67.164373) (xy 308.793896 -67.152774) (xy 308.761892 -67.057778)
			(xy 308.759579 -67.051923) (xy 308.752514 -67.041509) (xy 308.747922 -67.037204) (xy 303.647602 -67.037204)
			(xy 303.64299 -67.041458) (xy 303.635802 -67.051737) (xy 303.633378 -67.057524) (xy 303.616868 -67.101466)
			(xy 303.616868 -67.101974) (xy 303.59985 -67.145662) (xy 303.598464 -67.149781) (xy 303.596935 -67.158336)
			(xy 303.596802 -67.16268) (xy 303.596802 -67.16395) (xy 303.597119 -67.172141) (xy 303.602314 -67.187677)
			(xy 303.606962 -67.19443) (xy 303.61001 -67.198494) (xy 303.61382 -67.20205) (xy 303.633684 -67.220236)
			(xy 303.668608 -67.261233) (xy 303.697421 -67.306733) (xy 303.71955 -67.355831) (xy 303.734557 -67.407554)
			(xy 303.742143 -67.460872) (xy 303.742598 -67.4878) (xy 303.742598 -67.499992) (xy 303.74209 -67.50685)
			(xy 303.74209 -67.507358) (xy 303.740077 -67.536302) (xy 303.739813 -67.537584) (xy 304.27117 -67.537584)
			(xy 304.275241 -67.481962) (xy 304.287367 -67.427525) (xy 304.30729 -67.375434) (xy 304.334586 -67.326799)
			(xy 304.368672 -67.282656) (xy 304.408821 -67.243947) (xy 304.454179 -67.211496) (xy 304.503779 -67.185995)
			(xy 304.556563 -67.167988) (xy 304.611406 -67.157858) (xy 304.66714 -67.155821) (xy 304.722577 -67.161921)
			(xy 304.776534 -67.176027) (xy 304.827863 -67.197839) (xy 304.875469 -67.226893) (xy 304.918337 -67.262568)
			(xy 304.955554 -67.304105) (xy 304.986327 -67.350618) (xy 305.009999 -67.401115) (xy 305.026067 -67.454522)
			(xy 305.034187 -67.509698) (xy 305.034696 -67.537584) (xy 305.034187 -67.56547) (xy 305.030142 -67.592956)
			(xy 305.545234 -67.592956) (xy 305.549305 -67.537334) (xy 305.561431 -67.482897) (xy 305.581354 -67.430806)
			(xy 305.60865 -67.382171) (xy 305.642736 -67.338028) (xy 305.682885 -67.299319) (xy 305.728243 -67.266868)
			(xy 305.777843 -67.241367) (xy 305.830627 -67.22336) (xy 305.88547 -67.21323) (xy 305.941204 -67.211193)
			(xy 305.996641 -67.217293) (xy 306.050598 -67.231399) (xy 306.101927 -67.253211) (xy 306.149533 -67.282265)
			(xy 306.192401 -67.31794) (xy 306.229618 -67.359477) (xy 306.260391 -67.40599) (xy 306.284063 -67.456487)
			(xy 306.300131 -67.509894) (xy 306.308251 -67.56507) (xy 306.30876 -67.592956) (xy 306.308251 -67.620842)
			(xy 306.300131 -67.676018) (xy 306.284063 -67.729425) (xy 306.260391 -67.779922) (xy 306.229618 -67.826435)
			(xy 306.192401 -67.867972) (xy 306.149533 -67.903647) (xy 306.101927 -67.932701) (xy 306.050598 -67.954513)
			(xy 305.996641 -67.968619) (xy 305.941204 -67.974719) (xy 305.88547 -67.972682) (xy 305.830627 -67.962552)
			(xy 305.777843 -67.944545) (xy 305.728243 -67.919044) (xy 305.682885 -67.886593) (xy 305.642736 -67.847884)
			(xy 305.60865 -67.803741) (xy 305.581354 -67.755106) (xy 305.561431 -67.703015) (xy 305.549305 -67.648578)
			(xy 305.545234 -67.592956) (xy 305.030142 -67.592956) (xy 305.026067 -67.620646) (xy 305.009999 -67.674053)
			(xy 304.986327 -67.72455) (xy 304.955554 -67.771063) (xy 304.918337 -67.8126) (xy 304.875469 -67.848275)
			(xy 304.827863 -67.877329) (xy 304.776534 -67.899141) (xy 304.722577 -67.913247) (xy 304.66714 -67.919347)
			(xy 304.611406 -67.91731) (xy 304.556563 -67.90718) (xy 304.503779 -67.889173) (xy 304.454179 -67.863672)
			(xy 304.408821 -67.831221) (xy 304.368672 -67.792512) (xy 304.334586 -67.748369) (xy 304.30729 -67.699734)
			(xy 304.287367 -67.647643) (xy 304.275241 -67.593206) (xy 304.27117 -67.537584) (xy 303.739813 -67.537584)
			(xy 303.728394 -67.59313) (xy 303.70824 -67.647533) (xy 303.68008 -67.698258) (xy 303.644565 -67.744134)
			(xy 303.602512 -67.784103) (xy 303.554892 -67.817244) (xy 303.502803 -67.842792) (xy 303.447446 -67.860157)
			(xy 303.390098 -67.868941) (xy 303.36109 -67.869562) (xy 303.333355 -67.869057) (xy 303.278471 -67.861011)
			(xy 303.225331 -67.845105) (xy 303.175052 -67.821674) (xy 303.128695 -67.791211) (xy 303.087237 -67.754358)
			(xy 303.05155 -67.711892) (xy 303.022386 -67.664707) (xy 303.00036 -67.613797) (xy 302.985936 -67.560235)
			(xy 302.982122 -67.532758) (xy 302.980598 -67.51828) (xy 302.979328 -67.488054) (xy 302.979328 -67.467734)
			(xy 302.980598 -67.455796) (xy 302.983604 -67.42682) (xy 302.997296 -67.3702) (xy 303.019451 -67.316326)
			(xy 303.049551 -67.266453) (xy 303.086894 -67.221745) (xy 303.10836 -67.20205) (xy 303.114202 -67.19697)
			(xy 303.12233 -67.183762) (xy 303.124108 -67.176142) (xy 303.125567 -67.168782) (xy 303.124661 -67.15381)
			(xy 303.12233 -67.146678) (xy 303.107598 -67.107562) (xy 303.107598 -67.107054) (xy 303.088548 -67.05727)
			(xy 303.086189 -67.051552) (xy 303.079115 -67.041409) (xy 303.074578 -67.037204) (xy 300.031404 -67.037204)
			(xy 300.03115 -67.037458) (xy 300.028102 -67.039998) (xy 300.020228 -67.047618) (xy 300.019212 -67.048634)
			(xy 300.013624 -67.053968) (xy 300.006568 -67.061418) (xy 299.998571 -67.080293) (xy 299.99813 -67.090544)
			(xy 299.99813 -67.093592) (xy 299.998384 -67.101466) (xy 299.998384 -67.101974) (xy 299.997836 -67.131661)
			(xy 299.98935 -67.190428) (xy 299.972591 -67.247389) (xy 299.947899 -67.301387) (xy 299.915777 -67.351323)
			(xy 299.876877 -67.396181) (xy 299.831992 -67.43505) (xy 299.782034 -67.467137) (xy 299.728019 -67.491792)
			(xy 299.671046 -67.508512) (xy 299.612274 -67.516956) (xy 299.582586 -67.517518) (xy 299.551076 -67.516937)
			(xy 299.488777 -67.507439) (xy 299.428619 -67.488662) (xy 299.371978 -67.461035) (xy 299.320147 -67.425188)
			(xy 299.296836 -67.40398) (xy 299.29582 -67.402964) (xy 299.282104 -67.390264) (xy 299.275071 -67.384714)
			(xy 299.258288 -67.378477) (xy 299.249338 -67.378072) (xy 299.23486 -67.378072) (xy 299.22597 -67.378834)
			(xy 299.213016 -67.38112) (xy 299.203872 -67.384422) (xy 299.19676 -67.390518) (xy 299.175884 -67.407912)
			(xy 299.130134 -67.437232) (xy 299.080686 -67.45976) (xy 299.028541 -67.475042) (xy 298.974755 -67.482767)
			(xy 298.947586 -67.483228) (xy 298.918576 -67.482685) (xy 298.861226 -67.473896) (xy 298.805869 -67.456522)
			(xy 298.753781 -67.430965) (xy 298.706165 -67.397814) (xy 298.664118 -67.357835) (xy 298.628612 -67.311948)
			(xy 298.600465 -67.261213) (xy 298.580326 -67.206801) (xy 298.56866 -67.149966) (xy 298.566586 -67.121024)
			(xy 298.566078 -67.111118) (xy 298.562014 -67.102482) (xy 298.559895 -67.098163) (xy 298.554268 -67.090361)
			(xy 298.550838 -67.086988) (xy 298.506388 -67.04457) (xy 298.50588 -67.044062) (xy 298.499022 -67.037966)
			(xy 298.49826 -67.037204) (xy 277.647654 -67.037204) (xy 277.643038 -67.041455) (xy 277.635844 -67.051732)
			(xy 277.63343 -67.057524) (xy 277.61692 -67.101466) (xy 277.61692 -67.101974) (xy 277.599902 -67.145662)
			(xy 277.598517 -67.149781) (xy 277.59699 -67.158336) (xy 277.596854 -67.16268) (xy 277.596854 -67.16395)
			(xy 277.59717 -67.172141) (xy 277.60236 -67.187681) (xy 277.607014 -67.19443) (xy 277.610062 -67.198494)
			(xy 277.613872 -67.20205) (xy 277.633734 -67.220238) (xy 277.668653 -67.261236) (xy 277.697462 -67.306736)
			(xy 277.719588 -67.355835) (xy 277.734593 -67.407556) (xy 277.742178 -67.460873) (xy 277.74265 -67.4878)
			(xy 277.74265 -67.499992) (xy 277.742142 -67.50685) (xy 277.742142 -67.507358) (xy 277.740129 -67.536303)
			(xy 277.739866 -67.537584) (xy 278.271222 -67.537584) (xy 278.275293 -67.481962) (xy 278.287419 -67.427525)
			(xy 278.307342 -67.375434) (xy 278.334638 -67.326799) (xy 278.368724 -67.282656) (xy 278.408873 -67.243947)
			(xy 278.454231 -67.211496) (xy 278.503831 -67.185995) (xy 278.556615 -67.167988) (xy 278.611458 -67.157858)
			(xy 278.667192 -67.155821) (xy 278.722629 -67.161921) (xy 278.776586 -67.176027) (xy 278.827915 -67.197839)
			(xy 278.875521 -67.226893) (xy 278.918389 -67.262568) (xy 278.955606 -67.304105) (xy 278.986379 -67.350618)
			(xy 279.010051 -67.401115) (xy 279.026119 -67.454522) (xy 279.034239 -67.509698) (xy 279.034748 -67.537584)
			(xy 279.034239 -67.56547) (xy 279.030194 -67.592956) (xy 279.545286 -67.592956) (xy 279.549357 -67.537334)
			(xy 279.561483 -67.482897) (xy 279.581406 -67.430806) (xy 279.608702 -67.382171) (xy 279.642788 -67.338028)
			(xy 279.682937 -67.299319) (xy 279.728295 -67.266868) (xy 279.777895 -67.241367) (xy 279.830679 -67.22336)
			(xy 279.885522 -67.21323) (xy 279.941256 -67.211193) (xy 279.996693 -67.217293) (xy 280.05065 -67.231399)
			(xy 280.101979 -67.253211) (xy 280.149585 -67.282265) (xy 280.192453 -67.31794) (xy 280.22967 -67.359477)
			(xy 280.260443 -67.40599) (xy 280.284115 -67.456487) (xy 280.300183 -67.509894) (xy 280.3083 -67.565051)
			(xy 282.646593 -67.565051) (xy 282.646593 -67.510549) (xy 282.65435 -67.456601) (xy 282.669706 -67.404306)
			(xy 282.692348 -67.354729) (xy 282.721816 -67.308879) (xy 282.757509 -67.267689) (xy 282.798701 -67.231999)
			(xy 282.844553 -67.202535) (xy 282.894132 -67.179896) (xy 282.946428 -67.164544) (xy 283.000377 -67.156791)
			(xy 283.027628 -67.15633) (xy 283.054999 -67.156772) (xy 283.10918 -67.164595) (xy 283.161683 -67.180089)
			(xy 283.21143 -67.202936) (xy 283.257395 -67.232666) (xy 283.278326 -67.25031) (xy 283.27858 -67.250564)
			(xy 283.285663 -67.256156) (xy 283.302583 -67.262398) (xy 283.3116 -67.262756) (xy 283.378656 -67.262756)
			(xy 283.387672 -67.262387) (xy 283.404589 -67.256149) (xy 283.411676 -67.250564) (xy 283.411676 -67.25031)
			(xy 283.41193 -67.25031) (xy 283.432879 -67.232692) (xy 283.478847 -67.202976) (xy 283.52859 -67.180136)
			(xy 283.581087 -67.16464) (xy 283.63526 -67.156807) (xy 283.662628 -67.15633) (xy 283.689881 -67.156742)
			(xy 283.743831 -67.164502) (xy 283.796127 -67.179861) (xy 283.845706 -67.202506) (xy 283.891557 -67.231976)
			(xy 283.932748 -67.267671) (xy 283.96844 -67.308865) (xy 283.997907 -67.354719) (xy 284.020548 -67.404299)
			(xy 284.035904 -67.456597) (xy 284.04366 -67.510547) (xy 284.04366 -67.565053) (xy 284.035904 -67.619003)
			(xy 284.020548 -67.671301) (xy 283.997907 -67.720881) (xy 283.96844 -67.766735) (xy 283.932748 -67.807929)
			(xy 283.891557 -67.843624) (xy 283.845706 -67.873094) (xy 283.796127 -67.895739) (xy 283.743831 -67.911098)
			(xy 283.689881 -67.918858) (xy 283.662628 -67.919346) (xy 283.635258 -67.918877) (xy 283.581078 -67.911062)
			(xy 283.528575 -67.895574) (xy 283.478828 -67.872733) (xy 283.432861 -67.843008) (xy 283.41193 -67.825366)
			(xy 283.411676 -67.825112) (xy 283.4046 -67.819511) (xy 283.387675 -67.813272) (xy 283.378656 -67.81292)
			(xy 283.3116 -67.81292) (xy 283.302583 -67.813273) (xy 283.285665 -67.819523) (xy 283.27858 -67.825112)
			(xy 283.27858 -67.825366) (xy 283.278326 -67.825366) (xy 283.257391 -67.843001) (xy 283.211419 -67.872715)
			(xy 283.161673 -67.895552) (xy 283.109172 -67.911044) (xy 283.054997 -67.918872) (xy 283.027628 -67.919346)
			(xy 283.000377 -67.918809) (xy 282.946428 -67.911056) (xy 282.894132 -67.895704) (xy 282.844553 -67.873065)
			(xy 282.798701 -67.843601) (xy 282.757509 -67.807911) (xy 282.721816 -67.766721) (xy 282.692348 -67.720871)
			(xy 282.669706 -67.671294) (xy 282.65435 -67.618999) (xy 282.646593 -67.565051) (xy 280.3083 -67.565051)
			(xy 280.308303 -67.56507) (xy 280.308812 -67.592956) (xy 280.308303 -67.620842) (xy 280.300183 -67.676018)
			(xy 280.284115 -67.729425) (xy 280.260443 -67.779922) (xy 280.22967 -67.826435) (xy 280.192453 -67.867972)
			(xy 280.149585 -67.903647) (xy 280.101979 -67.932701) (xy 280.05065 -67.954513) (xy 279.996693 -67.968619)
			(xy 279.941256 -67.974719) (xy 279.885522 -67.972682) (xy 279.830679 -67.962552) (xy 279.777895 -67.944545)
			(xy 279.728295 -67.919044) (xy 279.682937 -67.886593) (xy 279.642788 -67.847884) (xy 279.608702 -67.803741)
			(xy 279.581406 -67.755106) (xy 279.561483 -67.703015) (xy 279.549357 -67.648578) (xy 279.545286 -67.592956)
			(xy 279.030194 -67.592956) (xy 279.026119 -67.620646) (xy 279.010051 -67.674053) (xy 278.986379 -67.72455)
			(xy 278.955606 -67.771063) (xy 278.918389 -67.8126) (xy 278.875521 -67.848275) (xy 278.827915 -67.877329)
			(xy 278.776586 -67.899141) (xy 278.722629 -67.913247) (xy 278.667192 -67.919347) (xy 278.611458 -67.91731)
			(xy 278.556615 -67.90718) (xy 278.503831 -67.889173) (xy 278.454231 -67.863672) (xy 278.408873 -67.831221)
			(xy 278.368724 -67.792512) (xy 278.334638 -67.748369) (xy 278.307342 -67.699734) (xy 278.287419 -67.647643)
			(xy 278.275293 -67.593206) (xy 278.271222 -67.537584) (xy 277.739866 -67.537584) (xy 277.728446 -67.593134)
			(xy 277.708293 -67.647541) (xy 277.680135 -67.69827) (xy 277.64462 -67.74415) (xy 277.602568 -67.784125)
			(xy 277.554949 -67.817271) (xy 277.502859 -67.842825) (xy 277.447502 -67.860198) (xy 277.390152 -67.868989)
			(xy 277.361142 -67.869562) (xy 277.333405 -67.86906) (xy 277.278516 -67.861021) (xy 277.225369 -67.845119)
			(xy 277.175084 -67.821691) (xy 277.12872 -67.79123) (xy 277.087255 -67.754377) (xy 277.051563 -67.71191)
			(xy 277.022394 -67.664723) (xy 277.000364 -67.61381) (xy 276.985937 -67.560244) (xy 276.982174 -67.532758)
			(xy 276.98065 -67.51828) (xy 276.97938 -67.488054) (xy 276.97938 -67.467734) (xy 276.98065 -67.455796)
			(xy 276.983656 -67.42682) (xy 276.997347 -67.370198) (xy 277.019499 -67.316322) (xy 277.049596 -67.266447)
			(xy 277.086937 -67.221735) (xy 277.108412 -67.20205) (xy 277.114254 -67.19697) (xy 277.122382 -67.183762)
			(xy 277.12416 -67.176142) (xy 277.125618 -67.168782) (xy 277.124713 -67.15381) (xy 277.122382 -67.146678)
			(xy 277.10765 -67.107562) (xy 277.10765 -67.107054) (xy 277.0886 -67.05727) (xy 277.086243 -67.05155)
			(xy 277.079175 -67.041402) (xy 277.07463 -67.037204) (xy 276.6822 -67.037204) (xy 276.649045 -67.03674)
			(xy 276.583151 -67.02932) (xy 276.518502 -67.014574) (xy 276.455908 -66.992686) (xy 276.396157 -66.963931)
			(xy 276.339999 -66.928672) (xy 276.288139 -66.887349) (xy 276.26437 -66.86423) (xy 269.55877 -60.15863)
			(xy 269.53566 -60.134852) (xy 269.494328 -60.082999) (xy 269.459061 -60.026844) (xy 269.430302 -59.967094)
			(xy 269.408414 -59.904501) (xy 269.393671 -59.83985) (xy 269.386258 -59.773955) (xy 269.385796 -59.7408)
			(xy 269.385796 -56.466486) (xy 269.057882 -50.998628) (xy 269.057628 -50.997612) (xy 269.057374 -50.993802)
			(xy 269.05712 -50.987706) (xy 269.05712 -50.986436) (xy 269.056612 -50.972974) (xy 269.056612 -50.959512)
			(xy 269.057249 -50.929421) (xy 269.063989 -50.869608) (xy 269.070074 -50.840132) (xy 269.34668 -49.573688)
			(xy 269.347696 -49.564036) (xy 269.347696 -47.598838) (xy 269.347261 -47.588773) (xy 269.339531 -47.570185)
			(xy 269.33271 -47.56277) (xy 260.479032 -38.709092) (xy 260.465316 -38.701726) (xy 260.457696 -38.700456)
			(xy 260.422518 -38.693553) (xy 260.354037 -38.672347) (xy 260.288621 -38.643019) (xy 260.227228 -38.606001)
			(xy 260.17076 -38.561834) (xy 260.145022 -38.53688) (xy 259.794502 -38.18636) (xy 259.76954 -38.16066)
			(xy 259.725373 -38.104246) (xy 259.688352 -38.042904) (xy 259.659023 -37.977535) (xy 259.637814 -37.909099)
			(xy 259.630926 -37.87394) (xy 259.616956 -37.847016) (xy 259.610606 -37.840666) (xy 259.57374 -37.834399)
			(xy 259.50186 -37.813775) (xy 259.433152 -37.784256) (xy 259.368712 -37.746314) (xy 259.309567 -37.700553)
			(xy 259.282692 -37.67455) (xy 258.932172 -37.32403) (xy 258.907212 -37.298329) (xy 258.86305 -37.241912)
			(xy 258.826035 -37.180569) (xy 258.79671 -37.1152) (xy 258.775506 -37.046764) (xy 258.768596 -37.01161)
			(xy 258.754626 -36.984686) (xy 258.748276 -36.978336) (xy 258.711408 -36.972073) (xy 258.639524 -36.951455)
			(xy 258.570811 -36.921941) (xy 258.506367 -36.884002) (xy 258.447218 -36.838243) (xy 258.420362 -36.81222)
			(xy 258.069842 -36.4617) (xy 258.044881 -36.435999) (xy 258.000717 -36.379584) (xy 257.9637 -36.318241)
			(xy 257.934375 -36.252872) (xy 257.913172 -36.184435) (xy 257.906266 -36.14928) (xy 257.892296 -36.122356)
			(xy 257.885946 -36.116006) (xy 257.849079 -36.109741) (xy 257.777198 -36.089119) (xy 257.708488 -36.059601)
			(xy 257.644048 -36.021659) (xy 257.584903 -35.975897) (xy 257.558032 -35.94989) (xy 257.207512 -35.59937)
			(xy 257.182549 -35.57367) (xy 257.13838 -35.517257) (xy 257.101358 -35.455915) (xy 257.072027 -35.390547)
			(xy 257.050817 -35.32211) (xy 257.043936 -35.28695) (xy 257.029966 -35.260026) (xy 257.023616 -35.253676)
			(xy 256.98675 -35.24741) (xy 256.914868 -35.226787) (xy 256.846159 -35.197269) (xy 256.781718 -35.159328)
			(xy 256.722572 -35.113568) (xy 256.695702 -35.08756) (xy 256.345182 -34.73704) (xy 256.320203 -34.711323)
			(xy 256.276013 -34.654866) (xy 256.238986 -34.593472) (xy 256.209668 -34.528046) (xy 256.18849 -34.45955)
			(xy 256.181606 -34.424366) (xy 256.180336 -34.416746) (xy 256.17297 -34.40303) (xy 255.99517 -34.22523)
			(xy 255.97206 -34.201452) (xy 255.930728 -34.149599) (xy 255.895461 -34.093444) (xy 255.866702 -34.033694)
			(xy 255.844814 -33.971101) (xy 255.830071 -33.90645) (xy 255.822658 -33.840555) (xy 255.822196 -33.8074)
			(xy 255.822196 -33.292288) (xy 255.817116 -33.27019) (xy 255.80318 -33.240421) (xy 255.781333 -33.178426)
			(xy 255.766598 -33.114366) (xy 255.759161 -33.049056) (xy 255.758696 -33.01619) (xy 255.758696 -32.65043)
			(xy 255.759144 -32.617603) (xy 255.766524 -32.552364) (xy 255.781194 -32.488369) (xy 255.802968 -32.42643)
			(xy 255.816862 -32.396684) (xy 255.819402 -32.391604) (xy 255.822196 -32.380174) (xy 255.822196 -32.134048)
			(xy 255.817116 -32.11195) (xy 255.814068 -32.105346) (xy 255.807708 -32.091519) (xy 255.796271 -32.063311)
			(xy 255.791208 -32.048958) (xy 255.790192 -32.04591) (xy 255.787906 -32.038798) (xy 255.787144 -32.037528)
			(xy 255.784604 -32.029146) (xy 255.78435 -32.028384) (xy 255.784096 -32.026352) (xy 255.781048 -32.015938)
			(xy 255.779524 -32.011366) (xy 255.776984 -32.00146) (xy 255.77673 -32.00019) (xy 255.774952 -31.992824)
			(xy 255.768348 -31.961328) (xy 255.768348 -31.961074) (xy 255.767586 -31.95701) (xy 255.761744 -31.910782)
			(xy 255.760982 -31.90113) (xy 255.760982 -31.897574) (xy 255.759712 -31.859474) (xy 255.759712 -31.415736)
			(xy 255.760223 -31.383311) (xy 255.767569 -31.318878) (xy 255.78204 -31.255662) (xy 255.803456 -31.194449)
			(xy 255.817116 -31.165038) (xy 255.817116 -31.164784) (xy 255.81991 -31.159196) (xy 255.822196 -31.154624)
			(xy 255.822196 -31.050738) (xy 255.821761 -31.040673) (xy 255.814031 -31.022085) (xy 255.80721 -31.01467)
			(xy 255.709928 -30.917388) (xy 255.700871 -30.913572) (xy 255.681271 -30.912381) (xy 255.671828 -30.915102)
			(xy 255.65862 -30.919928) (xy 255.646299 -30.916904) (xy 255.621906 -30.909915) (xy 255.609852 -30.905958)
			(xy 255.576796 -30.894347) (xy 255.513505 -30.864291) (xy 255.483614 -30.846014) (xy 255.456491 -30.82833)
			(xy 255.405952 -30.787852) (xy 255.382776 -30.765242) (xy 255.070102 -30.452568) (xy 255.043432 -30.424374)
			(xy 255.041654 -30.422342) (xy 255.041146 -30.421834) (xy 255.040384 -30.420818) (xy 255.038606 -30.418786)
			(xy 255.026007 -30.403804) (xy 255.002622 -30.372407) (xy 254.99187 -30.356048) (xy 254.986282 -30.347412)
			(xy 254.984504 -30.34411) (xy 254.983742 -30.34284) (xy 254.962152 -30.304232) (xy 254.960628 -30.301184)
			(xy 254.955802 -30.291278) (xy 254.954532 -30.287722) (xy 254.95377 -30.286198) (xy 254.9525 -30.283912)
			(xy 254.95123 -30.281372) (xy 254.948944 -30.276038) (xy 254.944372 -30.264862) (xy 254.943864 -30.264354)
			(xy 254.941324 -30.258004) (xy 254.937581 -30.249617) (xy 254.925214 -30.236061) (xy 254.917194 -30.231588)
			(xy 254.908812 -30.22727) (xy 254.890778 -30.225238) (xy 254.874268 -30.229556) (xy 254.872236 -30.230064)
			(xy 254.849544 -30.235262) (xy 254.803313 -30.240745) (xy 254.780034 -30.240986) (xy 254.773684 -30.240986)
			(xy 254.74803 -30.239716) (xy 254.745998 -30.239462) (xy 254.745744 -30.239462) (xy 254.727964 -30.23743)
			(xy 254.724662 -30.236922) (xy 254.724408 -30.236922) (xy 254.711962 -30.235144) (xy 254.691642 -30.240986)
			(xy 254.683514 -30.24759) (xy 254.67945 -30.250638) (xy 254.676402 -30.252416) (xy 254.66802 -30.259528)
			(xy 254.622808 -30.298136) (xy 254.616554 -30.303894) (xy 254.60798 -30.318561) (xy 254.606044 -30.326838)
			(xy 254.605028 -30.336744) (xy 254.605028 -30.92069) (xy 254.604538 -30.950658) (xy 254.596715 -31.01008)
			(xy 254.581202 -31.067973) (xy 254.558266 -31.123346) (xy 254.528299 -31.175252) (xy 254.491812 -31.222802)
			(xy 254.449432 -31.265182) (xy 254.401882 -31.301669) (xy 254.349976 -31.331636) (xy 254.294603 -31.354572)
			(xy 254.23671 -31.370085) (xy 254.177288 -31.377908) (xy 254.117352 -31.377908) (xy 254.05793 -31.370085)
			(xy 254.000037 -31.354572) (xy 253.944664 -31.331636) (xy 253.892758 -31.301669) (xy 253.845208 -31.265182)
			(xy 253.802828 -31.222802) (xy 253.766341 -31.175252) (xy 253.736374 -31.123346) (xy 253.713438 -31.067973)
			(xy 253.697925 -31.01008) (xy 253.690102 -30.950658) (xy 253.689612 -30.92069) (xy 253.689612 -30.503114)
			(xy 253.689358 -30.05709) (xy 253.689841 -30.027223) (xy 253.697609 -29.967996) (xy 253.713012 -29.910282)
			(xy 253.735789 -29.85506) (xy 253.765552 -29.803269) (xy 253.801797 -29.755788) (xy 253.843908 -29.713422)
			(xy 253.89117 -29.676891) (xy 253.94278 -29.646816) (xy 253.997863 -29.623706) (xy 254.055484 -29.607955)
			(xy 254.114663 -29.59983) (xy 254.144526 -29.599128) (xy 254.150114 -29.599128) (xy 254.15866 -29.5988)
			(xy 254.174798 -29.593172) (xy 254.188187 -29.582548) (xy 254.19304 -29.575506) (xy 254.19685 -29.56814)
			(xy 254.229108 -29.491432) (xy 254.230378 -29.487876) (xy 254.236728 -29.46908) (xy 254.237556 -29.46168)
			(xy 254.235364 -29.446959) (xy 254.23241 -29.440124) (xy 254.13716 -29.34462) (xy 254.128524 -29.341064)
			(xy 254.125476 -29.340556) (xy 254.117856 -29.33954) (xy 254.082508 -29.333706) (xy 254.013484 -29.314505)
			(xy 253.947339 -29.286976) (xy 253.885074 -29.251535) (xy 253.827632 -29.208718) (xy 253.801372 -29.184346)
			(xy 253.786894 -29.169868) (xy 253.786386 -29.16936) (xy 253.479554 -28.862528) (xy 253.45861 -28.841017)
			(xy 253.42079 -28.794385) (xy 253.38797 -28.744108) (xy 253.360499 -28.69072) (xy 253.349252 -28.662884)
			(xy 253.342169 -28.64446) (xy 253.33022 -28.606835) (xy 253.325376 -28.5877) (xy 253.325376 -28.587446)
			(xy 253.322074 -28.574492) (xy 253.320067 -28.569395) (xy 253.314175 -28.560164) (xy 253.31039 -28.556204)
			(xy 252.882146 -28.556204) (xy 252.850542 -28.55578) (xy 252.787696 -28.549009) (xy 252.725932 -28.535573)
			(xy 252.665953 -28.515624) (xy 252.637036 -28.502864) (xy 252.634496 -28.501848) (xy 252.606531 -28.49063)
			(xy 252.552873 -28.463212) (xy 252.502337 -28.430392) (xy 252.455465 -28.392524) (xy 252.433836 -28.371546)
			(xy 252.43282 -28.37053) (xy 252.430788 -28.368752) (xy 252.425573 -28.363845) (xy 252.413067 -28.356885)
			(xy 252.40615 -28.355036) (xy 252.399292 -28.353512) (xy 252.38583 -28.354274) (xy 252.363478 -28.361894)
			(xy 252.357382 -28.366212) (xy 252.353064 -28.36926) (xy 252.347476 -28.37307) (xy 252.346714 -28.373578)
			(xy 252.305566 -28.401518) (xy 252.293628 -28.409646) (xy 251.985526 -28.618942) (xy 251.985018 -28.618942)
			(xy 251.979938 -28.622498) (xy 251.971556 -28.631642) (xy 251.968762 -28.636976) (xy 251.966026 -28.642561)
			(xy 251.963065 -28.654635) (xy 251.96292 -28.660852) (xy 251.96292 -29.114242) (xy 251.96243 -29.14421)
			(xy 251.954607 -29.203632) (xy 251.939094 -29.261525) (xy 251.916158 -29.316898) (xy 251.886191 -29.368804)
			(xy 251.849704 -29.416354) (xy 251.807324 -29.458734) (xy 251.759774 -29.495221) (xy 251.707868 -29.525188)
			(xy 251.652495 -29.548124) (xy 251.594602 -29.563637) (xy 251.53518 -29.57146) (xy 251.475244 -29.57146)
			(xy 251.415822 -29.563637) (xy 251.357929 -29.548124) (xy 251.302556 -29.525188) (xy 251.25065 -29.495221)
			(xy 251.2031 -29.458734) (xy 251.16072 -29.416354) (xy 251.124233 -29.368804) (xy 251.094266 -29.316898)
			(xy 251.07133 -29.261525) (xy 251.055817 -29.203632) (xy 251.047994 -29.14421) (xy 251.047504 -29.114242)
			(xy 251.047504 -28.250134) (xy 251.047962 -28.221571) (xy 251.0551 -28.164891) (xy 251.061728 -28.137104)
			(xy 251.064522 -28.126182) (xy 251.06249 -28.115768) (xy 251.061463 -28.110699) (xy 251.057619 -28.1011)
			(xy 251.05487 -28.096718) (xy 251.013468 -28.034488) (xy 251.008528 -28.027666) (xy 250.995177 -28.017417)
			(xy 250.987306 -28.014422) (xy 250.978416 -28.011628) (xy 250.974352 -28.010866) (xy 250.97359 -28.010866)
			(xy 250.9375 -28.004601) (xy 250.867155 -27.984172) (xy 250.799931 -27.955074) (xy 250.736893 -27.917765)
			(xy 250.679037 -27.872838) (xy 250.652788 -27.84729) (xy 250.450604 -27.645106) (xy 250.448064 -27.64282)
			(xy 249.738134 -27.64282) (xy 249.72807 -27.643256) (xy 249.709484 -27.650989) (xy 249.702066 -27.657806)
			(xy 249.599196 -27.760676) (xy 249.575438 -27.783819) (xy 249.523596 -27.825192) (xy 249.467447 -27.860501)
			(xy 249.407697 -27.8893) (xy 249.345099 -27.911227) (xy 249.280438 -27.926006) (xy 249.21453 -27.933452)
			(xy 249.181366 -27.933904) (xy 249.145647 -27.933363) (xy 249.074729 -27.924748) (xy 249.005366 -27.907649)
			(xy 248.93857 -27.882315) (xy 248.875315 -27.849115) (xy 248.816522 -27.808532) (xy 248.763049 -27.76116)
			(xy 248.715675 -27.707688) (xy 248.675092 -27.648895) (xy 248.64189 -27.585641) (xy 248.616554 -27.518845)
			(xy 248.599454 -27.449483) (xy 248.590838 -27.378565) (xy 248.590308 -27.342846) (xy 248.59075 -27.310554)
			(xy 248.597815 -27.246357) (xy 248.611843 -27.183315) (xy 248.632667 -27.12218) (xy 248.660038 -27.063683)
			(xy 248.693629 -27.008522) (xy 248.71299 -26.982674) (xy 248.71299 -26.98242) (xy 248.71807 -26.975816)
			(xy 248.723404 -26.960322) (xy 248.723404 -26.870152) (xy 248.723079 -26.861873) (xy 248.717757 -26.846196)
			(xy 248.71299 -26.839418) (xy 248.69364 -26.813563) (xy 248.660068 -26.758393) (xy 248.632705 -26.699895)
			(xy 248.611877 -26.638764) (xy 248.597832 -26.575728) (xy 248.590738 -26.511537) (xy 248.590308 -26.479246)
			(xy 248.590753 -26.446076) (xy 248.598176 -26.380152) (xy 248.612933 -26.315473) (xy 248.634839 -26.252854)
			(xy 248.663619 -26.193081) (xy 248.698911 -26.136906) (xy 248.74027 -26.085036) (xy 248.787176 -26.038123)
			(xy 248.839041 -25.996757) (xy 248.895211 -25.961458) (xy 248.95498 -25.93267) (xy 249.017596 -25.910755)
			(xy 249.082273 -25.895989) (xy 249.148196 -25.888558) (xy 249.181366 -25.888188) (xy 249.214528 -25.888667)
			(xy 249.280433 -25.89612) (xy 249.345089 -25.910902) (xy 249.407685 -25.932827) (xy 249.467434 -25.96162)
			(xy 249.523584 -25.99692) (xy 249.575432 -26.038282) (xy 249.599196 -26.061416) (xy 249.702066 -26.164286)
			(xy 249.709468 -26.171123) (xy 249.728066 -26.178836) (xy 249.738134 -26.179272) (xy 250.84151 -26.179272)
			(xy 250.875526 -26.179747) (xy 250.943107 -26.187562) (xy 251.009341 -26.203097) (xy 251.073348 -26.226146)
			(xy 251.13428 -26.256405) (xy 251.163074 -26.274522) (xy 251.17298 -26.280872) (xy 251.196094 -26.283666)
			(xy 251.226828 -26.272998) (xy 251.228352 -26.27249) (xy 251.232258 -26.270852) (xy 251.239532 -26.266513)
			(xy 251.24283 -26.263854) (xy 251.258324 -26.249122) (xy 251.266198 -26.23947) (xy 251.2695 -26.23439)
			(xy 251.271532 -26.228548) (xy 251.281215 -26.200884) (xy 251.307157 -26.148328) (xy 251.340132 -26.099874)
			(xy 251.379504 -26.056457) (xy 251.424513 -26.018916) (xy 251.47429 -25.987974) (xy 251.527874 -25.964228)
			(xy 251.584233 -25.948138) (xy 251.642277 -25.940013) (xy 251.671582 -25.939496) (xy 251.701683 -25.940032)
			(xy 251.761273 -25.948597) (xy 251.819037 -25.965555) (xy 251.873799 -25.990562) (xy 251.924446 -26.023107)
			(xy 251.969945 -26.062529) (xy 252.009371 -26.108025) (xy 252.041921 -26.158669) (xy 252.066932 -26.213429)
			(xy 252.083895 -26.271192) (xy 252.090877 -26.319734) (xy 257.041902 -26.319734) (xy 257.045973 -26.264112)
			(xy 257.058099 -26.209675) (xy 257.078022 -26.157584) (xy 257.105318 -26.108949) (xy 257.139404 -26.064806)
			(xy 257.179553 -26.026097) (xy 257.224911 -25.993646) (xy 257.274511 -25.968145) (xy 257.327295 -25.950138)
			(xy 257.382138 -25.940008) (xy 257.437872 -25.937971) (xy 257.493309 -25.944071) (xy 257.547266 -25.958177)
			(xy 257.598595 -25.979989) (xy 257.646201 -26.009043) (xy 257.675866 -26.03373) (xy 263.467848 -26.03373)
			(xy 263.471919 -25.978108) (xy 263.484045 -25.923671) (xy 263.503968 -25.87158) (xy 263.531264 -25.822945)
			(xy 263.56535 -25.778802) (xy 263.605499 -25.740093) (xy 263.650857 -25.707642) (xy 263.700457 -25.682141)
			(xy 263.753241 -25.664134) (xy 263.808084 -25.654004) (xy 263.863818 -25.651967) (xy 263.919255 -25.658067)
			(xy 263.973212 -25.672173) (xy 264.024541 -25.693985) (xy 264.072147 -25.723039) (xy 264.115015 -25.758714)
			(xy 264.152232 -25.800251) (xy 264.183005 -25.846764) (xy 264.206677 -25.897261) (xy 264.222745 -25.950668)
			(xy 264.230865 -26.005844) (xy 264.231374 -26.03373) (xy 264.230865 -26.061616) (xy 264.222745 -26.116792)
			(xy 264.206677 -26.170199) (xy 264.183005 -26.220696) (xy 264.152771 -26.266394) (xy 266.720574 -26.266394)
			(xy 266.72106 -26.239143) (xy 266.728816 -26.185195) (xy 266.744171 -26.1329) (xy 266.766813 -26.083323)
			(xy 266.796279 -26.037473) (xy 266.83197 -25.996282) (xy 266.873161 -25.960591) (xy 266.919011 -25.931125)
			(xy 266.968588 -25.908483) (xy 267.020883 -25.893128) (xy 267.074831 -25.885372) (xy 267.129333 -25.885372)
			(xy 267.183281 -25.893128) (xy 267.235576 -25.908483) (xy 267.285153 -25.931125) (xy 267.331003 -25.960591)
			(xy 267.372194 -25.996282) (xy 267.407885 -26.037473) (xy 267.437351 -26.083323) (xy 267.459993 -26.1329)
			(xy 267.475348 -26.185195) (xy 267.483104 -26.239143) (xy 267.48359 -26.266394) (xy 267.483042 -26.295882)
			(xy 267.473947 -26.354153) (xy 267.455988 -26.410328) (xy 267.429594 -26.463069) (xy 267.395395 -26.511117)
			(xy 267.354205 -26.553326) (xy 267.330936 -26.571448) (xy 267.319789 -26.580314) (xy 267.302613 -26.603025)
			(xy 267.292371 -26.629594) (xy 267.28986 -26.657958) (xy 267.295273 -26.685913) (xy 267.308191 -26.711289)
			(xy 267.32761 -26.732114) (xy 267.339572 -26.73985) (xy 267.363302 -26.754765) (xy 267.406539 -26.790428)
			(xy 267.444092 -26.832033) (xy 267.475153 -26.878685) (xy 267.499054 -26.929381) (xy 267.51528 -26.983027)
			(xy 267.523481 -27.038471) (xy 267.523976 -27.066494) (xy 267.52349 -27.093745) (xy 267.515734 -27.147693)
			(xy 267.500379 -27.199988) (xy 267.477737 -27.249565) (xy 267.448271 -27.295415) (xy 267.41258 -27.336606)
			(xy 267.371389 -27.372297) (xy 267.325539 -27.401763) (xy 267.275962 -27.424405) (xy 267.223667 -27.43976)
			(xy 267.169719 -27.447516) (xy 267.115217 -27.447516) (xy 267.061269 -27.43976) (xy 267.008974 -27.424405)
			(xy 266.959397 -27.401763) (xy 266.913547 -27.372297) (xy 266.872356 -27.336606) (xy 266.836665 -27.295415)
			(xy 266.807199 -27.249565) (xy 266.784557 -27.199988) (xy 266.769202 -27.147693) (xy 266.761446 -27.093745)
			(xy 266.76096 -27.066494) (xy 266.761519 -27.037007) (xy 266.770615 -26.978737) (xy 266.788572 -26.922563)
			(xy 266.814964 -26.869823) (xy 266.849161 -26.821775) (xy 266.890347 -26.779564) (xy 266.913614 -26.76144)
			(xy 266.924678 -26.752476) (xy 266.941862 -26.72979) (xy 266.952116 -26.703242) (xy 266.954641 -26.674895)
			(xy 266.949242 -26.646953) (xy 266.936338 -26.621587) (xy 266.916933 -26.60077) (xy 266.904978 -26.593038)
			(xy 266.881231 -26.578149) (xy 266.837997 -26.54248) (xy 266.800447 -26.500869) (xy 266.769388 -26.454213)
			(xy 266.74549 -26.403514) (xy 266.729267 -26.349864) (xy 266.721068 -26.294418) (xy 266.720574 -26.266394)
			(xy 264.152771 -26.266394) (xy 264.152232 -26.267209) (xy 264.115015 -26.308746) (xy 264.072147 -26.344421)
			(xy 264.024541 -26.373475) (xy 263.973212 -26.395287) (xy 263.919255 -26.409393) (xy 263.863818 -26.415493)
			(xy 263.808084 -26.413456) (xy 263.753241 -26.403326) (xy 263.700457 -26.385319) (xy 263.650857 -26.359818)
			(xy 263.605499 -26.327367) (xy 263.56535 -26.288658) (xy 263.531264 -26.244515) (xy 263.503968 -26.19588)
			(xy 263.484045 -26.143789) (xy 263.471919 -26.089352) (xy 263.467848 -26.03373) (xy 257.675866 -26.03373)
			(xy 257.689069 -26.044718) (xy 257.726286 -26.086255) (xy 257.757059 -26.132768) (xy 257.780731 -26.183265)
			(xy 257.796799 -26.236672) (xy 257.804919 -26.291848) (xy 257.805428 -26.319734) (xy 257.804919 -26.34762)
			(xy 257.796799 -26.402796) (xy 257.780731 -26.456203) (xy 257.757059 -26.5067) (xy 257.726286 -26.553213)
			(xy 257.689069 -26.59475) (xy 257.646201 -26.630425) (xy 257.598595 -26.659479) (xy 257.547266 -26.681291)
			(xy 257.493309 -26.695397) (xy 257.437872 -26.701497) (xy 257.382138 -26.69946) (xy 257.327295 -26.68933)
			(xy 257.274511 -26.671323) (xy 257.224911 -26.645822) (xy 257.179553 -26.613371) (xy 257.139404 -26.574662)
			(xy 257.105318 -26.530519) (xy 257.078022 -26.481884) (xy 257.058099 -26.429793) (xy 257.045973 -26.375356)
			(xy 257.041902 -26.319734) (xy 252.090877 -26.319734) (xy 252.092466 -26.330781) (xy 252.092968 -26.360882)
			(xy 252.092233 -26.393165) (xy 252.082159 -26.456946) (xy 252.072902 -26.487882) (xy 252.070362 -26.49601)
			(xy 252.070616 -26.504392) (xy 252.070616 -26.51252) (xy 252.073156 -26.52014) (xy 252.074614 -26.52423)
			(xy 252.078703 -26.531888) (xy 252.081284 -26.53538) (xy 252.083316 -26.53792) (xy 252.099572 -26.558494)
			(xy 252.10008 -26.559256) (xy 252.46584 -26.559256) (xy 252.498994 -26.559722) (xy 252.564886 -26.567145)
			(xy 252.629534 -26.581895) (xy 252.692125 -26.603785) (xy 252.751875 -26.63254) (xy 252.808031 -26.667801)
			(xy 252.85989 -26.709123) (xy 252.88367 -26.73223) (xy 252.974348 -26.822908) (xy 252.983431 -26.831079)
			(xy 253.006661 -26.838521) (xy 253.018798 -26.837132) (xy 253.02337 -26.83637) (xy 253.04877 -26.832052)
			(xy 253.05131 -26.831544) (xy 253.054825 -26.830711) (xy 253.061587 -26.828168) (xy 253.064772 -26.826464)
			(xy 253.067885 -26.824665) (xy 253.073619 -26.820329) (xy 253.076202 -26.817828) (xy 253.089918 -26.804112)
			(xy 253.091696 -26.800556) (xy 253.093728 -26.796746) (xy 253.106083 -26.773708) (xy 253.136145 -26.73094)
			(xy 253.171761 -26.692673) (xy 253.212263 -26.659621) (xy 253.256894 -26.632402) (xy 253.304822 -26.611526)
			(xy 253.355148 -26.597381) (xy 253.406934 -26.590233) (xy 253.433072 -26.589736) (xy 253.460325 -26.590197)
			(xy 253.514277 -26.597951) (xy 253.566575 -26.613305) (xy 253.616156 -26.635947) (xy 253.66201 -26.665415)
			(xy 253.703202 -26.701109) (xy 253.738895 -26.742303) (xy 253.768361 -26.788158) (xy 253.791 -26.83774)
			(xy 253.806352 -26.890039) (xy 253.814104 -26.943991) (xy 253.81458 -26.971244) (xy 253.81458 -26.97226)
			(xy 253.814399 -26.989309) (xy 253.811349 -27.02327) (xy 253.808484 -27.040078) (xy 253.807976 -27.042618)
			(xy 253.805944 -27.054048) (xy 253.81077 -27.074368) (xy 253.81712 -27.08275) (xy 253.819406 -27.08656)
			(xy 253.824952 -27.094786) (xy 253.840897 -27.106556) (xy 253.850394 -27.10942) (xy 253.850648 -27.10942)
			(xy 253.881887 -27.117494) (xy 253.942529 -27.139542) (xy 254.000407 -27.168068) (xy 254.054831 -27.202731)
			(xy 254.105154 -27.24312) (xy 254.12827 -27.26563) (xy 255.331722 -28.469082) (xy 255.952496 -28.469082)
			(xy 255.956567 -28.41346) (xy 255.968693 -28.359023) (xy 255.988616 -28.306932) (xy 256.015912 -28.258297)
			(xy 256.049998 -28.214154) (xy 256.090147 -28.175445) (xy 256.135505 -28.142994) (xy 256.185105 -28.117493)
			(xy 256.237889 -28.099486) (xy 256.292732 -28.089356) (xy 256.348466 -28.087319) (xy 256.403903 -28.093419)
			(xy 256.45786 -28.107525) (xy 256.509189 -28.129337) (xy 256.525245 -28.139136) (xy 260.597902 -28.139136)
			(xy 260.601973 -28.083514) (xy 260.614099 -28.029077) (xy 260.634022 -27.976986) (xy 260.661318 -27.928351)
			(xy 260.695404 -27.884208) (xy 260.735553 -27.845499) (xy 260.780911 -27.813048) (xy 260.830511 -27.787547)
			(xy 260.883295 -27.76954) (xy 260.938138 -27.75941) (xy 260.993872 -27.757373) (xy 261.049309 -27.763473)
			(xy 261.103266 -27.777579) (xy 261.154595 -27.799391) (xy 261.202201 -27.828445) (xy 261.245069 -27.86412)
			(xy 261.282286 -27.905657) (xy 261.313059 -27.95217) (xy 261.336731 -28.002667) (xy 261.352799 -28.056074)
			(xy 261.360919 -28.11125) (xy 261.361428 -28.139136) (xy 261.867902 -28.139136) (xy 261.871973 -28.083514)
			(xy 261.884099 -28.029077) (xy 261.904022 -27.976986) (xy 261.931318 -27.928351) (xy 261.965404 -27.884208)
			(xy 262.005553 -27.845499) (xy 262.050911 -27.813048) (xy 262.100511 -27.787547) (xy 262.153295 -27.76954)
			(xy 262.208138 -27.75941) (xy 262.263872 -27.757373) (xy 262.319309 -27.763473) (xy 262.373266 -27.777579)
			(xy 262.424595 -27.799391) (xy 262.472201 -27.828445) (xy 262.515069 -27.86412) (xy 262.552286 -27.905657)
			(xy 262.583059 -27.95217) (xy 262.606731 -28.002667) (xy 262.622799 -28.056074) (xy 262.630919 -28.11125)
			(xy 262.631428 -28.139136) (xy 262.630919 -28.167022) (xy 262.622799 -28.222198) (xy 262.606731 -28.275605)
			(xy 262.583059 -28.326102) (xy 262.552286 -28.372615) (xy 262.515069 -28.414152) (xy 262.472201 -28.449827)
			(xy 262.424595 -28.478881) (xy 262.373266 -28.500693) (xy 262.319309 -28.514799) (xy 262.263872 -28.520899)
			(xy 262.208138 -28.518862) (xy 262.153295 -28.508732) (xy 262.100511 -28.490725) (xy 262.050911 -28.465224)
			(xy 262.005553 -28.432773) (xy 261.965404 -28.394064) (xy 261.931318 -28.349921) (xy 261.904022 -28.301286)
			(xy 261.884099 -28.249195) (xy 261.871973 -28.194758) (xy 261.867902 -28.139136) (xy 261.361428 -28.139136)
			(xy 261.360919 -28.167022) (xy 261.352799 -28.222198) (xy 261.336731 -28.275605) (xy 261.313059 -28.326102)
			(xy 261.282286 -28.372615) (xy 261.245069 -28.414152) (xy 261.202201 -28.449827) (xy 261.154595 -28.478881)
			(xy 261.103266 -28.500693) (xy 261.049309 -28.514799) (xy 260.993872 -28.520899) (xy 260.938138 -28.518862)
			(xy 260.883295 -28.508732) (xy 260.830511 -28.490725) (xy 260.780911 -28.465224) (xy 260.735553 -28.432773)
			(xy 260.695404 -28.394064) (xy 260.661318 -28.349921) (xy 260.634022 -28.301286) (xy 260.614099 -28.249195)
			(xy 260.601973 -28.194758) (xy 260.597902 -28.139136) (xy 256.525245 -28.139136) (xy 256.556795 -28.158391)
			(xy 256.599663 -28.194066) (xy 256.63688 -28.235603) (xy 256.667653 -28.282116) (xy 256.691325 -28.332613)
			(xy 256.707393 -28.38602) (xy 256.715513 -28.441196) (xy 256.716022 -28.469082) (xy 256.715513 -28.496968)
			(xy 256.707393 -28.552144) (xy 256.691325 -28.605551) (xy 256.667653 -28.656048) (xy 256.63688 -28.702561)
			(xy 256.599663 -28.744098) (xy 256.556795 -28.779773) (xy 256.509189 -28.808827) (xy 256.45786 -28.830639)
			(xy 256.403903 -28.844745) (xy 256.348466 -28.850845) (xy 256.292732 -28.848808) (xy 256.237889 -28.838678)
			(xy 256.185105 -28.820671) (xy 256.135505 -28.79517) (xy 256.090147 -28.762719) (xy 256.049998 -28.72401)
			(xy 256.015912 -28.679867) (xy 255.988616 -28.631232) (xy 255.968693 -28.579141) (xy 255.956567 -28.524704)
			(xy 255.952496 -28.469082) (xy 255.331722 -28.469082) (xy 255.98501 -29.12237) (xy 266.80668 -29.12237)
			(xy 266.80668 -28.25877) (xy 266.80717 -28.228786) (xy 266.814998 -28.16933) (xy 266.830519 -28.111405)
			(xy 266.853468 -28.056001) (xy 266.883452 -28.004067) (xy 266.919958 -27.956491) (xy 266.962363 -27.914086)
			(xy 267.009939 -27.87758) (xy 267.061873 -27.847596) (xy 267.117277 -27.824647) (xy 267.175202 -27.809126)
			(xy 267.234658 -27.801298) (xy 267.294626 -27.801298) (xy 267.354082 -27.809126) (xy 267.412007 -27.824647)
			(xy 267.467411 -27.847596) (xy 267.519345 -27.87758) (xy 267.566921 -27.914086) (xy 267.609326 -27.956491)
			(xy 267.645832 -28.004067) (xy 267.675816 -28.056001) (xy 267.698765 -28.111405) (xy 267.714286 -28.16933)
			(xy 267.722114 -28.228786) (xy 267.722604 -28.25877) (xy 267.722604 -29.12237) (xy 267.722114 -29.152354)
			(xy 267.714286 -29.21181) (xy 267.698765 -29.269735) (xy 267.675816 -29.325139) (xy 267.645832 -29.377073)
			(xy 267.609326 -29.424649) (xy 267.566921 -29.467054) (xy 267.519345 -29.50356) (xy 267.467411 -29.533544)
			(xy 267.412007 -29.556493) (xy 267.354082 -29.572014) (xy 267.294626 -29.579842) (xy 267.234658 -29.579842)
			(xy 267.175202 -29.572014) (xy 267.117277 -29.556493) (xy 267.061873 -29.533544) (xy 267.009939 -29.50356)
			(xy 266.962363 -29.467054) (xy 266.919958 -29.424649) (xy 266.883452 -29.377073) (xy 266.853468 -29.325139)
			(xy 266.830519 -29.269735) (xy 266.814998 -29.21181) (xy 266.80717 -29.152354) (xy 266.80668 -29.12237)
			(xy 255.98501 -29.12237) (xy 257.11277 -30.25013) (xy 257.13568 -30.273679) (xy 257.176703 -30.325001)
			(xy 257.209479 -30.376876) (xy 259.08889 -30.376876) (xy 259.089429 -30.347959) (xy 259.098149 -30.290788)
			(xy 259.1154 -30.235588) (xy 259.140788 -30.183625) (xy 259.17373 -30.136091) (xy 259.213471 -30.094075)
			(xy 259.235956 -30.075886) (xy 259.244769 -30.068285) (xy 259.254947 -30.047379) (xy 259.255514 -30.035754)
			(xy 259.255514 -29.955998) (xy 259.254957 -29.944369) (xy 259.24478 -29.923459) (xy 259.235956 -29.915866)
			(xy 259.213447 -29.897705) (xy 259.173715 -29.855678) (xy 259.140781 -29.808136) (xy 259.115397 -29.756169)
			(xy 259.098146 -29.700967) (xy 259.089422 -29.643794) (xy 259.08889 -29.614876) (xy 259.089376 -29.587625)
			(xy 259.097132 -29.533677) (xy 259.112487 -29.481382) (xy 259.135129 -29.431805) (xy 259.164595 -29.385955)
			(xy 259.200286 -29.344764) (xy 259.241477 -29.309073) (xy 259.287327 -29.279607) (xy 259.336904 -29.256965)
			(xy 259.389199 -29.24161) (xy 259.443147 -29.233854) (xy 259.497649 -29.233854) (xy 259.551597 -29.24161)
			(xy 259.603892 -29.256965) (xy 259.653469 -29.279607) (xy 259.699319 -29.309073) (xy 259.74051 -29.344764)
			(xy 259.776201 -29.385955) (xy 259.805667 -29.431805) (xy 259.828309 -29.481382) (xy 259.843664 -29.533677)
			(xy 259.85142 -29.587625) (xy 259.851906 -29.614876) (xy 259.851406 -29.643794) (xy 259.842678 -29.700968)
			(xy 259.825419 -29.756168) (xy 259.800024 -29.808131) (xy 259.767076 -29.855664) (xy 259.727329 -29.897678)
			(xy 259.70484 -29.915866) (xy 259.696048 -29.923487) (xy 259.685858 -29.944378) (xy 259.685282 -29.955998)
			(xy 259.685282 -30.035754) (xy 259.685811 -30.047387) (xy 259.696008 -30.068296) (xy 259.70484 -30.075886)
			(xy 259.727325 -30.094075) (xy 259.767058 -30.136096) (xy 259.799996 -30.183632) (xy 259.825384 -30.235593)
			(xy 259.84264 -30.290791) (xy 259.85137 -30.34796) (xy 259.851906 -30.376876) (xy 262.129016 -30.376876)
			(xy 262.129583 -30.347961) (xy 262.138301 -30.290792) (xy 262.155549 -30.235593) (xy 262.180931 -30.183631)
			(xy 262.213867 -30.136096) (xy 262.2536 -30.094077) (xy 262.276082 -30.075886) (xy 262.284899 -30.068289)
			(xy 262.295074 -30.04738) (xy 262.29564 -30.035754) (xy 262.29564 -29.955998) (xy 262.295109 -29.944365)
			(xy 262.284917 -29.923454) (xy 262.276082 -29.915866) (xy 262.253578 -29.897699) (xy 262.213845 -29.855673)
			(xy 262.180909 -29.808134) (xy 262.155524 -29.756168) (xy 262.138272 -29.700966) (xy 262.129548 -29.643793)
			(xy 262.129016 -29.614876) (xy 262.129502 -29.587625) (xy 262.137258 -29.533677) (xy 262.152613 -29.481382)
			(xy 262.175255 -29.431805) (xy 262.204721 -29.385955) (xy 262.240412 -29.344764) (xy 262.281603 -29.309073)
			(xy 262.327453 -29.279607) (xy 262.37703 -29.256965) (xy 262.429325 -29.24161) (xy 262.483273 -29.233854)
			(xy 262.537775 -29.233854) (xy 262.591723 -29.24161) (xy 262.644018 -29.256965) (xy 262.693595 -29.279607)
			(xy 262.739445 -29.309073) (xy 262.780636 -29.344764) (xy 262.816327 -29.385955) (xy 262.845793 -29.431805)
			(xy 262.868435 -29.481382) (xy 262.88379 -29.533677) (xy 262.891546 -29.587625) (xy 262.892032 -29.614876)
			(xy 262.891522 -29.643794) (xy 262.882795 -29.700966) (xy 262.865537 -29.756166) (xy 262.840144 -29.808129)
			(xy 262.807198 -29.855662) (xy 262.767453 -29.897677) (xy 262.744966 -29.915866) (xy 262.736179 -29.923492)
			(xy 262.725985 -29.944379) (xy 262.725408 -29.955998) (xy 262.725408 -30.035754) (xy 262.725927 -30.047388)
			(xy 262.73613 -30.068298) (xy 262.744966 -30.075886) (xy 262.767436 -30.094094) (xy 262.807173 -30.136109)
			(xy 262.840115 -30.18364) (xy 262.865506 -30.235598) (xy 262.882765 -30.290793) (xy 262.891496 -30.347961)
			(xy 262.892032 -30.376876) (xy 262.891546 -30.404127) (xy 262.88379 -30.458075) (xy 262.868435 -30.51037)
			(xy 262.845793 -30.559947) (xy 262.816327 -30.605797) (xy 262.780636 -30.646988) (xy 262.739445 -30.682679)
			(xy 262.693595 -30.712145) (xy 262.644018 -30.734787) (xy 262.591723 -30.750142) (xy 262.537775 -30.757898)
			(xy 262.483273 -30.757898) (xy 262.429325 -30.750142) (xy 262.37703 -30.734787) (xy 262.327453 -30.712145)
			(xy 262.281603 -30.682679) (xy 262.240412 -30.646988) (xy 262.204721 -30.605797) (xy 262.175255 -30.559947)
			(xy 262.152613 -30.51037) (xy 262.137258 -30.458075) (xy 262.129502 -30.404127) (xy 262.129016 -30.376876)
			(xy 259.851906 -30.376876) (xy 259.85142 -30.404127) (xy 259.843664 -30.458075) (xy 259.828309 -30.51037)
			(xy 259.805667 -30.559947) (xy 259.776201 -30.605797) (xy 259.74051 -30.646988) (xy 259.699319 -30.682679)
			(xy 259.653469 -30.712145) (xy 259.603892 -30.734787) (xy 259.551597 -30.750142) (xy 259.497649 -30.757898)
			(xy 259.443147 -30.757898) (xy 259.389199 -30.750142) (xy 259.336904 -30.734787) (xy 259.287327 -30.712145)
			(xy 259.241477 -30.682679) (xy 259.200286 -30.646988) (xy 259.164595 -30.605797) (xy 259.135129 -30.559947)
			(xy 259.112487 -30.51037) (xy 259.097132 -30.458075) (xy 259.089376 -30.404127) (xy 259.08889 -30.376876)
			(xy 257.209479 -30.376876) (xy 257.211798 -30.380546) (xy 257.226562 -30.409896) (xy 257.229864 -30.415738)
			(xy 257.247978 -30.44425) (xy 257.27823 -30.504651) (xy 257.301284 -30.568148) (xy 257.316829 -30.633888)
			(xy 257.324657 -30.700986) (xy 257.325114 -30.734762) (xy 257.325114 -30.735016) (xy 257.32486 -30.748224)
			(xy 257.32486 -30.922468) (xy 264.95248 -30.922468) (xy 264.95248 -30.058868) (xy 264.95297 -30.028884)
			(xy 264.960798 -29.969428) (xy 264.976319 -29.911503) (xy 264.999268 -29.856099) (xy 265.029252 -29.804165)
			(xy 265.065758 -29.756589) (xy 265.108163 -29.714184) (xy 265.155739 -29.677678) (xy 265.207673 -29.647694)
			(xy 265.263077 -29.624745) (xy 265.321002 -29.609224) (xy 265.380458 -29.601396) (xy 265.440426 -29.601396)
			(xy 265.499882 -29.609224) (xy 265.557807 -29.624745) (xy 265.613211 -29.647694) (xy 265.665145 -29.677678)
			(xy 265.712721 -29.714184) (xy 265.755126 -29.756589) (xy 265.791632 -29.804165) (xy 265.821616 -29.856099)
			(xy 265.844565 -29.911503) (xy 265.860086 -29.969428) (xy 265.867914 -30.028884) (xy 265.868404 -30.058868)
			(xy 265.868404 -30.92069) (xy 279.68956 -30.92069) (xy 279.68956 -30.05709) (xy 279.69005 -30.027122)
			(xy 279.697873 -29.9677) (xy 279.713386 -29.909807) (xy 279.736322 -29.854434) (xy 279.766289 -29.802528)
			(xy 279.802776 -29.754978) (xy 279.845156 -29.712598) (xy 279.892706 -29.676111) (xy 279.944612 -29.646144)
			(xy 279.999985 -29.623208) (xy 280.057878 -29.607695) (xy 280.1173 -29.599872) (xy 280.177236 -29.599872)
			(xy 280.236658 -29.607695) (xy 280.294551 -29.623208) (xy 280.349924 -29.646144) (xy 280.40183 -29.676111)
			(xy 280.44938 -29.712598) (xy 280.49176 -29.754978) (xy 280.528247 -29.802528) (xy 280.558214 -29.854434)
			(xy 280.58115 -29.909807) (xy 280.596663 -29.9677) (xy 280.604486 -30.027122) (xy 280.604976 -30.05709)
			(xy 280.604976 -30.92069) (xy 280.604486 -30.950658) (xy 280.596663 -31.01008) (xy 280.58115 -31.067973)
			(xy 280.558214 -31.123346) (xy 280.528247 -31.175252) (xy 280.49176 -31.222802) (xy 280.44938 -31.265182)
			(xy 280.40183 -31.301669) (xy 280.349924 -31.331636) (xy 280.294551 -31.354572) (xy 280.236658 -31.370085)
			(xy 280.177236 -31.377908) (xy 280.1173 -31.377908) (xy 280.057878 -31.370085) (xy 279.999985 -31.354572)
			(xy 279.944612 -31.331636) (xy 279.892706 -31.301669) (xy 279.845156 -31.265182) (xy 279.802776 -31.222802)
			(xy 279.766289 -31.175252) (xy 279.736322 -31.123346) (xy 279.713386 -31.067973) (xy 279.697873 -31.01008)
			(xy 279.69005 -30.950658) (xy 279.68956 -30.92069) (xy 265.868404 -30.92069) (xy 265.868404 -30.922468)
			(xy 265.867914 -30.952452) (xy 265.860086 -31.011908) (xy 265.844565 -31.069833) (xy 265.821616 -31.125237)
			(xy 265.791632 -31.177171) (xy 265.755126 -31.224747) (xy 265.712721 -31.267152) (xy 265.665145 -31.303658)
			(xy 265.613211 -31.333642) (xy 265.557807 -31.356591) (xy 265.499882 -31.372112) (xy 265.440426 -31.37994)
			(xy 265.380458 -31.37994) (xy 265.321002 -31.372112) (xy 265.263077 -31.356591) (xy 265.207673 -31.333642)
			(xy 265.155739 -31.303658) (xy 265.108163 -31.267152) (xy 265.065758 -31.224747) (xy 265.029252 -31.177171)
			(xy 264.999268 -31.125237) (xy 264.976319 -31.069833) (xy 264.960798 -31.011908) (xy 264.95297 -30.952452)
			(xy 264.95248 -30.922468) (xy 257.32486 -30.922468) (xy 257.32486 -31.567882) (xy 259.198616 -31.567882)
			(xy 259.202687 -31.51226) (xy 259.214813 -31.457823) (xy 259.234736 -31.405732) (xy 259.262032 -31.357097)
			(xy 259.296118 -31.312954) (xy 259.336267 -31.274245) (xy 259.381625 -31.241794) (xy 259.431225 -31.216293)
			(xy 259.484009 -31.198286) (xy 259.538852 -31.188156) (xy 259.594586 -31.186119) (xy 259.650023 -31.192219)
			(xy 259.70398 -31.206325) (xy 259.755309 -31.228137) (xy 259.802915 -31.257191) (xy 259.845783 -31.292866)
			(xy 259.883 -31.334403) (xy 259.913773 -31.380916) (xy 259.937445 -31.431413) (xy 259.953513 -31.48482)
			(xy 259.961633 -31.539996) (xy 259.962142 -31.567882) (xy 259.961633 -31.595768) (xy 259.953513 -31.650944)
			(xy 259.937445 -31.704351) (xy 259.930453 -31.719266) (xy 260.48538 -31.719266) (xy 260.489451 -31.663644)
			(xy 260.501577 -31.609207) (xy 260.5215 -31.557116) (xy 260.548796 -31.508481) (xy 260.582882 -31.464338)
			(xy 260.623031 -31.425629) (xy 260.668389 -31.393178) (xy 260.717989 -31.367677) (xy 260.770773 -31.34967)
			(xy 260.825616 -31.33954) (xy 260.88135 -31.337503) (xy 260.936787 -31.343603) (xy 260.990744 -31.357709)
			(xy 261.042073 -31.379521) (xy 261.089679 -31.408575) (xy 261.132547 -31.44425) (xy 261.169764 -31.485787)
			(xy 261.200537 -31.5323) (xy 261.224209 -31.582797) (xy 261.240277 -31.636204) (xy 261.244427 -31.664402)
			(xy 261.760968 -31.664402) (xy 261.765039 -31.60878) (xy 261.777165 -31.554343) (xy 261.797088 -31.502252)
			(xy 261.824384 -31.453617) (xy 261.85847 -31.409474) (xy 261.898619 -31.370765) (xy 261.943977 -31.338314)
			(xy 261.993577 -31.312813) (xy 262.046361 -31.294806) (xy 262.101204 -31.284676) (xy 262.156938 -31.282639)
			(xy 262.212375 -31.288739) (xy 262.266332 -31.302845) (xy 262.317661 -31.324657) (xy 262.365267 -31.353711)
			(xy 262.408135 -31.389386) (xy 262.445352 -31.430923) (xy 262.476125 -31.477436) (xy 262.499797 -31.527933)
			(xy 262.515865 -31.58134) (xy 262.523985 -31.636516) (xy 262.524494 -31.664402) (xy 262.523985 -31.692288)
			(xy 262.515865 -31.747464) (xy 262.506925 -31.777178) (xy 263.026142 -31.777178) (xy 263.030213 -31.721556)
			(xy 263.042339 -31.667119) (xy 263.062262 -31.615028) (xy 263.089558 -31.566393) (xy 263.123644 -31.52225)
			(xy 263.163793 -31.483541) (xy 263.209151 -31.45109) (xy 263.258751 -31.425589) (xy 263.311535 -31.407582)
			(xy 263.366378 -31.397452) (xy 263.422112 -31.395415) (xy 263.477549 -31.401515) (xy 263.531506 -31.415621)
			(xy 263.582835 -31.437433) (xy 263.630441 -31.466487) (xy 263.673309 -31.502162) (xy 263.710526 -31.543699)
			(xy 263.741299 -31.590212) (xy 263.764971 -31.640709) (xy 263.781039 -31.694116) (xy 263.789159 -31.749292)
			(xy 263.789668 -31.777178) (xy 263.789159 -31.805064) (xy 263.781039 -31.86024) (xy 263.764971 -31.913647)
			(xy 263.741299 -31.964144) (xy 263.710526 -32.010657) (xy 263.673309 -32.052194) (xy 263.630441 -32.087869)
			(xy 263.582835 -32.116923) (xy 263.531506 -32.138735) (xy 263.477549 -32.152841) (xy 263.422112 -32.158941)
			(xy 263.366378 -32.156904) (xy 263.311535 -32.146774) (xy 263.258751 -32.128767) (xy 263.209151 -32.103266)
			(xy 263.163793 -32.070815) (xy 263.123644 -32.032106) (xy 263.089558 -31.987963) (xy 263.062262 -31.939328)
			(xy 263.042339 -31.887237) (xy 263.030213 -31.8328) (xy 263.026142 -31.777178) (xy 262.506925 -31.777178)
			(xy 262.499797 -31.800871) (xy 262.476125 -31.851368) (xy 262.445352 -31.897881) (xy 262.408135 -31.939418)
			(xy 262.365267 -31.975093) (xy 262.317661 -32.004147) (xy 262.266332 -32.025959) (xy 262.212375 -32.040065)
			(xy 262.156938 -32.046165) (xy 262.101204 -32.044128) (xy 262.046361 -32.033998) (xy 261.993577 -32.015991)
			(xy 261.943977 -31.99049) (xy 261.898619 -31.958039) (xy 261.85847 -31.91933) (xy 261.824384 -31.875187)
			(xy 261.797088 -31.826552) (xy 261.777165 -31.774461) (xy 261.765039 -31.720024) (xy 261.760968 -31.664402)
			(xy 261.244427 -31.664402) (xy 261.248397 -31.69138) (xy 261.248906 -31.719266) (xy 261.248397 -31.747152)
			(xy 261.240277 -31.802328) (xy 261.224209 -31.855735) (xy 261.200537 -31.906232) (xy 261.169764 -31.952745)
			(xy 261.132547 -31.994282) (xy 261.089679 -32.029957) (xy 261.042073 -32.059011) (xy 260.990744 -32.080823)
			(xy 260.936787 -32.094929) (xy 260.88135 -32.101029) (xy 260.825616 -32.098992) (xy 260.770773 -32.088862)
			(xy 260.717989 -32.070855) (xy 260.668389 -32.045354) (xy 260.623031 -32.012903) (xy 260.582882 -31.974194)
			(xy 260.548796 -31.930051) (xy 260.5215 -31.881416) (xy 260.501577 -31.829325) (xy 260.489451 -31.774888)
			(xy 260.48538 -31.719266) (xy 259.930453 -31.719266) (xy 259.913773 -31.754848) (xy 259.883 -31.801361)
			(xy 259.845783 -31.842898) (xy 259.802915 -31.878573) (xy 259.755309 -31.907627) (xy 259.70398 -31.929439)
			(xy 259.650023 -31.943545) (xy 259.594586 -31.949645) (xy 259.538852 -31.947608) (xy 259.484009 -31.937478)
			(xy 259.431225 -31.919471) (xy 259.381625 -31.89397) (xy 259.336267 -31.861519) (xy 259.296118 -31.82281)
			(xy 259.262032 -31.778667) (xy 259.234736 -31.730032) (xy 259.214813 -31.677941) (xy 259.202687 -31.623504)
			(xy 259.198616 -31.567882) (xy 257.32486 -31.567882) (xy 257.32486 -32.722312) (xy 266.80668 -32.722312)
			(xy 266.80668 -31.858712) (xy 266.80717 -31.828728) (xy 266.814998 -31.769272) (xy 266.830519 -31.711347)
			(xy 266.853468 -31.655943) (xy 266.883452 -31.604009) (xy 266.919958 -31.556433) (xy 266.962363 -31.514028)
			(xy 267.009939 -31.477522) (xy 267.061873 -31.447538) (xy 267.117277 -31.424589) (xy 267.175202 -31.409068)
			(xy 267.234658 -31.40124) (xy 267.294626 -31.40124) (xy 267.354082 -31.409068) (xy 267.412007 -31.424589)
			(xy 267.467411 -31.447538) (xy 267.519345 -31.477522) (xy 267.566921 -31.514028) (xy 267.609326 -31.556433)
			(xy 267.645832 -31.604009) (xy 267.675816 -31.655943) (xy 267.698765 -31.711347) (xy 267.714286 -31.769272)
			(xy 267.722114 -31.828728) (xy 267.722604 -31.858712) (xy 267.722604 -32.714184) (xy 277.047452 -32.714184)
			(xy 277.047452 -31.850584) (xy 277.047942 -31.820616) (xy 277.055765 -31.761194) (xy 277.071278 -31.703301)
			(xy 277.094214 -31.647928) (xy 277.124181 -31.596022) (xy 277.160668 -31.548472) (xy 277.203048 -31.506092)
			(xy 277.250598 -31.469605) (xy 277.302504 -31.439638) (xy 277.357877 -31.416702) (xy 277.41577 -31.401189)
			(xy 277.475192 -31.393366) (xy 277.535128 -31.393366) (xy 277.59455 -31.401189) (xy 277.652443 -31.416702)
			(xy 277.707816 -31.439638) (xy 277.759722 -31.469605) (xy 277.807272 -31.506092) (xy 277.849652 -31.548472)
			(xy 277.886139 -31.596022) (xy 277.916106 -31.647928) (xy 277.939042 -31.703301) (xy 277.954555 -31.761194)
			(xy 277.962378 -31.820616) (xy 277.962868 -31.850584) (xy 277.962868 -32.714184) (xy 277.962378 -32.744152)
			(xy 277.954555 -32.803574) (xy 277.939042 -32.861467) (xy 277.916106 -32.91684) (xy 277.886139 -32.968746)
			(xy 277.849652 -33.016296) (xy 277.807272 -33.058676) (xy 277.759722 -33.095163) (xy 277.707816 -33.12513)
			(xy 277.652443 -33.148066) (xy 277.59455 -33.163579) (xy 277.535128 -33.171402) (xy 277.475192 -33.171402)
			(xy 277.41577 -33.163579) (xy 277.357877 -33.148066) (xy 277.302504 -33.12513) (xy 277.250598 -33.095163)
			(xy 277.203048 -33.058676) (xy 277.160668 -33.016296) (xy 277.124181 -32.968746) (xy 277.094214 -32.91684)
			(xy 277.071278 -32.861467) (xy 277.055765 -32.803574) (xy 277.047942 -32.744152) (xy 277.047452 -32.714184)
			(xy 267.722604 -32.714184) (xy 267.722604 -32.722312) (xy 267.722114 -32.752296) (xy 267.714286 -32.811752)
			(xy 267.698765 -32.869677) (xy 267.675816 -32.925081) (xy 267.645832 -32.977015) (xy 267.609326 -33.024591)
			(xy 267.566921 -33.066996) (xy 267.519345 -33.103502) (xy 267.467411 -33.133486) (xy 267.412007 -33.156435)
			(xy 267.354082 -33.171956) (xy 267.294626 -33.179784) (xy 267.234658 -33.179784) (xy 267.175202 -33.171956)
			(xy 267.117277 -33.156435) (xy 267.061873 -33.133486) (xy 267.009939 -33.103502) (xy 266.962363 -33.066996)
			(xy 266.919958 -33.024591) (xy 266.883452 -32.977015) (xy 266.853468 -32.925081) (xy 266.830519 -32.869677)
			(xy 266.814998 -32.811752) (xy 266.80717 -32.752296) (xy 266.80668 -32.722312) (xy 257.32486 -32.722312)
			(xy 257.32486 -33.439862) (xy 257.325876 -33.449514) (xy 257.327501 -33.456759) (xy 257.334339 -33.469932)
			(xy 257.339338 -33.475422) (xy 258.386326 -34.52241) (xy 264.95248 -34.52241) (xy 264.95248 -33.65881)
			(xy 264.95297 -33.628826) (xy 264.960798 -33.56937) (xy 264.976319 -33.511445) (xy 264.999268 -33.456041)
			(xy 265.029252 -33.404107) (xy 265.065758 -33.356531) (xy 265.108163 -33.314126) (xy 265.155739 -33.27762)
			(xy 265.207673 -33.247636) (xy 265.263077 -33.224687) (xy 265.321002 -33.209166) (xy 265.380458 -33.201338)
			(xy 265.440426 -33.201338) (xy 265.499882 -33.209166) (xy 265.557807 -33.224687) (xy 265.613211 -33.247636)
			(xy 265.665145 -33.27762) (xy 265.712721 -33.314126) (xy 265.755126 -33.356531) (xy 265.791632 -33.404107)
			(xy 265.821616 -33.456041) (xy 265.844565 -33.511445) (xy 265.860086 -33.56937) (xy 265.867914 -33.628826)
			(xy 265.868404 -33.65881) (xy 265.868404 -34.520886) (xy 279.68956 -34.520886) (xy 279.68956 -33.657286)
			(xy 279.69005 -33.627318) (xy 279.697873 -33.567896) (xy 279.713386 -33.510003) (xy 279.736322 -33.45463)
			(xy 279.766289 -33.402724) (xy 279.802776 -33.355174) (xy 279.845156 -33.312794) (xy 279.892706 -33.276307)
			(xy 279.944612 -33.24634) (xy 279.999985 -33.223404) (xy 280.057878 -33.207891) (xy 280.1173 -33.200068)
			(xy 280.177236 -33.200068) (xy 280.236658 -33.207891) (xy 280.294551 -33.223404) (xy 280.349924 -33.24634)
			(xy 280.40183 -33.276307) (xy 280.44938 -33.312794) (xy 280.49176 -33.355174) (xy 280.528247 -33.402724)
			(xy 280.558214 -33.45463) (xy 280.58115 -33.510003) (xy 280.596663 -33.567896) (xy 280.604486 -33.627318)
			(xy 280.604976 -33.657286) (xy 280.604976 -34.520886) (xy 280.604486 -34.550854) (xy 280.596663 -34.610276)
			(xy 280.58115 -34.668169) (xy 280.558214 -34.723542) (xy 280.528247 -34.775448) (xy 280.49176 -34.822998)
			(xy 280.44938 -34.865378) (xy 280.40183 -34.901865) (xy 280.349924 -34.931832) (xy 280.294551 -34.954768)
			(xy 280.236658 -34.970281) (xy 280.177236 -34.978104) (xy 280.1173 -34.978104) (xy 280.057878 -34.970281)
			(xy 279.999985 -34.954768) (xy 279.944612 -34.931832) (xy 279.892706 -34.901865) (xy 279.845156 -34.865378)
			(xy 279.802776 -34.822998) (xy 279.766289 -34.775448) (xy 279.736322 -34.723542) (xy 279.713386 -34.668169)
			(xy 279.697873 -34.610276) (xy 279.69005 -34.550854) (xy 279.68956 -34.520886) (xy 265.868404 -34.520886)
			(xy 265.868404 -34.52241) (xy 265.867914 -34.552394) (xy 265.860086 -34.61185) (xy 265.844565 -34.669775)
			(xy 265.821616 -34.725179) (xy 265.791632 -34.777113) (xy 265.755126 -34.824689) (xy 265.712721 -34.867094)
			(xy 265.665145 -34.9036) (xy 265.613211 -34.933584) (xy 265.557807 -34.956533) (xy 265.499882 -34.972054)
			(xy 265.440426 -34.979882) (xy 265.380458 -34.979882) (xy 265.321002 -34.972054) (xy 265.263077 -34.956533)
			(xy 265.207673 -34.933584) (xy 265.155739 -34.9036) (xy 265.108163 -34.867094) (xy 265.065758 -34.824689)
			(xy 265.029252 -34.777113) (xy 264.999268 -34.725179) (xy 264.976319 -34.669775) (xy 264.960798 -34.61185)
			(xy 264.95297 -34.552394) (xy 264.95248 -34.52241) (xy 258.386326 -34.52241) (xy 259.128768 -35.264852)
			(xy 262.102344 -35.264852) (xy 262.106415 -35.20923) (xy 262.118541 -35.154793) (xy 262.138464 -35.102702)
			(xy 262.16576 -35.054067) (xy 262.199846 -35.009924) (xy 262.239995 -34.971215) (xy 262.285353 -34.938764)
			(xy 262.334953 -34.913263) (xy 262.387737 -34.895256) (xy 262.44258 -34.885126) (xy 262.498314 -34.883089)
			(xy 262.553751 -34.889189) (xy 262.607708 -34.903295) (xy 262.659037 -34.925107) (xy 262.706643 -34.954161)
			(xy 262.749511 -34.989836) (xy 262.786728 -35.031373) (xy 262.817501 -35.077886) (xy 262.841173 -35.128383)
			(xy 262.857241 -35.18179) (xy 262.865361 -35.236966) (xy 262.86587 -35.264852) (xy 262.865361 -35.292738)
			(xy 262.857241 -35.347914) (xy 262.841173 -35.401321) (xy 262.817501 -35.451818) (xy 262.786728 -35.498331)
			(xy 262.749511 -35.539868) (xy 262.706643 -35.575543) (xy 262.659037 -35.604597) (xy 262.607708 -35.626409)
			(xy 262.553751 -35.640515) (xy 262.498314 -35.646615) (xy 262.44258 -35.644578) (xy 262.387737 -35.634448)
			(xy 262.334953 -35.616441) (xy 262.285353 -35.59094) (xy 262.239995 -35.558489) (xy 262.199846 -35.51978)
			(xy 262.16576 -35.475637) (xy 262.138464 -35.427002) (xy 262.118541 -35.374911) (xy 262.106415 -35.320474)
			(xy 262.102344 -35.264852) (xy 259.128768 -35.264852) (xy 260.150864 -36.286948) (xy 263.400284 -36.286948)
			(xy 263.404355 -36.231326) (xy 263.416481 -36.176889) (xy 263.436404 -36.124798) (xy 263.4637 -36.076163)
			(xy 263.497786 -36.03202) (xy 263.537935 -35.993311) (xy 263.583293 -35.96086) (xy 263.632893 -35.935359)
			(xy 263.685677 -35.917352) (xy 263.74052 -35.907222) (xy 263.796254 -35.905185) (xy 263.851691 -35.911285)
			(xy 263.905648 -35.925391) (xy 263.956977 -35.947203) (xy 264.004583 -35.976257) (xy 264.047451 -36.011932)
			(xy 264.084668 -36.053469) (xy 264.115441 -36.099982) (xy 264.139113 -36.150479) (xy 264.155181 -36.203886)
			(xy 264.163301 -36.259062) (xy 264.16381 -36.286948) (xy 264.163301 -36.314834) (xy 264.155181 -36.37001)
			(xy 264.139113 -36.423417) (xy 264.115441 -36.473914) (xy 264.087896 -36.515548) (xy 265.214098 -36.515548)
			(xy 265.218169 -36.459926) (xy 265.230295 -36.405489) (xy 265.250218 -36.353398) (xy 265.277514 -36.304763)
			(xy 265.3116 -36.26062) (xy 265.351749 -36.221911) (xy 265.397107 -36.18946) (xy 265.446707 -36.163959)
			(xy 265.499491 -36.145952) (xy 265.554334 -36.135822) (xy 265.610068 -36.133785) (xy 265.665505 -36.139885)
			(xy 265.719462 -36.153991) (xy 265.770791 -36.175803) (xy 265.818397 -36.204857) (xy 265.861265 -36.240532)
			(xy 265.898482 -36.282069) (xy 265.929255 -36.328582) (xy 265.952927 -36.379079) (xy 265.968995 -36.432486)
			(xy 265.977115 -36.487662) (xy 265.977624 -36.515548) (xy 265.977115 -36.543434) (xy 265.968995 -36.59861)
			(xy 265.968538 -36.60013) (xy 270.198603 -36.60013) (xy 270.202607 -36.512245) (xy 270.214587 -36.425088)
			(xy 270.234442 -36.339381) (xy 270.262009 -36.255836) (xy 270.297059 -36.175143) (xy 270.339301 -36.097971)
			(xy 270.388386 -36.024961) (xy 270.443907 -35.956717) (xy 270.505404 -35.893804) (xy 270.572366 -35.836744)
			(xy 270.64424 -35.78601) (xy 270.72043 -35.742022) (xy 270.800304 -35.705144) (xy 270.883201 -35.675683)
			(xy 270.968433 -35.653881) (xy 271.055295 -35.639921) (xy 271.143066 -35.633917) (xy 271.23102 -35.63592)
			(xy 271.318427 -35.645912) (xy 271.404563 -35.663812) (xy 271.488715 -35.68947) (xy 271.570185 -35.722674)
			(xy 271.648298 -35.763148) (xy 271.722406 -35.810559) (xy 271.791897 -35.864512) (xy 271.804988 -35.876738)
			(xy 276.917148 -35.876738) (xy 276.921219 -35.821116) (xy 276.933345 -35.766679) (xy 276.953268 -35.714588)
			(xy 276.980564 -35.665953) (xy 277.01465 -35.62181) (xy 277.054799 -35.583101) (xy 277.100157 -35.55065)
			(xy 277.149757 -35.525149) (xy 277.202541 -35.507142) (xy 277.257384 -35.497012) (xy 277.313118 -35.494975)
			(xy 277.368555 -35.501075) (xy 277.422512 -35.515181) (xy 277.473841 -35.536993) (xy 277.521447 -35.566047)
			(xy 277.564315 -35.601722) (xy 277.601532 -35.643259) (xy 277.632305 -35.689772) (xy 277.655977 -35.740269)
			(xy 277.672045 -35.793676) (xy 277.680165 -35.848852) (xy 277.680674 -35.876738) (xy 280.988768 -35.876738)
			(xy 280.992839 -35.821116) (xy 281.004965 -35.766679) (xy 281.024888 -35.714588) (xy 281.052184 -35.665953)
			(xy 281.08627 -35.62181) (xy 281.126419 -35.583101) (xy 281.171777 -35.55065) (xy 281.221377 -35.525149)
			(xy 281.274161 -35.507142) (xy 281.329004 -35.497012) (xy 281.384738 -35.494975) (xy 281.440175 -35.501075)
			(xy 281.494132 -35.515181) (xy 281.545461 -35.536993) (xy 281.593067 -35.566047) (xy 281.635935 -35.601722)
			(xy 281.673152 -35.643259) (xy 281.703925 -35.689772) (xy 281.727597 -35.740269) (xy 281.743665 -35.793676)
			(xy 281.751785 -35.848852) (xy 281.752294 -35.876738) (xy 281.751785 -35.904624) (xy 281.743665 -35.9598)
			(xy 281.727597 -36.013207) (xy 281.703925 -36.063704) (xy 281.673152 -36.110217) (xy 281.635935 -36.151754)
			(xy 281.593067 -36.187429) (xy 281.545461 -36.216483) (xy 281.494132 -36.238295) (xy 281.440175 -36.252401)
			(xy 281.384738 -36.258501) (xy 281.329004 -36.256464) (xy 281.274161 -36.246334) (xy 281.221377 -36.228327)
			(xy 281.171777 -36.202826) (xy 281.126419 -36.170375) (xy 281.08627 -36.131666) (xy 281.052184 -36.087523)
			(xy 281.024888 -36.038888) (xy 281.004965 -35.986797) (xy 280.992839 -35.93236) (xy 280.988768 -35.876738)
			(xy 277.680674 -35.876738) (xy 277.680165 -35.904624) (xy 277.672045 -35.9598) (xy 277.655977 -36.013207)
			(xy 277.632305 -36.063704) (xy 277.601532 -36.110217) (xy 277.564315 -36.151754) (xy 277.521447 -36.187429)
			(xy 277.473841 -36.216483) (xy 277.422512 -36.238295) (xy 277.368555 -36.252401) (xy 277.313118 -36.258501)
			(xy 277.257384 -36.256464) (xy 277.202541 -36.246334) (xy 277.149757 -36.228327) (xy 277.100157 -36.202826)
			(xy 277.054799 -36.170375) (xy 277.01465 -36.131666) (xy 276.980564 -36.087523) (xy 276.953268 -36.038888)
			(xy 276.933345 -35.986797) (xy 276.921219 -35.93236) (xy 276.917148 -35.876738) (xy 271.804988 -35.876738)
			(xy 271.856193 -35.92456) (xy 271.914762 -35.990207) (xy 271.967119 -36.060907) (xy 272.012831 -36.136076)
			(xy 272.051517 -36.21509) (xy 272.082858 -36.297295) (xy 272.106593 -36.382009) (xy 272.122527 -36.46853)
			(xy 272.12631 -36.50996) (xy 278.813766 -36.50996) (xy 278.817837 -36.454338) (xy 278.829963 -36.399901)
			(xy 278.849886 -36.34781) (xy 278.877182 -36.299175) (xy 278.911268 -36.255032) (xy 278.951417 -36.216323)
			(xy 278.996775 -36.183872) (xy 279.046375 -36.158371) (xy 279.099159 -36.140364) (xy 279.154002 -36.130234)
			(xy 279.209736 -36.128197) (xy 279.265173 -36.134297) (xy 279.31913 -36.148403) (xy 279.370459 -36.170215)
			(xy 279.418065 -36.199269) (xy 279.460933 -36.234944) (xy 279.49815 -36.276481) (xy 279.528923 -36.322994)
			(xy 279.552595 -36.373491) (xy 279.568663 -36.426898) (xy 279.572588 -36.453572) (xy 282.128466 -36.453572)
			(xy 282.132537 -36.39795) (xy 282.144663 -36.343513) (xy 282.164586 -36.291422) (xy 282.191882 -36.242787)
			(xy 282.225968 -36.198644) (xy 282.266117 -36.159935) (xy 282.311475 -36.127484) (xy 282.361075 -36.101983)
			(xy 282.413859 -36.083976) (xy 282.468702 -36.073846) (xy 282.524436 -36.071809) (xy 282.579873 -36.077909)
			(xy 282.63383 -36.092015) (xy 282.685159 -36.113827) (xy 282.732765 -36.142881) (xy 282.775633 -36.178556)
			(xy 282.81285 -36.220093) (xy 282.843623 -36.266606) (xy 282.867295 -36.317103) (xy 282.883363 -36.37051)
			(xy 282.891483 -36.425686) (xy 282.891992 -36.453572) (xy 282.891483 -36.481458) (xy 282.883363 -36.536634)
			(xy 282.867295 -36.590041) (xy 282.843623 -36.640538) (xy 282.81285 -36.687051) (xy 282.775633 -36.728588)
			(xy 282.732765 -36.764263) (xy 282.685159 -36.793317) (xy 282.63383 -36.815129) (xy 282.579873 -36.829235)
			(xy 282.524436 -36.835335) (xy 282.468702 -36.833298) (xy 282.413859 -36.823168) (xy 282.361075 -36.805161)
			(xy 282.311475 -36.77966) (xy 282.266117 -36.747209) (xy 282.225968 -36.7085) (xy 282.191882 -36.664357)
			(xy 282.164586 -36.615722) (xy 282.144663 -36.563631) (xy 282.132537 -36.509194) (xy 282.128466 -36.453572)
			(xy 279.572588 -36.453572) (xy 279.576783 -36.482074) (xy 279.577292 -36.50996) (xy 279.576783 -36.537846)
			(xy 279.568663 -36.593022) (xy 279.552595 -36.646429) (xy 279.528923 -36.696926) (xy 279.49815 -36.743439)
			(xy 279.460933 -36.784976) (xy 279.418065 -36.820651) (xy 279.370459 -36.849705) (xy 279.31913 -36.871517)
			(xy 279.265173 -36.885623) (xy 279.209736 -36.891723) (xy 279.154002 -36.889686) (xy 279.099159 -36.879556)
			(xy 279.046375 -36.861549) (xy 278.996775 -36.836048) (xy 278.951417 -36.803597) (xy 278.911268 -36.764888)
			(xy 278.877182 -36.720745) (xy 278.849886 -36.67211) (xy 278.829963 -36.620019) (xy 278.817837 -36.565582)
			(xy 278.813766 -36.50996) (xy 272.12631 -36.50996) (xy 272.130527 -36.556142) (xy 272.131028 -36.60013)
			(xy 272.130527 -36.644118) (xy 272.122527 -36.73173) (xy 272.106593 -36.818251) (xy 272.082858 -36.902965)
			(xy 272.051517 -36.98517) (xy 272.012831 -37.064184) (xy 271.967119 -37.139353) (xy 271.914762 -37.210053)
			(xy 271.856193 -37.2757) (xy 271.791897 -37.335748) (xy 271.722406 -37.389701) (xy 271.648298 -37.437112)
			(xy 271.574867 -37.47516) (xy 275.95906 -37.47516) (xy 275.963131 -37.419538) (xy 275.975257 -37.365101)
			(xy 275.99518 -37.31301) (xy 276.022476 -37.264375) (xy 276.056562 -37.220232) (xy 276.096711 -37.181523)
			(xy 276.142069 -37.149072) (xy 276.191669 -37.123571) (xy 276.244453 -37.105564) (xy 276.299296 -37.095434)
			(xy 276.35503 -37.093397) (xy 276.410467 -37.099497) (xy 276.464424 -37.113603) (xy 276.515753 -37.135415)
			(xy 276.563359 -37.164469) (xy 276.606227 -37.200144) (xy 276.643444 -37.241681) (xy 276.674217 -37.288194)
			(xy 276.697889 -37.338691) (xy 276.713957 -37.392098) (xy 276.722077 -37.447274) (xy 276.722586 -37.47516)
			(xy 276.722077 -37.503046) (xy 276.713957 -37.558222) (xy 276.697889 -37.611629) (xy 276.674217 -37.662126)
			(xy 276.674064 -37.662358) (xy 278.148286 -37.662358) (xy 278.152357 -37.606736) (xy 278.164483 -37.552299)
			(xy 278.184406 -37.500208) (xy 278.211702 -37.451573) (xy 278.245788 -37.40743) (xy 278.285937 -37.368721)
			(xy 278.331295 -37.33627) (xy 278.380895 -37.310769) (xy 278.433679 -37.292762) (xy 278.488522 -37.282632)
			(xy 278.544256 -37.280595) (xy 278.599693 -37.286695) (xy 278.65365 -37.300801) (xy 278.704979 -37.322613)
			(xy 278.752585 -37.351667) (xy 278.795453 -37.387342) (xy 278.83267 -37.428879) (xy 278.863443 -37.475392)
			(xy 278.887115 -37.525889) (xy 278.903183 -37.579296) (xy 278.911303 -37.634472) (xy 278.911812 -37.662358)
			(xy 278.911303 -37.690244) (xy 278.903183 -37.74542) (xy 278.887115 -37.798827) (xy 278.863443 -37.849324)
			(xy 278.83267 -37.895837) (xy 278.795453 -37.937374) (xy 278.752585 -37.973049) (xy 278.704979 -38.002103)
			(xy 278.65365 -38.023915) (xy 278.599693 -38.038021) (xy 278.544256 -38.044121) (xy 278.488522 -38.042084)
			(xy 278.433679 -38.031954) (xy 278.380895 -38.013947) (xy 278.331295 -37.988446) (xy 278.285937 -37.955995)
			(xy 278.245788 -37.917286) (xy 278.211702 -37.873143) (xy 278.184406 -37.824508) (xy 278.164483 -37.772417)
			(xy 278.152357 -37.71798) (xy 278.148286 -37.662358) (xy 276.674064 -37.662358) (xy 276.643444 -37.708639)
			(xy 276.606227 -37.750176) (xy 276.563359 -37.785851) (xy 276.515753 -37.814905) (xy 276.464424 -37.836717)
			(xy 276.410467 -37.850823) (xy 276.35503 -37.856923) (xy 276.299296 -37.854886) (xy 276.244453 -37.844756)
			(xy 276.191669 -37.826749) (xy 276.142069 -37.801248) (xy 276.096711 -37.768797) (xy 276.056562 -37.730088)
			(xy 276.022476 -37.685945) (xy 275.99518 -37.63731) (xy 275.975257 -37.585219) (xy 275.963131 -37.530782)
			(xy 275.95906 -37.47516) (xy 271.574867 -37.47516) (xy 271.570185 -37.477586) (xy 271.488715 -37.51079)
			(xy 271.404563 -37.536448) (xy 271.318427 -37.554348) (xy 271.23102 -37.56434) (xy 271.143066 -37.566343)
			(xy 271.055295 -37.560339) (xy 270.968433 -37.546379) (xy 270.883201 -37.524577) (xy 270.800304 -37.495116)
			(xy 270.72043 -37.458238) (xy 270.64424 -37.41425) (xy 270.572366 -37.363516) (xy 270.505404 -37.306456)
			(xy 270.443907 -37.243543) (xy 270.388386 -37.175299) (xy 270.339301 -37.102289) (xy 270.297059 -37.025117)
			(xy 270.262009 -36.944424) (xy 270.234442 -36.860879) (xy 270.214587 -36.775172) (xy 270.202607 -36.688015)
			(xy 270.198603 -36.60013) (xy 265.968538 -36.60013) (xy 265.952927 -36.652017) (xy 265.929255 -36.702514)
			(xy 265.898482 -36.749027) (xy 265.861265 -36.790564) (xy 265.818397 -36.826239) (xy 265.770791 -36.855293)
			(xy 265.719462 -36.877105) (xy 265.665505 -36.891211) (xy 265.610068 -36.897311) (xy 265.554334 -36.895274)
			(xy 265.499491 -36.885144) (xy 265.446707 -36.867137) (xy 265.397107 -36.841636) (xy 265.351749 -36.809185)
			(xy 265.3116 -36.770476) (xy 265.277514 -36.726333) (xy 265.250218 -36.677698) (xy 265.230295 -36.625607)
			(xy 265.218169 -36.57117) (xy 265.214098 -36.515548) (xy 264.087896 -36.515548) (xy 264.084668 -36.520427)
			(xy 264.047451 -36.561964) (xy 264.004583 -36.597639) (xy 263.956977 -36.626693) (xy 263.905648 -36.648505)
			(xy 263.851691 -36.662611) (xy 263.796254 -36.668711) (xy 263.74052 -36.666674) (xy 263.685677 -36.656544)
			(xy 263.632893 -36.638537) (xy 263.583293 -36.613036) (xy 263.537935 -36.580585) (xy 263.497786 -36.541876)
			(xy 263.4637 -36.497733) (xy 263.436404 -36.449098) (xy 263.416481 -36.397007) (xy 263.404355 -36.34257)
			(xy 263.400284 -36.286948) (xy 260.150864 -36.286948) (xy 261.638034 -37.774118) (xy 263.664698 -37.774118)
			(xy 263.668769 -37.718496) (xy 263.680895 -37.664059) (xy 263.700818 -37.611968) (xy 263.728114 -37.563333)
			(xy 263.7622 -37.51919) (xy 263.802349 -37.480481) (xy 263.847707 -37.44803) (xy 263.897307 -37.422529)
			(xy 263.950091 -37.404522) (xy 264.004934 -37.394392) (xy 264.060668 -37.392355) (xy 264.116105 -37.398455)
			(xy 264.170062 -37.412561) (xy 264.221391 -37.434373) (xy 264.268997 -37.463427) (xy 264.311865 -37.499102)
			(xy 264.349082 -37.540639) (xy 264.379855 -37.587152) (xy 264.403527 -37.637649) (xy 264.419595 -37.691056)
			(xy 264.427715 -37.746232) (xy 264.428224 -37.774118) (xy 264.427715 -37.802004) (xy 264.419595 -37.85718)
			(xy 264.403527 -37.910587) (xy 264.379855 -37.961084) (xy 264.349082 -38.007597) (xy 264.311865 -38.049134)
			(xy 264.268997 -38.084809) (xy 264.221391 -38.113863) (xy 264.170062 -38.135675) (xy 264.116105 -38.149781)
			(xy 264.060668 -38.155881) (xy 264.004934 -38.153844) (xy 263.950091 -38.143714) (xy 263.897307 -38.125707)
			(xy 263.847707 -38.100206) (xy 263.802349 -38.067755) (xy 263.7622 -38.029046) (xy 263.728114 -37.984903)
			(xy 263.700818 -37.936268) (xy 263.680895 -37.884177) (xy 263.668769 -37.82974) (xy 263.664698 -37.774118)
			(xy 261.638034 -37.774118) (xy 262.593863 -38.729947) (xy 281.90092 -38.729947) (xy 281.90092 -38.675453)
			(xy 281.908675 -38.621512) (xy 281.924028 -38.569225) (xy 281.946665 -38.519654) (xy 281.976127 -38.473809)
			(xy 282.011813 -38.432624) (xy 282.052997 -38.396937) (xy 282.09884 -38.367473) (xy 282.14841 -38.344834)
			(xy 282.200697 -38.329479) (xy 282.254637 -38.321721) (xy 282.281884 -38.321234) (xy 282.310188 -38.32172)
			(xy 282.366178 -38.330071) (xy 282.420318 -38.346606) (xy 282.471419 -38.370961) (xy 282.518359 -38.402603)
			(xy 282.560106 -38.440835) (xy 282.595743 -38.484818) (xy 282.61056 -38.50894) (xy 282.618113 -38.521005)
			(xy 282.638741 -38.540609) (xy 282.663983 -38.553751) (xy 282.691873 -38.559407) (xy 282.72024 -38.557137)
			(xy 282.746875 -38.547117) (xy 282.769705 -38.530129) (xy 282.778708 -38.5191) (xy 282.796895 -38.496224)
			(xy 282.839058 -38.45576) (xy 282.886893 -38.422193) (xy 282.939285 -38.396306) (xy 282.995009 -38.378703)
			(xy 283.052765 -38.369797) (xy 283.081984 -38.36924) (xy 283.109241 -38.369606) (xy 283.163201 -38.377362)
			(xy 283.215507 -38.392719) (xy 283.265095 -38.415363) (xy 283.310956 -38.444834) (xy 283.352156 -38.480533)
			(xy 283.387856 -38.521731) (xy 283.417329 -38.567591) (xy 283.439976 -38.617178) (xy 283.455335 -38.669484)
			(xy 283.463093 -38.723443) (xy 283.463093 -38.777957) (xy 283.455335 -38.831916) (xy 283.439976 -38.884222)
			(xy 283.417329 -38.933809) (xy 283.387856 -38.979669) (xy 283.352156 -39.020867) (xy 283.310956 -39.056566)
			(xy 283.265095 -39.086037) (xy 283.215507 -39.108681) (xy 283.163201 -39.124038) (xy 283.109241 -39.131794)
			(xy 283.081984 -39.132256) (xy 283.053681 -39.131721) (xy 282.997694 -39.12338) (xy 282.943555 -39.106854)
			(xy 282.892453 -39.082507) (xy 282.845513 -39.050873) (xy 282.803764 -39.012647) (xy 282.768125 -38.968669)
			(xy 282.753308 -38.94455) (xy 282.745666 -38.932546) (xy 282.725056 -38.912948) (xy 282.699834 -38.899806)
			(xy 282.671962 -38.894144) (xy 282.643611 -38.896401) (xy 282.616987 -38.906403) (xy 282.594162 -38.923372)
			(xy 282.58516 -38.93439) (xy 282.566989 -38.957279) (xy 282.524823 -38.997743) (xy 282.476984 -39.031309)
			(xy 282.424589 -39.057194) (xy 282.368862 -39.074793) (xy 282.311104 -39.083695) (xy 282.281884 -39.08425)
			(xy 282.254637 -39.083679) (xy 282.200697 -39.075921) (xy 282.14841 -39.060566) (xy 282.09884 -39.037927)
			(xy 282.052997 -39.008463) (xy 282.011813 -38.972776) (xy 281.976127 -38.931591) (xy 281.946665 -38.885746)
			(xy 281.924028 -38.836175) (xy 281.908675 -38.783888) (xy 281.90092 -38.729947) (xy 262.593863 -38.729947)
			(xy 263.835896 -39.97198) (xy 284.095696 -39.97198) (xy 284.099767 -39.916358) (xy 284.111893 -39.861921)
			(xy 284.131816 -39.80983) (xy 284.159112 -39.761195) (xy 284.193198 -39.717052) (xy 284.233347 -39.678343)
			(xy 284.278705 -39.645892) (xy 284.328305 -39.620391) (xy 284.381089 -39.602384) (xy 284.435932 -39.592254)
			(xy 284.491666 -39.590217) (xy 284.547103 -39.596317) (xy 284.60106 -39.610423) (xy 284.652389 -39.632235)
			(xy 284.699995 -39.661289) (xy 284.742863 -39.696964) (xy 284.78008 -39.738501) (xy 284.810853 -39.785014)
			(xy 284.834525 -39.835511) (xy 284.850593 -39.888918) (xy 284.858713 -39.944094) (xy 284.859222 -39.97198)
			(xy 284.858713 -39.999866) (xy 284.850593 -40.055042) (xy 284.834525 -40.108449) (xy 284.810853 -40.158946)
			(xy 284.78008 -40.205459) (xy 284.742863 -40.246996) (xy 284.699995 -40.282671) (xy 284.652389 -40.311725)
			(xy 284.60106 -40.333537) (xy 284.547103 -40.347643) (xy 284.491666 -40.353743) (xy 284.435932 -40.351706)
			(xy 284.381089 -40.341576) (xy 284.328305 -40.323569) (xy 284.278705 -40.298068) (xy 284.233347 -40.265617)
			(xy 284.193198 -40.226908) (xy 284.159112 -40.182765) (xy 284.131816 -40.13413) (xy 284.111893 -40.082039)
			(xy 284.099767 -40.027602) (xy 284.095696 -39.97198) (xy 263.835896 -39.97198) (xy 265.132671 -41.268755)
			(xy 274.043827 -41.268755) (xy 274.043827 -41.214245) (xy 274.051585 -41.16029) (xy 274.066942 -41.107988)
			(xy 274.089586 -41.058404) (xy 274.119057 -41.012547) (xy 274.154753 -40.971352) (xy 274.195949 -40.935655)
			(xy 274.241806 -40.906185) (xy 274.29139 -40.883541) (xy 274.343692 -40.868184) (xy 274.397647 -40.860427)
			(xy 274.424902 -40.859964) (xy 274.45364 -40.860496) (xy 274.510467 -40.869118) (xy 274.565357 -40.886167)
			(xy 274.617069 -40.911256) (xy 274.664432 -40.943819) (xy 274.68576 -40.963088) (xy 274.692618 -40.969692)
			(xy 274.710652 -40.976804) (xy 274.799552 -40.976804) (xy 274.817586 -40.969692) (xy 274.824444 -40.963088)
			(xy 274.845778 -40.943825) (xy 274.893137 -40.911255) (xy 274.944847 -40.886161) (xy 274.999736 -40.869108)
			(xy 275.056563 -40.860485) (xy 275.085302 -40.859964) (xy 275.112551 -40.860506) (xy 275.166495 -40.868263)
			(xy 275.218785 -40.883617) (xy 275.268358 -40.906256) (xy 275.314205 -40.93572) (xy 275.355392 -40.971409)
			(xy 275.391081 -41.012596) (xy 275.420545 -41.058443) (xy 275.443184 -41.108017) (xy 275.458538 -41.160307)
			(xy 275.466294 -41.214251) (xy 275.466294 -41.268749) (xy 275.458538 -41.322693) (xy 275.443184 -41.374983)
			(xy 275.420545 -41.424557) (xy 275.391081 -41.470404) (xy 275.355392 -41.511591) (xy 275.314205 -41.54728)
			(xy 275.268358 -41.576744) (xy 275.218785 -41.599383) (xy 275.166495 -41.614737) (xy 275.112551 -41.622494)
			(xy 275.085302 -41.62298) (xy 275.056564 -41.622434) (xy 274.999739 -41.613813) (xy 274.944849 -41.596767)
			(xy 274.893137 -41.571681) (xy 274.845773 -41.539123) (xy 274.824444 -41.519856) (xy 274.817586 -41.513252)
			(xy 274.799552 -41.50614) (xy 274.710652 -41.50614) (xy 274.692618 -41.513252) (xy 274.68576 -41.519856)
			(xy 274.664431 -41.539125) (xy 274.61707 -41.571692) (xy 274.565359 -41.596785) (xy 274.510468 -41.613836)
			(xy 274.453641 -41.622459) (xy 274.424902 -41.62298) (xy 274.397647 -41.622573) (xy 274.343692 -41.614816)
			(xy 274.29139 -41.599459) (xy 274.241806 -41.576815) (xy 274.195949 -41.547345) (xy 274.154753 -41.511648)
			(xy 274.119057 -41.470453) (xy 274.089586 -41.424596) (xy 274.066942 -41.375012) (xy 274.051585 -41.32271)
			(xy 274.043827 -41.268755) (xy 265.132671 -41.268755) (xy 267.169138 -43.305222) (xy 276.507194 -43.305222)
			(xy 276.507674 -43.277852) (xy 276.515489 -43.223674) (xy 276.530975 -43.171171) (xy 276.553813 -43.121424)
			(xy 276.583534 -43.075456) (xy 276.601174 -43.054524) (xy 276.601428 -43.05427) (xy 276.606995 -43.04717)
			(xy 276.613252 -43.030263) (xy 276.61362 -43.02125) (xy 276.61362 -42.954194) (xy 276.613261 -42.945177)
			(xy 276.607014 -42.928261) (xy 276.601428 -42.921174) (xy 276.601174 -42.921174) (xy 276.601174 -42.92092)
			(xy 276.583527 -42.899995) (xy 276.553817 -42.85402) (xy 276.530983 -42.80427) (xy 276.515494 -42.751768)
			(xy 276.507667 -42.697592) (xy 276.507194 -42.670222) (xy 276.507733 -42.641484) (xy 276.516352 -42.584657)
			(xy 276.533399 -42.529767) (xy 276.558487 -42.478055) (xy 276.591049 -42.430691) (xy 276.610318 -42.409364)
			(xy 276.616922 -42.402506) (xy 276.624034 -42.384472) (xy 276.624034 -42.295572) (xy 276.616922 -42.277538)
			(xy 276.610318 -42.27068) (xy 276.591069 -42.249334) (xy 276.558504 -42.201975) (xy 276.533411 -42.150266)
			(xy 276.51636 -42.095378) (xy 276.507736 -42.038554) (xy 276.507733 -41.981078) (xy 276.516353 -41.924253)
			(xy 276.5334 -41.869364) (xy 276.558488 -41.817653) (xy 276.591049 -41.770291) (xy 276.610318 -41.748964)
			(xy 276.616922 -41.742106) (xy 276.624034 -41.724072) (xy 276.624034 -41.635172) (xy 276.616922 -41.617138)
			(xy 276.610318 -41.61028) (xy 276.591054 -41.588947) (xy 276.558488 -41.541586) (xy 276.533394 -41.489876)
			(xy 276.516342 -41.434987) (xy 276.507717 -41.378161) (xy 276.507194 -41.349422) (xy 276.50768 -41.322171)
			(xy 276.515436 -41.268223) (xy 276.530791 -41.215928) (xy 276.553433 -41.166351) (xy 276.582899 -41.120501)
			(xy 276.61859 -41.07931) (xy 276.659781 -41.043619) (xy 276.705631 -41.014153) (xy 276.755208 -40.991511)
			(xy 276.807503 -40.976156) (xy 276.861451 -40.9684) (xy 276.915953 -40.9684) (xy 276.939074 -40.971724)
			(xy 284.793942 -40.971724) (xy 284.798013 -40.916102) (xy 284.810139 -40.861665) (xy 284.830062 -40.809574)
			(xy 284.857358 -40.760939) (xy 284.891444 -40.716796) (xy 284.931593 -40.678087) (xy 284.976951 -40.645636)
			(xy 285.026551 -40.620135) (xy 285.079335 -40.602128) (xy 285.134178 -40.591998) (xy 285.189912 -40.589961)
			(xy 285.245349 -40.596061) (xy 285.299306 -40.610167) (xy 285.350635 -40.631979) (xy 285.398241 -40.661033)
			(xy 285.441109 -40.696708) (xy 285.478326 -40.738245) (xy 285.509099 -40.784758) (xy 285.532771 -40.835255)
			(xy 285.548839 -40.888662) (xy 285.556959 -40.943838) (xy 285.557468 -40.971724) (xy 285.556959 -40.99961)
			(xy 285.548839 -41.054786) (xy 285.532771 -41.108193) (xy 285.509099 -41.15869) (xy 285.478326 -41.205203)
			(xy 285.441109 -41.24674) (xy 285.398241 -41.282415) (xy 285.350635 -41.311469) (xy 285.299306 -41.333281)
			(xy 285.245349 -41.347387) (xy 285.189912 -41.353487) (xy 285.134178 -41.35145) (xy 285.079335 -41.34132)
			(xy 285.026551 -41.323313) (xy 284.976951 -41.297812) (xy 284.931593 -41.265361) (xy 284.891444 -41.226652)
			(xy 284.857358 -41.182509) (xy 284.830062 -41.133874) (xy 284.810139 -41.081783) (xy 284.798013 -41.027346)
			(xy 284.793942 -40.971724) (xy 276.939074 -40.971724) (xy 276.969901 -40.976156) (xy 277.022196 -40.991511)
			(xy 277.071773 -41.014153) (xy 277.117623 -41.043619) (xy 277.158814 -41.07931) (xy 277.194505 -41.120501)
			(xy 277.223971 -41.166351) (xy 277.246613 -41.215928) (xy 277.261968 -41.268223) (xy 277.269724 -41.322171)
			(xy 277.27021 -41.349422) (xy 277.269697 -41.378161) (xy 277.261071 -41.434989) (xy 277.244019 -41.48988)
			(xy 277.218925 -41.541591) (xy 277.186358 -41.588953) (xy 277.167086 -41.61028) (xy 277.160482 -41.617138)
			(xy 277.15337 -41.635172) (xy 277.15337 -41.724072) (xy 277.160482 -41.742106) (xy 277.167086 -41.748964)
			(xy 277.186378 -41.770272) (xy 277.218942 -41.817638) (xy 277.244032 -41.869353) (xy 277.261079 -41.924246)
			(xy 277.2697 -41.981076) (xy 277.269697 -42.038556) (xy 277.261072 -42.095385) (xy 277.24402 -42.150277)
			(xy 277.218926 -42.20199) (xy 277.186358 -42.249353) (xy 277.167086 -42.27068) (xy 277.160482 -42.277538)
			(xy 277.15337 -42.295572) (xy 277.15337 -42.384472) (xy 277.160482 -42.402506) (xy 277.167086 -42.409364)
			(xy 277.186371 -42.430679) (xy 277.218935 -42.478044) (xy 277.244024 -42.529759) (xy 277.261071 -42.584653)
			(xy 277.269691 -42.641482) (xy 277.27021 -42.670222) (xy 277.269754 -42.697593) (xy 277.261934 -42.751772)
			(xy 277.246442 -42.804275) (xy 277.225887 -42.849038) (xy 279.091896 -42.849038) (xy 279.095967 -42.793416)
			(xy 279.108093 -42.738979) (xy 279.128016 -42.686888) (xy 279.155312 -42.638253) (xy 279.189398 -42.59411)
			(xy 279.229547 -42.555401) (xy 279.274905 -42.52295) (xy 279.324505 -42.497449) (xy 279.377289 -42.479442)
			(xy 279.432132 -42.469312) (xy 279.487866 -42.467275) (xy 279.543303 -42.473375) (xy 279.59726 -42.487481)
			(xy 279.648589 -42.509293) (xy 279.696195 -42.538347) (xy 279.739063 -42.574022) (xy 279.77628 -42.615559)
			(xy 279.807053 -42.662072) (xy 279.830725 -42.712569) (xy 279.846793 -42.765976) (xy 279.854913 -42.821152)
			(xy 279.855274 -42.84091) (xy 285.133032 -42.84091) (xy 285.137103 -42.785288) (xy 285.149229 -42.730851)
			(xy 285.169152 -42.67876) (xy 285.196448 -42.630125) (xy 285.230534 -42.585982) (xy 285.270683 -42.547273)
			(xy 285.316041 -42.514822) (xy 285.365641 -42.489321) (xy 285.418425 -42.471314) (xy 285.473268 -42.461184)
			(xy 285.529002 -42.459147) (xy 285.584439 -42.465247) (xy 285.638396 -42.479353) (xy 285.689725 -42.501165)
			(xy 285.737331 -42.530219) (xy 285.780199 -42.565894) (xy 285.817416 -42.607431) (xy 285.848189 -42.653944)
			(xy 285.871861 -42.704441) (xy 285.887929 -42.757848) (xy 285.896049 -42.813024) (xy 285.896558 -42.84091)
			(xy 285.896049 -42.868796) (xy 285.887929 -42.923972) (xy 285.871861 -42.977379) (xy 285.848189 -43.027876)
			(xy 285.817416 -43.074389) (xy 285.780199 -43.115926) (xy 285.737331 -43.151601) (xy 285.689725 -43.180655)
			(xy 285.638396 -43.202467) (xy 285.584439 -43.216573) (xy 285.529002 -43.222673) (xy 285.473268 -43.220636)
			(xy 285.418425 -43.210506) (xy 285.365641 -43.192499) (xy 285.316041 -43.166998) (xy 285.270683 -43.134547)
			(xy 285.230534 -43.095838) (xy 285.196448 -43.051695) (xy 285.169152 -43.00306) (xy 285.149229 -42.950969)
			(xy 285.137103 -42.896532) (xy 285.133032 -42.84091) (xy 279.855274 -42.84091) (xy 279.855422 -42.849038)
			(xy 279.854913 -42.876924) (xy 279.846793 -42.9321) (xy 279.830725 -42.985507) (xy 279.807053 -43.036004)
			(xy 279.77628 -43.082517) (xy 279.739063 -43.124054) (xy 279.696195 -43.159729) (xy 279.648589 -43.188783)
			(xy 279.59726 -43.210595) (xy 279.543303 -43.224701) (xy 279.487866 -43.230801) (xy 279.432132 -43.228764)
			(xy 279.377289 -43.218634) (xy 279.324505 -43.200627) (xy 279.274905 -43.175126) (xy 279.229547 -43.142675)
			(xy 279.189398 -43.103966) (xy 279.155312 -43.059823) (xy 279.128016 -43.011188) (xy 279.108093 -42.959097)
			(xy 279.095967 -42.90466) (xy 279.091896 -42.849038) (xy 277.225887 -42.849038) (xy 277.223598 -42.854022)
			(xy 277.193872 -42.899988) (xy 277.17623 -42.92092) (xy 277.175976 -42.921174) (xy 277.170392 -42.928262)
			(xy 277.164144 -42.945178) (xy 277.163784 -42.954194) (xy 277.163784 -43.02125) (xy 277.164168 -43.030264)
			(xy 277.170397 -43.047181) (xy 277.175976 -43.05427) (xy 277.17623 -43.05427) (xy 277.17623 -43.054524)
			(xy 277.193852 -43.07547) (xy 277.223565 -43.121439) (xy 277.246404 -43.171184) (xy 277.261899 -43.223681)
			(xy 277.269733 -43.277854) (xy 277.27021 -43.305222) (xy 277.269724 -43.332473) (xy 277.261968 -43.386421)
			(xy 277.246613 -43.438716) (xy 277.223971 -43.488293) (xy 277.194505 -43.534143) (xy 277.158814 -43.575334)
			(xy 277.117623 -43.611025) (xy 277.071773 -43.640491) (xy 277.022196 -43.663133) (xy 276.969901 -43.678488)
			(xy 276.915953 -43.686244) (xy 276.861451 -43.686244) (xy 276.807503 -43.678488) (xy 276.755208 -43.663133)
			(xy 276.705631 -43.640491) (xy 276.659781 -43.611025) (xy 276.61859 -43.575334) (xy 276.582899 -43.534143)
			(xy 276.553433 -43.488293) (xy 276.530791 -43.438716) (xy 276.515436 -43.386421) (xy 276.50768 -43.332473)
			(xy 276.507194 -43.305222) (xy 267.169138 -43.305222) (xy 267.600176 -43.73626) (xy 278.412954 -43.73626)
			(xy 278.417025 -43.680638) (xy 278.429151 -43.626201) (xy 278.449074 -43.57411) (xy 278.47637 -43.525475)
			(xy 278.510456 -43.481332) (xy 278.550605 -43.442623) (xy 278.595963 -43.410172) (xy 278.645563 -43.384671)
			(xy 278.698347 -43.366664) (xy 278.75319 -43.356534) (xy 278.808924 -43.354497) (xy 278.864361 -43.360597)
			(xy 278.918318 -43.374703) (xy 278.969647 -43.396515) (xy 279.017253 -43.425569) (xy 279.060121 -43.461244)
			(xy 279.097338 -43.502781) (xy 279.128111 -43.549294) (xy 279.136337 -43.566842) (xy 281.533344 -43.566842)
			(xy 281.537415 -43.51122) (xy 281.549541 -43.456783) (xy 281.569464 -43.404692) (xy 281.59676 -43.356057)
			(xy 281.630846 -43.311914) (xy 281.670995 -43.273205) (xy 281.716353 -43.240754) (xy 281.765953 -43.215253)
			(xy 281.818737 -43.197246) (xy 281.87358 -43.187116) (xy 281.929314 -43.185079) (xy 281.984751 -43.191179)
			(xy 282.038708 -43.205285) (xy 282.090037 -43.227097) (xy 282.137643 -43.256151) (xy 282.180511 -43.291826)
			(xy 282.217728 -43.333363) (xy 282.248501 -43.379876) (xy 282.272173 -43.430373) (xy 282.288241 -43.48378)
			(xy 282.296361 -43.538956) (xy 282.29687 -43.566842) (xy 282.296361 -43.594728) (xy 282.288241 -43.649904)
			(xy 282.272173 -43.703311) (xy 282.248501 -43.753808) (xy 282.217728 -43.800321) (xy 282.180511 -43.841858)
			(xy 282.162424 -43.85691) (xy 282.919676 -43.85691) (xy 282.923747 -43.801288) (xy 282.935873 -43.746851)
			(xy 282.955796 -43.69476) (xy 282.983092 -43.646125) (xy 283.017178 -43.601982) (xy 283.057327 -43.563273)
			(xy 283.102685 -43.530822) (xy 283.152285 -43.505321) (xy 283.205069 -43.487314) (xy 283.259912 -43.477184)
			(xy 283.315646 -43.475147) (xy 283.371083 -43.481247) (xy 283.42504 -43.495353) (xy 283.476369 -43.517165)
			(xy 283.523975 -43.546219) (xy 283.566843 -43.581894) (xy 283.60406 -43.623431) (xy 283.634833 -43.669944)
			(xy 283.658505 -43.720441) (xy 283.674573 -43.773848) (xy 283.682693 -43.829024) (xy 283.683202 -43.85691)
			(xy 283.682693 -43.884796) (xy 283.674573 -43.939972) (xy 283.658505 -43.993379) (xy 283.634833 -44.043876)
			(xy 283.60406 -44.090389) (xy 283.566843 -44.131926) (xy 283.523975 -44.167601) (xy 283.476369 -44.196655)
			(xy 283.42504 -44.218467) (xy 283.371083 -44.232573) (xy 283.315646 -44.238673) (xy 283.259912 -44.236636)
			(xy 283.205069 -44.226506) (xy 283.152285 -44.208499) (xy 283.102685 -44.182998) (xy 283.057327 -44.150547)
			(xy 283.017178 -44.111838) (xy 282.983092 -44.067695) (xy 282.955796 -44.01906) (xy 282.935873 -43.966969)
			(xy 282.923747 -43.912532) (xy 282.919676 -43.85691) (xy 282.162424 -43.85691) (xy 282.137643 -43.877533)
			(xy 282.090037 -43.906587) (xy 282.038708 -43.928399) (xy 281.984751 -43.942505) (xy 281.929314 -43.948605)
			(xy 281.87358 -43.946568) (xy 281.818737 -43.936438) (xy 281.765953 -43.918431) (xy 281.716353 -43.89293)
			(xy 281.670995 -43.860479) (xy 281.630846 -43.82177) (xy 281.59676 -43.777627) (xy 281.569464 -43.728992)
			(xy 281.549541 -43.676901) (xy 281.537415 -43.622464) (xy 281.533344 -43.566842) (xy 279.136337 -43.566842)
			(xy 279.151783 -43.599791) (xy 279.167851 -43.653198) (xy 279.175971 -43.708374) (xy 279.17648 -43.73626)
			(xy 279.175971 -43.764146) (xy 279.167851 -43.819322) (xy 279.151783 -43.872729) (xy 279.128111 -43.923226)
			(xy 279.097338 -43.969739) (xy 279.060121 -44.011276) (xy 279.017253 -44.046951) (xy 278.969647 -44.076005)
			(xy 278.918318 -44.097817) (xy 278.864361 -44.111923) (xy 278.808924 -44.118023) (xy 278.75319 -44.115986)
			(xy 278.698347 -44.105856) (xy 278.645563 -44.087849) (xy 278.595963 -44.062348) (xy 278.550605 -44.029897)
			(xy 278.510456 -43.991188) (xy 278.47637 -43.947045) (xy 278.449074 -43.89841) (xy 278.429151 -43.846319)
			(xy 278.417025 -43.791882) (xy 278.412954 -43.73626) (xy 267.600176 -43.73626) (xy 268.97838 -45.114464)
			(xy 278.26538 -45.114464) (xy 278.269451 -45.058842) (xy 278.281577 -45.004405) (xy 278.3015 -44.952314)
			(xy 278.328796 -44.903679) (xy 278.362882 -44.859536) (xy 278.403031 -44.820827) (xy 278.448389 -44.788376)
			(xy 278.497989 -44.762875) (xy 278.550773 -44.744868) (xy 278.605616 -44.734738) (xy 278.66135 -44.732701)
			(xy 278.716787 -44.738801) (xy 278.770744 -44.752907) (xy 278.822073 -44.774719) (xy 278.869679 -44.803773)
			(xy 278.912547 -44.839448) (xy 278.942529 -44.87291) (xy 285.133032 -44.87291) (xy 285.137103 -44.817288)
			(xy 285.149229 -44.762851) (xy 285.169152 -44.71076) (xy 285.196448 -44.662125) (xy 285.230534 -44.617982)
			(xy 285.270683 -44.579273) (xy 285.316041 -44.546822) (xy 285.365641 -44.521321) (xy 285.418425 -44.503314)
			(xy 285.473268 -44.493184) (xy 285.529002 -44.491147) (xy 285.584439 -44.497247) (xy 285.638396 -44.511353)
			(xy 285.689725 -44.533165) (xy 285.737331 -44.562219) (xy 285.780199 -44.597894) (xy 285.817416 -44.639431)
			(xy 285.848189 -44.685944) (xy 285.871861 -44.736441) (xy 285.887929 -44.789848) (xy 285.896049 -44.845024)
			(xy 285.896558 -44.87291) (xy 285.896049 -44.900796) (xy 285.887929 -44.955972) (xy 285.871861 -45.009379)
			(xy 285.848189 -45.059876) (xy 285.817416 -45.106389) (xy 285.780199 -45.147926) (xy 285.737331 -45.183601)
			(xy 285.689725 -45.212655) (xy 285.638396 -45.234467) (xy 285.584439 -45.248573) (xy 285.529002 -45.254673)
			(xy 285.473268 -45.252636) (xy 285.418425 -45.242506) (xy 285.365641 -45.224499) (xy 285.316041 -45.198998)
			(xy 285.270683 -45.166547) (xy 285.230534 -45.127838) (xy 285.196448 -45.083695) (xy 285.169152 -45.03506)
			(xy 285.149229 -44.982969) (xy 285.137103 -44.928532) (xy 285.133032 -44.87291) (xy 278.942529 -44.87291)
			(xy 278.949764 -44.880985) (xy 278.980537 -44.927498) (xy 279.004209 -44.977995) (xy 279.020277 -45.031402)
			(xy 279.028397 -45.086578) (xy 279.028906 -45.114464) (xy 279.028397 -45.14235) (xy 279.020277 -45.197526)
			(xy 279.004209 -45.250933) (xy 278.980537 -45.30143) (xy 278.949764 -45.347943) (xy 278.944122 -45.35424)
			(xy 282.903674 -45.35424) (xy 282.907745 -45.298618) (xy 282.919871 -45.244181) (xy 282.939794 -45.19209)
			(xy 282.96709 -45.143455) (xy 283.001176 -45.099312) (xy 283.041325 -45.060603) (xy 283.086683 -45.028152)
			(xy 283.136283 -45.002651) (xy 283.189067 -44.984644) (xy 283.24391 -44.974514) (xy 283.299644 -44.972477)
			(xy 283.355081 -44.978577) (xy 283.409038 -44.992683) (xy 283.460367 -45.014495) (xy 283.507973 -45.043549)
			(xy 283.550841 -45.079224) (xy 283.588058 -45.120761) (xy 283.618831 -45.167274) (xy 283.642503 -45.217771)
			(xy 283.658571 -45.271178) (xy 283.666691 -45.326354) (xy 283.6672 -45.35424) (xy 283.666691 -45.382126)
			(xy 283.658571 -45.437302) (xy 283.642503 -45.490709) (xy 283.618831 -45.541206) (xy 283.588058 -45.587719)
			(xy 283.550841 -45.629256) (xy 283.507973 -45.664931) (xy 283.460367 -45.693985) (xy 283.409038 -45.715797)
			(xy 283.355081 -45.729903) (xy 283.299644 -45.736003) (xy 283.24391 -45.733966) (xy 283.189067 -45.723836)
			(xy 283.136283 -45.705829) (xy 283.086683 -45.680328) (xy 283.041325 -45.647877) (xy 283.001176 -45.609168)
			(xy 282.96709 -45.565025) (xy 282.939794 -45.51639) (xy 282.919871 -45.464299) (xy 282.907745 -45.409862)
			(xy 282.903674 -45.35424) (xy 278.944122 -45.35424) (xy 278.912547 -45.38948) (xy 278.869679 -45.425155)
			(xy 278.822073 -45.454209) (xy 278.770744 -45.476021) (xy 278.716787 -45.490127) (xy 278.66135 -45.496227)
			(xy 278.605616 -45.49419) (xy 278.550773 -45.48406) (xy 278.497989 -45.466053) (xy 278.448389 -45.440552)
			(xy 278.403031 -45.408101) (xy 278.362882 -45.369392) (xy 278.328796 -45.325249) (xy 278.3015 -45.276614)
			(xy 278.281577 -45.224523) (xy 278.269451 -45.170086) (xy 278.26538 -45.114464) (xy 268.97838 -45.114464)
			(xy 269.94612 -46.082204) (xy 276.252432 -46.082204) (xy 276.252859 -46.054949) (xy 276.260617 -46.000995)
			(xy 276.275974 -45.948694) (xy 276.298619 -45.899111) (xy 276.32809 -45.853256) (xy 276.363788 -45.812063)
			(xy 276.404985 -45.776369) (xy 276.450843 -45.746902) (xy 276.500428 -45.724262) (xy 276.55273 -45.708909)
			(xy 276.606685 -45.701157) (xy 276.63394 -45.700696) (xy 276.660844 -45.701128) (xy 276.714115 -45.708705)
			(xy 276.765794 -45.72369) (xy 276.814856 -45.745785) (xy 276.860328 -45.774552) (xy 276.901308 -45.809421)
			(xy 276.936985 -45.8497) (xy 276.952202 -45.871892) (xy 276.959314 -45.882814) (xy 276.982174 -45.894752)
			(xy 277.094442 -45.89272) (xy 277.116794 -45.879766) (xy 277.123652 -45.86859) (xy 277.138552 -45.844974)
			(xy 277.174234 -45.802022) (xy 277.215796 -45.76473) (xy 277.26235 -45.733895) (xy 277.312901 -45.710174)
			(xy 277.36637 -45.694074) (xy 277.421614 -45.68594) (xy 277.449534 -45.685456) (xy 277.476528 -45.685897)
			(xy 277.529977 -45.693508) (xy 277.581821 -45.708573) (xy 277.631025 -45.730791) (xy 277.676608 -45.75972)
			(xy 277.697438 -45.776896) (xy 277.705566 -45.784008) (xy 277.72614 -45.790104) (xy 277.811484 -45.779182)
			(xy 277.822029 -45.77741) (xy 277.840312 -45.766354) (xy 277.84679 -45.757846) (xy 277.862156 -45.736625)
			(xy 277.897741 -45.698172) (xy 277.938256 -45.664953) (xy 277.982937 -45.637593) (xy 278.030943 -45.616608)
			(xy 278.08137 -45.602392) (xy 278.133268 -45.595215) (xy 278.159464 -45.594778) (xy 278.186718 -45.595267)
			(xy 278.24067 -45.603019) (xy 278.292971 -45.618372) (xy 278.342553 -45.641011) (xy 278.388409 -45.670477)
			(xy 278.429605 -45.70617) (xy 278.465301 -45.747362) (xy 278.494771 -45.793215) (xy 278.517416 -45.842796)
			(xy 278.532773 -45.895094) (xy 278.540531 -45.949047) (xy 278.540531 -46.003553) (xy 278.532773 -46.057506)
			(xy 278.517416 -46.109804) (xy 278.494771 -46.159385) (xy 278.465301 -46.205238) (xy 278.429605 -46.24643)
			(xy 278.388409 -46.282123) (xy 278.342553 -46.311589) (xy 278.292971 -46.334228) (xy 278.24067 -46.349581)
			(xy 278.186718 -46.357333) (xy 278.159464 -46.357794) (xy 278.132471 -46.357342) (xy 278.079022 -46.349732)
			(xy 278.027179 -46.334669) (xy 277.977975 -46.312453) (xy 277.932391 -46.283528) (xy 277.91156 -46.266354)
			(xy 277.903432 -46.259242) (xy 277.882858 -46.253146) (xy 277.797514 -46.264068) (xy 277.786973 -46.265857)
			(xy 277.76869 -46.276902) (xy 277.762208 -46.285404) (xy 277.744591 -46.309701) (xy 277.702998 -46.352963)
			(xy 277.679404 -46.37151) (xy 277.67153 -46.377352) (xy 277.661116 -46.394878) (xy 277.647908 -46.485302)
			(xy 277.652734 -46.504606) (xy 277.658576 -46.51248) (xy 277.658576 -46.512734) (xy 277.676079 -46.537478)
			(xy 277.703882 -46.591331) (xy 277.722818 -46.648903) (xy 277.730021 -46.693836) (xy 282.876244 -46.693836)
			(xy 282.87673 -46.666585) (xy 282.884486 -46.612637) (xy 282.899841 -46.560342) (xy 282.922483 -46.510765)
			(xy 282.951949 -46.464915) (xy 282.98764 -46.423724) (xy 283.028831 -46.388033) (xy 283.074681 -46.358567)
			(xy 283.124258 -46.335925) (xy 283.176553 -46.32057) (xy 283.230501 -46.312814) (xy 283.285003 -46.312814)
			(xy 283.338951 -46.32057) (xy 283.391246 -46.335925) (xy 283.440823 -46.358567) (xy 283.486673 -46.388033)
			(xy 283.527864 -46.423724) (xy 283.563555 -46.464915) (xy 283.593021 -46.510765) (xy 283.615663 -46.560342)
			(xy 283.631018 -46.612637) (xy 283.638774 -46.666585) (xy 283.63926 -46.693836) (xy 283.638793 -46.720264)
			(xy 283.631483 -46.772612) (xy 283.617008 -46.823447) (xy 283.595646 -46.871793) (xy 283.58211 -46.894496)
			(xy 283.581856 -46.89475) (xy 283.576519 -46.904768) (xy 283.574262 -46.927318) (xy 283.577538 -46.938184)
			(xy 283.6037 -47.01286) (xy 283.608062 -47.023387) (xy 283.624166 -47.039471) (xy 283.634688 -47.043848)
			(xy 283.634942 -47.043848) (xy 283.65945 -47.05292) (xy 283.705902 -47.076862) (xy 283.748655 -47.106917)
			(xy 283.786907 -47.142524) (xy 283.819943 -47.183017) (xy 283.847147 -47.227638) (xy 283.868009 -47.275553)
			(xy 283.882139 -47.325866) (xy 283.889273 -47.377636) (xy 283.889704 -47.403766) (xy 283.889218 -47.431017)
			(xy 283.887695 -47.441612) (xy 285.161734 -47.441612) (xy 285.165805 -47.38599) (xy 285.177931 -47.331553)
			(xy 285.197854 -47.279462) (xy 285.22515 -47.230827) (xy 285.259236 -47.186684) (xy 285.299385 -47.147975)
			(xy 285.344743 -47.115524) (xy 285.394343 -47.090023) (xy 285.447127 -47.072016) (xy 285.50197 -47.061886)
			(xy 285.557704 -47.059849) (xy 285.613141 -47.065949) (xy 285.667098 -47.080055) (xy 285.718427 -47.101867)
			(xy 285.766033 -47.130921) (xy 285.808901 -47.166596) (xy 285.846118 -47.208133) (xy 285.876891 -47.254646)
			(xy 285.900563 -47.305143) (xy 285.916631 -47.35855) (xy 285.924751 -47.413726) (xy 285.92526 -47.441612)
			(xy 285.924751 -47.469498) (xy 285.916631 -47.524674) (xy 285.900563 -47.578081) (xy 285.876891 -47.628578)
			(xy 285.846118 -47.675091) (xy 285.808901 -47.716628) (xy 285.766033 -47.752303) (xy 285.718427 -47.781357)
			(xy 285.667098 -47.803169) (xy 285.613141 -47.817275) (xy 285.557704 -47.823375) (xy 285.50197 -47.821338)
			(xy 285.447127 -47.811208) (xy 285.394343 -47.793201) (xy 285.344743 -47.7677) (xy 285.299385 -47.735249)
			(xy 285.259236 -47.69654) (xy 285.22515 -47.652397) (xy 285.197854 -47.603762) (xy 285.177931 -47.551671)
			(xy 285.165805 -47.497234) (xy 285.161734 -47.441612) (xy 283.887695 -47.441612) (xy 283.881462 -47.484965)
			(xy 283.866107 -47.53726) (xy 283.843465 -47.586837) (xy 283.813999 -47.632687) (xy 283.778308 -47.673878)
			(xy 283.737117 -47.709569) (xy 283.691267 -47.739035) (xy 283.64169 -47.761677) (xy 283.589395 -47.777032)
			(xy 283.535447 -47.784788) (xy 283.480945 -47.784788) (xy 283.426997 -47.777032) (xy 283.374702 -47.761677)
			(xy 283.325125 -47.739035) (xy 283.279275 -47.709569) (xy 283.238084 -47.673878) (xy 283.202393 -47.632687)
			(xy 283.172927 -47.586837) (xy 283.150285 -47.53726) (xy 283.13493 -47.484965) (xy 283.127174 -47.431017)
			(xy 283.126688 -47.403766) (xy 283.127163 -47.377339) (xy 283.134472 -47.324991) (xy 283.148945 -47.274156)
			(xy 283.170304 -47.225809) (xy 283.183838 -47.203106) (xy 283.184092 -47.202852) (xy 283.189427 -47.192834)
			(xy 283.191684 -47.170284) (xy 283.18841 -47.159418) (xy 283.162248 -47.084742) (xy 283.157863 -47.074227)
			(xy 283.141775 -47.058138) (xy 283.13126 -47.053754) (xy 283.131006 -47.053754) (xy 283.106488 -47.04471)
			(xy 283.060036 -47.020762) (xy 283.017286 -46.990701) (xy 282.979036 -46.95509) (xy 282.946001 -46.914594)
			(xy 282.918799 -46.869971) (xy 282.897938 -46.822053) (xy 282.883809 -46.771739) (xy 282.876675 -46.719967)
			(xy 282.876244 -46.693836) (xy 277.730021 -46.693836) (xy 277.732411 -46.708745) (xy 277.732998 -46.739048)
			(xy 277.732567 -46.766301) (xy 277.724803 -46.820251) (xy 277.709442 -46.872547) (xy 277.686794 -46.922126)
			(xy 277.657322 -46.967976) (xy 277.621625 -47.009166) (xy 277.58043 -47.044857) (xy 277.534575 -47.074322)
			(xy 277.484993 -47.096962) (xy 277.432694 -47.112316) (xy 277.378743 -47.120071) (xy 277.35149 -47.120556)
			(xy 277.325456 -47.120107) (xy 277.273874 -47.11302) (xy 277.223732 -47.09899) (xy 277.175961 -47.07828)
			(xy 277.131446 -47.051272) (xy 277.110952 -47.035212) (xy 277.103187 -47.029483) (xy 277.084783 -47.023735)
			(xy 277.075138 -47.024036) (xy 276.995382 -47.030386) (xy 276.977602 -47.039022) (xy 276.971252 -47.046388)
			(xy 276.953068 -47.066031) (xy 276.912161 -47.100553) (xy 276.866833 -47.129023) (xy 276.817972 -47.150881)
			(xy 276.766536 -47.165699) (xy 276.713536 -47.173186) (xy 276.686772 -47.173642) (xy 276.659522 -47.173148)
			(xy 276.605576 -47.165389) (xy 276.553283 -47.150032) (xy 276.503708 -47.12739) (xy 276.45786 -47.097924)
			(xy 276.416671 -47.062234) (xy 276.38098 -47.021045) (xy 276.351513 -46.975197) (xy 276.32887 -46.925622)
			(xy 276.313512 -46.87333) (xy 276.305752 -46.819384) (xy 276.305264 -46.792134) (xy 276.305798 -46.76336)
			(xy 276.314448 -46.706467) (xy 276.331543 -46.651517) (xy 276.356694 -46.599757) (xy 276.389331 -46.55236)
			(xy 276.408642 -46.531022) (xy 276.416008 -46.523148) (xy 276.42312 -46.503336) (xy 276.415754 -46.40707)
			(xy 276.405848 -46.388274) (xy 276.397466 -46.38167) (xy 276.375291 -46.363434) (xy 276.336078 -46.321502)
			(xy 276.30359 -46.274169) (xy 276.27856 -46.222503) (xy 276.261552 -46.167671) (xy 276.25295 -46.110909)
			(xy 276.252432 -46.082204) (xy 269.94612 -46.082204) (xy 270.615664 -46.751748) (xy 270.640595 -46.77737)
			(xy 270.684663 -46.833662) (xy 270.703548 -46.864016) (xy 270.708374 -46.870874) (xy 270.730502 -46.897631)
			(xy 270.769014 -46.955408) (xy 270.800487 -47.017302) (xy 270.824487 -47.082459) (xy 270.840683 -47.14998)
			(xy 270.848852 -47.218934) (xy 270.849344 -47.253652) (xy 270.849344 -48.30699) (xy 282.753814 -48.30699)
			(xy 282.757885 -48.251368) (xy 282.770011 -48.196931) (xy 282.789934 -48.14484) (xy 282.81723 -48.096205)
			(xy 282.851316 -48.052062) (xy 282.891465 -48.013353) (xy 282.936823 -47.980902) (xy 282.986423 -47.955401)
			(xy 283.039207 -47.937394) (xy 283.09405 -47.927264) (xy 283.149784 -47.925227) (xy 283.205221 -47.931327)
			(xy 283.259178 -47.945433) (xy 283.310507 -47.967245) (xy 283.358113 -47.996299) (xy 283.400981 -48.031974)
			(xy 283.438198 -48.073511) (xy 283.468971 -48.120024) (xy 283.492643 -48.170521) (xy 283.508711 -48.223928)
			(xy 283.516831 -48.279104) (xy 283.51734 -48.30699) (xy 283.516831 -48.334876) (xy 283.508711 -48.390052)
			(xy 283.492643 -48.443459) (xy 283.468971 -48.493956) (xy 283.438198 -48.540469) (xy 283.400981 -48.582006)
			(xy 283.358113 -48.617681) (xy 283.310507 -48.646735) (xy 283.259178 -48.668547) (xy 283.205221 -48.682653)
			(xy 283.149784 -48.688753) (xy 283.09405 -48.686716) (xy 283.039207 -48.676586) (xy 282.986423 -48.658579)
			(xy 282.936823 -48.633078) (xy 282.891465 -48.600627) (xy 282.851316 -48.561918) (xy 282.81723 -48.517775)
			(xy 282.789934 -48.46914) (xy 282.770011 -48.417049) (xy 282.757885 -48.362612) (xy 282.753814 -48.30699)
			(xy 270.849344 -48.30699) (xy 270.849344 -48.753014) (xy 279.368248 -48.753014) (xy 279.372319 -48.697392)
			(xy 279.384445 -48.642955) (xy 279.404368 -48.590864) (xy 279.431664 -48.542229) (xy 279.46575 -48.498086)
			(xy 279.505899 -48.459377) (xy 279.551257 -48.426926) (xy 279.600857 -48.401425) (xy 279.653641 -48.383418)
			(xy 279.708484 -48.373288) (xy 279.764218 -48.371251) (xy 279.819655 -48.377351) (xy 279.873612 -48.391457)
			(xy 279.924941 -48.413269) (xy 279.972547 -48.442323) (xy 280.015415 -48.477998) (xy 280.052632 -48.519535)
			(xy 280.083405 -48.566048) (xy 280.107077 -48.616545) (xy 280.123145 -48.669952) (xy 280.131265 -48.725128)
			(xy 280.131774 -48.753014) (xy 280.131265 -48.7809) (xy 280.123145 -48.836076) (xy 280.107077 -48.889483)
			(xy 280.105681 -48.89246) (xy 281.413964 -48.89246) (xy 281.418035 -48.836838) (xy 281.430161 -48.782401)
			(xy 281.450084 -48.73031) (xy 281.47738 -48.681675) (xy 281.511466 -48.637532) (xy 281.551615 -48.598823)
			(xy 281.596973 -48.566372) (xy 281.646573 -48.540871) (xy 281.699357 -48.522864) (xy 281.7542 -48.512734)
			(xy 281.809934 -48.510697) (xy 281.865371 -48.516797) (xy 281.919328 -48.530903) (xy 281.970657 -48.552715)
			(xy 282.018263 -48.581769) (xy 282.061131 -48.617444) (xy 282.098348 -48.658981) (xy 282.129121 -48.705494)
			(xy 282.152793 -48.755991) (xy 282.168861 -48.809398) (xy 282.176981 -48.864574) (xy 282.17749 -48.89246)
			(xy 282.176981 -48.920346) (xy 282.174543 -48.93691) (xy 285.133032 -48.93691) (xy 285.137103 -48.881288)
			(xy 285.149229 -48.826851) (xy 285.169152 -48.77476) (xy 285.196448 -48.726125) (xy 285.230534 -48.681982)
			(xy 285.270683 -48.643273) (xy 285.316041 -48.610822) (xy 285.365641 -48.585321) (xy 285.418425 -48.567314)
			(xy 285.473268 -48.557184) (xy 285.529002 -48.555147) (xy 285.584439 -48.561247) (xy 285.638396 -48.575353)
			(xy 285.689725 -48.597165) (xy 285.737331 -48.626219) (xy 285.780199 -48.661894) (xy 285.817416 -48.703431)
			(xy 285.848189 -48.749944) (xy 285.871861 -48.800441) (xy 285.887929 -48.853848) (xy 285.896049 -48.909024)
			(xy 285.896558 -48.93691) (xy 285.896049 -48.964796) (xy 285.887929 -49.019972) (xy 285.871861 -49.073379)
			(xy 285.848189 -49.123876) (xy 285.817416 -49.170389) (xy 285.780199 -49.211926) (xy 285.737331 -49.247601)
			(xy 285.689725 -49.276655) (xy 285.638396 -49.298467) (xy 285.584439 -49.312573) (xy 285.529002 -49.318673)
			(xy 285.473268 -49.316636) (xy 285.418425 -49.306506) (xy 285.365641 -49.288499) (xy 285.316041 -49.262998)
			(xy 285.270683 -49.230547) (xy 285.230534 -49.191838) (xy 285.196448 -49.147695) (xy 285.169152 -49.09906)
			(xy 285.149229 -49.046969) (xy 285.137103 -48.992532) (xy 285.133032 -48.93691) (xy 282.174543 -48.93691)
			(xy 282.168861 -48.975522) (xy 282.152793 -49.028929) (xy 282.129121 -49.079426) (xy 282.098348 -49.125939)
			(xy 282.061131 -49.167476) (xy 282.018263 -49.203151) (xy 281.970657 -49.232205) (xy 281.919328 -49.254017)
			(xy 281.865371 -49.268123) (xy 281.809934 -49.274223) (xy 281.7542 -49.272186) (xy 281.699357 -49.262056)
			(xy 281.646573 -49.244049) (xy 281.596973 -49.218548) (xy 281.551615 -49.186097) (xy 281.511466 -49.147388)
			(xy 281.47738 -49.103245) (xy 281.450084 -49.05461) (xy 281.430161 -49.002519) (xy 281.418035 -48.948082)
			(xy 281.413964 -48.89246) (xy 280.105681 -48.89246) (xy 280.083405 -48.93998) (xy 280.052632 -48.986493)
			(xy 280.015415 -49.02803) (xy 279.972547 -49.063705) (xy 279.924941 -49.092759) (xy 279.873612 -49.114571)
			(xy 279.819655 -49.128677) (xy 279.764218 -49.134777) (xy 279.708484 -49.13274) (xy 279.653641 -49.12261)
			(xy 279.600857 -49.104603) (xy 279.551257 -49.079102) (xy 279.505899 -49.046651) (xy 279.46575 -49.007942)
			(xy 279.431664 -48.963799) (xy 279.404368 -48.915164) (xy 279.384445 -48.863073) (xy 279.372319 -48.808636)
			(xy 279.368248 -48.753014) (xy 270.849344 -48.753014) (xy 270.849344 -49.95291) (xy 285.133032 -49.95291)
			(xy 285.137103 -49.897288) (xy 285.149229 -49.842851) (xy 285.169152 -49.79076) (xy 285.196448 -49.742125)
			(xy 285.230534 -49.697982) (xy 285.270683 -49.659273) (xy 285.316041 -49.626822) (xy 285.365641 -49.601321)
			(xy 285.418425 -49.583314) (xy 285.473268 -49.573184) (xy 285.529002 -49.571147) (xy 285.584439 -49.577247)
			(xy 285.638396 -49.591353) (xy 285.663331 -49.601949) (xy 290.312882 -49.601949) (xy 290.312882 -49.547451)
			(xy 290.320637 -49.493508) (xy 290.33599 -49.441217) (xy 290.358627 -49.391643) (xy 290.388089 -49.345795)
			(xy 290.423776 -49.304607) (xy 290.46496 -49.268916) (xy 290.510805 -49.239448) (xy 290.560376 -49.216805)
			(xy 290.612665 -49.201446) (xy 290.666607 -49.193685) (xy 290.693856 -49.193196) (xy 290.721225 -49.193689)
			(xy 290.775403 -49.2015) (xy 290.827906 -49.216983) (xy 290.877653 -49.239819) (xy 290.923621 -49.269538)
			(xy 290.944554 -49.287176) (xy 290.944808 -49.28743) (xy 290.951886 -49.293029) (xy 290.968809 -49.299267)
			(xy 290.977828 -49.299622) (xy 291.044884 -49.299622) (xy 291.053899 -49.299253) (xy 291.070816 -49.293013)
			(xy 291.077904 -49.28743) (xy 291.077904 -49.287176) (xy 291.078158 -49.287176) (xy 291.099091 -49.269535)
			(xy 291.145059 -49.239811) (xy 291.194805 -49.216965) (xy 291.247307 -49.201469) (xy 291.301485 -49.19364)
			(xy 291.356227 -49.19364) (xy 291.410405 -49.201469) (xy 291.462907 -49.216965) (xy 291.512653 -49.239811)
			(xy 291.558621 -49.269535) (xy 291.579554 -49.287176) (xy 291.579808 -49.28743) (xy 291.586886 -49.293029)
			(xy 291.603809 -49.299267) (xy 291.612828 -49.299622) (xy 291.679884 -49.299622) (xy 291.688899 -49.299253)
			(xy 291.705816 -49.293013) (xy 291.712904 -49.28743) (xy 291.712904 -49.287176) (xy 291.713158 -49.287176)
			(xy 291.734091 -49.269535) (xy 291.780059 -49.239811) (xy 291.829805 -49.216965) (xy 291.882307 -49.201469)
			(xy 291.936485 -49.19364) (xy 291.991227 -49.19364) (xy 292.045405 -49.201469) (xy 292.097907 -49.216965)
			(xy 292.147653 -49.239811) (xy 292.193621 -49.269535) (xy 292.214554 -49.287176) (xy 292.214808 -49.28743)
			(xy 292.221886 -49.293029) (xy 292.238809 -49.299267) (xy 292.247828 -49.299622) (xy 292.314884 -49.299622)
			(xy 292.323899 -49.299253) (xy 292.340816 -49.293013) (xy 292.347904 -49.28743) (xy 292.347904 -49.287176)
			(xy 292.348158 -49.287176) (xy 292.369092 -49.269539) (xy 292.415065 -49.239828) (xy 292.464812 -49.216992)
			(xy 292.517312 -49.2015) (xy 292.571487 -49.193671) (xy 292.598856 -49.193196) (xy 292.626111 -49.193648)
			(xy 292.680067 -49.2014) (xy 292.732371 -49.216753) (xy 292.781957 -49.239393) (xy 292.827816 -49.26886)
			(xy 292.869015 -49.304554) (xy 292.904714 -49.345748) (xy 292.934186 -49.391604) (xy 292.956832 -49.441188)
			(xy 292.97219 -49.49349) (xy 292.979949 -49.547445) (xy 292.979949 -49.601955) (xy 292.97219 -49.65591)
			(xy 292.956832 -49.708212) (xy 292.934186 -49.757796) (xy 292.904714 -49.803652) (xy 292.869015 -49.844846)
			(xy 292.827816 -49.88054) (xy 292.781957 -49.910007) (xy 292.732371 -49.932647) (xy 292.680067 -49.948)
			(xy 292.626111 -49.955752) (xy 292.598856 -49.956212) (xy 292.571487 -49.95571) (xy 292.51731 -49.947901)
			(xy 292.464807 -49.93242) (xy 292.41506 -49.909586) (xy 292.369091 -49.879869) (xy 292.348158 -49.862232)
			(xy 292.347904 -49.861978) (xy 292.340822 -49.856385) (xy 292.323902 -49.850143) (xy 292.314884 -49.849786)
			(xy 292.247828 -49.849786) (xy 292.238813 -49.850159) (xy 292.221896 -49.856396) (xy 292.214808 -49.861978)
			(xy 292.214554 -49.862232) (xy 292.193621 -49.879873) (xy 292.147653 -49.909597) (xy 292.097907 -49.932443)
			(xy 292.045405 -49.947939) (xy 291.991227 -49.955768) (xy 291.936485 -49.955768) (xy 291.882307 -49.947939)
			(xy 291.829805 -49.932443) (xy 291.780059 -49.909597) (xy 291.734091 -49.879873) (xy 291.713158 -49.862232)
			(xy 291.712904 -49.861978) (xy 291.705822 -49.856385) (xy 291.688902 -49.850143) (xy 291.679884 -49.849786)
			(xy 291.612828 -49.849786) (xy 291.603813 -49.850159) (xy 291.586896 -49.856396) (xy 291.579808 -49.861978)
			(xy 291.579808 -49.862232) (xy 291.579554 -49.862232) (xy 291.558621 -49.879873) (xy 291.512653 -49.909597)
			(xy 291.462907 -49.932443) (xy 291.410405 -49.947939) (xy 291.356227 -49.955768) (xy 291.301485 -49.955768)
			(xy 291.247307 -49.947939) (xy 291.194805 -49.932443) (xy 291.145059 -49.909597) (xy 291.099091 -49.879873)
			(xy 291.078158 -49.862232) (xy 291.077904 -49.861978) (xy 291.070822 -49.856385) (xy 291.053902 -49.850143)
			(xy 291.044884 -49.849786) (xy 290.977828 -49.849786) (xy 290.968813 -49.850159) (xy 290.951896 -49.856396)
			(xy 290.944808 -49.861978) (xy 290.944808 -49.862232) (xy 290.944554 -49.862232) (xy 290.923616 -49.879864)
			(xy 290.877645 -49.909576) (xy 290.827898 -49.932413) (xy 290.775399 -49.947906) (xy 290.721225 -49.955736)
			(xy 290.693856 -49.956212) (xy 290.666607 -49.955715) (xy 290.612665 -49.947954) (xy 290.560376 -49.932595)
			(xy 290.510805 -49.909952) (xy 290.46496 -49.880484) (xy 290.423776 -49.844793) (xy 290.388089 -49.803605)
			(xy 290.358627 -49.757757) (xy 290.33599 -49.708183) (xy 290.320637 -49.655892) (xy 290.312882 -49.601949)
			(xy 285.663331 -49.601949) (xy 285.689725 -49.613165) (xy 285.737331 -49.642219) (xy 285.780199 -49.677894)
			(xy 285.817416 -49.719431) (xy 285.848189 -49.765944) (xy 285.871861 -49.816441) (xy 285.887929 -49.869848)
			(xy 285.896049 -49.925024) (xy 285.896558 -49.95291) (xy 285.896049 -49.980796) (xy 285.887929 -50.035972)
			(xy 285.871861 -50.089379) (xy 285.848189 -50.139876) (xy 285.817416 -50.186389) (xy 285.780199 -50.227926)
			(xy 285.737331 -50.263601) (xy 285.689725 -50.292655) (xy 285.638396 -50.314467) (xy 285.584439 -50.328573)
			(xy 285.529002 -50.334673) (xy 285.473268 -50.332636) (xy 285.418425 -50.322506) (xy 285.365641 -50.304499)
			(xy 285.316041 -50.278998) (xy 285.270683 -50.246547) (xy 285.230534 -50.207838) (xy 285.196448 -50.163695)
			(xy 285.169152 -50.11506) (xy 285.149229 -50.062969) (xy 285.137103 -50.008532) (xy 285.133032 -49.95291)
			(xy 270.849344 -49.95291) (xy 270.849344 -51.019456) (xy 282.949394 -51.019456) (xy 282.953465 -50.963834)
			(xy 282.965591 -50.909397) (xy 282.985514 -50.857306) (xy 283.01281 -50.808671) (xy 283.046896 -50.764528)
			(xy 283.087045 -50.725819) (xy 283.132403 -50.693368) (xy 283.182003 -50.667867) (xy 283.234787 -50.64986)
			(xy 283.28963 -50.63973) (xy 283.345364 -50.637693) (xy 283.400801 -50.643793) (xy 283.454758 -50.657899)
			(xy 283.506087 -50.679711) (xy 283.553693 -50.708765) (xy 283.596561 -50.74444) (xy 283.633778 -50.785977)
			(xy 283.664551 -50.83249) (xy 283.688223 -50.882987) (xy 283.704291 -50.936394) (xy 283.712411 -50.99157)
			(xy 283.71292 -51.019456) (xy 283.712411 -51.047342) (xy 283.704291 -51.102518) (xy 283.688223 -51.155925)
			(xy 283.664551 -51.206422) (xy 283.639695 -51.243992) (xy 291.33292 -51.243992) (xy 291.333377 -51.216621)
			(xy 291.341196 -51.162442) (xy 291.356687 -51.109938) (xy 291.379531 -51.060192) (xy 291.409258 -51.014225)
			(xy 291.4269 -50.993294) (xy 291.427154 -50.99304) (xy 291.432736 -50.985951) (xy 291.438984 -50.969036)
			(xy 291.439346 -50.96002) (xy 291.439346 -50.892964) (xy 291.439018 -50.883944) (xy 291.432752 -50.867027)
			(xy 291.427154 -50.859944) (xy 291.4269 -50.859944) (xy 291.4269 -50.85969) (xy 291.409243 -50.838773)
			(xy 291.379534 -50.792796) (xy 291.356701 -50.743045) (xy 291.341214 -50.690541) (xy 291.333391 -50.636362)
			(xy 291.33292 -50.608992) (xy 291.333348 -50.581738) (xy 291.341107 -50.527784) (xy 291.356465 -50.475484)
			(xy 291.379111 -50.425902) (xy 291.408582 -50.380047) (xy 291.44428 -50.338854) (xy 291.485476 -50.303161)
			(xy 291.531333 -50.273693) (xy 291.580918 -50.251053) (xy 291.633219 -50.235699) (xy 291.687174 -50.227945)
			(xy 291.714428 -50.227484) (xy 291.743345 -50.228022) (xy 291.800516 -50.236743) (xy 291.855716 -50.253995)
			(xy 291.907679 -50.279382) (xy 291.955213 -50.312324) (xy 291.997229 -50.352065) (xy 292.015418 -50.37455)
			(xy 292.023018 -50.383364) (xy 292.043925 -50.393542) (xy 292.05555 -50.394108) (xy 292.135306 -50.394108)
			(xy 292.146936 -50.393555) (xy 292.167846 -50.383376) (xy 292.175438 -50.37455) (xy 292.193595 -50.352038)
			(xy 292.235623 -50.312307) (xy 292.283166 -50.279373) (xy 292.335133 -50.25399) (xy 292.390336 -50.236739)
			(xy 292.44751 -50.228016) (xy 292.476428 -50.227484) (xy 292.50368 -50.227952) (xy 292.557628 -50.235712)
			(xy 292.609922 -50.25107) (xy 292.659499 -50.273714) (xy 292.705349 -50.303182) (xy 292.746538 -50.338876)
			(xy 292.78223 -50.380067) (xy 292.811696 -50.425919) (xy 292.834337 -50.475497) (xy 292.849692 -50.527792)
			(xy 292.85745 -50.58174) (xy 292.857936 -50.608992) (xy 292.857452 -50.635305) (xy 292.850219 -50.687433)
			(xy 292.835902 -50.738075) (xy 292.814773 -50.786273) (xy 292.78723 -50.831117) (xy 292.753796 -50.871758)
			(xy 292.734746 -50.889916) (xy 292.727342 -50.897436) (xy 292.718818 -50.916717) (xy 292.718236 -50.927254)
			(xy 292.718236 -51.00193) (xy 292.718779 -51.012478) (xy 292.727303 -51.031775) (xy 292.734746 -51.039268)
			(xy 292.753836 -51.057388) (xy 292.787289 -51.098027) (xy 292.814842 -51.142875) (xy 292.835974 -51.191082)
			(xy 292.850284 -51.241735) (xy 292.857501 -51.293874) (xy 292.857936 -51.320192) (xy 292.857415 -51.347442)
			(xy 292.84966 -51.401387) (xy 292.834307 -51.453679) (xy 292.811669 -51.503255) (xy 292.782206 -51.549104)
			(xy 292.746519 -51.590293) (xy 292.705332 -51.625985) (xy 292.659486 -51.655452) (xy 292.609913 -51.678095)
			(xy 292.557622 -51.693453) (xy 292.503678 -51.701212) (xy 292.476428 -51.7017) (xy 292.448764 -51.701166)
			(xy 292.394016 -51.69317) (xy 292.340994 -51.677358) (xy 292.290811 -51.654058) (xy 292.244515 -51.62376)
			(xy 292.203076 -51.587098) (xy 292.167362 -51.544839) (xy 292.152324 -51.521614) (xy 292.145686 -51.511939)
			(xy 292.125825 -51.499495) (xy 292.114224 -51.497738) (xy 292.034214 -51.489864) (xy 292.022576 -51.489244)
			(xy 292.000739 -51.497316) (xy 291.992304 -51.505358) (xy 291.99205 -51.505612) (xy 291.973978 -51.524202)
			(xy 291.933644 -51.556779) (xy 291.889267 -51.583591) (xy 291.841667 -51.604142) (xy 291.791722 -51.618054)
			(xy 291.740352 -51.625069) (xy 291.714428 -51.6255) (xy 291.687175 -51.625019) (xy 291.633225 -51.617265)
			(xy 291.580927 -51.601912) (xy 291.531346 -51.579273) (xy 291.485493 -51.549807) (xy 291.444299 -51.514115)
			(xy 291.408605 -51.472923) (xy 291.379137 -51.427071) (xy 291.356495 -51.377492) (xy 291.341139 -51.325195)
			(xy 291.333383 -51.271244) (xy 291.33292 -51.243992) (xy 283.639695 -51.243992) (xy 283.633778 -51.252935)
			(xy 283.596561 -51.294472) (xy 283.553693 -51.330147) (xy 283.506087 -51.359201) (xy 283.454758 -51.381013)
			(xy 283.400801 -51.395119) (xy 283.345364 -51.401219) (xy 283.28963 -51.399182) (xy 283.234787 -51.389052)
			(xy 283.182003 -51.371045) (xy 283.132403 -51.345544) (xy 283.087045 -51.313093) (xy 283.046896 -51.274384)
			(xy 283.01281 -51.230241) (xy 282.985514 -51.181606) (xy 282.965591 -51.129515) (xy 282.953465 -51.075078)
			(xy 282.949394 -51.019456) (xy 270.849344 -51.019456) (xy 270.849344 -52.035456) (xy 285.14116 -52.035456)
			(xy 285.145231 -51.979834) (xy 285.157357 -51.925397) (xy 285.17728 -51.873306) (xy 285.204576 -51.824671)
			(xy 285.238662 -51.780528) (xy 285.278811 -51.741819) (xy 285.324169 -51.709368) (xy 285.373769 -51.683867)
			(xy 285.426553 -51.66586) (xy 285.481396 -51.65573) (xy 285.53713 -51.653693) (xy 285.592567 -51.659793)
			(xy 285.646524 -51.673899) (xy 285.697853 -51.695711) (xy 285.745459 -51.724765) (xy 285.788327 -51.76044)
			(xy 285.825544 -51.801977) (xy 285.856317 -51.84849) (xy 285.879989 -51.898987) (xy 285.896057 -51.952394)
			(xy 285.904177 -52.00757) (xy 285.904686 -52.035456) (xy 285.904177 -52.063342) (xy 285.896057 -52.118518)
			(xy 285.879989 -52.171925) (xy 285.856317 -52.222422) (xy 285.825544 -52.268935) (xy 285.788327 -52.310472)
			(xy 285.745459 -52.346147) (xy 285.697853 -52.375201) (xy 285.646524 -52.397013) (xy 285.592567 -52.411119)
			(xy 285.53713 -52.417219) (xy 285.481396 -52.415182) (xy 285.426553 -52.405052) (xy 285.373769 -52.387045)
			(xy 285.324169 -52.361544) (xy 285.278811 -52.329093) (xy 285.238662 -52.290384) (xy 285.204576 -52.246241)
			(xy 285.17728 -52.197606) (xy 285.157357 -52.145515) (xy 285.145231 -52.091078) (xy 285.14116 -52.035456)
			(xy 270.849344 -52.035456) (xy 270.849344 -54.731412) (xy 271.720564 -54.731412) (xy 271.721021 -54.704041)
			(xy 271.728839 -54.649861) (xy 271.744329 -54.597357) (xy 271.767173 -54.547611) (xy 271.796901 -54.501645)
			(xy 271.814544 -54.480714) (xy 271.814798 -54.48046) (xy 271.820365 -54.47336) (xy 271.826624 -54.456454)
			(xy 271.82699 -54.44744) (xy 271.82699 -54.380384) (xy 271.826643 -54.371366) (xy 271.820389 -54.354449)
			(xy 271.814798 -54.347364) (xy 271.814544 -54.347364) (xy 271.814544 -54.34711) (xy 271.796914 -54.326168)
			(xy 271.767188 -54.280202) (xy 271.744341 -54.230458) (xy 271.728843 -54.177957) (xy 271.721013 -54.123779)
			(xy 271.721011 -54.069039) (xy 271.728839 -54.014861) (xy 271.744334 -53.962359) (xy 271.767179 -53.912614)
			(xy 271.796903 -53.866646) (xy 271.814544 -53.845714) (xy 271.814798 -53.84546) (xy 271.820365 -53.83836)
			(xy 271.826624 -53.821454) (xy 271.82699 -53.81244) (xy 271.82699 -53.745384) (xy 271.826643 -53.736366)
			(xy 271.820389 -53.719449) (xy 271.814798 -53.712364) (xy 271.814544 -53.712364) (xy 271.814544 -53.71211)
			(xy 271.796914 -53.691168) (xy 271.767188 -53.645202) (xy 271.744341 -53.595458) (xy 271.728843 -53.542957)
			(xy 271.721013 -53.488779) (xy 271.721011 -53.434039) (xy 271.728839 -53.379861) (xy 271.744334 -53.327359)
			(xy 271.767179 -53.277614) (xy 271.796903 -53.231646) (xy 271.814544 -53.210714) (xy 271.814798 -53.21046)
			(xy 271.820365 -53.20336) (xy 271.826624 -53.186454) (xy 271.82699 -53.17744) (xy 271.82699 -53.110384)
			(xy 271.826643 -53.101366) (xy 271.820389 -53.084449) (xy 271.814798 -53.077364) (xy 271.814544 -53.077364)
			(xy 271.814544 -53.07711) (xy 271.796903 -53.056179) (xy 271.76719 -53.010207) (xy 271.744354 -52.960459)
			(xy 271.728863 -52.907958) (xy 271.721037 -52.853781) (xy 271.720564 -52.826412) (xy 271.72105 -52.799161)
			(xy 271.728806 -52.745213) (xy 271.744161 -52.692918) (xy 271.766803 -52.643341) (xy 271.796269 -52.597491)
			(xy 271.83196 -52.5563) (xy 271.873151 -52.520609) (xy 271.919001 -52.491143) (xy 271.968578 -52.468501)
			(xy 272.020873 -52.453146) (xy 272.074821 -52.44539) (xy 272.129323 -52.44539) (xy 272.183271 -52.453146)
			(xy 272.235566 -52.468501) (xy 272.285143 -52.491143) (xy 272.330993 -52.520609) (xy 272.372184 -52.5563)
			(xy 272.407875 -52.597491) (xy 272.437341 -52.643341) (xy 272.459983 -52.692918) (xy 272.475338 -52.745213)
			(xy 272.483094 -52.799161) (xy 272.48358 -52.826412) (xy 272.483126 -52.853783) (xy 272.475306 -52.907963)
			(xy 272.459814 -52.960466) (xy 272.43697 -53.010213) (xy 272.407243 -53.056179) (xy 272.3896 -53.07711)
			(xy 272.389346 -53.077364) (xy 272.383762 -53.084452) (xy 272.377515 -53.101368) (xy 272.377154 -53.110384)
			(xy 272.377154 -53.17744) (xy 272.37748 -53.18646) (xy 272.383748 -53.203378) (xy 272.389346 -53.21046)
			(xy 272.3896 -53.21046) (xy 272.3896 -53.210714) (xy 272.407251 -53.231638) (xy 272.436974 -53.277608)
			(xy 272.459817 -53.327356) (xy 272.475311 -53.379859) (xy 272.483138 -53.434038) (xy 272.483136 -53.48878)
			(xy 272.475307 -53.542959) (xy 272.45981 -53.595461) (xy 272.436965 -53.645208) (xy 272.40724 -53.691177)
			(xy 272.3896 -53.71211) (xy 272.389346 -53.712364) (xy 272.383762 -53.719452) (xy 272.377515 -53.736368)
			(xy 272.377154 -53.745384) (xy 272.377154 -53.81244) (xy 272.37748 -53.82146) (xy 272.383748 -53.838378)
			(xy 272.389346 -53.84546) (xy 272.3896 -53.84546) (xy 272.3896 -53.845714) (xy 272.407251 -53.866638)
			(xy 272.436974 -53.912608) (xy 272.459817 -53.962356) (xy 272.475311 -54.014859) (xy 272.483138 -54.069038)
			(xy 272.483136 -54.12378) (xy 272.475307 -54.177959) (xy 272.45981 -54.230461) (xy 272.436965 -54.280208)
			(xy 272.40724 -54.326177) (xy 272.3896 -54.34711) (xy 272.389346 -54.347364) (xy 272.383762 -54.354452)
			(xy 272.377515 -54.371368) (xy 272.377154 -54.380384) (xy 272.377154 -54.44744) (xy 272.37748 -54.45646)
			(xy 272.383748 -54.473378) (xy 272.389346 -54.48046) (xy 272.3896 -54.48046) (xy 272.3896 -54.480714)
			(xy 272.407212 -54.501668) (xy 272.436928 -54.547635) (xy 272.459769 -54.597377) (xy 272.475267 -54.649872)
			(xy 272.483102 -54.704044) (xy 272.48358 -54.731412) (xy 272.483094 -54.758663) (xy 272.47843 -54.791102)
			(xy 274.376388 -54.791102) (xy 274.376858 -54.763732) (xy 274.384675 -54.709553) (xy 274.400164 -54.65705)
			(xy 274.423004 -54.607303) (xy 274.452728 -54.561336) (xy 274.470368 -54.540404) (xy 274.470622 -54.54015)
			(xy 274.476196 -54.533055) (xy 274.48245 -54.516145) (xy 274.482814 -54.50713) (xy 274.482814 -54.440074)
			(xy 274.482466 -54.431056) (xy 274.476212 -54.41414) (xy 274.470622 -54.407054) (xy 274.470368 -54.407054)
			(xy 274.470368 -54.4068) (xy 274.452728 -54.385866) (xy 274.423 -54.3399) (xy 274.400152 -54.290154)
			(xy 274.384653 -54.237652) (xy 274.376824 -54.183472) (xy 274.376823 -54.128731) (xy 274.384653 -54.074551)
			(xy 274.400151 -54.022049) (xy 274.422998 -53.972303) (xy 274.452726 -53.926336) (xy 274.470368 -53.905404)
			(xy 274.470622 -53.90515) (xy 274.476196 -53.898055) (xy 274.48245 -53.881145) (xy 274.482814 -53.87213)
			(xy 274.482814 -53.805074) (xy 274.482466 -53.796056) (xy 274.476212 -53.77914) (xy 274.470622 -53.772054)
			(xy 274.470368 -53.772054) (xy 274.470368 -53.7718) (xy 274.452728 -53.750866) (xy 274.423 -53.7049)
			(xy 274.400152 -53.655154) (xy 274.384653 -53.602652) (xy 274.376824 -53.548472) (xy 274.376823 -53.493731)
			(xy 274.384653 -53.439551) (xy 274.400151 -53.387049) (xy 274.422998 -53.337303) (xy 274.452726 -53.291336)
			(xy 274.470368 -53.270404) (xy 274.470622 -53.27015) (xy 274.476196 -53.263055) (xy 274.48245 -53.246145)
			(xy 274.482814 -53.23713) (xy 274.482814 -53.170074) (xy 274.482466 -53.161056) (xy 274.476212 -53.14414)
			(xy 274.470622 -53.137054) (xy 274.470368 -53.137054) (xy 274.470368 -53.1368) (xy 274.45271 -53.115883)
			(xy 274.423002 -53.069905) (xy 274.400171 -53.020154) (xy 274.384684 -52.96765) (xy 274.37686 -52.913472)
			(xy 274.376388 -52.886102) (xy 274.376874 -52.858851) (xy 274.38463 -52.804903) (xy 274.399985 -52.752608)
			(xy 274.422627 -52.703031) (xy 274.452093 -52.657181) (xy 274.487784 -52.61599) (xy 274.528975 -52.580299)
			(xy 274.574825 -52.550833) (xy 274.624402 -52.528191) (xy 274.676697 -52.512836) (xy 274.730645 -52.50508)
			(xy 274.785147 -52.50508) (xy 274.839095 -52.512836) (xy 274.89139 -52.528191) (xy 274.93049 -52.546048)
			(xy 279.879596 -52.546048) (xy 279.879596 -52.491552) (xy 279.887351 -52.437611) (xy 279.902703 -52.385323)
			(xy 279.925339 -52.335751) (xy 279.9548 -52.289905) (xy 279.990484 -52.248718) (xy 280.031667 -52.213029)
			(xy 280.077509 -52.183563) (xy 280.127078 -52.16092) (xy 280.179364 -52.145561) (xy 280.233304 -52.1378)
			(xy 280.260552 -52.13731) (xy 280.287921 -52.137802) (xy 280.342099 -52.145613) (xy 280.394602 -52.161096)
			(xy 280.44435 -52.183932) (xy 280.490318 -52.213651) (xy 280.51125 -52.23129) (xy 280.511504 -52.231544)
			(xy 280.518581 -52.237144) (xy 280.535505 -52.243381) (xy 280.544524 -52.243736) (xy 280.61158 -52.243736)
			(xy 280.620595 -52.243361) (xy 280.637512 -52.237125) (xy 280.6446 -52.231544) (xy 280.6446 -52.23129)
			(xy 280.644854 -52.23129) (xy 280.665787 -52.213649) (xy 280.711755 -52.183925) (xy 280.761501 -52.161079)
			(xy 280.814003 -52.145583) (xy 280.868181 -52.137754) (xy 280.922923 -52.137754) (xy 280.977101 -52.145583)
			(xy 281.029603 -52.161079) (xy 281.079349 -52.183925) (xy 281.125317 -52.213649) (xy 281.14625 -52.23129)
			(xy 281.146504 -52.231544) (xy 281.153581 -52.237144) (xy 281.170505 -52.243381) (xy 281.179524 -52.243736)
			(xy 281.24658 -52.243736) (xy 281.255595 -52.243361) (xy 281.272512 -52.237125) (xy 281.2796 -52.231544)
			(xy 281.2796 -52.23129) (xy 281.279854 -52.23129) (xy 281.300791 -52.213657) (xy 281.346763 -52.183945)
			(xy 281.396509 -52.161108) (xy 281.449008 -52.145615) (xy 281.503183 -52.137785) (xy 281.530552 -52.13731)
			(xy 281.557808 -52.137734) (xy 281.611767 -52.145485) (xy 281.664073 -52.160838) (xy 281.713662 -52.183479)
			(xy 281.759523 -52.212947) (xy 281.800724 -52.248642) (xy 281.836424 -52.289838) (xy 281.865898 -52.335696)
			(xy 281.888545 -52.385282) (xy 281.903904 -52.437586) (xy 281.911663 -52.491544) (xy 281.911663 -52.546056)
			(xy 281.905718 -52.587398) (xy 282.955236 -52.587398) (xy 282.959307 -52.531776) (xy 282.971433 -52.477339)
			(xy 282.991356 -52.425248) (xy 283.018652 -52.376613) (xy 283.052738 -52.33247) (xy 283.092887 -52.293761)
			(xy 283.138245 -52.26131) (xy 283.187845 -52.235809) (xy 283.240629 -52.217802) (xy 283.295472 -52.207672)
			(xy 283.351206 -52.205635) (xy 283.406643 -52.211735) (xy 283.4606 -52.225841) (xy 283.511929 -52.247653)
			(xy 283.559535 -52.276707) (xy 283.602403 -52.312382) (xy 283.63962 -52.353919) (xy 283.670393 -52.400432)
			(xy 283.694065 -52.450929) (xy 283.710133 -52.504336) (xy 283.717729 -52.555948) (xy 290.783802 -52.555948)
			(xy 290.783802 -52.501452) (xy 290.791557 -52.44751) (xy 290.80691 -52.395221) (xy 290.829548 -52.345649)
			(xy 290.85901 -52.299802) (xy 290.894696 -52.258616) (xy 290.93588 -52.222926) (xy 290.981724 -52.193461)
			(xy 291.031295 -52.17082) (xy 291.083583 -52.155463) (xy 291.137524 -52.147704) (xy 291.164772 -52.147216)
			(xy 291.192142 -52.147695) (xy 291.246321 -52.155509) (xy 291.298824 -52.170995) (xy 291.348571 -52.193834)
			(xy 291.394538 -52.223556) (xy 291.41547 -52.241196) (xy 291.415724 -52.24145) (xy 291.422795 -52.247059)
			(xy 291.439724 -52.253291) (xy 291.448744 -52.253642) (xy 291.5158 -52.253642) (xy 291.524818 -52.253297)
			(xy 291.541736 -52.247043) (xy 291.54882 -52.24145) (xy 291.54882 -52.241196) (xy 291.549074 -52.241196)
			(xy 291.570005 -52.223555) (xy 291.615978 -52.193844) (xy 291.665726 -52.171008) (xy 291.718227 -52.155517)
			(xy 291.772403 -52.14769) (xy 291.799772 -52.147216) (xy 291.827028 -52.147629) (xy 291.880985 -52.155383)
			(xy 291.93329 -52.170738) (xy 291.982877 -52.19338) (xy 292.028736 -52.222849) (xy 292.069935 -52.258545)
			(xy 292.105634 -52.299741) (xy 292.135106 -52.345599) (xy 292.157752 -52.395184) (xy 292.173111 -52.447487)
			(xy 292.180869 -52.501444) (xy 292.180869 -52.555956) (xy 292.173111 -52.609913) (xy 292.157752 -52.662216)
			(xy 292.135106 -52.711801) (xy 292.105634 -52.757659) (xy 292.069935 -52.798855) (xy 292.028736 -52.834551)
			(xy 291.982877 -52.86402) (xy 291.93329 -52.886662) (xy 291.880985 -52.902017) (xy 291.827028 -52.909771)
			(xy 291.799772 -52.910232) (xy 291.7724 -52.909799) (xy 291.718219 -52.901976) (xy 291.665715 -52.88648)
			(xy 291.615969 -52.86363) (xy 291.570004 -52.833897) (xy 291.549074 -52.816252) (xy 291.54882 -52.815998)
			(xy 291.541732 -52.810413) (xy 291.524816 -52.804166) (xy 291.5158 -52.803806) (xy 291.448744 -52.803806)
			(xy 291.439729 -52.804183) (xy 291.422812 -52.810417) (xy 291.415724 -52.815998) (xy 291.415724 -52.816252)
			(xy 291.41547 -52.816252) (xy 291.394516 -52.833864) (xy 291.34855 -52.863582) (xy 291.298808 -52.886424)
			(xy 291.246312 -52.901921) (xy 291.19214 -52.909755) (xy 291.164772 -52.910232) (xy 291.137524 -52.909696)
			(xy 291.083583 -52.901937) (xy 291.031295 -52.88658) (xy 290.981724 -52.863939) (xy 290.93588 -52.834474)
			(xy 290.894696 -52.798784) (xy 290.85901 -52.757598) (xy 290.829548 -52.711751) (xy 290.80691 -52.662179)
			(xy 290.791557 -52.60989) (xy 290.783802 -52.555948) (xy 283.717729 -52.555948) (xy 283.718253 -52.559512)
			(xy 283.718762 -52.587398) (xy 283.718253 -52.615284) (xy 283.710133 -52.67046) (xy 283.694065 -52.723867)
			(xy 283.670393 -52.774364) (xy 283.63962 -52.820877) (xy 283.602403 -52.862414) (xy 283.559535 -52.898089)
			(xy 283.511929 -52.927143) (xy 283.4606 -52.948955) (xy 283.406643 -52.963061) (xy 283.351206 -52.969161)
			(xy 283.295472 -52.967124) (xy 283.240629 -52.956994) (xy 283.187845 -52.938987) (xy 283.138245 -52.913486)
			(xy 283.092887 -52.881035) (xy 283.052738 -52.842326) (xy 283.018652 -52.798183) (xy 282.991356 -52.749548)
			(xy 282.971433 -52.697457) (xy 282.959307 -52.64302) (xy 282.955236 -52.587398) (xy 281.905718 -52.587398)
			(xy 281.903904 -52.600014) (xy 281.888545 -52.652318) (xy 281.865898 -52.701904) (xy 281.836424 -52.747762)
			(xy 281.800724 -52.788958) (xy 281.759523 -52.824653) (xy 281.713662 -52.854121) (xy 281.664073 -52.876762)
			(xy 281.611767 -52.892115) (xy 281.557808 -52.899866) (xy 281.530552 -52.900326) (xy 281.503182 -52.899847)
			(xy 281.449003 -52.892035) (xy 281.396499 -52.87655) (xy 281.346752 -52.853711) (xy 281.300785 -52.823987)
			(xy 281.279854 -52.806346) (xy 281.2796 -52.806092) (xy 281.272518 -52.800498) (xy 281.255598 -52.794256)
			(xy 281.24658 -52.7939) (xy 281.179524 -52.7939) (xy 281.170508 -52.794268) (xy 281.153591 -52.800508)
			(xy 281.146504 -52.806092) (xy 281.14625 -52.806346) (xy 281.125317 -52.823987) (xy 281.079349 -52.853711)
			(xy 281.029603 -52.876557) (xy 280.977101 -52.892053) (xy 280.922923 -52.899882) (xy 280.868181 -52.899882)
			(xy 280.814003 -52.892053) (xy 280.761501 -52.876557) (xy 280.711755 -52.853711) (xy 280.665787 -52.823987)
			(xy 280.644854 -52.806346) (xy 280.6446 -52.806092) (xy 280.637518 -52.800498) (xy 280.620598 -52.794256)
			(xy 280.61158 -52.7939) (xy 280.544524 -52.7939) (xy 280.535508 -52.794268) (xy 280.518591 -52.800508)
			(xy 280.511504 -52.806092) (xy 280.511504 -52.806346) (xy 280.51125 -52.806346) (xy 280.490303 -52.823967)
			(xy 280.444335 -52.853683) (xy 280.394592 -52.876524) (xy 280.342094 -52.892019) (xy 280.28792 -52.89985)
			(xy 280.260552 -52.900326) (xy 280.233304 -52.8998) (xy 280.179364 -52.892039) (xy 280.127078 -52.87668)
			(xy 280.077509 -52.854037) (xy 280.031667 -52.824571) (xy 279.990484 -52.788882) (xy 279.9548 -52.747695)
			(xy 279.925339 -52.701849) (xy 279.902703 -52.652277) (xy 279.887351 -52.599989) (xy 279.879596 -52.546048)
			(xy 274.93049 -52.546048) (xy 274.940967 -52.550833) (xy 274.986817 -52.580299) (xy 275.028008 -52.61599)
			(xy 275.063699 -52.657181) (xy 275.093165 -52.703031) (xy 275.115807 -52.752608) (xy 275.131162 -52.804903)
			(xy 275.138918 -52.858851) (xy 275.139404 -52.886102) (xy 275.138938 -52.913472) (xy 275.13112 -52.967651)
			(xy 275.115631 -53.020154) (xy 275.092789 -53.069901) (xy 275.063065 -53.115868) (xy 275.045424 -53.1368)
			(xy 275.04517 -53.137054) (xy 275.039593 -53.144147) (xy 275.033342 -53.161059) (xy 275.032978 -53.170074)
			(xy 275.032978 -53.23713) (xy 275.033325 -53.246148) (xy 275.03958 -53.263064) (xy 275.04517 -53.27015)
			(xy 275.045424 -53.27015) (xy 275.045424 -53.270404) (xy 275.063069 -53.291334) (xy 275.092797 -53.337301)
			(xy 275.115645 -53.387048) (xy 275.131144 -53.43955) (xy 275.138973 -53.49373) (xy 275.138973 -53.548473)
			(xy 275.131143 -53.602652) (xy 275.115644 -53.655155) (xy 275.092796 -53.704901) (xy 275.063067 -53.750868)
			(xy 275.046494 -53.77053) (xy 275.410676 -53.77053) (xy 275.411187 -53.741612) (xy 275.419913 -53.68444)
			(xy 275.437171 -53.629239) (xy 275.462564 -53.577277) (xy 275.49551 -53.529744) (xy 275.535255 -53.487729)
			(xy 275.557742 -53.46954) (xy 275.566528 -53.461913) (xy 275.576721 -53.441027) (xy 275.5773 -53.429408)
			(xy 275.5773 -53.349652) (xy 275.576774 -53.338018) (xy 275.566576 -53.317109) (xy 275.557742 -53.30952)
			(xy 275.535277 -53.291307) (xy 275.495539 -53.249293) (xy 275.462596 -53.201763) (xy 275.437204 -53.149806)
			(xy 275.419945 -53.094612) (xy 275.411212 -53.037445) (xy 275.410676 -53.00853) (xy 275.411183 -52.981279)
			(xy 275.418936 -52.92733) (xy 275.434287 -52.875034) (xy 275.456925 -52.825455) (xy 275.486388 -52.779603)
			(xy 275.522077 -52.73841) (xy 275.563266 -52.702716) (xy 275.609115 -52.673247) (xy 275.658691 -52.650603)
			(xy 275.710985 -52.635245) (xy 275.764933 -52.627486) (xy 275.792184 -52.627022) (xy 275.818498 -52.627493)
			(xy 275.870627 -52.634726) (xy 275.921269 -52.649044) (xy 275.969469 -52.670176) (xy 276.014312 -52.697722)
			(xy 276.054952 -52.73116) (xy 276.073108 -52.750212) (xy 276.080623 -52.757621) (xy 276.099908 -52.766141)
			(xy 276.110446 -52.766722) (xy 276.185122 -52.766722) (xy 276.195667 -52.766158) (xy 276.214963 -52.757647)
			(xy 276.22246 -52.750212) (xy 276.240596 -52.731137) (xy 276.281229 -52.697681) (xy 276.326074 -52.670124)
			(xy 276.374279 -52.648989) (xy 276.42493 -52.634676) (xy 276.477067 -52.627457) (xy 276.503384 -52.627022)
			(xy 276.530638 -52.62747) (xy 276.584591 -52.635226) (xy 276.636891 -52.650581) (xy 276.686473 -52.673224)
			(xy 276.732328 -52.702693) (xy 276.773521 -52.738389) (xy 276.809215 -52.779584) (xy 276.838683 -52.825439)
			(xy 276.861324 -52.875022) (xy 276.876677 -52.927323) (xy 276.884431 -52.981276) (xy 276.884892 -53.00853)
			(xy 276.884407 -53.036196) (xy 276.882176 -53.051456) (xy 285.14116 -53.051456) (xy 285.145231 -52.995834)
			(xy 285.157357 -52.941397) (xy 285.17728 -52.889306) (xy 285.204576 -52.840671) (xy 285.238662 -52.796528)
			(xy 285.278811 -52.757819) (xy 285.324169 -52.725368) (xy 285.373769 -52.699867) (xy 285.426553 -52.68186)
			(xy 285.481396 -52.67173) (xy 285.53713 -52.669693) (xy 285.592567 -52.675793) (xy 285.646524 -52.689899)
			(xy 285.697853 -52.711711) (xy 285.745459 -52.740765) (xy 285.788327 -52.77644) (xy 285.825544 -52.817977)
			(xy 285.856317 -52.86449) (xy 285.879989 -52.914987) (xy 285.896057 -52.968394) (xy 285.904177 -53.02357)
			(xy 285.904686 -53.051456) (xy 285.904177 -53.079342) (xy 285.896057 -53.134518) (xy 285.879989 -53.187925)
			(xy 285.856317 -53.238422) (xy 285.825544 -53.284935) (xy 285.788327 -53.326472) (xy 285.745459 -53.362147)
			(xy 285.697853 -53.391201) (xy 285.646524 -53.413013) (xy 285.592567 -53.427119) (xy 285.53713 -53.433219)
			(xy 285.481396 -53.431182) (xy 285.426553 -53.421052) (xy 285.373769 -53.403045) (xy 285.324169 -53.377544)
			(xy 285.278811 -53.345093) (xy 285.238662 -53.306384) (xy 285.204576 -53.262241) (xy 285.17728 -53.213606)
			(xy 285.157357 -53.161515) (xy 285.145231 -53.107078) (xy 285.14116 -53.051456) (xy 276.882176 -53.051456)
			(xy 276.876403 -53.090947) (xy 276.860582 -53.143969) (xy 276.837275 -53.194153) (xy 276.806969 -53.240449)
			(xy 276.7703 -53.281886) (xy 276.728035 -53.317598) (xy 276.704806 -53.332634) (xy 276.695126 -53.339267)
			(xy 276.682681 -53.35913) (xy 276.68093 -53.370734) (xy 276.673056 -53.450744) (xy 276.672403 -53.462383)
			(xy 276.680498 -53.484222) (xy 276.68855 -53.492654) (xy 276.688804 -53.492908) (xy 276.707372 -53.511002)
			(xy 276.739952 -53.551331) (xy 276.766766 -53.595703) (xy 276.787321 -53.643299) (xy 276.801238 -53.693241)
			(xy 276.808258 -53.744608) (xy 276.808692 -53.77053) (xy 276.80825 -53.797783) (xy 276.800489 -53.851733)
			(xy 276.785129 -53.904029) (xy 276.762483 -53.953608) (xy 276.733013 -53.999459) (xy 276.697317 -54.040649)
			(xy 276.656122 -54.07634) (xy 276.610267 -54.105806) (xy 276.560686 -54.128445) (xy 276.508388 -54.143799)
			(xy 276.454437 -54.151553) (xy 276.427184 -54.152038) (xy 276.399813 -54.151596) (xy 276.345632 -54.143775)
			(xy 276.293128 -54.128281) (xy 276.243381 -54.105433) (xy 276.197416 -54.075703) (xy 276.176486 -54.058058)
			(xy 276.176232 -54.057804) (xy 276.16914 -54.052225) (xy 276.152227 -54.045974) (xy 276.143212 -54.045612)
			(xy 276.076156 -54.045612) (xy 276.067142 -54.045993) (xy 276.050224 -54.052224) (xy 276.043136 -54.057804)
			(xy 276.043136 -54.058058) (xy 276.042882 -54.058058) (xy 276.021924 -54.075666) (xy 275.975959 -54.105384)
			(xy 275.926218 -54.128226) (xy 275.873723 -54.143725) (xy 275.819552 -54.15156) (xy 275.792184 -54.152038)
			(xy 275.764934 -54.151537) (xy 275.710988 -54.143779) (xy 275.658695 -54.128424) (xy 275.60912 -54.105783)
			(xy 275.563271 -54.076318) (xy 275.522082 -54.040628) (xy 275.486391 -53.99944) (xy 275.456924 -53.953592)
			(xy 275.434281 -53.904018) (xy 275.418924 -53.851726) (xy 275.411164 -53.79778) (xy 275.410676 -53.77053)
			(xy 275.046494 -53.77053) (xy 275.045424 -53.7718) (xy 275.04517 -53.772054) (xy 275.039593 -53.779147)
			(xy 275.033342 -53.796059) (xy 275.032978 -53.805074) (xy 275.032978 -53.87213) (xy 275.033325 -53.881148)
			(xy 275.03958 -53.898064) (xy 275.04517 -53.90515) (xy 275.045424 -53.90515) (xy 275.045424 -53.905404)
			(xy 275.063069 -53.926334) (xy 275.092797 -53.972301) (xy 275.115645 -54.022048) (xy 275.131144 -54.07455)
			(xy 275.138973 -54.12873) (xy 275.138973 -54.183473) (xy 275.131143 -54.237652) (xy 275.115644 -54.290155)
			(xy 275.101851 -54.320186) (xy 277.330408 -54.320186) (xy 277.330864 -54.292815) (xy 277.338684 -54.238636)
			(xy 277.354175 -54.186132) (xy 277.377019 -54.136386) (xy 277.406746 -54.090419) (xy 277.424388 -54.069488)
			(xy 277.424642 -54.069234) (xy 277.430226 -54.062146) (xy 277.436473 -54.04523) (xy 277.436834 -54.036214)
			(xy 277.436834 -53.969158) (xy 277.436442 -53.960145) (xy 277.430218 -53.943228) (xy 277.424642 -53.936138)
			(xy 277.424388 -53.936138) (xy 277.424388 -53.935884) (xy 277.406773 -53.914933) (xy 277.377058 -53.868965)
			(xy 277.354218 -53.819222) (xy 277.338721 -53.766726) (xy 277.330886 -53.712554) (xy 277.330408 -53.685186)
			(xy 277.330894 -53.657935) (xy 277.33865 -53.603987) (xy 277.354005 -53.551692) (xy 277.376647 -53.502115)
			(xy 277.406113 -53.456265) (xy 277.441804 -53.415074) (xy 277.482995 -53.379383) (xy 277.528845 -53.349917)
			(xy 277.578422 -53.327275) (xy 277.630717 -53.31192) (xy 277.684665 -53.304164) (xy 277.739167 -53.304164)
			(xy 277.793115 -53.31192) (xy 277.84541 -53.327275) (xy 277.894987 -53.349917) (xy 277.940837 -53.379383)
			(xy 277.982028 -53.415074) (xy 278.017719 -53.456265) (xy 278.043612 -53.496555) (xy 290.333341 -53.496555)
			(xy 290.333341 -53.442045) (xy 290.341099 -53.388089) (xy 290.356457 -53.335787) (xy 290.379103 -53.286203)
			(xy 290.408575 -53.240347) (xy 290.444273 -53.199152) (xy 290.485471 -53.163457) (xy 290.531329 -53.133988)
			(xy 290.580915 -53.111347) (xy 290.633219 -53.095993) (xy 290.687175 -53.088239) (xy 290.71443 -53.087778)
			(xy 290.741802 -53.088207) (xy 290.795983 -53.096031) (xy 290.848487 -53.111528) (xy 290.898234 -53.134378)
			(xy 290.944198 -53.164112) (xy 290.965128 -53.181758) (xy 290.965382 -53.182012) (xy 290.972469 -53.187599)
			(xy 290.989385 -53.193845) (xy 290.998402 -53.194204) (xy 291.065458 -53.194204) (xy 291.074473 -53.193826)
			(xy 291.09139 -53.187593) (xy 291.098478 -53.182012) (xy 291.098478 -53.181758) (xy 291.098732 -53.181758)
			(xy 291.119673 -53.16413) (xy 291.165644 -53.134418) (xy 291.215389 -53.111581) (xy 291.267888 -53.096087)
			(xy 291.322062 -53.088254) (xy 291.34943 -53.087778) (xy 291.376679 -53.088294) (xy 291.430621 -53.096054)
			(xy 291.48291 -53.111411) (xy 291.532482 -53.134053) (xy 291.578327 -53.163519) (xy 291.619512 -53.199209)
			(xy 291.655199 -53.240397) (xy 291.684661 -53.286244) (xy 291.707299 -53.335818) (xy 291.722652 -53.388108)
			(xy 291.730408 -53.442051) (xy 291.730408 -53.496549) (xy 291.722652 -53.550492) (xy 291.707299 -53.602782)
			(xy 291.684661 -53.652356) (xy 291.655199 -53.698203) (xy 291.619512 -53.739391) (xy 291.578327 -53.775081)
			(xy 291.532482 -53.804547) (xy 291.48291 -53.827189) (xy 291.430621 -53.842546) (xy 291.376679 -53.850306)
			(xy 291.34943 -53.850794) (xy 291.32206 -53.850312) (xy 291.267882 -53.842498) (xy 291.215379 -53.827013)
			(xy 291.165632 -53.804175) (xy 291.119664 -53.774454) (xy 291.098732 -53.756814) (xy 291.098478 -53.75656)
			(xy 291.091405 -53.750953) (xy 291.074478 -53.74472) (xy 291.065458 -53.744368) (xy 290.998402 -53.744368)
			(xy 290.989386 -53.744733) (xy 290.97247 -53.750976) (xy 290.965382 -53.75656) (xy 290.965382 -53.756814)
			(xy 290.965128 -53.756814) (xy 290.944198 -53.774456) (xy 290.898224 -53.804167) (xy 290.848476 -53.827002)
			(xy 290.795975 -53.842492) (xy 290.741799 -53.85032) (xy 290.71443 -53.850794) (xy 290.687175 -53.850361)
			(xy 290.633219 -53.842607) (xy 290.580915 -53.827253) (xy 290.531329 -53.804612) (xy 290.485471 -53.775143)
			(xy 290.444273 -53.739448) (xy 290.408575 -53.698253) (xy 290.379103 -53.652397) (xy 290.356457 -53.602813)
			(xy 290.341099 -53.550511) (xy 290.333341 -53.496555) (xy 278.043612 -53.496555) (xy 278.047185 -53.502115)
			(xy 278.069827 -53.551692) (xy 278.085182 -53.603987) (xy 278.092938 -53.657935) (xy 278.093424 -53.685186)
			(xy 278.092968 -53.712557) (xy 278.085151 -53.766737) (xy 278.06966 -53.819241) (xy 278.046816 -53.868988)
			(xy 278.017087 -53.914953) (xy 277.999444 -53.935884) (xy 277.99919 -53.936138) (xy 277.993622 -53.943237)
			(xy 277.987365 -53.960144) (xy 277.986998 -53.969158) (xy 277.986998 -54.036214) (xy 277.987349 -54.045231)
			(xy 277.993601 -54.062148) (xy 277.99919 -54.069234) (xy 277.999444 -54.069234) (xy 277.999444 -54.069488)
			(xy 278.017098 -54.090408) (xy 278.046806 -54.136385) (xy 278.069639 -54.186135) (xy 278.085127 -54.238638)
			(xy 278.092952 -54.292816) (xy 278.093424 -54.320186) (xy 278.092938 -54.347437) (xy 278.085182 -54.401385)
			(xy 278.069827 -54.45368) (xy 278.047185 -54.503257) (xy 278.017719 -54.549107) (xy 277.982028 -54.590298)
			(xy 277.940837 -54.625989) (xy 277.894987 -54.655455) (xy 277.84541 -54.678097) (xy 277.793115 -54.693452)
			(xy 277.739167 -54.701208) (xy 277.684665 -54.701208) (xy 277.630717 -54.693452) (xy 277.578422 -54.678097)
			(xy 277.528845 -54.655455) (xy 277.482995 -54.625989) (xy 277.441804 -54.590298) (xy 277.406113 -54.549107)
			(xy 277.376647 -54.503257) (xy 277.354005 -54.45368) (xy 277.33865 -54.401385) (xy 277.330894 -54.347437)
			(xy 277.330408 -54.320186) (xy 275.101851 -54.320186) (xy 275.092796 -54.339901) (xy 275.063067 -54.385868)
			(xy 275.045424 -54.4068) (xy 275.04517 -54.407054) (xy 275.039593 -54.414147) (xy 275.033342 -54.431059)
			(xy 275.032978 -54.440074) (xy 275.032978 -54.50713) (xy 275.033325 -54.516148) (xy 275.03958 -54.533064)
			(xy 275.04517 -54.54015) (xy 275.045424 -54.54015) (xy 275.045424 -54.540404) (xy 275.063082 -54.561321)
			(xy 275.09279 -54.607298) (xy 275.115622 -54.65705) (xy 275.131109 -54.709553) (xy 275.138932 -54.763732)
			(xy 275.139049 -54.770528) (xy 278.27097 -54.770528) (xy 278.271435 -54.743158) (xy 278.279251 -54.688978)
			(xy 278.294739 -54.636474) (xy 278.317581 -54.586727) (xy 278.347308 -54.540761) (xy 278.36495 -54.51983)
			(xy 278.365204 -54.519576) (xy 278.370807 -54.512501) (xy 278.377044 -54.495575) (xy 278.377396 -54.486556)
			(xy 278.377396 -54.4195) (xy 278.37704 -54.410483) (xy 278.370792 -54.393566) (xy 278.365204 -54.38648)
			(xy 278.36495 -54.38648) (xy 278.36495 -54.386226) (xy 278.347317 -54.365289) (xy 278.317603 -54.319318)
			(xy 278.294765 -54.269572) (xy 278.279272 -54.217072) (xy 278.271444 -54.162897) (xy 278.27097 -54.135528)
			(xy 278.271456 -54.108277) (xy 278.279212 -54.054329) (xy 278.294567 -54.002034) (xy 278.317209 -53.952457)
			(xy 278.346675 -53.906607) (xy 278.382366 -53.865416) (xy 278.423557 -53.829725) (xy 278.469407 -53.800259)
			(xy 278.518984 -53.777617) (xy 278.571279 -53.762262) (xy 278.625227 -53.754506) (xy 278.679729 -53.754506)
			(xy 278.733677 -53.762262) (xy 278.785972 -53.777617) (xy 278.835549 -53.800259) (xy 278.881399 -53.829725)
			(xy 278.92259 -53.865416) (xy 278.958281 -53.906607) (xy 278.987747 -53.952457) (xy 278.992822 -53.96357)
			(xy 282.972 -53.96357) (xy 282.976071 -53.907948) (xy 282.988197 -53.853511) (xy 283.00812 -53.80142)
			(xy 283.035416 -53.752785) (xy 283.069502 -53.708642) (xy 283.109651 -53.669933) (xy 283.155009 -53.637482)
			(xy 283.204609 -53.611981) (xy 283.257393 -53.593974) (xy 283.312236 -53.583844) (xy 283.36797 -53.581807)
			(xy 283.423407 -53.587907) (xy 283.477364 -53.602013) (xy 283.528693 -53.623825) (xy 283.576299 -53.652879)
			(xy 283.619167 -53.688554) (xy 283.656384 -53.730091) (xy 283.687157 -53.776604) (xy 283.710829 -53.827101)
			(xy 283.726897 -53.880508) (xy 283.735017 -53.935684) (xy 283.735526 -53.96357) (xy 283.735017 -53.991456)
			(xy 283.726897 -54.046632) (xy 283.710829 -54.100039) (xy 283.687157 -54.150536) (xy 283.656384 -54.197049)
			(xy 283.619167 -54.238586) (xy 283.576299 -54.274261) (xy 283.528693 -54.303315) (xy 283.477364 -54.325127)
			(xy 283.423407 -54.339233) (xy 283.36797 -54.345333) (xy 283.312236 -54.343296) (xy 283.257393 -54.333166)
			(xy 283.204609 -54.315159) (xy 283.155009 -54.289658) (xy 283.109651 -54.257207) (xy 283.069502 -54.218498)
			(xy 283.035416 -54.174355) (xy 283.00812 -54.12572) (xy 282.988197 -54.073629) (xy 282.976071 -54.019192)
			(xy 282.972 -53.96357) (xy 278.992822 -53.96357) (xy 279.010389 -54.002034) (xy 279.025744 -54.054329)
			(xy 279.0335 -54.108277) (xy 279.033986 -54.135528) (xy 279.03354 -54.162899) (xy 279.025718 -54.217079)
			(xy 279.010224 -54.269583) (xy 278.987378 -54.319329) (xy 278.957649 -54.365295) (xy 278.940006 -54.386226)
			(xy 278.939752 -54.38648) (xy 278.934162 -54.393564) (xy 278.927919 -54.410483) (xy 278.92756 -54.4195)
			(xy 278.92756 -54.486556) (xy 278.927925 -54.495572) (xy 278.934166 -54.51249) (xy 278.939752 -54.519576)
			(xy 278.940006 -54.519576) (xy 278.940006 -54.51983) (xy 278.957627 -54.540777) (xy 278.987341 -54.586746)
			(xy 279.01018 -54.636489) (xy 279.025676 -54.688987) (xy 279.033509 -54.74316) (xy 279.033986 -54.770528)
			(xy 279.0335 -54.797779) (xy 279.025744 -54.851727) (xy 279.010389 -54.904022) (xy 278.987747 -54.953599)
			(xy 278.964961 -54.989055) (xy 288.100945 -54.989055) (xy 288.100945 -54.934545) (xy 288.108703 -54.880591)
			(xy 288.12406 -54.82829) (xy 288.146705 -54.778707) (xy 288.176176 -54.732851) (xy 288.211874 -54.691657)
			(xy 288.25307 -54.655962) (xy 288.298928 -54.626494) (xy 288.348512 -54.603852) (xy 288.400814 -54.588498)
			(xy 288.454769 -54.580743) (xy 288.482024 -54.580282) (xy 288.510116 -54.580758) (xy 288.565694 -54.588988)
			(xy 288.619464 -54.605283) (xy 288.670261 -54.629289) (xy 288.716988 -54.660486) (xy 288.758632 -54.698201)
			(xy 288.794294 -54.741616) (xy 288.809176 -54.765448) (xy 288.81451 -54.774338) (xy 288.831528 -54.78653)
			(xy 288.924746 -54.80685) (xy 288.94532 -54.802532) (xy 288.953956 -54.79669) (xy 288.97803 -54.780705)
			(xy 289.029958 -54.755359) (xy 289.085113 -54.73813) (xy 289.142234 -54.729409) (xy 289.171126 -54.728872)
			(xy 289.198377 -54.729354) (xy 289.252324 -54.737113) (xy 289.304617 -54.752471) (xy 289.354193 -54.775113)
			(xy 289.400043 -54.80458) (xy 289.441232 -54.840272) (xy 289.476923 -54.881462) (xy 289.50639 -54.927312)
			(xy 289.529032 -54.976888) (xy 289.544388 -55.029182) (xy 289.552147 -55.083129) (xy 289.552634 -55.11038)
			(xy 289.552172 -55.137751) (xy 289.544356 -55.19193) (xy 289.528867 -55.244434) (xy 289.506024 -55.294181)
			(xy 289.476297 -55.340147) (xy 289.458654 -55.361078) (xy 289.4584 -55.361332) (xy 289.452836 -55.368434)
			(xy 289.446576 -55.385339) (xy 289.446208 -55.394352) (xy 289.446208 -55.461408) (xy 289.446559 -55.470425)
			(xy 289.452811 -55.487342) (xy 289.4584 -55.494428) (xy 289.458654 -55.494428) (xy 289.458654 -55.494682)
			(xy 289.476276 -55.51563) (xy 289.506003 -55.561595) (xy 289.528851 -55.611338) (xy 289.544349 -55.663838)
			(xy 289.55218 -55.718015) (xy 289.552182 -55.772755) (xy 289.544356 -55.826932) (xy 289.528861 -55.879433)
			(xy 289.506017 -55.929179) (xy 289.476294 -55.975146) (xy 289.458654 -55.996078) (xy 289.4584 -55.996332)
			(xy 289.452836 -56.003434) (xy 289.446576 -56.020339) (xy 289.446208 -56.029352) (xy 289.446208 -56.096408)
			(xy 289.446559 -56.105425) (xy 289.452811 -56.122342) (xy 289.4584 -56.129428) (xy 289.458654 -56.129428)
			(xy 289.458654 -56.129682) (xy 289.476291 -56.150616) (xy 289.506005 -56.196588) (xy 289.528842 -56.246334)
			(xy 289.544333 -56.298835) (xy 289.552161 -56.353011) (xy 289.552634 -56.38038) (xy 289.552148 -56.407631)
			(xy 289.544392 -56.461579) (xy 289.529037 -56.513874) (xy 289.506395 -56.563451) (xy 289.476929 -56.609301)
			(xy 289.441238 -56.650492) (xy 289.400047 -56.686183) (xy 289.354197 -56.715649) (xy 289.30462 -56.738291)
			(xy 289.252325 -56.753646) (xy 289.198377 -56.761402) (xy 289.143875 -56.761402) (xy 289.089927 -56.753646)
			(xy 289.037632 -56.738291) (xy 288.988055 -56.715649) (xy 288.942205 -56.686183) (xy 288.901014 -56.650492)
			(xy 288.865323 -56.609301) (xy 288.835857 -56.563451) (xy 288.813215 -56.513874) (xy 288.79786 -56.461579)
			(xy 288.790104 -56.407631) (xy 288.789618 -56.38038) (xy 288.790068 -56.353009) (xy 288.797889 -56.298829)
			(xy 288.813382 -56.246326) (xy 288.836227 -56.196579) (xy 288.865955 -56.150613) (xy 288.883598 -56.129682)
			(xy 288.883852 -56.129428) (xy 288.889439 -56.122342) (xy 288.895684 -56.105425) (xy 288.896044 -56.096408)
			(xy 288.896044 -56.029352) (xy 288.895674 -56.020336) (xy 288.889437 -56.003418) (xy 288.883852 -55.996332)
			(xy 288.883598 -55.996332) (xy 288.883598 -55.996078) (xy 288.865939 -55.975161) (xy 288.836217 -55.929189)
			(xy 288.813375 -55.87944) (xy 288.797881 -55.826936) (xy 288.790055 -55.772756) (xy 288.790057 -55.718014)
			(xy 288.797888 -55.663834) (xy 288.813385 -55.611331) (xy 288.836232 -55.561584) (xy 288.865957 -55.515615)
			(xy 288.883598 -55.494682) (xy 288.883852 -55.494428) (xy 288.889439 -55.487342) (xy 288.895684 -55.470425)
			(xy 288.896044 -55.461408) (xy 288.896044 -55.394352) (xy 288.895674 -55.385336) (xy 288.889437 -55.368418)
			(xy 288.883852 -55.361332) (xy 288.883598 -55.360824) (xy 288.872654 -55.348089) (xy 288.852813 -55.320998)
			(xy 288.843974 -55.306722) (xy 288.83864 -55.297832) (xy 288.821622 -55.28564) (xy 288.728404 -55.26532)
			(xy 288.70783 -55.269638) (xy 288.699194 -55.27548) (xy 288.675132 -55.291483) (xy 288.6232 -55.316825)
			(xy 288.568041 -55.33405) (xy 288.510917 -55.342764) (xy 288.482024 -55.343298) (xy 288.454769 -55.342857)
			(xy 288.400814 -55.335102) (xy 288.348512 -55.319748) (xy 288.298928 -55.297106) (xy 288.25307 -55.267638)
			(xy 288.211874 -55.231943) (xy 288.176176 -55.190749) (xy 288.146705 -55.144893) (xy 288.12406 -55.09531)
			(xy 288.108703 -55.043009) (xy 288.100945 -54.989055) (xy 278.964961 -54.989055) (xy 278.958281 -54.999449)
			(xy 278.92259 -55.04064) (xy 278.881399 -55.076331) (xy 278.835549 -55.105797) (xy 278.785972 -55.128439)
			(xy 278.733677 -55.143794) (xy 278.679729 -55.15155) (xy 278.625227 -55.15155) (xy 278.571279 -55.143794)
			(xy 278.518984 -55.128439) (xy 278.469407 -55.105797) (xy 278.423557 -55.076331) (xy 278.382366 -55.04064)
			(xy 278.346675 -54.999449) (xy 278.317209 -54.953599) (xy 278.294567 -54.904022) (xy 278.279212 -54.851727)
			(xy 278.271456 -54.797779) (xy 278.27097 -54.770528) (xy 275.139049 -54.770528) (xy 275.139404 -54.791102)
			(xy 275.138918 -54.818353) (xy 275.131162 -54.872301) (xy 275.115807 -54.924596) (xy 275.093165 -54.974173)
			(xy 275.063699 -55.020023) (xy 275.028008 -55.061214) (xy 274.986817 -55.096905) (xy 274.940967 -55.126371)
			(xy 274.89139 -55.149013) (xy 274.839095 -55.164368) (xy 274.785147 -55.172124) (xy 274.730645 -55.172124)
			(xy 274.676697 -55.164368) (xy 274.624402 -55.149013) (xy 274.574825 -55.126371) (xy 274.528975 -55.096905)
			(xy 274.487784 -55.061214) (xy 274.452093 -55.020023) (xy 274.422627 -54.974173) (xy 274.399985 -54.924596)
			(xy 274.38463 -54.872301) (xy 274.376874 -54.818353) (xy 274.376388 -54.791102) (xy 272.47843 -54.791102)
			(xy 272.475338 -54.812611) (xy 272.459983 -54.864906) (xy 272.437341 -54.914483) (xy 272.407875 -54.960333)
			(xy 272.372184 -55.001524) (xy 272.330993 -55.037215) (xy 272.285143 -55.066681) (xy 272.235566 -55.089323)
			(xy 272.183271 -55.104678) (xy 272.129323 -55.112434) (xy 272.074821 -55.112434) (xy 272.020873 -55.104678)
			(xy 271.968578 -55.089323) (xy 271.919001 -55.066681) (xy 271.873151 -55.037215) (xy 271.83196 -55.001524)
			(xy 271.796269 -54.960333) (xy 271.766803 -54.914483) (xy 271.744161 -54.864906) (xy 271.728806 -54.812611)
			(xy 271.72105 -54.758663) (xy 271.720564 -54.731412) (xy 270.849344 -54.731412) (xy 270.849344 -55.722266)
			(xy 284.033974 -55.722266) (xy 284.038045 -55.666644) (xy 284.050171 -55.612207) (xy 284.070094 -55.560116)
			(xy 284.09739 -55.511481) (xy 284.131476 -55.467338) (xy 284.171625 -55.428629) (xy 284.216983 -55.396178)
			(xy 284.266583 -55.370677) (xy 284.319367 -55.35267) (xy 284.37421 -55.34254) (xy 284.429944 -55.340503)
			(xy 284.485381 -55.346603) (xy 284.539338 -55.360709) (xy 284.590667 -55.382521) (xy 284.638273 -55.411575)
			(xy 284.649424 -55.420855) (xy 286.424545 -55.420855) (xy 286.424545 -55.366345) (xy 286.432303 -55.312391)
			(xy 286.44766 -55.26009) (xy 286.470305 -55.210507) (xy 286.499776 -55.164651) (xy 286.535474 -55.123457)
			(xy 286.57667 -55.087762) (xy 286.622528 -55.058294) (xy 286.672112 -55.035652) (xy 286.724414 -55.020298)
			(xy 286.778369 -55.012543) (xy 286.805624 -55.012082) (xy 286.831938 -55.012539) (xy 286.884067 -55.019777)
			(xy 286.93471 -55.034098) (xy 286.982908 -55.055233) (xy 287.027752 -55.08278) (xy 287.068391 -55.11622)
			(xy 287.086548 -55.135272) (xy 287.094053 -55.142693) (xy 287.113346 -55.151207) (xy 287.123886 -55.151782)
			(xy 287.198562 -55.151782) (xy 287.209112 -55.151251) (xy 287.228407 -55.142718) (xy 287.2359 -55.135272)
			(xy 287.254057 -55.116218) (xy 287.294687 -55.082762) (xy 287.339527 -55.055203) (xy 287.387728 -55.034065)
			(xy 287.438375 -55.019747) (xy 287.490508 -55.012521) (xy 287.516824 -55.012082) (xy 287.544073 -55.01259)
			(xy 287.598017 -55.020349) (xy 287.650307 -55.035706) (xy 287.69988 -55.058348) (xy 287.745726 -55.087814)
			(xy 287.786913 -55.123504) (xy 287.822601 -55.164693) (xy 287.852064 -55.210541) (xy 287.874703 -55.260115)
			(xy 287.890056 -55.312406) (xy 287.897812 -55.366351) (xy 287.897812 -55.420849) (xy 287.890056 -55.474794)
			(xy 287.874703 -55.527085) (xy 287.852064 -55.576659) (xy 287.822601 -55.622507) (xy 287.786913 -55.663696)
			(xy 287.745726 -55.699386) (xy 287.69988 -55.728852) (xy 287.650307 -55.751494) (xy 287.598017 -55.766851)
			(xy 287.544073 -55.77461) (xy 287.516824 -55.775098) (xy 287.490511 -55.774615) (xy 287.438383 -55.767384)
			(xy 287.38774 -55.753068) (xy 287.339541 -55.731938) (xy 287.294697 -55.704395) (xy 287.254057 -55.670958)
			(xy 287.2359 -55.651908) (xy 287.228379 -55.644506) (xy 287.209099 -55.635981) (xy 287.198562 -55.635398)
			(xy 287.123886 -55.635398) (xy 287.113334 -55.635907) (xy 287.094039 -55.644456) (xy 287.086548 -55.651908)
			(xy 287.068412 -55.670983) (xy 287.027778 -55.704438) (xy 286.982934 -55.731995) (xy 286.934729 -55.75313)
			(xy 286.884078 -55.767443) (xy 286.831941 -55.774662) (xy 286.805624 -55.775098) (xy 286.778369 -55.774657)
			(xy 286.724414 -55.766902) (xy 286.672112 -55.751548) (xy 286.622528 -55.728906) (xy 286.57667 -55.699438)
			(xy 286.535474 -55.663743) (xy 286.499776 -55.622549) (xy 286.470305 -55.576693) (xy 286.44766 -55.52711)
			(xy 286.432303 -55.474809) (xy 286.424545 -55.420855) (xy 284.649424 -55.420855) (xy 284.681141 -55.44725)
			(xy 284.718358 -55.488787) (xy 284.749131 -55.5353) (xy 284.772803 -55.585797) (xy 284.788871 -55.639204)
			(xy 284.796991 -55.69438) (xy 284.7975 -55.722266) (xy 284.796991 -55.750152) (xy 284.788871 -55.805328)
			(xy 284.772803 -55.858735) (xy 284.749131 -55.909232) (xy 284.718358 -55.955745) (xy 284.681141 -55.997282)
			(xy 284.638273 -56.032957) (xy 284.590667 -56.062011) (xy 284.539338 -56.083823) (xy 284.485381 -56.097929)
			(xy 284.429944 -56.104029) (xy 284.37421 -56.101992) (xy 284.319367 -56.091862) (xy 284.266583 -56.073855)
			(xy 284.216983 -56.048354) (xy 284.171625 -56.015903) (xy 284.131476 -55.977194) (xy 284.09739 -55.933051)
			(xy 284.070094 -55.884416) (xy 284.050171 -55.832325) (xy 284.038045 -55.777888) (xy 284.033974 -55.722266)
			(xy 270.849344 -55.722266) (xy 270.849344 -56.845454) (xy 270.858812 -57.002934) (xy 279.763474 -57.002934)
			(xy 279.764 -56.974844) (xy 279.772222 -56.919268) (xy 279.788508 -56.8655) (xy 279.812505 -56.814703)
			(xy 279.843695 -56.767976) (xy 279.881403 -56.726329) (xy 279.924812 -56.690666) (xy 279.94864 -56.675782)
			(xy 279.95753 -56.670448) (xy 279.969722 -56.65343) (xy 279.990042 -56.560212) (xy 279.985724 -56.539638)
			(xy 279.979882 -56.531002) (xy 279.963879 -56.50694) (xy 279.938537 -56.455008) (xy 279.921313 -56.399849)
			(xy 279.912598 -56.342725) (xy 279.912064 -56.313832) (xy 279.912585 -56.286581) (xy 279.920337 -56.232634)
			(xy 279.935687 -56.180339) (xy 279.958324 -56.130761) (xy 279.987786 -56.084909) (xy 280.023474 -56.043716)
			(xy 280.064661 -56.008022) (xy 280.110508 -55.978553) (xy 280.160082 -55.955908) (xy 280.212375 -55.94055)
			(xy 280.266321 -55.932789) (xy 280.293572 -55.932324) (xy 280.320942 -55.932801) (xy 280.375121 -55.940615)
			(xy 280.427624 -55.956101) (xy 280.477371 -55.978941) (xy 280.523338 -56.008664) (xy 280.54427 -56.026304)
			(xy 280.544524 -56.026558) (xy 280.551595 -56.032168) (xy 280.568524 -56.038399) (xy 280.577544 -56.03875)
			(xy 280.6446 -56.03875) (xy 280.653618 -56.038404) (xy 280.670536 -56.03215) (xy 280.67762 -56.026558)
			(xy 280.67762 -56.026304) (xy 280.677874 -56.026304) (xy 280.698807 -56.008663) (xy 280.744775 -55.978939)
			(xy 280.794521 -55.956093) (xy 280.847023 -55.940597) (xy 280.901201 -55.932768) (xy 280.955943 -55.932768)
			(xy 281.010121 -55.940597) (xy 281.062623 -55.956093) (xy 281.112369 -55.978939) (xy 281.158337 -56.008663)
			(xy 281.17927 -56.026304) (xy 281.179524 -56.026558) (xy 281.186595 -56.032168) (xy 281.203524 -56.038399)
			(xy 281.212544 -56.03875) (xy 281.2796 -56.03875) (xy 281.288618 -56.038404) (xy 281.305536 -56.03215)
			(xy 281.31262 -56.026558) (xy 281.31262 -56.026304) (xy 281.312874 -56.026304) (xy 281.333806 -56.008664)
			(xy 281.379778 -55.978952) (xy 281.429526 -55.956116) (xy 281.482027 -55.940626) (xy 281.536203 -55.932798)
			(xy 281.563572 -55.932324) (xy 281.590828 -55.932721) (xy 281.644787 -55.940475) (xy 281.697093 -55.95583)
			(xy 281.746681 -55.978473) (xy 281.792541 -56.007943) (xy 281.833741 -56.04364) (xy 281.86944 -56.084836)
			(xy 281.898913 -56.130695) (xy 281.92156 -56.180281) (xy 281.936919 -56.232586) (xy 281.944677 -56.286544)
			(xy 281.944677 -56.297068) (xy 282.286454 -56.297068) (xy 282.290525 -56.241446) (xy 282.302651 -56.187009)
			(xy 282.322574 -56.134918) (xy 282.34987 -56.086283) (xy 282.383956 -56.04214) (xy 282.424105 -56.003431)
			(xy 282.469463 -55.97098) (xy 282.519063 -55.945479) (xy 282.571847 -55.927472) (xy 282.62669 -55.917342)
			(xy 282.682424 -55.915305) (xy 282.737861 -55.921405) (xy 282.791818 -55.935511) (xy 282.843147 -55.957323)
			(xy 282.890753 -55.986377) (xy 282.933621 -56.022052) (xy 282.970838 -56.063589) (xy 283.001611 -56.110102)
			(xy 283.025283 -56.160599) (xy 283.041351 -56.214006) (xy 283.049471 -56.269182) (xy 283.04998 -56.297068)
			(xy 283.049471 -56.324954) (xy 283.041351 -56.38013) (xy 283.025283 -56.433537) (xy 283.001611 -56.484034)
			(xy 282.970838 -56.530547) (xy 282.933621 -56.572084) (xy 282.890753 -56.607759) (xy 282.843147 -56.636813)
			(xy 282.791818 -56.658625) (xy 282.737861 -56.672731) (xy 282.682424 -56.678831) (xy 282.62669 -56.676794)
			(xy 282.571847 -56.666664) (xy 282.519063 -56.648657) (xy 282.469463 -56.623156) (xy 282.424105 -56.590705)
			(xy 282.383956 -56.551996) (xy 282.34987 -56.507853) (xy 282.322574 -56.459218) (xy 282.302651 -56.407127)
			(xy 282.290525 -56.35269) (xy 282.286454 -56.297068) (xy 281.944677 -56.297068) (xy 281.944677 -56.341056)
			(xy 281.936919 -56.395014) (xy 281.92156 -56.447319) (xy 281.898913 -56.496905) (xy 281.86944 -56.542764)
			(xy 281.833741 -56.58396) (xy 281.792541 -56.619657) (xy 281.746681 -56.649127) (xy 281.697093 -56.67177)
			(xy 281.644787 -56.687125) (xy 281.590828 -56.694879) (xy 281.563572 -56.69534) (xy 281.5362 -56.694905)
			(xy 281.482019 -56.687082) (xy 281.429515 -56.671586) (xy 281.379769 -56.648737) (xy 281.333804 -56.619005)
			(xy 281.312874 -56.60136) (xy 281.31262 -56.601106) (xy 281.305531 -56.595522) (xy 281.288616 -56.589274)
			(xy 281.2796 -56.588914) (xy 281.212544 -56.588914) (xy 281.203529 -56.589289) (xy 281.186612 -56.595524)
			(xy 281.179524 -56.601106) (xy 281.179524 -56.60136) (xy 281.17927 -56.60136) (xy 281.158337 -56.619001)
			(xy 281.112369 -56.648725) (xy 281.062623 -56.671571) (xy 281.010121 -56.687067) (xy 280.955943 -56.694896)
			(xy 280.901201 -56.694896) (xy 280.847023 -56.687067) (xy 280.794521 -56.671571) (xy 280.744775 -56.648725)
			(xy 280.698807 -56.619001) (xy 280.677874 -56.60136) (xy 280.67762 -56.601106) (xy 280.670531 -56.595522)
			(xy 280.653616 -56.589274) (xy 280.6446 -56.588914) (xy 280.577544 -56.588914) (xy 280.568529 -56.589289)
			(xy 280.551612 -56.595524) (xy 280.544524 -56.601106) (xy 280.544016 -56.60136) (xy 280.531285 -56.612308)
			(xy 280.504191 -56.632147) (xy 280.489914 -56.640984) (xy 280.481024 -56.646318) (xy 280.468832 -56.663336)
			(xy 280.448512 -56.756554) (xy 280.45283 -56.777128) (xy 280.458672 -56.785764) (xy 280.474656 -56.809838)
			(xy 280.500003 -56.861766) (xy 280.517233 -56.91692) (xy 280.525953 -56.974042) (xy 280.52649 -57.002934)
			(xy 280.526004 -57.030185) (xy 280.518248 -57.084133) (xy 280.502893 -57.136428) (xy 280.480251 -57.186005)
			(xy 280.450785 -57.231855) (xy 280.415094 -57.273046) (xy 280.373903 -57.308737) (xy 280.328053 -57.338203)
			(xy 280.278476 -57.360845) (xy 280.226181 -57.3762) (xy 280.172233 -57.383956) (xy 280.117731 -57.383956)
			(xy 280.063783 -57.3762) (xy 280.011488 -57.360845) (xy 279.961911 -57.338203) (xy 279.916061 -57.308737)
			(xy 279.87487 -57.273046) (xy 279.839179 -57.231855) (xy 279.809713 -57.186005) (xy 279.787071 -57.136428)
			(xy 279.771716 -57.084133) (xy 279.76396 -57.030185) (xy 279.763474 -57.002934) (xy 270.858812 -57.002934)
			(xy 270.883888 -57.420002) (xy 270.887803 -57.48528) (xy 288.805872 -57.48528) (xy 288.809943 -57.429658)
			(xy 288.822069 -57.375221) (xy 288.841992 -57.32313) (xy 288.869288 -57.274495) (xy 288.903374 -57.230352)
			(xy 288.943523 -57.191643) (xy 288.988881 -57.159192) (xy 289.038481 -57.133691) (xy 289.091265 -57.115684)
			(xy 289.146108 -57.105554) (xy 289.201842 -57.103517) (xy 289.257279 -57.109617) (xy 289.311236 -57.123723)
			(xy 289.362565 -57.145535) (xy 289.410171 -57.174589) (xy 289.453039 -57.210264) (xy 289.490256 -57.251801)
			(xy 289.521029 -57.298314) (xy 289.544701 -57.348811) (xy 289.560769 -57.402218) (xy 289.568889 -57.457394)
			(xy 289.569398 -57.48528) (xy 289.568889 -57.513166) (xy 289.560769 -57.568342) (xy 289.544701 -57.621749)
			(xy 289.521029 -57.672246) (xy 289.490256 -57.718759) (xy 289.453039 -57.760296) (xy 289.410171 -57.795971)
			(xy 289.362565 -57.825025) (xy 289.311236 -57.846837) (xy 289.257279 -57.860943) (xy 289.201842 -57.867043)
			(xy 289.146108 -57.865006) (xy 289.091265 -57.854876) (xy 289.038481 -57.836869) (xy 288.988881 -57.811368)
			(xy 288.943523 -57.778917) (xy 288.903374 -57.740208) (xy 288.869288 -57.696065) (xy 288.841992 -57.64743)
			(xy 288.822069 -57.595339) (xy 288.809943 -57.540902) (xy 288.805872 -57.48528) (xy 270.887803 -57.48528)
			(xy 270.952976 -58.571892) (xy 270.959425 -58.679334) (xy 280.195274 -58.679334) (xy 280.195706 -58.653019)
			(xy 280.202949 -58.600889) (xy 280.217276 -58.550246) (xy 280.238415 -58.502047) (xy 280.265967 -58.457205)
			(xy 280.29941 -58.416566) (xy 280.318464 -58.39841) (xy 280.325858 -58.390882) (xy 280.334388 -58.371607)
			(xy 280.334974 -58.361072) (xy 280.334974 -58.286396) (xy 280.334468 -58.275843) (xy 280.325917 -58.256548)
			(xy 280.318464 -58.249058) (xy 280.299388 -58.230923) (xy 280.265934 -58.190288) (xy 280.238379 -58.145443)
			(xy 280.217244 -58.097239) (xy 280.202931 -58.046588) (xy 280.19571 -57.994451) (xy 280.195274 -57.968134)
			(xy 280.19576 -57.940883) (xy 280.203516 -57.886935) (xy 280.218871 -57.83464) (xy 280.241513 -57.785063)
			(xy 280.270979 -57.739213) (xy 280.30667 -57.698022) (xy 280.347861 -57.662331) (xy 280.393711 -57.632865)
			(xy 280.443288 -57.610223) (xy 280.495583 -57.594868) (xy 280.549531 -57.587112) (xy 280.604033 -57.587112)
			(xy 280.657981 -57.594868) (xy 280.710276 -57.610223) (xy 280.759853 -57.632865) (xy 280.805703 -57.662331)
			(xy 280.846894 -57.698022) (xy 280.882585 -57.739213) (xy 280.912051 -57.785063) (xy 280.934693 -57.83464)
			(xy 280.950048 -57.886935) (xy 280.957804 -57.940883) (xy 280.95829 -57.968134) (xy 280.957848 -57.994449)
			(xy 280.950609 -58.046579) (xy 280.943341 -58.072274) (xy 284.193486 -58.072274) (xy 284.197557 -58.016652)
			(xy 284.209683 -57.962215) (xy 284.229606 -57.910124) (xy 284.256902 -57.861489) (xy 284.290988 -57.817346)
			(xy 284.331137 -57.778637) (xy 284.376495 -57.746186) (xy 284.426095 -57.720685) (xy 284.478879 -57.702678)
			(xy 284.533722 -57.692548) (xy 284.589456 -57.690511) (xy 284.644893 -57.696611) (xy 284.69885 -57.710717)
			(xy 284.750179 -57.732529) (xy 284.797785 -57.761583) (xy 284.840653 -57.797258) (xy 284.87787 -57.838795)
			(xy 284.908643 -57.885308) (xy 284.932315 -57.935805) (xy 284.948383 -57.989212) (xy 284.956503 -58.044388)
			(xy 284.957012 -58.072274) (xy 284.956942 -58.076084) (xy 289.557966 -58.076084) (xy 289.562037 -58.020462)
			(xy 289.574163 -57.966025) (xy 289.594086 -57.913934) (xy 289.621382 -57.865299) (xy 289.655468 -57.821156)
			(xy 289.695617 -57.782447) (xy 289.740975 -57.749996) (xy 289.790575 -57.724495) (xy 289.843359 -57.706488)
			(xy 289.898202 -57.696358) (xy 289.953936 -57.694321) (xy 290.009373 -57.700421) (xy 290.06333 -57.714527)
			(xy 290.114659 -57.736339) (xy 290.162265 -57.765393) (xy 290.205133 -57.801068) (xy 290.24235 -57.842605)
			(xy 290.258686 -57.867296) (xy 291.84295 -57.867296) (xy 291.847021 -57.811674) (xy 291.859147 -57.757237)
			(xy 291.87907 -57.705146) (xy 291.906366 -57.656511) (xy 291.940452 -57.612368) (xy 291.980601 -57.573659)
			(xy 292.025959 -57.541208) (xy 292.075559 -57.515707) (xy 292.128343 -57.4977) (xy 292.183186 -57.48757)
			(xy 292.23892 -57.485533) (xy 292.294357 -57.491633) (xy 292.348314 -57.505739) (xy 292.399643 -57.527551)
			(xy 292.447249 -57.556605) (xy 292.490117 -57.59228) (xy 292.527334 -57.633817) (xy 292.558107 -57.68033)
			(xy 292.581779 -57.730827) (xy 292.597847 -57.784234) (xy 292.605967 -57.83941) (xy 292.606476 -57.867296)
			(xy 292.605967 -57.895182) (xy 292.597847 -57.950358) (xy 292.581779 -58.003765) (xy 292.558107 -58.054262)
			(xy 292.527334 -58.100775) (xy 292.490117 -58.142312) (xy 292.447249 -58.177987) (xy 292.399643 -58.207041)
			(xy 292.348314 -58.228853) (xy 292.294357 -58.242959) (xy 292.23892 -58.249059) (xy 292.183186 -58.247022)
			(xy 292.128343 -58.236892) (xy 292.075559 -58.218885) (xy 292.025959 -58.193384) (xy 291.980601 -58.160933)
			(xy 291.940452 -58.122224) (xy 291.906366 -58.078081) (xy 291.87907 -58.029446) (xy 291.859147 -57.977355)
			(xy 291.847021 -57.922918) (xy 291.84295 -57.867296) (xy 290.258686 -57.867296) (xy 290.273123 -57.889118)
			(xy 290.296795 -57.939615) (xy 290.312863 -57.993022) (xy 290.320983 -58.048198) (xy 290.321492 -58.076084)
			(xy 290.320983 -58.10397) (xy 290.312863 -58.159146) (xy 290.296795 -58.212553) (xy 290.273123 -58.26305)
			(xy 290.24235 -58.309563) (xy 290.205133 -58.3511) (xy 290.162265 -58.386775) (xy 290.114659 -58.415829)
			(xy 290.06333 -58.437641) (xy 290.009373 -58.451747) (xy 289.953936 -58.457847) (xy 289.898202 -58.45581)
			(xy 289.843359 -58.44568) (xy 289.790575 -58.427673) (xy 289.740975 -58.402172) (xy 289.695617 -58.369721)
			(xy 289.655468 -58.331012) (xy 289.621382 -58.286869) (xy 289.594086 -58.238234) (xy 289.574163 -58.186143)
			(xy 289.562037 -58.131706) (xy 289.557966 -58.076084) (xy 284.956942 -58.076084) (xy 284.956503 -58.10016)
			(xy 284.948383 -58.155336) (xy 284.932315 -58.208743) (xy 284.908643 -58.25924) (xy 284.87787 -58.305753)
			(xy 284.840653 -58.34729) (xy 284.797785 -58.382965) (xy 284.750179 -58.412019) (xy 284.69885 -58.433831)
			(xy 284.644893 -58.447937) (xy 284.589456 -58.454037) (xy 284.533722 -58.452) (xy 284.478879 -58.44187)
			(xy 284.426095 -58.423863) (xy 284.376495 -58.398362) (xy 284.331137 -58.365911) (xy 284.290988 -58.327202)
			(xy 284.256902 -58.283059) (xy 284.229606 -58.234424) (xy 284.209683 -58.182333) (xy 284.197557 -58.127896)
			(xy 284.193486 -58.072274) (xy 280.943341 -58.072274) (xy 280.936285 -58.097222) (xy 280.915148 -58.145421)
			(xy 280.887597 -58.190264) (xy 280.854154 -58.230902) (xy 280.8351 -58.249058) (xy 280.827715 -58.256593)
			(xy 280.819181 -58.275863) (xy 280.81859 -58.286396) (xy 280.81859 -58.361072) (xy 280.819124 -58.371621)
			(xy 280.827656 -58.390916) (xy 280.8351 -58.39841) (xy 280.854153 -58.416568) (xy 280.887611 -58.457197)
			(xy 280.91517 -58.502037) (xy 280.936309 -58.550237) (xy 280.939415 -58.561224) (xy 290.76218 -58.561224)
			(xy 290.766251 -58.505602) (xy 290.778377 -58.451165) (xy 290.7983 -58.399074) (xy 290.825596 -58.350439)
			(xy 290.859682 -58.306296) (xy 290.899831 -58.267587) (xy 290.945189 -58.235136) (xy 290.994789 -58.209635)
			(xy 291.047573 -58.191628) (xy 291.102416 -58.181498) (xy 291.15815 -58.179461) (xy 291.213587 -58.185561)
			(xy 291.267544 -58.199667) (xy 291.318873 -58.221479) (xy 291.366479 -58.250533) (xy 291.409347 -58.286208)
			(xy 291.446564 -58.327745) (xy 291.477337 -58.374258) (xy 291.501009 -58.424755) (xy 291.508519 -58.449718)
			(xy 293.00881 -58.449718) (xy 293.012881 -58.394096) (xy 293.025007 -58.339659) (xy 293.04493 -58.287568)
			(xy 293.072226 -58.238933) (xy 293.106312 -58.19479) (xy 293.146461 -58.156081) (xy 293.191819 -58.12363)
			(xy 293.241419 -58.098129) (xy 293.294203 -58.080122) (xy 293.349046 -58.069992) (xy 293.40478 -58.067955)
			(xy 293.460217 -58.074055) (xy 293.514174 -58.088161) (xy 293.565503 -58.109973) (xy 293.613109 -58.139027)
			(xy 293.655977 -58.174702) (xy 293.693194 -58.216239) (xy 293.723967 -58.262752) (xy 293.747639 -58.313249)
			(xy 293.763707 -58.366656) (xy 293.771827 -58.421832) (xy 293.772336 -58.449718) (xy 293.771827 -58.477604)
			(xy 293.763707 -58.53278) (xy 293.747639 -58.586187) (xy 293.723967 -58.636684) (xy 293.693194 -58.683197)
			(xy 293.655977 -58.724734) (xy 293.613109 -58.760409) (xy 293.565503 -58.789463) (xy 293.514174 -58.811275)
			(xy 293.460217 -58.825381) (xy 293.40478 -58.831481) (xy 293.349046 -58.829444) (xy 293.294203 -58.819314)
			(xy 293.241419 -58.801307) (xy 293.191819 -58.775806) (xy 293.146461 -58.743355) (xy 293.106312 -58.704646)
			(xy 293.072226 -58.660503) (xy 293.04493 -58.611868) (xy 293.025007 -58.559777) (xy 293.012881 -58.50534)
			(xy 293.00881 -58.449718) (xy 291.508519 -58.449718) (xy 291.517077 -58.478162) (xy 291.525197 -58.533338)
			(xy 291.525706 -58.561224) (xy 291.525197 -58.58911) (xy 291.517077 -58.644286) (xy 291.501009 -58.697693)
			(xy 291.477337 -58.74819) (xy 291.446564 -58.794703) (xy 291.409347 -58.83624) (xy 291.366479 -58.871915)
			(xy 291.318873 -58.900969) (xy 291.267544 -58.922781) (xy 291.213587 -58.936887) (xy 291.15815 -58.942987)
			(xy 291.102416 -58.94095) (xy 291.047573 -58.93082) (xy 290.994789 -58.912813) (xy 290.945189 -58.887312)
			(xy 290.899831 -58.854861) (xy 290.859682 -58.816152) (xy 290.825596 -58.772009) (xy 290.7983 -58.723374)
			(xy 290.778377 -58.671283) (xy 290.766251 -58.616846) (xy 290.76218 -58.561224) (xy 280.939415 -58.561224)
			(xy 280.950626 -58.600884) (xy 280.957851 -58.653018) (xy 280.95829 -58.679334) (xy 280.957804 -58.706585)
			(xy 280.950048 -58.760533) (xy 280.934693 -58.812828) (xy 280.912051 -58.862405) (xy 280.882585 -58.908255)
			(xy 280.846894 -58.949446) (xy 280.805703 -58.985137) (xy 280.759853 -59.014603) (xy 280.710276 -59.037245)
			(xy 280.657981 -59.0526) (xy 280.604033 -59.060356) (xy 280.549531 -59.060356) (xy 280.495583 -59.0526)
			(xy 280.443288 -59.037245) (xy 280.393711 -59.014603) (xy 280.347861 -58.985137) (xy 280.30667 -58.949446)
			(xy 280.270979 -58.908255) (xy 280.241513 -58.862405) (xy 280.218871 -58.812828) (xy 280.203516 -58.760533)
			(xy 280.19576 -58.706585) (xy 280.195274 -58.679334) (xy 270.959425 -58.679334) (xy 270.989157 -59.174634)
			(xy 289.293044 -59.174634) (xy 289.297115 -59.119012) (xy 289.309241 -59.064575) (xy 289.329164 -59.012484)
			(xy 289.35646 -58.963849) (xy 289.390546 -58.919706) (xy 289.430695 -58.880997) (xy 289.476053 -58.848546)
			(xy 289.525653 -58.823045) (xy 289.578437 -58.805038) (xy 289.63328 -58.794908) (xy 289.689014 -58.792871)
			(xy 289.744451 -58.798971) (xy 289.798408 -58.813077) (xy 289.849737 -58.834889) (xy 289.897343 -58.863943)
			(xy 289.940211 -58.899618) (xy 289.977428 -58.941155) (xy 290.008201 -58.987668) (xy 290.031873 -59.038165)
			(xy 290.047941 -59.091572) (xy 290.056061 -59.146748) (xy 290.05657 -59.174634) (xy 290.056061 -59.20252)
			(xy 290.047941 -59.257696) (xy 290.031873 -59.311103) (xy 290.008201 -59.3616) (xy 289.977428 -59.408113)
			(xy 289.940211 -59.44965) (xy 289.897343 -59.485325) (xy 289.849737 -59.514379) (xy 289.798408 -59.536191)
			(xy 289.744451 -59.550297) (xy 289.689014 -59.556397) (xy 289.63328 -59.55436) (xy 289.578437 -59.54423)
			(xy 289.525653 -59.526223) (xy 289.476053 -59.500722) (xy 289.430695 -59.468271) (xy 289.390546 -59.429562)
			(xy 289.35646 -59.385419) (xy 289.329164 -59.336784) (xy 289.309241 -59.284693) (xy 289.297115 -59.230256)
			(xy 289.293044 -59.174634) (xy 270.989157 -59.174634) (xy 271.009618 -59.515502) (xy 271.011052 -59.523758)
			(xy 271.018435 -59.538788) (xy 271.024096 -59.544966) (xy 271.498384 -60.019254) (xy 280.335661 -60.019254)
			(xy 280.335661 -59.964746) (xy 280.343419 -59.910793) (xy 280.358777 -59.858493) (xy 280.381422 -59.808911)
			(xy 280.410892 -59.763057) (xy 280.446589 -59.721864) (xy 280.487786 -59.686171) (xy 280.533643 -59.656704)
			(xy 280.583227 -59.634064) (xy 280.635528 -59.618712) (xy 280.689482 -59.610959) (xy 280.716736 -59.610498)
			(xy 280.744107 -59.610943) (xy 280.798287 -59.618766) (xy 280.85079 -59.63426) (xy 280.900537 -59.657107)
			(xy 280.946503 -59.686835) (xy 280.967434 -59.704478) (xy 280.967688 -59.704732) (xy 280.974771 -59.710323)
			(xy 280.991691 -59.716566) (xy 281.000708 -59.716924) (xy 281.067764 -59.716924) (xy 281.076778 -59.716545)
			(xy 281.093695 -59.710312) (xy 281.100784 -59.704732) (xy 281.100784 -59.704478) (xy 281.101038 -59.704478)
			(xy 281.121971 -59.686837) (xy 281.167939 -59.657113) (xy 281.217685 -59.634267) (xy 281.270187 -59.618771)
			(xy 281.324365 -59.610942) (xy 281.379107 -59.610942) (xy 281.433285 -59.618771) (xy 281.485787 -59.634267)
			(xy 281.535533 -59.657113) (xy 281.581501 -59.686837) (xy 281.602434 -59.704478) (xy 281.602688 -59.704732)
			(xy 281.609771 -59.710323) (xy 281.626691 -59.716566) (xy 281.635708 -59.716924) (xy 281.702764 -59.716924)
			(xy 281.711778 -59.716545) (xy 281.728695 -59.710312) (xy 281.735784 -59.704732) (xy 281.735784 -59.704478)
			(xy 281.736038 -59.704478) (xy 281.75698 -59.686851) (xy 281.80295 -59.657138) (xy 281.852695 -59.6343)
			(xy 281.905194 -59.618806) (xy 281.959368 -59.610974) (xy 281.986736 -59.610498) (xy 282.013986 -59.610974)
			(xy 282.067931 -59.618735) (xy 282.120222 -59.634094) (xy 282.169795 -59.656737) (xy 282.215642 -59.686205)
			(xy 282.256829 -59.721897) (xy 282.292517 -59.763087) (xy 282.32198 -59.808936) (xy 282.344619 -59.858512)
			(xy 282.359973 -59.910805) (xy 282.367728 -59.96475) (xy 282.367728 -60.01925) (xy 282.359973 -60.073195)
			(xy 282.344619 -60.125488) (xy 282.32198 -60.175064) (xy 282.292517 -60.220913) (xy 282.256829 -60.262103)
			(xy 282.215642 -60.297795) (xy 282.169795 -60.327263) (xy 282.120222 -60.349906) (xy 282.067931 -60.365265)
			(xy 282.013986 -60.373026) (xy 281.986736 -60.373514) (xy 281.959367 -60.373023) (xy 281.905189 -60.365211)
			(xy 281.852686 -60.349727) (xy 281.802939 -60.326891) (xy 281.756971 -60.297172) (xy 281.736038 -60.279534)
			(xy 281.735784 -60.27928) (xy 281.728708 -60.273678) (xy 281.711783 -60.267441) (xy 281.702764 -60.267088)
			(xy 281.635708 -60.267088) (xy 281.626692 -60.267451) (xy 281.609775 -60.273695) (xy 281.602688 -60.27928)
			(xy 281.602434 -60.279534) (xy 281.581501 -60.297175) (xy 281.535533 -60.326899) (xy 281.485787 -60.349745)
			(xy 281.433285 -60.365241) (xy 281.379107 -60.37307) (xy 281.324365 -60.37307) (xy 281.270187 -60.365241)
			(xy 281.217685 -60.349745) (xy 281.167939 -60.326899) (xy 281.121971 -60.297175) (xy 281.101038 -60.279534)
			(xy 281.100784 -60.27928) (xy 281.093708 -60.273678) (xy 281.076783 -60.267441) (xy 281.067764 -60.267088)
			(xy 281.000708 -60.267088) (xy 280.991692 -60.267451) (xy 280.974775 -60.273695) (xy 280.967688 -60.27928)
			(xy 280.967688 -60.279534) (xy 280.967434 -60.279534) (xy 280.946504 -60.297176) (xy 280.90053 -60.326886)
			(xy 280.850782 -60.349721) (xy 280.798281 -60.365212) (xy 280.744105 -60.37304) (xy 280.716736 -60.373514)
			(xy 280.689482 -60.373041) (xy 280.635528 -60.365288) (xy 280.583227 -60.349936) (xy 280.533643 -60.327296)
			(xy 280.487786 -60.297829) (xy 280.446589 -60.262136) (xy 280.410892 -60.220943) (xy 280.381422 -60.175089)
			(xy 280.358777 -60.125507) (xy 280.343419 -60.073207) (xy 280.335661 -60.019254) (xy 271.498384 -60.019254)
			(xy 272.112486 -60.633356) (xy 291.996874 -60.633356) (xy 292.000945 -60.577734) (xy 292.013071 -60.523297)
			(xy 292.032994 -60.471206) (xy 292.06029 -60.422571) (xy 292.094376 -60.378428) (xy 292.134525 -60.339719)
			(xy 292.179883 -60.307268) (xy 292.229483 -60.281767) (xy 292.282267 -60.26376) (xy 292.33711 -60.25363)
			(xy 292.392844 -60.251593) (xy 292.448281 -60.257693) (xy 292.502238 -60.271799) (xy 292.553567 -60.293611)
			(xy 292.601173 -60.322665) (xy 292.644041 -60.35834) (xy 292.681258 -60.399877) (xy 292.712031 -60.44639)
			(xy 292.735703 -60.496887) (xy 292.751771 -60.550294) (xy 292.759891 -60.60547) (xy 292.7604 -60.633356)
			(xy 292.759891 -60.661242) (xy 292.751771 -60.716418) (xy 292.735703 -60.769825) (xy 292.712031 -60.820322)
			(xy 292.681258 -60.866835) (xy 292.644041 -60.908372) (xy 292.601173 -60.944047) (xy 292.553567 -60.973101)
			(xy 292.502238 -60.994913) (xy 292.448281 -61.009019) (xy 292.392844 -61.015119) (xy 292.33711 -61.013082)
			(xy 292.282267 -61.002952) (xy 292.229483 -60.984945) (xy 292.179883 -60.959444) (xy 292.134525 -60.926993)
			(xy 292.094376 -60.888284) (xy 292.06029 -60.844141) (xy 292.032994 -60.795506) (xy 292.013071 -60.743415)
			(xy 292.000945 -60.688978) (xy 291.996874 -60.633356) (xy 272.112486 -60.633356) (xy 272.966942 -61.487812)
			(xy 290.50437 -61.487812) (xy 290.508441 -61.43219) (xy 290.520567 -61.377753) (xy 290.54049 -61.325662)
			(xy 290.567786 -61.277027) (xy 290.601872 -61.232884) (xy 290.642021 -61.194175) (xy 290.687379 -61.161724)
			(xy 290.736979 -61.136223) (xy 290.789763 -61.118216) (xy 290.844606 -61.108086) (xy 290.90034 -61.106049)
			(xy 290.955777 -61.112149) (xy 291.009734 -61.126255) (xy 291.061063 -61.148067) (xy 291.108669 -61.177121)
			(xy 291.151537 -61.212796) (xy 291.188754 -61.254333) (xy 291.219527 -61.300846) (xy 291.243199 -61.351343)
			(xy 291.259267 -61.40475) (xy 291.267387 -61.459926) (xy 291.267896 -61.487812) (xy 291.267387 -61.515698)
			(xy 291.259267 -61.570874) (xy 291.243199 -61.624281) (xy 291.219527 -61.674778) (xy 291.188754 -61.721291)
			(xy 291.151537 -61.762828) (xy 291.108669 -61.798503) (xy 291.061063 -61.827557) (xy 291.009734 -61.849369)
			(xy 290.955777 -61.863475) (xy 290.90034 -61.869575) (xy 290.844606 -61.867538) (xy 290.789763 -61.857408)
			(xy 290.736979 -61.839401) (xy 290.687379 -61.8139) (xy 290.642021 -61.781449) (xy 290.601872 -61.74274)
			(xy 290.567786 -61.698597) (xy 290.54049 -61.649962) (xy 290.520567 -61.597871) (xy 290.508441 -61.543434)
			(xy 290.50437 -61.487812) (xy 272.966942 -61.487812) (xy 273.600164 -62.121034) (xy 288.442144 -62.121034)
			(xy 288.446215 -62.065412) (xy 288.458341 -62.010975) (xy 288.478264 -61.958884) (xy 288.50556 -61.910249)
			(xy 288.539646 -61.866106) (xy 288.579795 -61.827397) (xy 288.625153 -61.794946) (xy 288.674753 -61.769445)
			(xy 288.727537 -61.751438) (xy 288.78238 -61.741308) (xy 288.838114 -61.739271) (xy 288.893551 -61.745371)
			(xy 288.947508 -61.759477) (xy 288.998837 -61.781289) (xy 289.046443 -61.810343) (xy 289.089311 -61.846018)
			(xy 289.126528 -61.887555) (xy 289.157301 -61.934068) (xy 289.180973 -61.984565) (xy 289.197041 -62.037972)
			(xy 289.205161 -62.093148) (xy 289.20567 -62.121034) (xy 289.205161 -62.14892) (xy 289.197041 -62.204096)
			(xy 289.180973 -62.257503) (xy 289.157301 -62.308) (xy 289.126528 -62.354513) (xy 289.089311 -62.39605)
			(xy 289.046443 -62.431725) (xy 288.998837 -62.460779) (xy 288.947508 -62.482591) (xy 288.893551 -62.496697)
			(xy 288.838114 -62.502797) (xy 288.78238 -62.50076) (xy 288.727537 -62.49063) (xy 288.674753 -62.472623)
			(xy 288.625153 -62.447122) (xy 288.579795 -62.414671) (xy 288.539646 -62.375962) (xy 288.50556 -62.331819)
			(xy 288.478264 -62.283184) (xy 288.458341 -62.231093) (xy 288.446215 -62.176656) (xy 288.442144 -62.121034)
			(xy 273.600164 -62.121034) (xy 274.157903 -62.678773) (xy 291.866072 -62.678773) (xy 291.873825 -62.624825)
			(xy 291.889176 -62.57253) (xy 291.911814 -62.522951) (xy 291.941277 -62.477099) (xy 291.976965 -62.435906)
			(xy 292.018152 -62.400212) (xy 292.064 -62.370742) (xy 292.113575 -62.348097) (xy 292.165868 -62.332737)
			(xy 292.219815 -62.324976) (xy 292.247066 -62.324488) (xy 292.270621 -62.324856) (xy 292.317365 -62.330721)
			(xy 292.340284 -62.336172) (xy 292.354053 -62.339147) (xy 292.382198 -62.338305) (xy 292.409044 -62.32981)
			(xy 292.43255 -62.314309) (xy 292.450931 -62.292978) (xy 292.46279 -62.26744) (xy 292.467226 -62.239634)
			(xy 292.463901 -62.211673) (xy 292.458902 -62.198504) (xy 292.449588 -62.175116) (xy 292.436465 -62.126514)
			(xy 292.429843 -62.076609) (xy 292.429438 -62.051438) (xy 292.429837 -62.024184) (xy 292.437589 -61.97023)
			(xy 292.45294 -61.917929) (xy 292.475579 -61.868345) (xy 292.505043 -61.822487) (xy 292.540734 -61.781289)
			(xy 292.581924 -61.74559) (xy 292.627776 -61.716116) (xy 292.677355 -61.693468) (xy 292.729654 -61.678106)
			(xy 292.783606 -61.670343) (xy 292.838113 -61.670337) (xy 292.892067 -61.678088) (xy 292.944368 -61.693439)
			(xy 292.993953 -61.716077) (xy 293.039811 -61.745541) (xy 293.081009 -61.781232) (xy 293.116708 -61.822422)
			(xy 293.146182 -61.868273) (xy 293.168831 -61.917853) (xy 293.184194 -61.970151) (xy 293.191957 -62.024103)
			(xy 293.191963 -62.078611) (xy 293.184212 -62.132564) (xy 293.168862 -62.184866) (xy 293.146224 -62.23445)
			(xy 293.11676 -62.280309) (xy 293.08107 -62.321507) (xy 293.03988 -62.357207) (xy 292.994029 -62.386681)
			(xy 292.94445 -62.40933) (xy 292.892152 -62.424693) (xy 292.8382 -62.432457) (xy 292.810946 -62.432946)
			(xy 292.787391 -62.432575) (xy 292.740647 -62.426712) (xy 292.717728 -62.421262) (xy 292.703963 -62.418253)
			(xy 292.675811 -62.419092) (xy 292.648958 -62.427587) (xy 292.625445 -62.443093) (xy 292.607061 -62.46443)
			(xy 292.595202 -62.489977) (xy 292.590772 -62.517792) (xy 292.594106 -62.545759) (xy 292.59911 -62.55893)
			(xy 292.608434 -62.582314) (xy 292.621554 -62.630918) (xy 292.628171 -62.680824) (xy 292.628574 -62.705996)
			(xy 292.628127 -62.733247) (xy 292.620371 -62.787195) (xy 292.605017 -62.839489) (xy 292.582376 -62.889067)
			(xy 292.552911 -62.934917) (xy 292.517221 -62.976108) (xy 292.476032 -63.0118) (xy 292.430182 -63.041268)
			(xy 292.380606 -63.06391) (xy 292.328312 -63.079267) (xy 292.274365 -63.087025) (xy 292.219863 -63.087027)
			(xy 292.165915 -63.079273) (xy 292.11362 -63.06392) (xy 292.064042 -63.041281) (xy 292.018191 -63.011817)
			(xy 291.976999 -62.976128) (xy 291.941306 -62.93494) (xy 291.911837 -62.889091) (xy 291.889193 -62.839516)
			(xy 291.873835 -62.787222) (xy 291.866075 -62.733275) (xy 291.866072 -62.678773) (xy 274.157903 -62.678773)
			(xy 274.692678 -63.213548) (xy 280.320788 -63.213548) (xy 280.320788 -63.159052) (xy 280.328543 -63.10511)
			(xy 280.343895 -63.052821) (xy 280.366532 -63.003248) (xy 280.395993 -62.957401) (xy 280.431678 -62.916214)
			(xy 280.472861 -62.880523) (xy 280.518704 -62.851056) (xy 280.568274 -62.828413) (xy 280.620561 -62.813054)
			(xy 280.674502 -62.805292) (xy 280.70175 -62.804802) (xy 280.729119 -62.805297) (xy 280.783297 -62.813108)
			(xy 280.8358 -62.82859) (xy 280.885547 -62.851425) (xy 280.931515 -62.881144) (xy 280.952448 -62.898782)
			(xy 280.952702 -62.899036) (xy 280.959781 -62.904634) (xy 280.976704 -62.910873) (xy 280.985722 -62.911228)
			(xy 281.052778 -62.911228) (xy 281.061793 -62.910854) (xy 281.07871 -62.904618) (xy 281.085798 -62.899036)
			(xy 281.085798 -62.898782) (xy 281.086052 -62.898782) (xy 281.106985 -62.881141) (xy 281.152953 -62.851417)
			(xy 281.202699 -62.828571) (xy 281.255201 -62.813075) (xy 281.309379 -62.805246) (xy 281.364121 -62.805246)
			(xy 281.418299 -62.813075) (xy 281.470801 -62.828571) (xy 281.520547 -62.851417) (xy 281.566515 -62.881141)
			(xy 281.587448 -62.898782) (xy 281.587702 -62.899036) (xy 281.594781 -62.904634) (xy 281.611704 -62.910873)
			(xy 281.620722 -62.911228) (xy 281.687778 -62.911228) (xy 281.696793 -62.910854) (xy 281.71371 -62.904618)
			(xy 281.720798 -62.899036) (xy 281.720798 -62.898782) (xy 281.721052 -62.898782) (xy 281.741989 -62.881149)
			(xy 281.787961 -62.851437) (xy 281.837707 -62.8286) (xy 281.890206 -62.813108) (xy 281.944381 -62.805277)
			(xy 281.97175 -62.804802) (xy 281.999006 -62.805241) (xy 282.052964 -62.812993) (xy 282.105269 -62.828345)
			(xy 282.154857 -62.850985) (xy 282.200717 -62.880453) (xy 282.241917 -62.916147) (xy 282.277617 -62.957342)
			(xy 282.307091 -63.003199) (xy 282.329738 -63.052784) (xy 282.339561 -63.086234) (xy 285.587438 -63.086234)
			(xy 285.591509 -63.030612) (xy 285.603635 -62.976175) (xy 285.623558 -62.924084) (xy 285.650854 -62.875449)
			(xy 285.68494 -62.831306) (xy 285.725089 -62.792597) (xy 285.770447 -62.760146) (xy 285.820047 -62.734645)
			(xy 285.872831 -62.716638) (xy 285.927674 -62.706508) (xy 285.983408 -62.704471) (xy 286.038845 -62.710571)
			(xy 286.092802 -62.724677) (xy 286.144131 -62.746489) (xy 286.191737 -62.775543) (xy 286.234605 -62.811218)
			(xy 286.271822 -62.852755) (xy 286.302595 -62.899268) (xy 286.326267 -62.949765) (xy 286.342335 -63.003172)
			(xy 286.350455 -63.058348) (xy 286.350964 -63.086234) (xy 286.350455 -63.11412) (xy 286.342335 -63.169296)
			(xy 286.326267 -63.222703) (xy 286.302595 -63.2732) (xy 286.302442 -63.273432) (xy 287.776664 -63.273432)
			(xy 287.780735 -63.21781) (xy 287.792861 -63.163373) (xy 287.812784 -63.111282) (xy 287.84008 -63.062647)
			(xy 287.874166 -63.018504) (xy 287.914315 -62.979795) (xy 287.959673 -62.947344) (xy 288.009273 -62.921843)
			(xy 288.062057 -62.903836) (xy 288.1169 -62.893706) (xy 288.172634 -62.891669) (xy 288.228071 -62.897769)
			(xy 288.282028 -62.911875) (xy 288.333357 -62.933687) (xy 288.380963 -62.962741) (xy 288.423831 -62.998416)
			(xy 288.461048 -63.039953) (xy 288.491821 -63.086466) (xy 288.515493 -63.136963) (xy 288.531561 -63.19037)
			(xy 288.539681 -63.245546) (xy 288.54019 -63.273432) (xy 288.539681 -63.301318) (xy 288.531561 -63.356494)
			(xy 288.515493 -63.409901) (xy 288.491821 -63.460398) (xy 288.461048 -63.506911) (xy 288.423831 -63.548448)
			(xy 288.380963 -63.584123) (xy 288.333357 -63.613177) (xy 288.282028 -63.634989) (xy 288.228071 -63.649095)
			(xy 288.172634 -63.655195) (xy 288.1169 -63.653158) (xy 288.062057 -63.643028) (xy 288.009273 -63.625021)
			(xy 287.959673 -63.59952) (xy 287.914315 -63.567069) (xy 287.874166 -63.52836) (xy 287.84008 -63.484217)
			(xy 287.812784 -63.435582) (xy 287.792861 -63.383491) (xy 287.780735 -63.329054) (xy 287.776664 -63.273432)
			(xy 286.302442 -63.273432) (xy 286.271822 -63.319713) (xy 286.234605 -63.36125) (xy 286.191737 -63.396925)
			(xy 286.144131 -63.425979) (xy 286.092802 -63.447791) (xy 286.038845 -63.461897) (xy 285.983408 -63.467997)
			(xy 285.927674 -63.46596) (xy 285.872831 -63.45583) (xy 285.820047 -63.437823) (xy 285.770447 -63.412322)
			(xy 285.725089 -63.379871) (xy 285.68494 -63.341162) (xy 285.650854 -63.297019) (xy 285.623558 -63.248384)
			(xy 285.603635 -63.196293) (xy 285.591509 -63.141856) (xy 285.587438 -63.086234) (xy 282.339561 -63.086234)
			(xy 282.345097 -63.105087) (xy 282.352855 -63.159044) (xy 282.352855 -63.213556) (xy 282.345097 -63.267513)
			(xy 282.329738 -63.319816) (xy 282.307091 -63.369401) (xy 282.277617 -63.415258) (xy 282.241917 -63.456453)
			(xy 282.200717 -63.492147) (xy 282.154857 -63.521615) (xy 282.105269 -63.544255) (xy 282.052964 -63.559607)
			(xy 281.999006 -63.567359) (xy 281.97175 -63.567818) (xy 281.94438 -63.567343) (xy 281.8902 -63.55953)
			(xy 281.837697 -63.544044) (xy 281.787949 -63.521204) (xy 281.741983 -63.49148) (xy 281.721052 -63.473838)
			(xy 281.720798 -63.473584) (xy 281.713717 -63.467989) (xy 281.696796 -63.461748) (xy 281.687778 -63.461392)
			(xy 281.620722 -63.461392) (xy 281.611706 -63.461761) (xy 281.594789 -63.468) (xy 281.587702 -63.473584)
			(xy 281.587448 -63.473838) (xy 281.566515 -63.491479) (xy 281.520547 -63.521203) (xy 281.470801 -63.544049)
			(xy 281.418299 -63.559545) (xy 281.364121 -63.567374) (xy 281.309379 -63.567374) (xy 281.255201 -63.559545)
			(xy 281.202699 -63.544049) (xy 281.152953 -63.521203) (xy 281.106985 -63.491479) (xy 281.086052 -63.473838)
			(xy 281.085798 -63.473584) (xy 281.078717 -63.467989) (xy 281.061796 -63.461748) (xy 281.052778 -63.461392)
			(xy 280.985722 -63.461392) (xy 280.976706 -63.461761) (xy 280.959789 -63.468) (xy 280.952702 -63.473584)
			(xy 280.952702 -63.473838) (xy 280.952448 -63.473838) (xy 280.931514 -63.491474) (xy 280.885541 -63.521185)
			(xy 280.835794 -63.544021) (xy 280.783294 -63.559513) (xy 280.729119 -63.567343) (xy 280.70175 -63.567818)
			(xy 280.674502 -63.567308) (xy 280.620561 -63.559546) (xy 280.568274 -63.544187) (xy 280.518704 -63.521544)
			(xy 280.472861 -63.492077) (xy 280.431678 -63.456386) (xy 280.395993 -63.415199) (xy 280.366532 -63.369352)
			(xy 280.343895 -63.319779) (xy 280.328543 -63.26749) (xy 280.320788 -63.213548) (xy 274.692678 -63.213548)
			(xy 275.791422 -64.312292) (xy 291.105842 -64.312292) (xy 291.109913 -64.25667) (xy 291.122039 -64.202233)
			(xy 291.141962 -64.150142) (xy 291.169258 -64.101507) (xy 291.203344 -64.057364) (xy 291.243493 -64.018655)
			(xy 291.288851 -63.986204) (xy 291.338451 -63.960703) (xy 291.391235 -63.942696) (xy 291.446078 -63.932566)
			(xy 291.501812 -63.930529) (xy 291.557249 -63.936629) (xy 291.611206 -63.950735) (xy 291.662535 -63.972547)
			(xy 291.710141 -64.001601) (xy 291.753009 -64.037276) (xy 291.790226 -64.078813) (xy 291.820999 -64.125326)
			(xy 291.844671 -64.175823) (xy 291.860739 -64.22923) (xy 291.868859 -64.284406) (xy 291.869368 -64.312292)
			(xy 291.868859 -64.340178) (xy 291.860739 -64.395354) (xy 291.844671 -64.448761) (xy 291.820999 -64.499258)
			(xy 291.790226 -64.545771) (xy 291.753009 -64.587308) (xy 291.710141 -64.622983) (xy 291.662535 -64.652037)
			(xy 291.611206 -64.673849) (xy 291.557249 -64.687955) (xy 291.501812 -64.694055) (xy 291.446078 -64.692018)
			(xy 291.391235 -64.681888) (xy 291.338451 -64.663881) (xy 291.288851 -64.63838) (xy 291.243493 -64.605929)
			(xy 291.203344 -64.56722) (xy 291.169258 -64.523077) (xy 291.141962 -64.474442) (xy 291.122039 -64.422351)
			(xy 291.109913 -64.367914) (xy 291.105842 -64.312292) (xy 275.791422 -64.312292) (xy 277.037292 -65.558162)
			(xy 277.044688 -65.565014) (xy 277.063287 -65.572757) (xy 277.07336 -65.573148) (xy 278.405336 -65.573148)
			(xy 278.415745 -65.572661) (xy 278.43486 -65.564416) (xy 278.449126 -65.549256) (xy 278.453088 -65.53962)
			(xy 278.485346 -65.450212) (xy 278.486752 -65.446033) (xy 278.488278 -65.437348) (xy 278.488394 -65.43294)
			(xy 278.470106 -65.393824) (xy 278.449039 -65.37561) (xy 278.411899 -65.334115) (xy 278.381189 -65.287659)
			(xy 278.357564 -65.237231) (xy 278.341525 -65.183901) (xy 278.333416 -65.128806) (xy 278.332946 -65.100962)
			(xy 278.333432 -65.073711) (xy 278.341188 -65.019763) (xy 278.356543 -64.967468) (xy 278.379185 -64.917891)
			(xy 278.408651 -64.872041) (xy 278.444342 -64.83085) (xy 278.485533 -64.795159) (xy 278.531383 -64.765693)
			(xy 278.58096 -64.743051) (xy 278.633255 -64.727696) (xy 278.687203 -64.71994) (xy 278.741705 -64.71994)
			(xy 278.795653 -64.727696) (xy 278.847948 -64.743051) (xy 278.897525 -64.765693) (xy 278.943375 -64.795159)
			(xy 278.984566 -64.83085) (xy 279.020257 -64.872041) (xy 279.049723 -64.917891) (xy 279.072365 -64.967468)
			(xy 279.08772 -65.019763) (xy 279.095476 -65.073711) (xy 279.095962 -65.100962) (xy 279.095458 -65.128806)
			(xy 279.087362 -65.183904) (xy 279.071336 -65.237237) (xy 279.047722 -65.287671) (xy 279.017022 -65.334133)
			(xy 278.97989 -65.375635) (xy 278.958802 -65.393824) (xy 278.940514 -65.43294) (xy 278.940601 -65.437351)
			(xy 278.942132 -65.446038) (xy 278.943562 -65.450212) (xy 278.97582 -65.53962) (xy 278.979829 -65.549227)
			(xy 278.994085 -65.564369) (xy 279.013174 -65.572621) (xy 279.023572 -65.573148) (xy 298.518072 -65.573148)
			(xy 298.51985 -65.571624) (xy 298.525184 -65.566544) (xy 298.570142 -65.523872) (xy 298.573555 -65.520485)
			(xy 298.579173 -65.512682) (xy 298.581318 -65.508378) (xy 298.585382 -65.499742) (xy 298.58589 -65.489074)
			(xy 298.588135 -65.460296) (xy 298.600202 -65.40385) (xy 298.620627 -65.349862) (xy 298.648944 -65.299564)
			(xy 298.684509 -65.2541) (xy 298.72651 -65.214506) (xy 298.773992 -65.181684) (xy 298.825872 -65.156382)
			(xy 298.88097 -65.139176) (xy 298.938029 -65.130458) (xy 298.96689 -65.129918) (xy 298.995789 -65.130457)
			(xy 299.052924 -65.139185) (xy 299.10809 -65.156428) (xy 299.160025 -65.181791) (xy 299.207543 -65.214695)
			(xy 299.249557 -65.254387) (xy 299.285105 -65.299959) (xy 299.313377 -65.350371) (xy 299.333724 -65.404469)
			(xy 299.345682 -65.461016) (xy 299.34789 -65.489836) (xy 299.348144 -65.4939) (xy 299.348398 -65.499742)
			(xy 299.352462 -65.508378) (xy 299.354596 -65.512849) (xy 299.360355 -65.52091) (xy 299.363892 -65.52438)
			(xy 299.408342 -65.56629) (xy 299.41393 -65.571878) (xy 299.4152 -65.573148) (xy 304.405284 -65.573148)
			(xy 304.415688 -65.572653) (xy 304.434787 -65.564397) (xy 304.449038 -65.549237) (xy 304.453036 -65.53962)
			(xy 304.490882 -65.434972) (xy 304.4825 -65.404238) (xy 304.476912 -65.399666) (xy 304.455009 -65.381594)
			(xy 304.416287 -65.340063) (xy 304.384155 -65.293246) (xy 304.359326 -65.242179) (xy 304.342349 -65.187994)
			(xy 304.333599 -65.13189) (xy 304.332894 -65.103502) (xy 304.332894 -65.100708) (xy 304.333566 -65.068719)
			(xy 304.344292 -65.005646) (xy 304.35423 -64.975232) (xy 304.35553 -64.971163) (xy 304.356936 -64.962738)
			(xy 304.357024 -64.958468) (xy 304.357024 -64.951102) (xy 304.35423 -64.942466) (xy 304.348388 -64.93002)
			(xy 304.34153 -64.920368) (xy 304.299366 -64.86144) (xy 304.291492 -64.852804) (xy 301.25162 -64.852804)
			(xy 301.218465 -64.852341) (xy 301.15257 -64.844924) (xy 301.087919 -64.830179) (xy 301.025324 -64.808292)
			(xy 300.965572 -64.779539) (xy 300.909412 -64.74428) (xy 300.85755 -64.702959) (xy 300.83379 -64.67983)
			(xy 298.331382 -62.177422) (xy 298.327767 -62.173985) (xy 298.319452 -62.168476) (xy 298.314872 -62.1665)
			(xy 296.867834 -61.568838) (xy 296.837923 -61.555979) (xy 296.780908 -61.52454) (xy 296.727755 -61.486937)
			(xy 296.679129 -61.443639) (xy 296.635635 -61.395189) (xy 296.616374 -61.36894) (xy 295.690798 -60.071508)
			(xy 295.672227 -60.044711) (xy 295.640515 -59.987742) (xy 295.615374 -59.927584) (xy 295.59712 -59.864991)
			(xy 295.585982 -59.800749) (xy 295.58361 -59.768232) (xy 295.56329 -59.427364) (xy 295.562327 -59.418105)
			(xy 295.554634 -59.401171) (xy 295.548304 -59.394344) (xy 295.54297 -59.38901) (xy 295.519861 -59.365231)
			(xy 295.478531 -59.313378) (xy 295.443266 -59.257223) (xy 295.414509 -59.197473) (xy 295.392623 -59.13488)
			(xy 295.377882 -59.070229) (xy 295.370471 -59.004335) (xy 295.369996 -58.97118) (xy 295.369996 -56.205628)
			(xy 294.82669 -47.150274) (xy 294.825928 -47.144178) (xy 294.823896 -47.136304) (xy 294.75938 -46.9519)
			(xy 294.59555 -46.485302) (xy 294.376856 -45.861478) (xy 294.311578 -45.67555) (xy 294.309577 -45.670236)
			(xy 294.303559 -45.660609) (xy 294.29964 -45.6565) (xy 286.461962 -37.818822) (xy 286.448246 -37.811456)
			(xy 286.440626 -37.810186) (xy 286.405447 -37.803285) (xy 286.336963 -37.782083) (xy 286.271544 -37.752759)
			(xy 286.210148 -37.715744) (xy 286.153675 -37.67158) (xy 286.127952 -37.64661) (xy 285.777432 -37.29609)
			(xy 285.752472 -37.270389) (xy 285.708309 -37.213973) (xy 285.671294 -37.15263) (xy 285.641971 -37.08726)
			(xy 285.620769 -37.018823) (xy 285.613856 -36.98367) (xy 285.599886 -36.956746) (xy 285.593536 -36.950396)
			(xy 285.556669 -36.944132) (xy 285.484786 -36.923511) (xy 285.416075 -36.893996) (xy 285.351631 -36.856057)
			(xy 285.292482 -36.810299) (xy 285.265622 -36.78428) (xy 284.915102 -36.43376) (xy 284.89014 -36.40806)
			(xy 284.845973 -36.351646) (xy 284.808952 -36.290304) (xy 284.779623 -36.224935) (xy 284.758414 -36.156499)
			(xy 284.751526 -36.12134) (xy 284.737556 -36.094416) (xy 284.731206 -36.088066) (xy 284.69434 -36.081799)
			(xy 284.62246 -36.061175) (xy 284.553752 -36.031656) (xy 284.489312 -35.993714) (xy 284.430167 -35.947953)
			(xy 284.403292 -35.92195) (xy 284.052772 -35.57143) (xy 284.027812 -35.545729) (xy 283.98365 -35.489312)
			(xy 283.946635 -35.427969) (xy 283.91731 -35.3626) (xy 283.896106 -35.294164) (xy 283.889196 -35.25901)
			(xy 283.875226 -35.232086) (xy 283.868876 -35.225736) (xy 283.832008 -35.219473) (xy 283.760124 -35.198855)
			(xy 283.691411 -35.169341) (xy 283.626967 -35.131402) (xy 283.567818 -35.085643) (xy 283.540962 -35.05962)
			(xy 283.190442 -34.7091) (xy 283.165463 -34.683383) (xy 283.121272 -34.626927) (xy 283.084245 -34.565533)
			(xy 283.054928 -34.500106) (xy 283.033753 -34.43161) (xy 283.026866 -34.396426) (xy 283.025596 -34.388806)
			(xy 283.01823 -34.37509) (xy 282.84043 -34.19729) (xy 282.817319 -34.173512) (xy 282.775984 -34.121659)
			(xy 282.740714 -34.065505) (xy 282.711951 -34.005756) (xy 282.690058 -33.943162) (xy 282.675309 -33.878511)
			(xy 282.667891 -33.812616) (xy 282.667456 -33.77946) (xy 282.667456 -31.41345) (xy 282.663288 -31.409511)
			(xy 282.65354 -31.403475) (xy 282.648152 -31.401512) (xy 282.638754 -31.399226) (xy 282.607537 -31.391369)
			(xy 282.546928 -31.369677) (xy 282.489081 -31.341432) (xy 282.434702 -31.306978) (xy 282.384455 -31.266737)
			(xy 282.361386 -31.244286) (xy 282.048712 -30.931612) (xy 282.024423 -30.906627) (xy 281.981355 -30.851846)
			(xy 281.945133 -30.792316) (xy 281.916275 -30.728888) (xy 281.895195 -30.662469) (xy 281.888184 -30.628336)
			(xy 281.886406 -30.619446) (xy 281.738832 -30.471872) (xy 281.733244 -30.470856) (xy 281.697942 -30.463841)
			(xy 281.629281 -30.442243) (xy 281.563803 -30.412353) (xy 281.502506 -30.374626) (xy 281.446321 -30.329636)
			(xy 281.420824 -30.304232) (xy 281.420316 -30.303724) (xy 281.113484 -29.996892) (xy 281.089078 -29.971742)
			(xy 281.045832 -29.916594) (xy 281.009513 -29.856657) (xy 280.980644 -29.792797) (xy 280.959643 -29.725935)
			(xy 280.952702 -29.691584) (xy 280.951178 -29.684218) (xy 280.60396 -29.337) (xy 280.598372 -29.335984)
			(xy 280.563068 -29.328971) (xy 280.494405 -29.307377) (xy 280.428925 -29.27749) (xy 280.367623 -29.239766)
			(xy 280.311435 -29.194779) (xy 280.285952 -29.16936) (xy 280.285444 -29.168852) (xy 279.978612 -28.86202)
			(xy 279.957669 -28.840508) (xy 279.919853 -28.793874) (xy 279.887036 -28.743596) (xy 279.859567 -28.690208)
			(xy 279.84831 -28.662376) (xy 279.841885 -28.645728) (xy 279.830829 -28.611795) (xy 279.826212 -28.594558)
			(xy 279.820624 -28.572968) (xy 279.818704 -28.568345) (xy 279.813324 -28.559907) (xy 279.809956 -28.556204)
			(xy 279.018238 -28.556204) (xy 278.983657 -28.555701) (xy 278.914971 -28.5476) (xy 278.847702 -28.531528)
			(xy 278.782773 -28.507705) (xy 278.721072 -28.476457) (xy 278.663446 -28.438213) (xy 278.63673 -28.41625)
			(xy 278.63546 -28.415234) (xy 278.622257 -28.40458) (xy 278.596969 -28.381959) (xy 278.584914 -28.370022)
			(xy 278.387048 -28.17241) (xy 278.176228 -27.96159) (xy 278.16883 -27.954745) (xy 278.150231 -27.947023)
			(xy 278.14016 -27.946604) (xy 277.965154 -27.946604) (xy 277.960836 -27.953462) (xy 277.947374 -27.974544)
			(xy 277.929086 -28.003246) (xy 277.925377 -28.009495) (xy 277.92124 -28.023418) (xy 277.920958 -28.030678)
			(xy 277.920958 -28.05811) (xy 277.925276 -28.067762) (xy 277.929086 -28.07716) (xy 277.929086 -28.077414)
			(xy 277.931372 -28.083002) (xy 277.932642 -28.086304) (xy 277.935436 -28.09367) (xy 277.935436 -28.093924)
			(xy 277.935944 -28.095194) (xy 277.938992 -28.103576) (xy 277.940262 -28.108148) (xy 277.94077 -28.109418)
			(xy 277.942548 -28.115006) (xy 277.942548 -28.11526) (xy 277.94458 -28.122118) (xy 277.953096 -28.153371)
			(xy 277.962269 -28.217493) (xy 277.962868 -28.24988) (xy 277.962868 -29.114242) (xy 277.962378 -29.14421)
			(xy 277.954555 -29.203632) (xy 277.939042 -29.261525) (xy 277.916106 -29.316898) (xy 277.886139 -29.368804)
			(xy 277.849652 -29.416354) (xy 277.807272 -29.458734) (xy 277.759722 -29.495221) (xy 277.707816 -29.525188)
			(xy 277.652443 -29.548124) (xy 277.59455 -29.563637) (xy 277.535128 -29.57146) (xy 277.475192 -29.57146)
			(xy 277.41577 -29.563637) (xy 277.357877 -29.548124) (xy 277.302504 -29.525188) (xy 277.250598 -29.495221)
			(xy 277.203048 -29.458734) (xy 277.160668 -29.416354) (xy 277.124181 -29.368804) (xy 277.094214 -29.316898)
			(xy 277.071278 -29.261525) (xy 277.055765 -29.203632) (xy 277.047942 -29.14421) (xy 277.047452 -29.114242)
			(xy 277.047452 -28.250642) (xy 277.047523 -28.23715) (xy 277.049047 -28.210208) (xy 277.0505 -28.196794)
			(xy 277.05304 -28.178252) (xy 277.061422 -28.137612) (xy 277.06828 -28.112974) (xy 277.071582 -28.10256)
			(xy 277.071836 -28.101544) (xy 277.07336 -28.096972) (xy 277.073868 -28.095956) (xy 277.0759 -28.09113)
			(xy 277.076916 -28.088336) (xy 277.07717 -28.088336) (xy 277.07971 -28.081224) (xy 277.079964 -28.080462)
			(xy 277.081234 -28.07716) (xy 277.082504 -28.074112) (xy 277.083266 -28.072334) (xy 277.08352 -28.071826)
			(xy 277.084028 -28.070556) (xy 277.085298 -28.067) (xy 277.085552 -28.066492) (xy 277.089362 -28.057348)
			(xy 277.089362 -28.030678) (xy 277.089127 -28.02341) (xy 277.084988 -28.009475) (xy 277.081234 -28.003246)
			(xy 277.059898 -27.969972) (xy 277.055045 -27.96301) (xy 277.04172 -27.952514) (xy 277.025706 -27.946924)
			(xy 277.017226 -27.946604) (xy 276.960838 -27.946604) (xy 276.923893 -27.946007) (xy 276.850588 -27.936734)
			(xy 276.779014 -27.918379) (xy 276.710293 -27.891229) (xy 276.677628 -27.87396) (xy 276.672548 -27.871674)
			(xy 276.637151 -27.856471) (xy 276.570359 -27.818081) (xy 276.509205 -27.77123) (xy 276.48154 -27.74442)
			(xy 276.479 -27.74188) (xy 276.38248 -27.645106) (xy 276.37994 -27.64282) (xy 275.738082 -27.64282)
			(xy 275.728014 -27.643247) (xy 275.709416 -27.650968) (xy 275.702014 -27.657806) (xy 275.599144 -27.760676)
			(xy 275.575386 -27.783821) (xy 275.523545 -27.825199) (xy 275.467397 -27.860512) (xy 275.407648 -27.889315)
			(xy 275.345049 -27.911247) (xy 275.280388 -27.926032) (xy 275.214479 -27.933483) (xy 275.181314 -27.933904)
			(xy 275.145593 -27.933365) (xy 275.074671 -27.924756) (xy 275.005303 -27.907661) (xy 274.938502 -27.882329)
			(xy 274.875242 -27.849131) (xy 274.816444 -27.808549) (xy 274.762966 -27.761177) (xy 274.715588 -27.707704)
			(xy 274.675 -27.64891) (xy 274.641795 -27.585652) (xy 274.616457 -27.518854) (xy 274.599355 -27.449488)
			(xy 274.590738 -27.378567) (xy 274.590256 -27.342846) (xy 274.590698 -27.310554) (xy 274.597762 -27.246357)
			(xy 274.611789 -27.183314) (xy 274.632612 -27.122178) (xy 274.659981 -27.063679) (xy 274.69357 -27.008516)
			(xy 274.712938 -26.982674) (xy 274.712938 -26.98242) (xy 274.718018 -26.975816) (xy 274.723352 -26.960322)
			(xy 274.723352 -26.870152) (xy 274.723028 -26.861873) (xy 274.717709 -26.846192) (xy 274.712938 -26.839418)
			(xy 274.69359 -26.813562) (xy 274.66002 -26.758392) (xy 274.632659 -26.699893) (xy 274.611834 -26.638762)
			(xy 274.59779 -26.575726) (xy 274.590696 -26.511536) (xy 274.590256 -26.479246) (xy 274.590701 -26.446077)
			(xy 274.598124 -26.380155) (xy 274.612882 -26.315478) (xy 274.634788 -26.252861) (xy 274.663569 -26.193091)
			(xy 274.698861 -26.136919) (xy 274.74022 -26.085052) (xy 274.787128 -26.038142) (xy 274.838992 -25.996779)
			(xy 274.895163 -25.961484) (xy 274.954931 -25.932701) (xy 275.017547 -25.910791) (xy 275.082223 -25.896029)
			(xy 275.148145 -25.888603) (xy 275.181314 -25.888188) (xy 275.214475 -25.88867) (xy 275.280377 -25.896127)
			(xy 275.34503 -25.910913) (xy 275.407623 -25.932843) (xy 275.467368 -25.961639) (xy 275.523515 -25.996941)
			(xy 275.575358 -26.038305) (xy 275.599144 -26.061416) (xy 275.702014 -26.164286) (xy 275.709413 -26.171132)
			(xy 275.728011 -26.178863) (xy 275.738082 -26.179272) (xy 276.774656 -26.179272) (xy 276.80781 -26.179739)
			(xy 276.873701 -26.187164) (xy 276.938347 -26.201915) (xy 277.000937 -26.223807) (xy 277.060685 -26.252564)
			(xy 277.116839 -26.287826) (xy 277.168696 -26.32915) (xy 277.192486 -26.352246) (xy 277.204678 -26.364438)
			(xy 277.21209 -26.371122) (xy 277.230523 -26.378719) (xy 277.250461 -26.378719) (xy 277.268894 -26.371122)
			(xy 277.276306 -26.364438) (xy 277.28291 -26.357834) (xy 277.29053 -26.341324) (xy 277.291038 -26.33218)
			(xy 277.293598 -26.304717) (xy 277.305623 -26.250887) (xy 277.325271 -26.199349) (xy 277.352134 -26.151177)
			(xy 277.368508 -26.12898) (xy 277.385868 -26.107093) (xy 277.425921 -26.06815) (xy 277.471224 -26.035465)
			(xy 277.52081 -26.009736) (xy 277.573618 -25.991514) (xy 277.628519 -25.981187) (xy 277.684339 -25.978978)
			(xy 277.739884 -25.984932) (xy 277.793967 -25.998923) (xy 277.845432 -26.020652) (xy 277.893177 -26.049653)
			(xy 277.936183 -26.085308) (xy 277.973529 -26.126853) (xy 278.004418 -26.1734) (xy 278.028188 -26.223954)
			(xy 278.044331 -26.277434) (xy 278.050586 -26.319734) (xy 283.04185 -26.319734) (xy 283.045921 -26.264112)
			(xy 283.058047 -26.209675) (xy 283.07797 -26.157584) (xy 283.105266 -26.108949) (xy 283.139352 -26.064806)
			(xy 283.179501 -26.026097) (xy 283.224859 -25.993646) (xy 283.274459 -25.968145) (xy 283.327243 -25.950138)
			(xy 283.382086 -25.940008) (xy 283.43782 -25.937971) (xy 283.493257 -25.944071) (xy 283.547214 -25.958177)
			(xy 283.598543 -25.979989) (xy 283.646149 -26.009043) (xy 283.675814 -26.03373) (xy 289.467796 -26.03373)
			(xy 289.471867 -25.978108) (xy 289.483993 -25.923671) (xy 289.503916 -25.87158) (xy 289.531212 -25.822945)
			(xy 289.565298 -25.778802) (xy 289.605447 -25.740093) (xy 289.650805 -25.707642) (xy 289.700405 -25.682141)
			(xy 289.753189 -25.664134) (xy 289.808032 -25.654004) (xy 289.863766 -25.651967) (xy 289.919203 -25.658067)
			(xy 289.97316 -25.672173) (xy 290.024489 -25.693985) (xy 290.072095 -25.723039) (xy 290.114963 -25.758714)
			(xy 290.15218 -25.800251) (xy 290.182953 -25.846764) (xy 290.206625 -25.897261) (xy 290.222693 -25.950668)
			(xy 290.230813 -26.005844) (xy 290.231322 -26.03373) (xy 290.230813 -26.061616) (xy 290.222693 -26.116792)
			(xy 290.206625 -26.170199) (xy 290.182953 -26.220696) (xy 290.152719 -26.266394) (xy 292.720522 -26.266394)
			(xy 292.721008 -26.239143) (xy 292.728764 -26.185195) (xy 292.744119 -26.1329) (xy 292.766761 -26.083323)
			(xy 292.796227 -26.037473) (xy 292.831918 -25.996282) (xy 292.873109 -25.960591) (xy 292.918959 -25.931125)
			(xy 292.968536 -25.908483) (xy 293.020831 -25.893128) (xy 293.074779 -25.885372) (xy 293.129281 -25.885372)
			(xy 293.183229 -25.893128) (xy 293.235524 -25.908483) (xy 293.285101 -25.931125) (xy 293.330951 -25.960591)
			(xy 293.372142 -25.996282) (xy 293.407833 -26.037473) (xy 293.437299 -26.083323) (xy 293.459941 -26.1329)
			(xy 293.475296 -26.185195) (xy 293.483052 -26.239143) (xy 293.483538 -26.266394) (xy 293.482971 -26.295881)
			(xy 293.473877 -26.35415) (xy 293.455921 -26.410324) (xy 293.429531 -26.463064) (xy 293.395335 -26.511113)
			(xy 293.35415 -26.553324) (xy 293.330884 -26.571448) (xy 293.319729 -26.580308) (xy 293.302545 -26.603018)
			(xy 293.292298 -26.62959) (xy 293.289785 -26.657958) (xy 293.295201 -26.685917) (xy 293.308125 -26.711294)
			(xy 293.327553 -26.732118) (xy 293.33952 -26.73985) (xy 293.363261 -26.754748) (xy 293.406495 -26.790415)
			(xy 293.444046 -26.832024) (xy 293.475105 -26.87868) (xy 293.499004 -26.929377) (xy 293.515228 -26.983025)
			(xy 293.523429 -27.03847) (xy 293.523924 -27.066494) (xy 293.523438 -27.093745) (xy 293.515682 -27.147693)
			(xy 293.500327 -27.199988) (xy 293.477685 -27.249565) (xy 293.448219 -27.295415) (xy 293.412528 -27.336606)
			(xy 293.371337 -27.372297) (xy 293.325487 -27.401763) (xy 293.27591 -27.424405) (xy 293.223615 -27.43976)
			(xy 293.169667 -27.447516) (xy 293.115165 -27.447516) (xy 293.061217 -27.43976) (xy 293.008922 -27.424405)
			(xy 292.959345 -27.401763) (xy 292.913495 -27.372297) (xy 292.872304 -27.336606) (xy 292.836613 -27.295415)
			(xy 292.807147 -27.249565) (xy 292.784505 -27.199988) (xy 292.76915 -27.147693) (xy 292.761394 -27.093745)
			(xy 292.760908 -27.066494) (xy 292.761448 -27.037006) (xy 292.770545 -26.978735) (xy 292.788505 -26.922559)
			(xy 292.814901 -26.869818) (xy 292.849102 -26.821771) (xy 292.890293 -26.779562) (xy 292.913562 -26.76144)
			(xy 292.924619 -26.75247) (xy 292.941795 -26.729784) (xy 292.952043 -26.703238) (xy 292.954566 -26.674896)
			(xy 292.94917 -26.646957) (xy 292.936273 -26.621593) (xy 292.916876 -26.600773) (xy 292.904926 -26.593038)
			(xy 292.88119 -26.578132) (xy 292.837953 -26.542468) (xy 292.800401 -26.500861) (xy 292.76934 -26.454207)
			(xy 292.74544 -26.40351) (xy 292.729216 -26.349862) (xy 292.721016 -26.294418) (xy 292.720522 -26.266394)
			(xy 290.152719 -26.266394) (xy 290.15218 -26.267209) (xy 290.114963 -26.308746) (xy 290.072095 -26.344421)
			(xy 290.024489 -26.373475) (xy 289.97316 -26.395287) (xy 289.919203 -26.409393) (xy 289.863766 -26.415493)
			(xy 289.808032 -26.413456) (xy 289.753189 -26.403326) (xy 289.700405 -26.385319) (xy 289.650805 -26.359818)
			(xy 289.605447 -26.327367) (xy 289.565298 -26.288658) (xy 289.531212 -26.244515) (xy 289.503916 -26.19588)
			(xy 289.483993 -26.143789) (xy 289.471867 -26.089352) (xy 289.467796 -26.03373) (xy 283.675814 -26.03373)
			(xy 283.689017 -26.044718) (xy 283.726234 -26.086255) (xy 283.757007 -26.132768) (xy 283.780679 -26.183265)
			(xy 283.796747 -26.236672) (xy 283.804867 -26.291848) (xy 283.805376 -26.319734) (xy 283.804867 -26.34762)
			(xy 283.796747 -26.402796) (xy 283.780679 -26.456203) (xy 283.757007 -26.5067) (xy 283.726234 -26.553213)
			(xy 283.689017 -26.59475) (xy 283.646149 -26.630425) (xy 283.598543 -26.659479) (xy 283.547214 -26.681291)
			(xy 283.493257 -26.695397) (xy 283.43782 -26.701497) (xy 283.382086 -26.69946) (xy 283.327243 -26.68933)
			(xy 283.274459 -26.671323) (xy 283.224859 -26.645822) (xy 283.179501 -26.613371) (xy 283.139352 -26.574662)
			(xy 283.105266 -26.530519) (xy 283.07797 -26.481884) (xy 283.058047 -26.429793) (xy 283.045921 -26.375356)
			(xy 283.04185 -26.319734) (xy 278.050586 -26.319734) (xy 278.052503 -26.332696) (xy 278.053038 -26.360628)
			(xy 278.053038 -26.369518) (xy 278.05253 -26.38044) (xy 278.055578 -26.38933) (xy 278.057493 -26.394542)
			(xy 278.063262 -26.404027) (xy 278.067008 -26.408126) (xy 278.092408 -26.434796) (xy 278.092662 -26.43505)
			(xy 278.102314 -26.444956) (xy 278.102568 -26.44521) (xy 278.119078 -26.461974) (xy 278.120856 -26.463498)
			(xy 278.128049 -26.469364) (xy 278.145367 -26.475999) (xy 278.154638 -26.476452) (xy 278.485092 -26.476452)
			(xy 278.51218 -26.476784) (xy 278.566116 -26.48187) (xy 278.592788 -26.486612) (xy 278.596344 -26.48712)
			(xy 278.628889 -26.491455) (xy 278.692819 -26.506419) (xy 278.754696 -26.528378) (xy 278.813757 -26.557062)
			(xy 278.869274 -26.592117) (xy 278.920562 -26.633111) (xy 278.94407 -26.65603) (xy 279.023572 -26.735532)
			(xy 279.03143 -26.742592) (xy 279.051109 -26.750208) (xy 279.061672 -26.750264) (xy 279.095962 -26.74874)
			(xy 279.096216 -26.74874) (xy 279.11044 -26.748232) (xy 279.120346 -26.743152) (xy 279.130506 -26.738326)
			(xy 279.137872 -26.729436) (xy 279.156089 -26.70799) (xy 279.197754 -26.670173) (xy 279.244523 -26.638887)
			(xy 279.295382 -26.614814) (xy 279.349225 -26.598475) (xy 279.404886 -26.590224) (xy 279.43302 -26.589736)
			(xy 279.460271 -26.590201) (xy 279.514217 -26.59796) (xy 279.56651 -26.613318) (xy 279.616085 -26.635963)
			(xy 279.661932 -26.665432) (xy 279.703119 -26.701126) (xy 279.738806 -26.742319) (xy 279.768268 -26.788171)
			(xy 279.790904 -26.83775) (xy 279.806253 -26.890045) (xy 279.814004 -26.943993) (xy 279.814528 -26.971244)
			(xy 279.813766 -26.994104) (xy 279.813766 -26.99512) (xy 279.813258 -27.004264) (xy 279.81656 -27.013662)
			(xy 279.818314 -27.018397) (xy 279.823433 -27.0271) (xy 279.82672 -27.030934) (xy 279.83688 -27.042364)
			(xy 279.837642 -27.043126) (xy 279.874726 -27.082496) (xy 279.878028 -27.086052) (xy 279.885394 -27.092656)
			(xy 280.18486 -27.092656) (xy 280.218014 -27.093123) (xy 280.283905 -27.100549) (xy 280.348551 -27.1153)
			(xy 280.411141 -27.137191) (xy 280.470889 -27.165948) (xy 280.527044 -27.20121) (xy 280.578901 -27.242533)
			(xy 280.60269 -27.26563) (xy 281.804872 -28.467812) (xy 281.809219 -28.46936) (xy 281.818293 -28.471029)
			(xy 281.822906 -28.471114) (xy 281.831034 -28.471114) (xy 281.907996 -28.44673) (xy 281.90825 -28.44673)
			(xy 281.909774 -28.446222) (xy 281.91079 -28.445968) (xy 281.912822 -28.44546) (xy 281.915362 -28.444952)
			(xy 281.92349 -28.443428) (xy 281.92984 -28.440126) (xy 281.933314 -28.438286) (xy 281.939693 -28.433692)
			(xy 281.94254 -28.430982) (xy 281.94508 -28.428442) (xy 281.947805 -28.425607) (xy 281.952397 -28.419224)
			(xy 281.954224 -28.415742) (xy 281.957526 -28.408884) (xy 281.958796 -28.401772) (xy 281.963959 -28.37568)
			(xy 281.980553 -28.325146) (xy 282.004001 -28.277404) (xy 282.033847 -28.233379) (xy 282.069515 -28.193922)
			(xy 282.110314 -28.159797) (xy 282.155454 -28.131665) (xy 282.204062 -28.11007) (xy 282.255196 -28.09543)
			(xy 282.307868 -28.088029) (xy 282.334462 -28.087574) (xy 282.361717 -28.088034) (xy 282.415673 -28.095787)
			(xy 282.467977 -28.111139) (xy 282.517563 -28.133779) (xy 282.5259 -28.139136) (xy 286.59785 -28.139136)
			(xy 286.601921 -28.083514) (xy 286.614047 -28.029077) (xy 286.63397 -27.976986) (xy 286.661266 -27.928351)
			(xy 286.695352 -27.884208) (xy 286.735501 -27.845499) (xy 286.780859 -27.813048) (xy 286.830459 -27.787547)
			(xy 286.883243 -27.76954) (xy 286.938086 -27.75941) (xy 286.99382 -27.757373) (xy 287.049257 -27.763473)
			(xy 287.103214 -27.777579) (xy 287.154543 -27.799391) (xy 287.202149 -27.828445) (xy 287.245017 -27.86412)
			(xy 287.282234 -27.905657) (xy 287.313007 -27.95217) (xy 287.336679 -28.002667) (xy 287.352747 -28.056074)
			(xy 287.360867 -28.11125) (xy 287.361376 -28.139136) (xy 287.86785 -28.139136) (xy 287.871921 -28.083514)
			(xy 287.884047 -28.029077) (xy 287.90397 -27.976986) (xy 287.931266 -27.928351) (xy 287.965352 -27.884208)
			(xy 288.005501 -27.845499) (xy 288.050859 -27.813048) (xy 288.100459 -27.787547) (xy 288.153243 -27.76954)
			(xy 288.208086 -27.75941) (xy 288.26382 -27.757373) (xy 288.319257 -27.763473) (xy 288.373214 -27.777579)
			(xy 288.424543 -27.799391) (xy 288.472149 -27.828445) (xy 288.515017 -27.86412) (xy 288.552234 -27.905657)
			(xy 288.583007 -27.95217) (xy 288.606679 -28.002667) (xy 288.622747 -28.056074) (xy 288.630867 -28.11125)
			(xy 288.631376 -28.139136) (xy 288.630867 -28.167022) (xy 288.622747 -28.222198) (xy 288.606679 -28.275605)
			(xy 288.583007 -28.326102) (xy 288.552234 -28.372615) (xy 288.515017 -28.414152) (xy 288.472149 -28.449827)
			(xy 288.424543 -28.478881) (xy 288.373214 -28.500693) (xy 288.319257 -28.514799) (xy 288.26382 -28.520899)
			(xy 288.208086 -28.518862) (xy 288.153243 -28.508732) (xy 288.100459 -28.490725) (xy 288.050859 -28.465224)
			(xy 288.005501 -28.432773) (xy 287.965352 -28.394064) (xy 287.931266 -28.349921) (xy 287.90397 -28.301286)
			(xy 287.884047 -28.249195) (xy 287.871921 -28.194758) (xy 287.86785 -28.139136) (xy 287.361376 -28.139136)
			(xy 287.360867 -28.167022) (xy 287.352747 -28.222198) (xy 287.336679 -28.275605) (xy 287.313007 -28.326102)
			(xy 287.282234 -28.372615) (xy 287.245017 -28.414152) (xy 287.202149 -28.449827) (xy 287.154543 -28.478881)
			(xy 287.103214 -28.500693) (xy 287.049257 -28.514799) (xy 286.99382 -28.520899) (xy 286.938086 -28.518862)
			(xy 286.883243 -28.508732) (xy 286.830459 -28.490725) (xy 286.780859 -28.465224) (xy 286.735501 -28.432773)
			(xy 286.695352 -28.394064) (xy 286.661266 -28.349921) (xy 286.63397 -28.301286) (xy 286.614047 -28.249195)
			(xy 286.601921 -28.194758) (xy 286.59785 -28.139136) (xy 282.5259 -28.139136) (xy 282.563422 -28.163246)
			(xy 282.604621 -28.19894) (xy 282.64032 -28.240133) (xy 282.669794 -28.285988) (xy 282.692441 -28.335571)
			(xy 282.707801 -28.387872) (xy 282.715562 -28.441827) (xy 282.71597 -28.469082) (xy 282.715502 -28.495697)
			(xy 282.708092 -28.54841) (xy 282.693427 -28.599581) (xy 282.671791 -28.648216) (xy 282.643606 -28.693373)
			(xy 282.609418 -28.734173) (xy 282.56989 -28.769826) (xy 282.52579 -28.799638) (xy 282.477975 -28.823031)
			(xy 282.427373 -28.83955) (xy 282.401264 -28.844748) (xy 282.394406 -28.846018) (xy 282.38196 -28.852114)
			(xy 282.376626 -28.856686) (xy 282.371561 -28.861421) (xy 282.363964 -28.873013) (xy 282.36164 -28.879546)
			(xy 282.334208 -28.967176) (xy 282.332402 -28.974869) (xy 282.33304 -28.990648) (xy 282.335478 -28.998164)
			(xy 282.459665 -29.12237) (xy 292.806628 -29.12237) (xy 292.806628 -28.25877) (xy 292.807118 -28.228786)
			(xy 292.814946 -28.16933) (xy 292.830467 -28.111405) (xy 292.853416 -28.056001) (xy 292.8834 -28.004067)
			(xy 292.919906 -27.956491) (xy 292.962311 -27.914086) (xy 293.009887 -27.87758) (xy 293.061821 -27.847596)
			(xy 293.117225 -27.824647) (xy 293.17515 -27.809126) (xy 293.234606 -27.801298) (xy 293.294574 -27.801298)
			(xy 293.35403 -27.809126) (xy 293.411955 -27.824647) (xy 293.467359 -27.847596) (xy 293.519293 -27.87758)
			(xy 293.566869 -27.914086) (xy 293.609274 -27.956491) (xy 293.64578 -28.004067) (xy 293.675764 -28.056001)
			(xy 293.698713 -28.111405) (xy 293.714234 -28.16933) (xy 293.722062 -28.228786) (xy 293.722552 -28.25877)
			(xy 293.722552 -29.12237) (xy 293.722062 -29.152354) (xy 293.714234 -29.21181) (xy 293.698713 -29.269735)
			(xy 293.675764 -29.325139) (xy 293.64578 -29.377073) (xy 293.609274 -29.424649) (xy 293.566869 -29.467054)
			(xy 293.519293 -29.50356) (xy 293.467359 -29.533544) (xy 293.411955 -29.556493) (xy 293.35403 -29.572014)
			(xy 293.294574 -29.579842) (xy 293.234606 -29.579842) (xy 293.17515 -29.572014) (xy 293.117225 -29.556493)
			(xy 293.061821 -29.533544) (xy 293.009887 -29.50356) (xy 292.962311 -29.467054) (xy 292.919906 -29.424649)
			(xy 292.8834 -29.377073) (xy 292.853416 -29.325139) (xy 292.830467 -29.269735) (xy 292.814946 -29.21181)
			(xy 292.807118 -29.152354) (xy 292.806628 -29.12237) (xy 282.459665 -29.12237) (xy 283.713974 -30.376876)
			(xy 285.088838 -30.376876) (xy 285.089397 -30.34796) (xy 285.098115 -30.29079) (xy 285.115364 -30.235592)
			(xy 285.140748 -30.18363) (xy 285.173686 -30.136095) (xy 285.213421 -30.094077) (xy 285.235904 -30.075886)
			(xy 285.244708 -30.068276) (xy 285.254893 -30.047377) (xy 285.255462 -30.035754) (xy 285.255462 -29.955998)
			(xy 285.254923 -29.944366) (xy 285.244735 -29.923455) (xy 285.235904 -29.915866) (xy 285.213405 -29.897693)
			(xy 285.173671 -29.85567) (xy 285.140733 -29.808131) (xy 285.115348 -29.756166) (xy 285.098095 -29.700965)
			(xy 285.08937 -29.643793) (xy 285.088838 -29.614876) (xy 285.089324 -29.587625) (xy 285.09708 -29.533677)
			(xy 285.112435 -29.481382) (xy 285.135077 -29.431805) (xy 285.164543 -29.385955) (xy 285.200234 -29.344764)
			(xy 285.241425 -29.309073) (xy 285.287275 -29.279607) (xy 285.336852 -29.256965) (xy 285.389147 -29.24161)
			(xy 285.443095 -29.233854) (xy 285.497597 -29.233854) (xy 285.551545 -29.24161) (xy 285.60384 -29.256965)
			(xy 285.653417 -29.279607) (xy 285.699267 -29.309073) (xy 285.740458 -29.344764) (xy 285.776149 -29.385955)
			(xy 285.805615 -29.431805) (xy 285.828257 -29.481382) (xy 285.843612 -29.533677) (xy 285.851368 -29.587625)
			(xy 285.851854 -29.614876) (xy 285.851336 -29.643793) (xy 285.842609 -29.700965) (xy 285.825352 -29.756165)
			(xy 285.799961 -29.808127) (xy 285.767016 -29.855661) (xy 285.727274 -29.897677) (xy 285.704788 -29.915866)
			(xy 285.696004 -29.923496) (xy 285.685808 -29.944379) (xy 285.68523 -29.955998) (xy 285.68523 -30.035754)
			(xy 285.685742 -30.04739) (xy 285.695949 -30.068299) (xy 285.704788 -30.075886) (xy 285.727262 -30.094088)
			(xy 285.766999 -30.136105) (xy 285.799939 -30.183638) (xy 285.825329 -30.235597) (xy 285.842587 -30.290793)
			(xy 285.851318 -30.347961) (xy 285.851854 -30.376876) (xy 288.128964 -30.376876) (xy 288.129513 -30.34796)
			(xy 288.138232 -30.290789) (xy 288.155482 -30.23559) (xy 288.180868 -30.183627) (xy 288.213808 -30.136093)
			(xy 288.253546 -30.094076) (xy 288.27603 -30.075886) (xy 288.284839 -30.06828) (xy 288.29502 -30.047378)
			(xy 288.295588 -30.035754) (xy 288.295588 -29.955998) (xy 288.29504 -29.944367) (xy 288.284858 -29.923457)
			(xy 288.27603 -29.915866) (xy 288.253536 -29.897687) (xy 288.213801 -29.855665) (xy 288.180862 -29.808128)
			(xy 288.155475 -29.756165) (xy 288.138221 -29.700965) (xy 288.129496 -29.643793) (xy 288.128964 -29.614876)
			(xy 288.12945 -29.587625) (xy 288.137206 -29.533677) (xy 288.152561 -29.481382) (xy 288.175203 -29.431805)
			(xy 288.204669 -29.385955) (xy 288.24036 -29.344764) (xy 288.281551 -29.309073) (xy 288.327401 -29.279607)
			(xy 288.376978 -29.256965) (xy 288.429273 -29.24161) (xy 288.483221 -29.233854) (xy 288.537723 -29.233854)
			(xy 288.591671 -29.24161) (xy 288.643966 -29.256965) (xy 288.693543 -29.279607) (xy 288.739393 -29.309073)
			(xy 288.780584 -29.344764) (xy 288.816275 -29.385955) (xy 288.845741 -29.431805) (xy 288.868383 -29.481382)
			(xy 288.883738 -29.533677) (xy 288.891494 -29.587625) (xy 288.89198 -29.614876) (xy 288.891452 -29.643793)
			(xy 288.882726 -29.700964) (xy 288.86547 -29.756163) (xy 288.840081 -29.808125) (xy 288.807139 -29.855659)
			(xy 288.767399 -29.897676) (xy 288.744914 -29.915866) (xy 288.736118 -29.923483) (xy 288.725932 -29.944377)
			(xy 288.725356 -29.955998) (xy 288.725356 -30.035754) (xy 288.725859 -30.047391) (xy 288.736071 -30.068301)
			(xy 288.744914 -30.075886) (xy 288.767394 -30.094081) (xy 288.807128 -30.136101) (xy 288.840068 -30.183635)
			(xy 288.865456 -30.235595) (xy 288.882714 -30.290792) (xy 288.891444 -30.34796) (xy 288.89198 -30.376876)
			(xy 288.891494 -30.404127) (xy 288.883738 -30.458075) (xy 288.868383 -30.51037) (xy 288.845741 -30.559947)
			(xy 288.816275 -30.605797) (xy 288.780584 -30.646988) (xy 288.739393 -30.682679) (xy 288.693543 -30.712145)
			(xy 288.643966 -30.734787) (xy 288.591671 -30.750142) (xy 288.537723 -30.757898) (xy 288.483221 -30.757898)
			(xy 288.429273 -30.750142) (xy 288.376978 -30.734787) (xy 288.327401 -30.712145) (xy 288.281551 -30.682679)
			(xy 288.24036 -30.646988) (xy 288.204669 -30.605797) (xy 288.175203 -30.559947) (xy 288.152561 -30.51037)
			(xy 288.137206 -30.458075) (xy 288.12945 -30.404127) (xy 288.128964 -30.376876) (xy 285.851854 -30.376876)
			(xy 285.851368 -30.404127) (xy 285.843612 -30.458075) (xy 285.828257 -30.51037) (xy 285.805615 -30.559947)
			(xy 285.776149 -30.605797) (xy 285.740458 -30.646988) (xy 285.699267 -30.682679) (xy 285.653417 -30.712145)
			(xy 285.60384 -30.734787) (xy 285.551545 -30.750142) (xy 285.497597 -30.757898) (xy 285.443095 -30.757898)
			(xy 285.389147 -30.750142) (xy 285.336852 -30.734787) (xy 285.287275 -30.712145) (xy 285.241425 -30.682679)
			(xy 285.200234 -30.646988) (xy 285.164543 -30.605797) (xy 285.135077 -30.559947) (xy 285.112435 -30.51037)
			(xy 285.09708 -30.458075) (xy 285.089324 -30.404127) (xy 285.088838 -30.376876) (xy 283.713974 -30.376876)
			(xy 283.95803 -30.62097) (xy 283.98114 -30.644748) (xy 284.022472 -30.696601) (xy 284.057739 -30.752756)
			(xy 284.086498 -30.812506) (xy 284.108386 -30.875099) (xy 284.119188 -30.922468) (xy 290.952428 -30.922468)
			(xy 290.952428 -30.058868) (xy 290.952918 -30.028884) (xy 290.960746 -29.969428) (xy 290.976267 -29.911503)
			(xy 290.999216 -29.856099) (xy 291.0292 -29.804165) (xy 291.065706 -29.756589) (xy 291.108111 -29.714184)
			(xy 291.155687 -29.677678) (xy 291.207621 -29.647694) (xy 291.263025 -29.624745) (xy 291.32095 -29.609224)
			(xy 291.380406 -29.601396) (xy 291.440374 -29.601396) (xy 291.49983 -29.609224) (xy 291.557755 -29.624745)
			(xy 291.613159 -29.647694) (xy 291.665093 -29.677678) (xy 291.712669 -29.714184) (xy 291.755074 -29.756589)
			(xy 291.79158 -29.804165) (xy 291.821564 -29.856099) (xy 291.844513 -29.911503) (xy 291.860034 -29.969428)
			(xy 291.867862 -30.028884) (xy 291.868352 -30.058868) (xy 291.868352 -30.92069) (xy 305.689508 -30.92069)
			(xy 305.689508 -30.05709) (xy 305.689998 -30.027122) (xy 305.697821 -29.9677) (xy 305.713334 -29.909807)
			(xy 305.73627 -29.854434) (xy 305.766237 -29.802528) (xy 305.802724 -29.754978) (xy 305.845104 -29.712598)
			(xy 305.892654 -29.676111) (xy 305.94456 -29.646144) (xy 305.999933 -29.623208) (xy 306.057826 -29.607695)
			(xy 306.117248 -29.599872) (xy 306.177184 -29.599872) (xy 306.236606 -29.607695) (xy 306.294499 -29.623208)
			(xy 306.349872 -29.646144) (xy 306.401778 -29.676111) (xy 306.449328 -29.712598) (xy 306.491708 -29.754978)
			(xy 306.528195 -29.802528) (xy 306.558162 -29.854434) (xy 306.581098 -29.909807) (xy 306.596611 -29.9677)
			(xy 306.604434 -30.027122) (xy 306.604924 -30.05709) (xy 306.604924 -30.92069) (xy 306.604434 -30.950658)
			(xy 306.596611 -31.01008) (xy 306.581098 -31.067973) (xy 306.558162 -31.123346) (xy 306.528195 -31.175252)
			(xy 306.491708 -31.222802) (xy 306.449328 -31.265182) (xy 306.401778 -31.301669) (xy 306.349872 -31.331636)
			(xy 306.294499 -31.354572) (xy 306.236606 -31.370085) (xy 306.177184 -31.377908) (xy 306.117248 -31.377908)
			(xy 306.057826 -31.370085) (xy 305.999933 -31.354572) (xy 305.94456 -31.331636) (xy 305.892654 -31.301669)
			(xy 305.845104 -31.265182) (xy 305.802724 -31.222802) (xy 305.766237 -31.175252) (xy 305.73627 -31.123346)
			(xy 305.713334 -31.067973) (xy 305.697821 -31.01008) (xy 305.689998 -30.950658) (xy 305.689508 -30.92069)
			(xy 291.868352 -30.92069) (xy 291.868352 -30.922468) (xy 291.867862 -30.952452) (xy 291.860034 -31.011908)
			(xy 291.844513 -31.069833) (xy 291.821564 -31.125237) (xy 291.79158 -31.177171) (xy 291.755074 -31.224747)
			(xy 291.712669 -31.267152) (xy 291.665093 -31.303658) (xy 291.613159 -31.333642) (xy 291.557755 -31.356591)
			(xy 291.49983 -31.372112) (xy 291.440374 -31.37994) (xy 291.380406 -31.37994) (xy 291.32095 -31.372112)
			(xy 291.263025 -31.356591) (xy 291.207621 -31.333642) (xy 291.155687 -31.303658) (xy 291.108111 -31.267152)
			(xy 291.065706 -31.224747) (xy 291.0292 -31.177171) (xy 290.999216 -31.125237) (xy 290.976267 -31.069833)
			(xy 290.960746 -31.011908) (xy 290.952918 -30.952452) (xy 290.952428 -30.922468) (xy 284.119188 -30.922468)
			(xy 284.123129 -30.93975) (xy 284.130542 -31.005645) (xy 284.131004 -31.0388) (xy 284.131004 -31.567882)
			(xy 285.198564 -31.567882) (xy 285.202635 -31.51226) (xy 285.214761 -31.457823) (xy 285.234684 -31.405732)
			(xy 285.26198 -31.357097) (xy 285.296066 -31.312954) (xy 285.336215 -31.274245) (xy 285.381573 -31.241794)
			(xy 285.431173 -31.216293) (xy 285.483957 -31.198286) (xy 285.5388 -31.188156) (xy 285.594534 -31.186119)
			(xy 285.649971 -31.192219) (xy 285.703928 -31.206325) (xy 285.755257 -31.228137) (xy 285.802863 -31.257191)
			(xy 285.845731 -31.292866) (xy 285.882948 -31.334403) (xy 285.913721 -31.380916) (xy 285.937393 -31.431413)
			(xy 285.953461 -31.48482) (xy 285.961581 -31.539996) (xy 285.96209 -31.567882) (xy 285.961581 -31.595768)
			(xy 285.953461 -31.650944) (xy 285.937393 -31.704351) (xy 285.930401 -31.719266) (xy 286.485328 -31.719266)
			(xy 286.489399 -31.663644) (xy 286.501525 -31.609207) (xy 286.521448 -31.557116) (xy 286.548744 -31.508481)
			(xy 286.58283 -31.464338) (xy 286.622979 -31.425629) (xy 286.668337 -31.393178) (xy 286.717937 -31.367677)
			(xy 286.770721 -31.34967) (xy 286.825564 -31.33954) (xy 286.881298 -31.337503) (xy 286.936735 -31.343603)
			(xy 286.990692 -31.357709) (xy 287.042021 -31.379521) (xy 287.089627 -31.408575) (xy 287.132495 -31.44425)
			(xy 287.169712 -31.485787) (xy 287.200485 -31.5323) (xy 287.224157 -31.582797) (xy 287.240225 -31.636204)
			(xy 287.244375 -31.664402) (xy 287.760916 -31.664402) (xy 287.764987 -31.60878) (xy 287.777113 -31.554343)
			(xy 287.797036 -31.502252) (xy 287.824332 -31.453617) (xy 287.858418 -31.409474) (xy 287.898567 -31.370765)
			(xy 287.943925 -31.338314) (xy 287.993525 -31.312813) (xy 288.046309 -31.294806) (xy 288.101152 -31.284676)
			(xy 288.156886 -31.282639) (xy 288.212323 -31.288739) (xy 288.26628 -31.302845) (xy 288.317609 -31.324657)
			(xy 288.365215 -31.353711) (xy 288.408083 -31.389386) (xy 288.4453 -31.430923) (xy 288.476073 -31.477436)
			(xy 288.499745 -31.527933) (xy 288.515813 -31.58134) (xy 288.523933 -31.636516) (xy 288.524442 -31.664402)
			(xy 288.523933 -31.692288) (xy 288.515813 -31.747464) (xy 288.506873 -31.777178) (xy 289.02609 -31.777178)
			(xy 289.030161 -31.721556) (xy 289.042287 -31.667119) (xy 289.06221 -31.615028) (xy 289.089506 -31.566393)
			(xy 289.123592 -31.52225) (xy 289.163741 -31.483541) (xy 289.209099 -31.45109) (xy 289.258699 -31.425589)
			(xy 289.311483 -31.407582) (xy 289.366326 -31.397452) (xy 289.42206 -31.395415) (xy 289.477497 -31.401515)
			(xy 289.531454 -31.415621) (xy 289.582783 -31.437433) (xy 289.630389 -31.466487) (xy 289.673257 -31.502162)
			(xy 289.710474 -31.543699) (xy 289.741247 -31.590212) (xy 289.764919 -31.640709) (xy 289.780987 -31.694116)
			(xy 289.789107 -31.749292) (xy 289.789616 -31.777178) (xy 289.789107 -31.805064) (xy 289.780987 -31.86024)
			(xy 289.764919 -31.913647) (xy 289.741247 -31.964144) (xy 289.710474 -32.010657) (xy 289.673257 -32.052194)
			(xy 289.630389 -32.087869) (xy 289.582783 -32.116923) (xy 289.531454 -32.138735) (xy 289.477497 -32.152841)
			(xy 289.42206 -32.158941) (xy 289.366326 -32.156904) (xy 289.311483 -32.146774) (xy 289.258699 -32.128767)
			(xy 289.209099 -32.103266) (xy 289.163741 -32.070815) (xy 289.123592 -32.032106) (xy 289.089506 -31.987963)
			(xy 289.06221 -31.939328) (xy 289.042287 -31.887237) (xy 289.030161 -31.8328) (xy 289.02609 -31.777178)
			(xy 288.506873 -31.777178) (xy 288.499745 -31.800871) (xy 288.476073 -31.851368) (xy 288.4453 -31.897881)
			(xy 288.408083 -31.939418) (xy 288.365215 -31.975093) (xy 288.317609 -32.004147) (xy 288.26628 -32.025959)
			(xy 288.212323 -32.040065) (xy 288.156886 -32.046165) (xy 288.101152 -32.044128) (xy 288.046309 -32.033998)
			(xy 287.993525 -32.015991) (xy 287.943925 -31.99049) (xy 287.898567 -31.958039) (xy 287.858418 -31.91933)
			(xy 287.824332 -31.875187) (xy 287.797036 -31.826552) (xy 287.777113 -31.774461) (xy 287.764987 -31.720024)
			(xy 287.760916 -31.664402) (xy 287.244375 -31.664402) (xy 287.248345 -31.69138) (xy 287.248854 -31.719266)
			(xy 287.248345 -31.747152) (xy 287.240225 -31.802328) (xy 287.224157 -31.855735) (xy 287.200485 -31.906232)
			(xy 287.169712 -31.952745) (xy 287.132495 -31.994282) (xy 287.089627 -32.029957) (xy 287.042021 -32.059011)
			(xy 286.990692 -32.080823) (xy 286.936735 -32.094929) (xy 286.881298 -32.101029) (xy 286.825564 -32.098992)
			(xy 286.770721 -32.088862) (xy 286.717937 -32.070855) (xy 286.668337 -32.045354) (xy 286.622979 -32.012903)
			(xy 286.58283 -31.974194) (xy 286.548744 -31.930051) (xy 286.521448 -31.881416) (xy 286.501525 -31.829325)
			(xy 286.489399 -31.774888) (xy 286.485328 -31.719266) (xy 285.930401 -31.719266) (xy 285.913721 -31.754848)
			(xy 285.882948 -31.801361) (xy 285.845731 -31.842898) (xy 285.802863 -31.878573) (xy 285.755257 -31.907627)
			(xy 285.703928 -31.929439) (xy 285.649971 -31.943545) (xy 285.594534 -31.949645) (xy 285.5388 -31.947608)
			(xy 285.483957 -31.937478) (xy 285.431173 -31.919471) (xy 285.381573 -31.89397) (xy 285.336215 -31.861519)
			(xy 285.296066 -31.82281) (xy 285.26198 -31.778667) (xy 285.234684 -31.730032) (xy 285.214761 -31.677941)
			(xy 285.202635 -31.623504) (xy 285.198564 -31.567882) (xy 284.131004 -31.567882) (xy 284.131004 -32.722312)
			(xy 292.806628 -32.722312) (xy 292.806628 -31.858712) (xy 292.807118 -31.828728) (xy 292.814946 -31.769272)
			(xy 292.830467 -31.711347) (xy 292.853416 -31.655943) (xy 292.8834 -31.604009) (xy 292.919906 -31.556433)
			(xy 292.962311 -31.514028) (xy 293.009887 -31.477522) (xy 293.061821 -31.447538) (xy 293.117225 -31.424589)
			(xy 293.17515 -31.409068) (xy 293.234606 -31.40124) (xy 293.294574 -31.40124) (xy 293.35403 -31.409068)
			(xy 293.411955 -31.424589) (xy 293.467359 -31.447538) (xy 293.519293 -31.477522) (xy 293.566869 -31.514028)
			(xy 293.609274 -31.556433) (xy 293.64578 -31.604009) (xy 293.675764 -31.655943) (xy 293.698713 -31.711347)
			(xy 293.714234 -31.769272) (xy 293.722062 -31.828728) (xy 293.722552 -31.858712) (xy 293.722552 -32.714184)
			(xy 303.0474 -32.714184) (xy 303.0474 -31.850584) (xy 303.04789 -31.820616) (xy 303.055713 -31.761194)
			(xy 303.071226 -31.703301) (xy 303.094162 -31.647928) (xy 303.124129 -31.596022) (xy 303.160616 -31.548472)
			(xy 303.202996 -31.506092) (xy 303.250546 -31.469605) (xy 303.302452 -31.439638) (xy 303.357825 -31.416702)
			(xy 303.415718 -31.401189) (xy 303.47514 -31.393366) (xy 303.535076 -31.393366) (xy 303.594498 -31.401189)
			(xy 303.652391 -31.416702) (xy 303.707764 -31.439638) (xy 303.75967 -31.469605) (xy 303.80722 -31.506092)
			(xy 303.8496 -31.548472) (xy 303.886087 -31.596022) (xy 303.916054 -31.647928) (xy 303.93899 -31.703301)
			(xy 303.954503 -31.761194) (xy 303.962326 -31.820616) (xy 303.962816 -31.850584) (xy 303.962816 -32.714184)
			(xy 303.962326 -32.744152) (xy 303.954503 -32.803574) (xy 303.93899 -32.861467) (xy 303.916054 -32.91684)
			(xy 303.886087 -32.968746) (xy 303.8496 -33.016296) (xy 303.80722 -33.058676) (xy 303.75967 -33.095163)
			(xy 303.707764 -33.12513) (xy 303.652391 -33.148066) (xy 303.594498 -33.163579) (xy 303.535076 -33.171402)
			(xy 303.47514 -33.171402) (xy 303.415718 -33.163579) (xy 303.357825 -33.148066) (xy 303.302452 -33.12513)
			(xy 303.250546 -33.095163) (xy 303.202996 -33.058676) (xy 303.160616 -33.016296) (xy 303.124129 -32.968746)
			(xy 303.094162 -32.91684) (xy 303.071226 -32.861467) (xy 303.055713 -32.803574) (xy 303.04789 -32.744152)
			(xy 303.0474 -32.714184) (xy 293.722552 -32.714184) (xy 293.722552 -32.722312) (xy 293.722062 -32.752296)
			(xy 293.714234 -32.811752) (xy 293.698713 -32.869677) (xy 293.675764 -32.925081) (xy 293.64578 -32.977015)
			(xy 293.609274 -33.024591) (xy 293.566869 -33.066996) (xy 293.519293 -33.103502) (xy 293.467359 -33.133486)
			(xy 293.411955 -33.156435) (xy 293.35403 -33.171956) (xy 293.294574 -33.179784) (xy 293.234606 -33.179784)
			(xy 293.17515 -33.171956) (xy 293.117225 -33.156435) (xy 293.061821 -33.133486) (xy 293.009887 -33.103502)
			(xy 292.962311 -33.066996) (xy 292.919906 -33.024591) (xy 292.8834 -32.977015) (xy 292.853416 -32.925081)
			(xy 292.830467 -32.869677) (xy 292.814946 -32.811752) (xy 292.807118 -32.752296) (xy 292.806628 -32.722312)
			(xy 284.131004 -32.722312) (xy 284.131004 -33.40862) (xy 284.13583 -33.414208) (xy 285.244032 -34.52241)
			(xy 290.952428 -34.52241) (xy 290.952428 -33.65881) (xy 290.952918 -33.628826) (xy 290.960746 -33.56937)
			(xy 290.976267 -33.511445) (xy 290.999216 -33.456041) (xy 291.0292 -33.404107) (xy 291.065706 -33.356531)
			(xy 291.108111 -33.314126) (xy 291.155687 -33.27762) (xy 291.207621 -33.247636) (xy 291.263025 -33.224687)
			(xy 291.32095 -33.209166) (xy 291.380406 -33.201338) (xy 291.440374 -33.201338) (xy 291.49983 -33.209166)
			(xy 291.557755 -33.224687) (xy 291.613159 -33.247636) (xy 291.665093 -33.27762) (xy 291.712669 -33.314126)
			(xy 291.755074 -33.356531) (xy 291.79158 -33.404107) (xy 291.821564 -33.456041) (xy 291.844513 -33.511445)
			(xy 291.860034 -33.56937) (xy 291.867862 -33.628826) (xy 291.868352 -33.65881) (xy 291.868352 -34.520886)
			(xy 305.689508 -34.520886) (xy 305.689508 -33.657286) (xy 305.689998 -33.627318) (xy 305.697821 -33.567896)
			(xy 305.713334 -33.510003) (xy 305.73627 -33.45463) (xy 305.766237 -33.402724) (xy 305.802724 -33.355174)
			(xy 305.845104 -33.312794) (xy 305.892654 -33.276307) (xy 305.94456 -33.24634) (xy 305.999933 -33.223404)
			(xy 306.057826 -33.207891) (xy 306.117248 -33.200068) (xy 306.177184 -33.200068) (xy 306.236606 -33.207891)
			(xy 306.294499 -33.223404) (xy 306.349872 -33.24634) (xy 306.401778 -33.276307) (xy 306.449328 -33.312794)
			(xy 306.491708 -33.355174) (xy 306.528195 -33.402724) (xy 306.558162 -33.45463) (xy 306.581098 -33.510003)
			(xy 306.596611 -33.567896) (xy 306.604434 -33.627318) (xy 306.604924 -33.657286) (xy 306.604924 -34.520886)
			(xy 306.604434 -34.550854) (xy 306.596611 -34.610276) (xy 306.581098 -34.668169) (xy 306.558162 -34.723542)
			(xy 306.528195 -34.775448) (xy 306.491708 -34.822998) (xy 306.449328 -34.865378) (xy 306.401778 -34.901865)
			(xy 306.349872 -34.931832) (xy 306.294499 -34.954768) (xy 306.236606 -34.970281) (xy 306.177184 -34.978104)
			(xy 306.117248 -34.978104) (xy 306.057826 -34.970281) (xy 305.999933 -34.954768) (xy 305.94456 -34.931832)
			(xy 305.892654 -34.901865) (xy 305.845104 -34.865378) (xy 305.802724 -34.822998) (xy 305.766237 -34.775448)
			(xy 305.73627 -34.723542) (xy 305.713334 -34.668169) (xy 305.697821 -34.610276) (xy 305.689998 -34.550854)
			(xy 305.689508 -34.520886) (xy 291.868352 -34.520886) (xy 291.868352 -34.52241) (xy 291.867862 -34.552394)
			(xy 291.860034 -34.61185) (xy 291.844513 -34.669775) (xy 291.821564 -34.725179) (xy 291.79158 -34.777113)
			(xy 291.755074 -34.824689) (xy 291.712669 -34.867094) (xy 291.665093 -34.9036) (xy 291.613159 -34.933584)
			(xy 291.557755 -34.956533) (xy 291.49983 -34.972054) (xy 291.440374 -34.979882) (xy 291.380406 -34.979882)
			(xy 291.32095 -34.972054) (xy 291.263025 -34.956533) (xy 291.207621 -34.933584) (xy 291.155687 -34.9036)
			(xy 291.108111 -34.867094) (xy 291.065706 -34.824689) (xy 291.0292 -34.777113) (xy 290.999216 -34.725179)
			(xy 290.976267 -34.669775) (xy 290.960746 -34.61185) (xy 290.952918 -34.552394) (xy 290.952428 -34.52241)
			(xy 285.244032 -34.52241) (xy 285.986474 -35.264852) (xy 288.102292 -35.264852) (xy 288.106363 -35.20923)
			(xy 288.118489 -35.154793) (xy 288.138412 -35.102702) (xy 288.165708 -35.054067) (xy 288.199794 -35.009924)
			(xy 288.239943 -34.971215) (xy 288.285301 -34.938764) (xy 288.334901 -34.913263) (xy 288.387685 -34.895256)
			(xy 288.442528 -34.885126) (xy 288.498262 -34.883089) (xy 288.553699 -34.889189) (xy 288.607656 -34.903295)
			(xy 288.658985 -34.925107) (xy 288.706591 -34.954161) (xy 288.749459 -34.989836) (xy 288.786676 -35.031373)
			(xy 288.817449 -35.077886) (xy 288.841121 -35.128383) (xy 288.857189 -35.18179) (xy 288.865309 -35.236966)
			(xy 288.865818 -35.264852) (xy 288.865309 -35.292738) (xy 288.857189 -35.347914) (xy 288.841121 -35.401321)
			(xy 288.817449 -35.451818) (xy 288.786676 -35.498331) (xy 288.749459 -35.539868) (xy 288.706591 -35.575543)
			(xy 288.658985 -35.604597) (xy 288.607656 -35.626409) (xy 288.553699 -35.640515) (xy 288.498262 -35.646615)
			(xy 288.442528 -35.644578) (xy 288.387685 -35.634448) (xy 288.334901 -35.616441) (xy 288.285301 -35.59094)
			(xy 288.239943 -35.558489) (xy 288.199794 -35.51978) (xy 288.165708 -35.475637) (xy 288.138412 -35.427002)
			(xy 288.118489 -35.374911) (xy 288.106363 -35.320474) (xy 288.102292 -35.264852) (xy 285.986474 -35.264852)
			(xy 287.00857 -36.286948) (xy 289.400232 -36.286948) (xy 289.404303 -36.231326) (xy 289.416429 -36.176889)
			(xy 289.436352 -36.124798) (xy 289.463648 -36.076163) (xy 289.497734 -36.03202) (xy 289.537883 -35.993311)
			(xy 289.583241 -35.96086) (xy 289.632841 -35.935359) (xy 289.685625 -35.917352) (xy 289.740468 -35.907222)
			(xy 289.796202 -35.905185) (xy 289.851639 -35.911285) (xy 289.905596 -35.925391) (xy 289.956925 -35.947203)
			(xy 290.004531 -35.976257) (xy 290.047399 -36.011932) (xy 290.084616 -36.053469) (xy 290.115389 -36.099982)
			(xy 290.139061 -36.150479) (xy 290.155129 -36.203886) (xy 290.163249 -36.259062) (xy 290.163758 -36.286948)
			(xy 290.163249 -36.314834) (xy 290.155129 -36.37001) (xy 290.139061 -36.423417) (xy 290.115389 -36.473914)
			(xy 290.087844 -36.515548) (xy 291.214046 -36.515548) (xy 291.218117 -36.459926) (xy 291.230243 -36.405489)
			(xy 291.250166 -36.353398) (xy 291.277462 -36.304763) (xy 291.311548 -36.26062) (xy 291.351697 -36.221911)
			(xy 291.397055 -36.18946) (xy 291.446655 -36.163959) (xy 291.499439 -36.145952) (xy 291.554282 -36.135822)
			(xy 291.610016 -36.133785) (xy 291.665453 -36.139885) (xy 291.71941 -36.153991) (xy 291.770739 -36.175803)
			(xy 291.818345 -36.204857) (xy 291.861213 -36.240532) (xy 291.89843 -36.282069) (xy 291.929203 -36.328582)
			(xy 291.952875 -36.379079) (xy 291.968943 -36.432486) (xy 291.977063 -36.487662) (xy 291.977572 -36.515548)
			(xy 291.977063 -36.543434) (xy 291.968943 -36.59861) (xy 291.968486 -36.60013) (xy 296.198551 -36.60013)
			(xy 296.202555 -36.512245) (xy 296.214535 -36.425088) (xy 296.23439 -36.339381) (xy 296.261957 -36.255836)
			(xy 296.297007 -36.175143) (xy 296.339249 -36.097971) (xy 296.388334 -36.024961) (xy 296.443855 -35.956717)
			(xy 296.505352 -35.893804) (xy 296.572314 -35.836744) (xy 296.644188 -35.78601) (xy 296.720378 -35.742022)
			(xy 296.800252 -35.705144) (xy 296.883149 -35.675683) (xy 296.968381 -35.653881) (xy 297.055243 -35.639921)
			(xy 297.143014 -35.633917) (xy 297.230968 -35.63592) (xy 297.318375 -35.645912) (xy 297.404511 -35.663812)
			(xy 297.488663 -35.68947) (xy 297.570133 -35.722674) (xy 297.648246 -35.763148) (xy 297.722354 -35.810559)
			(xy 297.791845 -35.864512) (xy 297.804936 -35.876738) (xy 302.917096 -35.876738) (xy 302.921167 -35.821116)
			(xy 302.933293 -35.766679) (xy 302.953216 -35.714588) (xy 302.980512 -35.665953) (xy 303.014598 -35.62181)
			(xy 303.054747 -35.583101) (xy 303.100105 -35.55065) (xy 303.149705 -35.525149) (xy 303.202489 -35.507142)
			(xy 303.257332 -35.497012) (xy 303.313066 -35.494975) (xy 303.368503 -35.501075) (xy 303.42246 -35.515181)
			(xy 303.473789 -35.536993) (xy 303.521395 -35.566047) (xy 303.564263 -35.601722) (xy 303.60148 -35.643259)
			(xy 303.632253 -35.689772) (xy 303.655925 -35.740269) (xy 303.671993 -35.793676) (xy 303.680113 -35.848852)
			(xy 303.680622 -35.876738) (xy 306.988716 -35.876738) (xy 306.992787 -35.821116) (xy 307.004913 -35.766679)
			(xy 307.024836 -35.714588) (xy 307.052132 -35.665953) (xy 307.086218 -35.62181) (xy 307.126367 -35.583101)
			(xy 307.171725 -35.55065) (xy 307.221325 -35.525149) (xy 307.274109 -35.507142) (xy 307.328952 -35.497012)
			(xy 307.384686 -35.494975) (xy 307.440123 -35.501075) (xy 307.49408 -35.515181) (xy 307.545409 -35.536993)
			(xy 307.593015 -35.566047) (xy 307.635883 -35.601722) (xy 307.6731 -35.643259) (xy 307.703873 -35.689772)
			(xy 307.727545 -35.740269) (xy 307.743613 -35.793676) (xy 307.751733 -35.848852) (xy 307.752242 -35.876738)
			(xy 307.751733 -35.904624) (xy 307.743613 -35.9598) (xy 307.727545 -36.013207) (xy 307.703873 -36.063704)
			(xy 307.6731 -36.110217) (xy 307.635883 -36.151754) (xy 307.593015 -36.187429) (xy 307.545409 -36.216483)
			(xy 307.49408 -36.238295) (xy 307.440123 -36.252401) (xy 307.384686 -36.258501) (xy 307.328952 -36.256464)
			(xy 307.274109 -36.246334) (xy 307.221325 -36.228327) (xy 307.171725 -36.202826) (xy 307.126367 -36.170375)
			(xy 307.086218 -36.131666) (xy 307.052132 -36.087523) (xy 307.024836 -36.038888) (xy 307.004913 -35.986797)
			(xy 306.992787 -35.93236) (xy 306.988716 -35.876738) (xy 303.680622 -35.876738) (xy 303.680113 -35.904624)
			(xy 303.671993 -35.9598) (xy 303.655925 -36.013207) (xy 303.632253 -36.063704) (xy 303.60148 -36.110217)
			(xy 303.564263 -36.151754) (xy 303.521395 -36.187429) (xy 303.473789 -36.216483) (xy 303.42246 -36.238295)
			(xy 303.368503 -36.252401) (xy 303.313066 -36.258501) (xy 303.257332 -36.256464) (xy 303.202489 -36.246334)
			(xy 303.149705 -36.228327) (xy 303.100105 -36.202826) (xy 303.054747 -36.170375) (xy 303.014598 -36.131666)
			(xy 302.980512 -36.087523) (xy 302.953216 -36.038888) (xy 302.933293 -35.986797) (xy 302.921167 -35.93236)
			(xy 302.917096 -35.876738) (xy 297.804936 -35.876738) (xy 297.856141 -35.92456) (xy 297.91471 -35.990207)
			(xy 297.967067 -36.060907) (xy 298.012779 -36.136076) (xy 298.051465 -36.21509) (xy 298.082806 -36.297295)
			(xy 298.106541 -36.382009) (xy 298.122475 -36.46853) (xy 298.126258 -36.50996) (xy 304.813714 -36.50996)
			(xy 304.817785 -36.454338) (xy 304.829911 -36.399901) (xy 304.849834 -36.34781) (xy 304.87713 -36.299175)
			(xy 304.911216 -36.255032) (xy 304.951365 -36.216323) (xy 304.996723 -36.183872) (xy 305.046323 -36.158371)
			(xy 305.099107 -36.140364) (xy 305.15395 -36.130234) (xy 305.209684 -36.128197) (xy 305.265121 -36.134297)
			(xy 305.319078 -36.148403) (xy 305.370407 -36.170215) (xy 305.418013 -36.199269) (xy 305.460881 -36.234944)
			(xy 305.498098 -36.276481) (xy 305.528871 -36.322994) (xy 305.552543 -36.373491) (xy 305.568611 -36.426898)
			(xy 305.576731 -36.482074) (xy 305.57724 -36.50996) (xy 305.576731 -36.537846) (xy 305.568611 -36.593022)
			(xy 305.552543 -36.646429) (xy 305.528871 -36.696926) (xy 305.498098 -36.743439) (xy 305.460881 -36.784976)
			(xy 305.418013 -36.820651) (xy 305.370407 -36.849705) (xy 305.319078 -36.871517) (xy 305.265121 -36.885623)
			(xy 305.209684 -36.891723) (xy 305.15395 -36.889686) (xy 305.099107 -36.879556) (xy 305.046323 -36.861549)
			(xy 304.996723 -36.836048) (xy 304.951365 -36.803597) (xy 304.911216 -36.764888) (xy 304.87713 -36.720745)
			(xy 304.849834 -36.67211) (xy 304.829911 -36.620019) (xy 304.817785 -36.565582) (xy 304.813714 -36.50996)
			(xy 298.126258 -36.50996) (xy 298.130475 -36.556142) (xy 298.130976 -36.60013) (xy 298.130475 -36.644118)
			(xy 298.122475 -36.73173) (xy 298.106541 -36.818251) (xy 298.082806 -36.902965) (xy 298.051465 -36.98517)
			(xy 298.012779 -37.064184) (xy 297.967067 -37.139353) (xy 297.91471 -37.210053) (xy 297.856141 -37.2757)
			(xy 297.791845 -37.335748) (xy 297.722354 -37.389701) (xy 297.648246 -37.437112) (xy 297.574815 -37.47516)
			(xy 301.959008 -37.47516) (xy 301.963079 -37.419538) (xy 301.975205 -37.365101) (xy 301.995128 -37.31301)
			(xy 302.022424 -37.264375) (xy 302.05651 -37.220232) (xy 302.096659 -37.181523) (xy 302.142017 -37.149072)
			(xy 302.191617 -37.123571) (xy 302.244401 -37.105564) (xy 302.299244 -37.095434) (xy 302.354978 -37.093397)
			(xy 302.410415 -37.099497) (xy 302.464372 -37.113603) (xy 302.515701 -37.135415) (xy 302.563307 -37.164469)
			(xy 302.606175 -37.200144) (xy 302.643392 -37.241681) (xy 302.674165 -37.288194) (xy 302.697837 -37.338691)
			(xy 302.713905 -37.392098) (xy 302.722025 -37.447274) (xy 302.722534 -37.47516) (xy 302.722025 -37.503046)
			(xy 302.713905 -37.558222) (xy 302.697837 -37.611629) (xy 302.674165 -37.662126) (xy 302.674012 -37.662358)
			(xy 304.148234 -37.662358) (xy 304.152305 -37.606736) (xy 304.164431 -37.552299) (xy 304.184354 -37.500208)
			(xy 304.21165 -37.451573) (xy 304.245736 -37.40743) (xy 304.285885 -37.368721) (xy 304.331243 -37.33627)
			(xy 304.380843 -37.310769) (xy 304.433627 -37.292762) (xy 304.48847 -37.282632) (xy 304.544204 -37.280595)
			(xy 304.599641 -37.286695) (xy 304.653598 -37.300801) (xy 304.704927 -37.322613) (xy 304.752533 -37.351667)
			(xy 304.795401 -37.387342) (xy 304.832618 -37.428879) (xy 304.863391 -37.475392) (xy 304.887063 -37.525889)
			(xy 304.903131 -37.579296) (xy 304.911251 -37.634472) (xy 304.91176 -37.662358) (xy 304.911251 -37.690244)
			(xy 304.903131 -37.74542) (xy 304.887063 -37.798827) (xy 304.863391 -37.849324) (xy 304.832618 -37.895837)
			(xy 304.795401 -37.937374) (xy 304.752533 -37.973049) (xy 304.704927 -38.002103) (xy 304.653598 -38.023915)
			(xy 304.599641 -38.038021) (xy 304.544204 -38.044121) (xy 304.48847 -38.042084) (xy 304.433627 -38.031954)
			(xy 304.380843 -38.013947) (xy 304.331243 -37.988446) (xy 304.285885 -37.955995) (xy 304.245736 -37.917286)
			(xy 304.21165 -37.873143) (xy 304.184354 -37.824508) (xy 304.164431 -37.772417) (xy 304.152305 -37.71798)
			(xy 304.148234 -37.662358) (xy 302.674012 -37.662358) (xy 302.643392 -37.708639) (xy 302.606175 -37.750176)
			(xy 302.563307 -37.785851) (xy 302.515701 -37.814905) (xy 302.464372 -37.836717) (xy 302.410415 -37.850823)
			(xy 302.354978 -37.856923) (xy 302.299244 -37.854886) (xy 302.244401 -37.844756) (xy 302.191617 -37.826749)
			(xy 302.142017 -37.801248) (xy 302.096659 -37.768797) (xy 302.05651 -37.730088) (xy 302.022424 -37.685945)
			(xy 301.995128 -37.63731) (xy 301.975205 -37.585219) (xy 301.963079 -37.530782) (xy 301.959008 -37.47516)
			(xy 297.574815 -37.47516) (xy 297.570133 -37.477586) (xy 297.488663 -37.51079) (xy 297.404511 -37.536448)
			(xy 297.318375 -37.554348) (xy 297.230968 -37.56434) (xy 297.143014 -37.566343) (xy 297.055243 -37.560339)
			(xy 296.968381 -37.546379) (xy 296.883149 -37.524577) (xy 296.800252 -37.495116) (xy 296.720378 -37.458238)
			(xy 296.644188 -37.41425) (xy 296.572314 -37.363516) (xy 296.505352 -37.306456) (xy 296.443855 -37.243543)
			(xy 296.388334 -37.175299) (xy 296.339249 -37.102289) (xy 296.297007 -37.025117) (xy 296.261957 -36.944424)
			(xy 296.23439 -36.860879) (xy 296.214535 -36.775172) (xy 296.202555 -36.688015) (xy 296.198551 -36.60013)
			(xy 291.968486 -36.60013) (xy 291.952875 -36.652017) (xy 291.929203 -36.702514) (xy 291.89843 -36.749027)
			(xy 291.861213 -36.790564) (xy 291.818345 -36.826239) (xy 291.770739 -36.855293) (xy 291.71941 -36.877105)
			(xy 291.665453 -36.891211) (xy 291.610016 -36.897311) (xy 291.554282 -36.895274) (xy 291.499439 -36.885144)
			(xy 291.446655 -36.867137) (xy 291.397055 -36.841636) (xy 291.351697 -36.809185) (xy 291.311548 -36.770476)
			(xy 291.277462 -36.726333) (xy 291.250166 -36.677698) (xy 291.230243 -36.625607) (xy 291.218117 -36.57117)
			(xy 291.214046 -36.515548) (xy 290.087844 -36.515548) (xy 290.084616 -36.520427) (xy 290.047399 -36.561964)
			(xy 290.004531 -36.597639) (xy 289.956925 -36.626693) (xy 289.905596 -36.648505) (xy 289.851639 -36.662611)
			(xy 289.796202 -36.668711) (xy 289.740468 -36.666674) (xy 289.685625 -36.656544) (xy 289.632841 -36.638537)
			(xy 289.583241 -36.613036) (xy 289.537883 -36.580585) (xy 289.497734 -36.541876) (xy 289.463648 -36.497733)
			(xy 289.436352 -36.449098) (xy 289.416429 -36.397007) (xy 289.404303 -36.34257) (xy 289.400232 -36.286948)
			(xy 287.00857 -36.286948) (xy 288.49574 -37.774118) (xy 289.664646 -37.774118) (xy 289.668717 -37.718496)
			(xy 289.680843 -37.664059) (xy 289.700766 -37.611968) (xy 289.728062 -37.563333) (xy 289.762148 -37.51919)
			(xy 289.802297 -37.480481) (xy 289.847655 -37.44803) (xy 289.897255 -37.422529) (xy 289.950039 -37.404522)
			(xy 290.004882 -37.394392) (xy 290.060616 -37.392355) (xy 290.116053 -37.398455) (xy 290.17001 -37.412561)
			(xy 290.221339 -37.434373) (xy 290.268945 -37.463427) (xy 290.311813 -37.499102) (xy 290.34903 -37.540639)
			(xy 290.379803 -37.587152) (xy 290.403475 -37.637649) (xy 290.419543 -37.691056) (xy 290.427663 -37.746232)
			(xy 290.428172 -37.774118) (xy 290.427663 -37.802004) (xy 290.419543 -37.85718) (xy 290.403475 -37.910587)
			(xy 290.379803 -37.961084) (xy 290.34903 -38.007597) (xy 290.311813 -38.049134) (xy 290.268945 -38.084809)
			(xy 290.221339 -38.113863) (xy 290.17001 -38.135675) (xy 290.116053 -38.149781) (xy 290.060616 -38.155881)
			(xy 290.004882 -38.153844) (xy 289.950039 -38.143714) (xy 289.897255 -38.125707) (xy 289.847655 -38.100206)
			(xy 289.802297 -38.067755) (xy 289.762148 -38.029046) (xy 289.728062 -37.984903) (xy 289.700766 -37.936268)
			(xy 289.680843 -37.884177) (xy 289.668717 -37.82974) (xy 289.664646 -37.774118) (xy 288.49574 -37.774118)
			(xy 291.990373 -41.268751) (xy 300.04385 -41.268751) (xy 300.04385 -41.214249) (xy 300.051605 -41.160302)
			(xy 300.066959 -41.108007) (xy 300.089598 -41.05843) (xy 300.119062 -41.012578) (xy 300.154751 -40.971386)
			(xy 300.195938 -40.935692) (xy 300.241786 -40.906222) (xy 300.29136 -40.883577) (xy 300.343653 -40.868216)
			(xy 300.397599 -40.860453) (xy 300.42485 -40.859964) (xy 300.45359 -40.860467) (xy 300.510417 -40.869096)
			(xy 300.565308 -40.886152) (xy 300.617019 -40.911247) (xy 300.664381 -40.943816) (xy 300.685708 -40.963088)
			(xy 300.692566 -40.969692) (xy 300.7106 -40.976804) (xy 300.7995 -40.976804) (xy 300.817534 -40.969692)
			(xy 300.824392 -40.963088) (xy 300.845706 -40.943802) (xy 300.893071 -40.911236) (xy 300.944785 -40.886145)
			(xy 300.999679 -40.869099) (xy 301.05651 -40.860481) (xy 301.08525 -40.859964) (xy 301.112503 -40.86048)
			(xy 301.166456 -40.86823) (xy 301.218756 -40.883581) (xy 301.268338 -40.906219) (xy 301.314194 -40.935684)
			(xy 301.35539 -40.971375) (xy 301.391086 -41.012566) (xy 301.420557 -41.058418) (xy 301.443201 -41.107998)
			(xy 301.458559 -41.160296) (xy 301.466317 -41.214247) (xy 301.466317 -41.268753) (xy 301.458559 -41.322704)
			(xy 301.443201 -41.375002) (xy 301.420557 -41.424582) (xy 301.391086 -41.470434) (xy 301.35539 -41.511625)
			(xy 301.314194 -41.547316) (xy 301.268338 -41.576781) (xy 301.218756 -41.599419) (xy 301.166456 -41.61477)
			(xy 301.112503 -41.62252) (xy 301.08525 -41.62298) (xy 301.056511 -41.622465) (xy 300.999684 -41.613837)
			(xy 300.944794 -41.596784) (xy 300.893083 -41.571691) (xy 300.84572 -41.539126) (xy 300.824392 -41.519856)
			(xy 300.817534 -41.513252) (xy 300.7995 -41.50614) (xy 300.7106 -41.50614) (xy 300.692566 -41.513252)
			(xy 300.685708 -41.519856) (xy 300.664401 -41.539149) (xy 300.617033 -41.571713) (xy 300.565317 -41.596801)
			(xy 300.510422 -41.613846) (xy 300.45359 -41.622463) (xy 300.42485 -41.62298) (xy 300.397599 -41.622547)
			(xy 300.343653 -41.614784) (xy 300.29136 -41.599423) (xy 300.241786 -41.576778) (xy 300.195938 -41.547308)
			(xy 300.154751 -41.511614) (xy 300.119062 -41.470422) (xy 300.089598 -41.42457) (xy 300.066959 -41.374993)
			(xy 300.051605 -41.322698) (xy 300.04385 -41.268751) (xy 291.990373 -41.268751) (xy 294.026844 -43.305222)
			(xy 302.507142 -43.305222) (xy 302.507611 -43.277852) (xy 302.515426 -43.223672) (xy 302.530914 -43.171169)
			(xy 302.553756 -43.121422) (xy 302.58348 -43.075455) (xy 302.601122 -43.054524) (xy 302.601376 -43.05427)
			(xy 302.606948 -43.047174) (xy 302.613202 -43.030264) (xy 302.613568 -43.02125) (xy 302.613568 -42.954194)
			(xy 302.613221 -42.945176) (xy 302.606967 -42.928259) (xy 302.601376 -42.921174) (xy 302.601122 -42.921174)
			(xy 302.601122 -42.92092) (xy 302.583482 -42.899988) (xy 302.55377 -42.854016) (xy 302.530934 -42.804268)
			(xy 302.515443 -42.751767) (xy 302.507615 -42.697591) (xy 302.507142 -42.670222) (xy 302.507695 -42.641484)
			(xy 302.516313 -42.584659) (xy 302.533357 -42.529769) (xy 302.558441 -42.478057) (xy 302.590999 -42.430693)
			(xy 302.610266 -42.409364) (xy 302.61687 -42.402506) (xy 302.623982 -42.384472) (xy 302.623982 -42.295572)
			(xy 302.61687 -42.277538) (xy 302.610266 -42.27068) (xy 302.59102 -42.249333) (xy 302.558458 -42.201972)
			(xy 302.53337 -42.150263) (xy 302.516321 -42.095376) (xy 302.507697 -42.038553) (xy 302.507695 -41.981079)
			(xy 302.516313 -41.924255) (xy 302.533358 -41.869366) (xy 302.558442 -41.817655) (xy 302.590999 -41.770292)
			(xy 302.610266 -41.748964) (xy 302.61687 -41.742106) (xy 302.623982 -41.724072) (xy 302.623982 -41.635172)
			(xy 302.61687 -41.617138) (xy 302.610266 -41.61028) (xy 302.59101 -41.58894) (xy 302.558441 -41.541582)
			(xy 302.533345 -41.489874) (xy 302.516291 -41.434986) (xy 302.507665 -41.37816) (xy 302.507142 -41.349422)
			(xy 302.507628 -41.322171) (xy 302.515384 -41.268223) (xy 302.530739 -41.215928) (xy 302.553381 -41.166351)
			(xy 302.582847 -41.120501) (xy 302.618538 -41.07931) (xy 302.659729 -41.043619) (xy 302.705579 -41.014153)
			(xy 302.755156 -40.991511) (xy 302.807451 -40.976156) (xy 302.861399 -40.9684) (xy 302.915901 -40.9684)
			(xy 302.969849 -40.976156) (xy 303.022144 -40.991511) (xy 303.071721 -41.014153) (xy 303.117571 -41.043619)
			(xy 303.158762 -41.07931) (xy 303.194453 -41.120501) (xy 303.223919 -41.166351) (xy 303.246561 -41.215928)
			(xy 303.261916 -41.268223) (xy 303.269672 -41.322171) (xy 303.270158 -41.349422) (xy 303.269632 -41.378161)
			(xy 303.261008 -41.434987) (xy 303.243957 -41.489877) (xy 303.218867 -41.541589) (xy 303.186303 -41.588952)
			(xy 303.167034 -41.61028) (xy 303.16043 -41.617138) (xy 303.153318 -41.635172) (xy 303.153318 -41.724072)
			(xy 303.16043 -41.742106) (xy 303.167034 -41.748964) (xy 303.186324 -41.770273) (xy 303.218884 -41.81764)
			(xy 303.24397 -41.869355) (xy 303.261016 -41.924248) (xy 303.269635 -41.981077) (xy 303.269633 -42.038555)
			(xy 303.261009 -42.095383) (xy 303.243958 -42.150275) (xy 303.218868 -42.201987) (xy 303.186304 -42.249352)
			(xy 303.167034 -42.27068) (xy 303.16043 -42.277538) (xy 303.153318 -42.295572) (xy 303.153318 -42.384472)
			(xy 303.16043 -42.402506) (xy 303.167034 -42.409364) (xy 303.186311 -42.430686) (xy 303.218877 -42.478049)
			(xy 303.243969 -42.529762) (xy 303.261018 -42.584654) (xy 303.269639 -42.641483) (xy 303.270158 -42.670222)
			(xy 303.269715 -42.697593) (xy 303.261893 -42.751774) (xy 303.246399 -42.804277) (xy 303.225842 -42.849038)
			(xy 305.091844 -42.849038) (xy 305.095915 -42.793416) (xy 305.108041 -42.738979) (xy 305.127964 -42.686888)
			(xy 305.15526 -42.638253) (xy 305.189346 -42.59411) (xy 305.229495 -42.555401) (xy 305.274853 -42.52295)
			(xy 305.324453 -42.497449) (xy 305.377237 -42.479442) (xy 305.43208 -42.469312) (xy 305.487814 -42.467275)
			(xy 305.543251 -42.473375) (xy 305.597208 -42.487481) (xy 305.648537 -42.509293) (xy 305.696143 -42.538347)
			(xy 305.739011 -42.574022) (xy 305.776228 -42.615559) (xy 305.807001 -42.662072) (xy 305.830673 -42.712569)
			(xy 305.846741 -42.765976) (xy 305.854861 -42.821152) (xy 305.855222 -42.84091) (xy 311.13298 -42.84091)
			(xy 311.137051 -42.785288) (xy 311.149177 -42.730851) (xy 311.1691 -42.67876) (xy 311.196396 -42.630125)
			(xy 311.230482 -42.585982) (xy 311.270631 -42.547273) (xy 311.315989 -42.514822) (xy 311.365589 -42.489321)
			(xy 311.418373 -42.471314) (xy 311.473216 -42.461184) (xy 311.52895 -42.459147) (xy 311.584387 -42.465247)
			(xy 311.638344 -42.479353) (xy 311.689673 -42.501165) (xy 311.737279 -42.530219) (xy 311.780147 -42.565894)
			(xy 311.817364 -42.607431) (xy 311.848137 -42.653944) (xy 311.871809 -42.704441) (xy 311.887877 -42.757848)
			(xy 311.895997 -42.813024) (xy 311.896506 -42.84091) (xy 311.895997 -42.868796) (xy 311.887877 -42.923972)
			(xy 311.871809 -42.977379) (xy 311.848137 -43.027876) (xy 311.817364 -43.074389) (xy 311.780147 -43.115926)
			(xy 311.737279 -43.151601) (xy 311.689673 -43.180655) (xy 311.638344 -43.202467) (xy 311.584387 -43.216573)
			(xy 311.52895 -43.222673) (xy 311.473216 -43.220636) (xy 311.418373 -43.210506) (xy 311.365589 -43.192499)
			(xy 311.315989 -43.166998) (xy 311.270631 -43.134547) (xy 311.230482 -43.095838) (xy 311.196396 -43.051695)
			(xy 311.1691 -43.00306) (xy 311.149177 -42.950969) (xy 311.137051 -42.896532) (xy 311.13298 -42.84091)
			(xy 305.855222 -42.84091) (xy 305.85537 -42.849038) (xy 305.854861 -42.876924) (xy 305.846741 -42.9321)
			(xy 305.830673 -42.985507) (xy 305.807001 -43.036004) (xy 305.776228 -43.082517) (xy 305.739011 -43.124054)
			(xy 305.696143 -43.159729) (xy 305.648537 -43.188783) (xy 305.597208 -43.210595) (xy 305.543251 -43.224701)
			(xy 305.487814 -43.230801) (xy 305.43208 -43.228764) (xy 305.377237 -43.218634) (xy 305.324453 -43.200627)
			(xy 305.274853 -43.175126) (xy 305.229495 -43.142675) (xy 305.189346 -43.103966) (xy 305.15526 -43.059823)
			(xy 305.127964 -43.011188) (xy 305.108041 -42.959097) (xy 305.095915 -42.90466) (xy 305.091844 -42.849038)
			(xy 303.225842 -42.849038) (xy 303.223552 -42.854024) (xy 303.193822 -42.899989) (xy 303.176178 -42.92092)
			(xy 303.175924 -42.921174) (xy 303.170333 -42.928257) (xy 303.164091 -42.945177) (xy 303.163732 -42.954194)
			(xy 303.163732 -43.02125) (xy 303.164106 -43.030265) (xy 303.170341 -43.047183) (xy 303.175924 -43.05427)
			(xy 303.176178 -43.05427) (xy 303.176178 -43.054524) (xy 303.193792 -43.075477) (xy 303.223508 -43.121444)
			(xy 303.246349 -43.171186) (xy 303.261846 -43.223682) (xy 303.269681 -43.277854) (xy 303.270158 -43.305222)
			(xy 303.269672 -43.332473) (xy 303.261916 -43.386421) (xy 303.246561 -43.438716) (xy 303.223919 -43.488293)
			(xy 303.194453 -43.534143) (xy 303.158762 -43.575334) (xy 303.117571 -43.611025) (xy 303.071721 -43.640491)
			(xy 303.022144 -43.663133) (xy 302.969849 -43.678488) (xy 302.915901 -43.686244) (xy 302.861399 -43.686244)
			(xy 302.807451 -43.678488) (xy 302.755156 -43.663133) (xy 302.705579 -43.640491) (xy 302.659729 -43.611025)
			(xy 302.618538 -43.575334) (xy 302.582847 -43.534143) (xy 302.553381 -43.488293) (xy 302.530739 -43.438716)
			(xy 302.515384 -43.386421) (xy 302.507628 -43.332473) (xy 302.507142 -43.305222) (xy 294.026844 -43.305222)
			(xy 294.457882 -43.73626) (xy 304.412902 -43.73626) (xy 304.416973 -43.680638) (xy 304.429099 -43.626201)
			(xy 304.449022 -43.57411) (xy 304.476318 -43.525475) (xy 304.510404 -43.481332) (xy 304.550553 -43.442623)
			(xy 304.595911 -43.410172) (xy 304.645511 -43.384671) (xy 304.698295 -43.366664) (xy 304.753138 -43.356534)
			(xy 304.808872 -43.354497) (xy 304.864309 -43.360597) (xy 304.918266 -43.374703) (xy 304.969595 -43.396515)
			(xy 305.017201 -43.425569) (xy 305.060069 -43.461244) (xy 305.097286 -43.502781) (xy 305.128059 -43.549294)
			(xy 305.136285 -43.566842) (xy 307.533292 -43.566842) (xy 307.537363 -43.51122) (xy 307.549489 -43.456783)
			(xy 307.569412 -43.404692) (xy 307.596708 -43.356057) (xy 307.630794 -43.311914) (xy 307.670943 -43.273205)
			(xy 307.716301 -43.240754) (xy 307.765901 -43.215253) (xy 307.818685 -43.197246) (xy 307.873528 -43.187116)
			(xy 307.929262 -43.185079) (xy 307.984699 -43.191179) (xy 308.038656 -43.205285) (xy 308.089985 -43.227097)
			(xy 308.137591 -43.256151) (xy 308.180459 -43.291826) (xy 308.217676 -43.333363) (xy 308.248449 -43.379876)
			(xy 308.272121 -43.430373) (xy 308.288189 -43.48378) (xy 308.296309 -43.538956) (xy 308.296818 -43.566842)
			(xy 308.296309 -43.594728) (xy 308.288189 -43.649904) (xy 308.272121 -43.703311) (xy 308.248449 -43.753808)
			(xy 308.217676 -43.800321) (xy 308.180459 -43.841858) (xy 308.162372 -43.85691) (xy 308.919624 -43.85691)
			(xy 308.923695 -43.801288) (xy 308.935821 -43.746851) (xy 308.955744 -43.69476) (xy 308.98304 -43.646125)
			(xy 309.017126 -43.601982) (xy 309.057275 -43.563273) (xy 309.102633 -43.530822) (xy 309.152233 -43.505321)
			(xy 309.205017 -43.487314) (xy 309.25986 -43.477184) (xy 309.315594 -43.475147) (xy 309.371031 -43.481247)
			(xy 309.424988 -43.495353) (xy 309.476317 -43.517165) (xy 309.523923 -43.546219) (xy 309.566791 -43.581894)
			(xy 309.604008 -43.623431) (xy 309.634781 -43.669944) (xy 309.658453 -43.720441) (xy 309.674521 -43.773848)
			(xy 309.682641 -43.829024) (xy 309.68315 -43.85691) (xy 309.682641 -43.884796) (xy 309.674521 -43.939972)
			(xy 309.658453 -43.993379) (xy 309.634781 -44.043876) (xy 309.604008 -44.090389) (xy 309.566791 -44.131926)
			(xy 309.523923 -44.167601) (xy 309.476317 -44.196655) (xy 309.424988 -44.218467) (xy 309.371031 -44.232573)
			(xy 309.315594 -44.238673) (xy 309.25986 -44.236636) (xy 309.205017 -44.226506) (xy 309.152233 -44.208499)
			(xy 309.102633 -44.182998) (xy 309.057275 -44.150547) (xy 309.017126 -44.111838) (xy 308.98304 -44.067695)
			(xy 308.955744 -44.01906) (xy 308.935821 -43.966969) (xy 308.923695 -43.912532) (xy 308.919624 -43.85691)
			(xy 308.162372 -43.85691) (xy 308.137591 -43.877533) (xy 308.089985 -43.906587) (xy 308.038656 -43.928399)
			(xy 307.984699 -43.942505) (xy 307.929262 -43.948605) (xy 307.873528 -43.946568) (xy 307.818685 -43.936438)
			(xy 307.765901 -43.918431) (xy 307.716301 -43.89293) (xy 307.670943 -43.860479) (xy 307.630794 -43.82177)
			(xy 307.596708 -43.777627) (xy 307.569412 -43.728992) (xy 307.549489 -43.676901) (xy 307.537363 -43.622464)
			(xy 307.533292 -43.566842) (xy 305.136285 -43.566842) (xy 305.151731 -43.599791) (xy 305.167799 -43.653198)
			(xy 305.175919 -43.708374) (xy 305.176428 -43.73626) (xy 305.175919 -43.764146) (xy 305.167799 -43.819322)
			(xy 305.151731 -43.872729) (xy 305.128059 -43.923226) (xy 305.097286 -43.969739) (xy 305.060069 -44.011276)
			(xy 305.017201 -44.046951) (xy 304.969595 -44.076005) (xy 304.918266 -44.097817) (xy 304.864309 -44.111923)
			(xy 304.808872 -44.118023) (xy 304.753138 -44.115986) (xy 304.698295 -44.105856) (xy 304.645511 -44.087849)
			(xy 304.595911 -44.062348) (xy 304.550553 -44.029897) (xy 304.510404 -43.991188) (xy 304.476318 -43.947045)
			(xy 304.449022 -43.89841) (xy 304.429099 -43.846319) (xy 304.416973 -43.791882) (xy 304.412902 -43.73626)
			(xy 294.457882 -43.73626) (xy 295.439084 -44.717462) (xy 295.453052 -44.73165) (xy 295.479235 -44.76165)
			(xy 295.491408 -44.777406) (xy 295.493186 -44.779946) (xy 295.827704 -45.114464) (xy 304.265328 -45.114464)
			(xy 304.269399 -45.058842) (xy 304.281525 -45.004405) (xy 304.301448 -44.952314) (xy 304.328744 -44.903679)
			(xy 304.36283 -44.859536) (xy 304.402979 -44.820827) (xy 304.448337 -44.788376) (xy 304.497937 -44.762875)
			(xy 304.550721 -44.744868) (xy 304.605564 -44.734738) (xy 304.661298 -44.732701) (xy 304.716735 -44.738801)
			(xy 304.770692 -44.752907) (xy 304.822021 -44.774719) (xy 304.869627 -44.803773) (xy 304.912495 -44.839448)
			(xy 304.942477 -44.87291) (xy 311.13298 -44.87291) (xy 311.137051 -44.817288) (xy 311.149177 -44.762851)
			(xy 311.1691 -44.71076) (xy 311.196396 -44.662125) (xy 311.230482 -44.617982) (xy 311.270631 -44.579273)
			(xy 311.315989 -44.546822) (xy 311.365589 -44.521321) (xy 311.418373 -44.503314) (xy 311.473216 -44.493184)
			(xy 311.52895 -44.491147) (xy 311.584387 -44.497247) (xy 311.638344 -44.511353) (xy 311.689673 -44.533165)
			(xy 311.737279 -44.562219) (xy 311.780147 -44.597894) (xy 311.817364 -44.639431) (xy 311.848137 -44.685944)
			(xy 311.871809 -44.736441) (xy 311.887877 -44.789848) (xy 311.895997 -44.845024) (xy 311.896506 -44.87291)
			(xy 311.895997 -44.900796) (xy 311.887877 -44.955972) (xy 311.871809 -45.009379) (xy 311.848137 -45.059876)
			(xy 311.817364 -45.106389) (xy 311.780147 -45.147926) (xy 311.737279 -45.183601) (xy 311.689673 -45.212655)
			(xy 311.638344 -45.234467) (xy 311.584387 -45.248573) (xy 311.52895 -45.254673) (xy 311.473216 -45.252636)
			(xy 311.418373 -45.242506) (xy 311.365589 -45.224499) (xy 311.315989 -45.198998) (xy 311.270631 -45.166547)
			(xy 311.230482 -45.127838) (xy 311.196396 -45.083695) (xy 311.1691 -45.03506) (xy 311.149177 -44.982969)
			(xy 311.137051 -44.928532) (xy 311.13298 -44.87291) (xy 304.942477 -44.87291) (xy 304.949712 -44.880985)
			(xy 304.980485 -44.927498) (xy 305.004157 -44.977995) (xy 305.020225 -45.031402) (xy 305.028345 -45.086578)
			(xy 305.028854 -45.114464) (xy 305.028345 -45.14235) (xy 305.020225 -45.197526) (xy 305.004157 -45.250933)
			(xy 304.980485 -45.30143) (xy 304.949712 -45.347943) (xy 304.94407 -45.35424) (xy 308.903622 -45.35424)
			(xy 308.907693 -45.298618) (xy 308.919819 -45.244181) (xy 308.939742 -45.19209) (xy 308.967038 -45.143455)
			(xy 309.001124 -45.099312) (xy 309.041273 -45.060603) (xy 309.086631 -45.028152) (xy 309.136231 -45.002651)
			(xy 309.189015 -44.984644) (xy 309.243858 -44.974514) (xy 309.299592 -44.972477) (xy 309.355029 -44.978577)
			(xy 309.408986 -44.992683) (xy 309.460315 -45.014495) (xy 309.507921 -45.043549) (xy 309.550789 -45.079224)
			(xy 309.588006 -45.120761) (xy 309.618779 -45.167274) (xy 309.642451 -45.217771) (xy 309.658519 -45.271178)
			(xy 309.666639 -45.326354) (xy 309.667148 -45.35424) (xy 309.666639 -45.382126) (xy 309.658519 -45.437302)
			(xy 309.642451 -45.490709) (xy 309.618779 -45.541206) (xy 309.588006 -45.587719) (xy 309.550789 -45.629256)
			(xy 309.507921 -45.664931) (xy 309.460315 -45.693985) (xy 309.408986 -45.715797) (xy 309.355029 -45.729903)
			(xy 309.299592 -45.736003) (xy 309.243858 -45.733966) (xy 309.189015 -45.723836) (xy 309.136231 -45.705829)
			(xy 309.086631 -45.680328) (xy 309.041273 -45.647877) (xy 309.001124 -45.609168) (xy 308.967038 -45.565025)
			(xy 308.939742 -45.51639) (xy 308.919819 -45.464299) (xy 308.907693 -45.409862) (xy 308.903622 -45.35424)
			(xy 304.94407 -45.35424) (xy 304.912495 -45.38948) (xy 304.869627 -45.425155) (xy 304.822021 -45.454209)
			(xy 304.770692 -45.476021) (xy 304.716735 -45.490127) (xy 304.661298 -45.496227) (xy 304.605564 -45.49419)
			(xy 304.550721 -45.48406) (xy 304.497937 -45.466053) (xy 304.448337 -45.440552) (xy 304.402979 -45.408101)
			(xy 304.36283 -45.369392) (xy 304.328744 -45.325249) (xy 304.301448 -45.276614) (xy 304.281525 -45.224523)
			(xy 304.269399 -45.170086) (xy 304.265328 -45.114464) (xy 295.827704 -45.114464) (xy 296.66057 -45.94733)
			(xy 296.68368 -45.971109) (xy 296.725013 -46.022962) (xy 296.760282 -46.079116) (xy 296.761768 -46.082204)
			(xy 302.25238 -46.082204) (xy 302.252881 -46.054953) (xy 302.260637 -46.001007) (xy 302.275991 -45.948713)
			(xy 302.298631 -45.899137) (xy 302.328096 -45.853287) (xy 302.363786 -45.812097) (xy 302.404974 -45.776405)
			(xy 302.450823 -45.746939) (xy 302.500398 -45.724297) (xy 302.552691 -45.708941) (xy 302.606637 -45.701183)
			(xy 302.633888 -45.700696) (xy 302.66079 -45.701167) (xy 302.71406 -45.708738) (xy 302.765738 -45.723715)
			(xy 302.8148 -45.745804) (xy 302.860272 -45.774565) (xy 302.901254 -45.809428) (xy 302.936932 -45.849703)
			(xy 302.95215 -45.871892) (xy 302.959262 -45.882814) (xy 302.982122 -45.894752) (xy 303.09439 -45.89272)
			(xy 303.116742 -45.879766) (xy 303.1236 -45.86859) (xy 303.138535 -45.844997) (xy 303.174212 -45.802046)
			(xy 303.215768 -45.764752) (xy 303.262316 -45.733914) (xy 303.312861 -45.710189) (xy 303.366324 -45.694084)
			(xy 303.421564 -45.685944) (xy 303.449482 -45.685456) (xy 303.476475 -45.685928) (xy 303.529923 -45.693531)
			(xy 303.581766 -45.708589) (xy 303.630971 -45.7308) (xy 303.676555 -45.759723) (xy 303.697386 -45.776896)
			(xy 303.705514 -45.784008) (xy 303.726088 -45.790104) (xy 303.811432 -45.779182) (xy 303.821983 -45.777433)
			(xy 303.840263 -45.766361) (xy 303.846738 -45.757846) (xy 303.862074 -45.736602) (xy 303.897664 -45.69815)
			(xy 303.938184 -45.664932) (xy 303.98287 -45.637575) (xy 304.030881 -45.616594) (xy 304.081312 -45.602384)
			(xy 304.133214 -45.595212) (xy 304.159412 -45.594778) (xy 304.186662 -45.595293) (xy 304.240606 -45.603051)
			(xy 304.292897 -45.618406) (xy 304.342471 -45.641047) (xy 304.388318 -45.670513) (xy 304.429506 -45.706203)
			(xy 304.465194 -45.747391) (xy 304.494659 -45.793239) (xy 304.517298 -45.842814) (xy 304.532652 -45.895106)
			(xy 304.540408 -45.94905) (xy 304.540408 -46.00355) (xy 304.532652 -46.057494) (xy 304.517298 -46.109786)
			(xy 304.494659 -46.159361) (xy 304.465194 -46.205209) (xy 304.429506 -46.246397) (xy 304.388318 -46.282087)
			(xy 304.342471 -46.311553) (xy 304.292897 -46.334194) (xy 304.240606 -46.349549) (xy 304.186662 -46.357307)
			(xy 304.159412 -46.357794) (xy 304.13242 -46.357314) (xy 304.078973 -46.349711) (xy 304.02713 -46.334654)
			(xy 303.977925 -46.312445) (xy 303.93234 -46.283525) (xy 303.911508 -46.266354) (xy 303.90338 -46.259242)
			(xy 303.882806 -46.253146) (xy 303.797462 -46.264068) (xy 303.786927 -46.265881) (xy 303.768641 -46.276909)
			(xy 303.762156 -46.285404) (xy 303.744546 -46.309706) (xy 303.702948 -46.352965) (xy 303.679352 -46.37151)
			(xy 303.671478 -46.377352) (xy 303.661064 -46.394878) (xy 303.647856 -46.485302) (xy 303.652682 -46.504606)
			(xy 303.658524 -46.51248) (xy 303.658524 -46.512734) (xy 303.676021 -46.537483) (xy 303.703826 -46.591333)
			(xy 303.722764 -46.648904) (xy 303.729968 -46.693836) (xy 308.876192 -46.693836) (xy 308.876678 -46.666585)
			(xy 308.884434 -46.612637) (xy 308.899789 -46.560342) (xy 308.922431 -46.510765) (xy 308.951897 -46.464915)
			(xy 308.987588 -46.423724) (xy 309.028779 -46.388033) (xy 309.074629 -46.358567) (xy 309.124206 -46.335925)
			(xy 309.176501 -46.32057) (xy 309.230449 -46.312814) (xy 309.284951 -46.312814) (xy 309.338899 -46.32057)
			(xy 309.391194 -46.335925) (xy 309.440771 -46.358567) (xy 309.486621 -46.388033) (xy 309.527812 -46.423724)
			(xy 309.563503 -46.464915) (xy 309.592969 -46.510765) (xy 309.615611 -46.560342) (xy 309.630966 -46.612637)
			(xy 309.638722 -46.666585) (xy 309.639208 -46.693836) (xy 309.638734 -46.720264) (xy 309.631425 -46.772611)
			(xy 309.616952 -46.823446) (xy 309.595593 -46.871793) (xy 309.582058 -46.894496) (xy 309.581804 -46.89475)
			(xy 309.576467 -46.904768) (xy 309.574212 -46.927318) (xy 309.577486 -46.938184) (xy 309.603648 -47.01286)
			(xy 309.608034 -47.023374) (xy 309.624121 -47.039463) (xy 309.634636 -47.043848) (xy 309.63489 -47.043848)
			(xy 309.659408 -47.052893) (xy 309.70586 -47.07684) (xy 309.74861 -47.106901) (xy 309.786861 -47.142512)
			(xy 309.819896 -47.183008) (xy 309.847098 -47.227631) (xy 309.867959 -47.275548) (xy 309.882088 -47.325863)
			(xy 309.889221 -47.377635) (xy 309.889652 -47.403766) (xy 309.889166 -47.431017) (xy 309.887643 -47.441612)
			(xy 311.161682 -47.441612) (xy 311.165753 -47.38599) (xy 311.177879 -47.331553) (xy 311.197802 -47.279462)
			(xy 311.225098 -47.230827) (xy 311.259184 -47.186684) (xy 311.299333 -47.147975) (xy 311.344691 -47.115524)
			(xy 311.394291 -47.090023) (xy 311.447075 -47.072016) (xy 311.501918 -47.061886) (xy 311.557652 -47.059849)
			(xy 311.613089 -47.065949) (xy 311.667046 -47.080055) (xy 311.718375 -47.101867) (xy 311.765981 -47.130921)
			(xy 311.808849 -47.166596) (xy 311.846066 -47.208133) (xy 311.876839 -47.254646) (xy 311.900511 -47.305143)
			(xy 311.916579 -47.35855) (xy 311.924699 -47.413726) (xy 311.925208 -47.441612) (xy 311.924699 -47.469498)
			(xy 311.916579 -47.524674) (xy 311.900511 -47.578081) (xy 311.876839 -47.628578) (xy 311.846066 -47.675091)
			(xy 311.808849 -47.716628) (xy 311.765981 -47.752303) (xy 311.718375 -47.781357) (xy 311.667046 -47.803169)
			(xy 311.613089 -47.817275) (xy 311.557652 -47.823375) (xy 311.501918 -47.821338) (xy 311.447075 -47.811208)
			(xy 311.394291 -47.793201) (xy 311.344691 -47.7677) (xy 311.299333 -47.735249) (xy 311.259184 -47.69654)
			(xy 311.225098 -47.652397) (xy 311.197802 -47.603762) (xy 311.177879 -47.551671) (xy 311.165753 -47.497234)
			(xy 311.161682 -47.441612) (xy 309.887643 -47.441612) (xy 309.88141 -47.484965) (xy 309.866055 -47.53726)
			(xy 309.843413 -47.586837) (xy 309.813947 -47.632687) (xy 309.778256 -47.673878) (xy 309.737065 -47.709569)
			(xy 309.691215 -47.739035) (xy 309.641638 -47.761677) (xy 309.589343 -47.777032) (xy 309.535395 -47.784788)
			(xy 309.480893 -47.784788) (xy 309.426945 -47.777032) (xy 309.37465 -47.761677) (xy 309.325073 -47.739035)
			(xy 309.279223 -47.709569) (xy 309.238032 -47.673878) (xy 309.202341 -47.632687) (xy 309.172875 -47.586837)
			(xy 309.150233 -47.53726) (xy 309.134878 -47.484965) (xy 309.127122 -47.431017) (xy 309.126636 -47.403766)
			(xy 309.127105 -47.377338) (xy 309.134415 -47.324991) (xy 309.148889 -47.274156) (xy 309.170251 -47.225809)
			(xy 309.183786 -47.203106) (xy 309.18404 -47.202852) (xy 309.189375 -47.192833) (xy 309.191634 -47.170284)
			(xy 309.188358 -47.159418) (xy 309.162196 -47.084742) (xy 309.157835 -47.074215) (xy 309.141731 -47.058131)
			(xy 309.131208 -47.053754) (xy 309.130954 -47.053754) (xy 309.106446 -47.044683) (xy 309.059994 -47.02074)
			(xy 309.017242 -46.990685) (xy 308.97899 -46.955078) (xy 308.945953 -46.914585) (xy 308.918749 -46.869964)
			(xy 308.897887 -46.822049) (xy 308.883757 -46.771736) (xy 308.876623 -46.719966) (xy 308.876192 -46.693836)
			(xy 303.729968 -46.693836) (xy 303.732358 -46.708745) (xy 303.732946 -46.739048) (xy 303.732467 -46.766299)
			(xy 303.724705 -46.820245) (xy 303.709346 -46.872537) (xy 303.686702 -46.922112) (xy 303.657234 -46.96796)
			(xy 303.621542 -47.009149) (xy 303.580352 -47.04484) (xy 303.534503 -47.074306) (xy 303.484928 -47.096949)
			(xy 303.432635 -47.112307) (xy 303.378689 -47.120068) (xy 303.351438 -47.120556) (xy 303.325405 -47.12008)
			(xy 303.273824 -47.112999) (xy 303.223683 -47.098976) (xy 303.175911 -47.078271) (xy 303.131395 -47.051269)
			(xy 303.1109 -47.035212) (xy 303.10315 -47.029459) (xy 303.084734 -47.023725) (xy 303.075086 -47.024036)
			(xy 302.99533 -47.030386) (xy 302.97755 -47.039022) (xy 302.9712 -47.046388) (xy 302.953042 -47.066056)
			(xy 302.912129 -47.100576) (xy 302.866796 -47.129042) (xy 302.81793 -47.150896) (xy 302.76649 -47.165709)
			(xy 302.713485 -47.17319) (xy 302.68672 -47.173642) (xy 302.659471 -47.173103) (xy 302.605527 -47.16535)
			(xy 302.553235 -47.149999) (xy 302.50366 -47.127363) (xy 302.457812 -47.097902) (xy 302.416622 -47.062216)
			(xy 302.38093 -47.021032) (xy 302.351463 -46.975187) (xy 302.328819 -46.925615) (xy 302.313461 -46.873326)
			(xy 302.305701 -46.819383) (xy 302.305212 -46.792134) (xy 302.305733 -46.76336) (xy 302.314385 -46.706465)
			(xy 302.331481 -46.651515) (xy 302.356636 -46.599755) (xy 302.389277 -46.552359) (xy 302.40859 -46.531022)
			(xy 302.415956 -46.523148) (xy 302.423068 -46.503336) (xy 302.415702 -46.40707) (xy 302.405796 -46.388274)
			(xy 302.397414 -46.38167) (xy 302.375228 -46.363447) (xy 302.336019 -46.321511) (xy 302.303533 -46.274175)
			(xy 302.278505 -46.222507) (xy 302.261499 -46.167672) (xy 302.252898 -46.110909) (xy 302.25238 -46.082204)
			(xy 296.761768 -46.082204) (xy 296.789042 -46.138865) (xy 296.810933 -46.201459) (xy 296.82568 -46.266109)
			(xy 296.833096 -46.332004) (xy 296.833544 -46.36516) (xy 296.833544 -48.30699) (xy 308.753762 -48.30699)
			(xy 308.757833 -48.251368) (xy 308.769959 -48.196931) (xy 308.789882 -48.14484) (xy 308.817178 -48.096205)
			(xy 308.851264 -48.052062) (xy 308.891413 -48.013353) (xy 308.936771 -47.980902) (xy 308.986371 -47.955401)
			(xy 309.039155 -47.937394) (xy 309.093998 -47.927264) (xy 309.149732 -47.925227) (xy 309.205169 -47.931327)
			(xy 309.259126 -47.945433) (xy 309.310455 -47.967245) (xy 309.358061 -47.996299) (xy 309.400929 -48.031974)
			(xy 309.438146 -48.073511) (xy 309.468919 -48.120024) (xy 309.492591 -48.170521) (xy 309.508659 -48.223928)
			(xy 309.516779 -48.279104) (xy 309.517288 -48.30699) (xy 309.516779 -48.334876) (xy 309.508659 -48.390052)
			(xy 309.492591 -48.443459) (xy 309.468919 -48.493956) (xy 309.438146 -48.540469) (xy 309.400929 -48.582006)
			(xy 309.358061 -48.617681) (xy 309.310455 -48.646735) (xy 309.259126 -48.668547) (xy 309.205169 -48.682653)
			(xy 309.149732 -48.688753) (xy 309.093998 -48.686716) (xy 309.039155 -48.676586) (xy 308.986371 -48.658579)
			(xy 308.936771 -48.633078) (xy 308.891413 -48.600627) (xy 308.851264 -48.561918) (xy 308.817178 -48.517775)
			(xy 308.789882 -48.46914) (xy 308.769959 -48.417049) (xy 308.757833 -48.362612) (xy 308.753762 -48.30699)
			(xy 296.833544 -48.30699) (xy 296.833544 -48.753014) (xy 305.368196 -48.753014) (xy 305.372267 -48.697392)
			(xy 305.384393 -48.642955) (xy 305.404316 -48.590864) (xy 305.431612 -48.542229) (xy 305.465698 -48.498086)
			(xy 305.505847 -48.459377) (xy 305.551205 -48.426926) (xy 305.600805 -48.401425) (xy 305.653589 -48.383418)
			(xy 305.708432 -48.373288) (xy 305.764166 -48.371251) (xy 305.819603 -48.377351) (xy 305.87356 -48.391457)
			(xy 305.924889 -48.413269) (xy 305.972495 -48.442323) (xy 306.015363 -48.477998) (xy 306.05258 -48.519535)
			(xy 306.083353 -48.566048) (xy 306.107025 -48.616545) (xy 306.123093 -48.669952) (xy 306.131213 -48.725128)
			(xy 306.131722 -48.753014) (xy 306.131213 -48.7809) (xy 306.123093 -48.836076) (xy 306.120649 -48.8442)
			(xy 306.387244 -48.8442) (xy 306.391315 -48.788578) (xy 306.403441 -48.734141) (xy 306.423364 -48.68205)
			(xy 306.45066 -48.633415) (xy 306.484746 -48.589272) (xy 306.524895 -48.550563) (xy 306.570253 -48.518112)
			(xy 306.619853 -48.492611) (xy 306.672637 -48.474604) (xy 306.72748 -48.464474) (xy 306.783214 -48.462437)
			(xy 306.838651 -48.468537) (xy 306.892608 -48.482643) (xy 306.943937 -48.504455) (xy 306.991543 -48.533509)
			(xy 307.034411 -48.569184) (xy 307.071628 -48.610721) (xy 307.102401 -48.657234) (xy 307.126073 -48.707731)
			(xy 307.142141 -48.761138) (xy 307.150261 -48.816314) (xy 307.15077 -48.8442) (xy 307.150261 -48.872086)
			(xy 307.147263 -48.89246) (xy 307.413912 -48.89246) (xy 307.417983 -48.836838) (xy 307.430109 -48.782401)
			(xy 307.450032 -48.73031) (xy 307.477328 -48.681675) (xy 307.511414 -48.637532) (xy 307.551563 -48.598823)
			(xy 307.596921 -48.566372) (xy 307.646521 -48.540871) (xy 307.699305 -48.522864) (xy 307.754148 -48.512734)
			(xy 307.809882 -48.510697) (xy 307.865319 -48.516797) (xy 307.919276 -48.530903) (xy 307.970605 -48.552715)
			(xy 308.018211 -48.581769) (xy 308.061079 -48.617444) (xy 308.098296 -48.658981) (xy 308.129069 -48.705494)
			(xy 308.152741 -48.755991) (xy 308.168809 -48.809398) (xy 308.176929 -48.864574) (xy 308.177438 -48.89246)
			(xy 308.176929 -48.920346) (xy 308.174491 -48.93691) (xy 311.13298 -48.93691) (xy 311.137051 -48.881288)
			(xy 311.149177 -48.826851) (xy 311.1691 -48.77476) (xy 311.196396 -48.726125) (xy 311.230482 -48.681982)
			(xy 311.270631 -48.643273) (xy 311.315989 -48.610822) (xy 311.365589 -48.585321) (xy 311.418373 -48.567314)
			(xy 311.473216 -48.557184) (xy 311.52895 -48.555147) (xy 311.584387 -48.561247) (xy 311.638344 -48.575353)
			(xy 311.689673 -48.597165) (xy 311.737279 -48.626219) (xy 311.780147 -48.661894) (xy 311.817364 -48.703431)
			(xy 311.848137 -48.749944) (xy 311.871809 -48.800441) (xy 311.887877 -48.853848) (xy 311.895997 -48.909024)
			(xy 311.896506 -48.93691) (xy 311.895997 -48.964796) (xy 311.887877 -49.019972) (xy 311.871809 -49.073379)
			(xy 311.848137 -49.123876) (xy 311.817364 -49.170389) (xy 311.780147 -49.211926) (xy 311.737279 -49.247601)
			(xy 311.689673 -49.276655) (xy 311.638344 -49.298467) (xy 311.584387 -49.312573) (xy 311.52895 -49.318673)
			(xy 311.473216 -49.316636) (xy 311.418373 -49.306506) (xy 311.365589 -49.288499) (xy 311.315989 -49.262998)
			(xy 311.270631 -49.230547) (xy 311.230482 -49.191838) (xy 311.196396 -49.147695) (xy 311.1691 -49.09906)
			(xy 311.149177 -49.046969) (xy 311.137051 -48.992532) (xy 311.13298 -48.93691) (xy 308.174491 -48.93691)
			(xy 308.168809 -48.975522) (xy 308.152741 -49.028929) (xy 308.129069 -49.079426) (xy 308.098296 -49.125939)
			(xy 308.061079 -49.167476) (xy 308.018211 -49.203151) (xy 307.970605 -49.232205) (xy 307.919276 -49.254017)
			(xy 307.865319 -49.268123) (xy 307.809882 -49.274223) (xy 307.754148 -49.272186) (xy 307.699305 -49.262056)
			(xy 307.646521 -49.244049) (xy 307.596921 -49.218548) (xy 307.551563 -49.186097) (xy 307.511414 -49.147388)
			(xy 307.477328 -49.103245) (xy 307.450032 -49.05461) (xy 307.430109 -49.002519) (xy 307.417983 -48.948082)
			(xy 307.413912 -48.89246) (xy 307.147263 -48.89246) (xy 307.142141 -48.927262) (xy 307.126073 -48.980669)
			(xy 307.102401 -49.031166) (xy 307.071628 -49.077679) (xy 307.034411 -49.119216) (xy 306.991543 -49.154891)
			(xy 306.943937 -49.183945) (xy 306.892608 -49.205757) (xy 306.838651 -49.219863) (xy 306.783214 -49.225963)
			(xy 306.72748 -49.223926) (xy 306.672637 -49.213796) (xy 306.619853 -49.195789) (xy 306.570253 -49.170288)
			(xy 306.524895 -49.137837) (xy 306.484746 -49.099128) (xy 306.45066 -49.054985) (xy 306.423364 -49.00635)
			(xy 306.403441 -48.954259) (xy 306.391315 -48.899822) (xy 306.387244 -48.8442) (xy 306.120649 -48.8442)
			(xy 306.107025 -48.889483) (xy 306.083353 -48.93998) (xy 306.05258 -48.986493) (xy 306.015363 -49.02803)
			(xy 305.972495 -49.063705) (xy 305.924889 -49.092759) (xy 305.87356 -49.114571) (xy 305.819603 -49.128677)
			(xy 305.764166 -49.134777) (xy 305.708432 -49.13274) (xy 305.653589 -49.12261) (xy 305.600805 -49.104603)
			(xy 305.551205 -49.079102) (xy 305.505847 -49.046651) (xy 305.465698 -49.007942) (xy 305.431612 -48.963799)
			(xy 305.404316 -48.915164) (xy 305.384393 -48.863073) (xy 305.372267 -48.808636) (xy 305.368196 -48.753014)
			(xy 296.833544 -48.753014) (xy 296.833544 -49.601953) (xy 316.312759 -49.601953) (xy 316.312759 -49.547447)
			(xy 316.320516 -49.493497) (xy 316.335872 -49.441199) (xy 316.358515 -49.391619) (xy 316.387983 -49.345766)
			(xy 316.423677 -49.304574) (xy 316.464869 -49.268881) (xy 316.510723 -49.239413) (xy 316.560303 -49.216771)
			(xy 316.6126 -49.201415) (xy 316.666551 -49.193659) (xy 316.693804 -49.193196) (xy 316.721174 -49.193661)
			(xy 316.775353 -49.201479) (xy 316.827856 -49.216968) (xy 316.877603 -49.23981) (xy 316.92357 -49.269535)
			(xy 316.944502 -49.287176) (xy 316.944756 -49.28743) (xy 316.951849 -49.293008) (xy 316.968761 -49.299259)
			(xy 316.977776 -49.299622) (xy 317.044832 -49.299622) (xy 317.05385 -49.299276) (xy 317.070767 -49.29302)
			(xy 317.077852 -49.28743) (xy 317.077852 -49.287176) (xy 317.078106 -49.287176) (xy 317.099039 -49.269535)
			(xy 317.145007 -49.239811) (xy 317.194753 -49.216965) (xy 317.247255 -49.201469) (xy 317.301433 -49.19364)
			(xy 317.356175 -49.19364) (xy 317.410353 -49.201469) (xy 317.462855 -49.216965) (xy 317.512601 -49.239811)
			(xy 317.558569 -49.269535) (xy 317.579502 -49.287176) (xy 317.579756 -49.28743) (xy 317.586849 -49.293008)
			(xy 317.603761 -49.299259) (xy 317.612776 -49.299622) (xy 317.679832 -49.299622) (xy 317.68885 -49.299276)
			(xy 317.705767 -49.29302) (xy 317.712852 -49.28743) (xy 317.712852 -49.287176) (xy 317.713106 -49.287176)
			(xy 317.734039 -49.269535) (xy 317.780007 -49.239811) (xy 317.829753 -49.216965) (xy 317.882255 -49.201469)
			(xy 317.936433 -49.19364) (xy 317.991175 -49.19364) (xy 318.045353 -49.201469) (xy 318.097855 -49.216965)
			(xy 318.147601 -49.239811) (xy 318.193569 -49.269535) (xy 318.214502 -49.287176) (xy 318.214756 -49.28743)
			(xy 318.221849 -49.293008) (xy 318.238761 -49.299259) (xy 318.247776 -49.299622) (xy 318.314832 -49.299622)
			(xy 318.32385 -49.299276) (xy 318.340767 -49.29302) (xy 318.347852 -49.28743) (xy 318.347852 -49.287176)
			(xy 318.348106 -49.287176) (xy 318.369022 -49.269517) (xy 318.415 -49.239809) (xy 318.464751 -49.216977)
			(xy 318.517255 -49.201491) (xy 318.571434 -49.193667) (xy 318.598804 -49.193196) (xy 318.626055 -49.193674)
			(xy 318.680003 -49.201431) (xy 318.732298 -49.216787) (xy 318.781875 -49.239428) (xy 318.827726 -49.268895)
			(xy 318.868916 -49.304587) (xy 318.904607 -49.345778) (xy 318.934074 -49.391628) (xy 318.956715 -49.441206)
			(xy 318.97207 -49.493501) (xy 318.979826 -49.547449) (xy 318.979826 -49.601951) (xy 318.97207 -49.655899)
			(xy 318.956715 -49.708194) (xy 318.934074 -49.757772) (xy 318.904607 -49.803622) (xy 318.868916 -49.844813)
			(xy 318.827726 -49.880505) (xy 318.781875 -49.909972) (xy 318.732298 -49.932613) (xy 318.680003 -49.947969)
			(xy 318.626055 -49.955726) (xy 318.598804 -49.956212) (xy 318.571434 -49.955741) (xy 318.517255 -49.947924)
			(xy 318.464752 -49.932436) (xy 318.415005 -49.909595) (xy 318.369038 -49.879872) (xy 318.348106 -49.862232)
			(xy 318.347852 -49.861978) (xy 318.340757 -49.856405) (xy 318.323846 -49.850151) (xy 318.314832 -49.849786)
			(xy 318.247776 -49.849786) (xy 318.238758 -49.850135) (xy 318.221842 -49.856389) (xy 318.214756 -49.861978)
			(xy 318.214502 -49.862232) (xy 318.193569 -49.879873) (xy 318.147601 -49.909597) (xy 318.097855 -49.932443)
			(xy 318.045353 -49.947939) (xy 317.991175 -49.955768) (xy 317.936433 -49.955768) (xy 317.882255 -49.947939)
			(xy 317.829753 -49.932443) (xy 317.780007 -49.909597) (xy 317.734039 -49.879873) (xy 317.713106 -49.862232)
			(xy 317.712852 -49.861978) (xy 317.705757 -49.856405) (xy 317.688846 -49.850151) (xy 317.679832 -49.849786)
			(xy 317.612776 -49.849786) (xy 317.603758 -49.850135) (xy 317.586842 -49.856389) (xy 317.579756 -49.861978)
			(xy 317.579756 -49.862232) (xy 317.579502 -49.862232) (xy 317.558569 -49.879873) (xy 317.512601 -49.909597)
			(xy 317.462855 -49.932443) (xy 317.410353 -49.947939) (xy 317.356175 -49.955768) (xy 317.301433 -49.955768)
			(xy 317.247255 -49.947939) (xy 317.194753 -49.932443) (xy 317.145007 -49.909597) (xy 317.099039 -49.879873)
			(xy 317.078106 -49.862232) (xy 317.077852 -49.861978) (xy 317.070757 -49.856405) (xy 317.053846 -49.850151)
			(xy 317.044832 -49.849786) (xy 316.977776 -49.849786) (xy 316.968758 -49.850135) (xy 316.951842 -49.856389)
			(xy 316.944756 -49.861978) (xy 316.944756 -49.862232) (xy 316.944502 -49.862232) (xy 316.923584 -49.879889)
			(xy 316.877607 -49.909597) (xy 316.827856 -49.932429) (xy 316.775352 -49.947916) (xy 316.721174 -49.95574)
			(xy 316.693804 -49.956212) (xy 316.666551 -49.955741) (xy 316.6126 -49.947985) (xy 316.560303 -49.932629)
			(xy 316.510723 -49.909987) (xy 316.464869 -49.880519) (xy 316.423677 -49.844826) (xy 316.387983 -49.803634)
			(xy 316.358515 -49.757781) (xy 316.335872 -49.708201) (xy 316.320516 -49.655903) (xy 316.312759 -49.601953)
			(xy 296.833544 -49.601953) (xy 296.833544 -50.462434) (xy 307.026054 -50.462434) (xy 307.030125 -50.406812)
			(xy 307.042251 -50.352375) (xy 307.062174 -50.300284) (xy 307.08947 -50.251649) (xy 307.123556 -50.207506)
			(xy 307.163705 -50.168797) (xy 307.209063 -50.136346) (xy 307.258663 -50.110845) (xy 307.311447 -50.092838)
			(xy 307.36629 -50.082708) (xy 307.422024 -50.080671) (xy 307.477461 -50.086771) (xy 307.531418 -50.100877)
			(xy 307.582747 -50.122689) (xy 307.630353 -50.151743) (xy 307.673221 -50.187418) (xy 307.710438 -50.228955)
			(xy 307.741211 -50.275468) (xy 307.764883 -50.325965) (xy 307.780951 -50.379372) (xy 307.789071 -50.434548)
			(xy 307.78958 -50.462434) (xy 307.789071 -50.49032) (xy 307.780951 -50.545496) (xy 307.764883 -50.598903)
			(xy 307.741211 -50.6494) (xy 307.710438 -50.695913) (xy 307.673221 -50.73745) (xy 307.630353 -50.773125)
			(xy 307.582747 -50.802179) (xy 307.531418 -50.823991) (xy 307.477461 -50.838097) (xy 307.422024 -50.844197)
			(xy 307.36629 -50.84216) (xy 307.311447 -50.83203) (xy 307.258663 -50.814023) (xy 307.209063 -50.788522)
			(xy 307.163705 -50.756071) (xy 307.123556 -50.717362) (xy 307.08947 -50.673219) (xy 307.062174 -50.624584)
			(xy 307.042251 -50.572493) (xy 307.030125 -50.518056) (xy 307.026054 -50.462434) (xy 296.833544 -50.462434)
			(xy 296.833544 -51.019456) (xy 308.949342 -51.019456) (xy 308.953413 -50.963834) (xy 308.965539 -50.909397)
			(xy 308.985462 -50.857306) (xy 309.012758 -50.808671) (xy 309.046844 -50.764528) (xy 309.086993 -50.725819)
			(xy 309.132351 -50.693368) (xy 309.181951 -50.667867) (xy 309.234735 -50.64986) (xy 309.289578 -50.63973)
			(xy 309.345312 -50.637693) (xy 309.400749 -50.643793) (xy 309.454706 -50.657899) (xy 309.506035 -50.679711)
			(xy 309.553641 -50.708765) (xy 309.596509 -50.74444) (xy 309.633726 -50.785977) (xy 309.664499 -50.83249)
			(xy 309.688171 -50.882987) (xy 309.704239 -50.936394) (xy 309.712359 -50.99157) (xy 309.712868 -51.019456)
			(xy 309.712359 -51.047342) (xy 309.704239 -51.102518) (xy 309.688171 -51.155925) (xy 309.664499 -51.206422)
			(xy 309.639643 -51.243992) (xy 317.332868 -51.243992) (xy 317.333313 -51.216621) (xy 317.341133 -51.16244)
			(xy 317.356626 -51.109936) (xy 317.379473 -51.06019) (xy 317.409204 -51.014224) (xy 317.426848 -50.993294)
			(xy 317.427102 -50.99304) (xy 317.432678 -50.985946) (xy 317.438931 -50.969035) (xy 317.439294 -50.96002)
			(xy 317.439294 -50.892964) (xy 317.438955 -50.883945) (xy 317.432695 -50.867028) (xy 317.427102 -50.859944)
			(xy 317.426848 -50.859944) (xy 317.426848 -50.85969) (xy 317.409198 -50.838766) (xy 317.379486 -50.792792)
			(xy 317.356652 -50.743042) (xy 317.341163 -50.69054) (xy 317.333339 -50.636362) (xy 317.332868 -50.608992)
			(xy 317.33337 -50.581742) (xy 317.341127 -50.527796) (xy 317.356482 -50.475503) (xy 317.379123 -50.425927)
			(xy 317.408587 -50.380078) (xy 317.444277 -50.338888) (xy 317.485465 -50.303197) (xy 317.531313 -50.27373)
			(xy 317.580888 -50.251088) (xy 317.63318 -50.235731) (xy 317.687126 -50.227971) (xy 317.714376 -50.227484)
			(xy 317.743294 -50.227988) (xy 317.800467 -50.236715) (xy 317.855668 -50.253974) (xy 317.90763 -50.279368)
			(xy 317.955163 -50.312316) (xy 317.997178 -50.352062) (xy 318.015366 -50.37455) (xy 318.022989 -50.38334)
			(xy 318.043878 -50.393531) (xy 318.055498 -50.394108) (xy 318.135254 -50.394108) (xy 318.146888 -50.393583)
			(xy 318.167797 -50.383384) (xy 318.175386 -50.37455) (xy 318.193572 -50.352063) (xy 318.235595 -50.31233)
			(xy 318.283131 -50.279393) (xy 318.335093 -50.254006) (xy 318.39029 -50.23675) (xy 318.44746 -50.22802)
			(xy 318.476376 -50.227484) (xy 318.503628 -50.227978) (xy 318.557577 -50.235731) (xy 318.609874 -50.251084)
			(xy 318.659454 -50.273723) (xy 318.705306 -50.303188) (xy 318.746499 -50.338878) (xy 318.782193 -50.380068)
			(xy 318.811662 -50.425918) (xy 318.834305 -50.475496) (xy 318.849662 -50.527791) (xy 318.85742 -50.58174)
			(xy 318.857884 -50.608992) (xy 318.857416 -50.635306) (xy 318.850182 -50.687435) (xy 318.835864 -50.738078)
			(xy 318.814731 -50.786277) (xy 318.787185 -50.83112) (xy 318.753746 -50.87176) (xy 318.734694 -50.889916)
			(xy 318.727283 -50.897429) (xy 318.718764 -50.916716) (xy 318.718184 -50.927254) (xy 318.718184 -51.00193)
			(xy 318.718742 -51.012476) (xy 318.727257 -51.031772) (xy 318.734694 -51.039268) (xy 318.753774 -51.057399)
			(xy 318.78723 -51.098034) (xy 318.814785 -51.142879) (xy 318.83592 -51.191085) (xy 318.850231 -51.241737)
			(xy 318.857449 -51.293874) (xy 318.857884 -51.320192) (xy 318.857437 -51.347446) (xy 318.849681 -51.401399)
			(xy 318.834324 -51.453698) (xy 318.811681 -51.50328) (xy 318.782212 -51.549134) (xy 318.746516 -51.590328)
			(xy 318.705321 -51.626021) (xy 318.659466 -51.655489) (xy 318.609883 -51.67813) (xy 318.557583 -51.693484)
			(xy 318.50363 -51.701238) (xy 318.476376 -51.7017) (xy 318.44871 -51.701207) (xy 318.39396 -51.693204)
			(xy 318.340938 -51.677384) (xy 318.290754 -51.654078) (xy 318.244459 -51.623774) (xy 318.203021 -51.587106)
			(xy 318.167309 -51.544842) (xy 318.152272 -51.521614) (xy 318.145658 -51.511919) (xy 318.12578 -51.499485)
			(xy 318.114172 -51.497738) (xy 318.034162 -51.489864) (xy 318.022523 -51.489212) (xy 318.000684 -51.497306)
			(xy 317.992252 -51.505358) (xy 317.991998 -51.505612) (xy 317.973903 -51.524179) (xy 317.933574 -51.556758)
			(xy 317.889202 -51.583573) (xy 317.841607 -51.604128) (xy 317.791665 -51.618045) (xy 317.740298 -51.625066)
			(xy 317.714376 -51.6255) (xy 317.687124 -51.625044) (xy 317.633175 -51.617285) (xy 317.580879 -51.601926)
			(xy 317.531301 -51.579281) (xy 317.48545 -51.549812) (xy 317.44426 -51.514117) (xy 317.408569 -51.472924)
			(xy 317.379103 -51.427071) (xy 317.356463 -51.377491) (xy 317.341109 -51.325194) (xy 317.333353 -51.271244)
			(xy 317.332868 -51.243992) (xy 309.639643 -51.243992) (xy 309.633726 -51.252935) (xy 309.596509 -51.294472)
			(xy 309.553641 -51.330147) (xy 309.506035 -51.359201) (xy 309.454706 -51.381013) (xy 309.400749 -51.395119)
			(xy 309.345312 -51.401219) (xy 309.289578 -51.399182) (xy 309.234735 -51.389052) (xy 309.181951 -51.371045)
			(xy 309.132351 -51.345544) (xy 309.086993 -51.313093) (xy 309.046844 -51.274384) (xy 309.012758 -51.230241)
			(xy 308.985462 -51.181606) (xy 308.965539 -51.129515) (xy 308.953413 -51.075078) (xy 308.949342 -51.019456)
			(xy 296.833544 -51.019456) (xy 296.833544 -52.035456) (xy 311.141108 -52.035456) (xy 311.145179 -51.979834)
			(xy 311.157305 -51.925397) (xy 311.177228 -51.873306) (xy 311.204524 -51.824671) (xy 311.23861 -51.780528)
			(xy 311.278759 -51.741819) (xy 311.324117 -51.709368) (xy 311.373717 -51.683867) (xy 311.426501 -51.66586)
			(xy 311.481344 -51.65573) (xy 311.537078 -51.653693) (xy 311.592515 -51.659793) (xy 311.646472 -51.673899)
			(xy 311.697801 -51.695711) (xy 311.745407 -51.724765) (xy 311.788275 -51.76044) (xy 311.825492 -51.801977)
			(xy 311.856265 -51.84849) (xy 311.879937 -51.898987) (xy 311.896005 -51.952394) (xy 311.904125 -52.00757)
			(xy 311.904634 -52.035456) (xy 311.904125 -52.063342) (xy 311.896005 -52.118518) (xy 311.879937 -52.171925)
			(xy 311.856265 -52.222422) (xy 311.825492 -52.268935) (xy 311.788275 -52.310472) (xy 311.745407 -52.346147)
			(xy 311.697801 -52.375201) (xy 311.646472 -52.397013) (xy 311.592515 -52.411119) (xy 311.537078 -52.417219)
			(xy 311.481344 -52.415182) (xy 311.426501 -52.405052) (xy 311.373717 -52.387045) (xy 311.324117 -52.361544)
			(xy 311.278759 -52.329093) (xy 311.23861 -52.290384) (xy 311.204524 -52.246241) (xy 311.177228 -52.197606)
			(xy 311.157305 -52.145515) (xy 311.145179 -52.091078) (xy 311.141108 -52.035456) (xy 296.833544 -52.035456)
			(xy 296.833544 -54.731412) (xy 297.720512 -54.731412) (xy 297.720982 -54.704042) (xy 297.728799 -54.649863)
			(xy 297.744287 -54.59736) (xy 297.767127 -54.547613) (xy 297.796851 -54.501646) (xy 297.814492 -54.480714)
			(xy 297.814746 -54.48046) (xy 297.820319 -54.473364) (xy 297.826573 -54.456454) (xy 297.826938 -54.44744)
			(xy 297.826938 -54.380384) (xy 297.826581 -54.371367) (xy 297.820332 -54.354451) (xy 297.814746 -54.347364)
			(xy 297.814492 -54.347364) (xy 297.814492 -54.34711) (xy 297.796865 -54.326167) (xy 297.767142 -54.2802)
			(xy 297.744298 -54.230455) (xy 297.728802 -54.177955) (xy 297.720973 -54.123779) (xy 297.720972 -54.069039)
			(xy 297.728798 -54.014863) (xy 297.744292 -53.962362) (xy 297.767133 -53.912616) (xy 297.796854 -53.866647)
			(xy 297.814492 -53.845714) (xy 297.814746 -53.84546) (xy 297.820319 -53.838364) (xy 297.826573 -53.821454)
			(xy 297.826938 -53.81244) (xy 297.826938 -53.745384) (xy 297.826581 -53.736367) (xy 297.820332 -53.719451)
			(xy 297.814746 -53.712364) (xy 297.814492 -53.712364) (xy 297.814492 -53.71211) (xy 297.796865 -53.691167)
			(xy 297.767142 -53.6452) (xy 297.744298 -53.595455) (xy 297.728802 -53.542955) (xy 297.720973 -53.488779)
			(xy 297.720972 -53.434039) (xy 297.728798 -53.379863) (xy 297.744292 -53.327362) (xy 297.767133 -53.277616)
			(xy 297.796854 -53.231647) (xy 297.814492 -53.210714) (xy 297.814746 -53.21046) (xy 297.820319 -53.203364)
			(xy 297.826573 -53.186454) (xy 297.826938 -53.17744) (xy 297.826938 -53.110384) (xy 297.826581 -53.101367)
			(xy 297.820332 -53.084451) (xy 297.814746 -53.077364) (xy 297.814492 -53.077364) (xy 297.814492 -53.07711)
			(xy 297.796843 -53.056186) (xy 297.767133 -53.010211) (xy 297.744299 -52.960461) (xy 297.72881 -52.907959)
			(xy 297.720985 -52.853782) (xy 297.720512 -52.826412) (xy 297.720998 -52.799161) (xy 297.728754 -52.745213)
			(xy 297.744109 -52.692918) (xy 297.766751 -52.643341) (xy 297.796217 -52.597491) (xy 297.831908 -52.5563)
			(xy 297.873099 -52.520609) (xy 297.918949 -52.491143) (xy 297.968526 -52.468501) (xy 298.020821 -52.453146)
			(xy 298.074769 -52.44539) (xy 298.129271 -52.44539) (xy 298.183219 -52.453146) (xy 298.235514 -52.468501)
			(xy 298.285091 -52.491143) (xy 298.330941 -52.520609) (xy 298.372132 -52.5563) (xy 298.407823 -52.597491)
			(xy 298.437289 -52.643341) (xy 298.459931 -52.692918) (xy 298.475286 -52.745213) (xy 298.483042 -52.799161)
			(xy 298.483528 -52.826412) (xy 298.483087 -52.853783) (xy 298.475265 -52.907964) (xy 298.459772 -52.960468)
			(xy 298.436924 -53.010215) (xy 298.407193 -53.05618) (xy 298.389548 -53.07711) (xy 298.389294 -53.077364)
			(xy 298.383716 -53.084456) (xy 298.377464 -53.101369) (xy 298.377102 -53.110384) (xy 298.377102 -53.17744)
			(xy 298.37744 -53.186459) (xy 298.383701 -53.203376) (xy 298.389294 -53.21046) (xy 298.389548 -53.21046)
			(xy 298.389548 -53.210714) (xy 298.407201 -53.231637) (xy 298.436928 -53.277606) (xy 298.459774 -53.327353)
			(xy 298.47527 -53.379857) (xy 298.483098 -53.434038) (xy 298.483097 -53.48878) (xy 298.475266 -53.54296)
			(xy 298.459768 -53.595464) (xy 298.436919 -53.64521) (xy 298.407191 -53.691178) (xy 298.389548 -53.71211)
			(xy 298.389294 -53.712364) (xy 298.383716 -53.719456) (xy 298.377464 -53.736369) (xy 298.377102 -53.745384)
			(xy 298.377102 -53.81244) (xy 298.37744 -53.821459) (xy 298.383701 -53.838376) (xy 298.389294 -53.84546)
			(xy 298.389548 -53.84546) (xy 298.389548 -53.845714) (xy 298.407201 -53.866637) (xy 298.436928 -53.912606)
			(xy 298.459774 -53.962353) (xy 298.47527 -54.014857) (xy 298.483098 -54.069038) (xy 298.483097 -54.12378)
			(xy 298.475266 -54.17796) (xy 298.459768 -54.230464) (xy 298.436919 -54.28021) (xy 298.407191 -54.326178)
			(xy 298.389548 -54.34711) (xy 298.389294 -54.347364) (xy 298.383716 -54.354456) (xy 298.377464 -54.371369)
			(xy 298.377102 -54.380384) (xy 298.377102 -54.44744) (xy 298.37744 -54.456459) (xy 298.383701 -54.473376)
			(xy 298.389294 -54.48046) (xy 298.389548 -54.48046) (xy 298.389548 -54.480714) (xy 298.407152 -54.501674)
			(xy 298.436871 -54.547639) (xy 298.459715 -54.597379) (xy 298.475214 -54.649874) (xy 298.48305 -54.704045)
			(xy 298.483528 -54.731412) (xy 298.483042 -54.758663) (xy 298.478378 -54.791102) (xy 300.376336 -54.791102)
			(xy 300.376794 -54.763731) (xy 300.384613 -54.709552) (xy 300.400103 -54.657048) (xy 300.422947 -54.607301)
			(xy 300.452674 -54.561335) (xy 300.470316 -54.540404) (xy 300.47057 -54.54015) (xy 300.47615 -54.533059)
			(xy 300.482399 -54.516145) (xy 300.482762 -54.50713) (xy 300.482762 -54.440074) (xy 300.482426 -54.431055)
			(xy 300.476165 -54.414138) (xy 300.47057 -54.407054) (xy 300.470316 -54.407054) (xy 300.470316 -54.4068)
			(xy 300.452678 -54.385865) (xy 300.422954 -54.339898) (xy 300.400109 -54.290152) (xy 300.384613 -54.23765)
			(xy 300.376784 -54.183472) (xy 300.376784 -54.128731) (xy 300.384612 -54.074553) (xy 300.400108 -54.022051)
			(xy 300.422952 -53.972305) (xy 300.452676 -53.926337) (xy 300.470316 -53.905404) (xy 300.47057 -53.90515)
			(xy 300.47615 -53.898059) (xy 300.482399 -53.881145) (xy 300.482762 -53.87213) (xy 300.482762 -53.805074)
			(xy 300.482426 -53.796055) (xy 300.476165 -53.779138) (xy 300.47057 -53.772054) (xy 300.470316 -53.772054)
			(xy 300.470316 -53.7718) (xy 300.452678 -53.750865) (xy 300.422954 -53.704898) (xy 300.400109 -53.655152)
			(xy 300.384613 -53.60265) (xy 300.376784 -53.548472) (xy 300.376784 -53.493731) (xy 300.384612 -53.439553)
			(xy 300.400108 -53.387051) (xy 300.422952 -53.337305) (xy 300.452676 -53.291337) (xy 300.470316 -53.270404)
			(xy 300.47057 -53.27015) (xy 300.47615 -53.263059) (xy 300.482399 -53.246145) (xy 300.482762 -53.23713)
			(xy 300.482762 -53.170074) (xy 300.482426 -53.161055) (xy 300.476165 -53.144138) (xy 300.47057 -53.137054)
			(xy 300.470316 -53.137054) (xy 300.470316 -53.1368) (xy 300.452666 -53.115877) (xy 300.422955 -53.069902)
			(xy 300.400121 -53.020152) (xy 300.384633 -52.967649) (xy 300.376808 -52.913472) (xy 300.376336 -52.886102)
			(xy 300.376822 -52.858851) (xy 300.384578 -52.804903) (xy 300.399933 -52.752608) (xy 300.422575 -52.703031)
			(xy 300.452041 -52.657181) (xy 300.487732 -52.61599) (xy 300.528923 -52.580299) (xy 300.574773 -52.550833)
			(xy 300.62435 -52.528191) (xy 300.676645 -52.512836) (xy 300.730593 -52.50508) (xy 300.785095 -52.50508)
			(xy 300.839043 -52.512836) (xy 300.891338 -52.528191) (xy 300.930442 -52.54605) (xy 305.879496 -52.54605)
			(xy 305.879496 -52.49155) (xy 305.887252 -52.437605) (xy 305.902607 -52.385313) (xy 305.925247 -52.335738)
			(xy 305.954712 -52.28989) (xy 305.990401 -52.248701) (xy 306.03159 -52.213012) (xy 306.077438 -52.183547)
			(xy 306.127013 -52.160907) (xy 306.179305 -52.145552) (xy 306.23325 -52.137796) (xy 306.2605 -52.13731)
			(xy 306.28787 -52.137774) (xy 306.34205 -52.145592) (xy 306.394553 -52.161081) (xy 306.4443 -52.183924)
			(xy 306.490266 -52.213649) (xy 306.511198 -52.23129) (xy 306.511452 -52.231544) (xy 306.518544 -52.237122)
			(xy 306.535457 -52.243373) (xy 306.544472 -52.243736) (xy 306.611528 -52.243736) (xy 306.620545 -52.243385)
			(xy 306.637462 -52.237132) (xy 306.644548 -52.231544) (xy 306.644548 -52.23129) (xy 306.644802 -52.23129)
			(xy 306.665735 -52.213649) (xy 306.711703 -52.183925) (xy 306.761449 -52.161079) (xy 306.813951 -52.145583)
			(xy 306.868129 -52.137754) (xy 306.922871 -52.137754) (xy 306.977049 -52.145583) (xy 307.029551 -52.161079)
			(xy 307.079297 -52.183925) (xy 307.125265 -52.213649) (xy 307.146198 -52.23129) (xy 307.146452 -52.231544)
			(xy 307.153544 -52.237122) (xy 307.170457 -52.243373) (xy 307.179472 -52.243736) (xy 307.246528 -52.243736)
			(xy 307.255545 -52.243385) (xy 307.272462 -52.237132) (xy 307.279548 -52.231544) (xy 307.279548 -52.23129)
			(xy 307.279802 -52.23129) (xy 307.300721 -52.213635) (xy 307.346698 -52.183926) (xy 307.396448 -52.161093)
			(xy 307.448952 -52.145606) (xy 307.50313 -52.137782) (xy 307.5305 -52.13731) (xy 307.557753 -52.13776)
			(xy 307.611703 -52.145517) (xy 307.664 -52.160873) (xy 307.71358 -52.183515) (xy 307.759432 -52.212982)
			(xy 307.800624 -52.248676) (xy 307.836318 -52.289868) (xy 307.865785 -52.33572) (xy 307.888427 -52.3853)
			(xy 307.903783 -52.437597) (xy 307.91154 -52.491547) (xy 307.91154 -52.546053) (xy 307.905595 -52.587398)
			(xy 308.955184 -52.587398) (xy 308.959255 -52.531776) (xy 308.971381 -52.477339) (xy 308.991304 -52.425248)
			(xy 309.0186 -52.376613) (xy 309.052686 -52.33247) (xy 309.092835 -52.293761) (xy 309.138193 -52.26131)
			(xy 309.187793 -52.235809) (xy 309.240577 -52.217802) (xy 309.29542 -52.207672) (xy 309.351154 -52.205635)
			(xy 309.406591 -52.211735) (xy 309.460548 -52.225841) (xy 309.511877 -52.247653) (xy 309.559483 -52.276707)
			(xy 309.602351 -52.312382) (xy 309.639568 -52.353919) (xy 309.670341 -52.400432) (xy 309.694013 -52.450929)
			(xy 309.710081 -52.504336) (xy 309.717677 -52.555952) (xy 316.783679 -52.555952) (xy 316.783679 -52.501448)
			(xy 316.791436 -52.447499) (xy 316.806792 -52.395203) (xy 316.829435 -52.345624) (xy 316.858903 -52.299773)
			(xy 316.894597 -52.258582) (xy 316.935789 -52.222891) (xy 316.981642 -52.193425) (xy 317.031221 -52.170785)
			(xy 317.083518 -52.155432) (xy 317.137468 -52.147678) (xy 317.16472 -52.147216) (xy 317.192091 -52.147666)
			(xy 317.246271 -52.155487) (xy 317.298774 -52.17098) (xy 317.348521 -52.193825) (xy 317.394487 -52.223553)
			(xy 317.415418 -52.241196) (xy 317.415672 -52.24145) (xy 317.422758 -52.247037) (xy 317.439675 -52.253282)
			(xy 317.448692 -52.253642) (xy 317.515748 -52.253642) (xy 317.524764 -52.253273) (xy 317.541682 -52.247035)
			(xy 317.548768 -52.24145) (xy 317.548768 -52.241196) (xy 317.549022 -52.241196) (xy 317.569972 -52.223579)
			(xy 317.61594 -52.193864) (xy 317.665683 -52.171024) (xy 317.71818 -52.155528) (xy 317.772352 -52.147693)
			(xy 317.79972 -52.147216) (xy 317.826972 -52.147655) (xy 317.880921 -52.155415) (xy 317.933217 -52.170772)
			(xy 317.982794 -52.193416) (xy 318.028645 -52.222885) (xy 318.069836 -52.258579) (xy 318.105527 -52.299771)
			(xy 318.134994 -52.345623) (xy 318.157635 -52.395202) (xy 318.17299 -52.447499) (xy 318.180746 -52.501448)
			(xy 318.180746 -52.555952) (xy 318.17299 -52.609901) (xy 318.157635 -52.662198) (xy 318.134994 -52.711777)
			(xy 318.105527 -52.757629) (xy 318.069836 -52.798821) (xy 318.028645 -52.834515) (xy 317.982794 -52.863984)
			(xy 317.933217 -52.886628) (xy 317.880921 -52.901985) (xy 317.826972 -52.909745) (xy 317.79972 -52.910232)
			(xy 317.772349 -52.909771) (xy 317.718169 -52.901954) (xy 317.665666 -52.886465) (xy 317.615919 -52.863622)
			(xy 317.569953 -52.833895) (xy 317.549022 -52.816252) (xy 317.548768 -52.815998) (xy 317.541666 -52.810434)
			(xy 317.524761 -52.804174) (xy 317.515748 -52.803806) (xy 317.448692 -52.803806) (xy 317.439675 -52.804158)
			(xy 317.422758 -52.810409) (xy 317.415672 -52.815998) (xy 317.415672 -52.816252) (xy 317.415418 -52.816252)
			(xy 317.394484 -52.833889) (xy 317.348512 -52.863603) (xy 317.298765 -52.88644) (xy 317.246265 -52.901931)
			(xy 317.192089 -52.909759) (xy 317.16472 -52.910232) (xy 317.137468 -52.909722) (xy 317.083518 -52.901968)
			(xy 317.031221 -52.886615) (xy 316.981642 -52.863975) (xy 316.935789 -52.834509) (xy 316.894597 -52.798818)
			(xy 316.858903 -52.757627) (xy 316.829435 -52.711776) (xy 316.806792 -52.662197) (xy 316.791436 -52.609901)
			(xy 316.783679 -52.555952) (xy 309.717677 -52.555952) (xy 309.718201 -52.559512) (xy 309.71871 -52.587398)
			(xy 309.718201 -52.615284) (xy 309.710081 -52.67046) (xy 309.694013 -52.723867) (xy 309.670341 -52.774364)
			(xy 309.639568 -52.820877) (xy 309.602351 -52.862414) (xy 309.559483 -52.898089) (xy 309.511877 -52.927143)
			(xy 309.460548 -52.948955) (xy 309.406591 -52.963061) (xy 309.351154 -52.969161) (xy 309.29542 -52.967124)
			(xy 309.240577 -52.956994) (xy 309.187793 -52.938987) (xy 309.138193 -52.913486) (xy 309.092835 -52.881035)
			(xy 309.052686 -52.842326) (xy 309.0186 -52.798183) (xy 308.991304 -52.749548) (xy 308.971381 -52.697457)
			(xy 308.959255 -52.64302) (xy 308.955184 -52.587398) (xy 307.905595 -52.587398) (xy 307.903783 -52.600003)
			(xy 307.888427 -52.6523) (xy 307.865785 -52.70188) (xy 307.836318 -52.747732) (xy 307.800624 -52.788924)
			(xy 307.759432 -52.824618) (xy 307.71358 -52.854085) (xy 307.664 -52.876727) (xy 307.611703 -52.892083)
			(xy 307.557753 -52.89984) (xy 307.5305 -52.900326) (xy 307.503129 -52.899878) (xy 307.448948 -52.892059)
			(xy 307.396444 -52.876566) (xy 307.346698 -52.85372) (xy 307.300732 -52.82399) (xy 307.279802 -52.806346)
			(xy 307.279548 -52.806092) (xy 307.272453 -52.800518) (xy 307.255543 -52.794264) (xy 307.246528 -52.7939)
			(xy 307.179472 -52.7939) (xy 307.170454 -52.794244) (xy 307.153537 -52.800501) (xy 307.146452 -52.806092)
			(xy 307.146198 -52.806346) (xy 307.125265 -52.823987) (xy 307.079297 -52.853711) (xy 307.029551 -52.876557)
			(xy 306.977049 -52.892053) (xy 306.922871 -52.899882) (xy 306.868129 -52.899882) (xy 306.813951 -52.892053)
			(xy 306.761449 -52.876557) (xy 306.711703 -52.853711) (xy 306.665735 -52.823987) (xy 306.644802 -52.806346)
			(xy 306.644548 -52.806092) (xy 306.637453 -52.800518) (xy 306.620543 -52.794264) (xy 306.611528 -52.7939)
			(xy 306.544472 -52.7939) (xy 306.535454 -52.794244) (xy 306.518537 -52.800501) (xy 306.511452 -52.806092)
			(xy 306.511452 -52.806346) (xy 306.511198 -52.806346) (xy 306.490271 -52.823991) (xy 306.444297 -52.853704)
			(xy 306.394549 -52.87654) (xy 306.342047 -52.892029) (xy 306.28787 -52.899854) (xy 306.2605 -52.900326)
			(xy 306.23325 -52.899804) (xy 306.179305 -52.892048) (xy 306.127013 -52.876693) (xy 306.077438 -52.854053)
			(xy 306.03159 -52.824588) (xy 305.990401 -52.788899) (xy 305.954712 -52.74771) (xy 305.925247 -52.701862)
			(xy 305.902607 -52.652287) (xy 305.887252 -52.599995) (xy 305.879496 -52.54605) (xy 300.930442 -52.54605)
			(xy 300.940915 -52.550833) (xy 300.986765 -52.580299) (xy 301.027956 -52.61599) (xy 301.063647 -52.657181)
			(xy 301.093113 -52.703031) (xy 301.115755 -52.752608) (xy 301.13111 -52.804903) (xy 301.138866 -52.858851)
			(xy 301.139352 -52.886102) (xy 301.138899 -52.913473) (xy 301.13108 -52.967653) (xy 301.115588 -53.020157)
			(xy 301.092743 -53.069903) (xy 301.063015 -53.115869) (xy 301.045372 -53.1368) (xy 301.045118 -53.137054)
			(xy 301.039547 -53.144151) (xy 301.033291 -53.16106) (xy 301.032926 -53.170074) (xy 301.032926 -53.23713)
			(xy 301.033263 -53.246149) (xy 301.039524 -53.263066) (xy 301.045118 -53.27015) (xy 301.045372 -53.27015)
			(xy 301.045372 -53.270404) (xy 301.063015 -53.291335) (xy 301.092739 -53.337303) (xy 301.115585 -53.38705)
			(xy 301.131081 -53.439552) (xy 301.138909 -53.493731) (xy 301.138909 -53.548472) (xy 301.13108 -53.602651)
			(xy 301.115584 -53.655153) (xy 301.092738 -53.704899) (xy 301.063013 -53.750867) (xy 301.046442 -53.77053)
			(xy 301.410624 -53.77053) (xy 301.411155 -53.741613) (xy 301.41988 -53.684442) (xy 301.437135 -53.629243)
			(xy 301.462524 -53.577282) (xy 301.495466 -53.529747) (xy 301.535205 -53.48773) (xy 301.55769 -53.46954)
			(xy 301.566468 -53.461904) (xy 301.576668 -53.441025) (xy 301.577248 -53.429408) (xy 301.577248 -53.349652)
			(xy 301.57674 -53.338016) (xy 301.566531 -53.317105) (xy 301.55769 -53.30952) (xy 301.535214 -53.29132)
			(xy 301.495479 -53.249302) (xy 301.462539 -53.201769) (xy 301.43715 -53.149809) (xy 301.419892 -53.094613)
			(xy 301.41116 -53.037445) (xy 301.410624 -53.00853) (xy 301.411083 -52.981276) (xy 301.418837 -52.927324)
			(xy 301.434191 -52.875024) (xy 301.456832 -52.825442) (xy 301.4863 -52.779587) (xy 301.521994 -52.738393)
			(xy 301.563188 -52.702699) (xy 301.609043 -52.673231) (xy 301.658626 -52.65059) (xy 301.710926 -52.635237)
			(xy 301.764878 -52.627483) (xy 301.792132 -52.627022) (xy 301.818447 -52.627461) (xy 301.870577 -52.634701)
			(xy 301.921221 -52.649025) (xy 301.96942 -52.670163) (xy 302.014262 -52.697714) (xy 302.0549 -52.731158)
			(xy 302.073056 -52.750212) (xy 302.08059 -52.757598) (xy 302.099861 -52.766131) (xy 302.110394 -52.766722)
			(xy 302.18507 -52.766722) (xy 302.195618 -52.766183) (xy 302.214913 -52.757654) (xy 302.222408 -52.750212)
			(xy 302.240569 -52.731162) (xy 302.281197 -52.697704) (xy 302.326036 -52.670144) (xy 302.374236 -52.649004)
			(xy 302.424883 -52.634686) (xy 302.477016 -52.627461) (xy 302.503332 -52.627022) (xy 302.530585 -52.627448)
			(xy 302.584537 -52.63521) (xy 302.636835 -52.65057) (xy 302.686414 -52.673218) (xy 302.732266 -52.70269)
			(xy 302.773456 -52.738388) (xy 302.809147 -52.779584) (xy 302.838612 -52.825441) (xy 302.861251 -52.875024)
			(xy 302.876603 -52.927324) (xy 302.884356 -52.981277) (xy 302.88484 -53.00853) (xy 302.884379 -53.036197)
			(xy 302.882148 -53.051456) (xy 311.141108 -53.051456) (xy 311.145179 -52.995834) (xy 311.157305 -52.941397)
			(xy 311.177228 -52.889306) (xy 311.204524 -52.840671) (xy 311.23861 -52.796528) (xy 311.278759 -52.757819)
			(xy 311.324117 -52.725368) (xy 311.373717 -52.699867) (xy 311.426501 -52.68186) (xy 311.481344 -52.67173)
			(xy 311.537078 -52.669693) (xy 311.592515 -52.675793) (xy 311.646472 -52.689899) (xy 311.697801 -52.711711)
			(xy 311.745407 -52.740765) (xy 311.788275 -52.77644) (xy 311.825492 -52.817977) (xy 311.856265 -52.86449)
			(xy 311.879937 -52.914987) (xy 311.896005 -52.968394) (xy 311.904125 -53.02357) (xy 311.904634 -53.051456)
			(xy 311.904125 -53.079342) (xy 311.896005 -53.134518) (xy 311.879937 -53.187925) (xy 311.856265 -53.238422)
			(xy 311.825492 -53.284935) (xy 311.788275 -53.326472) (xy 311.745407 -53.362147) (xy 311.697801 -53.391201)
			(xy 311.646472 -53.413013) (xy 311.592515 -53.427119) (xy 311.537078 -53.433219) (xy 311.481344 -53.431182)
			(xy 311.426501 -53.421052) (xy 311.373717 -53.403045) (xy 311.324117 -53.377544) (xy 311.278759 -53.345093)
			(xy 311.23861 -53.306384) (xy 311.204524 -53.262241) (xy 311.177228 -53.213606) (xy 311.157305 -53.161515)
			(xy 311.145179 -53.107078) (xy 311.141108 -53.051456) (xy 302.882148 -53.051456) (xy 302.876374 -53.09095)
			(xy 302.86055 -53.143974) (xy 302.83724 -53.194159) (xy 302.80693 -53.240454) (xy 302.770256 -53.28189)
			(xy 302.727985 -53.317599) (xy 302.704754 -53.332634) (xy 302.695064 -53.339255) (xy 302.682626 -53.359128)
			(xy 302.680878 -53.370734) (xy 302.673004 -53.450744) (xy 302.672366 -53.462382) (xy 302.680452 -53.484219)
			(xy 302.688498 -53.492654) (xy 302.688752 -53.492908) (xy 302.70731 -53.511012) (xy 302.739893 -53.551338)
			(xy 302.76671 -53.595707) (xy 302.787267 -53.643301) (xy 302.801185 -53.693242) (xy 302.808206 -53.744608)
			(xy 302.80864 -53.77053) (xy 302.80815 -53.797781) (xy 302.80039 -53.851726) (xy 302.785033 -53.904019)
			(xy 302.762391 -53.953594) (xy 302.732924 -53.999443) (xy 302.697234 -54.040632) (xy 302.656045 -54.076323)
			(xy 302.610196 -54.10579) (xy 302.560621 -54.128432) (xy 302.508328 -54.14379) (xy 302.454383 -54.15155)
			(xy 302.427132 -54.152038) (xy 302.399762 -54.151568) (xy 302.345582 -54.143754) (xy 302.293079 -54.128266)
			(xy 302.243332 -54.105425) (xy 302.197365 -54.0757) (xy 302.176434 -54.058058) (xy 302.17618 -54.057804)
			(xy 302.169103 -54.052203) (xy 302.152179 -54.045965) (xy 302.14316 -54.045612) (xy 302.076104 -54.045612)
			(xy 302.067087 -54.045968) (xy 302.05017 -54.052216) (xy 302.043084 -54.057804) (xy 302.043084 -54.058058)
			(xy 302.04283 -54.058058) (xy 302.021892 -54.07569) (xy 301.975922 -54.105404) (xy 301.926176 -54.128242)
			(xy 301.873676 -54.143735) (xy 301.819501 -54.151564) (xy 301.792132 -54.152038) (xy 301.764881 -54.151515)
			(xy 301.710934 -54.143763) (xy 301.658639 -54.128413) (xy 301.609061 -54.105776) (xy 301.563209 -54.076314)
			(xy 301.522017 -54.040627) (xy 301.486323 -53.99944) (xy 301.456854 -53.953593) (xy 301.434209 -53.904019)
			(xy 301.41885 -53.851727) (xy 301.411089 -53.797781) (xy 301.410624 -53.77053) (xy 301.046442 -53.77053)
			(xy 301.045372 -53.7718) (xy 301.045118 -53.772054) (xy 301.039547 -53.779151) (xy 301.033291 -53.79606)
			(xy 301.032926 -53.805074) (xy 301.032926 -53.87213) (xy 301.033263 -53.881149) (xy 301.039524 -53.898066)
			(xy 301.045118 -53.90515) (xy 301.045372 -53.90515) (xy 301.045372 -53.905404) (xy 301.063015 -53.926335)
			(xy 301.092739 -53.972303) (xy 301.115585 -54.02205) (xy 301.131081 -54.074552) (xy 301.138909 -54.128731)
			(xy 301.138909 -54.183472) (xy 301.13108 -54.237651) (xy 301.115584 -54.290153) (xy 301.101791 -54.320186)
			(xy 303.330356 -54.320186) (xy 303.3308 -54.292815) (xy 303.338621 -54.238634) (xy 303.354115 -54.18613)
			(xy 303.376962 -54.136384) (xy 303.406692 -54.090418) (xy 303.424336 -54.069488) (xy 303.42459 -54.069234)
			(xy 303.430167 -54.062141) (xy 303.43642 -54.045229) (xy 303.436782 -54.036214) (xy 303.436782 -53.969158)
			(xy 303.436401 -53.960143) (xy 303.43017 -53.943226) (xy 303.42459 -53.936138) (xy 303.424336 -53.936138)
			(xy 303.424336 -53.935884) (xy 303.406728 -53.914926) (xy 303.377011 -53.868961) (xy 303.354168 -53.81922)
			(xy 303.33867 -53.766725) (xy 303.330834 -53.712554) (xy 303.330356 -53.685186) (xy 303.330842 -53.657935)
			(xy 303.338598 -53.603987) (xy 303.353953 -53.551692) (xy 303.376595 -53.502115) (xy 303.406061 -53.456265)
			(xy 303.441752 -53.415074) (xy 303.482943 -53.379383) (xy 303.528793 -53.349917) (xy 303.57837 -53.327275)
			(xy 303.630665 -53.31192) (xy 303.684613 -53.304164) (xy 303.739115 -53.304164) (xy 303.793063 -53.31192)
			(xy 303.845358 -53.327275) (xy 303.894935 -53.349917) (xy 303.940785 -53.379383) (xy 303.981976 -53.415074)
			(xy 304.017667 -53.456265) (xy 304.043557 -53.496551) (xy 316.333364 -53.496551) (xy 316.333364 -53.442049)
			(xy 316.34112 -53.388101) (xy 316.356475 -53.335806) (xy 316.379115 -53.286228) (xy 316.40858 -53.240377)
			(xy 316.444271 -53.199186) (xy 316.48546 -53.163493) (xy 316.531309 -53.134025) (xy 316.580885 -53.111382)
			(xy 316.633179 -53.096025) (xy 316.687127 -53.088265) (xy 316.714378 -53.087778) (xy 316.741749 -53.088238)
			(xy 316.795929 -53.096054) (xy 316.848433 -53.111544) (xy 316.89818 -53.134387) (xy 316.944145 -53.164115)
			(xy 316.965076 -53.181758) (xy 316.96533 -53.182012) (xy 316.972431 -53.187577) (xy 316.989337 -53.193836)
			(xy 316.99835 -53.194204) (xy 317.065406 -53.194204) (xy 317.074423 -53.193849) (xy 317.09134 -53.1876)
			(xy 317.098426 -53.182012) (xy 317.098426 -53.181758) (xy 317.09868 -53.181758) (xy 317.119603 -53.164108)
			(xy 317.165579 -53.134399) (xy 317.215329 -53.111566) (xy 317.267831 -53.096077) (xy 317.322008 -53.088251)
			(xy 317.349378 -53.087778) (xy 317.376631 -53.088268) (xy 317.430582 -53.096022) (xy 317.482881 -53.111376)
			(xy 317.532462 -53.134016) (xy 317.578316 -53.163482) (xy 317.61951 -53.199175) (xy 317.655205 -53.240366)
			(xy 317.684674 -53.286219) (xy 317.707317 -53.335799) (xy 317.722673 -53.388096) (xy 317.730431 -53.442047)
			(xy 317.730431 -53.496553) (xy 317.722673 -53.550504) (xy 317.707317 -53.602801) (xy 317.684674 -53.652381)
			(xy 317.655205 -53.698234) (xy 317.61951 -53.739425) (xy 317.578316 -53.775118) (xy 317.532462 -53.804584)
			(xy 317.482881 -53.827224) (xy 317.430582 -53.842578) (xy 317.376631 -53.850332) (xy 317.349378 -53.850794)
			(xy 317.322007 -53.850342) (xy 317.267827 -53.842521) (xy 317.215324 -53.827029) (xy 317.165578 -53.804184)
			(xy 317.119611 -53.774457) (xy 317.09868 -53.756814) (xy 317.098426 -53.75656) (xy 317.09134 -53.750973)
			(xy 317.074423 -53.744728) (xy 317.065406 -53.744368) (xy 316.99835 -53.744368) (xy 316.989336 -53.744756)
			(xy 316.97242 -53.750983) (xy 316.96533 -53.75656) (xy 316.96533 -53.756814) (xy 316.965076 -53.756814)
			(xy 316.944128 -53.774433) (xy 316.898159 -53.804147) (xy 316.848416 -53.826987) (xy 316.795919 -53.842483)
			(xy 316.741746 -53.850317) (xy 316.714378 -53.850794) (xy 316.687127 -53.850335) (xy 316.633179 -53.842575)
			(xy 316.580885 -53.827218) (xy 316.531309 -53.804575) (xy 316.48546 -53.775107) (xy 316.444271 -53.739414)
			(xy 316.40858 -53.698223) (xy 316.379115 -53.652372) (xy 316.356475 -53.602794) (xy 316.34112 -53.550499)
			(xy 316.333364 -53.496551) (xy 304.043557 -53.496551) (xy 304.047133 -53.502115) (xy 304.069775 -53.551692)
			(xy 304.08513 -53.603987) (xy 304.092886 -53.657935) (xy 304.093372 -53.685186) (xy 304.092905 -53.712556)
			(xy 304.085088 -53.766736) (xy 304.0696 -53.819239) (xy 304.046758 -53.868986) (xy 304.017033 -53.914952)
			(xy 303.999392 -53.935884) (xy 303.999138 -53.936138) (xy 303.993564 -53.943233) (xy 303.987311 -53.960144)
			(xy 303.986946 -53.969158) (xy 303.986946 -54.036214) (xy 303.987286 -54.045233) (xy 303.993544 -54.06215)
			(xy 303.999138 -54.069234) (xy 303.999392 -54.069234) (xy 303.999392 -54.069488) (xy 304.017038 -54.090415)
			(xy 304.046749 -54.136389) (xy 304.069584 -54.186138) (xy 304.085073 -54.23864) (xy 304.092899 -54.292816)
			(xy 304.093372 -54.320186) (xy 304.092886 -54.347437) (xy 304.08513 -54.401385) (xy 304.069775 -54.45368)
			(xy 304.047133 -54.503257) (xy 304.017667 -54.549107) (xy 303.981976 -54.590298) (xy 303.940785 -54.625989)
			(xy 303.894935 -54.655455) (xy 303.845358 -54.678097) (xy 303.793063 -54.693452) (xy 303.739115 -54.701208)
			(xy 303.684613 -54.701208) (xy 303.630665 -54.693452) (xy 303.57837 -54.678097) (xy 303.528793 -54.655455)
			(xy 303.482943 -54.625989) (xy 303.441752 -54.590298) (xy 303.406061 -54.549107) (xy 303.376595 -54.503257)
			(xy 303.353953 -54.45368) (xy 303.338598 -54.401385) (xy 303.330842 -54.347437) (xy 303.330356 -54.320186)
			(xy 301.101791 -54.320186) (xy 301.092738 -54.339899) (xy 301.063013 -54.385867) (xy 301.045372 -54.4068)
			(xy 301.045118 -54.407054) (xy 301.039547 -54.414151) (xy 301.033291 -54.43106) (xy 301.032926 -54.440074)
			(xy 301.032926 -54.50713) (xy 301.033263 -54.516149) (xy 301.039524 -54.533066) (xy 301.045118 -54.54015)
			(xy 301.045372 -54.54015) (xy 301.045372 -54.540404) (xy 301.063022 -54.561327) (xy 301.092733 -54.607302)
			(xy 301.115567 -54.657052) (xy 301.131056 -54.709555) (xy 301.13888 -54.763732) (xy 301.138997 -54.770528)
			(xy 304.270918 -54.770528) (xy 304.271396 -54.743158) (xy 304.27921 -54.688979) (xy 304.294696 -54.636476)
			(xy 304.317536 -54.586729) (xy 304.347258 -54.540762) (xy 304.364898 -54.51983) (xy 304.365152 -54.519576)
			(xy 304.370761 -54.512505) (xy 304.376993 -54.495576) (xy 304.377344 -54.486556) (xy 304.377344 -54.4195)
			(xy 304.376999 -54.410482) (xy 304.370744 -54.393564) (xy 304.365152 -54.38648) (xy 304.364898 -54.38648)
			(xy 304.364898 -54.386226) (xy 304.347257 -54.365295) (xy 304.317546 -54.319322) (xy 304.29471 -54.269574)
			(xy 304.279219 -54.217073) (xy 304.271392 -54.162897) (xy 304.270918 -54.135528) (xy 304.271404 -54.108277)
			(xy 304.27916 -54.054329) (xy 304.294515 -54.002034) (xy 304.317157 -53.952457) (xy 304.346623 -53.906607)
			(xy 304.382314 -53.865416) (xy 304.423505 -53.829725) (xy 304.469355 -53.800259) (xy 304.518932 -53.777617)
			(xy 304.571227 -53.762262) (xy 304.625175 -53.754506) (xy 304.679677 -53.754506) (xy 304.733625 -53.762262)
			(xy 304.78592 -53.777617) (xy 304.835497 -53.800259) (xy 304.881347 -53.829725) (xy 304.922538 -53.865416)
			(xy 304.958229 -53.906607) (xy 304.987695 -53.952457) (xy 304.99277 -53.96357) (xy 308.971948 -53.96357)
			(xy 308.976019 -53.907948) (xy 308.988145 -53.853511) (xy 309.008068 -53.80142) (xy 309.035364 -53.752785)
			(xy 309.06945 -53.708642) (xy 309.109599 -53.669933) (xy 309.154957 -53.637482) (xy 309.204557 -53.611981)
			(xy 309.257341 -53.593974) (xy 309.312184 -53.583844) (xy 309.367918 -53.581807) (xy 309.423355 -53.587907)
			(xy 309.477312 -53.602013) (xy 309.528641 -53.623825) (xy 309.576247 -53.652879) (xy 309.619115 -53.688554)
			(xy 309.656332 -53.730091) (xy 309.687105 -53.776604) (xy 309.710777 -53.827101) (xy 309.726845 -53.880508)
			(xy 309.734965 -53.935684) (xy 309.735474 -53.96357) (xy 309.734965 -53.991456) (xy 309.726845 -54.046632)
			(xy 309.710777 -54.100039) (xy 309.687105 -54.150536) (xy 309.656332 -54.197049) (xy 309.619115 -54.238586)
			(xy 309.576247 -54.274261) (xy 309.528641 -54.303315) (xy 309.477312 -54.325127) (xy 309.423355 -54.339233)
			(xy 309.367918 -54.345333) (xy 309.312184 -54.343296) (xy 309.257341 -54.333166) (xy 309.204557 -54.315159)
			(xy 309.154957 -54.289658) (xy 309.109599 -54.257207) (xy 309.06945 -54.218498) (xy 309.035364 -54.174355)
			(xy 309.008068 -54.12572) (xy 308.988145 -54.073629) (xy 308.976019 -54.019192) (xy 308.971948 -53.96357)
			(xy 304.99277 -53.96357) (xy 305.010337 -54.002034) (xy 305.025692 -54.054329) (xy 305.033448 -54.108277)
			(xy 305.033934 -54.135528) (xy 305.0335 -54.1629) (xy 305.025677 -54.217081) (xy 305.010181 -54.269585)
			(xy 304.987332 -54.319331) (xy 304.957599 -54.365296) (xy 304.939954 -54.386226) (xy 304.9397 -54.38648)
			(xy 304.934116 -54.393568) (xy 304.927868 -54.410484) (xy 304.927508 -54.4195) (xy 304.927508 -54.486556)
			(xy 304.927885 -54.495571) (xy 304.934119 -54.512488) (xy 304.9397 -54.519576) (xy 304.939954 -54.519576)
			(xy 304.939954 -54.51983) (xy 304.957567 -54.540784) (xy 304.987284 -54.58675) (xy 305.010126 -54.636492)
			(xy 305.025623 -54.688988) (xy 305.033457 -54.74316) (xy 305.033934 -54.770528) (xy 305.033448 -54.797779)
			(xy 305.025692 -54.851727) (xy 305.010337 -54.904022) (xy 304.987695 -54.953599) (xy 304.964911 -54.989051)
			(xy 314.100968 -54.989051) (xy 314.100968 -54.934549) (xy 314.108724 -54.880603) (xy 314.124078 -54.828309)
			(xy 314.146718 -54.778732) (xy 314.176182 -54.732882) (xy 314.211871 -54.691691) (xy 314.253059 -54.655999)
			(xy 314.298907 -54.626531) (xy 314.348482 -54.603888) (xy 314.400775 -54.58853) (xy 314.454721 -54.58077)
			(xy 314.481972 -54.580282) (xy 314.510063 -54.580799) (xy 314.565639 -54.589022) (xy 314.619407 -54.605309)
			(xy 314.670205 -54.629308) (xy 314.716932 -54.6605) (xy 314.758578 -54.698209) (xy 314.794241 -54.741619)
			(xy 314.809124 -54.765448) (xy 314.814458 -54.774338) (xy 314.831476 -54.78653) (xy 314.924694 -54.80685)
			(xy 314.945268 -54.802532) (xy 314.953904 -54.79669) (xy 314.977965 -54.780685) (xy 315.029897 -54.755344)
			(xy 315.085056 -54.738119) (xy 315.142181 -54.729406) (xy 315.171074 -54.728872) (xy 315.198325 -54.729379)
			(xy 315.252274 -54.737132) (xy 315.304569 -54.752484) (xy 315.354148 -54.775122) (xy 315.4 -54.804586)
			(xy 315.441193 -54.840275) (xy 315.476887 -54.881463) (xy 315.506356 -54.927311) (xy 315.529 -54.976887)
			(xy 315.544358 -55.029181) (xy 315.552117 -55.083129) (xy 315.552582 -55.11038) (xy 315.552109 -55.13775)
			(xy 315.544293 -55.191929) (xy 315.528806 -55.244432) (xy 315.505966 -55.294179) (xy 315.476243 -55.340146)
			(xy 315.458602 -55.361078) (xy 315.458348 -55.361332) (xy 315.452778 -55.368429) (xy 315.446522 -55.385338)
			(xy 315.446156 -55.394352) (xy 315.446156 -55.461408) (xy 315.446497 -55.470427) (xy 315.452755 -55.487344)
			(xy 315.458348 -55.494428) (xy 315.458602 -55.494428) (xy 315.458602 -55.494682) (xy 315.476222 -55.515631)
			(xy 315.505945 -55.561597) (xy 315.52879 -55.611341) (xy 315.544287 -55.66384) (xy 315.552116 -55.718016)
			(xy 315.552119 -55.772754) (xy 315.544293 -55.826931) (xy 315.528801 -55.879431) (xy 315.50596 -55.929177)
			(xy 315.47624 -55.975145) (xy 315.458602 -55.996078) (xy 315.458348 -55.996332) (xy 315.452778 -56.003429)
			(xy 315.446522 -56.020338) (xy 315.446156 -56.029352) (xy 315.446156 -56.096408) (xy 315.446497 -56.105427)
			(xy 315.452755 -56.122344) (xy 315.458348 -56.129428) (xy 315.458602 -56.129428) (xy 315.458602 -56.129682)
			(xy 315.476246 -56.15061) (xy 315.505957 -56.196584) (xy 315.528792 -56.246332) (xy 315.544282 -56.298834)
			(xy 315.552109 -56.353011) (xy 315.552582 -56.38038) (xy 315.552096 -56.407631) (xy 315.54434 -56.461579)
			(xy 315.528985 -56.513874) (xy 315.506343 -56.563451) (xy 315.476877 -56.609301) (xy 315.441186 -56.650492)
			(xy 315.399995 -56.686183) (xy 315.354145 -56.715649) (xy 315.304568 -56.738291) (xy 315.252273 -56.753646)
			(xy 315.198325 -56.761402) (xy 315.143823 -56.761402) (xy 315.089875 -56.753646) (xy 315.03758 -56.738291)
			(xy 314.988003 -56.715649) (xy 314.942153 -56.686183) (xy 314.900962 -56.650492) (xy 314.865271 -56.609301)
			(xy 314.835805 -56.563451) (xy 314.813163 -56.513874) (xy 314.797808 -56.461579) (xy 314.790052 -56.407631)
			(xy 314.789566 -56.38038) (xy 314.790004 -56.353009) (xy 314.797826 -56.298828) (xy 314.813321 -56.246324)
			(xy 314.836169 -56.196577) (xy 314.865901 -56.150612) (xy 314.883546 -56.129682) (xy 314.8838 -56.129428)
			(xy 314.889381 -56.122338) (xy 314.895631 -56.105424) (xy 314.895992 -56.096408) (xy 314.895992 -56.029352)
			(xy 314.895612 -56.020337) (xy 314.88938 -56.00342) (xy 314.8838 -55.996332) (xy 314.883546 -55.996332)
			(xy 314.883546 -55.996078) (xy 314.865885 -55.975162) (xy 314.836159 -55.929191) (xy 314.813314 -55.879443)
			(xy 314.797819 -55.826938) (xy 314.789991 -55.772757) (xy 314.789994 -55.718013) (xy 314.797825 -55.663833)
			(xy 314.813325 -55.611329) (xy 314.836174 -55.561582) (xy 314.865903 -55.515614) (xy 314.883546 -55.494682)
			(xy 314.8838 -55.494428) (xy 314.889381 -55.487338) (xy 314.895631 -55.470424) (xy 314.895992 -55.461408)
			(xy 314.895992 -55.394352) (xy 314.895612 -55.385337) (xy 314.88938 -55.36842) (xy 314.8838 -55.361332)
			(xy 314.883546 -55.360824) (xy 314.872599 -55.348092) (xy 314.85276 -55.320999) (xy 314.843922 -55.306722)
			(xy 314.838588 -55.297832) (xy 314.82157 -55.28564) (xy 314.728352 -55.26532) (xy 314.707778 -55.269638)
			(xy 314.699142 -55.27548) (xy 314.675067 -55.291462) (xy 314.62314 -55.316809) (xy 314.567985 -55.33404)
			(xy 314.510864 -55.342761) (xy 314.481972 -55.343298) (xy 314.454721 -55.34283) (xy 314.400775 -55.33507)
			(xy 314.348482 -55.319712) (xy 314.298907 -55.297069) (xy 314.253059 -55.267601) (xy 314.211871 -55.231909)
			(xy 314.176182 -55.190718) (xy 314.146718 -55.144868) (xy 314.124078 -55.095291) (xy 314.108724 -55.042997)
			(xy 314.100968 -54.989051) (xy 304.964911 -54.989051) (xy 304.958229 -54.999449) (xy 304.922538 -55.04064)
			(xy 304.881347 -55.076331) (xy 304.835497 -55.105797) (xy 304.78592 -55.128439) (xy 304.733625 -55.143794)
			(xy 304.679677 -55.15155) (xy 304.625175 -55.15155) (xy 304.571227 -55.143794) (xy 304.518932 -55.128439)
			(xy 304.469355 -55.105797) (xy 304.423505 -55.076331) (xy 304.382314 -55.04064) (xy 304.346623 -54.999449)
			(xy 304.317157 -54.953599) (xy 304.294515 -54.904022) (xy 304.27916 -54.851727) (xy 304.271404 -54.797779)
			(xy 304.270918 -54.770528) (xy 301.138997 -54.770528) (xy 301.139352 -54.791102) (xy 301.138866 -54.818353)
			(xy 301.13111 -54.872301) (xy 301.115755 -54.924596) (xy 301.093113 -54.974173) (xy 301.063647 -55.020023)
			(xy 301.027956 -55.061214) (xy 300.986765 -55.096905) (xy 300.940915 -55.126371) (xy 300.891338 -55.149013)
			(xy 300.839043 -55.164368) (xy 300.785095 -55.172124) (xy 300.730593 -55.172124) (xy 300.676645 -55.164368)
			(xy 300.62435 -55.149013) (xy 300.574773 -55.126371) (xy 300.528923 -55.096905) (xy 300.487732 -55.061214)
			(xy 300.452041 -55.020023) (xy 300.422575 -54.974173) (xy 300.399933 -54.924596) (xy 300.384578 -54.872301)
			(xy 300.376822 -54.818353) (xy 300.376336 -54.791102) (xy 298.478378 -54.791102) (xy 298.475286 -54.812611)
			(xy 298.459931 -54.864906) (xy 298.437289 -54.914483) (xy 298.407823 -54.960333) (xy 298.372132 -55.001524)
			(xy 298.330941 -55.037215) (xy 298.285091 -55.066681) (xy 298.235514 -55.089323) (xy 298.183219 -55.104678)
			(xy 298.129271 -55.112434) (xy 298.074769 -55.112434) (xy 298.020821 -55.104678) (xy 297.968526 -55.089323)
			(xy 297.918949 -55.066681) (xy 297.873099 -55.037215) (xy 297.831908 -55.001524) (xy 297.796217 -54.960333)
			(xy 297.766751 -54.914483) (xy 297.744109 -54.864906) (xy 297.728754 -54.812611) (xy 297.720998 -54.758663)
			(xy 297.720512 -54.731412) (xy 296.833544 -54.731412) (xy 296.833544 -55.722266) (xy 310.033922 -55.722266)
			(xy 310.037993 -55.666644) (xy 310.050119 -55.612207) (xy 310.070042 -55.560116) (xy 310.097338 -55.511481)
			(xy 310.131424 -55.467338) (xy 310.171573 -55.428629) (xy 310.216931 -55.396178) (xy 310.266531 -55.370677)
			(xy 310.319315 -55.35267) (xy 310.374158 -55.34254) (xy 310.429892 -55.340503) (xy 310.485329 -55.346603)
			(xy 310.539286 -55.360709) (xy 310.590615 -55.382521) (xy 310.638221 -55.411575) (xy 310.649367 -55.420851)
			(xy 312.424568 -55.420851) (xy 312.424568 -55.366349) (xy 312.432324 -55.312403) (xy 312.447678 -55.260109)
			(xy 312.470318 -55.210532) (xy 312.499782 -55.164682) (xy 312.535471 -55.123491) (xy 312.576659 -55.087799)
			(xy 312.622507 -55.058331) (xy 312.672082 -55.035688) (xy 312.724375 -55.02033) (xy 312.778321 -55.01257)
			(xy 312.805572 -55.012082) (xy 312.831887 -55.012507) (xy 312.884017 -55.019751) (xy 312.934661 -55.034079)
			(xy 312.982859 -55.05522) (xy 313.027702 -55.082773) (xy 313.06834 -55.116218) (xy 313.086496 -55.135272)
			(xy 313.094021 -55.14267) (xy 313.113298 -55.151197) (xy 313.123834 -55.151782) (xy 313.19851 -55.151782)
			(xy 313.209063 -55.151277) (xy 313.228358 -55.142725) (xy 313.235848 -55.135272) (xy 313.253982 -55.116195)
			(xy 313.294617 -55.082741) (xy 313.339462 -55.055185) (xy 313.387667 -55.034051) (xy 313.438318 -55.019738)
			(xy 313.490455 -55.012518) (xy 313.516772 -55.012082) (xy 313.544025 -55.012563) (xy 313.597978 -55.020317)
			(xy 313.650278 -55.03567) (xy 313.69986 -55.05831) (xy 313.745716 -55.087777) (xy 313.786911 -55.12347)
			(xy 313.822606 -55.164662) (xy 313.852076 -55.210515) (xy 313.87472 -55.260096) (xy 313.890077 -55.312395)
			(xy 313.897835 -55.366347) (xy 313.897835 -55.420853) (xy 313.890077 -55.474805) (xy 313.87472 -55.527104)
			(xy 313.852076 -55.576685) (xy 313.822606 -55.622538) (xy 313.786911 -55.66373) (xy 313.745716 -55.699423)
			(xy 313.69986 -55.72889) (xy 313.650278 -55.75153) (xy 313.597978 -55.766883) (xy 313.544025 -55.774637)
			(xy 313.516772 -55.775098) (xy 313.490457 -55.77465) (xy 313.438328 -55.767411) (xy 313.387685 -55.753088)
			(xy 313.339486 -55.731952) (xy 313.294643 -55.704403) (xy 313.254004 -55.670961) (xy 313.235848 -55.651908)
			(xy 313.228347 -55.644483) (xy 313.209051 -55.635972) (xy 313.19851 -55.635398) (xy 313.123834 -55.635398)
			(xy 313.113285 -55.635933) (xy 313.09399 -55.644464) (xy 313.086496 -55.651908) (xy 313.068337 -55.67096)
			(xy 313.027708 -55.704417) (xy 312.982868 -55.731976) (xy 312.934668 -55.753115) (xy 312.884021 -55.767433)
			(xy 312.831888 -55.774659) (xy 312.805572 -55.775098) (xy 312.778321 -55.77463) (xy 312.724375 -55.76687)
			(xy 312.672082 -55.751512) (xy 312.622507 -55.728869) (xy 312.576659 -55.699401) (xy 312.535471 -55.663709)
			(xy 312.499782 -55.622518) (xy 312.470318 -55.576668) (xy 312.447678 -55.527091) (xy 312.432324 -55.474797)
			(xy 312.424568 -55.420851) (xy 310.649367 -55.420851) (xy 310.681089 -55.44725) (xy 310.718306 -55.488787)
			(xy 310.749079 -55.5353) (xy 310.772751 -55.585797) (xy 310.788819 -55.639204) (xy 310.796939 -55.69438)
			(xy 310.797448 -55.722266) (xy 310.796939 -55.750152) (xy 310.788819 -55.805328) (xy 310.772751 -55.858735)
			(xy 310.749079 -55.909232) (xy 310.718306 -55.955745) (xy 310.681089 -55.997282) (xy 310.638221 -56.032957)
			(xy 310.590615 -56.062011) (xy 310.539286 -56.083823) (xy 310.485329 -56.097929) (xy 310.429892 -56.104029)
			(xy 310.374158 -56.101992) (xy 310.319315 -56.091862) (xy 310.266531 -56.073855) (xy 310.216931 -56.048354)
			(xy 310.171573 -56.015903) (xy 310.131424 -55.977194) (xy 310.097338 -55.933051) (xy 310.070042 -55.884416)
			(xy 310.050119 -55.832325) (xy 310.037993 -55.777888) (xy 310.033922 -55.722266) (xy 296.833544 -55.722266)
			(xy 296.833544 -56.582818) (xy 296.858781 -57.002934) (xy 305.763422 -57.002934) (xy 305.763924 -56.974842)
			(xy 305.772148 -56.919265) (xy 305.788436 -56.865495) (xy 305.812437 -56.814697) (xy 305.843631 -56.76797)
			(xy 305.881343 -56.726325) (xy 305.924757 -56.690664) (xy 305.948588 -56.675782) (xy 305.957478 -56.670448)
			(xy 305.96967 -56.65343) (xy 305.98999 -56.560212) (xy 305.985672 -56.539638) (xy 305.97983 -56.531002)
			(xy 305.963832 -56.506937) (xy 305.938488 -56.455006) (xy 305.921262 -56.399849) (xy 305.912546 -56.342724)
			(xy 305.912012 -56.313832) (xy 305.912485 -56.286579) (xy 305.920238 -56.232627) (xy 305.935591 -56.180329)
			(xy 305.958231 -56.130747) (xy 305.987698 -56.084893) (xy 306.023391 -56.043699) (xy 306.064583 -56.008005)
			(xy 306.110437 -55.978537) (xy 306.160017 -55.955895) (xy 306.212316 -55.940541) (xy 306.266267 -55.932786)
			(xy 306.29352 -55.932324) (xy 306.320891 -55.932772) (xy 306.375071 -55.940594) (xy 306.427575 -55.956087)
			(xy 306.477321 -55.978932) (xy 306.523287 -56.008661) (xy 306.544218 -56.026304) (xy 306.544472 -56.026558)
			(xy 306.551557 -56.032146) (xy 306.568475 -56.03839) (xy 306.577492 -56.03875) (xy 306.644548 -56.03875)
			(xy 306.653564 -56.038379) (xy 306.670481 -56.032142) (xy 306.677568 -56.026558) (xy 306.677568 -56.026304)
			(xy 306.677822 -56.026304) (xy 306.698755 -56.008663) (xy 306.744723 -55.978939) (xy 306.794469 -55.956093)
			(xy 306.846971 -55.940597) (xy 306.901149 -55.932768) (xy 306.955891 -55.932768) (xy 307.010069 -55.940597)
			(xy 307.062571 -55.956093) (xy 307.112317 -55.978939) (xy 307.158285 -56.008663) (xy 307.179218 -56.026304)
			(xy 307.179472 -56.026558) (xy 307.186557 -56.032146) (xy 307.203475 -56.03839) (xy 307.212492 -56.03875)
			(xy 307.279548 -56.03875) (xy 307.288564 -56.038379) (xy 307.305481 -56.032142) (xy 307.312568 -56.026558)
			(xy 307.312568 -56.026304) (xy 307.312822 -56.026304) (xy 307.333773 -56.008689) (xy 307.379741 -55.978973)
			(xy 307.429483 -55.956133) (xy 307.48198 -55.940636) (xy 307.536152 -55.932801) (xy 307.56352 -55.932324)
			(xy 307.590773 -55.932747) (xy 307.644723 -55.940507) (xy 307.697019 -55.955865) (xy 307.746598 -55.978509)
			(xy 307.79245 -56.007978) (xy 307.833641 -56.043673) (xy 307.869334 -56.084866) (xy 307.898801 -56.130719)
			(xy 307.921442 -56.180299) (xy 307.936798 -56.232597) (xy 307.944554 -56.286547) (xy 307.944554 -56.297068)
			(xy 308.286402 -56.297068) (xy 308.290473 -56.241446) (xy 308.302599 -56.187009) (xy 308.322522 -56.134918)
			(xy 308.349818 -56.086283) (xy 308.383904 -56.04214) (xy 308.424053 -56.003431) (xy 308.469411 -55.97098)
			(xy 308.519011 -55.945479) (xy 308.571795 -55.927472) (xy 308.626638 -55.917342) (xy 308.682372 -55.915305)
			(xy 308.737809 -55.921405) (xy 308.791766 -55.935511) (xy 308.843095 -55.957323) (xy 308.890701 -55.986377)
			(xy 308.933569 -56.022052) (xy 308.970786 -56.063589) (xy 309.001559 -56.110102) (xy 309.025231 -56.160599)
			(xy 309.041299 -56.214006) (xy 309.049419 -56.269182) (xy 309.049928 -56.297068) (xy 309.049419 -56.324954)
			(xy 309.041299 -56.38013) (xy 309.025231 -56.433537) (xy 309.001559 -56.484034) (xy 308.970786 -56.530547)
			(xy 308.933569 -56.572084) (xy 308.890701 -56.607759) (xy 308.843095 -56.636813) (xy 308.791766 -56.658625)
			(xy 308.737809 -56.672731) (xy 308.682372 -56.678831) (xy 308.626638 -56.676794) (xy 308.571795 -56.666664)
			(xy 308.519011 -56.648657) (xy 308.469411 -56.623156) (xy 308.424053 -56.590705) (xy 308.383904 -56.551996)
			(xy 308.349818 -56.507853) (xy 308.322522 -56.459218) (xy 308.302599 -56.407127) (xy 308.290473 -56.35269)
			(xy 308.286402 -56.297068) (xy 307.944554 -56.297068) (xy 307.944554 -56.341053) (xy 307.936798 -56.395003)
			(xy 307.921442 -56.447301) (xy 307.898801 -56.496881) (xy 307.869334 -56.542734) (xy 307.833641 -56.583927)
			(xy 307.79245 -56.619622) (xy 307.746598 -56.649091) (xy 307.697019 -56.671735) (xy 307.644723 -56.687093)
			(xy 307.590773 -56.694853) (xy 307.56352 -56.69534) (xy 307.536149 -56.694877) (xy 307.48197 -56.687061)
			(xy 307.429466 -56.671572) (xy 307.379719 -56.648729) (xy 307.333753 -56.619002) (xy 307.312822 -56.60136)
			(xy 307.312568 -56.601106) (xy 307.305466 -56.595542) (xy 307.288561 -56.589282) (xy 307.279548 -56.588914)
			(xy 307.212492 -56.588914) (xy 307.203474 -56.589264) (xy 307.186557 -56.595516) (xy 307.179472 -56.601106)
			(xy 307.179472 -56.60136) (xy 307.179218 -56.60136) (xy 307.158285 -56.619001) (xy 307.112317 -56.648725)
			(xy 307.062571 -56.671571) (xy 307.010069 -56.687067) (xy 306.955891 -56.694896) (xy 306.901149 -56.694896)
			(xy 306.846971 -56.687067) (xy 306.794469 -56.671571) (xy 306.744723 -56.648725) (xy 306.698755 -56.619001)
			(xy 306.677822 -56.60136) (xy 306.677568 -56.601106) (xy 306.670466 -56.595542) (xy 306.653561 -56.589282)
			(xy 306.644548 -56.588914) (xy 306.577492 -56.588914) (xy 306.568474 -56.589264) (xy 306.551557 -56.595516)
			(xy 306.544472 -56.601106) (xy 306.543964 -56.60136) (xy 306.531229 -56.612304) (xy 306.504138 -56.632145)
			(xy 306.489862 -56.640984) (xy 306.480972 -56.646318) (xy 306.46878 -56.663336) (xy 306.44846 -56.756554)
			(xy 306.452778 -56.777128) (xy 306.45862 -56.785764) (xy 306.474609 -56.809835) (xy 306.499954 -56.861764)
			(xy 306.517182 -56.91692) (xy 306.525901 -56.974042) (xy 306.526438 -57.002934) (xy 306.525952 -57.030185)
			(xy 306.518196 -57.084133) (xy 306.502841 -57.136428) (xy 306.480199 -57.186005) (xy 306.450733 -57.231855)
			(xy 306.415042 -57.273046) (xy 306.373851 -57.308737) (xy 306.328001 -57.338203) (xy 306.278424 -57.360845)
			(xy 306.226129 -57.3762) (xy 306.172181 -57.383956) (xy 306.117679 -57.383956) (xy 306.063731 -57.3762)
			(xy 306.011436 -57.360845) (xy 305.961859 -57.338203) (xy 305.916009 -57.308737) (xy 305.874818 -57.273046)
			(xy 305.839127 -57.231855) (xy 305.809661 -57.186005) (xy 305.787019 -57.136428) (xy 305.771664 -57.084133)
			(xy 305.763908 -57.030185) (xy 305.763422 -57.002934) (xy 296.858781 -57.002934) (xy 296.887756 -57.48528)
			(xy 314.80582 -57.48528) (xy 314.809891 -57.429658) (xy 314.822017 -57.375221) (xy 314.84194 -57.32313)
			(xy 314.869236 -57.274495) (xy 314.903322 -57.230352) (xy 314.943471 -57.191643) (xy 314.988829 -57.159192)
			(xy 315.038429 -57.133691) (xy 315.091213 -57.115684) (xy 315.146056 -57.105554) (xy 315.20179 -57.103517)
			(xy 315.257227 -57.109617) (xy 315.311184 -57.123723) (xy 315.362513 -57.145535) (xy 315.410119 -57.174589)
			(xy 315.452987 -57.210264) (xy 315.490204 -57.251801) (xy 315.520977 -57.298314) (xy 315.544649 -57.348811)
			(xy 315.560717 -57.402218) (xy 315.568837 -57.457394) (xy 315.569346 -57.48528) (xy 315.568837 -57.513166)
			(xy 315.560717 -57.568342) (xy 315.544649 -57.621749) (xy 315.520977 -57.672246) (xy 315.490204 -57.718759)
			(xy 315.452987 -57.760296) (xy 315.410119 -57.795971) (xy 315.362513 -57.825025) (xy 315.311184 -57.846837)
			(xy 315.257227 -57.860943) (xy 315.20179 -57.867043) (xy 315.146056 -57.865006) (xy 315.091213 -57.854876)
			(xy 315.038429 -57.836869) (xy 314.988829 -57.811368) (xy 314.943471 -57.778917) (xy 314.903322 -57.740208)
			(xy 314.869236 -57.696065) (xy 314.84194 -57.64743) (xy 314.822017 -57.595339) (xy 314.809891 -57.540902)
			(xy 314.80582 -57.48528) (xy 296.887756 -57.48528) (xy 296.915586 -57.948576) (xy 296.959393 -58.679334)
			(xy 306.195222 -58.679334) (xy 306.195638 -58.653018) (xy 306.202883 -58.600887) (xy 306.217211 -58.550243)
			(xy 306.238353 -58.502044) (xy 306.265909 -58.457202) (xy 306.299356 -58.416565) (xy 306.318412 -58.39841)
			(xy 306.325813 -58.390888) (xy 306.334337 -58.371608) (xy 306.334922 -58.361072) (xy 306.334922 -58.286396)
			(xy 306.334402 -58.275845) (xy 306.32586 -58.256551) (xy 306.318412 -58.249058) (xy 306.299345 -58.230913)
			(xy 306.265889 -58.190282) (xy 306.238331 -58.145439) (xy 306.217194 -58.097236) (xy 306.20288 -58.046587)
			(xy 306.195658 -57.994451) (xy 306.195222 -57.968134) (xy 306.195708 -57.940883) (xy 306.203464 -57.886935)
			(xy 306.218819 -57.83464) (xy 306.241461 -57.785063) (xy 306.270927 -57.739213) (xy 306.306618 -57.698022)
			(xy 306.347809 -57.662331) (xy 306.393659 -57.632865) (xy 306.443236 -57.610223) (xy 306.495531 -57.594868)
			(xy 306.549479 -57.587112) (xy 306.603981 -57.587112) (xy 306.657929 -57.594868) (xy 306.710224 -57.610223)
			(xy 306.759801 -57.632865) (xy 306.805651 -57.662331) (xy 306.846842 -57.698022) (xy 306.882533 -57.739213)
			(xy 306.911999 -57.785063) (xy 306.934641 -57.83464) (xy 306.949996 -57.886935) (xy 306.957752 -57.940883)
			(xy 306.958238 -57.968134) (xy 306.957813 -57.99445) (xy 306.950572 -58.046581) (xy 306.943304 -58.072274)
			(xy 310.193434 -58.072274) (xy 310.197505 -58.016652) (xy 310.209631 -57.962215) (xy 310.229554 -57.910124)
			(xy 310.25685 -57.861489) (xy 310.290936 -57.817346) (xy 310.331085 -57.778637) (xy 310.376443 -57.746186)
			(xy 310.426043 -57.720685) (xy 310.478827 -57.702678) (xy 310.53367 -57.692548) (xy 310.589404 -57.690511)
			(xy 310.644841 -57.696611) (xy 310.698798 -57.710717) (xy 310.750127 -57.732529) (xy 310.797733 -57.761583)
			(xy 310.840601 -57.797258) (xy 310.877818 -57.838795) (xy 310.908591 -57.885308) (xy 310.932263 -57.935805)
			(xy 310.948331 -57.989212) (xy 310.956451 -58.044388) (xy 310.95696 -58.072274) (xy 310.95689 -58.076084)
			(xy 315.557914 -58.076084) (xy 315.561985 -58.020462) (xy 315.574111 -57.966025) (xy 315.594034 -57.913934)
			(xy 315.62133 -57.865299) (xy 315.655416 -57.821156) (xy 315.695565 -57.782447) (xy 315.740923 -57.749996)
			(xy 315.790523 -57.724495) (xy 315.843307 -57.706488) (xy 315.89815 -57.696358) (xy 315.953884 -57.694321)
			(xy 316.009321 -57.700421) (xy 316.063278 -57.714527) (xy 316.114607 -57.736339) (xy 316.162213 -57.765393)
			(xy 316.205081 -57.801068) (xy 316.242298 -57.842605) (xy 316.258634 -57.867296) (xy 317.842898 -57.867296)
			(xy 317.846969 -57.811674) (xy 317.859095 -57.757237) (xy 317.879018 -57.705146) (xy 317.906314 -57.656511)
			(xy 317.9404 -57.612368) (xy 317.980549 -57.573659) (xy 318.025907 -57.541208) (xy 318.075507 -57.515707)
			(xy 318.128291 -57.4977) (xy 318.183134 -57.48757) (xy 318.238868 -57.485533) (xy 318.294305 -57.491633)
			(xy 318.348262 -57.505739) (xy 318.399591 -57.527551) (xy 318.447197 -57.556605) (xy 318.490065 -57.59228)
			(xy 318.527282 -57.633817) (xy 318.558055 -57.68033) (xy 318.581727 -57.730827) (xy 318.597795 -57.784234)
			(xy 318.605915 -57.83941) (xy 318.606424 -57.867296) (xy 318.605915 -57.895182) (xy 318.597795 -57.950358)
			(xy 318.581727 -58.003765) (xy 318.558055 -58.054262) (xy 318.527282 -58.100775) (xy 318.490065 -58.142312)
			(xy 318.447197 -58.177987) (xy 318.399591 -58.207041) (xy 318.348262 -58.228853) (xy 318.294305 -58.242959)
			(xy 318.238868 -58.249059) (xy 318.183134 -58.247022) (xy 318.128291 -58.236892) (xy 318.075507 -58.218885)
			(xy 318.025907 -58.193384) (xy 317.980549 -58.160933) (xy 317.9404 -58.122224) (xy 317.906314 -58.078081)
			(xy 317.879018 -58.029446) (xy 317.859095 -57.977355) (xy 317.846969 -57.922918) (xy 317.842898 -57.867296)
			(xy 316.258634 -57.867296) (xy 316.273071 -57.889118) (xy 316.296743 -57.939615) (xy 316.312811 -57.993022)
			(xy 316.320931 -58.048198) (xy 316.32144 -58.076084) (xy 316.320931 -58.10397) (xy 316.312811 -58.159146)
			(xy 316.296743 -58.212553) (xy 316.273071 -58.26305) (xy 316.242298 -58.309563) (xy 316.205081 -58.3511)
			(xy 316.162213 -58.386775) (xy 316.114607 -58.415829) (xy 316.063278 -58.437641) (xy 316.009321 -58.451747)
			(xy 315.953884 -58.457847) (xy 315.89815 -58.45581) (xy 315.843307 -58.44568) (xy 315.790523 -58.427673)
			(xy 315.740923 -58.402172) (xy 315.695565 -58.369721) (xy 315.655416 -58.331012) (xy 315.62133 -58.286869)
			(xy 315.594034 -58.238234) (xy 315.574111 -58.186143) (xy 315.561985 -58.131706) (xy 315.557914 -58.076084)
			(xy 310.95689 -58.076084) (xy 310.956451 -58.10016) (xy 310.948331 -58.155336) (xy 310.932263 -58.208743)
			(xy 310.908591 -58.25924) (xy 310.877818 -58.305753) (xy 310.840601 -58.34729) (xy 310.797733 -58.382965)
			(xy 310.750127 -58.412019) (xy 310.698798 -58.433831) (xy 310.644841 -58.447937) (xy 310.589404 -58.454037)
			(xy 310.53367 -58.452) (xy 310.478827 -58.44187) (xy 310.426043 -58.423863) (xy 310.376443 -58.398362)
			(xy 310.331085 -58.365911) (xy 310.290936 -58.327202) (xy 310.25685 -58.283059) (xy 310.229554 -58.234424)
			(xy 310.209631 -58.182333) (xy 310.197505 -58.127896) (xy 310.193434 -58.072274) (xy 306.943304 -58.072274)
			(xy 306.936246 -58.097225) (xy 306.915106 -58.145424) (xy 306.887551 -58.190267) (xy 306.854104 -58.230904)
			(xy 306.835048 -58.249058) (xy 306.82767 -58.2566) (xy 306.819131 -58.275864) (xy 306.818538 -58.286396)
			(xy 306.818538 -58.361072) (xy 306.819058 -58.371623) (xy 306.827598 -58.390919) (xy 306.835048 -58.39841)
			(xy 306.854111 -58.416558) (xy 306.887565 -58.457191) (xy 306.915122 -58.502033) (xy 306.936259 -58.550235)
			(xy 306.939365 -58.561224) (xy 316.762128 -58.561224) (xy 316.766199 -58.505602) (xy 316.778325 -58.451165)
			(xy 316.798248 -58.399074) (xy 316.825544 -58.350439) (xy 316.85963 -58.306296) (xy 316.899779 -58.267587)
			(xy 316.945137 -58.235136) (xy 316.994737 -58.209635) (xy 317.047521 -58.191628) (xy 317.102364 -58.181498)
			(xy 317.158098 -58.179461) (xy 317.213535 -58.185561) (xy 317.267492 -58.199667) (xy 317.318821 -58.221479)
			(xy 317.366427 -58.250533) (xy 317.409295 -58.286208) (xy 317.446512 -58.327745) (xy 317.477285 -58.374258)
			(xy 317.500957 -58.424755) (xy 317.508467 -58.449718) (xy 319.008758 -58.449718) (xy 319.012829 -58.394096)
			(xy 319.024955 -58.339659) (xy 319.044878 -58.287568) (xy 319.072174 -58.238933) (xy 319.10626 -58.19479)
			(xy 319.146409 -58.156081) (xy 319.191767 -58.12363) (xy 319.241367 -58.098129) (xy 319.294151 -58.080122)
			(xy 319.348994 -58.069992) (xy 319.404728 -58.067955) (xy 319.460165 -58.074055) (xy 319.514122 -58.088161)
			(xy 319.565451 -58.109973) (xy 319.613057 -58.139027) (xy 319.655925 -58.174702) (xy 319.693142 -58.216239)
			(xy 319.723915 -58.262752) (xy 319.747587 -58.313249) (xy 319.763655 -58.366656) (xy 319.771775 -58.421832)
			(xy 319.772284 -58.449718) (xy 319.771775 -58.477604) (xy 319.763655 -58.53278) (xy 319.747587 -58.586187)
			(xy 319.723915 -58.636684) (xy 319.693142 -58.683197) (xy 319.655925 -58.724734) (xy 319.613057 -58.760409)
			(xy 319.565451 -58.789463) (xy 319.514122 -58.811275) (xy 319.460165 -58.825381) (xy 319.404728 -58.831481)
			(xy 319.348994 -58.829444) (xy 319.294151 -58.819314) (xy 319.241367 -58.801307) (xy 319.191767 -58.775806)
			(xy 319.146409 -58.743355) (xy 319.10626 -58.704646) (xy 319.072174 -58.660503) (xy 319.044878 -58.611868)
			(xy 319.024955 -58.559777) (xy 319.012829 -58.50534) (xy 319.008758 -58.449718) (xy 317.508467 -58.449718)
			(xy 317.517025 -58.478162) (xy 317.525145 -58.533338) (xy 317.525654 -58.561224) (xy 317.525145 -58.58911)
			(xy 317.517025 -58.644286) (xy 317.500957 -58.697693) (xy 317.477285 -58.74819) (xy 317.446512 -58.794703)
			(xy 317.409295 -58.83624) (xy 317.366427 -58.871915) (xy 317.318821 -58.900969) (xy 317.267492 -58.922781)
			(xy 317.213535 -58.936887) (xy 317.158098 -58.942987) (xy 317.102364 -58.94095) (xy 317.047521 -58.93082)
			(xy 316.994737 -58.912813) (xy 316.945137 -58.887312) (xy 316.899779 -58.854861) (xy 316.85963 -58.816152)
			(xy 316.825544 -58.772009) (xy 316.798248 -58.723374) (xy 316.778325 -58.671283) (xy 316.766199 -58.616846)
			(xy 316.762128 -58.561224) (xy 306.939365 -58.561224) (xy 306.950575 -58.600883) (xy 306.9578 -58.653018)
			(xy 306.958238 -58.679334) (xy 306.957752 -58.706585) (xy 306.949996 -58.760533) (xy 306.934641 -58.812828)
			(xy 306.911999 -58.862405) (xy 306.882533 -58.908255) (xy 306.846842 -58.949446) (xy 306.805651 -58.985137)
			(xy 306.759801 -59.014603) (xy 306.710224 -59.037245) (xy 306.657929 -59.0526) (xy 306.603981 -59.060356)
			(xy 306.549479 -59.060356) (xy 306.495531 -59.0526) (xy 306.443236 -59.037245) (xy 306.393659 -59.014603)
			(xy 306.347809 -58.985137) (xy 306.306618 -58.949446) (xy 306.270927 -58.908255) (xy 306.241461 -58.862405)
			(xy 306.218819 -58.812828) (xy 306.203464 -58.760533) (xy 306.195708 -58.706585) (xy 306.195222 -58.679334)
			(xy 296.959393 -58.679334) (xy 296.961814 -58.71972) (xy 296.962774 -58.72898) (xy 296.970464 -58.745918)
			(xy 296.9768 -58.75274) (xy 297.398694 -59.174634) (xy 315.292992 -59.174634) (xy 315.297063 -59.119012)
			(xy 315.309189 -59.064575) (xy 315.329112 -59.012484) (xy 315.356408 -58.963849) (xy 315.390494 -58.919706)
			(xy 315.430643 -58.880997) (xy 315.476001 -58.848546) (xy 315.525601 -58.823045) (xy 315.578385 -58.805038)
			(xy 315.633228 -58.794908) (xy 315.688962 -58.792871) (xy 315.744399 -58.798971) (xy 315.798356 -58.813077)
			(xy 315.849685 -58.834889) (xy 315.897291 -58.863943) (xy 315.940159 -58.899618) (xy 315.977376 -58.941155)
			(xy 316.008149 -58.987668) (xy 316.031821 -59.038165) (xy 316.047889 -59.091572) (xy 316.056009 -59.146748)
			(xy 316.056518 -59.174634) (xy 316.056009 -59.20252) (xy 316.047889 -59.257696) (xy 316.031821 -59.311103)
			(xy 316.008149 -59.3616) (xy 315.977376 -59.408113) (xy 315.940159 -59.44965) (xy 315.897291 -59.485325)
			(xy 315.849685 -59.514379) (xy 315.798356 -59.536191) (xy 315.744399 -59.550297) (xy 315.688962 -59.556397)
			(xy 315.633228 -59.55436) (xy 315.578385 -59.54423) (xy 315.525601 -59.526223) (xy 315.476001 -59.500722)
			(xy 315.430643 -59.468271) (xy 315.390494 -59.429562) (xy 315.356408 -59.385419) (xy 315.329112 -59.336784)
			(xy 315.309189 -59.284693) (xy 315.297063 -59.230256) (xy 315.292992 -59.174634) (xy 297.398694 -59.174634)
			(xy 298.24331 -60.01925) (xy 306.335684 -60.01925) (xy 306.335684 -59.96475) (xy 306.34344 -59.910804)
			(xy 306.358794 -59.858512) (xy 306.381433 -59.808936) (xy 306.410898 -59.763087) (xy 306.446587 -59.721898)
			(xy 306.487775 -59.686207) (xy 306.533622 -59.656741) (xy 306.583197 -59.634099) (xy 306.635489 -59.618743)
			(xy 306.689434 -59.610985) (xy 306.716684 -59.610498) (xy 306.744054 -59.610974) (xy 306.798233 -59.618789)
			(xy 306.850736 -59.634276) (xy 306.900483 -59.657116) (xy 306.94645 -59.686838) (xy 306.967382 -59.704478)
			(xy 306.967636 -59.704732) (xy 306.974734 -59.710301) (xy 306.991642 -59.716557) (xy 307.000656 -59.716924)
			(xy 307.067712 -59.716924) (xy 307.076729 -59.716567) (xy 307.093645 -59.710319) (xy 307.100732 -59.704732)
			(xy 307.100732 -59.704478) (xy 307.100986 -59.704478) (xy 307.121919 -59.686837) (xy 307.167887 -59.657113)
			(xy 307.217633 -59.634267) (xy 307.270135 -59.618771) (xy 307.324313 -59.610942) (xy 307.379055 -59.610942)
			(xy 307.433233 -59.618771) (xy 307.485735 -59.634267) (xy 307.535481 -59.657113) (xy 307.581449 -59.686837)
			(xy 307.602382 -59.704478) (xy 307.602636 -59.704732) (xy 307.609734 -59.710301) (xy 307.626642 -59.716557)
			(xy 307.635656 -59.716924) (xy 307.702712 -59.716924) (xy 307.711729 -59.716567) (xy 307.728645 -59.710319)
			(xy 307.735732 -59.704732) (xy 307.735732 -59.704478) (xy 307.735986 -59.704478) (xy 307.75691 -59.686829)
			(xy 307.802885 -59.657119) (xy 307.852635 -59.634285) (xy 307.905137 -59.618797) (xy 307.959314 -59.610971)
			(xy 307.986684 -59.610498) (xy 308.013938 -59.610948) (xy 308.067892 -59.618704) (xy 308.120192 -59.634058)
			(xy 308.169775 -59.6567) (xy 308.215631 -59.686168) (xy 308.256826 -59.721863) (xy 308.292522 -59.763056)
			(xy 308.321992 -59.808911) (xy 308.344636 -59.858493) (xy 308.359993 -59.910793) (xy 308.367751 -59.964746)
			(xy 308.367751 -60.019254) (xy 308.359993 -60.073207) (xy 308.344636 -60.125507) (xy 308.321992 -60.175089)
			(xy 308.292522 -60.220944) (xy 308.256826 -60.262137) (xy 308.215631 -60.297832) (xy 308.169775 -60.3273)
			(xy 308.120192 -60.349942) (xy 308.067892 -60.365296) (xy 308.013938 -60.373052) (xy 307.986684 -60.373514)
			(xy 307.959314 -60.373054) (xy 307.905134 -60.365234) (xy 307.852631 -60.349743) (xy 307.802885 -60.326901)
			(xy 307.756918 -60.297175) (xy 307.735986 -60.279534) (xy 307.735732 -60.27928) (xy 307.728642 -60.273698)
			(xy 307.711728 -60.267449) (xy 307.702712 -60.267088) (xy 307.635656 -60.267088) (xy 307.626642 -60.267474)
			(xy 307.609725 -60.273702) (xy 307.602636 -60.27928) (xy 307.602382 -60.279534) (xy 307.581449 -60.297175)
			(xy 307.535481 -60.326899) (xy 307.485735 -60.349745) (xy 307.433233 -60.365241) (xy 307.379055 -60.37307)
			(xy 307.324313 -60.37307) (xy 307.270135 -60.365241) (xy 307.217633 -60.349745) (xy 307.167887 -60.326899)
			(xy 307.121919 -60.297175) (xy 307.100986 -60.279534) (xy 307.100732 -60.27928) (xy 307.093642 -60.273698)
			(xy 307.076728 -60.267449) (xy 307.067712 -60.267088) (xy 307.000656 -60.267088) (xy 306.991642 -60.267474)
			(xy 306.974725 -60.273702) (xy 306.967636 -60.27928) (xy 306.967636 -60.279534) (xy 306.967382 -60.279534)
			(xy 306.946434 -60.297153) (xy 306.900465 -60.326867) (xy 306.850722 -60.349706) (xy 306.798225 -60.365202)
			(xy 306.744052 -60.373036) (xy 306.716684 -60.373514) (xy 306.689434 -60.373015) (xy 306.635489 -60.365257)
			(xy 306.583197 -60.349901) (xy 306.533622 -60.327259) (xy 306.487775 -60.297793) (xy 306.446587 -60.262102)
			(xy 306.410898 -60.220913) (xy 306.381433 -60.175064) (xy 306.358794 -60.125488) (xy 306.34344 -60.073196)
			(xy 306.335684 -60.01925) (xy 298.24331 -60.01925) (xy 298.857416 -60.633356) (xy 317.996822 -60.633356)
			(xy 318.000893 -60.577734) (xy 318.013019 -60.523297) (xy 318.032942 -60.471206) (xy 318.060238 -60.422571)
			(xy 318.094324 -60.378428) (xy 318.134473 -60.339719) (xy 318.179831 -60.307268) (xy 318.229431 -60.281767)
			(xy 318.282215 -60.26376) (xy 318.337058 -60.25363) (xy 318.392792 -60.251593) (xy 318.448229 -60.257693)
			(xy 318.502186 -60.271799) (xy 318.553515 -60.293611) (xy 318.601121 -60.322665) (xy 318.643989 -60.35834)
			(xy 318.681206 -60.399877) (xy 318.711979 -60.44639) (xy 318.735651 -60.496887) (xy 318.751719 -60.550294)
			(xy 318.759839 -60.60547) (xy 318.760348 -60.633356) (xy 318.759839 -60.661242) (xy 318.751719 -60.716418)
			(xy 318.735651 -60.769825) (xy 318.711979 -60.820322) (xy 318.681206 -60.866835) (xy 318.643989 -60.908372)
			(xy 318.601121 -60.944047) (xy 318.553515 -60.973101) (xy 318.502186 -60.994913) (xy 318.448229 -61.009019)
			(xy 318.392792 -61.015119) (xy 318.337058 -61.013082) (xy 318.282215 -61.002952) (xy 318.229431 -60.984945)
			(xy 318.179831 -60.959444) (xy 318.134473 -60.926993) (xy 318.094324 -60.888284) (xy 318.060238 -60.844141)
			(xy 318.032942 -60.795506) (xy 318.013019 -60.743415) (xy 318.000893 -60.688978) (xy 317.996822 -60.633356)
			(xy 298.857416 -60.633356) (xy 299.711872 -61.487812) (xy 316.504318 -61.487812) (xy 316.508389 -61.43219)
			(xy 316.520515 -61.377753) (xy 316.540438 -61.325662) (xy 316.567734 -61.277027) (xy 316.60182 -61.232884)
			(xy 316.641969 -61.194175) (xy 316.687327 -61.161724) (xy 316.736927 -61.136223) (xy 316.789711 -61.118216)
			(xy 316.844554 -61.108086) (xy 316.900288 -61.106049) (xy 316.955725 -61.112149) (xy 317.009682 -61.126255)
			(xy 317.061011 -61.148067) (xy 317.108617 -61.177121) (xy 317.151485 -61.212796) (xy 317.188702 -61.254333)
			(xy 317.219475 -61.300846) (xy 317.243147 -61.351343) (xy 317.259215 -61.40475) (xy 317.267335 -61.459926)
			(xy 317.267844 -61.487812) (xy 317.267335 -61.515698) (xy 317.259215 -61.570874) (xy 317.243147 -61.624281)
			(xy 317.219475 -61.674778) (xy 317.188702 -61.721291) (xy 317.151485 -61.762828) (xy 317.108617 -61.798503)
			(xy 317.061011 -61.827557) (xy 317.009682 -61.849369) (xy 316.955725 -61.863475) (xy 316.900288 -61.869575)
			(xy 316.844554 -61.867538) (xy 316.789711 -61.857408) (xy 316.736927 -61.839401) (xy 316.687327 -61.8139)
			(xy 316.641969 -61.781449) (xy 316.60182 -61.74274) (xy 316.567734 -61.698597) (xy 316.540438 -61.649962)
			(xy 316.520515 -61.597871) (xy 316.508389 -61.543434) (xy 316.504318 -61.487812) (xy 299.711872 -61.487812)
			(xy 300.345094 -62.121034) (xy 314.442092 -62.121034) (xy 314.446163 -62.065412) (xy 314.458289 -62.010975)
			(xy 314.478212 -61.958884) (xy 314.505508 -61.910249) (xy 314.539594 -61.866106) (xy 314.579743 -61.827397)
			(xy 314.625101 -61.794946) (xy 314.674701 -61.769445) (xy 314.727485 -61.751438) (xy 314.782328 -61.741308)
			(xy 314.838062 -61.739271) (xy 314.893499 -61.745371) (xy 314.947456 -61.759477) (xy 314.998785 -61.781289)
			(xy 315.046391 -61.810343) (xy 315.089259 -61.846018) (xy 315.126476 -61.887555) (xy 315.157249 -61.934068)
			(xy 315.180921 -61.984565) (xy 315.196989 -62.037972) (xy 315.205109 -62.093148) (xy 315.205618 -62.121034)
			(xy 315.205109 -62.14892) (xy 315.196989 -62.204096) (xy 315.180921 -62.257503) (xy 315.157249 -62.308)
			(xy 315.126476 -62.354513) (xy 315.089259 -62.39605) (xy 315.046391 -62.431725) (xy 314.998785 -62.460779)
			(xy 314.947456 -62.482591) (xy 314.893499 -62.496697) (xy 314.838062 -62.502797) (xy 314.782328 -62.50076)
			(xy 314.727485 -62.49063) (xy 314.674701 -62.472623) (xy 314.625101 -62.447122) (xy 314.579743 -62.414671)
			(xy 314.539594 -62.375962) (xy 314.505508 -62.331819) (xy 314.478212 -62.283184) (xy 314.458289 -62.231093)
			(xy 314.446163 -62.176656) (xy 314.442092 -62.121034) (xy 300.345094 -62.121034) (xy 301.59833 -63.37427)
			(xy 301.605729 -63.381115) (xy 301.624327 -63.388843) (xy 301.634398 -63.389256) (xy 306.266088 -63.389256)
			(xy 306.272438 -63.382652) (xy 306.284884 -63.36665) (xy 306.284884 -63.366142) (xy 306.294282 -63.354458)
			(xy 306.30114 -63.343028) (xy 306.302156 -63.340996) (xy 306.303172 -63.337948) (xy 306.30483 -63.33226)
			(xy 306.305737 -63.320451) (xy 306.30495 -63.31458) (xy 306.303934 -63.307468) (xy 306.302918 -63.303912)
			(xy 306.294969 -63.275228) (xy 306.286426 -63.216324) (xy 306.2859 -63.186564) (xy 306.2859 -63.18631)
			(xy 306.286404 -63.156607) (xy 306.294857 -63.097806) (xy 306.311592 -63.040806) (xy 306.33627 -62.986768)
			(xy 306.368386 -62.936793) (xy 306.407288 -62.891896) (xy 306.452183 -62.852993) (xy 306.502158 -62.820875)
			(xy 306.556195 -62.796197) (xy 306.613194 -62.77946) (xy 306.671995 -62.771005) (xy 306.701698 -62.770512)
			(xy 306.730162 -62.770976) (xy 306.786561 -62.77873) (xy 306.841377 -62.794093) (xy 306.893591 -62.816778)
			(xy 306.942228 -62.846365) (xy 306.964588 -62.863984) (xy 306.971192 -62.869318) (xy 306.996084 -62.878716)
			(xy 307.000153 -62.880015) (xy 307.008578 -62.881419) (xy 307.012848 -62.88151) (xy 307.025548 -62.88151)
			(xy 307.029821 -62.881451) (xy 307.038251 -62.880047) (xy 307.042312 -62.878716) (xy 307.067204 -62.869318)
			(xy 307.073808 -62.863984) (xy 307.096151 -62.846384) (xy 307.144735 -62.816807) (xy 307.196895 -62.794127)
			(xy 307.251659 -62.778764) (xy 307.308005 -62.771007) (xy 307.336444 -62.770512) (xy 307.336698 -62.770512)
			(xy 307.368208 -62.771092) (xy 307.430508 -62.780588) (xy 307.490666 -62.799364) (xy 307.547308 -62.826992)
			(xy 307.599139 -62.862839) (xy 307.622448 -62.88405) (xy 307.623464 -62.885066) (xy 307.63718 -62.897766)
			(xy 307.64421 -62.903325) (xy 307.660993 -62.909576) (xy 307.669946 -62.909958) (xy 307.684424 -62.909958)
			(xy 307.693314 -62.909196) (xy 307.706014 -62.90691) (xy 307.706268 -62.90691) (xy 307.715412 -62.903608)
			(xy 307.722524 -62.897512) (xy 307.743401 -62.880121) (xy 307.789152 -62.85081) (xy 307.838601 -62.82829)
			(xy 307.890746 -62.813019) (xy 307.94453 -62.805305) (xy 307.971698 -62.804802) (xy 307.998788 -62.805277)
			(xy 308.052422 -62.812942) (xy 308.104432 -62.828118) (xy 308.153772 -62.850499) (xy 308.19945 -62.879636)
			(xy 308.240545 -62.914943) (xy 308.276232 -62.955708) (xy 308.305793 -63.001113) (xy 308.328633 -63.050242)
			(xy 308.339499 -63.086234) (xy 311.587386 -63.086234) (xy 311.591457 -63.030612) (xy 311.603583 -62.976175)
			(xy 311.623506 -62.924084) (xy 311.650802 -62.875449) (xy 311.684888 -62.831306) (xy 311.725037 -62.792597)
			(xy 311.770395 -62.760146) (xy 311.819995 -62.734645) (xy 311.872779 -62.716638) (xy 311.927622 -62.706508)
			(xy 311.983356 -62.704471) (xy 312.038793 -62.710571) (xy 312.09275 -62.724677) (xy 312.112913 -62.733245)
			(xy 317.865951 -62.733245) (xy 317.865952 -62.678739) (xy 317.87371 -62.624787) (xy 317.889068 -62.572488)
			(xy 317.911712 -62.522908) (xy 317.941182 -62.477054) (xy 317.976877 -62.435862) (xy 318.018072 -62.400169)
			(xy 318.063927 -62.370702) (xy 318.113509 -62.34806) (xy 318.165808 -62.332706) (xy 318.219761 -62.32495)
			(xy 318.247014 -62.324488) (xy 318.270569 -62.324865) (xy 318.317313 -62.330724) (xy 318.340232 -62.336172)
			(xy 318.353991 -62.339195) (xy 318.38214 -62.338343) (xy 318.408987 -62.329839) (xy 318.432493 -62.31433)
			(xy 318.450874 -62.292994) (xy 318.462733 -62.267451) (xy 318.46717 -62.239641) (xy 318.463847 -62.211676)
			(xy 318.45885 -62.198504) (xy 318.449539 -62.175115) (xy 318.436414 -62.126514) (xy 318.429791 -62.076609)
			(xy 318.429386 -62.051438) (xy 318.429814 -62.024182) (xy 318.437567 -61.970223) (xy 318.45292 -61.917917)
			(xy 318.475561 -61.868329) (xy 318.505029 -61.822468) (xy 318.540724 -61.781267) (xy 318.581919 -61.745566)
			(xy 318.627775 -61.71609) (xy 318.67736 -61.693442) (xy 318.729663 -61.67808) (xy 318.78362 -61.670319)
			(xy 318.838133 -61.670315) (xy 318.892091 -61.67807) (xy 318.944396 -61.693425) (xy 318.993984 -61.716068)
			(xy 319.039844 -61.745538) (xy 319.081043 -61.781234) (xy 319.116743 -61.82243) (xy 319.146217 -61.868288)
			(xy 319.168864 -61.917874) (xy 319.184223 -61.970178) (xy 319.191982 -62.024135) (xy 319.191984 -62.078648)
			(xy 319.184227 -62.132605) (xy 319.16887 -62.18491) (xy 319.146225 -62.234497) (xy 319.116754 -62.280356)
			(xy 319.081056 -62.321554) (xy 319.039858 -62.357252) (xy 318.993999 -62.386724) (xy 318.944413 -62.409369)
			(xy 318.892108 -62.424726) (xy 318.83815 -62.432483) (xy 318.810894 -62.432946) (xy 318.787339 -62.432566)
			(xy 318.740595 -62.426709) (xy 318.717676 -62.421262) (xy 318.703923 -62.4182) (xy 318.675766 -62.41905)
			(xy 318.648911 -62.427555) (xy 318.625398 -62.443069) (xy 318.607014 -62.464413) (xy 318.595156 -62.489965)
			(xy 318.590723 -62.517784) (xy 318.594055 -62.545756) (xy 318.599058 -62.55893) (xy 318.60838 -62.582315)
			(xy 318.621501 -62.630918) (xy 318.628119 -62.680825) (xy 318.628522 -62.705996) (xy 318.628049 -62.733249)
			(xy 318.620292 -62.787202) (xy 318.604936 -62.839501) (xy 318.582294 -62.889082) (xy 318.552825 -62.934936)
			(xy 318.517131 -62.97613) (xy 318.475938 -63.011824) (xy 318.430084 -63.041293) (xy 318.380502 -63.063936)
			(xy 318.328203 -63.079292) (xy 318.274251 -63.087049) (xy 318.219745 -63.087048) (xy 318.165793 -63.079291)
			(xy 318.113494 -63.063934) (xy 318.063913 -63.041291) (xy 318.018059 -63.011822) (xy 317.976866 -62.976127)
			(xy 317.941172 -62.934933) (xy 317.911704 -62.889078) (xy 317.889062 -62.839497) (xy 317.873707 -62.787198)
			(xy 317.865951 -62.733245) (xy 312.112913 -62.733245) (xy 312.144079 -62.746489) (xy 312.191685 -62.775543)
			(xy 312.234553 -62.811218) (xy 312.27177 -62.852755) (xy 312.302543 -62.899268) (xy 312.326215 -62.949765)
			(xy 312.342283 -63.003172) (xy 312.350403 -63.058348) (xy 312.350912 -63.086234) (xy 312.350403 -63.11412)
			(xy 312.342283 -63.169296) (xy 312.326215 -63.222703) (xy 312.302543 -63.2732) (xy 312.30239 -63.273432)
			(xy 313.776612 -63.273432) (xy 313.780683 -63.21781) (xy 313.792809 -63.163373) (xy 313.812732 -63.111282)
			(xy 313.840028 -63.062647) (xy 313.874114 -63.018504) (xy 313.914263 -62.979795) (xy 313.959621 -62.947344)
			(xy 314.009221 -62.921843) (xy 314.062005 -62.903836) (xy 314.116848 -62.893706) (xy 314.172582 -62.891669)
			(xy 314.228019 -62.897769) (xy 314.281976 -62.911875) (xy 314.333305 -62.933687) (xy 314.380911 -62.962741)
			(xy 314.423779 -62.998416) (xy 314.460996 -63.039953) (xy 314.491769 -63.086466) (xy 314.515441 -63.136963)
			(xy 314.531509 -63.19037) (xy 314.539629 -63.245546) (xy 314.540138 -63.273432) (xy 314.539629 -63.301318)
			(xy 314.531509 -63.356494) (xy 314.515441 -63.409901) (xy 314.491769 -63.460398) (xy 314.460996 -63.506911)
			(xy 314.423779 -63.548448) (xy 314.380911 -63.584123) (xy 314.333305 -63.613177) (xy 314.281976 -63.634989)
			(xy 314.228019 -63.649095) (xy 314.172582 -63.655195) (xy 314.116848 -63.653158) (xy 314.062005 -63.643028)
			(xy 314.009221 -63.625021) (xy 313.959621 -63.59952) (xy 313.914263 -63.567069) (xy 313.874114 -63.52836)
			(xy 313.840028 -63.484217) (xy 313.812732 -63.435582) (xy 313.792809 -63.383491) (xy 313.780683 -63.329054)
			(xy 313.776612 -63.273432) (xy 312.30239 -63.273432) (xy 312.27177 -63.319713) (xy 312.234553 -63.36125)
			(xy 312.191685 -63.396925) (xy 312.144079 -63.425979) (xy 312.09275 -63.447791) (xy 312.038793 -63.461897)
			(xy 311.983356 -63.467997) (xy 311.927622 -63.46596) (xy 311.872779 -63.45583) (xy 311.819995 -63.437823)
			(xy 311.770395 -63.412322) (xy 311.725037 -63.379871) (xy 311.684888 -63.341162) (xy 311.650802 -63.297019)
			(xy 311.623506 -63.248384) (xy 311.603583 -63.196293) (xy 311.591457 -63.141856) (xy 311.587386 -63.086234)
			(xy 308.339499 -63.086234) (xy 308.344292 -63.102109) (xy 308.352455 -63.15567) (xy 308.353206 -63.182754)
			(xy 308.353206 -63.186564) (xy 308.352686 -63.21509) (xy 308.344155 -63.271501) (xy 308.327309 -63.32601)
			(xy 308.31536 -63.351918) (xy 308.311804 -63.362332) (xy 308.30774 -63.379604) (xy 308.307825 -63.383548)
			(xy 308.309097 -63.391334) (xy 308.31028 -63.395098) (xy 308.319932 -63.42126) (xy 308.319932 -63.421768)
			(xy 308.337966 -63.469266) (xy 308.341121 -63.475831) (xy 308.350541 -63.486934) (xy 308.356508 -63.49111)
			(xy 308.360318 -63.493396) (xy 308.363112 -63.494666) (xy 312.296402 -65.124076) (xy 316.307214 -65.124076)
			(xy 316.311285 -65.068454) (xy 316.323411 -65.014017) (xy 316.343334 -64.961926) (xy 316.37063 -64.913291)
			(xy 316.404716 -64.869148) (xy 316.444865 -64.830439) (xy 316.490223 -64.797988) (xy 316.539823 -64.772487)
			(xy 316.592607 -64.75448) (xy 316.64745 -64.74435) (xy 316.703184 -64.742313) (xy 316.758621 -64.748413)
			(xy 316.812578 -64.762519) (xy 316.863907 -64.784331) (xy 316.911513 -64.813385) (xy 316.954381 -64.84906)
			(xy 316.991598 -64.890597) (xy 317.022371 -64.93711) (xy 317.046043 -64.987607) (xy 317.062111 -65.041014)
			(xy 317.070231 -65.09619) (xy 317.07074 -65.124076) (xy 317.070231 -65.151962) (xy 317.062111 -65.207138)
			(xy 317.046043 -65.260545) (xy 317.022371 -65.311042) (xy 316.991598 -65.357555) (xy 316.954381 -65.399092)
			(xy 316.911513 -65.434767) (xy 316.863907 -65.463821) (xy 316.812578 -65.485633) (xy 316.758621 -65.499739)
			(xy 316.703184 -65.505839) (xy 316.64745 -65.503802) (xy 316.592607 -65.493672) (xy 316.539823 -65.475665)
			(xy 316.490223 -65.450164) (xy 316.444865 -65.417713) (xy 316.404716 -65.379004) (xy 316.37063 -65.334861)
			(xy 316.343334 -65.286226) (xy 316.323411 -65.234135) (xy 316.311285 -65.179698) (xy 316.307214 -65.124076)
			(xy 312.296402 -65.124076) (xy 313.820667 -65.75552) (xy 324.546466 -65.75552) (xy 324.550537 -65.699898)
			(xy 324.562663 -65.645461) (xy 324.582586 -65.59337) (xy 324.609882 -65.544735) (xy 324.643968 -65.500592)
			(xy 324.684117 -65.461883) (xy 324.729475 -65.429432) (xy 324.779075 -65.403931) (xy 324.831859 -65.385924)
			(xy 324.886702 -65.375794) (xy 324.942436 -65.373757) (xy 324.997873 -65.379857) (xy 325.05183 -65.393963)
			(xy 325.103159 -65.415775) (xy 325.150765 -65.444829) (xy 325.193633 -65.480504) (xy 325.23085 -65.522041)
			(xy 325.261623 -65.568554) (xy 325.285295 -65.619051) (xy 325.301363 -65.672458) (xy 325.309483 -65.727634)
			(xy 325.309992 -65.75552) (xy 325.309483 -65.783406) (xy 325.301363 -65.838582) (xy 325.285295 -65.891989)
			(xy 325.261623 -65.942486) (xy 325.23085 -65.988999) (xy 325.193633 -66.030536) (xy 325.150765 -66.066211)
			(xy 325.103159 -66.095265) (xy 325.05183 -66.117077) (xy 324.997873 -66.131183) (xy 324.942436 -66.137283)
			(xy 324.886702 -66.135246) (xy 324.831859 -66.125116) (xy 324.779075 -66.107109) (xy 324.729475 -66.081608)
			(xy 324.684117 -66.049157) (xy 324.643968 -66.010448) (xy 324.609882 -65.966305) (xy 324.582586 -65.91767)
			(xy 324.562663 -65.865579) (xy 324.550537 -65.811142) (xy 324.546466 -65.75552) (xy 313.820667 -65.75552)
			(xy 316.23889 -66.757296) (xy 316.254697 -66.763988) (xy 316.285578 -66.778983) (xy 316.300612 -66.787268)
			(xy 316.301882 -66.787776) (xy 316.337409 -66.803117) (xy 316.40445 -66.841773) (xy 316.46586 -66.888864)
			(xy 316.493652 -66.915792) (xy 316.706813 -67.128953) (xy 324.566475 -67.128953) (xy 324.566475 -67.074447)
			(xy 324.574233 -67.020496) (xy 324.58959 -66.968198) (xy 324.612234 -66.918618) (xy 324.641703 -66.872766)
			(xy 324.677399 -66.831575) (xy 324.718593 -66.795883) (xy 324.764448 -66.766417) (xy 324.81403 -66.743778)
			(xy 324.866329 -66.728426) (xy 324.920281 -66.720673) (xy 324.947534 -66.720212) (xy 324.974905 -66.720655)
			(xy 325.029085 -66.728478) (xy 325.081589 -66.743972) (xy 325.131335 -66.766819) (xy 325.177301 -66.796549)
			(xy 325.198232 -66.814192) (xy 325.198486 -66.814446) (xy 325.205568 -66.820038) (xy 325.222489 -66.82628)
			(xy 325.231506 -66.826638) (xy 325.298562 -66.826638) (xy 325.307576 -66.826255) (xy 325.324493 -66.820024)
			(xy 325.331582 -66.814446) (xy 325.331582 -66.814192) (xy 325.331836 -66.814192) (xy 325.35278 -66.796568)
			(xy 325.39875 -66.766854) (xy 325.448494 -66.744016) (xy 325.500992 -66.728521) (xy 325.555166 -66.720688)
			(xy 325.582534 -66.720212) (xy 325.609785 -66.72066) (xy 325.663732 -66.728421) (xy 325.716025 -66.74378)
			(xy 325.765601 -66.766424) (xy 325.811449 -66.795893) (xy 325.852638 -66.831586) (xy 325.888328 -66.872778)
			(xy 325.917792 -66.918629) (xy 325.940432 -66.968207) (xy 325.955786 -67.020501) (xy 325.963542 -67.074449)
			(xy 325.963542 -67.128951) (xy 325.955786 -67.182899) (xy 325.940432 -67.235193) (xy 325.917792 -67.284771)
			(xy 325.888328 -67.330622) (xy 325.852638 -67.371814) (xy 325.811449 -67.407507) (xy 325.765601 -67.436976)
			(xy 325.716025 -67.45962) (xy 325.663732 -67.474979) (xy 325.609785 -67.48274) (xy 325.582534 -67.483228)
			(xy 325.555164 -67.48276) (xy 325.500984 -67.474945) (xy 325.44848 -67.459457) (xy 325.398733 -67.436616)
			(xy 325.352767 -67.40689) (xy 325.331836 -67.389248) (xy 325.331582 -67.388994) (xy 325.324505 -67.383393)
			(xy 325.307581 -67.377155) (xy 325.298562 -67.376802) (xy 325.231506 -67.376802) (xy 325.222489 -67.377161)
			(xy 325.205572 -67.383407) (xy 325.198486 -67.388994) (xy 325.198486 -67.389248) (xy 325.198232 -67.389248)
			(xy 325.177292 -67.406877) (xy 325.131322 -67.436593) (xy 325.081577 -67.459431) (xy 325.029078 -67.474924)
			(xy 324.974903 -67.482754) (xy 324.947534 -67.483228) (xy 324.920281 -67.482727) (xy 324.866329 -67.474974)
			(xy 324.81403 -67.459622) (xy 324.764448 -67.436983) (xy 324.718593 -67.407517) (xy 324.677399 -67.371825)
			(xy 324.641703 -67.330634) (xy 324.612234 -67.284782) (xy 324.58959 -67.235202) (xy 324.574233 -67.182904)
			(xy 324.566475 -67.128953) (xy 316.706813 -67.128953) (xy 317.065914 -67.488054) (xy 328.97902 -67.488054)
			(xy 328.983091 -67.432432) (xy 328.995217 -67.377995) (xy 329.01514 -67.325904) (xy 329.042436 -67.277269)
			(xy 329.076522 -67.233126) (xy 329.116671 -67.194417) (xy 329.162029 -67.161966) (xy 329.211629 -67.136465)
			(xy 329.264413 -67.118458) (xy 329.319256 -67.108328) (xy 329.37499 -67.106291) (xy 329.430427 -67.112391)
			(xy 329.484384 -67.126497) (xy 329.535713 -67.148309) (xy 329.583319 -67.177363) (xy 329.626187 -67.213038)
			(xy 329.663404 -67.254575) (xy 329.694177 -67.301088) (xy 329.717849 -67.351585) (xy 329.733917 -67.404992)
			(xy 329.742037 -67.460168) (xy 329.742546 -67.488054) (xy 329.742037 -67.51594) (xy 329.738852 -67.537584)
			(xy 330.271118 -67.537584) (xy 330.275189 -67.481962) (xy 330.287315 -67.427525) (xy 330.307238 -67.375434)
			(xy 330.334534 -67.326799) (xy 330.36862 -67.282656) (xy 330.408769 -67.243947) (xy 330.454127 -67.211496)
			(xy 330.503727 -67.185995) (xy 330.556511 -67.167988) (xy 330.611354 -67.157858) (xy 330.667088 -67.155821)
			(xy 330.722525 -67.161921) (xy 330.776482 -67.176027) (xy 330.827811 -67.197839) (xy 330.875417 -67.226893)
			(xy 330.918285 -67.262568) (xy 330.955502 -67.304105) (xy 330.986275 -67.350618) (xy 331.009947 -67.401115)
			(xy 331.026015 -67.454522) (xy 331.034135 -67.509698) (xy 331.034644 -67.537584) (xy 331.034135 -67.56547)
			(xy 331.03009 -67.592956) (xy 331.545182 -67.592956) (xy 331.549253 -67.537334) (xy 331.561379 -67.482897)
			(xy 331.581302 -67.430806) (xy 331.608598 -67.382171) (xy 331.642684 -67.338028) (xy 331.682833 -67.299319)
			(xy 331.728191 -67.266868) (xy 331.777791 -67.241367) (xy 331.830575 -67.22336) (xy 331.885418 -67.21323)
			(xy 331.941152 -67.211193) (xy 331.996589 -67.217293) (xy 332.050546 -67.231399) (xy 332.101875 -67.253211)
			(xy 332.149481 -67.282265) (xy 332.192349 -67.31794) (xy 332.229566 -67.359477) (xy 332.260339 -67.40599)
			(xy 332.284011 -67.456487) (xy 332.300079 -67.509894) (xy 332.308199 -67.56507) (xy 332.308708 -67.592956)
			(xy 332.308199 -67.620842) (xy 332.300079 -67.676018) (xy 332.284011 -67.729425) (xy 332.260339 -67.779922)
			(xy 332.229566 -67.826435) (xy 332.192349 -67.867972) (xy 332.149481 -67.903647) (xy 332.101875 -67.932701)
			(xy 332.050546 -67.954513) (xy 331.996589 -67.968619) (xy 331.941152 -67.974719) (xy 331.885418 -67.972682)
			(xy 331.830575 -67.962552) (xy 331.777791 -67.944545) (xy 331.728191 -67.919044) (xy 331.682833 -67.886593)
			(xy 331.642684 -67.847884) (xy 331.608598 -67.803741) (xy 331.581302 -67.755106) (xy 331.561379 -67.703015)
			(xy 331.549253 -67.648578) (xy 331.545182 -67.592956) (xy 331.03009 -67.592956) (xy 331.026015 -67.620646)
			(xy 331.009947 -67.674053) (xy 330.986275 -67.72455) (xy 330.955502 -67.771063) (xy 330.918285 -67.8126)
			(xy 330.875417 -67.848275) (xy 330.827811 -67.877329) (xy 330.776482 -67.899141) (xy 330.722525 -67.913247)
			(xy 330.667088 -67.919347) (xy 330.611354 -67.91731) (xy 330.556511 -67.90718) (xy 330.503727 -67.889173)
			(xy 330.454127 -67.863672) (xy 330.408769 -67.831221) (xy 330.36862 -67.792512) (xy 330.334534 -67.748369)
			(xy 330.307238 -67.699734) (xy 330.287315 -67.647643) (xy 330.275189 -67.593206) (xy 330.271118 -67.537584)
			(xy 329.738852 -67.537584) (xy 329.733917 -67.571116) (xy 329.717849 -67.624523) (xy 329.694177 -67.67502)
			(xy 329.663404 -67.721533) (xy 329.626187 -67.76307) (xy 329.583319 -67.798745) (xy 329.535713 -67.827799)
			(xy 329.484384 -67.849611) (xy 329.430427 -67.863717) (xy 329.37499 -67.869817) (xy 329.319256 -67.86778)
			(xy 329.264413 -67.85765) (xy 329.211629 -67.839643) (xy 329.162029 -67.814142) (xy 329.116671 -67.781691)
			(xy 329.076522 -67.742982) (xy 329.042436 -67.698839) (xy 329.01514 -67.650204) (xy 328.995217 -67.598113)
			(xy 328.983091 -67.543676) (xy 328.97902 -67.488054) (xy 317.065914 -67.488054) (xy 318.769492 -69.191632)
			(xy 318.77639 -69.189834) (xy 318.788901 -69.183014) (xy 318.79413 -69.17817) (xy 319.31483 -68.65747)
			(xy 319.3669 -68.605654) (xy 319.390301 -68.582873) (xy 319.441362 -68.542148) (xy 319.496661 -68.507397)
			(xy 319.555504 -68.479056) (xy 319.617149 -68.457482) (xy 319.680823 -68.442946) (xy 319.745724 -68.435631)
			(xy 319.77838 -68.43522) (xy 320.187574 -68.43522) (xy 320.189352 -68.434966) (xy 320.193162 -68.434966)
			(xy 320.210942 -68.434712) (xy 320.214244 -68.434712) (xy 320.249206 -68.435306) (xy 320.31861 -68.443836)
			(xy 320.352674 -68.45173) (xy 320.391627 -68.462069) (xy 320.466446 -68.492021) (xy 320.501772 -68.51142)
			(xy 320.535235 -68.531204) (xy 320.597042 -68.578352) (xy 320.60556 -68.586604) (xy 326.825102 -68.586604)
			(xy 326.82557 -68.559234) (xy 326.833387 -68.505055) (xy 326.848876 -68.452552) (xy 326.871717 -68.402805)
			(xy 326.901441 -68.356838) (xy 326.919082 -68.335906) (xy 326.919336 -68.335652) (xy 326.924911 -68.328558)
			(xy 326.931164 -68.311647) (xy 326.931528 -68.302632) (xy 326.931528 -68.235576) (xy 326.931177 -68.226559)
			(xy 326.924925 -68.209642) (xy 326.919336 -68.202556) (xy 326.919082 -68.202556) (xy 326.919082 -68.202302)
			(xy 326.901428 -68.181382) (xy 326.871719 -68.135406) (xy 326.848886 -68.085655) (xy 326.833398 -68.033152)
			(xy 326.825574 -67.978974) (xy 326.825102 -67.951604) (xy 326.825559 -67.924351) (xy 326.833316 -67.870399)
			(xy 326.848672 -67.818101) (xy 326.871315 -67.76852) (xy 326.900783 -67.722666) (xy 326.936477 -67.681473)
			(xy 326.977671 -67.645779) (xy 327.023525 -67.616312) (xy 327.073106 -67.59367) (xy 327.125405 -67.578314)
			(xy 327.179357 -67.570559) (xy 327.20661 -67.570096) (xy 327.232924 -67.570558) (xy 327.285053 -67.577794)
			(xy 327.335696 -67.592114) (xy 327.383895 -67.613248) (xy 327.428738 -67.640795) (xy 327.469377 -67.674234)
			(xy 327.487534 -67.693286) (xy 327.495043 -67.700703) (xy 327.514333 -67.709219) (xy 327.524872 -67.709796)
			(xy 327.599548 -67.709796) (xy 327.610096 -67.709254) (xy 327.629392 -67.700728) (xy 327.636886 -67.693286)
			(xy 327.655053 -67.674242) (xy 327.69568 -67.640784) (xy 327.740518 -67.613224) (xy 327.788717 -67.592084)
			(xy 327.839362 -67.577764) (xy 327.891495 -67.570536) (xy 327.91781 -67.570096) (xy 327.94518 -67.570557)
			(xy 327.99936 -67.578376) (xy 328.051863 -67.593867) (xy 328.10161 -67.616709) (xy 328.147576 -67.646435)
			(xy 328.168508 -67.664076) (xy 328.168762 -67.66433) (xy 328.175853 -67.66991) (xy 328.192766 -67.67616)
			(xy 328.201782 -67.676522) (xy 328.268838 -67.676522) (xy 328.277856 -67.676179) (xy 328.294773 -67.669921)
			(xy 328.301858 -67.66433) (xy 328.301858 -67.664076) (xy 328.302112 -67.664076) (xy 328.323063 -67.646461)
			(xy 328.369031 -67.616746) (xy 328.418774 -67.593906) (xy 328.47127 -67.578409) (xy 328.525442 -67.570574)
			(xy 328.55281 -67.570096) (xy 328.580062 -67.570569) (xy 328.63401 -67.578326) (xy 328.686305 -67.593683)
			(xy 328.735883 -67.616326) (xy 328.781733 -67.645793) (xy 328.822924 -67.681486) (xy 328.858615 -67.722678)
			(xy 328.888081 -67.768529) (xy 328.910722 -67.818108) (xy 328.926077 -67.870404) (xy 328.933832 -67.924352)
			(xy 328.934318 -67.951604) (xy 328.933874 -67.978975) (xy 328.926054 -68.033156) (xy 328.910561 -68.08566)
			(xy 328.887714 -68.135407) (xy 328.857983 -68.181372) (xy 328.840338 -68.202302) (xy 328.840084 -68.202556)
			(xy 328.834508 -68.20965) (xy 328.828255 -68.226561) (xy 328.827892 -68.235576) (xy 328.827892 -68.302632)
			(xy 328.828236 -68.31165) (xy 328.834493 -68.328567) (xy 328.840084 -68.335652) (xy 328.840338 -68.335652)
			(xy 328.840338 -68.335906) (xy 328.858 -68.35682) (xy 328.887707 -68.402798) (xy 328.910538 -68.45255)
			(xy 328.926024 -68.505055) (xy 328.933847 -68.559234) (xy 328.934318 -68.586604) (xy 328.933826 -68.613855)
			(xy 328.926069 -68.667802) (xy 328.910714 -68.720096) (xy 328.894075 -68.75653) (xy 332.370176 -68.75653)
			(xy 332.370641 -68.72916) (xy 332.378456 -68.67498) (xy 332.393945 -68.622476) (xy 332.416787 -68.572729)
			(xy 332.446513 -68.526763) (xy 332.464156 -68.505832) (xy 332.46441 -68.505578) (xy 332.470013 -68.498503)
			(xy 332.47625 -68.481577) (xy 332.476602 -68.472558) (xy 332.476602 -68.405502) (xy 332.476244 -68.396485)
			(xy 332.469997 -68.379568) (xy 332.46441 -68.372482) (xy 332.464156 -68.372482) (xy 332.464156 -68.372228)
			(xy 332.446509 -68.351302) (xy 332.4168 -68.305327) (xy 332.393966 -68.255578) (xy 332.378477 -68.203076)
			(xy 332.370649 -68.148899) (xy 332.370176 -68.12153) (xy 332.370683 -68.094279) (xy 332.378436 -68.04033)
			(xy 332.393787 -67.988034) (xy 332.416425 -67.938455) (xy 332.445888 -67.892603) (xy 332.481577 -67.85141)
			(xy 332.522766 -67.815716) (xy 332.568615 -67.786247) (xy 332.618191 -67.763603) (xy 332.670485 -67.748245)
			(xy 332.724433 -67.740486) (xy 332.751684 -67.740022) (xy 332.779054 -67.740492) (xy 332.833233 -67.748308)
			(xy 332.885737 -67.763796) (xy 332.935483 -67.786637) (xy 332.98145 -67.816361) (xy 333.002382 -67.834002)
			(xy 333.002636 -67.834256) (xy 333.009732 -67.839829) (xy 333.026642 -67.846082) (xy 333.035656 -67.846448)
			(xy 333.102712 -67.846448) (xy 333.111731 -67.846108) (xy 333.128648 -67.83985) (xy 333.135732 -67.834256)
			(xy 333.135732 -67.834002) (xy 333.135986 -67.834002) (xy 333.156913 -67.816356) (xy 333.202887 -67.786645)
			(xy 333.252636 -67.763811) (xy 333.305138 -67.748321) (xy 333.359314 -67.740495) (xy 333.386684 -67.740022)
			(xy 333.412998 -67.740493) (xy 333.465127 -67.747726) (xy 333.515769 -67.762044) (xy 333.563969 -67.783176)
			(xy 333.608812 -67.810722) (xy 333.649452 -67.84416) (xy 333.667608 -67.863212) (xy 333.675123 -67.870621)
			(xy 333.694408 -67.879141) (xy 333.704946 -67.879722) (xy 333.779622 -67.879722) (xy 333.790167 -67.879158)
			(xy 333.809463 -67.870647) (xy 333.81696 -67.863212) (xy 333.835096 -67.844137) (xy 333.875729 -67.810681)
			(xy 333.920574 -67.783124) (xy 333.968779 -67.761989) (xy 334.01943 -67.747676) (xy 334.071567 -67.740457)
			(xy 334.097884 -67.740022) (xy 334.125138 -67.74047) (xy 334.179091 -67.748226) (xy 334.231391 -67.763581)
			(xy 334.280973 -67.786224) (xy 334.326828 -67.815693) (xy 334.368021 -67.851389) (xy 334.403715 -67.892584)
			(xy 334.433183 -67.938439) (xy 334.455824 -67.988022) (xy 334.471177 -68.040323) (xy 334.478931 -68.094276)
			(xy 334.479392 -68.12153) (xy 334.478945 -68.148901) (xy 334.471123 -68.203081) (xy 334.45563 -68.255584)
			(xy 334.432784 -68.305331) (xy 334.403055 -68.351297) (xy 334.385412 -68.372228) (xy 334.385158 -68.372482)
			(xy 334.379568 -68.379566) (xy 334.373324 -68.396485) (xy 334.372966 -68.405502) (xy 334.372966 -68.472558)
			(xy 334.37335 -68.481572) (xy 334.37958 -68.498489) (xy 334.385158 -68.505578) (xy 334.385412 -68.505578)
			(xy 334.385412 -68.505832) (xy 334.403035 -68.526777) (xy 334.432748 -68.572747) (xy 334.455587 -68.622491)
			(xy 334.471082 -68.674989) (xy 334.478915 -68.729162) (xy 334.479392 -68.75653) (xy 334.47895 -68.783783)
			(xy 334.471189 -68.837733) (xy 334.455829 -68.890029) (xy 334.433183 -68.939608) (xy 334.403713 -68.985459)
			(xy 334.368017 -69.026649) (xy 334.326822 -69.06234) (xy 334.280967 -69.091806) (xy 334.231386 -69.114445)
			(xy 334.179088 -69.129799) (xy 334.125137 -69.137553) (xy 334.097884 -69.138038) (xy 334.071569 -69.137601)
			(xy 334.019438 -69.130363) (xy 333.968794 -69.116039) (xy 333.920595 -69.094901) (xy 333.875752 -69.067349)
			(xy 333.835115 -69.033903) (xy 333.81696 -69.014848) (xy 333.809449 -69.007434) (xy 333.790161 -68.998915)
			(xy 333.779622 -68.998338) (xy 333.704946 -68.998338) (xy 333.694396 -68.998867) (xy 333.6751 -69.007401)
			(xy 333.667608 -69.014848) (xy 333.649451 -69.033902) (xy 333.60882 -69.067357) (xy 333.56398 -69.094915)
			(xy 333.51578 -69.116054) (xy 333.465133 -69.130372) (xy 333.413 -69.137598) (xy 333.386684 -69.138038)
			(xy 333.359313 -69.137596) (xy 333.305132 -69.129775) (xy 333.252628 -69.114281) (xy 333.202881 -69.091433)
			(xy 333.156916 -69.061703) (xy 333.135986 -69.044058) (xy 333.135732 -69.043804) (xy 333.12864 -69.038225)
			(xy 333.111727 -69.031974) (xy 333.102712 -69.031612) (xy 333.035656 -69.031612) (xy 333.026642 -69.031993)
			(xy 333.009724 -69.038224) (xy 333.002636 -69.043804) (xy 333.002636 -69.044058) (xy 333.002382 -69.044058)
			(xy 332.981424 -69.061666) (xy 332.935459 -69.091384) (xy 332.885718 -69.114226) (xy 332.833223 -69.129725)
			(xy 332.779052 -69.13756) (xy 332.751684 -69.138038) (xy 332.724434 -69.137537) (xy 332.670488 -69.129779)
			(xy 332.618195 -69.114424) (xy 332.56862 -69.091783) (xy 332.522771 -69.062318) (xy 332.481582 -69.026628)
			(xy 332.445891 -68.98544) (xy 332.416424 -68.939592) (xy 332.393781 -68.890018) (xy 332.378424 -68.837726)
			(xy 332.370664 -68.78378) (xy 332.370176 -68.75653) (xy 328.894075 -68.75653) (xy 328.888073 -68.769672)
			(xy 328.858607 -68.815522) (xy 328.822917 -68.856712) (xy 328.781727 -68.892404) (xy 328.735878 -68.92187)
			(xy 328.686302 -68.944512) (xy 328.634008 -68.959868) (xy 328.580061 -68.967626) (xy 328.55281 -68.968112)
			(xy 328.52544 -68.967637) (xy 328.471262 -68.959821) (xy 328.418759 -68.944334) (xy 328.369012 -68.921494)
			(xy 328.323044 -68.891772) (xy 328.302112 -68.874132) (xy 328.301858 -68.873878) (xy 328.294761 -68.868307)
			(xy 328.277852 -68.862052) (xy 328.268838 -68.861686) (xy 328.201782 -68.861686) (xy 328.192765 -68.862038)
			(xy 328.175848 -68.868289) (xy 328.168762 -68.873878) (xy 328.168762 -68.874132) (xy 328.168508 -68.874132)
			(xy 328.147588 -68.891786) (xy 328.101611 -68.921494) (xy 328.051861 -68.944327) (xy 327.999358 -68.959815)
			(xy 327.94518 -68.96764) (xy 327.91781 -68.968112) (xy 327.891496 -68.967634) (xy 327.839369 -68.960401)
			(xy 327.788726 -68.946084) (xy 327.740527 -68.924953) (xy 327.695683 -68.897409) (xy 327.655043 -68.863972)
			(xy 327.636886 -68.844922) (xy 327.629369 -68.837515) (xy 327.610086 -68.828993) (xy 327.599548 -68.828412)
			(xy 327.524872 -68.828412) (xy 327.514325 -68.828963) (xy 327.495029 -68.837483) (xy 327.487534 -68.844922)
			(xy 327.469408 -68.864007) (xy 327.428771 -68.89746) (xy 327.383925 -68.925015) (xy 327.335718 -68.946148)
			(xy 327.285066 -68.960459) (xy 327.232928 -68.967677) (xy 327.20661 -68.968112) (xy 327.179358 -68.967635)
			(xy 327.125407 -68.95988) (xy 327.07311 -68.944525) (xy 327.02353 -68.921884) (xy 326.977677 -68.892418)
			(xy 326.936485 -68.856725) (xy 326.900791 -68.815534) (xy 326.871322 -68.769682) (xy 326.84868 -68.720103)
			(xy 326.833323 -68.667806) (xy 326.825566 -68.613856) (xy 326.825102 -68.586604) (xy 320.60556 -68.586604)
			(xy 320.624962 -68.6054) (xy 320.83248 -68.812918) (xy 321.223386 -69.204078) (xy 321.246138 -69.227479)
			(xy 321.286832 -69.27851) (xy 321.32156 -69.333774) (xy 321.349885 -69.392578) (xy 321.371452 -69.454181)
			(xy 321.38599 -69.517812) (xy 321.393316 -69.582669) (xy 321.39382 -69.615304) (xy 321.394074 -70.05066)
			(xy 321.394074 -70.050914) (xy 321.393616 -70.083568) (xy 321.386303 -70.148465) (xy 321.37177 -70.212135)
			(xy 321.350201 -70.273779) (xy 321.321866 -70.33262) (xy 321.287122 -70.387919) (xy 321.246406 -70.43898)
			(xy 321.22364 -70.462394) (xy 321.171824 -70.514464) (xy 320.651124 -71.035164) (xy 320.646262 -71.040383)
			(xy 320.639414 -71.052888) (xy 320.637662 -71.059802) (xy 320.99885 -71.42099) (xy 322.597016 -71.42099)
			(xy 322.601087 -71.365368) (xy 322.613213 -71.310931) (xy 322.633136 -71.25884) (xy 322.660432 -71.210205)
			(xy 322.694518 -71.166062) (xy 322.734667 -71.127353) (xy 322.780025 -71.094902) (xy 322.829625 -71.069401)
			(xy 322.882409 -71.051394) (xy 322.937252 -71.041264) (xy 322.992986 -71.039227) (xy 323.048423 -71.045327)
			(xy 323.10238 -71.059433) (xy 323.153709 -71.081245) (xy 323.201315 -71.110299) (xy 323.244183 -71.145974)
			(xy 323.2814 -71.187511) (xy 323.312173 -71.234024) (xy 323.335845 -71.284521) (xy 323.351913 -71.337928)
			(xy 323.360033 -71.393104) (xy 323.360542 -71.42099) (xy 323.360033 -71.448876) (xy 323.351913 -71.504052)
			(xy 323.336325 -71.555864) (xy 329.39431 -71.555864) (xy 329.398381 -71.500242) (xy 329.410507 -71.445805)
			(xy 329.43043 -71.393714) (xy 329.457726 -71.345079) (xy 329.491812 -71.300936) (xy 329.531961 -71.262227)
			(xy 329.577319 -71.229776) (xy 329.626919 -71.204275) (xy 329.679703 -71.186268) (xy 329.734546 -71.176138)
			(xy 329.79028 -71.174101) (xy 329.845717 -71.180201) (xy 329.899674 -71.194307) (xy 329.951003 -71.216119)
			(xy 329.998609 -71.245173) (xy 330.041477 -71.280848) (xy 330.078694 -71.322385) (xy 330.109467 -71.368898)
			(xy 330.133139 -71.419395) (xy 330.149207 -71.472802) (xy 330.157327 -71.527978) (xy 330.157836 -71.555864)
			(xy 330.157327 -71.58375) (xy 330.151488 -71.623428) (xy 330.903324 -71.623428) (xy 330.907395 -71.567806)
			(xy 330.919521 -71.513369) (xy 330.939444 -71.461278) (xy 330.96674 -71.412643) (xy 331.000826 -71.3685)
			(xy 331.040975 -71.329791) (xy 331.086333 -71.29734) (xy 331.135933 -71.271839) (xy 331.188717 -71.253832)
			(xy 331.24356 -71.243702) (xy 331.299294 -71.241665) (xy 331.354731 -71.247765) (xy 331.408688 -71.261871)
			(xy 331.460017 -71.283683) (xy 331.507623 -71.312737) (xy 331.550491 -71.348412) (xy 331.587708 -71.389949)
			(xy 331.618481 -71.436462) (xy 331.642153 -71.486959) (xy 331.658221 -71.540366) (xy 331.666341 -71.595542)
			(xy 331.66685 -71.623428) (xy 331.666341 -71.651314) (xy 331.658221 -71.70649) (xy 331.642153 -71.759897)
			(xy 331.618481 -71.810394) (xy 331.587708 -71.856907) (xy 331.550491 -71.898444) (xy 331.507623 -71.934119)
			(xy 331.460017 -71.963173) (xy 331.408688 -71.984985) (xy 331.354731 -71.999091) (xy 331.299294 -72.005191)
			(xy 331.24356 -72.003154) (xy 331.188717 -71.993024) (xy 331.135933 -71.975017) (xy 331.086333 -71.949516)
			(xy 331.040975 -71.917065) (xy 331.000826 -71.878356) (xy 330.96674 -71.834213) (xy 330.939444 -71.785578)
			(xy 330.919521 -71.733487) (xy 330.907395 -71.67905) (xy 330.903324 -71.623428) (xy 330.151488 -71.623428)
			(xy 330.149207 -71.638926) (xy 330.133139 -71.692333) (xy 330.109467 -71.74283) (xy 330.078694 -71.789343)
			(xy 330.041477 -71.83088) (xy 329.998609 -71.866555) (xy 329.951003 -71.895609) (xy 329.899674 -71.917421)
			(xy 329.845717 -71.931527) (xy 329.79028 -71.937627) (xy 329.734546 -71.93559) (xy 329.679703 -71.92546)
			(xy 329.626919 -71.907453) (xy 329.577319 -71.881952) (xy 329.531961 -71.849501) (xy 329.491812 -71.810792)
			(xy 329.457726 -71.766649) (xy 329.43043 -71.718014) (xy 329.410507 -71.665923) (xy 329.398381 -71.611486)
			(xy 329.39431 -71.555864) (xy 323.336325 -71.555864) (xy 323.335845 -71.557459) (xy 323.312173 -71.607956)
			(xy 323.2814 -71.654469) (xy 323.244183 -71.696006) (xy 323.201315 -71.731681) (xy 323.153709 -71.760735)
			(xy 323.10238 -71.782547) (xy 323.048423 -71.796653) (xy 322.992986 -71.802753) (xy 322.937252 -71.800716)
			(xy 322.882409 -71.790586) (xy 322.829625 -71.772579) (xy 322.780025 -71.747078) (xy 322.734667 -71.714627)
			(xy 322.694518 -71.675918) (xy 322.660432 -71.631775) (xy 322.633136 -71.58314) (xy 322.613213 -71.531049)
			(xy 322.601087 -71.476612) (xy 322.597016 -71.42099) (xy 320.99885 -71.42099) (xy 324.805802 -75.227942)
			(xy 324.813198 -75.234795) (xy 324.831796 -75.242537) (xy 324.84187 -75.242928) (xy 334.678782 -75.242928)
			(xy 334.688794 -75.242444) (xy 334.707297 -75.234788) (xy 334.721462 -75.220636) (xy 334.729135 -75.20214)
			(xy 334.729582 -75.192128) (xy 334.729582 -68.04279) (xy 334.729419 -68.036779) (xy 334.726603 -68.025093)
			(xy 334.723994 -68.019676) (xy 334.722154 -68.016202) (xy 334.71756 -68.009824) (xy 334.71485 -68.006976)
			(xy 333.419704 -66.71183) (xy 333.416222 -66.708546) (xy 333.408294 -66.703186) (xy 333.403956 -66.701162)
			(xy 333.395828 -66.697606) (xy 333.385668 -66.697098) (xy 333.349234 -66.695311) (xy 333.277207 -66.683774)
			(xy 333.207187 -66.66332) (xy 333.140276 -66.634269) (xy 333.077524 -66.597077) (xy 333.019915 -66.552329)
			(xy 332.993746 -66.526918) (xy 332.685898 -66.21907) (xy 332.663117 -66.195669) (xy 332.622392 -66.144609)
			(xy 332.587641 -66.08931) (xy 332.559301 -66.030467) (xy 332.537728 -65.968821) (xy 332.523194 -65.905147)
			(xy 332.515882 -65.840246) (xy 332.515464 -65.80759) (xy 332.515464 -64.906144) (xy 332.515051 -64.89612)
			(xy 332.507388 -64.877594) (xy 332.493213 -64.863416) (xy 332.474688 -64.85575) (xy 332.464664 -64.855344)
			(xy 331.175614 -64.855344) (xy 331.16742 -64.855652) (xy 331.151874 -64.860834) (xy 331.145134 -64.865504)
			(xy 331.13726 -64.873378) (xy 331.13218 -64.87922) (xy 331.089 -64.938148) (xy 331.085481 -64.9431)
			(xy 331.080723 -64.954275) (xy 331.079602 -64.960246) (xy 331.077824 -64.971676) (xy 331.081634 -64.983614)
			(xy 331.090179 -65.012195) (xy 331.09936 -65.071136) (xy 331.099922 -65.100962) (xy 331.099431 -65.128504)
			(xy 331.091592 -65.183026) (xy 331.076073 -65.235878) (xy 331.053191 -65.285983) (xy 331.023411 -65.332322)
			(xy 330.987339 -65.373951) (xy 330.94571 -65.410023) (xy 330.899371 -65.439803) (xy 330.849266 -65.462685)
			(xy 330.796414 -65.478204) (xy 330.741892 -65.486043) (xy 330.686808 -65.486043) (xy 330.632286 -65.478204)
			(xy 330.579434 -65.462685) (xy 330.529329 -65.439803) (xy 330.48299 -65.410023) (xy 330.441361 -65.373951)
			(xy 330.405289 -65.332322) (xy 330.375509 -65.285983) (xy 330.352627 -65.235878) (xy 330.337108 -65.183026)
			(xy 330.329269 -65.128504) (xy 330.328778 -65.100962) (xy 330.329338 -65.071136) (xy 330.338527 -65.012197)
			(xy 330.347066 -64.983614) (xy 330.347066 -64.98336) (xy 330.348741 -64.97761) (xy 330.349649 -64.965672)
			(xy 330.348844 -64.959738) (xy 330.347066 -64.948308) (xy 330.318364 -64.908938) (xy 330.294234 -64.876172)
			(xy 330.29398 -64.875918) (xy 330.288138 -64.867282) (xy 330.276708 -64.861186) (xy 330.271988 -64.858884)
			(xy 330.261872 -64.856072) (xy 330.256642 -64.855598) (xy 330.253086 -64.855344) (xy 325.160386 -64.855344)
			(xy 325.124872 -64.854797) (xy 325.054375 -64.846131) (xy 324.985452 -64.828964) (xy 324.952106 -64.816736)
			(xy 324.945502 -64.814704) (xy 324.913541 -64.806813) (xy 324.85147 -64.784871) (xy 324.792223 -64.756163)
			(xy 324.736537 -64.721045) (xy 324.685101 -64.679952) (xy 324.66153 -64.65697) (xy 321.34683 -61.34227)
			(xy 321.32372 -61.318491) (xy 321.282387 -61.266638) (xy 321.247118 -61.210484) (xy 321.218358 -61.150735)
			(xy 321.196467 -61.088141) (xy 321.18172 -61.023491) (xy 321.174304 -60.957596) (xy 321.173856 -60.92444)
			(xy 321.173856 -52.940204) (xy 321.114166 -51.945794) (xy 321.092576 -51.586892) (xy 321.091992 -51.582875)
			(xy 321.08969 -51.575091) (xy 321.088004 -51.571398) (xy 320.846704 -51.140106) (xy 320.784728 -51.02987)
			(xy 320.782696 -51.026568) (xy 318.991488 -48.345598) (xy 318.985138 -48.337978) (xy 311.656984 -41.009824)
			(xy 311.650229 -41.003549) (xy 311.63347 -40.995902) (xy 311.615085 -40.994731) (xy 311.606184 -40.997124)
			(xy 311.589166 -41.002204) (xy 311.587388 -41.002712) (xy 311.583324 -41.004236) (xy 311.577225 -41.006667)
			(xy 311.566429 -41.014132) (xy 311.561988 -41.018968) (xy 311.553352 -41.029128) (xy 311.552844 -41.03243)
			(xy 311.550812 -41.04259) (xy 311.545469 -41.068461) (xy 311.528595 -41.118522) (xy 311.504975 -41.165774)
			(xy 311.47506 -41.209315) (xy 311.439423 -41.248312) (xy 311.398746 -41.282018) (xy 311.353806 -41.309788)
			(xy 311.305464 -41.33109) (xy 311.254645 -41.345518) (xy 311.202322 -41.352796) (xy 311.175908 -41.353232)
			(xy 311.148656 -41.352747) (xy 311.094706 -41.344991) (xy 311.042409 -41.329637) (xy 310.992829 -41.306997)
			(xy 310.946976 -41.277531) (xy 310.905783 -41.24184) (xy 310.870088 -41.20065) (xy 310.840619 -41.154799)
			(xy 310.817974 -41.105221) (xy 310.802615 -41.052925) (xy 310.794856 -40.998976) (xy 310.7944 -40.971724)
			(xy 310.794845 -40.945335) (xy 310.802115 -40.89306) (xy 310.816519 -40.842286) (xy 310.837783 -40.793981)
			(xy 310.865501 -40.749068) (xy 310.899144 -40.708403) (xy 310.93807 -40.672762) (xy 310.981537 -40.642825)
			(xy 311.028714 -40.619165) (xy 311.078701 -40.602231) (xy 311.104534 -40.59682) (xy 311.117488 -40.59428)
			(xy 311.124092 -40.588692) (xy 311.127648 -40.585898) (xy 311.132328 -40.581844) (xy 311.139776 -40.571958)
			(xy 311.14238 -40.56634) (xy 311.144666 -40.561006) (xy 311.145428 -40.558466) (xy 311.14746 -40.551862)
			(xy 311.150508 -40.541448) (xy 311.152791 -40.532535) (xy 311.151583 -40.51419) (xy 311.144023 -40.497432)
			(xy 311.137808 -40.490648) (xy 310.889904 -40.242744) (xy 310.882492 -40.236065) (xy 310.864057 -40.22849)
			(xy 310.85409 -40.228012) (xy 310.772302 -40.227758) (xy 310.75376 -40.235632) (xy 310.746648 -40.242744)
			(xy 310.736176 -40.252875) (xy 310.713927 -40.271691) (xy 310.702198 -40.280336) (xy 310.702198 -40.281098)
			(xy 310.686704 -40.291766) (xy 310.685688 -40.292528) (xy 310.662368 -40.307057) (xy 310.612448 -40.330011)
			(xy 310.559761 -40.345597) (xy 310.505388 -40.353493) (xy 310.477916 -40.353996) (xy 310.477662 -40.353996)
			(xy 310.450377 -40.353507) (xy 310.396362 -40.345735) (xy 310.344004 -40.330356) (xy 310.294367 -40.307683)
			(xy 310.248461 -40.278176) (xy 310.207222 -40.242436) (xy 310.171489 -40.201192) (xy 310.141989 -40.155282)
			(xy 310.119323 -40.105642) (xy 310.103952 -40.053281) (xy 310.096189 -39.999265) (xy 310.095646 -39.97198)
			(xy 310.096162 -39.943633) (xy 310.104537 -39.887561) (xy 310.121099 -39.83334) (xy 310.145486 -39.78216)
			(xy 310.177164 -39.735141) (xy 310.215437 -39.693315) (xy 310.237124 -39.675054) (xy 310.239156 -39.67353)
			(xy 310.23941 -39.673276) (xy 310.240426 -39.672514) (xy 310.24417 -39.669193) (xy 310.250439 -39.661393)
			(xy 310.252872 -39.65702) (xy 310.25846 -39.645082) (xy 310.260099 -39.641133) (xy 310.262144 -39.632831)
			(xy 310.262524 -39.628572) (xy 310.263286 -39.616126) (xy 309.527448 -38.880288) (xy 309.518201 -38.871879)
			(xy 309.494373 -38.864428) (xy 309.481982 -38.866064) (xy 309.471822 -38.868096) (xy 309.465589 -38.869477)
			(xy 309.454021 -38.874869) (xy 309.448962 -38.878764) (xy 309.443628 -38.883082) (xy 309.436262 -38.892988)
			(xy 309.433722 -38.89883) (xy 309.433722 -38.899084) (xy 309.42238 -38.924724) (xy 309.393279 -38.972644)
			(xy 309.357476 -39.015788) (xy 309.315741 -39.053224) (xy 309.268975 -39.084146) (xy 309.218186 -39.107888)
			(xy 309.164468 -39.123938) (xy 309.136796 -39.128446) (xy 309.109779 -39.131876) (xy 309.05532 -39.131954)
			(xy 309.001403 -39.124294) (xy 308.949122 -39.109049) (xy 308.899536 -39.086531) (xy 308.853654 -39.057196)
			(xy 308.812406 -39.021638) (xy 308.776629 -38.98058) (xy 308.761384 -38.958012) (xy 308.76113 -38.957758)
			(xy 308.760114 -38.956234) (xy 308.759352 -38.955218) (xy 308.756304 -38.950138) (xy 308.751224 -38.945058)
			(xy 308.742842 -38.9382) (xy 308.73319 -38.932358) (xy 308.732682 -38.93185) (xy 308.712362 -38.919658)
			(xy 308.699916 -38.918896) (xy 308.629304 -38.914324) (xy 308.628542 -38.914324) (xy 308.615588 -38.913562)
			(xy 308.604158 -38.91915) (xy 308.59861 -38.921946) (xy 308.588965 -38.929774) (xy 308.585108 -38.934644)
			(xy 308.583076 -38.937438) (xy 308.582822 -38.937692) (xy 308.580028 -38.941248) (xy 308.561784 -38.963141)
			(xy 308.519915 -39.001798) (xy 308.47277 -39.033811) (xy 308.421396 -39.05847) (xy 308.366929 -39.075229)
			(xy 308.310579 -39.083717) (xy 308.282086 -39.08425) (xy 308.281832 -39.08425) (xy 308.254575 -39.083789)
			(xy 308.200614 -39.076035) (xy 308.148307 -39.06068) (xy 308.098717 -39.038037) (xy 308.052855 -39.008567)
			(xy 308.011654 -38.972869) (xy 307.975953 -38.931671) (xy 307.946478 -38.885811) (xy 307.923831 -38.836223)
			(xy 307.908472 -38.783917) (xy 307.900713 -38.729957) (xy 307.900713 -38.675443) (xy 307.908472 -38.621483)
			(xy 307.923831 -38.569177) (xy 307.946478 -38.519589) (xy 307.975953 -38.473729) (xy 308.011654 -38.432531)
			(xy 308.052855 -38.396833) (xy 308.098717 -38.367363) (xy 308.148307 -38.34472) (xy 308.200614 -38.329365)
			(xy 308.254575 -38.321611) (xy 308.281832 -38.321234) (xy 308.308908 -38.321707) (xy 308.362518 -38.329356)
			(xy 308.414512 -38.344497) (xy 308.463847 -38.366825) (xy 308.509537 -38.395894) (xy 308.550665 -38.431121)
			(xy 308.586409 -38.471802) (xy 308.601618 -38.494208) (xy 308.608476 -38.50259) (xy 308.616604 -38.510464)
			(xy 308.624986 -38.517068) (xy 308.640226 -38.526974) (xy 308.645707 -38.530165) (xy 308.657786 -38.534022)
			(xy 308.664102 -38.534594) (xy 308.732682 -38.539166) (xy 308.737508 -38.539166) (xy 308.744395 -38.538903)
			(xy 308.757658 -38.535171) (xy 308.76367 -38.5318) (xy 308.765702 -38.530784) (xy 308.773322 -38.524434)
			(xy 308.777386 -38.52037) (xy 308.779672 -38.517322) (xy 308.795462 -38.497603) (xy 308.831393 -38.462093)
			(xy 308.871692 -38.43163) (xy 308.915655 -38.406746) (xy 308.93893 -38.396926) (xy 308.946042 -38.393878)
			(xy 308.96179 -38.37432) (xy 308.962552 -38.370256) (xy 308.966362 -38.351206) (xy 308.968168 -38.338717)
			(xy 308.960844 -38.314601) (xy 308.952392 -38.305232) (xy 308.77383 -38.12667) (xy 308.748056 -38.100115)
			(xy 308.702637 -38.041689) (xy 308.664869 -37.978049) (xy 308.635343 -37.910191) (xy 308.614523 -37.839177)
			(xy 308.602733 -37.766119) (xy 308.600856 -37.72916) (xy 308.600094 -37.721794) (xy 308.595718 -37.696109)
			(xy 308.591011 -37.644215) (xy 308.590696 -37.618162) (xy 308.590696 -36.936172) (xy 308.589426 -36.924996)
			(xy 308.587802 -36.918609) (xy 308.581753 -36.906906) (xy 308.577488 -36.901882) (xy 308.571392 -36.895532)
			(xy 308.537864 -36.86048) (xy 308.530868 -36.853747) (xy 308.51324 -36.845642) (xy 308.503574 -36.844732)
			(xy 308.502304 -36.844732) (xy 308.474753 -36.843675) (xy 308.420342 -36.834777) (xy 308.36772 -36.818325)
			(xy 308.31793 -36.794646) (xy 308.271958 -36.764209) (xy 308.230717 -36.727618) (xy 308.195023 -36.685598)
			(xy 308.165584 -36.638982) (xy 308.142983 -36.588693) (xy 308.127668 -36.535729) (xy 308.119943 -36.481139)
			(xy 308.119526 -36.453572) (xy 308.119998 -36.426039) (xy 308.127726 -36.371517) (xy 308.143027 -36.318618)
			(xy 308.165598 -36.268389) (xy 308.194991 -36.221823) (xy 308.230626 -36.17984) (xy 308.271798 -36.143272)
			(xy 308.317693 -36.112841) (xy 308.367403 -36.089149) (xy 308.419944 -36.072665) (xy 308.474279 -36.063715)
			(xy 308.501796 -36.062666) (xy 308.511702 -36.062412) (xy 308.5211 -36.058602) (xy 308.525863 -36.056415)
			(xy 308.53444 -36.050397) (xy 308.538118 -36.046664) (xy 308.576726 -36.00577) (xy 308.58311 -35.99845)
			(xy 308.590296 -35.980423) (xy 308.590696 -35.970718) (xy 308.590696 -35.81146) (xy 308.590472 -35.804188)
			(xy 308.586347 -35.790244) (xy 308.582568 -35.784028) (xy 308.582568 -35.783774) (xy 308.564307 -35.754895)
			(xy 308.533818 -35.693745) (xy 308.510587 -35.629487) (xy 308.494924 -35.562977) (xy 308.487037 -35.495105)
			(xy 308.486556 -35.46094) (xy 308.486556 -34.96564) (xy 308.487057 -34.931501) (xy 308.494958 -34.863682)
			(xy 308.510626 -34.797226) (xy 308.533851 -34.73302) (xy 308.564323 -34.671919) (xy 308.582568 -34.64306)
			(xy 308.582568 -34.642552) (xy 308.586632 -34.636202) (xy 308.590696 -34.62274) (xy 308.590696 -34.59226)
			(xy 308.590472 -34.584988) (xy 308.586347 -34.571044) (xy 308.582568 -34.564828) (xy 308.582568 -34.564574)
			(xy 308.564307 -34.535695) (xy 308.533818 -34.474545) (xy 308.510587 -34.410287) (xy 308.494924 -34.343777)
			(xy 308.487037 -34.275905) (xy 308.486556 -34.24174) (xy 308.486556 -33.74644) (xy 308.487057 -33.712301)
			(xy 308.494958 -33.644482) (xy 308.510626 -33.578026) (xy 308.533851 -33.51382) (xy 308.564323 -33.452719)
			(xy 308.582568 -33.42386) (xy 308.582568 -33.423352) (xy 308.586632 -33.417002) (xy 308.590696 -33.40354)
			(xy 308.590696 -33.37306) (xy 308.590472 -33.365788) (xy 308.586347 -33.351844) (xy 308.582568 -33.345628)
			(xy 308.582568 -33.345374) (xy 308.564307 -33.316495) (xy 308.533818 -33.255345) (xy 308.510587 -33.191087)
			(xy 308.494924 -33.124577) (xy 308.487037 -33.056705) (xy 308.486556 -33.02254) (xy 308.486556 -32.52724)
			(xy 308.487057 -32.493101) (xy 308.494958 -32.425282) (xy 308.510626 -32.358826) (xy 308.533851 -32.29462)
			(xy 308.564323 -32.233519) (xy 308.582568 -32.20466) (xy 308.582568 -32.204152) (xy 308.586632 -32.197802)
			(xy 308.590696 -32.18434) (xy 308.590696 -32.15386) (xy 308.590472 -32.146588) (xy 308.586347 -32.132644)
			(xy 308.582568 -32.126428) (xy 308.582568 -32.126174) (xy 308.564307 -32.097295) (xy 308.533818 -32.036145)
			(xy 308.510587 -31.971887) (xy 308.494924 -31.905377) (xy 308.487037 -31.837505) (xy 308.486556 -31.80334)
			(xy 308.486556 -31.30804) (xy 308.487057 -31.273901) (xy 308.494958 -31.206082) (xy 308.510626 -31.139626)
			(xy 308.533851 -31.07542) (xy 308.564323 -31.014319) (xy 308.582568 -30.98546) (xy 308.582568 -30.984952)
			(xy 308.586632 -30.978602) (xy 308.590696 -30.96514) (xy 308.590696 -30.954218) (xy 308.590258 -30.944155)
			(xy 308.582522 -30.925572) (xy 308.57571 -30.91815) (xy 308.329584 -30.672024) (xy 308.323234 -30.670754)
			(xy 308.291291 -30.664273) (xy 308.228987 -30.645124) (xy 308.169213 -30.619133) (xy 308.112716 -30.586626)
			(xy 308.060206 -30.548011) (xy 308.03596 -30.526228) (xy 308.012592 -30.503368) (xy 308.011576 -30.502352)
			(xy 307.76037 -30.250892) (xy 307.736629 -30.226523) (xy 307.694399 -30.173178) (xy 307.658683 -30.115269)
			(xy 307.629969 -30.053588) (xy 307.608649 -29.988977) (xy 307.601366 -29.955744) (xy 307.599607 -29.94847)
			(xy 307.592501 -29.935309) (xy 307.587396 -29.929836) (xy 307.407056 -29.749496) (xy 307.39588 -29.74721)
			(xy 307.361549 -29.739869) (xy 307.294824 -29.718035) (xy 307.231212 -29.688331) (xy 307.171635 -29.651189)
			(xy 307.11696 -29.607149) (xy 307.092096 -29.582364) (xy 307.091588 -29.581856) (xy 306.784248 -29.274516)
			(xy 306.758423 -29.247797) (xy 306.713065 -29.188936) (xy 306.675563 -29.124784) (xy 306.646529 -29.056381)
			(xy 306.635912 -29.02077) (xy 306.635912 -29.020262) (xy 306.633118 -29.010864) (xy 306.606194 -28.990544)
			(xy 306.4764 -28.990544) (xy 306.47132 -28.993592) (xy 306.443717 -29.010149) (xy 306.385561 -29.037744)
			(xy 306.324713 -29.058745) (xy 306.261918 -29.072897) (xy 306.197943 -29.080025) (xy 306.165758 -29.08046)
			(xy 305.722782 -29.08046) (xy 305.691408 -29.080021) (xy 305.629027 -29.073238) (xy 305.567735 -29.059796)
			(xy 305.508242 -29.039849) (xy 305.451234 -29.013629) (xy 305.424078 -28.99791) (xy 305.418236 -28.994354)
			(xy 305.405028 -28.990544) (xy 305.208686 -28.990544) (xy 305.175544 -28.990075) (xy 305.109676 -28.982648)
			(xy 305.045052 -28.967901) (xy 304.982483 -28.946019) (xy 304.922754 -28.917275) (xy 304.866615 -28.882032)
			(xy 304.840386 -28.861766) (xy 304.836576 -28.858972) (xy 304.811529 -28.842149) (xy 304.7647 -28.804097)
			(xy 304.743104 -28.783026) (xy 304.488596 -28.528772) (xy 304.366422 -28.406598) (xy 304.36185 -28.402534)
			(xy 304.35337 -28.396553) (xy 304.333311 -28.391312) (xy 304.322988 -28.392374) (xy 304.308002 -28.395676)
			(xy 304.304446 -28.3972) (xy 304.302414 -28.398216) (xy 304.276869 -28.409693) (xy 304.223257 -28.425874)
			(xy 304.167855 -28.434041) (xy 304.139854 -28.434538) (xy 304.1396 -28.434538) (xy 304.125007 -28.434495)
			(xy 304.095892 -28.432459) (xy 304.081434 -28.430474) (xy 304.07864 -28.429966) (xy 304.053748 -28.429204)
			(xy 304.044559 -28.429641) (xy 304.027394 -28.436213) (xy 304.013652 -28.448421) (xy 304.009044 -28.456382)
			(xy 304.004726 -28.465272) (xy 304.002325 -28.469942) (xy 303.995929 -28.478269) (xy 303.992026 -28.481782)
			(xy 303.980596 -28.491688) (xy 303.973268 -28.498489) (xy 303.96423 -28.516302) (xy 303.96307 -28.526232)
			(xy 303.962816 -28.530296) (xy 303.962816 -29.114242) (xy 303.962326 -29.14421) (xy 303.954503 -29.203632)
			(xy 303.93899 -29.261525) (xy 303.916054 -29.316898) (xy 303.886087 -29.368804) (xy 303.8496 -29.416354)
			(xy 303.80722 -29.458734) (xy 303.75967 -29.495221) (xy 303.707764 -29.525188) (xy 303.652391 -29.548124)
			(xy 303.594498 -29.563637) (xy 303.535076 -29.57146) (xy 303.47514 -29.57146) (xy 303.415718 -29.563637)
			(xy 303.357825 -29.548124) (xy 303.302452 -29.525188) (xy 303.250546 -29.495221) (xy 303.202996 -29.458734)
			(xy 303.160616 -29.416354) (xy 303.124129 -29.368804) (xy 303.094162 -29.316898) (xy 303.071226 -29.261525)
			(xy 303.055713 -29.203632) (xy 303.04789 -29.14421) (xy 303.0474 -29.114242) (xy 303.0474 -28.24988)
			(xy 303.04792 -28.218608) (xy 303.056465 -28.156652) (xy 303.07338 -28.096439) (xy 303.098348 -28.039095)
			(xy 303.114202 -28.012136) (xy 303.117758 -28.006294) (xy 303.122584 -27.989276) (xy 303.124362 -27.982672)
			(xy 303.124616 -27.969464) (xy 303.120044 -27.950922) (xy 303.120044 -27.950414) (xy 303.105566 -27.89428)
			(xy 303.105312 -27.893264) (xy 303.084738 -27.88285) (xy 303.057181 -27.868402) (xy 303.004976 -27.834541)
			(xy 302.956625 -27.795375) (xy 302.93437 -27.77363) (xy 302.819308 -27.658568) (xy 302.807116 -27.66187)
			(xy 302.78832 -27.672792) (xy 302.787812 -27.6733) (xy 302.75657 -27.690826) (xy 302.756062 -27.690826)
			(xy 302.745394 -27.696414) (xy 302.727868 -27.704796) (xy 302.718216 -27.709114) (xy 302.689119 -27.721303)
			(xy 302.628887 -27.740067) (xy 302.566982 -27.752219) (xy 302.53559 -27.755342) (xy 302.516794 -27.756358)
			(xy 302.487584 -27.75712) (xy 302.039782 -27.75712) (xy 302.008537 -27.756454) (xy 301.946455 -27.749249)
			(xy 301.885504 -27.73543) (xy 301.826385 -27.715154) (xy 301.769781 -27.688657) (xy 301.742856 -27.672792)
			(xy 301.7393 -27.67076) (xy 301.730664 -27.667204) (xy 301.72533 -27.665426) (xy 301.72025 -27.663902)
			(xy 301.714517 -27.662481) (xy 301.702719 -27.661976) (xy 301.696882 -27.662886) (xy 301.599092 -27.760676)
			(xy 301.575334 -27.783818) (xy 301.523491 -27.825192) (xy 301.467343 -27.8605) (xy 301.407593 -27.889298)
			(xy 301.344994 -27.911225) (xy 301.280334 -27.926004) (xy 301.214426 -27.933449) (xy 301.181262 -27.933904)
			(xy 301.145543 -27.933362) (xy 301.074625 -27.924748) (xy 301.005263 -27.907648) (xy 300.938468 -27.882314)
			(xy 300.875213 -27.849113) (xy 300.81642 -27.808531) (xy 300.762947 -27.761158) (xy 300.715574 -27.707686)
			(xy 300.674991 -27.648894) (xy 300.64179 -27.58564) (xy 300.616454 -27.518844) (xy 300.599354 -27.449483)
			(xy 300.590738 -27.378565) (xy 300.590204 -27.342846) (xy 300.590646 -27.310554) (xy 300.597711 -27.246357)
			(xy 300.611739 -27.183315) (xy 300.632563 -27.12218) (xy 300.659933 -27.063683) (xy 300.693524 -27.008521)
			(xy 300.712886 -26.982674) (xy 300.72203 -26.970736) (xy 300.7233 -26.959306) (xy 300.7233 -26.870152)
			(xy 300.722975 -26.861873) (xy 300.717652 -26.846196) (xy 300.712886 -26.839418) (xy 300.693537 -26.813563)
			(xy 300.659964 -26.758393) (xy 300.632601 -26.699895) (xy 300.611773 -26.638764) (xy 300.597729 -26.575727)
			(xy 300.590635 -26.511537) (xy 300.590204 -26.479246) (xy 300.590649 -26.446076) (xy 300.598072 -26.380151)
			(xy 300.612829 -26.315473) (xy 300.634735 -26.252853) (xy 300.663515 -26.19308) (xy 300.698806 -26.136905)
			(xy 300.740166 -26.085035) (xy 300.787072 -26.038122) (xy 300.838937 -25.996755) (xy 300.895107 -25.961456)
			(xy 300.954876 -25.932668) (xy 301.017492 -25.910752) (xy 301.082168 -25.895986) (xy 301.148092 -25.888554)
			(xy 301.181262 -25.888188) (xy 301.214424 -25.888667) (xy 301.280329 -25.896119) (xy 301.344986 -25.910901)
			(xy 301.407582 -25.932826) (xy 301.467331 -25.961619) (xy 301.523482 -25.996918) (xy 301.57533 -26.03828)
			(xy 301.599092 -26.061416) (xy 301.701962 -26.164286) (xy 301.709363 -26.171124) (xy 301.727962 -26.178838)
			(xy 301.73803 -26.179272) (xy 303.165256 -26.179272) (xy 303.195506 -26.179617) (xy 303.255695 -26.185729)
			(xy 303.285398 -26.191464) (xy 303.294542 -26.193496) (xy 303.313084 -26.190448) (xy 303.322482 -26.18486)
			(xy 303.331118 -26.17978) (xy 303.340262 -26.17089) (xy 303.343818 -26.165048) (xy 303.343818 -26.164794)
			(xy 303.358735 -26.140939) (xy 303.394468 -26.097483) (xy 303.436184 -26.059733) (xy 303.482982 -26.028505)
			(xy 303.533852 -26.004474) (xy 303.587695 -25.988157) (xy 303.643348 -25.979908) (xy 303.671478 -25.979374)
			(xy 303.698732 -25.979835) (xy 303.752687 -25.98759) (xy 303.804988 -26.002944) (xy 303.854572 -26.025585)
			(xy 303.90043 -26.055052) (xy 303.941626 -26.090745) (xy 303.977324 -26.131938) (xy 304.006796 -26.177792)
			(xy 304.029442 -26.227374) (xy 304.044802 -26.279674) (xy 304.050564 -26.319734) (xy 309.041798 -26.319734)
			(xy 309.045869 -26.264112) (xy 309.057995 -26.209675) (xy 309.077918 -26.157584) (xy 309.105214 -26.108949)
			(xy 309.1393 -26.064806) (xy 309.179449 -26.026097) (xy 309.224807 -25.993646) (xy 309.274407 -25.968145)
			(xy 309.327191 -25.950138) (xy 309.382034 -25.940008) (xy 309.437768 -25.937971) (xy 309.493205 -25.944071)
			(xy 309.547162 -25.958177) (xy 309.598491 -25.979989) (xy 309.646097 -26.009043) (xy 309.675762 -26.03373)
			(xy 315.467744 -26.03373) (xy 315.471815 -25.978108) (xy 315.483941 -25.923671) (xy 315.503864 -25.87158)
			(xy 315.53116 -25.822945) (xy 315.565246 -25.778802) (xy 315.605395 -25.740093) (xy 315.650753 -25.707642)
			(xy 315.700353 -25.682141) (xy 315.753137 -25.664134) (xy 315.80798 -25.654004) (xy 315.863714 -25.651967)
			(xy 315.919151 -25.658067) (xy 315.973108 -25.672173) (xy 316.024437 -25.693985) (xy 316.072043 -25.723039)
			(xy 316.114911 -25.758714) (xy 316.152128 -25.800251) (xy 316.182901 -25.846764) (xy 316.206573 -25.897261)
			(xy 316.222641 -25.950668) (xy 316.230761 -26.005844) (xy 316.23127 -26.03373) (xy 316.230761 -26.061616)
			(xy 316.222641 -26.116792) (xy 316.206573 -26.170199) (xy 316.182901 -26.220696) (xy 316.152667 -26.266394)
			(xy 318.72047 -26.266394) (xy 318.720956 -26.239143) (xy 318.728712 -26.185195) (xy 318.744067 -26.1329)
			(xy 318.766709 -26.083323) (xy 318.796175 -26.037473) (xy 318.831866 -25.996282) (xy 318.873057 -25.960591)
			(xy 318.918907 -25.931125) (xy 318.968484 -25.908483) (xy 319.020779 -25.893128) (xy 319.074727 -25.885372)
			(xy 319.129229 -25.885372) (xy 319.183177 -25.893128) (xy 319.235472 -25.908483) (xy 319.285049 -25.931125)
			(xy 319.330899 -25.960591) (xy 319.37209 -25.996282) (xy 319.407781 -26.037473) (xy 319.437247 -26.083323)
			(xy 319.459889 -26.1329) (xy 319.475244 -26.185195) (xy 319.483 -26.239143) (xy 319.483486 -26.266394)
			(xy 319.48294 -26.295882) (xy 319.473844 -26.354153) (xy 319.455886 -26.410329) (xy 319.429491 -26.463069)
			(xy 319.395291 -26.511117) (xy 319.354101 -26.553326) (xy 319.330832 -26.571448) (xy 319.319685 -26.580314)
			(xy 319.30251 -26.603025) (xy 319.292269 -26.629594) (xy 319.289758 -26.657958) (xy 319.295171 -26.685913)
			(xy 319.308088 -26.711288) (xy 319.327506 -26.732114) (xy 319.339468 -26.73985) (xy 319.363197 -26.754766)
			(xy 319.406434 -26.790429) (xy 319.443987 -26.832034) (xy 319.475049 -26.878686) (xy 319.49895 -26.929381)
			(xy 319.515176 -26.983027) (xy 319.523377 -27.038471) (xy 319.523872 -27.066494) (xy 319.523386 -27.093745)
			(xy 319.51563 -27.147693) (xy 319.500275 -27.199988) (xy 319.477633 -27.249565) (xy 319.448167 -27.295415)
			(xy 319.412476 -27.336606) (xy 319.371285 -27.372297) (xy 319.325435 -27.401763) (xy 319.275858 -27.424405)
			(xy 319.223563 -27.43976) (xy 319.169615 -27.447516) (xy 319.115113 -27.447516) (xy 319.061165 -27.43976)
			(xy 319.00887 -27.424405) (xy 318.959293 -27.401763) (xy 318.913443 -27.372297) (xy 318.872252 -27.336606)
			(xy 318.836561 -27.295415) (xy 318.807095 -27.249565) (xy 318.784453 -27.199988) (xy 318.769098 -27.147693)
			(xy 318.761342 -27.093745) (xy 318.760856 -27.066494) (xy 318.761417 -27.037007) (xy 318.770512 -26.978738)
			(xy 318.78847 -26.922563) (xy 318.814861 -26.869823) (xy 318.849058 -26.821775) (xy 318.890244 -26.779564)
			(xy 318.91351 -26.76144) (xy 318.924575 -26.752476) (xy 318.94176 -26.729791) (xy 318.952014 -26.703243)
			(xy 318.954539 -26.674895) (xy 318.94914 -26.646953) (xy 318.936235 -26.621587) (xy 318.916829 -26.60077)
			(xy 318.904874 -26.593038) (xy 318.881126 -26.578151) (xy 318.837892 -26.542481) (xy 318.800342 -26.50087)
			(xy 318.769284 -26.454213) (xy 318.745386 -26.403514) (xy 318.729163 -26.349864) (xy 318.720964 -26.294418)
			(xy 318.72047 -26.266394) (xy 316.152667 -26.266394) (xy 316.152128 -26.267209) (xy 316.114911 -26.308746)
			(xy 316.072043 -26.344421) (xy 316.024437 -26.373475) (xy 315.973108 -26.395287) (xy 315.919151 -26.409393)
			(xy 315.863714 -26.415493) (xy 315.80798 -26.413456) (xy 315.753137 -26.403326) (xy 315.700353 -26.385319)
			(xy 315.650753 -26.359818) (xy 315.605395 -26.327367) (xy 315.565246 -26.288658) (xy 315.53116 -26.244515)
			(xy 315.503864 -26.19588) (xy 315.483941 -26.143789) (xy 315.471815 -26.089352) (xy 315.467744 -26.03373)
			(xy 309.675762 -26.03373) (xy 309.688965 -26.044718) (xy 309.726182 -26.086255) (xy 309.756955 -26.132768)
			(xy 309.780627 -26.183265) (xy 309.796695 -26.236672) (xy 309.804815 -26.291848) (xy 309.805324 -26.319734)
			(xy 309.804815 -26.34762) (xy 309.796695 -26.402796) (xy 309.780627 -26.456203) (xy 309.756955 -26.5067)
			(xy 309.726182 -26.553213) (xy 309.688965 -26.59475) (xy 309.646097 -26.630425) (xy 309.598491 -26.659479)
			(xy 309.547162 -26.681291) (xy 309.493205 -26.695397) (xy 309.437768 -26.701497) (xy 309.382034 -26.69946)
			(xy 309.327191 -26.68933) (xy 309.274407 -26.671323) (xy 309.224807 -26.645822) (xy 309.179449 -26.613371)
			(xy 309.1393 -26.574662) (xy 309.105214 -26.530519) (xy 309.077918 -26.481884) (xy 309.057995 -26.429793)
			(xy 309.045869 -26.375356) (xy 309.041798 -26.319734) (xy 304.050564 -26.319734) (xy 304.052562 -26.333628)
			(xy 304.052986 -26.360882) (xy 304.052986 -26.361898) (xy 304.051716 -26.392632) (xy 304.050954 -26.4033)
			(xy 304.054256 -26.412952) (xy 304.056041 -26.418043) (xy 304.061426 -26.427387) (xy 304.064924 -26.431494)
			(xy 304.097182 -26.466546) (xy 304.104672 -26.473998) (xy 304.123968 -26.482543) (xy 304.13452 -26.483056)
			(xy 304.28184 -26.483056) (xy 304.314994 -26.483522) (xy 304.380886 -26.490945) (xy 304.445534 -26.505695)
			(xy 304.508125 -26.527585) (xy 304.567875 -26.55634) (xy 304.624031 -26.591601) (xy 304.67589 -26.632923)
			(xy 304.69967 -26.65603) (xy 304.937922 -26.894028) (xy 304.944312 -26.899962) (xy 304.960038 -26.907466)
			(xy 304.977376 -26.909206) (xy 304.985928 -26.90749) (xy 304.987198 -26.907236) (xy 305.02987 -26.896822)
			(xy 305.034696 -26.895044) (xy 305.0413 -26.892758) (xy 305.047904 -26.887424) (xy 305.051022 -26.884963)
			(xy 305.056512 -26.879223) (xy 305.058826 -26.875994) (xy 305.061112 -26.872438) (xy 305.067462 -26.861516)
			(xy 305.068732 -26.857706) (xy 305.06924 -26.855928) (xy 305.077768 -26.830515) (xy 305.100952 -26.782184)
			(xy 305.130677 -26.737576) (xy 305.166354 -26.69757) (xy 305.207283 -26.662954) (xy 305.252655 -26.63441)
			(xy 305.301578 -26.612501) (xy 305.353086 -26.597659) (xy 305.406166 -26.590176) (xy 305.432968 -26.589736)
			(xy 305.460221 -26.590197) (xy 305.514173 -26.597951) (xy 305.566472 -26.613304) (xy 305.616054 -26.635946)
			(xy 305.661908 -26.665414) (xy 305.703101 -26.701108) (xy 305.738794 -26.742302) (xy 305.76826 -26.788157)
			(xy 305.7909 -26.837739) (xy 305.806252 -26.890038) (xy 305.814004 -26.943991) (xy 305.814476 -26.971244)
			(xy 305.813942 -27.00011) (xy 305.805236 -27.057182) (xy 305.78803 -27.11229) (xy 305.762716 -27.164176)
			(xy 305.729873 -27.211656) (xy 305.690251 -27.253644) (xy 305.644753 -27.289183) (xy 305.594421 -27.31746)
			(xy 305.567588 -27.328114) (xy 305.566572 -27.328622) (xy 305.55946 -27.331416) (xy 305.54295 -27.350974)
			(xy 305.522884 -27.446732) (xy 305.521445 -27.455079) (xy 305.523554 -27.471876) (xy 305.531034 -27.487062)
			(xy 305.536854 -27.493214) (xy 305.543966 -27.500326) (xy 305.551365 -27.50717) (xy 305.569964 -27.514892)
			(xy 305.580034 -27.515312) (xy 306.998116 -27.515312) (xy 307.030926 -27.515779) (xy 307.096127 -27.523194)
			(xy 307.16008 -27.537895) (xy 307.221974 -27.559695) (xy 307.281023 -27.588318) (xy 307.336479 -27.623399)
			(xy 307.362352 -27.643582) (xy 307.363876 -27.644598) (xy 307.38067 -27.657425) (xy 307.41258 -27.685136)
			(xy 307.42763 -27.69997) (xy 307.935376 -28.207716) (xy 307.940641 -28.210161) (xy 307.951927 -28.212866)
			(xy 307.957728 -28.21305) (xy 308.003956 -28.213304) (xy 308.028848 -28.213304) (xy 308.033801 -28.213181)
			(xy 308.043519 -28.211253) (xy 308.048152 -28.209494) (xy 308.058566 -28.205176) (xy 308.065678 -28.198064)
			(xy 308.087253 -28.177504) (xy 308.135601 -28.142661) (xy 308.188777 -28.115757) (xy 308.24549 -28.097448)
			(xy 308.304359 -28.088176) (xy 308.334156 -28.087574) (xy 308.334664 -28.087574) (xy 308.350666 -28.087828)
			(xy 308.356508 -28.088082) (xy 308.382534 -28.090014) (xy 308.433739 -28.1001) (xy 308.483091 -28.117072)
			(xy 308.526743 -28.139136) (xy 312.597798 -28.139136) (xy 312.601869 -28.083514) (xy 312.613995 -28.029077)
			(xy 312.633918 -27.976986) (xy 312.661214 -27.928351) (xy 312.6953 -27.884208) (xy 312.735449 -27.845499)
			(xy 312.780807 -27.813048) (xy 312.830407 -27.787547) (xy 312.883191 -27.76954) (xy 312.938034 -27.75941)
			(xy 312.993768 -27.757373) (xy 313.049205 -27.763473) (xy 313.103162 -27.777579) (xy 313.154491 -27.799391)
			(xy 313.202097 -27.828445) (xy 313.244965 -27.86412) (xy 313.282182 -27.905657) (xy 313.312955 -27.95217)
			(xy 313.336627 -28.002667) (xy 313.352695 -28.056074) (xy 313.360815 -28.11125) (xy 313.361324 -28.139136)
			(xy 313.867798 -28.139136) (xy 313.871869 -28.083514) (xy 313.883995 -28.029077) (xy 313.903918 -27.976986)
			(xy 313.931214 -27.928351) (xy 313.9653 -27.884208) (xy 314.005449 -27.845499) (xy 314.050807 -27.813048)
			(xy 314.100407 -27.787547) (xy 314.153191 -27.76954) (xy 314.208034 -27.75941) (xy 314.263768 -27.757373)
			(xy 314.319205 -27.763473) (xy 314.373162 -27.777579) (xy 314.424491 -27.799391) (xy 314.472097 -27.828445)
			(xy 314.514965 -27.86412) (xy 314.552182 -27.905657) (xy 314.582955 -27.95217) (xy 314.606627 -28.002667)
			(xy 314.622695 -28.056074) (xy 314.630815 -28.11125) (xy 314.631324 -28.139136) (xy 314.630815 -28.167022)
			(xy 314.622695 -28.222198) (xy 314.606627 -28.275605) (xy 314.582955 -28.326102) (xy 314.552182 -28.372615)
			(xy 314.514965 -28.414152) (xy 314.472097 -28.449827) (xy 314.424491 -28.478881) (xy 314.373162 -28.500693)
			(xy 314.319205 -28.514799) (xy 314.263768 -28.520899) (xy 314.208034 -28.518862) (xy 314.153191 -28.508732)
			(xy 314.100407 -28.490725) (xy 314.050807 -28.465224) (xy 314.005449 -28.432773) (xy 313.9653 -28.394064)
			(xy 313.931214 -28.349921) (xy 313.903918 -28.301286) (xy 313.883995 -28.249195) (xy 313.871869 -28.194758)
			(xy 313.867798 -28.139136) (xy 313.361324 -28.139136) (xy 313.360815 -28.167022) (xy 313.352695 -28.222198)
			(xy 313.336627 -28.275605) (xy 313.312955 -28.326102) (xy 313.282182 -28.372615) (xy 313.244965 -28.414152)
			(xy 313.202097 -28.449827) (xy 313.154491 -28.478881) (xy 313.103162 -28.500693) (xy 313.049205 -28.514799)
			(xy 312.993768 -28.520899) (xy 312.938034 -28.518862) (xy 312.883191 -28.508732) (xy 312.830407 -28.490725)
			(xy 312.780807 -28.465224) (xy 312.735449 -28.432773) (xy 312.6953 -28.394064) (xy 312.661214 -28.349921)
			(xy 312.633918 -28.301286) (xy 312.613995 -28.249195) (xy 312.601869 -28.194758) (xy 312.597798 -28.139136)
			(xy 308.526743 -28.139136) (xy 308.529669 -28.140615) (xy 308.572602 -28.170287) (xy 308.611088 -28.205535)
			(xy 308.644411 -28.245702) (xy 308.658514 -28.26766) (xy 308.67113 -28.288667) (xy 308.691461 -28.333253)
			(xy 308.705917 -28.380075) (xy 308.714258 -28.428362) (xy 308.715664 -28.452826) (xy 308.715664 -28.454096)
			(xy 308.715918 -28.468828) (xy 308.715918 -28.469336) (xy 308.715787 -28.484643) (xy 308.713372 -28.51516)
			(xy 308.711092 -28.530296) (xy 308.706232 -28.557364) (xy 308.689764 -28.609835) (xy 308.665946 -28.659404)
			(xy 308.635269 -28.705048) (xy 308.598367 -28.745823) (xy 308.577488 -28.763722) (xy 308.57571 -28.765246)
			(xy 308.573678 -28.767278) (xy 308.567079 -28.774699) (xy 308.559626 -28.793085) (xy 308.559707 -28.812924)
			(xy 308.567309 -28.831249) (xy 308.573932 -28.838652) (xy 308.590442 -28.855162) (xy 308.590442 -28.862782)
			(xy 308.85003 -29.12237) (xy 318.806576 -29.12237) (xy 318.806576 -28.25877) (xy 318.807066 -28.228786)
			(xy 318.814894 -28.16933) (xy 318.830415 -28.111405) (xy 318.853364 -28.056001) (xy 318.883348 -28.004067)
			(xy 318.919854 -27.956491) (xy 318.962259 -27.914086) (xy 319.009835 -27.87758) (xy 319.061769 -27.847596)
			(xy 319.117173 -27.824647) (xy 319.175098 -27.809126) (xy 319.234554 -27.801298) (xy 319.294522 -27.801298)
			(xy 319.353978 -27.809126) (xy 319.411903 -27.824647) (xy 319.467307 -27.847596) (xy 319.519241 -27.87758)
			(xy 319.566817 -27.914086) (xy 319.609222 -27.956491) (xy 319.645728 -28.004067) (xy 319.675712 -28.056001)
			(xy 319.698661 -28.111405) (xy 319.714182 -28.16933) (xy 319.72201 -28.228786) (xy 319.7225 -28.25877)
			(xy 319.7225 -29.12237) (xy 319.72201 -29.152354) (xy 319.714182 -29.21181) (xy 319.698661 -29.269735)
			(xy 319.675712 -29.325139) (xy 319.645728 -29.377073) (xy 319.609222 -29.424649) (xy 319.566817 -29.467054)
			(xy 319.519241 -29.50356) (xy 319.467307 -29.533544) (xy 319.411903 -29.556493) (xy 319.353978 -29.572014)
			(xy 319.294522 -29.579842) (xy 319.234554 -29.579842) (xy 319.175098 -29.572014) (xy 319.117173 -29.556493)
			(xy 319.061769 -29.533544) (xy 319.009835 -29.50356) (xy 318.962259 -29.467054) (xy 318.919854 -29.424649)
			(xy 318.883348 -29.377073) (xy 318.853364 -29.325139) (xy 318.830415 -29.269735) (xy 318.814894 -29.21181)
			(xy 318.807066 -29.152354) (xy 318.806576 -29.12237) (xy 308.85003 -29.12237) (xy 309.89143 -30.16377)
			(xy 309.91454 -30.187548) (xy 309.955872 -30.239401) (xy 309.991139 -30.295556) (xy 310.019898 -30.355306)
			(xy 310.027441 -30.376876) (xy 311.088786 -30.376876) (xy 311.089326 -30.34796) (xy 311.098046 -30.290788)
			(xy 311.115298 -30.235588) (xy 311.140685 -30.183626) (xy 311.173626 -30.136091) (xy 311.213367 -30.094075)
			(xy 311.235852 -30.075886) (xy 311.244664 -30.068284) (xy 311.254843 -30.047379) (xy 311.25541 -30.035754)
			(xy 311.25541 -29.955998) (xy 311.254854 -29.944368) (xy 311.244677 -29.923459) (xy 311.235852 -29.915866)
			(xy 311.213342 -29.897706) (xy 311.173611 -29.855679) (xy 311.140676 -29.808137) (xy 311.115293 -29.75617)
			(xy 311.098042 -29.700967) (xy 311.089318 -29.643794) (xy 311.088786 -29.614876) (xy 311.089272 -29.587625)
			(xy 311.097028 -29.533677) (xy 311.112383 -29.481382) (xy 311.135025 -29.431805) (xy 311.164491 -29.385955)
			(xy 311.200182 -29.344764) (xy 311.241373 -29.309073) (xy 311.287223 -29.279607) (xy 311.3368 -29.256965)
			(xy 311.389095 -29.24161) (xy 311.443043 -29.233854) (xy 311.497545 -29.233854) (xy 311.551493 -29.24161)
			(xy 311.603788 -29.256965) (xy 311.653365 -29.279607) (xy 311.699215 -29.309073) (xy 311.740406 -29.344764)
			(xy 311.776097 -29.385955) (xy 311.805563 -29.431805) (xy 311.828205 -29.481382) (xy 311.84356 -29.533677)
			(xy 311.851316 -29.587625) (xy 311.851802 -29.614876) (xy 311.851266 -29.643792) (xy 311.84254 -29.700963)
			(xy 311.825286 -29.756161) (xy 311.799898 -29.808123) (xy 311.766957 -29.855657) (xy 311.72722 -29.897675)
			(xy 311.704736 -29.915866) (xy 311.695943 -29.923487) (xy 311.685754 -29.944378) (xy 311.685178 -29.955998)
			(xy 311.685178 -30.035754) (xy 311.685708 -30.047387) (xy 311.695904 -30.068295) (xy 311.704736 -30.075886)
			(xy 311.72722 -30.094076) (xy 311.766954 -30.136097) (xy 311.799892 -30.183632) (xy 311.82528 -30.235594)
			(xy 311.842536 -30.290791) (xy 311.851266 -30.34796) (xy 311.851802 -30.376876) (xy 314.128912 -30.376876)
			(xy 314.12948 -30.347961) (xy 314.138198 -30.290792) (xy 314.155446 -30.235594) (xy 314.180828 -30.183632)
			(xy 314.213763 -30.136097) (xy 314.253496 -30.094077) (xy 314.275978 -30.075886) (xy 314.284794 -30.068288)
			(xy 314.29497 -30.04738) (xy 314.295536 -30.035754) (xy 314.295536 -29.955998) (xy 314.295006 -29.944364)
			(xy 314.284813 -29.923453) (xy 314.275978 -29.915866) (xy 314.253474 -29.8977) (xy 314.213741 -29.855674)
			(xy 314.180805 -29.808134) (xy 314.15542 -29.756168) (xy 314.138168 -29.700966) (xy 314.129444 -29.643793)
			(xy 314.128912 -29.614876) (xy 314.129398 -29.587625) (xy 314.137154 -29.533677) (xy 314.152509 -29.481382)
			(xy 314.175151 -29.431805) (xy 314.204617 -29.385955) (xy 314.240308 -29.344764) (xy 314.281499 -29.309073)
			(xy 314.327349 -29.279607) (xy 314.376926 -29.256965) (xy 314.429221 -29.24161) (xy 314.483169 -29.233854)
			(xy 314.537671 -29.233854) (xy 314.591619 -29.24161) (xy 314.643914 -29.256965) (xy 314.693491 -29.279607)
			(xy 314.739341 -29.309073) (xy 314.780532 -29.344764) (xy 314.816223 -29.385955) (xy 314.845689 -29.431805)
			(xy 314.868331 -29.481382) (xy 314.883686 -29.533677) (xy 314.891442 -29.587625) (xy 314.891928 -29.614876)
			(xy 314.89142 -29.643794) (xy 314.882693 -29.700967) (xy 314.865434 -29.756167) (xy 314.840041 -29.808129)
			(xy 314.807094 -29.855662) (xy 314.76735 -29.897677) (xy 314.744862 -29.915866) (xy 314.736074 -29.923491)
			(xy 314.725881 -29.944378) (xy 314.725304 -29.955998) (xy 314.725304 -30.035754) (xy 314.725825 -30.047388)
			(xy 314.736026 -30.068298) (xy 314.744862 -30.075886) (xy 314.767331 -30.094095) (xy 314.807069 -30.136109)
			(xy 314.840011 -30.18364) (xy 314.865402 -30.235598) (xy 314.882661 -30.290793) (xy 314.891392 -30.347961)
			(xy 314.891928 -30.376876) (xy 314.891442 -30.404127) (xy 314.883686 -30.458075) (xy 314.868331 -30.51037)
			(xy 314.845689 -30.559947) (xy 314.816223 -30.605797) (xy 314.780532 -30.646988) (xy 314.739341 -30.682679)
			(xy 314.693491 -30.712145) (xy 314.643914 -30.734787) (xy 314.591619 -30.750142) (xy 314.537671 -30.757898)
			(xy 314.483169 -30.757898) (xy 314.429221 -30.750142) (xy 314.376926 -30.734787) (xy 314.327349 -30.712145)
			(xy 314.281499 -30.682679) (xy 314.240308 -30.646988) (xy 314.204617 -30.605797) (xy 314.175151 -30.559947)
			(xy 314.152509 -30.51037) (xy 314.137154 -30.458075) (xy 314.129398 -30.404127) (xy 314.128912 -30.376876)
			(xy 311.851802 -30.376876) (xy 311.851316 -30.404127) (xy 311.84356 -30.458075) (xy 311.828205 -30.51037)
			(xy 311.805563 -30.559947) (xy 311.776097 -30.605797) (xy 311.740406 -30.646988) (xy 311.699215 -30.682679)
			(xy 311.653365 -30.712145) (xy 311.603788 -30.734787) (xy 311.551493 -30.750142) (xy 311.497545 -30.757898)
			(xy 311.443043 -30.757898) (xy 311.389095 -30.750142) (xy 311.3368 -30.734787) (xy 311.287223 -30.712145)
			(xy 311.241373 -30.682679) (xy 311.200182 -30.646988) (xy 311.164491 -30.605797) (xy 311.135025 -30.559947)
			(xy 311.112383 -30.51037) (xy 311.097028 -30.458075) (xy 311.089272 -30.404127) (xy 311.088786 -30.376876)
			(xy 310.027441 -30.376876) (xy 310.041786 -30.417899) (xy 310.056529 -30.48255) (xy 310.063942 -30.548445)
			(xy 310.064404 -30.5816) (xy 310.064404 -30.922468) (xy 316.952376 -30.922468) (xy 316.952376 -30.058868)
			(xy 316.952866 -30.028884) (xy 316.960694 -29.969428) (xy 316.976215 -29.911503) (xy 316.999164 -29.856099)
			(xy 317.029148 -29.804165) (xy 317.065654 -29.756589) (xy 317.108059 -29.714184) (xy 317.155635 -29.677678)
			(xy 317.207569 -29.647694) (xy 317.262973 -29.624745) (xy 317.320898 -29.609224) (xy 317.380354 -29.601396)
			(xy 317.440322 -29.601396) (xy 317.499778 -29.609224) (xy 317.557703 -29.624745) (xy 317.613107 -29.647694)
			(xy 317.665041 -29.677678) (xy 317.712617 -29.714184) (xy 317.755022 -29.756589) (xy 317.791528 -29.804165)
			(xy 317.821512 -29.856099) (xy 317.844461 -29.911503) (xy 317.859982 -29.969428) (xy 317.86781 -30.028884)
			(xy 317.8683 -30.058868) (xy 317.8683 -30.92069) (xy 331.689456 -30.92069) (xy 331.689456 -30.05709)
			(xy 331.689946 -30.027122) (xy 331.697769 -29.9677) (xy 331.713282 -29.909807) (xy 331.736218 -29.854434)
			(xy 331.766185 -29.802528) (xy 331.802672 -29.754978) (xy 331.845052 -29.712598) (xy 331.892602 -29.676111)
			(xy 331.944508 -29.646144) (xy 331.999881 -29.623208) (xy 332.057774 -29.607695) (xy 332.117196 -29.599872)
			(xy 332.177132 -29.599872) (xy 332.236554 -29.607695) (xy 332.294447 -29.623208) (xy 332.34982 -29.646144)
			(xy 332.401726 -29.676111) (xy 332.449276 -29.712598) (xy 332.491656 -29.754978) (xy 332.528143 -29.802528)
			(xy 332.55811 -29.854434) (xy 332.581046 -29.909807) (xy 332.596559 -29.9677) (xy 332.604382 -30.027122)
			(xy 332.604872 -30.05709) (xy 332.604872 -30.92069) (xy 332.604382 -30.950658) (xy 332.596559 -31.01008)
			(xy 332.581046 -31.067973) (xy 332.55811 -31.123346) (xy 332.528143 -31.175252) (xy 332.491656 -31.222802)
			(xy 332.449276 -31.265182) (xy 332.401726 -31.301669) (xy 332.34982 -31.331636) (xy 332.294447 -31.354572)
			(xy 332.236554 -31.370085) (xy 332.177132 -31.377908) (xy 332.117196 -31.377908) (xy 332.057774 -31.370085)
			(xy 331.999881 -31.354572) (xy 331.944508 -31.331636) (xy 331.892602 -31.301669) (xy 331.845052 -31.265182)
			(xy 331.802672 -31.222802) (xy 331.766185 -31.175252) (xy 331.736218 -31.123346) (xy 331.713282 -31.067973)
			(xy 331.697769 -31.01008) (xy 331.689946 -30.950658) (xy 331.689456 -30.92069) (xy 317.8683 -30.92069)
			(xy 317.8683 -30.922468) (xy 317.86781 -30.952452) (xy 317.859982 -31.011908) (xy 317.844461 -31.069833)
			(xy 317.821512 -31.125237) (xy 317.791528 -31.177171) (xy 317.755022 -31.224747) (xy 317.712617 -31.267152)
			(xy 317.665041 -31.303658) (xy 317.613107 -31.333642) (xy 317.557703 -31.356591) (xy 317.499778 -31.372112)
			(xy 317.440322 -31.37994) (xy 317.380354 -31.37994) (xy 317.320898 -31.372112) (xy 317.262973 -31.356591)
			(xy 317.207569 -31.333642) (xy 317.155635 -31.303658) (xy 317.108059 -31.267152) (xy 317.065654 -31.224747)
			(xy 317.029148 -31.177171) (xy 316.999164 -31.125237) (xy 316.976215 -31.069833) (xy 316.960694 -31.011908)
			(xy 316.952866 -30.952452) (xy 316.952376 -30.922468) (xy 310.064404 -30.922468) (xy 310.064404 -31.567882)
			(xy 311.198512 -31.567882) (xy 311.202583 -31.51226) (xy 311.214709 -31.457823) (xy 311.234632 -31.405732)
			(xy 311.261928 -31.357097) (xy 311.296014 -31.312954) (xy 311.336163 -31.274245) (xy 311.381521 -31.241794)
			(xy 311.431121 -31.216293) (xy 311.483905 -31.198286) (xy 311.538748 -31.188156) (xy 311.594482 -31.186119)
			(xy 311.649919 -31.192219) (xy 311.703876 -31.206325) (xy 311.755205 -31.228137) (xy 311.802811 -31.257191)
			(xy 311.845679 -31.292866) (xy 311.882896 -31.334403) (xy 311.913669 -31.380916) (xy 311.937341 -31.431413)
			(xy 311.953409 -31.48482) (xy 311.961529 -31.539996) (xy 311.962038 -31.567882) (xy 311.961529 -31.595768)
			(xy 311.953409 -31.650944) (xy 311.937341 -31.704351) (xy 311.930349 -31.719266) (xy 312.485276 -31.719266)
			(xy 312.489347 -31.663644) (xy 312.501473 -31.609207) (xy 312.521396 -31.557116) (xy 312.548692 -31.508481)
			(xy 312.582778 -31.464338) (xy 312.622927 -31.425629) (xy 312.668285 -31.393178) (xy 312.717885 -31.367677)
			(xy 312.770669 -31.34967) (xy 312.825512 -31.33954) (xy 312.881246 -31.337503) (xy 312.936683 -31.343603)
			(xy 312.99064 -31.357709) (xy 313.041969 -31.379521) (xy 313.089575 -31.408575) (xy 313.132443 -31.44425)
			(xy 313.16966 -31.485787) (xy 313.200433 -31.5323) (xy 313.224105 -31.582797) (xy 313.240173 -31.636204)
			(xy 313.244323 -31.664402) (xy 313.760864 -31.664402) (xy 313.764935 -31.60878) (xy 313.777061 -31.554343)
			(xy 313.796984 -31.502252) (xy 313.82428 -31.453617) (xy 313.858366 -31.409474) (xy 313.898515 -31.370765)
			(xy 313.943873 -31.338314) (xy 313.993473 -31.312813) (xy 314.046257 -31.294806) (xy 314.1011 -31.284676)
			(xy 314.156834 -31.282639) (xy 314.212271 -31.288739) (xy 314.266228 -31.302845) (xy 314.317557 -31.324657)
			(xy 314.365163 -31.353711) (xy 314.408031 -31.389386) (xy 314.445248 -31.430923) (xy 314.476021 -31.477436)
			(xy 314.499693 -31.527933) (xy 314.515761 -31.58134) (xy 314.523881 -31.636516) (xy 314.52439 -31.664402)
			(xy 314.523881 -31.692288) (xy 314.515761 -31.747464) (xy 314.506821 -31.777178) (xy 315.026038 -31.777178)
			(xy 315.030109 -31.721556) (xy 315.042235 -31.667119) (xy 315.062158 -31.615028) (xy 315.089454 -31.566393)
			(xy 315.12354 -31.52225) (xy 315.163689 -31.483541) (xy 315.209047 -31.45109) (xy 315.258647 -31.425589)
			(xy 315.311431 -31.407582) (xy 315.366274 -31.397452) (xy 315.422008 -31.395415) (xy 315.477445 -31.401515)
			(xy 315.531402 -31.415621) (xy 315.582731 -31.437433) (xy 315.630337 -31.466487) (xy 315.673205 -31.502162)
			(xy 315.710422 -31.543699) (xy 315.741195 -31.590212) (xy 315.764867 -31.640709) (xy 315.780935 -31.694116)
			(xy 315.789055 -31.749292) (xy 315.789564 -31.777178) (xy 315.789055 -31.805064) (xy 315.780935 -31.86024)
			(xy 315.764867 -31.913647) (xy 315.741195 -31.964144) (xy 315.710422 -32.010657) (xy 315.673205 -32.052194)
			(xy 315.630337 -32.087869) (xy 315.582731 -32.116923) (xy 315.531402 -32.138735) (xy 315.477445 -32.152841)
			(xy 315.422008 -32.158941) (xy 315.366274 -32.156904) (xy 315.311431 -32.146774) (xy 315.258647 -32.128767)
			(xy 315.209047 -32.103266) (xy 315.163689 -32.070815) (xy 315.12354 -32.032106) (xy 315.089454 -31.987963)
			(xy 315.062158 -31.939328) (xy 315.042235 -31.887237) (xy 315.030109 -31.8328) (xy 315.026038 -31.777178)
			(xy 314.506821 -31.777178) (xy 314.499693 -31.800871) (xy 314.476021 -31.851368) (xy 314.445248 -31.897881)
			(xy 314.408031 -31.939418) (xy 314.365163 -31.975093) (xy 314.317557 -32.004147) (xy 314.266228 -32.025959)
			(xy 314.212271 -32.040065) (xy 314.156834 -32.046165) (xy 314.1011 -32.044128) (xy 314.046257 -32.033998)
			(xy 313.993473 -32.015991) (xy 313.943873 -31.99049) (xy 313.898515 -31.958039) (xy 313.858366 -31.91933)
			(xy 313.82428 -31.875187) (xy 313.796984 -31.826552) (xy 313.777061 -31.774461) (xy 313.764935 -31.720024)
			(xy 313.760864 -31.664402) (xy 313.244323 -31.664402) (xy 313.248293 -31.69138) (xy 313.248802 -31.719266)
			(xy 313.248293 -31.747152) (xy 313.240173 -31.802328) (xy 313.224105 -31.855735) (xy 313.200433 -31.906232)
			(xy 313.16966 -31.952745) (xy 313.132443 -31.994282) (xy 313.089575 -32.029957) (xy 313.041969 -32.059011)
			(xy 312.99064 -32.080823) (xy 312.936683 -32.094929) (xy 312.881246 -32.101029) (xy 312.825512 -32.098992)
			(xy 312.770669 -32.088862) (xy 312.717885 -32.070855) (xy 312.668285 -32.045354) (xy 312.622927 -32.012903)
			(xy 312.582778 -31.974194) (xy 312.548692 -31.930051) (xy 312.521396 -31.881416) (xy 312.501473 -31.829325)
			(xy 312.489347 -31.774888) (xy 312.485276 -31.719266) (xy 311.930349 -31.719266) (xy 311.913669 -31.754848)
			(xy 311.882896 -31.801361) (xy 311.845679 -31.842898) (xy 311.802811 -31.878573) (xy 311.755205 -31.907627)
			(xy 311.703876 -31.929439) (xy 311.649919 -31.943545) (xy 311.594482 -31.949645) (xy 311.538748 -31.947608)
			(xy 311.483905 -31.937478) (xy 311.431121 -31.919471) (xy 311.381521 -31.89397) (xy 311.336163 -31.861519)
			(xy 311.296014 -31.82281) (xy 311.261928 -31.778667) (xy 311.234632 -31.730032) (xy 311.214709 -31.677941)
			(xy 311.202583 -31.623504) (xy 311.198512 -31.567882) (xy 310.064404 -31.567882) (xy 310.064404 -32.722312)
			(xy 318.806576 -32.722312) (xy 318.806576 -31.858712) (xy 318.807066 -31.828728) (xy 318.814894 -31.769272)
			(xy 318.830415 -31.711347) (xy 318.853364 -31.655943) (xy 318.883348 -31.604009) (xy 318.919854 -31.556433)
			(xy 318.962259 -31.514028) (xy 319.009835 -31.477522) (xy 319.061769 -31.447538) (xy 319.117173 -31.424589)
			(xy 319.175098 -31.409068) (xy 319.234554 -31.40124) (xy 319.294522 -31.40124) (xy 319.353978 -31.409068)
			(xy 319.411903 -31.424589) (xy 319.467307 -31.447538) (xy 319.519241 -31.477522) (xy 319.566817 -31.514028)
			(xy 319.609222 -31.556433) (xy 319.645728 -31.604009) (xy 319.675712 -31.655943) (xy 319.698661 -31.711347)
			(xy 319.714182 -31.769272) (xy 319.72201 -31.828728) (xy 319.7225 -31.858712) (xy 319.7225 -32.714184)
			(xy 329.047348 -32.714184) (xy 329.047348 -31.850584) (xy 329.047838 -31.820616) (xy 329.055661 -31.761194)
			(xy 329.071174 -31.703301) (xy 329.09411 -31.647928) (xy 329.124077 -31.596022) (xy 329.160564 -31.548472)
			(xy 329.202944 -31.506092) (xy 329.250494 -31.469605) (xy 329.3024 -31.439638) (xy 329.357773 -31.416702)
			(xy 329.415666 -31.401189) (xy 329.475088 -31.393366) (xy 329.535024 -31.393366) (xy 329.594446 -31.401189)
			(xy 329.652339 -31.416702) (xy 329.707712 -31.439638) (xy 329.759618 -31.469605) (xy 329.807168 -31.506092)
			(xy 329.849548 -31.548472) (xy 329.886035 -31.596022) (xy 329.916002 -31.647928) (xy 329.938938 -31.703301)
			(xy 329.954451 -31.761194) (xy 329.962274 -31.820616) (xy 329.962764 -31.850584) (xy 329.962764 -32.714184)
			(xy 329.962274 -32.744152) (xy 329.954451 -32.803574) (xy 329.938938 -32.861467) (xy 329.916002 -32.91684)
			(xy 329.886035 -32.968746) (xy 329.849548 -33.016296) (xy 329.807168 -33.058676) (xy 329.759618 -33.095163)
			(xy 329.707712 -33.12513) (xy 329.652339 -33.148066) (xy 329.594446 -33.163579) (xy 329.535024 -33.171402)
			(xy 329.475088 -33.171402) (xy 329.415666 -33.163579) (xy 329.357773 -33.148066) (xy 329.3024 -33.12513)
			(xy 329.250494 -33.095163) (xy 329.202944 -33.058676) (xy 329.160564 -33.016296) (xy 329.124077 -32.968746)
			(xy 329.09411 -32.91684) (xy 329.071174 -32.861467) (xy 329.055661 -32.803574) (xy 329.047838 -32.744152)
			(xy 329.047348 -32.714184) (xy 319.7225 -32.714184) (xy 319.7225 -32.722312) (xy 319.72201 -32.752296)
			(xy 319.714182 -32.811752) (xy 319.698661 -32.869677) (xy 319.675712 -32.925081) (xy 319.645728 -32.977015)
			(xy 319.609222 -33.024591) (xy 319.566817 -33.066996) (xy 319.519241 -33.103502) (xy 319.467307 -33.133486)
			(xy 319.411903 -33.156435) (xy 319.353978 -33.171956) (xy 319.294522 -33.179784) (xy 319.234554 -33.179784)
			(xy 319.175098 -33.171956) (xy 319.117173 -33.156435) (xy 319.061769 -33.133486) (xy 319.009835 -33.103502)
			(xy 318.962259 -33.066996) (xy 318.919854 -33.024591) (xy 318.883348 -32.977015) (xy 318.853364 -32.925081)
			(xy 318.830415 -32.869677) (xy 318.814894 -32.811752) (xy 318.807066 -32.752296) (xy 318.806576 -32.722312)
			(xy 310.064404 -32.722312) (xy 310.064404 -34.52241) (xy 316.952376 -34.52241) (xy 316.952376 -33.65881)
			(xy 316.952866 -33.628826) (xy 316.960694 -33.56937) (xy 316.976215 -33.511445) (xy 316.999164 -33.456041)
			(xy 317.029148 -33.404107) (xy 317.065654 -33.356531) (xy 317.108059 -33.314126) (xy 317.155635 -33.27762)
			(xy 317.207569 -33.247636) (xy 317.262973 -33.224687) (xy 317.320898 -33.209166) (xy 317.380354 -33.201338)
			(xy 317.440322 -33.201338) (xy 317.499778 -33.209166) (xy 317.557703 -33.224687) (xy 317.613107 -33.247636)
			(xy 317.665041 -33.27762) (xy 317.712617 -33.314126) (xy 317.755022 -33.356531) (xy 317.791528 -33.404107)
			(xy 317.821512 -33.456041) (xy 317.844461 -33.511445) (xy 317.859982 -33.56937) (xy 317.86781 -33.628826)
			(xy 317.8683 -33.65881) (xy 317.8683 -34.520886) (xy 331.689456 -34.520886) (xy 331.689456 -33.657286)
			(xy 331.689946 -33.627318) (xy 331.697769 -33.567896) (xy 331.713282 -33.510003) (xy 331.736218 -33.45463)
			(xy 331.766185 -33.402724) (xy 331.802672 -33.355174) (xy 331.845052 -33.312794) (xy 331.892602 -33.276307)
			(xy 331.944508 -33.24634) (xy 331.999881 -33.223404) (xy 332.057774 -33.207891) (xy 332.117196 -33.200068)
			(xy 332.177132 -33.200068) (xy 332.236554 -33.207891) (xy 332.294447 -33.223404) (xy 332.34982 -33.24634)
			(xy 332.401726 -33.276307) (xy 332.449276 -33.312794) (xy 332.491656 -33.355174) (xy 332.528143 -33.402724)
			(xy 332.55811 -33.45463) (xy 332.581046 -33.510003) (xy 332.596559 -33.567896) (xy 332.604382 -33.627318)
			(xy 332.604872 -33.657286) (xy 332.604872 -34.520886) (xy 332.604382 -34.550854) (xy 332.596559 -34.610276)
			(xy 332.581046 -34.668169) (xy 332.55811 -34.723542) (xy 332.528143 -34.775448) (xy 332.491656 -34.822998)
			(xy 332.449276 -34.865378) (xy 332.401726 -34.901865) (xy 332.34982 -34.931832) (xy 332.294447 -34.954768)
			(xy 332.236554 -34.970281) (xy 332.177132 -34.978104) (xy 332.117196 -34.978104) (xy 332.057774 -34.970281)
			(xy 331.999881 -34.954768) (xy 331.944508 -34.931832) (xy 331.892602 -34.901865) (xy 331.845052 -34.865378)
			(xy 331.802672 -34.822998) (xy 331.766185 -34.775448) (xy 331.736218 -34.723542) (xy 331.713282 -34.668169)
			(xy 331.697769 -34.610276) (xy 331.689946 -34.550854) (xy 331.689456 -34.520886) (xy 317.8683 -34.520886)
			(xy 317.8683 -34.52241) (xy 317.86781 -34.552394) (xy 317.859982 -34.61185) (xy 317.844461 -34.669775)
			(xy 317.821512 -34.725179) (xy 317.791528 -34.777113) (xy 317.755022 -34.824689) (xy 317.712617 -34.867094)
			(xy 317.665041 -34.9036) (xy 317.613107 -34.933584) (xy 317.557703 -34.956533) (xy 317.499778 -34.972054)
			(xy 317.440322 -34.979882) (xy 317.380354 -34.979882) (xy 317.320898 -34.972054) (xy 317.262973 -34.956533)
			(xy 317.207569 -34.933584) (xy 317.155635 -34.9036) (xy 317.108059 -34.867094) (xy 317.065654 -34.824689)
			(xy 317.029148 -34.777113) (xy 316.999164 -34.725179) (xy 316.976215 -34.669775) (xy 316.960694 -34.61185)
			(xy 316.952866 -34.552394) (xy 316.952376 -34.52241) (xy 310.064404 -34.52241) (xy 310.064404 -35.264852)
			(xy 314.10224 -35.264852) (xy 314.106311 -35.20923) (xy 314.118437 -35.154793) (xy 314.13836 -35.102702)
			(xy 314.165656 -35.054067) (xy 314.199742 -35.009924) (xy 314.239891 -34.971215) (xy 314.285249 -34.938764)
			(xy 314.334849 -34.913263) (xy 314.387633 -34.895256) (xy 314.442476 -34.885126) (xy 314.49821 -34.883089)
			(xy 314.553647 -34.889189) (xy 314.607604 -34.903295) (xy 314.658933 -34.925107) (xy 314.706539 -34.954161)
			(xy 314.749407 -34.989836) (xy 314.786624 -35.031373) (xy 314.817397 -35.077886) (xy 314.841069 -35.128383)
			(xy 314.857137 -35.18179) (xy 314.865257 -35.236966) (xy 314.865766 -35.264852) (xy 314.865257 -35.292738)
			(xy 314.857137 -35.347914) (xy 314.841069 -35.401321) (xy 314.817397 -35.451818) (xy 314.786624 -35.498331)
			(xy 314.749407 -35.539868) (xy 314.706539 -35.575543) (xy 314.658933 -35.604597) (xy 314.607604 -35.626409)
			(xy 314.553647 -35.640515) (xy 314.49821 -35.646615) (xy 314.442476 -35.644578) (xy 314.387633 -35.634448)
			(xy 314.334849 -35.616441) (xy 314.285249 -35.59094) (xy 314.239891 -35.558489) (xy 314.199742 -35.51978)
			(xy 314.165656 -35.475637) (xy 314.13836 -35.427002) (xy 314.118437 -35.374911) (xy 314.106311 -35.320474)
			(xy 314.10224 -35.264852) (xy 310.064404 -35.264852) (xy 310.064404 -36.286948) (xy 315.40018 -36.286948)
			(xy 315.404251 -36.231326) (xy 315.416377 -36.176889) (xy 315.4363 -36.124798) (xy 315.463596 -36.076163)
			(xy 315.497682 -36.03202) (xy 315.537831 -35.993311) (xy 315.583189 -35.96086) (xy 315.632789 -35.935359)
			(xy 315.685573 -35.917352) (xy 315.740416 -35.907222) (xy 315.79615 -35.905185) (xy 315.851587 -35.911285)
			(xy 315.905544 -35.925391) (xy 315.956873 -35.947203) (xy 316.004479 -35.976257) (xy 316.047347 -36.011932)
			(xy 316.084564 -36.053469) (xy 316.115337 -36.099982) (xy 316.139009 -36.150479) (xy 316.155077 -36.203886)
			(xy 316.163197 -36.259062) (xy 316.163706 -36.286948) (xy 316.163197 -36.314834) (xy 316.155077 -36.37001)
			(xy 316.139009 -36.423417) (xy 316.115337 -36.473914) (xy 316.087792 -36.515548) (xy 317.213994 -36.515548)
			(xy 317.218065 -36.459926) (xy 317.230191 -36.405489) (xy 317.250114 -36.353398) (xy 317.27741 -36.304763)
			(xy 317.311496 -36.26062) (xy 317.351645 -36.221911) (xy 317.397003 -36.18946) (xy 317.446603 -36.163959)
			(xy 317.499387 -36.145952) (xy 317.55423 -36.135822) (xy 317.609964 -36.133785) (xy 317.665401 -36.139885)
			(xy 317.719358 -36.153991) (xy 317.770687 -36.175803) (xy 317.818293 -36.204857) (xy 317.861161 -36.240532)
			(xy 317.898378 -36.282069) (xy 317.929151 -36.328582) (xy 317.952823 -36.379079) (xy 317.968891 -36.432486)
			(xy 317.977011 -36.487662) (xy 317.97752 -36.515548) (xy 317.977011 -36.543434) (xy 317.968891 -36.59861)
			(xy 317.968434 -36.60013) (xy 322.197991 -36.60013) (xy 322.201996 -36.512222) (xy 322.213979 -36.425042)
			(xy 322.233839 -36.339313) (xy 322.261414 -36.255745) (xy 322.296473 -36.175031) (xy 322.338726 -36.097839)
			(xy 322.387824 -36.02481) (xy 322.44336 -35.956548) (xy 322.504872 -35.893618) (xy 322.571853 -35.836544)
			(xy 322.643746 -35.785796) (xy 322.719955 -35.741796) (xy 322.79985 -35.704909) (xy 322.882769 -35.67544)
			(xy 322.968024 -35.653633) (xy 323.054908 -35.639669) (xy 323.142702 -35.633663) (xy 323.230679 -35.635667)
			(xy 323.318109 -35.645662) (xy 323.404268 -35.663566) (xy 323.488442 -35.68923) (xy 323.569933 -35.722443)
			(xy 323.648067 -35.762929) (xy 323.722195 -35.810351) (xy 323.791703 -35.864318) (xy 323.856017 -35.924383)
			(xy 323.914601 -35.990047) (xy 323.966972 -36.060766) (xy 324.012695 -36.135954) (xy 324.051392 -36.214989)
			(xy 324.082741 -36.297215) (xy 324.106483 -36.381951) (xy 324.122421 -36.468495) (xy 324.130423 -36.55613)
			(xy 324.130924 -36.60013) (xy 324.130423 -36.64413) (xy 324.122421 -36.731765) (xy 324.106483 -36.818309)
			(xy 324.082741 -36.903045) (xy 324.051392 -36.985271) (xy 324.012695 -37.064306) (xy 323.966972 -37.139494)
			(xy 323.914601 -37.210213) (xy 323.856017 -37.275877) (xy 323.791703 -37.335942) (xy 323.722195 -37.389909)
			(xy 323.648067 -37.437331) (xy 323.569933 -37.477817) (xy 323.488442 -37.51103) (xy 323.404268 -37.536694)
			(xy 323.318109 -37.554598) (xy 323.230679 -37.564593) (xy 323.142702 -37.566597) (xy 323.054908 -37.560591)
			(xy 322.968024 -37.546627) (xy 322.882769 -37.52482) (xy 322.79985 -37.495351) (xy 322.719955 -37.458464)
			(xy 322.643746 -37.414464) (xy 322.571853 -37.363716) (xy 322.504872 -37.306642) (xy 322.44336 -37.243712)
			(xy 322.387824 -37.17545) (xy 322.338726 -37.102421) (xy 322.296473 -37.025229) (xy 322.261414 -36.944515)
			(xy 322.233839 -36.860947) (xy 322.213979 -36.775218) (xy 322.201996 -36.688038) (xy 322.197991 -36.60013)
			(xy 317.968434 -36.60013) (xy 317.952823 -36.652017) (xy 317.929151 -36.702514) (xy 317.898378 -36.749027)
			(xy 317.861161 -36.790564) (xy 317.818293 -36.826239) (xy 317.770687 -36.855293) (xy 317.719358 -36.877105)
			(xy 317.665401 -36.891211) (xy 317.609964 -36.897311) (xy 317.55423 -36.895274) (xy 317.499387 -36.885144)
			(xy 317.446603 -36.867137) (xy 317.397003 -36.841636) (xy 317.351645 -36.809185) (xy 317.311496 -36.770476)
			(xy 317.27741 -36.726333) (xy 317.250114 -36.677698) (xy 317.230191 -36.625607) (xy 317.218065 -36.57117)
			(xy 317.213994 -36.515548) (xy 316.087792 -36.515548) (xy 316.084564 -36.520427) (xy 316.047347 -36.561964)
			(xy 316.004479 -36.597639) (xy 315.956873 -36.626693) (xy 315.905544 -36.648505) (xy 315.851587 -36.662611)
			(xy 315.79615 -36.668711) (xy 315.740416 -36.666674) (xy 315.685573 -36.656544) (xy 315.632789 -36.638537)
			(xy 315.583189 -36.613036) (xy 315.537831 -36.580585) (xy 315.497682 -36.541876) (xy 315.463596 -36.497733)
			(xy 315.4363 -36.449098) (xy 315.416377 -36.397007) (xy 315.404251 -36.34257) (xy 315.40018 -36.286948)
			(xy 310.064404 -36.286948) (xy 310.064404 -37.27577) (xy 310.06484 -37.285834) (xy 310.072573 -37.30442)
			(xy 310.07939 -37.311838) (xy 310.54167 -37.774118) (xy 315.664594 -37.774118) (xy 315.668665 -37.718496)
			(xy 315.680791 -37.664059) (xy 315.700714 -37.611968) (xy 315.72801 -37.563333) (xy 315.762096 -37.51919)
			(xy 315.802245 -37.480481) (xy 315.847603 -37.44803) (xy 315.897203 -37.422529) (xy 315.949987 -37.404522)
			(xy 316.00483 -37.394392) (xy 316.060564 -37.392355) (xy 316.116001 -37.398455) (xy 316.169958 -37.412561)
			(xy 316.221287 -37.434373) (xy 316.268893 -37.463427) (xy 316.311761 -37.499102) (xy 316.348978 -37.540639)
			(xy 316.379751 -37.587152) (xy 316.403423 -37.637649) (xy 316.419491 -37.691056) (xy 316.427611 -37.746232)
			(xy 316.42812 -37.774118) (xy 316.427611 -37.802004) (xy 316.419491 -37.85718) (xy 316.403423 -37.910587)
			(xy 316.379751 -37.961084) (xy 316.348978 -38.007597) (xy 316.311761 -38.049134) (xy 316.268893 -38.084809)
			(xy 316.221287 -38.113863) (xy 316.169958 -38.135675) (xy 316.116001 -38.149781) (xy 316.060564 -38.155881)
			(xy 316.00483 -38.153844) (xy 315.949987 -38.143714) (xy 315.897203 -38.125707) (xy 315.847603 -38.100206)
			(xy 315.802245 -38.067755) (xy 315.762096 -38.029046) (xy 315.72801 -37.984903) (xy 315.700714 -37.936268)
			(xy 315.680791 -37.884177) (xy 315.668665 -37.82974) (xy 315.664594 -37.774118) (xy 310.54167 -37.774118)
			(xy 314.036305 -41.268753) (xy 326.04375 -41.268753) (xy 326.04375 -41.214247) (xy 326.051507 -41.160295)
			(xy 326.066863 -41.107997) (xy 326.089506 -41.058416) (xy 326.118974 -41.012563) (xy 326.154668 -40.971369)
			(xy 326.195861 -40.935675) (xy 326.241714 -40.906207) (xy 326.291295 -40.883564) (xy 326.343593 -40.868207)
			(xy 326.397545 -40.86045) (xy 326.424798 -40.859964) (xy 326.453536 -40.860499) (xy 326.510363 -40.86912)
			(xy 326.565253 -40.886168) (xy 326.616965 -40.911257) (xy 326.664328 -40.943819) (xy 326.685656 -40.963088)
			(xy 326.692514 -40.969692) (xy 326.710548 -40.976804) (xy 326.799448 -40.976804) (xy 326.817482 -40.969692)
			(xy 326.82434 -40.963088) (xy 326.845675 -40.943827) (xy 326.893034 -40.911257) (xy 326.944744 -40.886162)
			(xy 326.999633 -40.869109) (xy 327.056459 -40.860485) (xy 327.085198 -40.859964) (xy 327.112449 -40.860483)
			(xy 327.166396 -40.868239) (xy 327.21869 -40.883594) (xy 327.268267 -40.906235) (xy 327.314117 -40.935701)
			(xy 327.355307 -40.971392) (xy 327.390998 -41.012581) (xy 327.420464 -41.058431) (xy 327.443105 -41.108008)
			(xy 327.45846 -41.160302) (xy 327.466217 -41.214249) (xy 327.466217 -41.268751) (xy 327.45846 -41.322698)
			(xy 327.443105 -41.374992) (xy 327.420464 -41.424569) (xy 327.390998 -41.470419) (xy 327.355307 -41.511608)
			(xy 327.314117 -41.547299) (xy 327.268267 -41.576765) (xy 327.21869 -41.599406) (xy 327.166396 -41.614761)
			(xy 327.112449 -41.622517) (xy 327.085198 -41.62298) (xy 327.05646 -41.622436) (xy 326.999635 -41.613815)
			(xy 326.944745 -41.596769) (xy 326.893033 -41.571682) (xy 326.845669 -41.539123) (xy 326.82434 -41.519856)
			(xy 326.817482 -41.513252) (xy 326.799448 -41.50614) (xy 326.710548 -41.50614) (xy 326.692514 -41.513252)
			(xy 326.685656 -41.519856) (xy 326.664329 -41.539127) (xy 326.616967 -41.571693) (xy 326.565255 -41.596786)
			(xy 326.510365 -41.613836) (xy 326.453537 -41.622459) (xy 326.424798 -41.62298) (xy 326.397545 -41.62255)
			(xy 326.343593 -41.614793) (xy 326.291295 -41.599436) (xy 326.241714 -41.576793) (xy 326.195861 -41.547325)
			(xy 326.154668 -41.511631) (xy 326.118974 -41.470437) (xy 326.089506 -41.424584) (xy 326.066863 -41.375003)
			(xy 326.051507 -41.322705) (xy 326.04375 -41.268753) (xy 314.036305 -41.268753) (xy 316.072774 -43.305222)
			(xy 328.50709 -43.305222) (xy 328.507571 -43.277852) (xy 328.515386 -43.223674) (xy 328.530872 -43.171171)
			(xy 328.55371 -43.121424) (xy 328.583431 -43.075456) (xy 328.60107 -43.054524) (xy 328.601324 -43.05427)
			(xy 328.60689 -43.04717) (xy 328.613148 -43.030263) (xy 328.613516 -43.02125) (xy 328.613516 -42.954194)
			(xy 328.613158 -42.945177) (xy 328.606911 -42.928261) (xy 328.601324 -42.921174) (xy 328.60107 -42.921174)
			(xy 328.60107 -42.92092) (xy 328.583422 -42.899995) (xy 328.553713 -42.85402) (xy 328.530879 -42.80427)
			(xy 328.51539 -42.751768) (xy 328.507563 -42.697592) (xy 328.50709 -42.670222) (xy 328.50763 -42.641484)
			(xy 328.516249 -42.584657) (xy 328.533295 -42.529767) (xy 328.558383 -42.478055) (xy 328.590945 -42.430691)
			(xy 328.610214 -42.409364) (xy 328.616818 -42.402506) (xy 328.62393 -42.384472) (xy 328.62393 -42.295572)
			(xy 328.616818 -42.277538) (xy 328.610214 -42.27068) (xy 328.590965 -42.249334) (xy 328.5584 -42.201975)
			(xy 328.533308 -42.150266) (xy 328.516257 -42.095378) (xy 328.507633 -42.038554) (xy 328.50763 -41.981078)
			(xy 328.51625 -41.924253) (xy 328.533296 -41.869364) (xy 328.558384 -41.817653) (xy 328.590945 -41.770291)
			(xy 328.610214 -41.748964) (xy 328.616818 -41.742106) (xy 328.62393 -41.724072) (xy 328.62393 -41.635172)
			(xy 328.616818 -41.617138) (xy 328.610214 -41.61028) (xy 328.59095 -41.588947) (xy 328.558383 -41.541587)
			(xy 328.53329 -41.489876) (xy 328.516238 -41.434987) (xy 328.507613 -41.378161) (xy 328.50709 -41.349422)
			(xy 328.507576 -41.322171) (xy 328.515332 -41.268223) (xy 328.530687 -41.215928) (xy 328.553329 -41.166351)
			(xy 328.582795 -41.120501) (xy 328.618486 -41.07931) (xy 328.659677 -41.043619) (xy 328.705527 -41.014153)
			(xy 328.755104 -40.991511) (xy 328.807399 -40.976156) (xy 328.861347 -40.9684) (xy 328.915849 -40.9684)
			(xy 328.969797 -40.976156) (xy 329.022092 -40.991511) (xy 329.071669 -41.014153) (xy 329.117519 -41.043619)
			(xy 329.15871 -41.07931) (xy 329.194401 -41.120501) (xy 329.223867 -41.166351) (xy 329.246509 -41.215928)
			(xy 329.261864 -41.268223) (xy 329.26962 -41.322171) (xy 329.270106 -41.349422) (xy 329.269594 -41.378161)
			(xy 329.260968 -41.434989) (xy 329.243915 -41.48988) (xy 329.218821 -41.541591) (xy 329.186254 -41.588954)
			(xy 329.166982 -41.61028) (xy 329.160378 -41.617138) (xy 329.153266 -41.635172) (xy 329.153266 -41.724072)
			(xy 329.160378 -41.742106) (xy 329.166982 -41.748964) (xy 329.186274 -41.770272) (xy 329.218838 -41.817638)
			(xy 329.243928 -41.869353) (xy 329.260976 -41.924246) (xy 329.269597 -41.981076) (xy 329.269594 -42.038556)
			(xy 329.260969 -42.095385) (xy 329.243917 -42.150277) (xy 329.218822 -42.20199) (xy 329.186254 -42.249353)
			(xy 329.166982 -42.27068) (xy 329.160378 -42.277538) (xy 329.153266 -42.295572) (xy 329.153266 -42.384472)
			(xy 329.160378 -42.402506) (xy 329.166982 -42.409364) (xy 329.186266 -42.430679) (xy 329.21883 -42.478045)
			(xy 329.24392 -42.529759) (xy 329.260967 -42.584653) (xy 329.269587 -42.641482) (xy 329.270106 -42.670222)
			(xy 329.269651 -42.697593) (xy 329.261831 -42.751772) (xy 329.246339 -42.804275) (xy 329.225784 -42.849038)
			(xy 331.091792 -42.849038) (xy 331.095863 -42.793416) (xy 331.107989 -42.738979) (xy 331.127912 -42.686888)
			(xy 331.155208 -42.638253) (xy 331.189294 -42.59411) (xy 331.229443 -42.555401) (xy 331.274801 -42.52295)
			(xy 331.324401 -42.497449) (xy 331.377185 -42.479442) (xy 331.432028 -42.469312) (xy 331.487762 -42.467275)
			(xy 331.543199 -42.473375) (xy 331.597156 -42.487481) (xy 331.648485 -42.509293) (xy 331.696091 -42.538347)
			(xy 331.738959 -42.574022) (xy 331.776176 -42.615559) (xy 331.806949 -42.662072) (xy 331.830621 -42.712569)
			(xy 331.846689 -42.765976) (xy 331.854809 -42.821152) (xy 331.85517 -42.84091) (xy 337.132928 -42.84091)
			(xy 337.136999 -42.785288) (xy 337.149125 -42.730851) (xy 337.169048 -42.67876) (xy 337.196344 -42.630125)
			(xy 337.23043 -42.585982) (xy 337.270579 -42.547273) (xy 337.315937 -42.514822) (xy 337.365537 -42.489321)
			(xy 337.418321 -42.471314) (xy 337.473164 -42.461184) (xy 337.528898 -42.459147) (xy 337.584335 -42.465247)
			(xy 337.638292 -42.479353) (xy 337.689621 -42.501165) (xy 337.737227 -42.530219) (xy 337.780095 -42.565894)
			(xy 337.817312 -42.607431) (xy 337.848085 -42.653944) (xy 337.871757 -42.704441) (xy 337.887825 -42.757848)
			(xy 337.895945 -42.813024) (xy 337.896454 -42.84091) (xy 337.895945 -42.868796) (xy 337.887825 -42.923972)
			(xy 337.871757 -42.977379) (xy 337.848085 -43.027876) (xy 337.817312 -43.074389) (xy 337.780095 -43.115926)
			(xy 337.737227 -43.151601) (xy 337.689621 -43.180655) (xy 337.638292 -43.202467) (xy 337.584335 -43.216573)
			(xy 337.528898 -43.222673) (xy 337.473164 -43.220636) (xy 337.418321 -43.210506) (xy 337.365537 -43.192499)
			(xy 337.315937 -43.166998) (xy 337.270579 -43.134547) (xy 337.23043 -43.095838) (xy 337.196344 -43.051695)
			(xy 337.169048 -43.00306) (xy 337.149125 -42.950969) (xy 337.136999 -42.896532) (xy 337.132928 -42.84091)
			(xy 331.85517 -42.84091) (xy 331.855318 -42.849038) (xy 331.854809 -42.876924) (xy 331.846689 -42.9321)
			(xy 331.830621 -42.985507) (xy 331.806949 -43.036004) (xy 331.776176 -43.082517) (xy 331.738959 -43.124054)
			(xy 331.696091 -43.159729) (xy 331.648485 -43.188783) (xy 331.597156 -43.210595) (xy 331.543199 -43.224701)
			(xy 331.487762 -43.230801) (xy 331.432028 -43.228764) (xy 331.377185 -43.218634) (xy 331.324401 -43.200627)
			(xy 331.274801 -43.175126) (xy 331.229443 -43.142675) (xy 331.189294 -43.103966) (xy 331.155208 -43.059823)
			(xy 331.127912 -43.011188) (xy 331.107989 -42.959097) (xy 331.095863 -42.90466) (xy 331.091792 -42.849038)
			(xy 329.225784 -42.849038) (xy 329.223495 -42.854022) (xy 329.193768 -42.899988) (xy 329.176126 -42.92092)
			(xy 329.175872 -42.921174) (xy 329.170287 -42.928262) (xy 329.16404 -42.945178) (xy 329.16368 -42.954194)
			(xy 329.16368 -43.02125) (xy 329.164065 -43.030264) (xy 329.170294 -43.047181) (xy 329.175872 -43.05427)
			(xy 329.176126 -43.05427) (xy 329.176126 -43.054524) (xy 329.193747 -43.075471) (xy 329.223461 -43.12144)
			(xy 329.2463 -43.171184) (xy 329.261795 -43.223681) (xy 329.269629 -43.277854) (xy 329.270106 -43.305222)
			(xy 329.26962 -43.332473) (xy 329.261864 -43.386421) (xy 329.246509 -43.438716) (xy 329.223867 -43.488293)
			(xy 329.194401 -43.534143) (xy 329.15871 -43.575334) (xy 329.117519 -43.611025) (xy 329.071669 -43.640491)
			(xy 329.022092 -43.663133) (xy 328.969797 -43.678488) (xy 328.915849 -43.686244) (xy 328.861347 -43.686244)
			(xy 328.807399 -43.678488) (xy 328.755104 -43.663133) (xy 328.705527 -43.640491) (xy 328.659677 -43.611025)
			(xy 328.618486 -43.575334) (xy 328.582795 -43.534143) (xy 328.553329 -43.488293) (xy 328.530687 -43.438716)
			(xy 328.515332 -43.386421) (xy 328.507576 -43.332473) (xy 328.50709 -43.305222) (xy 316.072774 -43.305222)
			(xy 316.503812 -43.73626) (xy 330.41285 -43.73626) (xy 330.416921 -43.680638) (xy 330.429047 -43.626201)
			(xy 330.44897 -43.57411) (xy 330.476266 -43.525475) (xy 330.510352 -43.481332) (xy 330.550501 -43.442623)
			(xy 330.595859 -43.410172) (xy 330.645459 -43.384671) (xy 330.698243 -43.366664) (xy 330.753086 -43.356534)
			(xy 330.80882 -43.354497) (xy 330.864257 -43.360597) (xy 330.918214 -43.374703) (xy 330.969543 -43.396515)
			(xy 331.017149 -43.425569) (xy 331.060017 -43.461244) (xy 331.097234 -43.502781) (xy 331.128007 -43.549294)
			(xy 331.136233 -43.566842) (xy 333.53324 -43.566842) (xy 333.537311 -43.51122) (xy 333.549437 -43.456783)
			(xy 333.56936 -43.404692) (xy 333.596656 -43.356057) (xy 333.630742 -43.311914) (xy 333.670891 -43.273205)
			(xy 333.716249 -43.240754) (xy 333.765849 -43.215253) (xy 333.818633 -43.197246) (xy 333.873476 -43.187116)
			(xy 333.92921 -43.185079) (xy 333.984647 -43.191179) (xy 334.038604 -43.205285) (xy 334.089933 -43.227097)
			(xy 334.137539 -43.256151) (xy 334.180407 -43.291826) (xy 334.217624 -43.333363) (xy 334.248397 -43.379876)
			(xy 334.272069 -43.430373) (xy 334.288137 -43.48378) (xy 334.296257 -43.538956) (xy 334.296766 -43.566842)
			(xy 334.296257 -43.594728) (xy 334.288137 -43.649904) (xy 334.272069 -43.703311) (xy 334.248397 -43.753808)
			(xy 334.217624 -43.800321) (xy 334.180407 -43.841858) (xy 334.16232 -43.85691) (xy 334.919572 -43.85691)
			(xy 334.923643 -43.801288) (xy 334.935769 -43.746851) (xy 334.955692 -43.69476) (xy 334.982988 -43.646125)
			(xy 335.017074 -43.601982) (xy 335.057223 -43.563273) (xy 335.102581 -43.530822) (xy 335.152181 -43.505321)
			(xy 335.204965 -43.487314) (xy 335.259808 -43.477184) (xy 335.315542 -43.475147) (xy 335.370979 -43.481247)
			(xy 335.424936 -43.495353) (xy 335.476265 -43.517165) (xy 335.523871 -43.546219) (xy 335.566739 -43.581894)
			(xy 335.603956 -43.623431) (xy 335.634729 -43.669944) (xy 335.658401 -43.720441) (xy 335.674469 -43.773848)
			(xy 335.682589 -43.829024) (xy 335.683098 -43.85691) (xy 335.682589 -43.884796) (xy 335.674469 -43.939972)
			(xy 335.658401 -43.993379) (xy 335.634729 -44.043876) (xy 335.603956 -44.090389) (xy 335.566739 -44.131926)
			(xy 335.523871 -44.167601) (xy 335.476265 -44.196655) (xy 335.424936 -44.218467) (xy 335.370979 -44.232573)
			(xy 335.315542 -44.238673) (xy 335.259808 -44.236636) (xy 335.204965 -44.226506) (xy 335.152181 -44.208499)
			(xy 335.102581 -44.182998) (xy 335.057223 -44.150547) (xy 335.017074 -44.111838) (xy 334.982988 -44.067695)
			(xy 334.955692 -44.01906) (xy 334.935769 -43.966969) (xy 334.923643 -43.912532) (xy 334.919572 -43.85691)
			(xy 334.16232 -43.85691) (xy 334.137539 -43.877533) (xy 334.089933 -43.906587) (xy 334.038604 -43.928399)
			(xy 333.984647 -43.942505) (xy 333.92921 -43.948605) (xy 333.873476 -43.946568) (xy 333.818633 -43.936438)
			(xy 333.765849 -43.918431) (xy 333.716249 -43.89293) (xy 333.670891 -43.860479) (xy 333.630742 -43.82177)
			(xy 333.596656 -43.777627) (xy 333.56936 -43.728992) (xy 333.549437 -43.676901) (xy 333.537311 -43.622464)
			(xy 333.53324 -43.566842) (xy 331.136233 -43.566842) (xy 331.151679 -43.599791) (xy 331.167747 -43.653198)
			(xy 331.175867 -43.708374) (xy 331.176376 -43.73626) (xy 331.175867 -43.764146) (xy 331.167747 -43.819322)
			(xy 331.151679 -43.872729) (xy 331.128007 -43.923226) (xy 331.097234 -43.969739) (xy 331.060017 -44.011276)
			(xy 331.017149 -44.046951) (xy 330.969543 -44.076005) (xy 330.918214 -44.097817) (xy 330.864257 -44.111923)
			(xy 330.80882 -44.118023) (xy 330.753086 -44.115986) (xy 330.698243 -44.105856) (xy 330.645459 -44.087849)
			(xy 330.595859 -44.062348) (xy 330.550501 -44.029897) (xy 330.510352 -43.991188) (xy 330.476266 -43.947045)
			(xy 330.44897 -43.89841) (xy 330.429047 -43.846319) (xy 330.416921 -43.791882) (xy 330.41285 -43.73626)
			(xy 316.503812 -43.73626) (xy 317.882016 -45.114464) (xy 330.265276 -45.114464) (xy 330.269347 -45.058842)
			(xy 330.281473 -45.004405) (xy 330.301396 -44.952314) (xy 330.328692 -44.903679) (xy 330.362778 -44.859536)
			(xy 330.402927 -44.820827) (xy 330.448285 -44.788376) (xy 330.497885 -44.762875) (xy 330.550669 -44.744868)
			(xy 330.605512 -44.734738) (xy 330.661246 -44.732701) (xy 330.716683 -44.738801) (xy 330.77064 -44.752907)
			(xy 330.821969 -44.774719) (xy 330.869575 -44.803773) (xy 330.912443 -44.839448) (xy 330.94966 -44.880985)
			(xy 330.965229 -44.904517) (xy 337.032551 -44.904517) (xy 337.032551 -44.841283) (xy 337.040805 -44.778591)
			(xy 337.057172 -44.717512) (xy 337.081372 -44.659092) (xy 337.11299 -44.604332) (xy 337.151486 -44.554167)
			(xy 337.196201 -44.509456) (xy 337.24637 -44.470964) (xy 337.301134 -44.439351) (xy 337.359556 -44.415157)
			(xy 337.420636 -44.398796) (xy 337.483329 -44.390548) (xy 337.514946 -44.390056) (xy 339.765132 -44.390056)
			(xy 339.796692 -44.390573) (xy 339.859269 -44.398853) (xy 339.920233 -44.415214) (xy 339.978547 -44.439377)
			(xy 340.033215 -44.470932) (xy 340.083307 -44.50934) (xy 340.106 -44.53128) (xy 340.62797 -45.05325)
			(xy 340.649983 -45.075971) (xy 340.688482 -45.126171) (xy 340.720103 -45.180965) (xy 340.744305 -45.239417)
			(xy 340.760674 -45.300526) (xy 340.76893 -45.363248) (xy 340.769448 -45.39488) (xy 340.769448 -50.68316)
			(xy 340.768939 -50.714793) (xy 340.760696 -50.77752) (xy 340.744333 -50.838633) (xy 340.72013 -50.897087)
			(xy 340.688501 -50.951879) (xy 340.649988 -51.002072) (xy 340.62797 -51.02479) (xy 339.275674 -52.377086)
			(xy 339.252928 -52.399072) (xy 339.202735 -52.437577) (xy 339.147947 -52.469204) (xy 339.0895 -52.493411)
			(xy 339.028394 -52.509784) (xy 338.965675 -52.518044) (xy 338.934044 -52.518564) (xy 337.523074 -52.518564)
			(xy 337.491442 -52.518133) (xy 337.428718 -52.509872) (xy 337.36761 -52.493496) (xy 337.309161 -52.469283)
			(xy 337.254374 -52.437648) (xy 337.204183 -52.399133) (xy 337.159449 -52.354397) (xy 337.120937 -52.304205)
			(xy 337.089306 -52.249415) (xy 337.065096 -52.190966) (xy 337.048722 -52.129856) (xy 337.040465 -52.067132)
			(xy 337.040465 -52.003868) (xy 337.048722 -51.941144) (xy 337.065096 -51.880034) (xy 337.089306 -51.821585)
			(xy 337.120937 -51.766795) (xy 337.159449 -51.716603) (xy 337.204183 -51.671867) (xy 337.254374 -51.633352)
			(xy 337.309161 -51.601717) (xy 337.36761 -51.577504) (xy 337.428718 -51.561128) (xy 337.491442 -51.552867)
			(xy 337.523074 -51.552348) (xy 338.71281 -51.552348) (xy 338.722882 -51.551942) (xy 338.74148 -51.544209)
			(xy 338.748878 -51.537362) (xy 339.788246 -50.497994) (xy 339.795088 -50.490595) (xy 339.802805 -50.471995)
			(xy 339.803232 -50.461926) (xy 339.803232 -45.616114) (xy 339.802817 -45.606043) (xy 339.795091 -45.587444)
			(xy 339.788246 -45.580046) (xy 339.579204 -45.37075) (xy 339.571791 -45.363926) (xy 339.553202 -45.356195)
			(xy 339.543136 -45.355764) (xy 337.514946 -45.355764) (xy 337.483329 -45.355252) (xy 337.420636 -45.347004)
			(xy 337.359556 -45.330643) (xy 337.301134 -45.306449) (xy 337.24637 -45.274836) (xy 337.196201 -45.236344)
			(xy 337.151486 -45.191633) (xy 337.11299 -45.141468) (xy 337.081372 -45.086708) (xy 337.057172 -45.028288)
			(xy 337.040805 -44.967209) (xy 337.032551 -44.904517) (xy 330.965229 -44.904517) (xy 330.980433 -44.927498)
			(xy 331.004105 -44.977995) (xy 331.020173 -45.031402) (xy 331.028293 -45.086578) (xy 331.028802 -45.114464)
			(xy 331.028293 -45.14235) (xy 331.020173 -45.197526) (xy 331.004105 -45.250933) (xy 330.980433 -45.30143)
			(xy 330.94966 -45.347943) (xy 330.944018 -45.35424) (xy 334.90357 -45.35424) (xy 334.907641 -45.298618)
			(xy 334.919767 -45.244181) (xy 334.93969 -45.19209) (xy 334.966986 -45.143455) (xy 335.001072 -45.099312)
			(xy 335.041221 -45.060603) (xy 335.086579 -45.028152) (xy 335.136179 -45.002651) (xy 335.188963 -44.984644)
			(xy 335.243806 -44.974514) (xy 335.29954 -44.972477) (xy 335.354977 -44.978577) (xy 335.408934 -44.992683)
			(xy 335.460263 -45.014495) (xy 335.507869 -45.043549) (xy 335.550737 -45.079224) (xy 335.587954 -45.120761)
			(xy 335.618727 -45.167274) (xy 335.642399 -45.217771) (xy 335.658467 -45.271178) (xy 335.666587 -45.326354)
			(xy 335.667096 -45.35424) (xy 335.666587 -45.382126) (xy 335.658467 -45.437302) (xy 335.642399 -45.490709)
			(xy 335.618727 -45.541206) (xy 335.587954 -45.587719) (xy 335.550737 -45.629256) (xy 335.507869 -45.664931)
			(xy 335.460263 -45.693985) (xy 335.408934 -45.715797) (xy 335.354977 -45.729903) (xy 335.29954 -45.736003)
			(xy 335.243806 -45.733966) (xy 335.188963 -45.723836) (xy 335.136179 -45.705829) (xy 335.086579 -45.680328)
			(xy 335.041221 -45.647877) (xy 335.001072 -45.609168) (xy 334.966986 -45.565025) (xy 334.93969 -45.51639)
			(xy 334.919767 -45.464299) (xy 334.907641 -45.409862) (xy 334.90357 -45.35424) (xy 330.944018 -45.35424)
			(xy 330.912443 -45.38948) (xy 330.869575 -45.425155) (xy 330.821969 -45.454209) (xy 330.77064 -45.476021)
			(xy 330.716683 -45.490127) (xy 330.661246 -45.496227) (xy 330.605512 -45.49419) (xy 330.550669 -45.48406)
			(xy 330.497885 -45.466053) (xy 330.448285 -45.440552) (xy 330.402927 -45.408101) (xy 330.362778 -45.369392)
			(xy 330.328692 -45.325249) (xy 330.301396 -45.276614) (xy 330.281473 -45.224523) (xy 330.269347 -45.170086)
			(xy 330.265276 -45.114464) (xy 317.882016 -45.114464) (xy 318.849756 -46.082204) (xy 328.252328 -46.082204)
			(xy 328.252759 -46.05495) (xy 328.260517 -46.000996) (xy 328.275874 -45.948695) (xy 328.298519 -45.899113)
			(xy 328.327989 -45.853258) (xy 328.363687 -45.812064) (xy 328.404883 -45.77637) (xy 328.450741 -45.746903)
			(xy 328.500325 -45.724263) (xy 328.552627 -45.70891) (xy 328.606582 -45.701157) (xy 328.633836 -45.700696)
			(xy 328.66074 -45.701131) (xy 328.714011 -45.708708) (xy 328.76569 -45.723692) (xy 328.814751 -45.745786)
			(xy 328.860224 -45.774553) (xy 328.901204 -45.809422) (xy 328.936881 -45.849701) (xy 328.952098 -45.871892)
			(xy 328.95921 -45.882814) (xy 328.98207 -45.894752) (xy 329.094338 -45.89272) (xy 329.11669 -45.879766)
			(xy 329.123548 -45.86859) (xy 329.13845 -45.844976) (xy 329.174133 -45.802024) (xy 329.215694 -45.764732)
			(xy 329.262247 -45.733896) (xy 329.312798 -45.710175) (xy 329.366266 -45.694075) (xy 329.42151 -45.68594)
			(xy 329.44943 -45.685456) (xy 329.476424 -45.6859) (xy 329.529873 -45.69351) (xy 329.581716 -45.708574)
			(xy 329.630921 -45.730792) (xy 329.676504 -45.75972) (xy 329.697334 -45.776896) (xy 329.705462 -45.784008)
			(xy 329.726036 -45.790104) (xy 329.81138 -45.779182) (xy 329.821925 -45.777408) (xy 329.840208 -45.766353)
			(xy 329.846686 -45.757846) (xy 329.862055 -45.736627) (xy 329.897639 -45.698174) (xy 329.938153 -45.664954)
			(xy 329.982834 -45.637594) (xy 330.03084 -45.616609) (xy 330.081266 -45.602393) (xy 330.133164 -45.595215)
			(xy 330.15936 -45.594778) (xy 330.186614 -45.595267) (xy 330.240567 -45.603019) (xy 330.292868 -45.618371)
			(xy 330.342451 -45.64101) (xy 330.388308 -45.670476) (xy 330.429503 -45.706168) (xy 330.4652 -45.74736)
			(xy 330.494671 -45.793214) (xy 330.517315 -45.842795) (xy 330.532673 -45.895094) (xy 330.540431 -45.949046)
			(xy 330.540431 -46.003554) (xy 330.532673 -46.057506) (xy 330.517315 -46.109805) (xy 330.494671 -46.159386)
			(xy 330.4652 -46.20524) (xy 330.429503 -46.246432) (xy 330.388308 -46.282124) (xy 330.342451 -46.31159)
			(xy 330.292868 -46.334229) (xy 330.240567 -46.349581) (xy 330.186614 -46.357333) (xy 330.15936 -46.357794)
			(xy 330.132366 -46.357344) (xy 330.078918 -46.349734) (xy 330.027075 -46.33467) (xy 329.977871 -46.312454)
			(xy 329.932287 -46.283528) (xy 329.911456 -46.266354) (xy 329.903328 -46.259242) (xy 329.882754 -46.253146)
			(xy 329.79741 -46.264068) (xy 329.786869 -46.265855) (xy 329.768586 -46.276902) (xy 329.762104 -46.285404)
			(xy 329.744487 -46.309701) (xy 329.702894 -46.352963) (xy 329.6793 -46.37151) (xy 329.671426 -46.377352)
			(xy 329.661012 -46.394878) (xy 329.647804 -46.485302) (xy 329.65263 -46.504606) (xy 329.658472 -46.51248)
			(xy 329.658472 -46.512734) (xy 329.675975 -46.537478) (xy 329.703777 -46.591331) (xy 329.722714 -46.648903)
			(xy 329.729917 -46.693836) (xy 334.87614 -46.693836) (xy 334.876626 -46.666585) (xy 334.884382 -46.612637)
			(xy 334.899737 -46.560342) (xy 334.922379 -46.510765) (xy 334.951845 -46.464915) (xy 334.987536 -46.423724)
			(xy 335.028727 -46.388033) (xy 335.074577 -46.358567) (xy 335.124154 -46.335925) (xy 335.176449 -46.32057)
			(xy 335.230397 -46.312814) (xy 335.284899 -46.312814) (xy 335.338847 -46.32057) (xy 335.391142 -46.335925)
			(xy 335.440719 -46.358567) (xy 335.486569 -46.388033) (xy 335.52776 -46.423724) (xy 335.563451 -46.464915)
			(xy 335.592917 -46.510765) (xy 335.615559 -46.560342) (xy 335.630914 -46.612637) (xy 335.63867 -46.666585)
			(xy 335.639156 -46.693836) (xy 335.638689 -46.720264) (xy 335.631379 -46.772612) (xy 335.616904 -46.823447)
			(xy 335.595542 -46.871793) (xy 335.582006 -46.894496) (xy 335.581752 -46.89475) (xy 335.576415 -46.904768)
			(xy 335.574158 -46.927318) (xy 335.577434 -46.938184) (xy 335.603596 -47.01286) (xy 335.60796 -47.023386)
			(xy 335.624062 -47.03947) (xy 335.634584 -47.043848) (xy 335.634838 -47.043848) (xy 335.659345 -47.052922)
			(xy 335.705798 -47.076864) (xy 335.74855 -47.106919) (xy 335.786802 -47.142525) (xy 335.819839 -47.183018)
			(xy 335.847043 -47.227638) (xy 335.867905 -47.275553) (xy 335.882035 -47.325866) (xy 335.889169 -47.377636)
			(xy 335.8896 -47.403766) (xy 335.889114 -47.431017) (xy 335.887591 -47.441612) (xy 337.16163 -47.441612)
			(xy 337.165701 -47.38599) (xy 337.177827 -47.331553) (xy 337.19775 -47.279462) (xy 337.225046 -47.230827)
			(xy 337.259132 -47.186684) (xy 337.299281 -47.147975) (xy 337.344639 -47.115524) (xy 337.394239 -47.090023)
			(xy 337.447023 -47.072016) (xy 337.501866 -47.061886) (xy 337.5576 -47.059849) (xy 337.613037 -47.065949)
			(xy 337.666994 -47.080055) (xy 337.718323 -47.101867) (xy 337.765929 -47.130921) (xy 337.808797 -47.166596)
			(xy 337.846014 -47.208133) (xy 337.876787 -47.254646) (xy 337.900459 -47.305143) (xy 337.916527 -47.35855)
			(xy 337.924647 -47.413726) (xy 337.925156 -47.441612) (xy 337.924647 -47.469498) (xy 337.916527 -47.524674)
			(xy 337.900459 -47.578081) (xy 337.876787 -47.628578) (xy 337.846014 -47.675091) (xy 337.808797 -47.716628)
			(xy 337.765929 -47.752303) (xy 337.718323 -47.781357) (xy 337.666994 -47.803169) (xy 337.613037 -47.817275)
			(xy 337.5576 -47.823375) (xy 337.501866 -47.821338) (xy 337.447023 -47.811208) (xy 337.394239 -47.793201)
			(xy 337.344639 -47.7677) (xy 337.299281 -47.735249) (xy 337.259132 -47.69654) (xy 337.225046 -47.652397)
			(xy 337.19775 -47.603762) (xy 337.177827 -47.551671) (xy 337.165701 -47.497234) (xy 337.16163 -47.441612)
			(xy 335.887591 -47.441612) (xy 335.881358 -47.484965) (xy 335.866003 -47.53726) (xy 335.843361 -47.586837)
			(xy 335.813895 -47.632687) (xy 335.778204 -47.673878) (xy 335.737013 -47.709569) (xy 335.691163 -47.739035)
			(xy 335.641586 -47.761677) (xy 335.589291 -47.777032) (xy 335.535343 -47.784788) (xy 335.480841 -47.784788)
			(xy 335.426893 -47.777032) (xy 335.374598 -47.761677) (xy 335.325021 -47.739035) (xy 335.279171 -47.709569)
			(xy 335.23798 -47.673878) (xy 335.202289 -47.632687) (xy 335.172823 -47.586837) (xy 335.150181 -47.53726)
			(xy 335.134826 -47.484965) (xy 335.12707 -47.431017) (xy 335.126584 -47.403766) (xy 335.12706 -47.377339)
			(xy 335.134369 -47.324991) (xy 335.148841 -47.274157) (xy 335.1702 -47.225809) (xy 335.183734 -47.203106)
			(xy 335.183988 -47.202852) (xy 335.189323 -47.192834) (xy 335.19158 -47.170284) (xy 335.188306 -47.159418)
			(xy 335.162144 -47.084742) (xy 335.157761 -47.074226) (xy 335.141672 -47.058138) (xy 335.131156 -47.053754)
			(xy 335.130902 -47.053754) (xy 335.106383 -47.044712) (xy 335.059932 -47.020764) (xy 335.017181 -46.990703)
			(xy 334.978931 -46.955091) (xy 334.945896 -46.914595) (xy 334.918694 -46.869971) (xy 334.897834 -46.822054)
			(xy 334.883705 -46.771739) (xy 334.876571 -46.719967) (xy 334.87614 -46.693836) (xy 329.729917 -46.693836)
			(xy 329.732307 -46.708745) (xy 329.732894 -46.739048) (xy 329.732467 -46.766301) (xy 329.724703 -46.820252)
			(xy 329.709341 -46.872548) (xy 329.686694 -46.922127) (xy 329.657221 -46.967977) (xy 329.621524 -47.009167)
			(xy 329.580328 -47.044858) (xy 329.534472 -47.074323) (xy 329.48489 -47.096963) (xy 329.432591 -47.112317)
			(xy 329.378639 -47.120071) (xy 329.351386 -47.120556) (xy 329.325352 -47.12011) (xy 329.27377 -47.113021)
			(xy 329.223628 -47.098992) (xy 329.175857 -47.078281) (xy 329.131342 -47.051272) (xy 329.110848 -47.035212)
			(xy 329.103084 -47.029482) (xy 329.084679 -47.023734) (xy 329.075034 -47.024036) (xy 328.995278 -47.030386)
			(xy 328.977498 -47.039022) (xy 328.971148 -47.046388) (xy 328.952966 -47.066033) (xy 328.912059 -47.100555)
			(xy 328.86673 -47.129024) (xy 328.817869 -47.150882) (xy 328.766433 -47.1657) (xy 328.713432 -47.173187)
			(xy 328.686668 -47.173642) (xy 328.659418 -47.173152) (xy 328.605472 -47.165392) (xy 328.553179 -47.150035)
			(xy 328.503604 -47.127392) (xy 328.457755 -47.097926) (xy 328.416566 -47.062235) (xy 328.380875 -47.021046)
			(xy 328.351409 -46.975198) (xy 328.328766 -46.925623) (xy 328.313408 -46.87333) (xy 328.305648 -46.819384)
			(xy 328.30516 -46.792134) (xy 328.305695 -46.76336) (xy 328.314345 -46.706467) (xy 328.33144 -46.651517)
			(xy 328.35659 -46.599757) (xy 328.389228 -46.55236) (xy 328.408538 -46.531022) (xy 328.415904 -46.523148)
			(xy 328.423016 -46.503336) (xy 328.41565 -46.40707) (xy 328.405744 -46.388274) (xy 328.397362 -46.38167)
			(xy 328.375186 -46.363435) (xy 328.335974 -46.321503) (xy 328.303486 -46.27417) (xy 328.278455 -46.222504)
			(xy 328.261448 -46.167671) (xy 328.252846 -46.110909) (xy 328.252328 -46.082204) (xy 318.849756 -46.082204)
			(xy 320.638678 -47.871126) (xy 320.666502 -47.899849) (xy 320.714812 -47.963574) (xy 320.734944 -47.998126)
			(xy 320.908076 -48.30699) (xy 334.75371 -48.30699) (xy 334.757781 -48.251368) (xy 334.769907 -48.196931)
			(xy 334.78983 -48.14484) (xy 334.817126 -48.096205) (xy 334.851212 -48.052062) (xy 334.891361 -48.013353)
			(xy 334.936719 -47.980902) (xy 334.986319 -47.955401) (xy 335.039103 -47.937394) (xy 335.093946 -47.927264)
			(xy 335.14968 -47.925227) (xy 335.205117 -47.931327) (xy 335.259074 -47.945433) (xy 335.310403 -47.967245)
			(xy 335.358009 -47.996299) (xy 335.400877 -48.031974) (xy 335.438094 -48.073511) (xy 335.468867 -48.120024)
			(xy 335.492539 -48.170521) (xy 335.508607 -48.223928) (xy 335.516727 -48.279104) (xy 335.517236 -48.30699)
			(xy 335.516727 -48.334876) (xy 335.508607 -48.390052) (xy 335.492539 -48.443459) (xy 335.468867 -48.493956)
			(xy 335.438094 -48.540469) (xy 335.400877 -48.582006) (xy 335.358009 -48.617681) (xy 335.310403 -48.646735)
			(xy 335.259074 -48.668547) (xy 335.205117 -48.682653) (xy 335.14968 -48.688753) (xy 335.093946 -48.686716)
			(xy 335.039103 -48.676586) (xy 334.986319 -48.658579) (xy 334.936719 -48.633078) (xy 334.891361 -48.600627)
			(xy 334.851212 -48.561918) (xy 334.817126 -48.517775) (xy 334.78983 -48.46914) (xy 334.769907 -48.417049)
			(xy 334.757781 -48.362612) (xy 334.75371 -48.30699) (xy 320.908076 -48.30699) (xy 321.158092 -48.753014)
			(xy 331.368144 -48.753014) (xy 331.372215 -48.697392) (xy 331.384341 -48.642955) (xy 331.404264 -48.590864)
			(xy 331.43156 -48.542229) (xy 331.465646 -48.498086) (xy 331.505795 -48.459377) (xy 331.551153 -48.426926)
			(xy 331.600753 -48.401425) (xy 331.653537 -48.383418) (xy 331.70838 -48.373288) (xy 331.764114 -48.371251)
			(xy 331.819551 -48.377351) (xy 331.873508 -48.391457) (xy 331.924837 -48.413269) (xy 331.972443 -48.442323)
			(xy 332.015311 -48.477998) (xy 332.052528 -48.519535) (xy 332.083301 -48.566048) (xy 332.106973 -48.616545)
			(xy 332.123041 -48.669952) (xy 332.131161 -48.725128) (xy 332.13167 -48.753014) (xy 332.131161 -48.7809)
			(xy 332.123041 -48.836076) (xy 332.120597 -48.8442) (xy 332.387192 -48.8442) (xy 332.391263 -48.788578)
			(xy 332.403389 -48.734141) (xy 332.423312 -48.68205) (xy 332.450608 -48.633415) (xy 332.484694 -48.589272)
			(xy 332.524843 -48.550563) (xy 332.570201 -48.518112) (xy 332.619801 -48.492611) (xy 332.672585 -48.474604)
			(xy 332.727428 -48.464474) (xy 332.783162 -48.462437) (xy 332.838599 -48.468537) (xy 332.892556 -48.482643)
			(xy 332.943885 -48.504455) (xy 332.991491 -48.533509) (xy 333.034359 -48.569184) (xy 333.071576 -48.610721)
			(xy 333.102349 -48.657234) (xy 333.126021 -48.707731) (xy 333.142089 -48.761138) (xy 333.150209 -48.816314)
			(xy 333.150718 -48.8442) (xy 333.150209 -48.872086) (xy 333.147211 -48.89246) (xy 333.41386 -48.89246)
			(xy 333.417931 -48.836838) (xy 333.430057 -48.782401) (xy 333.44998 -48.73031) (xy 333.477276 -48.681675)
			(xy 333.511362 -48.637532) (xy 333.551511 -48.598823) (xy 333.596869 -48.566372) (xy 333.646469 -48.540871)
			(xy 333.699253 -48.522864) (xy 333.754096 -48.512734) (xy 333.80983 -48.510697) (xy 333.865267 -48.516797)
			(xy 333.919224 -48.530903) (xy 333.970553 -48.552715) (xy 334.018159 -48.581769) (xy 334.061027 -48.617444)
			(xy 334.098244 -48.658981) (xy 334.129017 -48.705494) (xy 334.152689 -48.755991) (xy 334.168757 -48.809398)
			(xy 334.176877 -48.864574) (xy 334.177386 -48.89246) (xy 334.176877 -48.920346) (xy 334.174439 -48.93691)
			(xy 337.132928 -48.93691) (xy 337.136999 -48.881288) (xy 337.149125 -48.826851) (xy 337.169048 -48.77476)
			(xy 337.196344 -48.726125) (xy 337.23043 -48.681982) (xy 337.270579 -48.643273) (xy 337.315937 -48.610822)
			(xy 337.365537 -48.585321) (xy 337.418321 -48.567314) (xy 337.473164 -48.557184) (xy 337.528898 -48.555147)
			(xy 337.584335 -48.561247) (xy 337.638292 -48.575353) (xy 337.689621 -48.597165) (xy 337.737227 -48.626219)
			(xy 337.780095 -48.661894) (xy 337.817312 -48.703431) (xy 337.848085 -48.749944) (xy 337.871757 -48.800441)
			(xy 337.887825 -48.853848) (xy 337.895945 -48.909024) (xy 337.896454 -48.93691) (xy 337.895945 -48.964796)
			(xy 337.887825 -49.019972) (xy 337.871757 -49.073379) (xy 337.848085 -49.123876) (xy 337.817312 -49.170389)
			(xy 337.780095 -49.211926) (xy 337.737227 -49.247601) (xy 337.689621 -49.276655) (xy 337.638292 -49.298467)
			(xy 337.584335 -49.312573) (xy 337.528898 -49.318673) (xy 337.473164 -49.316636) (xy 337.418321 -49.306506)
			(xy 337.365537 -49.288499) (xy 337.315937 -49.262998) (xy 337.270579 -49.230547) (xy 337.23043 -49.191838)
			(xy 337.196344 -49.147695) (xy 337.169048 -49.09906) (xy 337.149125 -49.046969) (xy 337.136999 -48.992532)
			(xy 337.132928 -48.93691) (xy 334.174439 -48.93691) (xy 334.168757 -48.975522) (xy 334.152689 -49.028929)
			(xy 334.129017 -49.079426) (xy 334.098244 -49.125939) (xy 334.061027 -49.167476) (xy 334.018159 -49.203151)
			(xy 333.970553 -49.232205) (xy 333.919224 -49.254017) (xy 333.865267 -49.268123) (xy 333.80983 -49.274223)
			(xy 333.754096 -49.272186) (xy 333.699253 -49.262056) (xy 333.646469 -49.244049) (xy 333.596869 -49.218548)
			(xy 333.551511 -49.186097) (xy 333.511362 -49.147388) (xy 333.477276 -49.103245) (xy 333.44998 -49.05461)
			(xy 333.430057 -49.002519) (xy 333.417931 -48.948082) (xy 333.41386 -48.89246) (xy 333.147211 -48.89246)
			(xy 333.142089 -48.927262) (xy 333.126021 -48.980669) (xy 333.102349 -49.031166) (xy 333.071576 -49.077679)
			(xy 333.034359 -49.119216) (xy 332.991491 -49.154891) (xy 332.943885 -49.183945) (xy 332.892556 -49.205757)
			(xy 332.838599 -49.219863) (xy 332.783162 -49.225963) (xy 332.727428 -49.223926) (xy 332.672585 -49.213796)
			(xy 332.619801 -49.195789) (xy 332.570201 -49.170288) (xy 332.524843 -49.137837) (xy 332.484694 -49.099128)
			(xy 332.450608 -49.054985) (xy 332.423312 -49.00635) (xy 332.403389 -48.954259) (xy 332.391263 -48.899822)
			(xy 332.387192 -48.8442) (xy 332.120597 -48.8442) (xy 332.106973 -48.889483) (xy 332.083301 -48.93998)
			(xy 332.052528 -48.986493) (xy 332.015311 -49.02803) (xy 331.972443 -49.063705) (xy 331.924837 -49.092759)
			(xy 331.873508 -49.114571) (xy 331.819551 -49.128677) (xy 331.764114 -49.134777) (xy 331.70838 -49.13274)
			(xy 331.653537 -49.12261) (xy 331.600753 -49.104603) (xy 331.551153 -49.079102) (xy 331.505795 -49.046651)
			(xy 331.465646 -49.007942) (xy 331.43156 -48.963799) (xy 331.404264 -48.915164) (xy 331.384341 -48.863073)
			(xy 331.372215 -48.808636) (xy 331.368144 -48.753014) (xy 321.158092 -48.753014) (xy 321.830687 -49.95291)
			(xy 337.132928 -49.95291) (xy 337.136999 -49.897288) (xy 337.149125 -49.842851) (xy 337.169048 -49.79076)
			(xy 337.196344 -49.742125) (xy 337.23043 -49.697982) (xy 337.270579 -49.659273) (xy 337.315937 -49.626822)
			(xy 337.365537 -49.601321) (xy 337.418321 -49.583314) (xy 337.473164 -49.573184) (xy 337.528898 -49.571147)
			(xy 337.584335 -49.577247) (xy 337.638292 -49.591353) (xy 337.689621 -49.613165) (xy 337.737227 -49.642219)
			(xy 337.780095 -49.677894) (xy 337.817312 -49.719431) (xy 337.848085 -49.765944) (xy 337.871757 -49.816441)
			(xy 337.887825 -49.869848) (xy 337.895945 -49.925024) (xy 337.896454 -49.95291) (xy 337.895945 -49.980796)
			(xy 337.887825 -50.035972) (xy 337.871757 -50.089379) (xy 337.848085 -50.139876) (xy 337.817312 -50.186389)
			(xy 337.780095 -50.227926) (xy 337.737227 -50.263601) (xy 337.689621 -50.292655) (xy 337.638292 -50.314467)
			(xy 337.584335 -50.328573) (xy 337.528898 -50.334673) (xy 337.473164 -50.332636) (xy 337.418321 -50.322506)
			(xy 337.365537 -50.304499) (xy 337.315937 -50.278998) (xy 337.270579 -50.246547) (xy 337.23043 -50.207838)
			(xy 337.196344 -50.163695) (xy 337.169048 -50.11506) (xy 337.149125 -50.062969) (xy 337.136999 -50.008532)
			(xy 337.132928 -49.95291) (xy 321.830687 -49.95291) (xy 321.854322 -49.995074) (xy 321.856354 -49.998376)
			(xy 322.537836 -51.01844) (xy 322.538493 -51.019456) (xy 334.94929 -51.019456) (xy 334.953361 -50.963834)
			(xy 334.965487 -50.909397) (xy 334.98541 -50.857306) (xy 335.012706 -50.808671) (xy 335.046792 -50.764528)
			(xy 335.086941 -50.725819) (xy 335.132299 -50.693368) (xy 335.181899 -50.667867) (xy 335.234683 -50.64986)
			(xy 335.289526 -50.63973) (xy 335.34526 -50.637693) (xy 335.400697 -50.643793) (xy 335.454654 -50.657899)
			(xy 335.505983 -50.679711) (xy 335.553589 -50.708765) (xy 335.596457 -50.74444) (xy 335.633674 -50.785977)
			(xy 335.664447 -50.83249) (xy 335.688119 -50.882987) (xy 335.704187 -50.936394) (xy 335.712307 -50.99157)
			(xy 335.712816 -51.019456) (xy 335.712307 -51.047342) (xy 335.704187 -51.102518) (xy 335.688119 -51.155925)
			(xy 335.664447 -51.206422) (xy 335.633674 -51.252935) (xy 335.596457 -51.294472) (xy 335.553589 -51.330147)
			(xy 335.505983 -51.359201) (xy 335.454654 -51.381013) (xy 335.400697 -51.395119) (xy 335.34526 -51.401219)
			(xy 335.289526 -51.399182) (xy 335.234683 -51.389052) (xy 335.181899 -51.371045) (xy 335.132299 -51.345544)
			(xy 335.086941 -51.313093) (xy 335.046792 -51.274384) (xy 335.012706 -51.230241) (xy 334.98541 -51.181606)
			(xy 334.965487 -51.129515) (xy 334.953361 -51.075078) (xy 334.94929 -51.019456) (xy 322.538493 -51.019456)
			(xy 322.556747 -51.047663) (xy 322.588343 -51.109688) (xy 322.612437 -51.174995) (xy 322.628695 -51.242679)
			(xy 322.636892 -51.311804) (xy 322.637404 -51.346608) (xy 322.637404 -53.315108) (xy 322.722439 -54.731412)
			(xy 323.72046 -54.731412) (xy 323.720918 -54.704041) (xy 323.728736 -54.649861) (xy 323.744226 -54.597358)
			(xy 323.76707 -54.547611) (xy 323.796797 -54.501645) (xy 323.81444 -54.480714) (xy 323.814694 -54.48046)
			(xy 323.820261 -54.47336) (xy 323.82652 -54.456454) (xy 323.826886 -54.44744) (xy 323.826886 -54.380384)
			(xy 323.82654 -54.371366) (xy 323.820285 -54.354449) (xy 323.814694 -54.347364) (xy 323.81444 -54.347364)
			(xy 323.81444 -54.34711) (xy 323.796811 -54.326168) (xy 323.767084 -54.280202) (xy 323.744237 -54.230457)
			(xy 323.72874 -54.177957) (xy 323.72091 -54.123779) (xy 323.720908 -54.069039) (xy 323.728736 -54.014861)
			(xy 323.744231 -53.962359) (xy 323.767076 -53.912614) (xy 323.7968 -53.866646) (xy 323.81444 -53.845714)
			(xy 323.814694 -53.84546) (xy 323.820261 -53.83836) (xy 323.82652 -53.821454) (xy 323.826886 -53.81244)
			(xy 323.826886 -53.745384) (xy 323.82654 -53.736366) (xy 323.820285 -53.719449) (xy 323.814694 -53.712364)
			(xy 323.81444 -53.712364) (xy 323.81444 -53.71211) (xy 323.796811 -53.691168) (xy 323.767084 -53.645202)
			(xy 323.744237 -53.595457) (xy 323.72874 -53.542957) (xy 323.72091 -53.488779) (xy 323.720908 -53.434039)
			(xy 323.728736 -53.379861) (xy 323.744231 -53.327359) (xy 323.767076 -53.277614) (xy 323.7968 -53.231646)
			(xy 323.81444 -53.210714) (xy 323.814694 -53.21046) (xy 323.820261 -53.20336) (xy 323.82652 -53.186454)
			(xy 323.826886 -53.17744) (xy 323.826886 -53.110384) (xy 323.82654 -53.101366) (xy 323.820285 -53.084449)
			(xy 323.814694 -53.077364) (xy 323.81444 -53.077364) (xy 323.81444 -53.07711) (xy 323.796798 -53.05618)
			(xy 323.767086 -53.010207) (xy 323.744249 -52.960459) (xy 323.728759 -52.907958) (xy 323.720933 -52.853781)
			(xy 323.72046 -52.826412) (xy 323.720946 -52.799161) (xy 323.728702 -52.745213) (xy 323.744057 -52.692918)
			(xy 323.766699 -52.643341) (xy 323.796165 -52.597491) (xy 323.831856 -52.5563) (xy 323.873047 -52.520609)
			(xy 323.918897 -52.491143) (xy 323.968474 -52.468501) (xy 324.020769 -52.453146) (xy 324.074717 -52.44539)
			(xy 324.129219 -52.44539) (xy 324.183167 -52.453146) (xy 324.235462 -52.468501) (xy 324.285039 -52.491143)
			(xy 324.330889 -52.520609) (xy 324.37208 -52.5563) (xy 324.407771 -52.597491) (xy 324.437237 -52.643341)
			(xy 324.459879 -52.692918) (xy 324.475234 -52.745213) (xy 324.48299 -52.799161) (xy 324.483476 -52.826412)
			(xy 324.483023 -52.853783) (xy 324.475203 -52.907963) (xy 324.459711 -52.960466) (xy 324.436866 -53.010213)
			(xy 324.407139 -53.056179) (xy 324.389496 -53.07711) (xy 324.389242 -53.077364) (xy 324.383657 -53.084452)
			(xy 324.377411 -53.101368) (xy 324.37705 -53.110384) (xy 324.37705 -53.17744) (xy 324.377377 -53.18646)
			(xy 324.383644 -53.203377) (xy 324.389242 -53.21046) (xy 324.389496 -53.21046) (xy 324.389496 -53.210714)
			(xy 324.407147 -53.231638) (xy 324.43687 -53.277608) (xy 324.459713 -53.327355) (xy 324.475208 -53.379859)
			(xy 324.483035 -53.434038) (xy 324.483033 -53.48878) (xy 324.475204 -53.542959) (xy 324.459707 -53.595461)
			(xy 324.436861 -53.645208) (xy 324.407137 -53.691177) (xy 324.389496 -53.71211) (xy 324.389242 -53.712364)
			(xy 324.383657 -53.719452) (xy 324.377411 -53.736368) (xy 324.37705 -53.745384) (xy 324.37705 -53.81244)
			(xy 324.377377 -53.82146) (xy 324.383644 -53.838377) (xy 324.389242 -53.84546) (xy 324.389496 -53.84546)
			(xy 324.389496 -53.845714) (xy 324.407147 -53.866638) (xy 324.43687 -53.912608) (xy 324.459713 -53.962355)
			(xy 324.475208 -54.014859) (xy 324.483035 -54.069038) (xy 324.483033 -54.12378) (xy 324.475204 -54.177959)
			(xy 324.459707 -54.230461) (xy 324.436861 -54.280208) (xy 324.407137 -54.326177) (xy 324.389496 -54.34711)
			(xy 324.389242 -54.347364) (xy 324.383657 -54.354452) (xy 324.377411 -54.371368) (xy 324.37705 -54.380384)
			(xy 324.37705 -54.44744) (xy 324.377377 -54.45646) (xy 324.383644 -54.473377) (xy 324.389242 -54.48046)
			(xy 324.389496 -54.48046) (xy 324.389496 -54.480714) (xy 324.407108 -54.501668) (xy 324.436824 -54.547635)
			(xy 324.459665 -54.597377) (xy 324.475163 -54.649873) (xy 324.482998 -54.704044) (xy 324.483476 -54.731412)
			(xy 324.48299 -54.758663) (xy 324.478326 -54.791102) (xy 326.376284 -54.791102) (xy 326.376731 -54.763731)
			(xy 326.38455 -54.70955) (xy 326.400043 -54.657046) (xy 326.422889 -54.607299) (xy 326.45262 -54.561334)
			(xy 326.470264 -54.540404) (xy 326.470518 -54.54015) (xy 326.476092 -54.533055) (xy 326.482346 -54.516145)
			(xy 326.48271 -54.50713) (xy 326.48271 -54.440074) (xy 326.482363 -54.431056) (xy 326.476108 -54.414139)
			(xy 326.470518 -54.407054) (xy 326.470264 -54.407054) (xy 326.470264 -54.4068) (xy 326.452624 -54.385866)
			(xy 326.422896 -54.3399) (xy 326.400048 -54.290154) (xy 326.38455 -54.237652) (xy 326.376721 -54.183472)
			(xy 326.37672 -54.128731) (xy 326.38455 -54.074551) (xy 326.400047 -54.022049) (xy 326.422895 -53.972303)
			(xy 326.452622 -53.926336) (xy 326.470264 -53.905404) (xy 326.470518 -53.90515) (xy 326.476092 -53.898055)
			(xy 326.482346 -53.881145) (xy 326.48271 -53.87213) (xy 326.48271 -53.805074) (xy 326.482363 -53.796056)
			(xy 326.476108 -53.779139) (xy 326.470518 -53.772054) (xy 326.470264 -53.772054) (xy 326.470264 -53.7718)
			(xy 326.452624 -53.750866) (xy 326.422896 -53.7049) (xy 326.400048 -53.655154) (xy 326.38455 -53.602652)
			(xy 326.376721 -53.548472) (xy 326.37672 -53.493731) (xy 326.38455 -53.439551) (xy 326.400047 -53.387049)
			(xy 326.422895 -53.337303) (xy 326.452622 -53.291336) (xy 326.470264 -53.270404) (xy 326.470518 -53.27015)
			(xy 326.476092 -53.263055) (xy 326.482346 -53.246145) (xy 326.48271 -53.23713) (xy 326.48271 -53.170074)
			(xy 326.482363 -53.161056) (xy 326.476108 -53.144139) (xy 326.470518 -53.137054) (xy 326.470264 -53.137054)
			(xy 326.470264 -53.1368) (xy 326.452606 -53.115883) (xy 326.422898 -53.069906) (xy 326.400066 -53.020154)
			(xy 326.38458 -52.96765) (xy 326.376756 -52.913472) (xy 326.376284 -52.886102) (xy 326.37677 -52.858851)
			(xy 326.384526 -52.804903) (xy 326.399881 -52.752608) (xy 326.422523 -52.703031) (xy 326.451989 -52.657181)
			(xy 326.48768 -52.61599) (xy 326.528871 -52.580299) (xy 326.574721 -52.550833) (xy 326.624298 -52.528191)
			(xy 326.676593 -52.512836) (xy 326.730541 -52.50508) (xy 326.785043 -52.50508) (xy 326.838991 -52.512836)
			(xy 326.891286 -52.528191) (xy 326.930399 -52.546054) (xy 331.879373 -52.546054) (xy 331.879373 -52.491546)
			(xy 331.887131 -52.437594) (xy 331.902489 -52.385294) (xy 331.925134 -52.335713) (xy 331.954605 -52.28986)
			(xy 331.990302 -52.248668) (xy 332.031499 -52.212976) (xy 332.077356 -52.183511) (xy 332.126939 -52.160872)
			(xy 332.179241 -52.145521) (xy 332.233194 -52.13777) (xy 332.260448 -52.13731) (xy 332.287817 -52.137804)
			(xy 332.341995 -52.145615) (xy 332.394498 -52.161097) (xy 332.444245 -52.183933) (xy 332.490213 -52.213651)
			(xy 332.511146 -52.23129) (xy 332.5114 -52.231544) (xy 332.518479 -52.237142) (xy 332.535402 -52.243381)
			(xy 332.54442 -52.243736) (xy 332.611476 -52.243736) (xy 332.620491 -52.24336) (xy 332.637407 -52.237125)
			(xy 332.644496 -52.231544) (xy 332.644496 -52.23129) (xy 332.64475 -52.23129) (xy 332.665683 -52.213649)
			(xy 332.711651 -52.183925) (xy 332.761397 -52.161079) (xy 332.813899 -52.145583) (xy 332.868077 -52.137754)
			(xy 332.922819 -52.137754) (xy 332.976997 -52.145583) (xy 333.029499 -52.161079) (xy 333.079245 -52.183925)
			(xy 333.125213 -52.213649) (xy 333.146146 -52.23129) (xy 333.1464 -52.231544) (xy 333.153479 -52.237142)
			(xy 333.170402 -52.243381) (xy 333.17942 -52.243736) (xy 333.246476 -52.243736) (xy 333.255491 -52.24336)
			(xy 333.272407 -52.237125) (xy 333.279496 -52.231544) (xy 333.279496 -52.23129) (xy 333.27975 -52.23129)
			(xy 333.300689 -52.213659) (xy 333.34666 -52.183947) (xy 333.396406 -52.161109) (xy 333.448905 -52.145616)
			(xy 333.503079 -52.137785) (xy 333.530448 -52.13731) (xy 333.557698 -52.137763) (xy 333.611643 -52.145526)
			(xy 333.663935 -52.160886) (xy 333.713508 -52.18353) (xy 333.759355 -52.212999) (xy 333.800541 -52.248693)
			(xy 333.836229 -52.289884) (xy 333.865693 -52.335734) (xy 333.888331 -52.38531) (xy 333.903685 -52.437604)
			(xy 333.91144 -52.49155) (xy 333.91144 -52.54605) (xy 333.905496 -52.587398) (xy 334.955132 -52.587398)
			(xy 334.959203 -52.531776) (xy 334.971329 -52.477339) (xy 334.991252 -52.425248) (xy 335.018548 -52.376613)
			(xy 335.052634 -52.33247) (xy 335.092783 -52.293761) (xy 335.138141 -52.26131) (xy 335.187741 -52.235809)
			(xy 335.240525 -52.217802) (xy 335.295368 -52.207672) (xy 335.351102 -52.205635) (xy 335.406539 -52.211735)
			(xy 335.460496 -52.225841) (xy 335.511825 -52.247653) (xy 335.559431 -52.276707) (xy 335.602299 -52.312382)
			(xy 335.639516 -52.353919) (xy 335.670289 -52.400432) (xy 335.693961 -52.450929) (xy 335.710029 -52.504336)
			(xy 335.718149 -52.559512) (xy 335.718658 -52.587398) (xy 335.718149 -52.615284) (xy 335.710029 -52.67046)
			(xy 335.693961 -52.723867) (xy 335.670289 -52.774364) (xy 335.639516 -52.820877) (xy 335.602299 -52.862414)
			(xy 335.559431 -52.898089) (xy 335.511825 -52.927143) (xy 335.460496 -52.948955) (xy 335.406539 -52.963061)
			(xy 335.351102 -52.969161) (xy 335.295368 -52.967124) (xy 335.240525 -52.956994) (xy 335.187741 -52.938987)
			(xy 335.138141 -52.913486) (xy 335.092783 -52.881035) (xy 335.052634 -52.842326) (xy 335.018548 -52.798183)
			(xy 334.991252 -52.749548) (xy 334.971329 -52.697457) (xy 334.959203 -52.64302) (xy 334.955132 -52.587398)
			(xy 333.905496 -52.587398) (xy 333.903685 -52.599996) (xy 333.888331 -52.65229) (xy 333.865693 -52.701866)
			(xy 333.836229 -52.747716) (xy 333.800541 -52.788907) (xy 333.759355 -52.824601) (xy 333.713508 -52.85407)
			(xy 333.663935 -52.876714) (xy 333.611643 -52.892074) (xy 333.557698 -52.899837) (xy 333.530448 -52.900326)
			(xy 333.503078 -52.89985) (xy 333.448899 -52.892037) (xy 333.396395 -52.876552) (xy 333.346648 -52.853712)
			(xy 333.300681 -52.823987) (xy 333.27975 -52.806346) (xy 333.279496 -52.806092) (xy 333.272415 -52.800497)
			(xy 333.255494 -52.794256) (xy 333.246476 -52.7939) (xy 333.17942 -52.7939) (xy 333.170404 -52.794266)
			(xy 333.153487 -52.800507) (xy 333.1464 -52.806092) (xy 333.146146 -52.806346) (xy 333.125213 -52.823987)
			(xy 333.079245 -52.853711) (xy 333.029499 -52.876557) (xy 332.976997 -52.892053) (xy 332.922819 -52.899882)
			(xy 332.868077 -52.899882) (xy 332.813899 -52.892053) (xy 332.761397 -52.876557) (xy 332.711651 -52.853711)
			(xy 332.665683 -52.823987) (xy 332.64475 -52.806346) (xy 332.644496 -52.806092) (xy 332.637415 -52.800497)
			(xy 332.620494 -52.794256) (xy 332.611476 -52.7939) (xy 332.54442 -52.7939) (xy 332.535404 -52.794266)
			(xy 332.518487 -52.800507) (xy 332.5114 -52.806092) (xy 332.5114 -52.806346) (xy 332.511146 -52.806346)
			(xy 332.4902 -52.823969) (xy 332.444232 -52.853685) (xy 332.394488 -52.876525) (xy 332.34199 -52.892019)
			(xy 332.287816 -52.899851) (xy 332.260448 -52.900326) (xy 332.233194 -52.89983) (xy 332.179241 -52.892079)
			(xy 332.126939 -52.876728) (xy 332.077356 -52.854089) (xy 332.031499 -52.824624) (xy 331.990302 -52.788932)
			(xy 331.954605 -52.74774) (xy 331.925134 -52.701887) (xy 331.902489 -52.652306) (xy 331.887131 -52.600006)
			(xy 331.879373 -52.546054) (xy 326.930399 -52.546054) (xy 326.940863 -52.550833) (xy 326.986713 -52.580299)
			(xy 327.027904 -52.61599) (xy 327.063595 -52.657181) (xy 327.093061 -52.703031) (xy 327.115703 -52.752608)
			(xy 327.131058 -52.804903) (xy 327.138814 -52.858851) (xy 327.1393 -52.886102) (xy 327.138835 -52.913472)
			(xy 327.131017 -52.967651) (xy 327.115528 -53.020155) (xy 327.092686 -53.069901) (xy 327.062961 -53.115868)
			(xy 327.04532 -53.1368) (xy 327.045066 -53.137054) (xy 327.039489 -53.144147) (xy 327.033238 -53.161059)
			(xy 327.032874 -53.170074) (xy 327.032874 -53.23713) (xy 327.033222 -53.246148) (xy 327.039476 -53.263064)
			(xy 327.045066 -53.27015) (xy 327.04532 -53.27015) (xy 327.04532 -53.270404) (xy 327.062961 -53.291336)
			(xy 327.092682 -53.337305) (xy 327.115524 -53.387052) (xy 327.131018 -53.439554) (xy 327.138846 -53.493731)
			(xy 327.138845 -53.548472) (xy 327.131018 -53.602649) (xy 327.115523 -53.655151) (xy 327.09268 -53.704897)
			(xy 327.062959 -53.750866) (xy 327.04639 -53.77053) (xy 327.410572 -53.77053) (xy 327.411084 -53.741613)
			(xy 327.419811 -53.68444) (xy 327.437068 -53.62924) (xy 327.462461 -53.577277) (xy 327.495407 -53.529744)
			(xy 327.535151 -53.487729) (xy 327.557638 -53.46954) (xy 327.566423 -53.461912) (xy 327.576617 -53.441027)
			(xy 327.577196 -53.429408) (xy 327.577196 -53.349652) (xy 327.576672 -53.338018) (xy 327.566473 -53.317109)
			(xy 327.557638 -53.30952) (xy 327.535172 -53.291308) (xy 327.495434 -53.249294) (xy 327.462492 -53.201764)
			(xy 327.4371 -53.149806) (xy 327.419841 -53.094612) (xy 327.411108 -53.037445) (xy 327.410572 -53.00853)
			(xy 327.411083 -52.981279) (xy 327.418836 -52.927331) (xy 327.434187 -52.875035) (xy 327.456824 -52.825456)
			(xy 327.486287 -52.779604) (xy 327.521976 -52.738411) (xy 327.563164 -52.702717) (xy 327.609012 -52.673248)
			(xy 327.658588 -52.650604) (xy 327.710882 -52.635246) (xy 327.764829 -52.627487) (xy 327.79208 -52.627022)
			(xy 327.818394 -52.627496) (xy 327.870522 -52.634728) (xy 327.921165 -52.649046) (xy 327.969364 -52.670177)
			(xy 328.014208 -52.697722) (xy 328.054848 -52.731161) (xy 328.073004 -52.750212) (xy 328.08052 -52.757619)
			(xy 328.099804 -52.76614) (xy 328.110342 -52.766722) (xy 328.185018 -52.766722) (xy 328.195563 -52.766155)
			(xy 328.214858 -52.757646) (xy 328.222356 -52.750212) (xy 328.240494 -52.731139) (xy 328.281127 -52.697683)
			(xy 328.325971 -52.670126) (xy 328.374175 -52.64899) (xy 328.424826 -52.634677) (xy 328.476963 -52.627458)
			(xy 328.50328 -52.627022) (xy 328.530534 -52.627474) (xy 328.584487 -52.635229) (xy 328.636787 -52.650584)
			(xy 328.686369 -52.673226) (xy 328.732223 -52.702695) (xy 328.773417 -52.73839) (xy 328.809111 -52.779585)
			(xy 328.838578 -52.82544) (xy 328.861219 -52.875023) (xy 328.876573 -52.927323) (xy 328.884327 -52.981276)
			(xy 328.884788 -53.00853) (xy 328.884305 -53.036196) (xy 328.882074 -53.051456) (xy 337.141056 -53.051456)
			(xy 337.145127 -52.995834) (xy 337.157253 -52.941397) (xy 337.177176 -52.889306) (xy 337.204472 -52.840671)
			(xy 337.238558 -52.796528) (xy 337.278707 -52.757819) (xy 337.324065 -52.725368) (xy 337.373665 -52.699867)
			(xy 337.426449 -52.68186) (xy 337.481292 -52.67173) (xy 337.537026 -52.669693) (xy 337.592463 -52.675793)
			(xy 337.64642 -52.689899) (xy 337.697749 -52.711711) (xy 337.745355 -52.740765) (xy 337.788223 -52.77644)
			(xy 337.82544 -52.817977) (xy 337.856213 -52.86449) (xy 337.879885 -52.914987) (xy 337.895953 -52.968394)
			(xy 337.904073 -53.02357) (xy 337.904582 -53.051456) (xy 337.904073 -53.079342) (xy 337.895953 -53.134518)
			(xy 337.879885 -53.187925) (xy 337.856213 -53.238422) (xy 337.82544 -53.284935) (xy 337.788223 -53.326472)
			(xy 337.745355 -53.362147) (xy 337.697749 -53.391201) (xy 337.64642 -53.413013) (xy 337.592463 -53.427119)
			(xy 337.537026 -53.433219) (xy 337.481292 -53.431182) (xy 337.426449 -53.421052) (xy 337.373665 -53.403045)
			(xy 337.324065 -53.377544) (xy 337.278707 -53.345093) (xy 337.238558 -53.306384) (xy 337.204472 -53.262241)
			(xy 337.177176 -53.213606) (xy 337.157253 -53.161515) (xy 337.145127 -53.107078) (xy 337.141056 -53.051456)
			(xy 328.882074 -53.051456) (xy 328.876301 -53.090947) (xy 328.86048 -53.143969) (xy 328.837172 -53.194154)
			(xy 328.806866 -53.240449) (xy 328.770197 -53.281886) (xy 328.727931 -53.317598) (xy 328.704702 -53.332634)
			(xy 328.695021 -53.339266) (xy 328.682577 -53.35913) (xy 328.680826 -53.370734) (xy 328.672952 -53.450744)
			(xy 328.6723 -53.462383) (xy 328.680394 -53.484221) (xy 328.688446 -53.492654) (xy 328.6887 -53.492908)
			(xy 328.707267 -53.511003) (xy 328.739847 -53.551332) (xy 328.766662 -53.595703) (xy 328.787217 -53.643299)
			(xy 328.801133 -53.693241) (xy 328.808154 -53.744608) (xy 328.808588 -53.77053) (xy 328.80815 -53.797783)
			(xy 328.800389 -53.851733) (xy 328.785029 -53.90403) (xy 328.762383 -53.953609) (xy 328.732912 -53.99946)
			(xy 328.697215 -54.040651) (xy 328.65602 -54.076342) (xy 328.610165 -54.105807) (xy 328.560583 -54.128446)
			(xy 328.508284 -54.1438) (xy 328.454333 -54.151554) (xy 328.42708 -54.152038) (xy 328.399709 -54.151599)
			(xy 328.345528 -54.143777) (xy 328.293024 -54.128282) (xy 328.243277 -54.105434) (xy 328.197312 -54.075703)
			(xy 328.176382 -54.058058) (xy 328.176128 -54.057804) (xy 328.169037 -54.052223) (xy 328.152124 -54.045973)
			(xy 328.143108 -54.045612) (xy 328.076052 -54.045612) (xy 328.067037 -54.045991) (xy 328.05012 -54.052223)
			(xy 328.043032 -54.057804) (xy 328.043032 -54.058058) (xy 328.042778 -54.058058) (xy 328.021822 -54.075667)
			(xy 327.975856 -54.105385) (xy 327.926115 -54.128228) (xy 327.873619 -54.143725) (xy 327.819448 -54.151561)
			(xy 327.79208 -54.152038) (xy 327.76483 -54.151541) (xy 327.710884 -54.143782) (xy 327.658591 -54.128426)
			(xy 327.609016 -54.105785) (xy 327.563167 -54.076319) (xy 327.521978 -54.040629) (xy 327.486287 -53.999441)
			(xy 327.45682 -53.953593) (xy 327.434177 -53.904018) (xy 327.41882 -53.851726) (xy 327.41106 -53.79778)
			(xy 327.410572 -53.77053) (xy 327.04639 -53.77053) (xy 327.04532 -53.7718) (xy 327.045066 -53.772054)
			(xy 327.039489 -53.779147) (xy 327.033238 -53.796059) (xy 327.032874 -53.805074) (xy 327.032874 -53.87213)
			(xy 327.033222 -53.881148) (xy 327.039476 -53.898064) (xy 327.045066 -53.90515) (xy 327.04532 -53.90515)
			(xy 327.04532 -53.905404) (xy 327.062961 -53.926336) (xy 327.092682 -53.972305) (xy 327.115524 -54.022052)
			(xy 327.131018 -54.074554) (xy 327.138846 -54.128731) (xy 327.138845 -54.183472) (xy 327.131018 -54.237649)
			(xy 327.115523 -54.290151) (xy 327.101731 -54.320186) (xy 329.330304 -54.320186) (xy 329.330761 -54.292815)
			(xy 329.338581 -54.238636) (xy 329.354072 -54.186133) (xy 329.376916 -54.136386) (xy 329.406642 -54.090419)
			(xy 329.424284 -54.069488) (xy 329.424538 -54.069234) (xy 329.430121 -54.062145) (xy 329.436369 -54.04523)
			(xy 329.43673 -54.036214) (xy 329.43673 -53.969158) (xy 329.436339 -53.960145) (xy 329.430114 -53.943228)
			(xy 329.424538 -53.936138) (xy 329.424284 -53.936138) (xy 329.424284 -53.935884) (xy 329.406668 -53.914933)
			(xy 329.376954 -53.868965) (xy 329.354113 -53.819222) (xy 329.338617 -53.766726) (xy 329.330782 -53.712554)
			(xy 329.330304 -53.685186) (xy 329.33079 -53.657935) (xy 329.338546 -53.603987) (xy 329.353901 -53.551692)
			(xy 329.376543 -53.502115) (xy 329.406009 -53.456265) (xy 329.4417 -53.415074) (xy 329.482891 -53.379383)
			(xy 329.528741 -53.349917) (xy 329.578318 -53.327275) (xy 329.630613 -53.31192) (xy 329.684561 -53.304164)
			(xy 329.739063 -53.304164) (xy 329.793011 -53.31192) (xy 329.845306 -53.327275) (xy 329.894883 -53.349917)
			(xy 329.940733 -53.379383) (xy 329.981924 -53.415074) (xy 330.017615 -53.456265) (xy 330.047081 -53.502115)
			(xy 330.069723 -53.551692) (xy 330.085078 -53.603987) (xy 330.092834 -53.657935) (xy 330.09332 -53.685186)
			(xy 330.092865 -53.712557) (xy 330.085048 -53.766737) (xy 330.069557 -53.819241) (xy 330.046712 -53.868988)
			(xy 330.016984 -53.914954) (xy 329.99934 -53.935884) (xy 329.999086 -53.936138) (xy 329.993518 -53.943237)
			(xy 329.98726 -53.960144) (xy 329.986894 -53.969158) (xy 329.986894 -54.036214) (xy 329.987246 -54.045231)
			(xy 329.993497 -54.062148) (xy 329.999086 -54.069234) (xy 329.99934 -54.069234) (xy 329.99934 -54.069488)
			(xy 330.016994 -54.090408) (xy 330.046702 -54.136385) (xy 330.069535 -54.186136) (xy 330.085022 -54.238639)
			(xy 330.092848 -54.292816) (xy 330.09332 -54.320186) (xy 330.092834 -54.347437) (xy 330.085078 -54.401385)
			(xy 330.069723 -54.45368) (xy 330.047081 -54.503257) (xy 330.017615 -54.549107) (xy 329.981924 -54.590298)
			(xy 329.940733 -54.625989) (xy 329.894883 -54.655455) (xy 329.845306 -54.678097) (xy 329.793011 -54.693452)
			(xy 329.739063 -54.701208) (xy 329.684561 -54.701208) (xy 329.630613 -54.693452) (xy 329.578318 -54.678097)
			(xy 329.528741 -54.655455) (xy 329.482891 -54.625989) (xy 329.4417 -54.590298) (xy 329.406009 -54.549107)
			(xy 329.376543 -54.503257) (xy 329.353901 -54.45368) (xy 329.338546 -54.401385) (xy 329.33079 -54.347437)
			(xy 329.330304 -54.320186) (xy 327.101731 -54.320186) (xy 327.09268 -54.339897) (xy 327.062959 -54.385866)
			(xy 327.04532 -54.4068) (xy 327.045066 -54.407054) (xy 327.039489 -54.414147) (xy 327.033238 -54.431059)
			(xy 327.032874 -54.440074) (xy 327.032874 -54.50713) (xy 327.033222 -54.516148) (xy 327.039476 -54.533064)
			(xy 327.045066 -54.54015) (xy 327.04532 -54.54015) (xy 327.04532 -54.540404) (xy 327.062978 -54.561321)
			(xy 327.092686 -54.607298) (xy 327.115518 -54.65705) (xy 327.131005 -54.709554) (xy 327.138828 -54.763732)
			(xy 327.138945 -54.770528) (xy 330.270866 -54.770528) (xy 330.271332 -54.743158) (xy 330.279148 -54.688978)
			(xy 330.294636 -54.636474) (xy 330.317478 -54.586727) (xy 330.347204 -54.540761) (xy 330.364846 -54.51983)
			(xy 330.3651 -54.519576) (xy 330.370703 -54.5125) (xy 330.37694 -54.495575) (xy 330.377292 -54.486556)
			(xy 330.377292 -54.4195) (xy 330.376937 -54.410483) (xy 330.370688 -54.393566) (xy 330.3651 -54.38648)
			(xy 330.364846 -54.38648) (xy 330.364846 -54.386226) (xy 330.347213 -54.365289) (xy 330.317498 -54.319318)
			(xy 330.294661 -54.269572) (xy 330.279168 -54.217072) (xy 330.27134 -54.162897) (xy 330.270866 -54.135528)
			(xy 330.271352 -54.108277) (xy 330.279108 -54.054329) (xy 330.294463 -54.002034) (xy 330.317105 -53.952457)
			(xy 330.346571 -53.906607) (xy 330.382262 -53.865416) (xy 330.423453 -53.829725) (xy 330.469303 -53.800259)
			(xy 330.51888 -53.777617) (xy 330.571175 -53.762262) (xy 330.625123 -53.754506) (xy 330.679625 -53.754506)
			(xy 330.733573 -53.762262) (xy 330.785868 -53.777617) (xy 330.835445 -53.800259) (xy 330.881295 -53.829725)
			(xy 330.922486 -53.865416) (xy 330.958177 -53.906607) (xy 330.987643 -53.952457) (xy 330.992718 -53.96357)
			(xy 334.971896 -53.96357) (xy 334.975967 -53.907948) (xy 334.988093 -53.853511) (xy 335.008016 -53.80142)
			(xy 335.035312 -53.752785) (xy 335.069398 -53.708642) (xy 335.109547 -53.669933) (xy 335.154905 -53.637482)
			(xy 335.204505 -53.611981) (xy 335.257289 -53.593974) (xy 335.312132 -53.583844) (xy 335.367866 -53.581807)
			(xy 335.423303 -53.587907) (xy 335.47726 -53.602013) (xy 335.528589 -53.623825) (xy 335.576195 -53.652879)
			(xy 335.619063 -53.688554) (xy 335.65628 -53.730091) (xy 335.687053 -53.776604) (xy 335.710725 -53.827101)
			(xy 335.726793 -53.880508) (xy 335.734913 -53.935684) (xy 335.735422 -53.96357) (xy 335.734913 -53.991456)
			(xy 335.726793 -54.046632) (xy 335.710725 -54.100039) (xy 335.687053 -54.150536) (xy 335.65628 -54.197049)
			(xy 335.619063 -54.238586) (xy 335.576195 -54.274261) (xy 335.528589 -54.303315) (xy 335.47726 -54.325127)
			(xy 335.423303 -54.339233) (xy 335.367866 -54.345333) (xy 335.312132 -54.343296) (xy 335.257289 -54.333166)
			(xy 335.204505 -54.315159) (xy 335.154905 -54.289658) (xy 335.109547 -54.257207) (xy 335.069398 -54.218498)
			(xy 335.035312 -54.174355) (xy 335.008016 -54.12572) (xy 334.988093 -54.073629) (xy 334.975967 -54.019192)
			(xy 334.971896 -53.96357) (xy 330.992718 -53.96357) (xy 331.010285 -54.002034) (xy 331.02564 -54.054329)
			(xy 331.033396 -54.108277) (xy 331.033882 -54.135528) (xy 331.033437 -54.162899) (xy 331.025615 -54.217079)
			(xy 331.010121 -54.269583) (xy 330.987274 -54.319329) (xy 330.957545 -54.365295) (xy 330.939902 -54.386226)
			(xy 330.939648 -54.38648) (xy 330.934057 -54.393564) (xy 330.927814 -54.410483) (xy 330.927456 -54.4195)
			(xy 330.927456 -54.486556) (xy 330.927822 -54.495572) (xy 330.934062 -54.51249) (xy 330.939648 -54.519576)
			(xy 330.939902 -54.519576) (xy 330.939902 -54.51983) (xy 330.957522 -54.540777) (xy 330.987237 -54.586746)
			(xy 331.010076 -54.63649) (xy 331.025572 -54.688987) (xy 331.033405 -54.74316) (xy 331.033882 -54.770528)
			(xy 331.033396 -54.797779) (xy 331.02564 -54.851727) (xy 331.010285 -54.904022) (xy 330.987643 -54.953599)
			(xy 330.958177 -54.999449) (xy 330.922486 -55.04064) (xy 330.881295 -55.076331) (xy 330.835445 -55.105797)
			(xy 330.785868 -55.128439) (xy 330.733573 -55.143794) (xy 330.679625 -55.15155) (xy 330.625123 -55.15155)
			(xy 330.571175 -55.143794) (xy 330.51888 -55.128439) (xy 330.469303 -55.105797) (xy 330.423453 -55.076331)
			(xy 330.382262 -55.04064) (xy 330.346571 -54.999449) (xy 330.317105 -54.953599) (xy 330.294463 -54.904022)
			(xy 330.279108 -54.851727) (xy 330.271352 -54.797779) (xy 330.270866 -54.770528) (xy 327.138945 -54.770528)
			(xy 327.1393 -54.791102) (xy 327.138814 -54.818353) (xy 327.131058 -54.872301) (xy 327.115703 -54.924596)
			(xy 327.093061 -54.974173) (xy 327.063595 -55.020023) (xy 327.027904 -55.061214) (xy 326.986713 -55.096905)
			(xy 326.940863 -55.126371) (xy 326.891286 -55.149013) (xy 326.838991 -55.164368) (xy 326.785043 -55.172124)
			(xy 326.730541 -55.172124) (xy 326.676593 -55.164368) (xy 326.624298 -55.149013) (xy 326.574721 -55.126371)
			(xy 326.528871 -55.096905) (xy 326.48768 -55.061214) (xy 326.451989 -55.020023) (xy 326.422523 -54.974173)
			(xy 326.399881 -54.924596) (xy 326.384526 -54.872301) (xy 326.37677 -54.818353) (xy 326.376284 -54.791102)
			(xy 324.478326 -54.791102) (xy 324.475234 -54.812611) (xy 324.459879 -54.864906) (xy 324.437237 -54.914483)
			(xy 324.407771 -54.960333) (xy 324.37208 -55.001524) (xy 324.330889 -55.037215) (xy 324.285039 -55.066681)
			(xy 324.235462 -55.089323) (xy 324.183167 -55.104678) (xy 324.129219 -55.112434) (xy 324.074717 -55.112434)
			(xy 324.020769 -55.104678) (xy 323.968474 -55.089323) (xy 323.918897 -55.066681) (xy 323.873047 -55.037215)
			(xy 323.831856 -55.001524) (xy 323.796165 -54.960333) (xy 323.766699 -54.914483) (xy 323.744057 -54.864906)
			(xy 323.728702 -54.812611) (xy 323.720946 -54.758663) (xy 323.72046 -54.731412) (xy 322.722439 -54.731412)
			(xy 322.78193 -55.722266) (xy 336.03387 -55.722266) (xy 336.037941 -55.666644) (xy 336.050067 -55.612207)
			(xy 336.06999 -55.560116) (xy 336.097286 -55.511481) (xy 336.131372 -55.467338) (xy 336.171521 -55.428629)
			(xy 336.216879 -55.396178) (xy 336.266479 -55.370677) (xy 336.319263 -55.35267) (xy 336.374106 -55.34254)
			(xy 336.42984 -55.340503) (xy 336.485277 -55.346603) (xy 336.539234 -55.360709) (xy 336.590563 -55.382521)
			(xy 336.638169 -55.411575) (xy 336.681037 -55.44725) (xy 336.718254 -55.488787) (xy 336.749027 -55.5353)
			(xy 336.772699 -55.585797) (xy 336.788767 -55.639204) (xy 336.796887 -55.69438) (xy 336.797396 -55.722266)
			(xy 336.796887 -55.750152) (xy 336.788767 -55.805328) (xy 336.772699 -55.858735) (xy 336.749027 -55.909232)
			(xy 336.718254 -55.955745) (xy 336.681037 -55.997282) (xy 336.638169 -56.032957) (xy 336.590563 -56.062011)
			(xy 336.539234 -56.083823) (xy 336.485277 -56.097929) (xy 336.42984 -56.104029) (xy 336.374106 -56.101992)
			(xy 336.319263 -56.091862) (xy 336.266479 -56.073855) (xy 336.216879 -56.048354) (xy 336.171521 -56.015903)
			(xy 336.131372 -55.977194) (xy 336.097286 -55.933051) (xy 336.06999 -55.884416) (xy 336.050067 -55.832325)
			(xy 336.037941 -55.777888) (xy 336.03387 -55.722266) (xy 322.78193 -55.722266) (xy 322.858821 -57.002934)
			(xy 331.76337 -57.002934) (xy 331.763897 -56.974844) (xy 331.772119 -56.919268) (xy 331.788405 -56.8655)
			(xy 331.812403 -56.814703) (xy 331.843592 -56.767976) (xy 331.881299 -56.72633) (xy 331.924708 -56.690666)
			(xy 331.948536 -56.675782) (xy 331.957426 -56.670448) (xy 331.969618 -56.65343) (xy 331.989938 -56.560212)
			(xy 331.98562 -56.539638) (xy 331.979778 -56.531002) (xy 331.963774 -56.506941) (xy 331.938433 -56.455008)
			(xy 331.921208 -56.399849) (xy 331.912494 -56.342725) (xy 331.91196 -56.313832) (xy 331.912508 -56.286583)
			(xy 331.920259 -56.232639) (xy 331.935609 -56.180348) (xy 331.958244 -56.130773) (xy 331.987704 -56.084924)
			(xy 332.023389 -56.043734) (xy 332.064572 -56.008042) (xy 332.110416 -55.978574) (xy 332.159988 -55.955931)
			(xy 332.212277 -55.940573) (xy 332.266219 -55.932812) (xy 332.293468 -55.932324) (xy 332.320838 -55.932803)
			(xy 332.375017 -55.940617) (xy 332.42752 -55.956103) (xy 332.477267 -55.978942) (xy 332.523234 -56.008664)
			(xy 332.544166 -56.026304) (xy 332.54442 -56.026558) (xy 332.551492 -56.032166) (xy 332.56842 -56.038398)
			(xy 332.57744 -56.03875) (xy 332.644496 -56.03875) (xy 332.653514 -56.038402) (xy 332.670431 -56.032149)
			(xy 332.677516 -56.026558) (xy 332.677516 -56.026304) (xy 332.67777 -56.026304) (xy 332.698703 -56.008663)
			(xy 332.744671 -55.978939) (xy 332.794417 -55.956093) (xy 332.846919 -55.940597) (xy 332.901097 -55.932768)
			(xy 332.955839 -55.932768) (xy 333.010017 -55.940597) (xy 333.062519 -55.956093) (xy 333.112265 -55.978939)
			(xy 333.158233 -56.008663) (xy 333.179166 -56.026304) (xy 333.17942 -56.026558) (xy 333.186492 -56.032166)
			(xy 333.20342 -56.038398) (xy 333.21244 -56.03875) (xy 333.279496 -56.03875) (xy 333.288514 -56.038402)
			(xy 333.305431 -56.032149) (xy 333.312516 -56.026558) (xy 333.312516 -56.026304) (xy 333.31277 -56.026304)
			(xy 333.333703 -56.008666) (xy 333.379676 -55.978954) (xy 333.429423 -55.956118) (xy 333.481923 -55.940626)
			(xy 333.536099 -55.932798) (xy 333.563468 -55.932324) (xy 333.590725 -55.932721) (xy 333.644684 -55.940475)
			(xy 333.69699 -55.955829) (xy 333.746578 -55.978472) (xy 333.792439 -56.007941) (xy 333.833639 -56.043638)
			(xy 333.869339 -56.084835) (xy 333.898813 -56.130694) (xy 333.92146 -56.18028) (xy 333.936819 -56.232585)
			(xy 333.944577 -56.286543) (xy 333.944577 -56.297068) (xy 334.28635 -56.297068) (xy 334.290421 -56.241446)
			(xy 334.302547 -56.187009) (xy 334.32247 -56.134918) (xy 334.349766 -56.086283) (xy 334.383852 -56.04214)
			(xy 334.424001 -56.003431) (xy 334.469359 -55.97098) (xy 334.518959 -55.945479) (xy 334.571743 -55.927472)
			(xy 334.626586 -55.917342) (xy 334.68232 -55.915305) (xy 334.737757 -55.921405) (xy 334.791714 -55.935511)
			(xy 334.843043 -55.957323) (xy 334.890649 -55.986377) (xy 334.933517 -56.022052) (xy 334.970734 -56.063589)
			(xy 335.001507 -56.110102) (xy 335.025179 -56.160599) (xy 335.041247 -56.214006) (xy 335.049367 -56.269182)
			(xy 335.049876 -56.297068) (xy 335.049367 -56.324954) (xy 335.041247 -56.38013) (xy 335.025179 -56.433537)
			(xy 335.001507 -56.484034) (xy 334.970734 -56.530547) (xy 334.933517 -56.572084) (xy 334.890649 -56.607759)
			(xy 334.843043 -56.636813) (xy 334.791714 -56.658625) (xy 334.737757 -56.672731) (xy 334.68232 -56.678831)
			(xy 334.626586 -56.676794) (xy 334.571743 -56.666664) (xy 334.518959 -56.648657) (xy 334.469359 -56.623156)
			(xy 334.424001 -56.590705) (xy 334.383852 -56.551996) (xy 334.349766 -56.507853) (xy 334.32247 -56.459218)
			(xy 334.302547 -56.407127) (xy 334.290421 -56.35269) (xy 334.28635 -56.297068) (xy 333.944577 -56.297068)
			(xy 333.944577 -56.341057) (xy 333.936819 -56.395015) (xy 333.92146 -56.44732) (xy 333.898813 -56.496906)
			(xy 333.869339 -56.542765) (xy 333.833639 -56.583962) (xy 333.792439 -56.619659) (xy 333.746578 -56.649128)
			(xy 333.69699 -56.671771) (xy 333.644684 -56.687125) (xy 333.590725 -56.694879) (xy 333.563468 -56.69534)
			(xy 333.536096 -56.694907) (xy 333.481915 -56.687084) (xy 333.429411 -56.671588) (xy 333.379665 -56.648738)
			(xy 333.3337 -56.619005) (xy 333.31277 -56.60136) (xy 333.312516 -56.601106) (xy 333.305429 -56.595521)
			(xy 333.288512 -56.589273) (xy 333.279496 -56.588914) (xy 333.21244 -56.588914) (xy 333.203425 -56.589287)
			(xy 333.186508 -56.595523) (xy 333.17942 -56.601106) (xy 333.17942 -56.60136) (xy 333.179166 -56.60136)
			(xy 333.158233 -56.619001) (xy 333.112265 -56.648725) (xy 333.062519 -56.671571) (xy 333.010017 -56.687067)
			(xy 332.955839 -56.694896) (xy 332.901097 -56.694896) (xy 332.846919 -56.687067) (xy 332.794417 -56.671571)
			(xy 332.744671 -56.648725) (xy 332.698703 -56.619001) (xy 332.67777 -56.60136) (xy 332.677516 -56.601106)
			(xy 332.670429 -56.595521) (xy 332.653512 -56.589273) (xy 332.644496 -56.588914) (xy 332.57744 -56.588914)
			(xy 332.568425 -56.589287) (xy 332.551508 -56.595523) (xy 332.54442 -56.601106) (xy 332.543912 -56.60136)
			(xy 332.531181 -56.612308) (xy 332.504087 -56.632147) (xy 332.48981 -56.640984) (xy 332.48092 -56.646318)
			(xy 332.468728 -56.663336) (xy 332.448408 -56.756554) (xy 332.452726 -56.777128) (xy 332.458568 -56.785764)
			(xy 332.474551 -56.809839) (xy 332.499899 -56.861766) (xy 332.517129 -56.916921) (xy 332.525849 -56.974042)
			(xy 332.526386 -57.002934) (xy 332.5259 -57.030185) (xy 332.518144 -57.084133) (xy 332.502789 -57.136428)
			(xy 332.480147 -57.186005) (xy 332.450681 -57.231855) (xy 332.41499 -57.273046) (xy 332.373799 -57.308737)
			(xy 332.327949 -57.338203) (xy 332.278372 -57.360845) (xy 332.226077 -57.3762) (xy 332.172129 -57.383956)
			(xy 332.117627 -57.383956) (xy 332.063679 -57.3762) (xy 332.011384 -57.360845) (xy 331.961807 -57.338203)
			(xy 331.915957 -57.308737) (xy 331.874766 -57.273046) (xy 331.839075 -57.231855) (xy 331.809609 -57.186005)
			(xy 331.786967 -57.136428) (xy 331.771612 -57.084133) (xy 331.763856 -57.030185) (xy 331.76337 -57.002934)
			(xy 322.858821 -57.002934) (xy 322.959472 -58.679334) (xy 332.19517 -58.679334) (xy 332.195603 -58.653019)
			(xy 332.202846 -58.600889) (xy 332.217173 -58.550246) (xy 332.238312 -58.502048) (xy 332.265863 -58.457205)
			(xy 332.299307 -58.416566) (xy 332.31836 -58.39841) (xy 332.325753 -58.390881) (xy 332.334284 -58.371607)
			(xy 332.33487 -58.361072) (xy 332.33487 -58.286396) (xy 332.334365 -58.275843) (xy 332.325814 -58.256548)
			(xy 332.31836 -58.249058) (xy 332.299283 -58.230924) (xy 332.26583 -58.190289) (xy 332.238274 -58.145444)
			(xy 332.21714 -58.097239) (xy 332.202827 -58.046588) (xy 332.195606 -57.994451) (xy 332.19517 -57.968134)
			(xy 332.195656 -57.940883) (xy 332.203412 -57.886935) (xy 332.218767 -57.83464) (xy 332.241409 -57.785063)
			(xy 332.270875 -57.739213) (xy 332.306566 -57.698022) (xy 332.347757 -57.662331) (xy 332.393607 -57.632865)
			(xy 332.443184 -57.610223) (xy 332.495479 -57.594868) (xy 332.549427 -57.587112) (xy 332.603929 -57.587112)
			(xy 332.657877 -57.594868) (xy 332.710172 -57.610223) (xy 332.759749 -57.632865) (xy 332.805599 -57.662331)
			(xy 332.84679 -57.698022) (xy 332.882481 -57.739213) (xy 332.911947 -57.785063) (xy 332.934589 -57.83464)
			(xy 332.949944 -57.886935) (xy 332.9577 -57.940883) (xy 332.958186 -57.968134) (xy 332.957746 -57.994449)
			(xy 332.950506 -58.046579) (xy 332.943238 -58.072274) (xy 336.193382 -58.072274) (xy 336.197453 -58.016652)
			(xy 336.209579 -57.962215) (xy 336.229502 -57.910124) (xy 336.256798 -57.861489) (xy 336.290884 -57.817346)
			(xy 336.331033 -57.778637) (xy 336.376391 -57.746186) (xy 336.425991 -57.720685) (xy 336.478775 -57.702678)
			(xy 336.533618 -57.692548) (xy 336.589352 -57.690511) (xy 336.644789 -57.696611) (xy 336.698746 -57.710717)
			(xy 336.750075 -57.732529) (xy 336.797681 -57.761583) (xy 336.840549 -57.797258) (xy 336.877766 -57.838795)
			(xy 336.908539 -57.885308) (xy 336.932211 -57.935805) (xy 336.948279 -57.989212) (xy 336.956399 -58.044388)
			(xy 336.956908 -58.072274) (xy 336.956399 -58.10016) (xy 336.948279 -58.155336) (xy 336.932211 -58.208743)
			(xy 336.908539 -58.25924) (xy 336.877766 -58.305753) (xy 336.840549 -58.34729) (xy 336.797681 -58.382965)
			(xy 336.750075 -58.412019) (xy 336.698746 -58.433831) (xy 336.644789 -58.447937) (xy 336.589352 -58.454037)
			(xy 336.533618 -58.452) (xy 336.478775 -58.44187) (xy 336.425991 -58.423863) (xy 336.376391 -58.398362)
			(xy 336.331033 -58.365911) (xy 336.290884 -58.327202) (xy 336.256798 -58.283059) (xy 336.229502 -58.234424)
			(xy 336.209579 -58.182333) (xy 336.197453 -58.127896) (xy 336.193382 -58.072274) (xy 332.943238 -58.072274)
			(xy 332.936182 -58.097222) (xy 332.915044 -58.145421) (xy 332.887493 -58.190264) (xy 332.85405 -58.230902)
			(xy 332.834996 -58.249058) (xy 332.82761 -58.256593) (xy 332.819077 -58.275863) (xy 332.818486 -58.286396)
			(xy 332.818486 -58.361072) (xy 332.819021 -58.371621) (xy 332.827553 -58.390916) (xy 332.834996 -58.39841)
			(xy 332.854049 -58.416569) (xy 332.887506 -58.457197) (xy 332.915066 -58.502037) (xy 332.936205 -58.550237)
			(xy 332.950522 -58.600884) (xy 332.957747 -58.653018) (xy 332.958186 -58.679334) (xy 332.9577 -58.706585)
			(xy 332.949944 -58.760533) (xy 332.934589 -58.812828) (xy 332.911947 -58.862405) (xy 332.882481 -58.908255)
			(xy 332.84679 -58.949446) (xy 332.805599 -58.985137) (xy 332.759749 -59.014603) (xy 332.710172 -59.037245)
			(xy 332.657877 -59.0526) (xy 332.603929 -59.060356) (xy 332.549427 -59.060356) (xy 332.495479 -59.0526)
			(xy 332.443184 -59.037245) (xy 332.393607 -59.014603) (xy 332.347757 -58.985137) (xy 332.306566 -58.949446)
			(xy 332.270875 -58.908255) (xy 332.241409 -58.862405) (xy 332.218767 -58.812828) (xy 332.203412 -58.760533)
			(xy 332.195656 -58.706585) (xy 332.19517 -58.679334) (xy 322.959472 -58.679334) (xy 323.03339 -59.910472)
			(xy 323.033644 -59.916822) (xy 323.065463 -60.019254) (xy 332.335561 -60.019254) (xy 332.335561 -59.964746)
			(xy 332.343319 -59.910793) (xy 332.358677 -59.858494) (xy 332.381321 -59.808912) (xy 332.410791 -59.763058)
			(xy 332.446488 -59.721865) (xy 332.487684 -59.686172) (xy 332.53354 -59.656706) (xy 332.583124 -59.634065)
			(xy 332.635425 -59.618712) (xy 332.689378 -59.610959) (xy 332.716632 -59.610498) (xy 332.744003 -59.610946)
			(xy 332.798183 -59.618768) (xy 332.850686 -59.634261) (xy 332.900433 -59.657107) (xy 332.946399 -59.686835)
			(xy 332.96733 -59.704478) (xy 332.967584 -59.704732) (xy 332.974668 -59.710322) (xy 332.991587 -59.716565)
			(xy 333.000604 -59.716924) (xy 333.06766 -59.716924) (xy 333.076674 -59.716543) (xy 333.093591 -59.710311)
			(xy 333.10068 -59.704732) (xy 333.10068 -59.704478) (xy 333.100934 -59.704478) (xy 333.121867 -59.686837)
			(xy 333.167835 -59.657113) (xy 333.217581 -59.634267) (xy 333.270083 -59.618771) (xy 333.324261 -59.610942)
			(xy 333.379003 -59.610942) (xy 333.433181 -59.618771) (xy 333.485683 -59.634267) (xy 333.535429 -59.657113)
			(xy 333.581397 -59.686837) (xy 333.60233 -59.704478) (xy 333.602584 -59.704732) (xy 333.609668 -59.710322)
			(xy 333.626587 -59.716565) (xy 333.635604 -59.716924) (xy 333.70266 -59.716924) (xy 333.711674 -59.716543)
			(xy 333.728591 -59.710311) (xy 333.73568 -59.704732) (xy 333.73568 -59.704478) (xy 333.735934 -59.704478)
			(xy 333.756877 -59.686853) (xy 333.802847 -59.65714) (xy 333.852592 -59.634301) (xy 333.90509 -59.618807)
			(xy 333.959264 -59.610975) (xy 333.986632 -59.610498) (xy 334.013882 -59.610974) (xy 334.067827 -59.618734)
			(xy 334.120119 -59.634092) (xy 334.169693 -59.656736) (xy 334.21554 -59.686203) (xy 334.256727 -59.721895)
			(xy 334.292416 -59.763086) (xy 334.32188 -59.808935) (xy 334.344519 -59.858511) (xy 334.359872 -59.910804)
			(xy 334.367628 -59.96475) (xy 334.367628 -60.01925) (xy 334.359872 -60.073196) (xy 334.344519 -60.125489)
			(xy 334.32188 -60.175065) (xy 334.292416 -60.220914) (xy 334.256727 -60.262105) (xy 334.21554 -60.297797)
			(xy 334.169693 -60.327264) (xy 334.120119 -60.349908) (xy 334.067827 -60.365266) (xy 334.013882 -60.373026)
			(xy 333.986632 -60.373514) (xy 333.959263 -60.373026) (xy 333.905085 -60.365213) (xy 333.852582 -60.349729)
			(xy 333.802835 -60.326892) (xy 333.756867 -60.297173) (xy 333.735934 -60.279534) (xy 333.73568 -60.27928)
			(xy 333.728605 -60.273677) (xy 333.711679 -60.267441) (xy 333.70266 -60.267088) (xy 333.635604 -60.267088)
			(xy 333.626588 -60.26745) (xy 333.609671 -60.273694) (xy 333.602584 -60.27928) (xy 333.60233 -60.279534)
			(xy 333.581397 -60.297175) (xy 333.535429 -60.326899) (xy 333.485683 -60.349745) (xy 333.433181 -60.365241)
			(xy 333.379003 -60.37307) (xy 333.324261 -60.37307) (xy 333.270083 -60.365241) (xy 333.217581 -60.349745)
			(xy 333.167835 -60.326899) (xy 333.121867 -60.297175) (xy 333.100934 -60.279534) (xy 333.10068 -60.27928)
			(xy 333.093605 -60.273677) (xy 333.076679 -60.267441) (xy 333.06766 -60.267088) (xy 333.000604 -60.267088)
			(xy 332.991588 -60.26745) (xy 332.974671 -60.273694) (xy 332.967584 -60.27928) (xy 332.967584 -60.279534)
			(xy 332.96733 -60.279534) (xy 332.946402 -60.297178) (xy 332.900427 -60.326888) (xy 332.850679 -60.349722)
			(xy 332.798178 -60.365212) (xy 332.744001 -60.37304) (xy 332.716632 -60.373514) (xy 332.689378 -60.373041)
			(xy 332.635425 -60.365288) (xy 332.583124 -60.349935) (xy 332.53354 -60.327294) (xy 332.487684 -60.297828)
			(xy 332.446488 -60.262135) (xy 332.410791 -60.220942) (xy 332.381321 -60.175088) (xy 332.358677 -60.125506)
			(xy 332.343319 -60.073207) (xy 332.335561 -60.019254) (xy 323.065463 -60.019254) (xy 323.081142 -60.06973)
			(xy 323.489066 -61.383164) (xy 323.491044 -61.388546) (xy 323.497069 -61.398298) (xy 323.501004 -61.402468)
			(xy 325.09714 -62.998604) (xy 325.449692 -63.35141) (xy 325.457086 -63.358267) (xy 325.475685 -63.366019)
			(xy 325.48576 -63.366396) (xy 332.190344 -63.366396) (xy 332.201358 -63.365847) (xy 332.221359 -63.356616)
			(xy 332.228952 -63.348616) (xy 332.286356 -63.28156) (xy 332.292452 -63.260478) (xy 332.290928 -63.25108)
			(xy 332.288569 -63.235119) (xy 332.286024 -63.202952) (xy 332.285848 -63.186818) (xy 332.285848 -63.18631)
			(xy 332.286352 -63.156608) (xy 332.294805 -63.09781) (xy 332.311541 -63.040813) (xy 332.336219 -62.986778)
			(xy 332.368336 -62.936806) (xy 332.407239 -62.891913) (xy 332.452134 -62.853014) (xy 332.50211 -62.820902)
			(xy 332.556146 -62.796229) (xy 332.613145 -62.779498) (xy 332.671944 -62.77105) (xy 332.701646 -62.770512)
			(xy 332.730109 -62.770979) (xy 332.786505 -62.778739) (xy 332.841318 -62.794107) (xy 332.893527 -62.816797)
			(xy 332.942159 -62.846387) (xy 332.964536 -62.863984) (xy 332.97114 -62.869318) (xy 332.996032 -62.878716)
			(xy 333.0001 -62.880019) (xy 333.008525 -62.881431) (xy 333.012796 -62.88151) (xy 333.025496 -62.88151)
			(xy 333.029769 -62.881447) (xy 333.038195 -62.880036) (xy 333.04226 -62.878716) (xy 333.067152 -62.869318)
			(xy 333.073756 -62.863984) (xy 333.096098 -62.846381) (xy 333.144681 -62.816799) (xy 333.19684 -62.794111)
			(xy 333.251604 -62.778742) (xy 333.307952 -62.770978) (xy 333.336392 -62.770512) (xy 333.336646 -62.770512)
			(xy 333.368155 -62.771095) (xy 333.430451 -62.780598) (xy 333.490605 -62.79938) (xy 333.547241 -62.827012)
			(xy 333.599067 -62.862862) (xy 333.622396 -62.88405) (xy 333.623412 -62.885066) (xy 333.637128 -62.897766)
			(xy 333.64416 -62.903318) (xy 333.660943 -62.909553) (xy 333.669894 -62.909958) (xy 333.684372 -62.909958)
			(xy 333.693262 -62.909196) (xy 333.705962 -62.90691) (xy 333.706216 -62.90691) (xy 333.71536 -62.903608)
			(xy 333.722472 -62.897512) (xy 333.743348 -62.880118) (xy 333.789098 -62.8508) (xy 333.838546 -62.828274)
			(xy 333.890691 -62.812996) (xy 333.944477 -62.805274) (xy 333.971646 -62.804802) (xy 333.99878 -62.805283)
			(xy 334.052498 -62.81298) (xy 334.104584 -62.828211) (xy 334.153986 -62.850669) (xy 334.199707 -62.879902)
			(xy 334.240824 -62.915318) (xy 334.276507 -62.956204) (xy 334.306036 -63.001733) (xy 334.328816 -63.050988)
			(xy 334.344386 -63.102973) (xy 334.352432 -63.156641) (xy 334.353154 -63.18377) (xy 334.353154 -63.187834)
			(xy 334.353014 -63.203077) (xy 334.350595 -63.233466) (xy 334.348328 -63.24854) (xy 334.34655 -63.259716)
			(xy 334.352392 -63.281052) (xy 334.409796 -63.348616) (xy 334.417369 -63.356638) (xy 334.437385 -63.365857)
			(xy 334.448404 -63.366396) (xy 335.534762 -63.366396) (xy 335.574133 -63.367082) (xy 335.65217 -63.377603)
			(xy 335.728121 -63.398386) (xy 335.764632 -63.413132) (xy 335.769372 -63.414998) (xy 335.779352 -63.417036)
			(xy 335.784444 -63.417196) (xy 339.698076 -63.417196) (xy 339.707728 -63.41618) (xy 339.714974 -63.414556)
			(xy 339.728148 -63.40772) (xy 339.733636 -63.402718) (xy 340.882478 -62.253876) (xy 340.885791 -62.250345)
			(xy 340.891156 -62.242288) (xy 340.893146 -62.237874) (xy 340.89721 -62.228476) (xy 340.89721 -60.446412)
			(xy 340.897631 -60.436341) (xy 340.905344 -60.417734) (xy 340.912196 -60.410344) (xy 343.495376 -57.827164)
			(xy 343.498688 -57.823633) (xy 343.504052 -57.815575) (xy 343.506044 -57.811162) (xy 343.510108 -57.801764)
			(xy 343.510108 -43.40987) (xy 343.510014 -43.404992) (xy 343.508227 -43.395402) (xy 343.506552 -43.39082)
			(xy 343.502742 -43.381676) (xy 340.703662 -40.582342) (xy 340.677821 -40.555679) (xy 340.632418 -40.496926)
			(xy 340.594862 -40.432872) (xy 340.565764 -40.36456) (xy 340.545595 -40.293099) (xy 340.539578 -40.25646)
			(xy 340.539578 -40.255444) (xy 340.535698 -40.231118) (xy 340.531499 -40.182032) (xy 340.531196 -40.1574)
			(xy 340.531196 -37.944044) (xy 340.529418 -37.938964) (xy 340.525608 -37.92982) (xy 340.518496 -37.922454)
			(xy 340.485222 -37.888672) (xy 340.48446 -37.88791) (xy 340.465664 -37.869622) (xy 340.458905 -37.864016)
			(xy 340.442665 -37.857373) (xy 340.433914 -37.856668) (xy 340.432644 -37.856668) (xy 340.397338 -37.854128)
			(xy 340.371862 -37.850746) (xy 340.32207 -37.83802) (xy 340.274436 -37.81873) (xy 340.22982 -37.793224)
			(xy 340.189029 -37.761962) (xy 340.1528 -37.725512) (xy 340.121789 -37.68453) (xy 340.108794 -37.662358)
			(xy 340.102531 -37.651074) (xy 340.091344 -37.627814) (xy 340.086442 -37.615876) (xy 340.08568 -37.613336)
			(xy 340.084156 -37.60978) (xy 340.072697 -37.577119) (xy 340.060432 -37.509005) (xy 340.059772 -37.474398)
			(xy 340.059772 -37.467286) (xy 340.060871 -37.438637) (xy 340.070594 -37.382135) (xy 340.088649 -37.32772)
			(xy 340.114631 -37.276614) (xy 340.147957 -37.229962) (xy 340.187878 -37.188814) (xy 340.233499 -37.154091)
			(xy 340.2584 -37.13988) (xy 340.258654 -37.13988) (xy 340.26666 -37.135029) (xy 340.278655 -37.120675)
			(xy 340.282022 -37.11194) (xy 340.283292 -37.107876) (xy 340.29396 -37.066474) (xy 340.298278 -37.04971)
			(xy 340.298278 -37.049202) (xy 340.304628 -37.025326) (xy 340.304374 -37.023802) (xy 340.207854 -36.879276)
			(xy 340.203275 -36.87299) (xy 340.191124 -36.863295) (xy 340.183978 -36.860226) (xy 340.150872 -36.846598)
			(xy 340.08794 -36.81246) (xy 340.029593 -36.770968) (xy 339.976688 -36.722731) (xy 339.929999 -36.668454)
			(xy 339.909658 -36.638992) (xy 339.634322 -36.227004) (xy 339.615396 -36.197812) (xy 339.583763 -36.135845)
			(xy 339.559622 -36.070593) (xy 339.54331 -36.002958) (xy 339.53505 -35.933876) (xy 339.5345 -35.89909)
			(xy 339.5345 -35.898074) (xy 339.534754 -35.888676) (xy 339.534754 -35.888422) (xy 339.534534 -35.880738)
			(xy 339.530144 -35.866015) (xy 339.526118 -35.859466) (xy 339.425788 -35.709098) (xy 339.419438 -35.701478)
			(xy 339.121242 -35.403282) (xy 339.107526 -35.395916) (xy 339.099906 -35.394646) (xy 339.064728 -35.387744)
			(xy 338.996246 -35.366538) (xy 338.93083 -35.337211) (xy 338.869437 -35.300193) (xy 338.812968 -35.256026)
			(xy 338.787232 -35.23107) (xy 338.436712 -34.88055) (xy 338.41175 -34.85485) (xy 338.367583 -34.798436)
			(xy 338.330563 -34.737094) (xy 338.301234 -34.671725) (xy 338.280026 -34.603288) (xy 338.273136 -34.56813)
			(xy 338.259166 -34.541206) (xy 338.252816 -34.534856) (xy 338.21595 -34.52859) (xy 338.144069 -34.507966)
			(xy 338.075361 -34.478448) (xy 338.01092 -34.440506) (xy 337.951775 -34.394745) (xy 337.924902 -34.36874)
			(xy 337.574382 -34.01822) (xy 337.548208 -33.991214) (xy 337.502208 -33.931715) (xy 337.464132 -33.866858)
			(xy 337.434595 -33.797694) (xy 337.42376 -33.76168) (xy 337.420238 -33.75111) (xy 337.405746 -33.734224)
			(xy 337.39582 -33.729168) (xy 337.369984 -33.717018) (xy 337.320588 -33.688381) (xy 337.274231 -33.65505)
			(xy 337.252564 -33.636458) (xy 337.24961 -33.634003) (xy 337.243106 -33.62992) (xy 337.23961 -33.62833)
			(xy 337.206925 -33.613139) (xy 337.14518 -33.575953) (xy 337.088415 -33.531534) (xy 337.062572 -33.50641)
			(xy 336.712052 -33.15589) (xy 336.687228 -33.130338) (xy 336.643243 -33.074296) (xy 336.606313 -33.013374)
			(xy 336.591148 -32.981138) (xy 336.579464 -32.964882) (xy 336.560414 -32.946086) (xy 336.559906 -32.945578)
			(xy 336.557366 -32.943038) (xy 336.382614 -32.768286) (xy 336.374232 -32.764476) (xy 336.342143 -32.749363)
			(xy 336.281498 -32.71257) (xy 336.225691 -32.668788) (xy 336.200242 -32.64408) (xy 335.849722 -32.29356)
			(xy 335.825016 -32.26811) (xy 335.781232 -32.212304) (xy 335.74445 -32.151654) (xy 335.729326 -32.11957)
			(xy 335.725516 -32.111188) (xy 335.643474 -32.029146) (xy 335.622312 -32.007375) (xy 335.584134 -31.960162)
			(xy 335.567274 -31.934912) (xy 335.562655 -31.928373) (xy 335.550234 -31.918289) (xy 335.54289 -31.9151)
			(xy 335.514307 -31.90363) (xy 335.459473 -31.875582) (xy 335.407847 -31.841993) (xy 335.359988 -31.803225)
			(xy 335.337912 -31.78175) (xy 334.987392 -31.43123) (xy 334.963905 -31.407059) (xy 334.92198 -31.354287)
			(xy 334.886321 -31.297094) (xy 334.85739 -31.23622) (xy 334.835562 -31.172454) (xy 334.82788 -31.139638)
			(xy 334.823816 -31.120842) (xy 334.818736 -31.115762) (xy 334.800194 -31.104332) (xy 334.795114 -31.102554)
			(xy 334.75168 -31.084774) (xy 334.75041 -31.084266) (xy 334.74914 -31.083758) (xy 334.74533 -31.08198)
			(xy 334.71104 -31.064454) (xy 334.702658 -31.060644) (xy 334.670888 -31.049313) (xy 334.609928 -31.020436)
			(xy 334.552648 -30.984813) (xy 334.499791 -30.942907) (xy 334.475582 -30.91942) (xy 334.125062 -30.5689)
			(xy 334.098533 -30.541491) (xy 334.052016 -30.481035) (xy 334.013648 -30.415106) (xy 333.998316 -30.380178)
			(xy 333.995467 -30.374073) (xy 333.987096 -30.363522) (xy 333.981806 -30.35935) (xy 333.96357 -30.34538)
			(xy 333.929114 -30.314989) (xy 333.912972 -30.298644) (xy 333.912464 -30.298136) (xy 333.795624 -30.181296)
			(xy 333.787242 -30.177486) (xy 333.755152 -30.162373) (xy 333.694507 -30.125582) (xy 333.638698 -30.081801)
			(xy 333.613252 -30.05709) (xy 333.262732 -29.70657) (xy 333.238025 -29.68112) (xy 333.19424 -29.625315)
			(xy 333.157456 -29.564666) (xy 333.142336 -29.53258) (xy 333.138526 -29.524198) (xy 332.998826 -29.384498)
			(xy 332.9871 -29.372614) (xy 332.964862 -29.347706) (xy 332.954376 -29.334714) (xy 332.934818 -29.319728)
			(xy 332.900803 -29.30443) (xy 332.836589 -29.266487) (xy 332.777668 -29.220755) (xy 332.750922 -29.19476)
			(xy 332.400402 -28.84424) (xy 332.37904 -28.82233) (xy 332.34047 -28.774819) (xy 332.307011 -28.723579)
			(xy 332.279022 -28.669159) (xy 332.26756 -28.640786) (xy 332.262734 -28.631388) (xy 332.242414 -28.597606)
			(xy 332.241652 -28.596336) (xy 332.240382 -28.59405) (xy 332.225904 -28.58262) (xy 332.141068 -28.556458)
			(xy 332.122272 -28.557728) (xy 332.113636 -28.562046) (xy 332.08378 -28.575796) (xy 332.02168 -28.59735)
			(xy 331.957573 -28.611883) (xy 331.892249 -28.619216) (xy 331.859382 -28.619704) (xy 331.363066 -28.619704)
			(xy 331.327275 -28.619163) (xy 331.256221 -28.610484) (xy 331.186734 -28.593294) (xy 331.119829 -28.567844)
			(xy 331.056484 -28.534505) (xy 331.02677 -28.514548) (xy 330.997814 -28.505404) (xy 330.733146 -28.505404)
			(xy 330.701421 -28.504984) (xy 330.638337 -28.498185) (xy 330.576344 -28.48467) (xy 330.516154 -28.464595)
			(xy 330.458459 -28.438191) (xy 330.403923 -28.405761) (xy 330.378308 -28.38704) (xy 330.356718 -28.377642)
			(xy 330.354432 -28.377134) (xy 330.330302 -28.383484) (xy 330.324714 -28.386532) (xy 330.297039 -28.401198)
			(xy 330.238065 -28.422279) (xy 330.176437 -28.433432) (xy 330.145136 -28.434538) (xy 330.138278 -28.434538)
			(xy 330.124003 -28.43445) (xy 330.095525 -28.432413) (xy 330.081382 -28.430474) (xy 330.078588 -28.429966)
			(xy 330.053696 -28.429204) (xy 330.044503 -28.429633) (xy 330.027324 -28.436195) (xy 330.013569 -28.4484)
			(xy 330.008992 -28.456382) (xy 330.004674 -28.465272) (xy 330.002271 -28.469941) (xy 329.995871 -28.478263)
			(xy 329.991974 -28.481782) (xy 329.980544 -28.491688) (xy 329.973223 -28.498492) (xy 329.964194 -28.516306)
			(xy 329.963018 -28.526232) (xy 329.962764 -28.530296) (xy 329.962764 -29.114242) (xy 329.962274 -29.14421)
			(xy 329.954451 -29.203632) (xy 329.938938 -29.261525) (xy 329.916002 -29.316898) (xy 329.886035 -29.368804)
			(xy 329.849548 -29.416354) (xy 329.807168 -29.458734) (xy 329.759618 -29.495221) (xy 329.707712 -29.525188)
			(xy 329.652339 -29.548124) (xy 329.594446 -29.563637) (xy 329.535024 -29.57146) (xy 329.475088 -29.57146)
			(xy 329.415666 -29.563637) (xy 329.357773 -29.548124) (xy 329.3024 -29.525188) (xy 329.250494 -29.495221)
			(xy 329.202944 -29.458734) (xy 329.160564 -29.416354) (xy 329.124077 -29.368804) (xy 329.09411 -29.316898)
			(xy 329.071174 -29.261525) (xy 329.055661 -29.203632) (xy 329.047838 -29.14421) (xy 329.047348 -29.114242)
			(xy 329.047348 -28.250642) (xy 329.047602 -28.227236) (xy 329.05231 -28.180661) (xy 329.056746 -28.157678)
			(xy 329.060035 -28.142392) (xy 329.068426 -28.112267) (xy 329.07351 -28.09748) (xy 329.088496 -28.06065)
			(xy 329.095187 -28.046167) (xy 329.110313 -28.018074) (xy 329.118722 -28.004516) (xy 329.122354 -27.998316)
			(xy 329.126346 -27.98452) (xy 329.126596 -27.977338) (xy 329.126596 -27.967432) (xy 329.11542 -27.92222)
			(xy 329.088242 -27.888438) (xy 329.058451 -27.873626) (xy 329.002087 -27.838273) (xy 328.950042 -27.796824)
			(xy 328.92619 -27.77363) (xy 328.817478 -27.664918) (xy 328.813414 -27.666188) (xy 328.806302 -27.669236)
			(xy 328.790808 -27.677872) (xy 328.7903 -27.67838) (xy 328.756868 -27.697078) (xy 328.686149 -27.726514)
			(xy 328.612183 -27.746435) (xy 328.536246 -27.756499) (xy 328.497946 -27.75712) (xy 328.05497 -27.75712)
			(xy 328.021983 -27.756665) (xy 327.956431 -27.749211) (xy 327.892142 -27.734391) (xy 327.829943 -27.712395)
			(xy 327.77063 -27.683506) (xy 327.74255 -27.666188) (xy 327.738994 -27.663902) (xy 327.730866 -27.660346)
			(xy 327.724046 -27.657844) (xy 327.709595 -27.656426) (xy 327.702418 -27.657552) (xy 327.599294 -27.76093)
			(xy 327.57553 -27.784031) (xy 327.523709 -27.825349) (xy 327.467591 -27.86061) (xy 327.40788 -27.88937)
			(xy 327.345325 -27.911268) (xy 327.280714 -27.92603) (xy 327.214856 -27.93347) (xy 327.181718 -27.933904)
			(xy 327.18121 -27.933904) (xy 327.145489 -27.933365) (xy 327.074567 -27.924755) (xy 327.0052 -27.90766)
			(xy 326.9384 -27.882328) (xy 326.875139 -27.849129) (xy 326.816342 -27.808548) (xy 326.762864 -27.761175)
			(xy 326.715487 -27.707702) (xy 326.6749 -27.648909) (xy 326.641695 -27.585651) (xy 326.616357 -27.518853)
			(xy 326.599255 -27.449488) (xy 326.590638 -27.378567) (xy 326.590152 -27.342846) (xy 326.590152 -27.342338)
			(xy 326.590646 -27.308703) (xy 326.598318 -27.24187) (xy 326.613523 -27.17634) (xy 326.636064 -27.112957)
			(xy 326.665649 -27.052541) (xy 326.701898 -26.995871) (xy 326.72274 -26.969466) (xy 326.723248 -26.968958)
			(xy 326.723248 -26.870152) (xy 326.722924 -26.861873) (xy 326.717605 -26.846193) (xy 326.712834 -26.839418)
			(xy 326.693486 -26.813562) (xy 326.659917 -26.758392) (xy 326.632556 -26.699893) (xy 326.61173 -26.638762)
			(xy 326.597687 -26.575726) (xy 326.590593 -26.511536) (xy 326.590152 -26.479246) (xy 326.590597 -26.446077)
			(xy 326.59802 -26.380154) (xy 326.612778 -26.315478) (xy 326.634684 -26.25286) (xy 326.663465 -26.19309)
			(xy 326.698757 -26.136918) (xy 326.740116 -26.08505) (xy 326.787023 -26.03814) (xy 326.838888 -25.996777)
			(xy 326.895058 -25.961482) (xy 326.954827 -25.932698) (xy 327.017443 -25.910788) (xy 327.082119 -25.896026)
			(xy 327.148041 -25.888599) (xy 327.18121 -25.888188) (xy 327.214371 -25.888669) (xy 327.280273 -25.896127)
			(xy 327.344927 -25.910912) (xy 327.40752 -25.932841) (xy 327.467265 -25.961637) (xy 327.523412 -25.996939)
			(xy 327.575256 -26.038303) (xy 327.59904 -26.061416) (xy 327.70191 -26.164286) (xy 327.709309 -26.171132)
			(xy 327.727907 -26.178865) (xy 327.737978 -26.179272) (xy 329.157076 -26.179272) (xy 329.188948 -26.179645)
			(xy 329.252331 -26.186394) (xy 329.283568 -26.192734) (xy 329.301348 -26.196798) (xy 329.308206 -26.19375)
			(xy 329.323192 -26.185368) (xy 329.323954 -26.18486) (xy 329.328587 -26.182087) (xy 329.336648 -26.174905)
			(xy 329.339956 -26.170636) (xy 329.345036 -26.163016) (xy 329.359968 -26.139355) (xy 329.395665 -26.096273)
			(xy 329.437271 -26.058866) (xy 329.483892 -26.027934) (xy 329.53453 -26.004141) (xy 329.588099 -25.987996)
			(xy 329.643451 -25.979845) (xy 329.671426 -25.979374) (xy 329.698665 -25.979861) (xy 329.752588 -25.987614)
			(xy 329.804861 -26.002958) (xy 329.854419 -26.025582) (xy 329.900255 -26.055025) (xy 329.941437 -26.090689)
			(xy 329.977127 -26.131848) (xy 330.0066 -26.177665) (xy 330.029256 -26.227208) (xy 330.044634 -26.279471)
			(xy 330.05045 -26.319734) (xy 335.041746 -26.319734) (xy 335.045817 -26.264112) (xy 335.057943 -26.209675)
			(xy 335.077866 -26.157584) (xy 335.105162 -26.108949) (xy 335.139248 -26.064806) (xy 335.179397 -26.026097)
			(xy 335.224755 -25.993646) (xy 335.274355 -25.968145) (xy 335.327139 -25.950138) (xy 335.381982 -25.940008)
			(xy 335.437716 -25.937971) (xy 335.493153 -25.944071) (xy 335.54711 -25.958177) (xy 335.598439 -25.979989)
			(xy 335.646045 -26.009043) (xy 335.67571 -26.03373) (xy 353.567998 -26.03373) (xy 353.572069 -25.978108)
			(xy 353.584195 -25.923671) (xy 353.604118 -25.87158) (xy 353.631414 -25.822945) (xy 353.6655 -25.778802)
			(xy 353.705649 -25.740093) (xy 353.751007 -25.707642) (xy 353.800607 -25.682141) (xy 353.853391 -25.664134)
			(xy 353.908234 -25.654004) (xy 353.963968 -25.651967) (xy 354.019405 -25.658067) (xy 354.073362 -25.672173)
			(xy 354.124691 -25.693985) (xy 354.172297 -25.723039) (xy 354.215165 -25.758714) (xy 354.252382 -25.800251)
			(xy 354.283155 -25.846764) (xy 354.306827 -25.897261) (xy 354.322895 -25.950668) (xy 354.331015 -26.005844)
			(xy 354.331524 -26.03373) (xy 354.331015 -26.061616) (xy 354.322895 -26.116792) (xy 354.306827 -26.170199)
			(xy 354.283155 -26.220696) (xy 354.252921 -26.266394) (xy 356.820724 -26.266394) (xy 356.82121 -26.239143)
			(xy 356.828966 -26.185195) (xy 356.844321 -26.1329) (xy 356.866963 -26.083323) (xy 356.896429 -26.037473)
			(xy 356.93212 -25.996282) (xy 356.973311 -25.960591) (xy 357.019161 -25.931125) (xy 357.068738 -25.908483)
			(xy 357.121033 -25.893128) (xy 357.174981 -25.885372) (xy 357.229483 -25.885372) (xy 357.283431 -25.893128)
			(xy 357.335726 -25.908483) (xy 357.385303 -25.931125) (xy 357.431153 -25.960591) (xy 357.472344 -25.996282)
			(xy 357.508035 -26.037473) (xy 357.537501 -26.083323) (xy 357.560143 -26.1329) (xy 357.575498 -26.185195)
			(xy 357.583254 -26.239143) (xy 357.58374 -26.266394) (xy 357.583172 -26.295881) (xy 357.574079 -26.35415)
			(xy 357.556122 -26.410324) (xy 357.529732 -26.463064) (xy 357.495537 -26.511113) (xy 357.454352 -26.553324)
			(xy 357.431086 -26.571448) (xy 357.419931 -26.580308) (xy 357.402746 -26.603018) (xy 357.392499 -26.62959)
			(xy 357.389986 -26.657958) (xy 357.395402 -26.685917) (xy 357.408327 -26.711295) (xy 357.427755 -26.732118)
			(xy 357.439722 -26.73985) (xy 357.463464 -26.754747) (xy 357.506698 -26.790415) (xy 357.544248 -26.832024)
			(xy 357.575307 -26.878679) (xy 357.599206 -26.929377) (xy 357.61543 -26.983025) (xy 357.623631 -27.03847)
			(xy 357.624126 -27.066494) (xy 357.62364 -27.093745) (xy 357.615884 -27.147693) (xy 357.600529 -27.199988)
			(xy 357.577887 -27.249565) (xy 357.548421 -27.295415) (xy 357.51273 -27.336606) (xy 357.471539 -27.372297)
			(xy 357.425689 -27.401763) (xy 357.376112 -27.424405) (xy 357.323817 -27.43976) (xy 357.269869 -27.447516)
			(xy 357.215367 -27.447516) (xy 357.161419 -27.43976) (xy 357.109124 -27.424405) (xy 357.059547 -27.401763)
			(xy 357.013697 -27.372297) (xy 356.972506 -27.336606) (xy 356.936815 -27.295415) (xy 356.907349 -27.249565)
			(xy 356.884707 -27.199988) (xy 356.869352 -27.147693) (xy 356.861596 -27.093745) (xy 356.86111 -27.066494)
			(xy 356.861649 -27.037006) (xy 356.870746 -26.978734) (xy 356.888707 -26.922559) (xy 356.915102 -26.869818)
			(xy 356.949303 -26.821771) (xy 356.990495 -26.779562) (xy 357.013764 -26.76144) (xy 357.024821 -26.75247)
			(xy 357.041996 -26.729784) (xy 357.052244 -26.703238) (xy 357.054767 -26.674896) (xy 357.049371 -26.646957)
			(xy 357.036474 -26.621593) (xy 357.017078 -26.600773) (xy 357.005128 -26.593038) (xy 356.981392 -26.578131)
			(xy 356.938156 -26.542467) (xy 356.900603 -26.50086) (xy 356.869542 -26.454207) (xy 356.845643 -26.40351)
			(xy 356.829418 -26.349862) (xy 356.821218 -26.294418) (xy 356.820724 -26.266394) (xy 354.252921 -26.266394)
			(xy 354.252382 -26.267209) (xy 354.215165 -26.308746) (xy 354.172297 -26.344421) (xy 354.124691 -26.373475)
			(xy 354.073362 -26.395287) (xy 354.019405 -26.409393) (xy 353.963968 -26.415493) (xy 353.908234 -26.413456)
			(xy 353.853391 -26.403326) (xy 353.800607 -26.385319) (xy 353.751007 -26.359818) (xy 353.705649 -26.327367)
			(xy 353.6655 -26.288658) (xy 353.631414 -26.244515) (xy 353.604118 -26.19588) (xy 353.584195 -26.143789)
			(xy 353.572069 -26.089352) (xy 353.567998 -26.03373) (xy 335.67571 -26.03373) (xy 335.688913 -26.044718)
			(xy 335.72613 -26.086255) (xy 335.756903 -26.132768) (xy 335.780575 -26.183265) (xy 335.796643 -26.236672)
			(xy 335.804763 -26.291848) (xy 335.805272 -26.319734) (xy 335.804763 -26.34762) (xy 335.796643 -26.402796)
			(xy 335.780575 -26.456203) (xy 335.756903 -26.5067) (xy 335.72613 -26.553213) (xy 335.688913 -26.59475)
			(xy 335.646045 -26.630425) (xy 335.598439 -26.659479) (xy 335.54711 -26.681291) (xy 335.493153 -26.695397)
			(xy 335.437716 -26.701497) (xy 335.381982 -26.69946) (xy 335.327139 -26.68933) (xy 335.274355 -26.671323)
			(xy 335.224755 -26.645822) (xy 335.179397 -26.613371) (xy 335.139248 -26.574662) (xy 335.105162 -26.530519)
			(xy 335.077866 -26.481884) (xy 335.057943 -26.429793) (xy 335.045817 -26.375356) (xy 335.041746 -26.319734)
			(xy 330.05045 -26.319734) (xy 330.052422 -26.333389) (xy 330.052934 -26.360628) (xy 330.052934 -26.360882)
			(xy 330.051918 -26.388314) (xy 330.051918 -26.390854) (xy 330.051156 -26.401522) (xy 330.054458 -26.41092)
			(xy 330.056314 -26.415747) (xy 330.061698 -26.424574) (xy 330.065126 -26.428446) (xy 330.071222 -26.43505)
			(xy 330.075286 -26.439622) (xy 330.100432 -26.4668) (xy 330.107904 -26.474132) (xy 330.12706 -26.482518)
			(xy 330.137516 -26.483056) (xy 330.29144 -26.483056) (xy 330.324594 -26.483522) (xy 330.390486 -26.490945)
			(xy 330.455134 -26.505695) (xy 330.517725 -26.527585) (xy 330.577475 -26.55634) (xy 330.633631 -26.591601)
			(xy 330.68549 -26.632923) (xy 330.70927 -26.65603) (xy 330.93152 -26.87828) (xy 330.937801 -26.88415)
			(xy 330.953253 -26.891661) (xy 330.970322 -26.893614) (xy 330.978764 -26.891996) (xy 330.998576 -26.887424)
			(xy 330.999084 -26.887424) (xy 331.037946 -26.87828) (xy 331.046846 -26.875464) (xy 331.061841 -26.864366)
			(xy 331.067156 -26.85669) (xy 331.071982 -26.847546) (xy 331.072236 -26.84653) (xy 331.07249 -26.846022)
			(xy 331.07249 -26.845768) (xy 331.081534 -26.82117) (xy 331.105411 -26.774515) (xy 331.135443 -26.731564)
			(xy 331.171068 -26.693124) (xy 331.211615 -26.659918) (xy 331.256323 -26.632569) (xy 331.30435 -26.611591)
			(xy 331.354796 -26.597379) (xy 331.406711 -26.5902) (xy 331.432916 -26.589736) (xy 331.459442 -26.590193)
			(xy 331.511983 -26.597543) (xy 331.563 -26.612099) (xy 331.611509 -26.63358) (xy 331.656575 -26.661573)
			(xy 331.69733 -26.695538) (xy 331.732988 -26.73482) (xy 331.762862 -26.778661) (xy 331.786376 -26.826218)
			(xy 331.803077 -26.876574) (xy 331.812643 -26.928757) (xy 331.81417 -26.955242) (xy 331.81417 -26.955496)
			(xy 331.814678 -26.965148) (xy 331.822552 -26.983182) (xy 331.829664 -26.99004) (xy 331.863192 -27.022552)
			(xy 331.880464 -27.039316) (xy 331.883258 -27.041856) (xy 332.585568 -27.041856) (xy 332.622257 -27.04241)
			(xy 332.695071 -27.051497) (xy 332.766198 -27.069535) (xy 332.834542 -27.096247) (xy 332.89905 -27.13122)
			(xy 332.92923 -27.152092) (xy 332.930246 -27.153108) (xy 332.953222 -27.168988) (xy 332.996347 -27.204484)
			(xy 333.016352 -27.223974) (xy 333.461614 -27.668982) (xy 333.977234 -28.184602) (xy 333.983577 -28.190493)
			(xy 333.999158 -28.198013) (xy 334.007714 -28.199334) (xy 334.010508 -28.199588) (xy 334.034638 -28.199588)
			(xy 334.047846 -28.19781) (xy 334.051656 -28.19654) (xy 334.077564 -28.186634) (xy 334.084168 -28.180792)
			(xy 334.105045 -28.163331) (xy 334.150816 -28.133887) (xy 334.20031 -28.111253) (xy 334.25252 -28.095888)
			(xy 334.306384 -28.088104) (xy 334.333596 -28.087574) (xy 334.499204 -28.087574) (xy 334.50854 -28.087992)
			(xy 334.525973 -28.094681) (xy 334.539855 -28.107169) (xy 334.548343 -28.123801) (xy 334.54975 -28.13304)
			(xy 334.55036 -28.139136) (xy 350.698052 -28.139136) (xy 350.702123 -28.083514) (xy 350.714249 -28.029077)
			(xy 350.734172 -27.976986) (xy 350.761468 -27.928351) (xy 350.795554 -27.884208) (xy 350.835703 -27.845499)
			(xy 350.881061 -27.813048) (xy 350.930661 -27.787547) (xy 350.983445 -27.76954) (xy 351.038288 -27.75941)
			(xy 351.094022 -27.757373) (xy 351.149459 -27.763473) (xy 351.203416 -27.777579) (xy 351.254745 -27.799391)
			(xy 351.302351 -27.828445) (xy 351.345219 -27.86412) (xy 351.382436 -27.905657) (xy 351.413209 -27.95217)
			(xy 351.436881 -28.002667) (xy 351.452949 -28.056074) (xy 351.461069 -28.11125) (xy 351.461578 -28.139136)
			(xy 351.968052 -28.139136) (xy 351.972123 -28.083514) (xy 351.984249 -28.029077) (xy 352.004172 -27.976986)
			(xy 352.031468 -27.928351) (xy 352.065554 -27.884208) (xy 352.105703 -27.845499) (xy 352.151061 -27.813048)
			(xy 352.200661 -27.787547) (xy 352.253445 -27.76954) (xy 352.308288 -27.75941) (xy 352.364022 -27.757373)
			(xy 352.419459 -27.763473) (xy 352.473416 -27.777579) (xy 352.524745 -27.799391) (xy 352.572351 -27.828445)
			(xy 352.615219 -27.86412) (xy 352.652436 -27.905657) (xy 352.683209 -27.95217) (xy 352.706881 -28.002667)
			(xy 352.722949 -28.056074) (xy 352.731069 -28.11125) (xy 352.731578 -28.139136) (xy 352.731069 -28.167022)
			(xy 352.722949 -28.222198) (xy 352.706881 -28.275605) (xy 352.683209 -28.326102) (xy 352.652436 -28.372615)
			(xy 352.615219 -28.414152) (xy 352.572351 -28.449827) (xy 352.524745 -28.478881) (xy 352.473416 -28.500693)
			(xy 352.419459 -28.514799) (xy 352.364022 -28.520899) (xy 352.308288 -28.518862) (xy 352.253445 -28.508732)
			(xy 352.200661 -28.490725) (xy 352.151061 -28.465224) (xy 352.105703 -28.432773) (xy 352.065554 -28.394064)
			(xy 352.031468 -28.349921) (xy 352.004172 -28.301286) (xy 351.984249 -28.249195) (xy 351.972123 -28.194758)
			(xy 351.968052 -28.139136) (xy 351.461578 -28.139136) (xy 351.461069 -28.167022) (xy 351.452949 -28.222198)
			(xy 351.436881 -28.275605) (xy 351.413209 -28.326102) (xy 351.382436 -28.372615) (xy 351.345219 -28.414152)
			(xy 351.302351 -28.449827) (xy 351.254745 -28.478881) (xy 351.203416 -28.500693) (xy 351.149459 -28.514799)
			(xy 351.094022 -28.520899) (xy 351.038288 -28.518862) (xy 350.983445 -28.508732) (xy 350.930661 -28.490725)
			(xy 350.881061 -28.465224) (xy 350.835703 -28.432773) (xy 350.795554 -28.394064) (xy 350.761468 -28.349921)
			(xy 350.734172 -28.301286) (xy 350.714249 -28.249195) (xy 350.702123 -28.194758) (xy 350.698052 -28.139136)
			(xy 334.55036 -28.139136) (xy 334.550766 -28.1432) (xy 334.555592 -28.15209) (xy 334.558064 -28.156491)
			(xy 334.564464 -28.164294) (xy 334.568292 -28.167584) (xy 334.571848 -28.170378) (xy 334.593898 -28.188544)
			(xy 334.632827 -28.230356) (xy 334.665079 -28.277511) (xy 334.689931 -28.328952) (xy 334.706826 -28.383525)
			(xy 334.715387 -28.44001) (xy 334.715866 -28.468574) (xy 334.715866 -28.476702) (xy 334.714789 -28.504974)
			(xy 334.705324 -28.560753) (xy 334.687728 -28.614523) (xy 334.662386 -28.665107) (xy 334.629854 -28.711394)
			(xy 334.61071 -28.732226) (xy 334.603852 -28.739338) (xy 334.594962 -28.76169) (xy 334.591609 -28.773288)
			(xy 334.594926 -28.797164) (xy 334.601312 -28.80741) (xy 334.603344 -28.810458) (xy 334.606646 -28.814014)
			(xy 334.915002 -29.12237) (xy 356.907084 -29.12237) (xy 356.907084 -28.25877) (xy 356.907574 -28.228802)
			(xy 356.915397 -28.16938) (xy 356.93091 -28.111487) (xy 356.953846 -28.056114) (xy 356.983813 -28.004208)
			(xy 357.0203 -27.956658) (xy 357.06268 -27.914278) (xy 357.11023 -27.877791) (xy 357.162136 -27.847824)
			(xy 357.217509 -27.824888) (xy 357.275402 -27.809375) (xy 357.334824 -27.801552) (xy 357.39476 -27.801552)
			(xy 357.454182 -27.809375) (xy 357.512075 -27.824888) (xy 357.567448 -27.847824) (xy 357.619354 -27.877791)
			(xy 357.666904 -27.914278) (xy 357.709284 -27.956658) (xy 357.745771 -28.004208) (xy 357.775738 -28.056114)
			(xy 357.798674 -28.111487) (xy 357.814187 -28.16938) (xy 357.82201 -28.228802) (xy 357.8225 -28.25877)
			(xy 357.8225 -29.12237) (xy 357.82201 -29.152338) (xy 357.814187 -29.21176) (xy 357.798674 -29.269653)
			(xy 357.775738 -29.325026) (xy 357.745771 -29.376932) (xy 357.709284 -29.424482) (xy 357.666904 -29.466862)
			(xy 357.619354 -29.503349) (xy 357.567448 -29.533316) (xy 357.512075 -29.556252) (xy 357.454182 -29.571765)
			(xy 357.39476 -29.579588) (xy 357.334824 -29.579588) (xy 357.275402 -29.571765) (xy 357.217509 -29.556252)
			(xy 357.162136 -29.533316) (xy 357.11023 -29.503349) (xy 357.06268 -29.466862) (xy 357.0203 -29.424482)
			(xy 356.983813 -29.376932) (xy 356.953846 -29.325026) (xy 356.93091 -29.269653) (xy 356.915397 -29.21176)
			(xy 356.907574 -29.152338) (xy 356.907084 -29.12237) (xy 334.915002 -29.12237) (xy 335.262728 -29.470096)
			(xy 335.271285 -29.477868) (xy 335.29311 -29.485414) (xy 335.304638 -29.484574) (xy 335.31429 -29.482542)
			(xy 335.3308 -29.477208) (xy 335.33715 -29.472636) (xy 335.361419 -29.45617) (xy 335.413944 -29.430087)
			(xy 335.46984 -29.41234) (xy 335.527792 -29.403346) (xy 335.557114 -29.402786) (xy 335.557368 -29.402786)
			(xy 335.585106 -29.403288) (xy 335.639997 -29.411329) (xy 335.693145 -29.42723) (xy 335.743432 -29.450658)
			(xy 335.789798 -29.481118) (xy 335.831266 -29.51797) (xy 335.866962 -29.560436) (xy 335.896136 -29.607622)
			(xy 335.918171 -29.658534) (xy 335.932605 -29.7121) (xy 335.936336 -29.73959) (xy 335.93786 -29.753814)
			(xy 335.939449 -29.779043) (xy 335.936765 -29.829524) (xy 335.927451 -29.879211) (xy 335.911671 -29.927237)
			(xy 335.889701 -29.972765) (xy 335.876138 -29.994098) (xy 335.87055 -30.00248) (xy 335.862168 -30.014926)
			(xy 335.861152 -30.016704) (xy 335.86039 -30.018482) (xy 335.857214 -30.025393) (xy 335.854622 -30.040372)
			(xy 335.85531 -30.047946) (xy 335.85658 -30.05582) (xy 335.86293 -30.069536) (xy 335.867756 -30.07487)
			(xy 335.868772 -30.075886) (xy 335.869534 -30.076648) (xy 335.871058 -30.078426) (xy 336.169508 -30.376876)
			(xy 349.18904 -30.376876) (xy 349.189598 -30.34796) (xy 349.198317 -30.29079) (xy 349.215566 -30.235592)
			(xy 349.24095 -30.18363) (xy 349.273887 -30.136095) (xy 349.313623 -30.094077) (xy 349.336106 -30.075886)
			(xy 349.344911 -30.068276) (xy 349.355095 -30.047378) (xy 349.355664 -30.035754) (xy 349.355664 -29.955998)
			(xy 349.355124 -29.944366) (xy 349.344937 -29.923456) (xy 349.336106 -29.915866) (xy 349.313607 -29.897693)
			(xy 349.273873 -29.855669) (xy 349.240936 -29.808131) (xy 349.21555 -29.756166) (xy 349.198297 -29.700965)
			(xy 349.189572 -29.643793) (xy 349.18904 -29.614876) (xy 349.189526 -29.587625) (xy 349.197282 -29.533677)
			(xy 349.212637 -29.481382) (xy 349.235279 -29.431805) (xy 349.264745 -29.385955) (xy 349.300436 -29.344764)
			(xy 349.341627 -29.309073) (xy 349.387477 -29.279607) (xy 349.437054 -29.256965) (xy 349.489349 -29.24161)
			(xy 349.543297 -29.233854) (xy 349.597799 -29.233854) (xy 349.651747 -29.24161) (xy 349.704042 -29.256965)
			(xy 349.753619 -29.279607) (xy 349.799469 -29.309073) (xy 349.84066 -29.344764) (xy 349.876351 -29.385955)
			(xy 349.905817 -29.431805) (xy 349.928459 -29.481382) (xy 349.943814 -29.533677) (xy 349.95157 -29.587625)
			(xy 349.952056 -29.614876) (xy 349.951537 -29.643793) (xy 349.942811 -29.700965) (xy 349.925554 -29.756165)
			(xy 349.900162 -29.808127) (xy 349.867218 -29.85566) (xy 349.827476 -29.897677) (xy 349.80499 -29.915866)
			(xy 349.796207 -29.923496) (xy 349.78601 -29.944379) (xy 349.785432 -29.955998) (xy 349.785432 -30.035754)
			(xy 349.785943 -30.04739) (xy 349.796151 -30.068299) (xy 349.80499 -30.075886) (xy 349.827465 -30.094087)
			(xy 349.867201 -30.136105) (xy 349.900141 -30.183637) (xy 349.925531 -30.235597) (xy 349.942789 -30.290792)
			(xy 349.95152 -30.347961) (xy 349.952056 -30.376876) (xy 352.229166 -30.376876) (xy 352.229714 -30.34796)
			(xy 352.238433 -30.290789) (xy 352.255684 -30.23559) (xy 352.28107 -30.183627) (xy 352.314009 -30.136093)
			(xy 352.353748 -30.094076) (xy 352.376232 -30.075886) (xy 352.385041 -30.068281) (xy 352.395222 -30.047378)
			(xy 352.39579 -30.035754) (xy 352.39579 -29.955998) (xy 352.395241 -29.944367) (xy 352.38506 -29.923457)
			(xy 352.376232 -29.915866) (xy 352.353739 -29.897686) (xy 352.314003 -29.855665) (xy 352.281064 -29.808128)
			(xy 352.255677 -29.756164) (xy 352.238423 -29.700964) (xy 352.229698 -29.643793) (xy 352.229166 -29.614876)
			(xy 352.229652 -29.587625) (xy 352.237408 -29.533677) (xy 352.252763 -29.481382) (xy 352.275405 -29.431805)
			(xy 352.304871 -29.385955) (xy 352.340562 -29.344764) (xy 352.381753 -29.309073) (xy 352.427603 -29.279607)
			(xy 352.47718 -29.256965) (xy 352.529475 -29.24161) (xy 352.583423 -29.233854) (xy 352.637925 -29.233854)
			(xy 352.691873 -29.24161) (xy 352.744168 -29.256965) (xy 352.793745 -29.279607) (xy 352.839595 -29.309073)
			(xy 352.880786 -29.344764) (xy 352.916477 -29.385955) (xy 352.945943 -29.431805) (xy 352.968585 -29.481382)
			(xy 352.98394 -29.533677) (xy 352.991696 -29.587625) (xy 352.992182 -29.614876) (xy 352.991653 -29.643793)
			(xy 352.982927 -29.700964) (xy 352.965672 -29.756163) (xy 352.940282 -29.808124) (xy 352.90734 -29.855659)
			(xy 352.867601 -29.897676) (xy 352.845116 -29.915866) (xy 352.83632 -29.923483) (xy 352.826134 -29.944377)
			(xy 352.825558 -29.955998) (xy 352.825558 -30.035754) (xy 352.82606 -30.047391) (xy 352.836273 -30.068302)
			(xy 352.845116 -30.075886) (xy 352.867596 -30.094081) (xy 352.907331 -30.1361) (xy 352.94027 -30.183635)
			(xy 352.965659 -30.235595) (xy 352.982916 -30.290792) (xy 352.991646 -30.34796) (xy 352.992182 -30.376876)
			(xy 352.991696 -30.404127) (xy 352.98394 -30.458075) (xy 352.968585 -30.51037) (xy 352.945943 -30.559947)
			(xy 352.916477 -30.605797) (xy 352.880786 -30.646988) (xy 352.839595 -30.682679) (xy 352.793745 -30.712145)
			(xy 352.744168 -30.734787) (xy 352.691873 -30.750142) (xy 352.637925 -30.757898) (xy 352.583423 -30.757898)
			(xy 352.529475 -30.750142) (xy 352.47718 -30.734787) (xy 352.427603 -30.712145) (xy 352.381753 -30.682679)
			(xy 352.340562 -30.646988) (xy 352.304871 -30.605797) (xy 352.275405 -30.559947) (xy 352.252763 -30.51037)
			(xy 352.237408 -30.458075) (xy 352.229652 -30.404127) (xy 352.229166 -30.376876) (xy 349.952056 -30.376876)
			(xy 349.95157 -30.404127) (xy 349.943814 -30.458075) (xy 349.928459 -30.51037) (xy 349.905817 -30.559947)
			(xy 349.876351 -30.605797) (xy 349.84066 -30.646988) (xy 349.799469 -30.682679) (xy 349.753619 -30.712145)
			(xy 349.704042 -30.734787) (xy 349.651747 -30.750142) (xy 349.597799 -30.757898) (xy 349.543297 -30.757898)
			(xy 349.489349 -30.750142) (xy 349.437054 -30.734787) (xy 349.387477 -30.712145) (xy 349.341627 -30.682679)
			(xy 349.300436 -30.646988) (xy 349.264745 -30.605797) (xy 349.235279 -30.559947) (xy 349.212637 -30.51037)
			(xy 349.197282 -30.458075) (xy 349.189526 -30.404127) (xy 349.18904 -30.376876) (xy 336.169508 -30.376876)
			(xy 336.7151 -30.922468) (xy 355.052884 -30.922468) (xy 355.052884 -30.058868) (xy 355.053374 -30.0289)
			(xy 355.061197 -29.969478) (xy 355.07671 -29.911585) (xy 355.099646 -29.856212) (xy 355.129613 -29.804306)
			(xy 355.1661 -29.756756) (xy 355.20848 -29.714376) (xy 355.25603 -29.677889) (xy 355.307936 -29.647922)
			(xy 355.363309 -29.624986) (xy 355.421202 -29.609473) (xy 355.480624 -29.60165) (xy 355.54056 -29.60165)
			(xy 355.599982 -29.609473) (xy 355.657875 -29.624986) (xy 355.713248 -29.647922) (xy 355.765154 -29.677889)
			(xy 355.812704 -29.714376) (xy 355.855084 -29.756756) (xy 355.891571 -29.804306) (xy 355.921538 -29.856212)
			(xy 355.944474 -29.911585) (xy 355.959987 -29.969478) (xy 355.96781 -30.0289) (xy 355.9683 -30.058868)
			(xy 355.9683 -30.922468) (xy 355.96781 -30.952436) (xy 355.959987 -31.011858) (xy 355.944474 -31.069751)
			(xy 355.921538 -31.125124) (xy 355.891571 -31.17703) (xy 355.855084 -31.22458) (xy 355.812704 -31.26696)
			(xy 355.765154 -31.303447) (xy 355.713248 -31.333414) (xy 355.657875 -31.35635) (xy 355.599982 -31.371863)
			(xy 355.54056 -31.379686) (xy 355.480624 -31.379686) (xy 355.421202 -31.371863) (xy 355.363309 -31.35635)
			(xy 355.307936 -31.333414) (xy 355.25603 -31.303447) (xy 355.20848 -31.26696) (xy 355.1661 -31.22458)
			(xy 355.129613 -31.17703) (xy 355.099646 -31.125124) (xy 355.07671 -31.069751) (xy 355.061197 -31.011858)
			(xy 355.053374 -30.952436) (xy 355.052884 -30.922468) (xy 336.7151 -30.922468) (xy 337.360514 -31.567882)
			(xy 349.298766 -31.567882) (xy 349.302837 -31.51226) (xy 349.314963 -31.457823) (xy 349.334886 -31.405732)
			(xy 349.362182 -31.357097) (xy 349.396268 -31.312954) (xy 349.436417 -31.274245) (xy 349.481775 -31.241794)
			(xy 349.531375 -31.216293) (xy 349.584159 -31.198286) (xy 349.639002 -31.188156) (xy 349.694736 -31.186119)
			(xy 349.750173 -31.192219) (xy 349.80413 -31.206325) (xy 349.855459 -31.228137) (xy 349.903065 -31.257191)
			(xy 349.945933 -31.292866) (xy 349.98315 -31.334403) (xy 350.013923 -31.380916) (xy 350.037595 -31.431413)
			(xy 350.053663 -31.48482) (xy 350.061783 -31.539996) (xy 350.062292 -31.567882) (xy 350.061783 -31.595768)
			(xy 350.053663 -31.650944) (xy 350.037595 -31.704351) (xy 350.030603 -31.719266) (xy 350.58553 -31.719266)
			(xy 350.589601 -31.663644) (xy 350.601727 -31.609207) (xy 350.62165 -31.557116) (xy 350.648946 -31.508481)
			(xy 350.683032 -31.464338) (xy 350.723181 -31.425629) (xy 350.768539 -31.393178) (xy 350.818139 -31.367677)
			(xy 350.870923 -31.34967) (xy 350.925766 -31.33954) (xy 350.9815 -31.337503) (xy 351.036937 -31.343603)
			(xy 351.090894 -31.357709) (xy 351.142223 -31.379521) (xy 351.189829 -31.408575) (xy 351.232697 -31.44425)
			(xy 351.269914 -31.485787) (xy 351.300687 -31.5323) (xy 351.324359 -31.582797) (xy 351.340427 -31.636204)
			(xy 351.344577 -31.664402) (xy 351.861118 -31.664402) (xy 351.865189 -31.60878) (xy 351.877315 -31.554343)
			(xy 351.897238 -31.502252) (xy 351.924534 -31.453617) (xy 351.95862 -31.409474) (xy 351.998769 -31.370765)
			(xy 352.044127 -31.338314) (xy 352.093727 -31.312813) (xy 352.146511 -31.294806) (xy 352.201354 -31.284676)
			(xy 352.257088 -31.282639) (xy 352.312525 -31.288739) (xy 352.366482 -31.302845) (xy 352.417811 -31.324657)
			(xy 352.465417 -31.353711) (xy 352.508285 -31.389386) (xy 352.545502 -31.430923) (xy 352.576275 -31.477436)
			(xy 352.599947 -31.527933) (xy 352.616015 -31.58134) (xy 352.624135 -31.636516) (xy 352.624644 -31.664402)
			(xy 352.624135 -31.692288) (xy 352.616015 -31.747464) (xy 352.607075 -31.777178) (xy 353.126292 -31.777178)
			(xy 353.130363 -31.721556) (xy 353.142489 -31.667119) (xy 353.162412 -31.615028) (xy 353.189708 -31.566393)
			(xy 353.223794 -31.52225) (xy 353.263943 -31.483541) (xy 353.309301 -31.45109) (xy 353.358901 -31.425589)
			(xy 353.411685 -31.407582) (xy 353.466528 -31.397452) (xy 353.522262 -31.395415) (xy 353.577699 -31.401515)
			(xy 353.631656 -31.415621) (xy 353.682985 -31.437433) (xy 353.730591 -31.466487) (xy 353.773459 -31.502162)
			(xy 353.810676 -31.543699) (xy 353.841449 -31.590212) (xy 353.865121 -31.640709) (xy 353.881189 -31.694116)
			(xy 353.889309 -31.749292) (xy 353.889818 -31.777178) (xy 353.889309 -31.805064) (xy 353.881189 -31.86024)
			(xy 353.865121 -31.913647) (xy 353.841449 -31.964144) (xy 353.810676 -32.010657) (xy 353.773459 -32.052194)
			(xy 353.730591 -32.087869) (xy 353.682985 -32.116923) (xy 353.631656 -32.138735) (xy 353.577699 -32.152841)
			(xy 353.522262 -32.158941) (xy 353.466528 -32.156904) (xy 353.411685 -32.146774) (xy 353.358901 -32.128767)
			(xy 353.309301 -32.103266) (xy 353.263943 -32.070815) (xy 353.223794 -32.032106) (xy 353.189708 -31.987963)
			(xy 353.162412 -31.939328) (xy 353.142489 -31.887237) (xy 353.130363 -31.8328) (xy 353.126292 -31.777178)
			(xy 352.607075 -31.777178) (xy 352.599947 -31.800871) (xy 352.576275 -31.851368) (xy 352.545502 -31.897881)
			(xy 352.508285 -31.939418) (xy 352.465417 -31.975093) (xy 352.417811 -32.004147) (xy 352.366482 -32.025959)
			(xy 352.312525 -32.040065) (xy 352.257088 -32.046165) (xy 352.201354 -32.044128) (xy 352.146511 -32.033998)
			(xy 352.093727 -32.015991) (xy 352.044127 -31.99049) (xy 351.998769 -31.958039) (xy 351.95862 -31.91933)
			(xy 351.924534 -31.875187) (xy 351.897238 -31.826552) (xy 351.877315 -31.774461) (xy 351.865189 -31.720024)
			(xy 351.861118 -31.664402) (xy 351.344577 -31.664402) (xy 351.348547 -31.69138) (xy 351.349056 -31.719266)
			(xy 351.348547 -31.747152) (xy 351.340427 -31.802328) (xy 351.324359 -31.855735) (xy 351.300687 -31.906232)
			(xy 351.269914 -31.952745) (xy 351.232697 -31.994282) (xy 351.189829 -32.029957) (xy 351.142223 -32.059011)
			(xy 351.090894 -32.080823) (xy 351.036937 -32.094929) (xy 350.9815 -32.101029) (xy 350.925766 -32.098992)
			(xy 350.870923 -32.088862) (xy 350.818139 -32.070855) (xy 350.768539 -32.045354) (xy 350.723181 -32.012903)
			(xy 350.683032 -31.974194) (xy 350.648946 -31.930051) (xy 350.62165 -31.881416) (xy 350.601727 -31.829325)
			(xy 350.589601 -31.774888) (xy 350.58553 -31.719266) (xy 350.030603 -31.719266) (xy 350.013923 -31.754848)
			(xy 349.98315 -31.801361) (xy 349.945933 -31.842898) (xy 349.903065 -31.878573) (xy 349.855459 -31.907627)
			(xy 349.80413 -31.929439) (xy 349.750173 -31.943545) (xy 349.694736 -31.949645) (xy 349.639002 -31.947608)
			(xy 349.584159 -31.937478) (xy 349.531375 -31.919471) (xy 349.481775 -31.89397) (xy 349.436417 -31.861519)
			(xy 349.396268 -31.82281) (xy 349.362182 -31.778667) (xy 349.334886 -31.730032) (xy 349.314963 -31.677941)
			(xy 349.302837 -31.623504) (xy 349.298766 -31.567882) (xy 337.360514 -31.567882) (xy 338.514944 -32.722312)
			(xy 356.907084 -32.722312) (xy 356.907084 -31.858712) (xy 356.907574 -31.828744) (xy 356.915397 -31.769322)
			(xy 356.93091 -31.711429) (xy 356.953846 -31.656056) (xy 356.983813 -31.60415) (xy 357.0203 -31.5566)
			(xy 357.06268 -31.51422) (xy 357.11023 -31.477733) (xy 357.162136 -31.447766) (xy 357.217509 -31.42483)
			(xy 357.275402 -31.409317) (xy 357.334824 -31.401494) (xy 357.39476 -31.401494) (xy 357.454182 -31.409317)
			(xy 357.512075 -31.42483) (xy 357.567448 -31.447766) (xy 357.619354 -31.477733) (xy 357.666904 -31.51422)
			(xy 357.709284 -31.5566) (xy 357.745771 -31.60415) (xy 357.775738 -31.656056) (xy 357.798674 -31.711429)
			(xy 357.814187 -31.769322) (xy 357.82201 -31.828744) (xy 357.8225 -31.858712) (xy 357.8225 -32.722312)
			(xy 357.82201 -32.75228) (xy 357.814187 -32.811702) (xy 357.798674 -32.869595) (xy 357.775738 -32.924968)
			(xy 357.745771 -32.976874) (xy 357.709284 -33.024424) (xy 357.666904 -33.066804) (xy 357.619354 -33.103291)
			(xy 357.567448 -33.133258) (xy 357.512075 -33.156194) (xy 357.454182 -33.171707) (xy 357.39476 -33.17953)
			(xy 357.334824 -33.17953) (xy 357.275402 -33.171707) (xy 357.217509 -33.156194) (xy 357.162136 -33.133258)
			(xy 357.11023 -33.103291) (xy 357.06268 -33.066804) (xy 357.0203 -33.024424) (xy 356.983813 -32.976874)
			(xy 356.953846 -32.924968) (xy 356.93091 -32.869595) (xy 356.915397 -32.811702) (xy 356.907574 -32.75228)
			(xy 356.907084 -32.722312) (xy 338.514944 -32.722312) (xy 340.315042 -34.52241) (xy 355.052884 -34.52241)
			(xy 355.052884 -33.65881) (xy 355.053374 -33.628842) (xy 355.061197 -33.56942) (xy 355.07671 -33.511527)
			(xy 355.099646 -33.456154) (xy 355.129613 -33.404248) (xy 355.1661 -33.356698) (xy 355.20848 -33.314318)
			(xy 355.25603 -33.277831) (xy 355.307936 -33.247864) (xy 355.363309 -33.224928) (xy 355.421202 -33.209415)
			(xy 355.480624 -33.201592) (xy 355.54056 -33.201592) (xy 355.599982 -33.209415) (xy 355.657875 -33.224928)
			(xy 355.713248 -33.247864) (xy 355.765154 -33.277831) (xy 355.812704 -33.314318) (xy 355.855084 -33.356698)
			(xy 355.891571 -33.404248) (xy 355.921538 -33.456154) (xy 355.944474 -33.511527) (xy 355.959987 -33.56942)
			(xy 355.96781 -33.628842) (xy 355.9683 -33.65881) (xy 355.9683 -34.52241) (xy 355.96781 -34.552378)
			(xy 355.959987 -34.6118) (xy 355.944474 -34.669693) (xy 355.921538 -34.725066) (xy 355.891571 -34.776972)
			(xy 355.855084 -34.824522) (xy 355.812704 -34.866902) (xy 355.765154 -34.903389) (xy 355.713248 -34.933356)
			(xy 355.657875 -34.956292) (xy 355.599982 -34.971805) (xy 355.54056 -34.979628) (xy 355.480624 -34.979628)
			(xy 355.421202 -34.971805) (xy 355.363309 -34.956292) (xy 355.307936 -34.933356) (xy 355.25603 -34.903389)
			(xy 355.20848 -34.866902) (xy 355.1661 -34.824522) (xy 355.129613 -34.776972) (xy 355.099646 -34.725066)
			(xy 355.07671 -34.669693) (xy 355.061197 -34.6118) (xy 355.053374 -34.552378) (xy 355.052884 -34.52241)
			(xy 340.315042 -34.52241) (xy 340.439248 -34.646616) (xy 340.440264 -34.647378) (xy 340.453449 -34.660205)
			(xy 340.478358 -34.687277) (xy 340.490048 -34.70148) (xy 340.491064 -34.70275) (xy 340.491826 -34.703766)
			(xy 340.51875 -34.73069) (xy 340.538987 -34.751427) (xy 340.575757 -34.796211) (xy 340.592156 -34.820098)
			(xy 340.889439 -35.264852) (xy 352.202494 -35.264852) (xy 352.206565 -35.20923) (xy 352.218691 -35.154793)
			(xy 352.238614 -35.102702) (xy 352.26591 -35.054067) (xy 352.299996 -35.009924) (xy 352.340145 -34.971215)
			(xy 352.385503 -34.938764) (xy 352.435103 -34.913263) (xy 352.487887 -34.895256) (xy 352.54273 -34.885126)
			(xy 352.598464 -34.883089) (xy 352.653901 -34.889189) (xy 352.707858 -34.903295) (xy 352.759187 -34.925107)
			(xy 352.806793 -34.954161) (xy 352.849661 -34.989836) (xy 352.886878 -35.031373) (xy 352.917651 -35.077886)
			(xy 352.941323 -35.128383) (xy 352.957391 -35.18179) (xy 352.965511 -35.236966) (xy 352.96602 -35.264852)
			(xy 352.965511 -35.292738) (xy 352.957391 -35.347914) (xy 352.941323 -35.401321) (xy 352.917651 -35.451818)
			(xy 352.886878 -35.498331) (xy 352.849661 -35.539868) (xy 352.806793 -35.575543) (xy 352.759187 -35.604597)
			(xy 352.707858 -35.626409) (xy 352.653901 -35.640515) (xy 352.598464 -35.646615) (xy 352.54273 -35.644578)
			(xy 352.487887 -35.634448) (xy 352.435103 -35.616441) (xy 352.385503 -35.59094) (xy 352.340145 -35.558489)
			(xy 352.299996 -35.51978) (xy 352.26591 -35.475637) (xy 352.238614 -35.427002) (xy 352.218691 -35.374911)
			(xy 352.206565 -35.320474) (xy 352.202494 -35.264852) (xy 340.889439 -35.264852) (xy 341.076026 -35.543998)
			(xy 341.092028 -35.55492) (xy 341.098124 -35.55619) (xy 341.107268 -35.558222) (xy 341.108284 -35.558476)
			(xy 341.14994 -35.566604) (xy 341.17026 -35.566604) (xy 341.179404 -35.564572) (xy 341.187786 -35.558984)
			(xy 341.211405 -35.543852) (xy 341.262142 -35.519929) (xy 341.315832 -35.503687) (xy 341.371321 -35.495476)
			(xy 341.399368 -35.494976) (xy 341.403686 -35.494976) (xy 341.41283 -35.495484) (xy 341.414862 -35.495484)
			(xy 341.441784 -35.497048) (xy 341.494821 -35.506811) (xy 341.545955 -35.523942) (xy 341.594169 -35.548102)
			(xy 341.638501 -35.578808) (xy 341.678069 -35.615449) (xy 341.712084 -35.657295) (xy 341.739871 -35.703514)
			(xy 341.760873 -35.753183) (xy 341.774675 -35.805315) (xy 341.778336 -35.832034) (xy 341.779606 -35.842956)
			(xy 341.780911 -35.859311) (xy 341.780978 -35.876738) (xy 345.08897 -35.876738) (xy 345.093041 -35.821116)
			(xy 345.105167 -35.766679) (xy 345.12509 -35.714588) (xy 345.152386 -35.665953) (xy 345.186472 -35.62181)
			(xy 345.226621 -35.583101) (xy 345.271979 -35.55065) (xy 345.321579 -35.525149) (xy 345.374363 -35.507142)
			(xy 345.429206 -35.497012) (xy 345.48494 -35.494975) (xy 345.540377 -35.501075) (xy 345.594334 -35.515181)
			(xy 345.645663 -35.536993) (xy 345.693269 -35.566047) (xy 345.736137 -35.601722) (xy 345.773354 -35.643259)
			(xy 345.804127 -35.689772) (xy 345.827799 -35.740269) (xy 345.843867 -35.793676) (xy 345.851987 -35.848852)
			(xy 345.852496 -35.876738) (xy 345.851987 -35.904624) (xy 345.843867 -35.9598) (xy 345.827799 -36.013207)
			(xy 345.804127 -36.063704) (xy 345.773354 -36.110217) (xy 345.736137 -36.151754) (xy 345.693269 -36.187429)
			(xy 345.645663 -36.216483) (xy 345.594334 -36.238295) (xy 345.540377 -36.252401) (xy 345.48494 -36.258501)
			(xy 345.429206 -36.256464) (xy 345.374363 -36.246334) (xy 345.321579 -36.228327) (xy 345.271979 -36.202826)
			(xy 345.226621 -36.170375) (xy 345.186472 -36.131666) (xy 345.152386 -36.087523) (xy 345.12509 -36.038888)
			(xy 345.105167 -35.986797) (xy 345.093041 -35.93236) (xy 345.08897 -35.876738) (xy 341.780978 -35.876738)
			(xy 341.781038 -35.892123) (xy 341.77986 -35.908488) (xy 341.779606 -35.910266) (xy 341.776639 -35.938011)
			(xy 341.763681 -35.992282) (xy 341.742962 -36.044089) (xy 341.714922 -36.092329) (xy 341.680159 -36.135973)
			(xy 341.639414 -36.174092) (xy 341.616792 -36.190428) (xy 341.615268 -36.191444) (xy 341.607648 -36.197794)
			(xy 341.603838 -36.201604) (xy 341.59865 -36.20709) (xy 341.591538 -36.220402) (xy 341.589868 -36.227766)
			(xy 341.577168 -36.29152) (xy 341.57666 -36.293552) (xy 341.721317 -36.50996) (xy 342.913968 -36.50996)
			(xy 342.918039 -36.454338) (xy 342.930165 -36.399901) (xy 342.950088 -36.34781) (xy 342.977384 -36.299175)
			(xy 343.01147 -36.255032) (xy 343.051619 -36.216323) (xy 343.096977 -36.183872) (xy 343.146577 -36.158371)
			(xy 343.199361 -36.140364) (xy 343.254204 -36.130234) (xy 343.309938 -36.128197) (xy 343.365375 -36.134297)
			(xy 343.419332 -36.148403) (xy 343.470661 -36.170215) (xy 343.518267 -36.199269) (xy 343.561135 -36.234944)
			(xy 343.598352 -36.276481) (xy 343.629125 -36.322994) (xy 343.652797 -36.373491) (xy 343.668865 -36.426898)
			(xy 343.67279 -36.453572) (xy 346.228668 -36.453572) (xy 346.232739 -36.39795) (xy 346.244865 -36.343513)
			(xy 346.264788 -36.291422) (xy 346.292084 -36.242787) (xy 346.32617 -36.198644) (xy 346.366319 -36.159935)
			(xy 346.411677 -36.127484) (xy 346.461277 -36.101983) (xy 346.514061 -36.083976) (xy 346.568904 -36.073846)
			(xy 346.624638 -36.071809) (xy 346.680075 -36.077909) (xy 346.734032 -36.092015) (xy 346.785361 -36.113827)
			(xy 346.832967 -36.142881) (xy 346.875835 -36.178556) (xy 346.913052 -36.220093) (xy 346.943825 -36.266606)
			(xy 346.953361 -36.286948) (xy 353.500434 -36.286948) (xy 353.504505 -36.231326) (xy 353.516631 -36.176889)
			(xy 353.536554 -36.124798) (xy 353.56385 -36.076163) (xy 353.597936 -36.03202) (xy 353.638085 -35.993311)
			(xy 353.683443 -35.96086) (xy 353.733043 -35.935359) (xy 353.785827 -35.917352) (xy 353.84067 -35.907222)
			(xy 353.896404 -35.905185) (xy 353.951841 -35.911285) (xy 354.005798 -35.925391) (xy 354.057127 -35.947203)
			(xy 354.104733 -35.976257) (xy 354.147601 -36.011932) (xy 354.184818 -36.053469) (xy 354.215591 -36.099982)
			(xy 354.239263 -36.150479) (xy 354.255331 -36.203886) (xy 354.263451 -36.259062) (xy 354.26396 -36.286948)
			(xy 354.263451 -36.314834) (xy 354.255331 -36.37001) (xy 354.239263 -36.423417) (xy 354.215591 -36.473914)
			(xy 354.188046 -36.515548) (xy 355.314248 -36.515548) (xy 355.318319 -36.459926) (xy 355.330445 -36.405489)
			(xy 355.350368 -36.353398) (xy 355.377664 -36.304763) (xy 355.41175 -36.26062) (xy 355.451899 -36.221911)
			(xy 355.497257 -36.18946) (xy 355.546857 -36.163959) (xy 355.599641 -36.145952) (xy 355.654484 -36.135822)
			(xy 355.710218 -36.133785) (xy 355.765655 -36.139885) (xy 355.819612 -36.153991) (xy 355.870941 -36.175803)
			(xy 355.918547 -36.204857) (xy 355.961415 -36.240532) (xy 355.998632 -36.282069) (xy 356.029405 -36.328582)
			(xy 356.053077 -36.379079) (xy 356.069145 -36.432486) (xy 356.077265 -36.487662) (xy 356.077774 -36.515548)
			(xy 356.077265 -36.543434) (xy 356.069145 -36.59861) (xy 356.068688 -36.60013) (xy 360.298245 -36.60013)
			(xy 360.30225 -36.512222) (xy 360.314233 -36.425042) (xy 360.334093 -36.339313) (xy 360.361668 -36.255745)
			(xy 360.396727 -36.175031) (xy 360.43898 -36.097839) (xy 360.488078 -36.02481) (xy 360.543614 -35.956548)
			(xy 360.605126 -35.893618) (xy 360.672107 -35.836544) (xy 360.744 -35.785796) (xy 360.820209 -35.741796)
			(xy 360.900104 -35.704909) (xy 360.983023 -35.67544) (xy 361.068278 -35.653633) (xy 361.155162 -35.639669)
			(xy 361.242956 -35.633663) (xy 361.330933 -35.635667) (xy 361.418363 -35.645662) (xy 361.504522 -35.663566)
			(xy 361.588696 -35.68923) (xy 361.670187 -35.722443) (xy 361.748321 -35.762929) (xy 361.822449 -35.810351)
			(xy 361.891957 -35.864318) (xy 361.956271 -35.924383) (xy 362.014855 -35.990047) (xy 362.067226 -36.060766)
			(xy 362.112949 -36.135954) (xy 362.151646 -36.214989) (xy 362.182995 -36.297215) (xy 362.206737 -36.381951)
			(xy 362.222675 -36.468495) (xy 362.230677 -36.55613) (xy 362.231178 -36.60013) (xy 362.230677 -36.64413)
			(xy 362.222675 -36.731765) (xy 362.206737 -36.818309) (xy 362.182995 -36.903045) (xy 362.151646 -36.985271)
			(xy 362.112949 -37.064306) (xy 362.067226 -37.139494) (xy 362.014855 -37.210213) (xy 361.956271 -37.275877)
			(xy 361.891957 -37.335942) (xy 361.822449 -37.389909) (xy 361.748321 -37.437331) (xy 361.670187 -37.477817)
			(xy 361.588696 -37.51103) (xy 361.504522 -37.536694) (xy 361.418363 -37.554598) (xy 361.330933 -37.564593)
			(xy 361.242956 -37.566597) (xy 361.155162 -37.560591) (xy 361.068278 -37.546627) (xy 360.983023 -37.52482)
			(xy 360.900104 -37.495351) (xy 360.820209 -37.458464) (xy 360.744 -37.414464) (xy 360.672107 -37.363716)
			(xy 360.605126 -37.306642) (xy 360.543614 -37.243712) (xy 360.488078 -37.17545) (xy 360.43898 -37.102421)
			(xy 360.396727 -37.025229) (xy 360.361668 -36.944515) (xy 360.334093 -36.860947) (xy 360.314233 -36.775218)
			(xy 360.30225 -36.688038) (xy 360.298245 -36.60013) (xy 356.068688 -36.60013) (xy 356.053077 -36.652017)
			(xy 356.029405 -36.702514) (xy 355.998632 -36.749027) (xy 355.961415 -36.790564) (xy 355.918547 -36.826239)
			(xy 355.870941 -36.855293) (xy 355.819612 -36.877105) (xy 355.765655 -36.891211) (xy 355.710218 -36.897311)
			(xy 355.654484 -36.895274) (xy 355.599641 -36.885144) (xy 355.546857 -36.867137) (xy 355.497257 -36.841636)
			(xy 355.451899 -36.809185) (xy 355.41175 -36.770476) (xy 355.377664 -36.726333) (xy 355.350368 -36.677698)
			(xy 355.330445 -36.625607) (xy 355.318319 -36.57117) (xy 355.314248 -36.515548) (xy 354.188046 -36.515548)
			(xy 354.184818 -36.520427) (xy 354.147601 -36.561964) (xy 354.104733 -36.597639) (xy 354.057127 -36.626693)
			(xy 354.005798 -36.648505) (xy 353.951841 -36.662611) (xy 353.896404 -36.668711) (xy 353.84067 -36.666674)
			(xy 353.785827 -36.656544) (xy 353.733043 -36.638537) (xy 353.683443 -36.613036) (xy 353.638085 -36.580585)
			(xy 353.597936 -36.541876) (xy 353.56385 -36.497733) (xy 353.536554 -36.449098) (xy 353.516631 -36.397007)
			(xy 353.504505 -36.34257) (xy 353.500434 -36.286948) (xy 346.953361 -36.286948) (xy 346.967497 -36.317103)
			(xy 346.983565 -36.37051) (xy 346.991685 -36.425686) (xy 346.992194 -36.453572) (xy 346.991685 -36.481458)
			(xy 346.983565 -36.536634) (xy 346.967497 -36.590041) (xy 346.943825 -36.640538) (xy 346.913052 -36.687051)
			(xy 346.875835 -36.728588) (xy 346.832967 -36.764263) (xy 346.785361 -36.793317) (xy 346.734032 -36.815129)
			(xy 346.680075 -36.829235) (xy 346.624638 -36.835335) (xy 346.568904 -36.833298) (xy 346.514061 -36.823168)
			(xy 346.461277 -36.805161) (xy 346.411677 -36.77966) (xy 346.366319 -36.747209) (xy 346.32617 -36.7085)
			(xy 346.292084 -36.664357) (xy 346.264788 -36.615722) (xy 346.244865 -36.563631) (xy 346.232739 -36.509194)
			(xy 346.228668 -36.453572) (xy 343.67279 -36.453572) (xy 343.676985 -36.482074) (xy 343.677494 -36.50996)
			(xy 343.676985 -36.537846) (xy 343.668865 -36.593022) (xy 343.652797 -36.646429) (xy 343.629125 -36.696926)
			(xy 343.598352 -36.743439) (xy 343.561135 -36.784976) (xy 343.518267 -36.820651) (xy 343.470661 -36.849705)
			(xy 343.419332 -36.871517) (xy 343.365375 -36.885623) (xy 343.309938 -36.891723) (xy 343.254204 -36.889686)
			(xy 343.199361 -36.879556) (xy 343.146577 -36.861549) (xy 343.096977 -36.836048) (xy 343.051619 -36.803597)
			(xy 343.01147 -36.764888) (xy 342.977384 -36.720745) (xy 342.950088 -36.67211) (xy 342.930165 -36.620019)
			(xy 342.918039 -36.565582) (xy 342.913968 -36.50996) (xy 341.721317 -36.50996) (xy 341.895176 -36.770056)
			(xy 341.914088 -36.799279) (xy 341.945686 -36.861303) (xy 341.96978 -36.92661) (xy 341.986038 -36.994294)
			(xy 341.994234 -37.063419) (xy 341.994744 -37.098224) (xy 341.994744 -37.662358) (xy 342.248488 -37.662358)
			(xy 342.252559 -37.606736) (xy 342.264685 -37.552299) (xy 342.284608 -37.500208) (xy 342.311904 -37.451573)
			(xy 342.34599 -37.40743) (xy 342.386139 -37.368721) (xy 342.431497 -37.33627) (xy 342.481097 -37.310769)
			(xy 342.533881 -37.292762) (xy 342.588724 -37.282632) (xy 342.644458 -37.280595) (xy 342.699895 -37.286695)
			(xy 342.753852 -37.300801) (xy 342.805181 -37.322613) (xy 342.852787 -37.351667) (xy 342.895655 -37.387342)
			(xy 342.932872 -37.428879) (xy 342.963645 -37.475392) (xy 342.987317 -37.525889) (xy 343.003385 -37.579296)
			(xy 343.011505 -37.634472) (xy 343.012014 -37.662358) (xy 343.011505 -37.690244) (xy 343.003385 -37.74542)
			(xy 342.994751 -37.774118) (xy 353.764848 -37.774118) (xy 353.768919 -37.718496) (xy 353.781045 -37.664059)
			(xy 353.800968 -37.611968) (xy 353.828264 -37.563333) (xy 353.86235 -37.51919) (xy 353.902499 -37.480481)
			(xy 353.947857 -37.44803) (xy 353.997457 -37.422529) (xy 354.050241 -37.404522) (xy 354.105084 -37.394392)
			(xy 354.160818 -37.392355) (xy 354.216255 -37.398455) (xy 354.270212 -37.412561) (xy 354.321541 -37.434373)
			(xy 354.369147 -37.463427) (xy 354.412015 -37.499102) (xy 354.449232 -37.540639) (xy 354.480005 -37.587152)
			(xy 354.503677 -37.637649) (xy 354.519745 -37.691056) (xy 354.527865 -37.746232) (xy 354.528374 -37.774118)
			(xy 354.527865 -37.802004) (xy 354.519745 -37.85718) (xy 354.503677 -37.910587) (xy 354.480005 -37.961084)
			(xy 354.449232 -38.007597) (xy 354.412015 -38.049134) (xy 354.369147 -38.084809) (xy 354.321541 -38.113863)
			(xy 354.270212 -38.135675) (xy 354.216255 -38.149781) (xy 354.160818 -38.155881) (xy 354.105084 -38.153844)
			(xy 354.050241 -38.143714) (xy 353.997457 -38.125707) (xy 353.947857 -38.100206) (xy 353.902499 -38.067755)
			(xy 353.86235 -38.029046) (xy 353.828264 -37.984903) (xy 353.800968 -37.936268) (xy 353.781045 -37.884177)
			(xy 353.768919 -37.82974) (xy 353.764848 -37.774118) (xy 342.994751 -37.774118) (xy 342.987317 -37.798827)
			(xy 342.963645 -37.849324) (xy 342.932872 -37.895837) (xy 342.895655 -37.937374) (xy 342.852787 -37.973049)
			(xy 342.805181 -38.002103) (xy 342.753852 -38.023915) (xy 342.699895 -38.038021) (xy 342.644458 -38.044121)
			(xy 342.588724 -38.042084) (xy 342.533881 -38.031954) (xy 342.481097 -38.013947) (xy 342.431497 -37.988446)
			(xy 342.386139 -37.955995) (xy 342.34599 -37.917286) (xy 342.311904 -37.873143) (xy 342.284608 -37.824508)
			(xy 342.264685 -37.772417) (xy 342.252559 -37.71798) (xy 342.248488 -37.662358) (xy 341.994744 -37.662358)
			(xy 341.994744 -38.729948) (xy 346.00112 -38.729948) (xy 346.00112 -38.675452) (xy 346.008875 -38.621512)
			(xy 346.024228 -38.569224) (xy 346.046866 -38.519653) (xy 346.076327 -38.473809) (xy 346.112013 -38.432623)
			(xy 346.153197 -38.396936) (xy 346.199041 -38.367472) (xy 346.248611 -38.344833) (xy 346.300898 -38.329478)
			(xy 346.354838 -38.321721) (xy 346.382086 -38.321234) (xy 346.410391 -38.321719) (xy 346.46638 -38.33007)
			(xy 346.52052 -38.346605) (xy 346.571621 -38.37096) (xy 346.618561 -38.402602) (xy 346.660308 -38.440835)
			(xy 346.695945 -38.484818) (xy 346.710762 -38.50894) (xy 346.718313 -38.521007) (xy 346.738941 -38.540611)
			(xy 346.764183 -38.553753) (xy 346.792074 -38.559408) (xy 346.820441 -38.557138) (xy 346.847077 -38.547118)
			(xy 346.869907 -38.530129) (xy 346.87891 -38.5191) (xy 346.897096 -38.496223) (xy 346.939259 -38.455759)
			(xy 346.987095 -38.422192) (xy 347.039487 -38.396305) (xy 347.095211 -38.378703) (xy 347.152967 -38.369797)
			(xy 347.182186 -38.36924) (xy 347.209443 -38.369606) (xy 347.263402 -38.377362) (xy 347.315708 -38.392719)
			(xy 347.365297 -38.415364) (xy 347.411157 -38.444835) (xy 347.452357 -38.480533) (xy 347.488057 -38.521731)
			(xy 347.51753 -38.567591) (xy 347.540176 -38.617178) (xy 347.555535 -38.669484) (xy 347.563293 -38.723443)
			(xy 347.563293 -38.777957) (xy 347.555535 -38.831916) (xy 347.540176 -38.884222) (xy 347.51753 -38.933809)
			(xy 347.488057 -38.979669) (xy 347.452357 -39.020867) (xy 347.411157 -39.056565) (xy 347.365297 -39.086036)
			(xy 347.315708 -39.108681) (xy 347.263402 -39.124038) (xy 347.209443 -39.131794) (xy 347.182186 -39.132256)
			(xy 347.153883 -39.131719) (xy 347.097896 -39.123379) (xy 347.043757 -39.106853) (xy 346.992656 -39.082506)
			(xy 346.945715 -39.050872) (xy 346.903966 -39.012647) (xy 346.868327 -38.968669) (xy 346.85351 -38.94455)
			(xy 346.845866 -38.932548) (xy 346.825256 -38.91295) (xy 346.800034 -38.899808) (xy 346.772163 -38.894145)
			(xy 346.743812 -38.896403) (xy 346.717189 -38.906404) (xy 346.694364 -38.923372) (xy 346.685362 -38.93439)
			(xy 346.66719 -38.957278) (xy 346.625024 -38.997742) (xy 346.577186 -39.031308) (xy 346.524791 -39.057193)
			(xy 346.469064 -39.074793) (xy 346.411306 -39.083695) (xy 346.382086 -39.08425) (xy 346.354838 -39.083679)
			(xy 346.300898 -39.075922) (xy 346.248611 -39.060567) (xy 346.199041 -39.037928) (xy 346.153197 -39.008464)
			(xy 346.112013 -38.972777) (xy 346.076327 -38.931591) (xy 346.046866 -38.885747) (xy 346.024228 -38.836176)
			(xy 346.008875 -38.783888) (xy 346.00112 -38.729948) (xy 341.994744 -38.729948) (xy 341.994744 -39.774622)
			(xy 341.995172 -39.784689) (xy 342.002897 -39.803284) (xy 342.00973 -39.81069) (xy 342.17102 -39.97198)
			(xy 348.195898 -39.97198) (xy 348.199969 -39.916358) (xy 348.212095 -39.861921) (xy 348.232018 -39.80983)
			(xy 348.259314 -39.761195) (xy 348.2934 -39.717052) (xy 348.333549 -39.678343) (xy 348.378907 -39.645892)
			(xy 348.428507 -39.620391) (xy 348.481291 -39.602384) (xy 348.536134 -39.592254) (xy 348.591868 -39.590217)
			(xy 348.647305 -39.596317) (xy 348.701262 -39.610423) (xy 348.752591 -39.632235) (xy 348.800197 -39.661289)
			(xy 348.843065 -39.696964) (xy 348.880282 -39.738501) (xy 348.911055 -39.785014) (xy 348.934727 -39.835511)
			(xy 348.950795 -39.888918) (xy 348.958915 -39.944094) (xy 348.959424 -39.97198) (xy 348.958915 -39.999866)
			(xy 348.950795 -40.055042) (xy 348.934727 -40.108449) (xy 348.911055 -40.158946) (xy 348.880282 -40.205459)
			(xy 348.843065 -40.246996) (xy 348.800197 -40.282671) (xy 348.752591 -40.311725) (xy 348.701262 -40.333537)
			(xy 348.647305 -40.347643) (xy 348.591868 -40.353743) (xy 348.536134 -40.351706) (xy 348.481291 -40.341576)
			(xy 348.428507 -40.323569) (xy 348.378907 -40.298068) (xy 348.333549 -40.265617) (xy 348.2934 -40.226908)
			(xy 348.259314 -40.182765) (xy 348.232018 -40.13413) (xy 348.212095 -40.082039) (xy 348.199969 -40.027602)
			(xy 348.195898 -39.97198) (xy 342.17102 -39.97198) (xy 343.170764 -40.971724) (xy 348.894144 -40.971724)
			(xy 348.898215 -40.916102) (xy 348.910341 -40.861665) (xy 348.930264 -40.809574) (xy 348.95756 -40.760939)
			(xy 348.991646 -40.716796) (xy 349.031795 -40.678087) (xy 349.077153 -40.645636) (xy 349.126753 -40.620135)
			(xy 349.179537 -40.602128) (xy 349.23438 -40.591998) (xy 349.290114 -40.589961) (xy 349.345551 -40.596061)
			(xy 349.399508 -40.610167) (xy 349.450837 -40.631979) (xy 349.498443 -40.661033) (xy 349.541311 -40.696708)
			(xy 349.578528 -40.738245) (xy 349.609301 -40.784758) (xy 349.632973 -40.835255) (xy 349.649041 -40.888662)
			(xy 349.657161 -40.943838) (xy 349.65767 -40.971724) (xy 349.657161 -40.99961) (xy 349.649041 -41.054786)
			(xy 349.632973 -41.108193) (xy 349.609301 -41.15869) (xy 349.578528 -41.205203) (xy 349.541311 -41.24674)
			(xy 349.498443 -41.282415) (xy 349.450837 -41.311469) (xy 349.399508 -41.333281) (xy 349.345551 -41.347387)
			(xy 349.290114 -41.353487) (xy 349.23438 -41.35145) (xy 349.179537 -41.34132) (xy 349.126753 -41.323313)
			(xy 349.077153 -41.297812) (xy 349.031795 -41.265361) (xy 348.991646 -41.226652) (xy 348.95756 -41.182509)
			(xy 348.930264 -41.133874) (xy 348.910341 -41.081783) (xy 348.898215 -41.027346) (xy 348.894144 -40.971724)
			(xy 343.170764 -40.971724) (xy 344.81897 -42.61993) (xy 344.84208 -42.643709) (xy 344.883413 -42.695562)
			(xy 344.918682 -42.751716) (xy 344.947442 -42.811465) (xy 344.969333 -42.874059) (xy 344.98408 -42.938709)
			(xy 344.991496 -43.004604) (xy 344.991944 -43.03776) (xy 344.991944 -49.601949) (xy 354.413082 -49.601949)
			(xy 354.413082 -49.547451) (xy 354.420837 -49.493507) (xy 354.43619 -49.441217) (xy 354.458828 -49.391643)
			(xy 354.48829 -49.345795) (xy 354.523976 -49.304606) (xy 354.565161 -49.268915) (xy 354.611006 -49.239448)
			(xy 354.660577 -49.216805) (xy 354.712866 -49.201446) (xy 354.766809 -49.193685) (xy 354.794058 -49.193196)
			(xy 354.821427 -49.193688) (xy 354.875605 -49.201499) (xy 354.928108 -49.216983) (xy 354.977855 -49.239819)
			(xy 355.023823 -49.269537) (xy 355.044756 -49.287176) (xy 355.04501 -49.28743) (xy 355.052087 -49.29303)
			(xy 355.069011 -49.299268) (xy 355.07803 -49.299622) (xy 355.145086 -49.299622) (xy 355.154102 -49.299253)
			(xy 355.171018 -49.293013) (xy 355.178106 -49.28743) (xy 355.178106 -49.287176) (xy 355.17836 -49.287176)
			(xy 355.199293 -49.269535) (xy 355.245261 -49.239811) (xy 355.295007 -49.216965) (xy 355.347509 -49.201469)
			(xy 355.401687 -49.19364) (xy 355.456429 -49.19364) (xy 355.510607 -49.201469) (xy 355.563109 -49.216965)
			(xy 355.612855 -49.239811) (xy 355.658823 -49.269535) (xy 355.679756 -49.287176) (xy 355.68001 -49.28743)
			(xy 355.687087 -49.29303) (xy 355.704011 -49.299268) (xy 355.71303 -49.299622) (xy 355.780086 -49.299622)
			(xy 355.789102 -49.299253) (xy 355.806018 -49.293013) (xy 355.813106 -49.28743) (xy 355.813106 -49.287176)
			(xy 355.81336 -49.287176) (xy 355.834293 -49.269535) (xy 355.880261 -49.239811) (xy 355.930007 -49.216965)
			(xy 355.982509 -49.201469) (xy 356.036687 -49.19364) (xy 356.091429 -49.19364) (xy 356.145607 -49.201469)
			(xy 356.198109 -49.216965) (xy 356.247855 -49.239811) (xy 356.293823 -49.269535) (xy 356.314756 -49.287176)
			(xy 356.31501 -49.28743) (xy 356.322087 -49.29303) (xy 356.339011 -49.299268) (xy 356.34803 -49.299622)
			(xy 356.415086 -49.299622) (xy 356.424102 -49.299253) (xy 356.441018 -49.293013) (xy 356.448106 -49.28743)
			(xy 356.448106 -49.287176) (xy 356.44836 -49.287176) (xy 356.469293 -49.269538) (xy 356.515266 -49.239827)
			(xy 356.565013 -49.216991) (xy 356.617514 -49.2015) (xy 356.671689 -49.193671) (xy 356.699058 -49.193196)
			(xy 356.726313 -49.193648) (xy 356.780269 -49.201401) (xy 356.832573 -49.216753) (xy 356.882158 -49.239394)
			(xy 356.928017 -49.268861) (xy 356.969215 -49.304555) (xy 357.004914 -49.345749) (xy 357.034386 -49.391605)
			(xy 357.057032 -49.441188) (xy 357.07239 -49.49349) (xy 357.080149 -49.547445) (xy 357.080149 -49.601955)
			(xy 357.07239 -49.65591) (xy 357.057032 -49.708212) (xy 357.034386 -49.757795) (xy 357.004914 -49.803651)
			(xy 356.969215 -49.844845) (xy 356.928017 -49.880539) (xy 356.882158 -49.910006) (xy 356.832573 -49.932647)
			(xy 356.780269 -49.947999) (xy 356.726313 -49.955752) (xy 356.699058 -49.956212) (xy 356.671689 -49.955709)
			(xy 356.617512 -49.9479) (xy 356.565009 -49.932419) (xy 356.515262 -49.909586) (xy 356.469293 -49.879869)
			(xy 356.44836 -49.862232) (xy 356.448106 -49.861978) (xy 356.441024 -49.856385) (xy 356.424104 -49.850143)
			(xy 356.415086 -49.849786) (xy 356.34803 -49.849786) (xy 356.339015 -49.85016) (xy 356.322098 -49.856396)
			(xy 356.31501 -49.861978) (xy 356.314756 -49.862232) (xy 356.293823 -49.879873) (xy 356.247855 -49.909597)
			(xy 356.198109 -49.932443) (xy 356.145607 -49.947939) (xy 356.091429 -49.955768) (xy 356.036687 -49.955768)
			(xy 355.982509 -49.947939) (xy 355.930007 -49.932443) (xy 355.880261 -49.909597) (xy 355.834293 -49.879873)
			(xy 355.81336 -49.862232) (xy 355.813106 -49.861978) (xy 355.806024 -49.856385) (xy 355.789104 -49.850143)
			(xy 355.780086 -49.849786) (xy 355.71303 -49.849786) (xy 355.704015 -49.85016) (xy 355.687098 -49.856396)
			(xy 355.68001 -49.861978) (xy 355.68001 -49.862232) (xy 355.679756 -49.862232) (xy 355.658823 -49.879873)
			(xy 355.612855 -49.909597) (xy 355.563109 -49.932443) (xy 355.510607 -49.947939) (xy 355.456429 -49.955768)
			(xy 355.401687 -49.955768) (xy 355.347509 -49.947939) (xy 355.295007 -49.932443) (xy 355.245261 -49.909597)
			(xy 355.199293 -49.879873) (xy 355.17836 -49.862232) (xy 355.178106 -49.861978) (xy 355.171024 -49.856385)
			(xy 355.154104 -49.850143) (xy 355.145086 -49.849786) (xy 355.07803 -49.849786) (xy 355.069015 -49.85016)
			(xy 355.052098 -49.856396) (xy 355.04501 -49.861978) (xy 355.04501 -49.862232) (xy 355.044756 -49.862232)
			(xy 355.023818 -49.879863) (xy 354.977846 -49.909575) (xy 354.9281 -49.932412) (xy 354.875601 -49.947905)
			(xy 354.821427 -49.955736) (xy 354.794058 -49.956212) (xy 354.766809 -49.955715) (xy 354.712866 -49.947954)
			(xy 354.660577 -49.932595) (xy 354.611006 -49.909952) (xy 354.565161 -49.880485) (xy 354.523976 -49.844794)
			(xy 354.48829 -49.803605) (xy 354.458828 -49.757757) (xy 354.43619 -49.708183) (xy 354.420837 -49.655893)
			(xy 354.413082 -49.601949) (xy 344.991944 -49.601949) (xy 344.991944 -51.243992) (xy 355.433122 -51.243992)
			(xy 355.433578 -51.216621) (xy 355.441397 -51.162442) (xy 355.456889 -51.109938) (xy 355.479733 -51.060191)
			(xy 355.50946 -51.014225) (xy 355.527102 -50.993294) (xy 355.527356 -50.99304) (xy 355.532939 -50.985951)
			(xy 355.539186 -50.969036) (xy 355.539548 -50.96002) (xy 355.539548 -50.892964) (xy 355.53922 -50.883944)
			(xy 355.532954 -50.867027) (xy 355.527356 -50.859944) (xy 355.527102 -50.859944) (xy 355.527102 -50.85969)
			(xy 355.509445 -50.838772) (xy 355.479736 -50.792796) (xy 355.456903 -50.743044) (xy 355.441416 -50.690541)
			(xy 355.433593 -50.636362) (xy 355.433122 -50.608992) (xy 355.433548 -50.581738) (xy 355.441307 -50.527784)
			(xy 355.456665 -50.475483) (xy 355.479311 -50.425901) (xy 355.508783 -50.380047) (xy 355.54448 -50.338853)
			(xy 355.585677 -50.30316) (xy 355.631535 -50.273693) (xy 355.681119 -50.251052) (xy 355.733421 -50.235699)
			(xy 355.787376 -50.227945) (xy 355.81463 -50.227484) (xy 355.843547 -50.228021) (xy 355.900718 -50.236742)
			(xy 355.955918 -50.253994) (xy 356.007881 -50.279382) (xy 356.055415 -50.312324) (xy 356.097431 -50.352065)
			(xy 356.11562 -50.37455) (xy 356.123219 -50.383365) (xy 356.144126 -50.393542) (xy 356.155752 -50.394108)
			(xy 356.235508 -50.394108) (xy 356.247138 -50.393556) (xy 356.268048 -50.383376) (xy 356.27564 -50.37455)
			(xy 356.293796 -50.352037) (xy 356.335824 -50.312306) (xy 356.383367 -50.279372) (xy 356.435335 -50.253989)
			(xy 356.490538 -50.236739) (xy 356.547712 -50.228016) (xy 356.57663 -50.227484) (xy 356.603882 -50.22795)
			(xy 356.65783 -50.23571) (xy 356.710124 -50.251069) (xy 356.759701 -50.273713) (xy 356.805551 -50.303182)
			(xy 356.846741 -50.338875) (xy 356.882432 -50.380067) (xy 356.911898 -50.425918) (xy 356.934539 -50.475496)
			(xy 356.949894 -50.527792) (xy 356.957652 -50.58174) (xy 356.958138 -50.608992) (xy 356.957685 -50.635307)
			(xy 356.95045 -50.687437) (xy 356.936129 -50.73808) (xy 356.914994 -50.78628) (xy 356.887445 -50.831123)
			(xy 356.854002 -50.871761) (xy 356.834948 -50.889916) (xy 356.827545 -50.897436) (xy 356.81902 -50.916717)
			(xy 356.818438 -50.927254) (xy 356.818438 -51.00193) (xy 356.81898 -51.012478) (xy 356.827505 -51.031775)
			(xy 356.834948 -51.039268) (xy 356.854039 -51.057388) (xy 356.887491 -51.098026) (xy 356.915044 -51.142875)
			(xy 356.936176 -51.191082) (xy 356.950486 -51.241735) (xy 356.957703 -51.293874) (xy 356.958138 -51.320192)
			(xy 356.957615 -51.347442) (xy 356.94986 -51.401387) (xy 356.934508 -51.453679) (xy 356.91187 -51.503254)
			(xy 356.882407 -51.549103) (xy 356.846719 -51.590293) (xy 356.805533 -51.625984) (xy 356.759687 -51.655451)
			(xy 356.710114 -51.678094) (xy 356.657824 -51.693452) (xy 356.60388 -51.701212) (xy 356.57663 -51.7017)
			(xy 356.548966 -51.701164) (xy 356.494218 -51.693169) (xy 356.441197 -51.677357) (xy 356.391013 -51.654057)
			(xy 356.344717 -51.62376) (xy 356.303278 -51.587098) (xy 356.267564 -51.544839) (xy 356.252526 -51.521614)
			(xy 356.245887 -51.51194) (xy 356.226027 -51.499496) (xy 356.214426 -51.497738) (xy 356.134416 -51.489864)
			(xy 356.122778 -51.489246) (xy 356.100941 -51.497316) (xy 356.092506 -51.505358) (xy 356.092252 -51.505612)
			(xy 356.074179 -51.524201) (xy 356.033845 -51.556778) (xy 355.989469 -51.58359) (xy 355.941869 -51.604141)
			(xy 355.891923 -51.618053) (xy 355.840554 -51.625069) (xy 355.81463 -51.6255) (xy 355.787378 -51.625017)
			(xy 355.733427 -51.617264) (xy 355.681129 -51.601911) (xy 355.631548 -51.579271) (xy 355.585695 -51.549806)
			(xy 355.544501 -51.514114) (xy 355.508807 -51.472923) (xy 355.479339 -51.427071) (xy 355.456697 -51.377492)
			(xy 355.441341 -51.325195) (xy 355.433585 -51.271244) (xy 355.433122 -51.243992) (xy 344.991944 -51.243992)
			(xy 344.991944 -52.555948) (xy 354.884002 -52.555948) (xy 354.884002 -52.501452) (xy 354.891757 -52.44751)
			(xy 354.90711 -52.39522) (xy 354.929748 -52.345648) (xy 354.95921 -52.299802) (xy 354.994897 -52.258615)
			(xy 355.036081 -52.222926) (xy 355.081925 -52.193461) (xy 355.131496 -52.170819) (xy 355.183784 -52.155463)
			(xy 355.237726 -52.147704) (xy 355.264974 -52.147216) (xy 355.292344 -52.147693) (xy 355.346523 -52.155508)
			(xy 355.399026 -52.170994) (xy 355.448773 -52.193833) (xy 355.49474 -52.223556) (xy 355.515672 -52.241196)
			(xy 355.515926 -52.24145) (xy 355.523025 -52.247018) (xy 355.539932 -52.253275) (xy 355.548946 -52.253642)
			(xy 355.616002 -52.253642) (xy 355.62502 -52.253298) (xy 355.641938 -52.247043) (xy 355.649022 -52.24145)
			(xy 355.649022 -52.241196) (xy 355.649276 -52.241196) (xy 355.670206 -52.223554) (xy 355.716179 -52.193843)
			(xy 355.765927 -52.171007) (xy 355.818429 -52.155517) (xy 355.872605 -52.14769) (xy 355.899974 -52.147216)
			(xy 355.92723 -52.147629) (xy 355.981187 -52.155384) (xy 356.033491 -52.170738) (xy 356.083078 -52.193381)
			(xy 356.128937 -52.22285) (xy 356.170136 -52.258546) (xy 356.205834 -52.299742) (xy 356.235307 -52.345599)
			(xy 356.257953 -52.395184) (xy 356.273311 -52.447488) (xy 356.281069 -52.501444) (xy 356.281069 -52.555956)
			(xy 356.273311 -52.609912) (xy 356.257953 -52.662216) (xy 356.235307 -52.711801) (xy 356.205834 -52.757658)
			(xy 356.170136 -52.798854) (xy 356.128937 -52.83455) (xy 356.083078 -52.864019) (xy 356.033491 -52.886662)
			(xy 355.981187 -52.902016) (xy 355.92723 -52.909771) (xy 355.899974 -52.910232) (xy 355.872602 -52.909798)
			(xy 355.818421 -52.901975) (xy 355.765917 -52.886479) (xy 355.716171 -52.86363) (xy 355.670206 -52.833897)
			(xy 355.649276 -52.816252) (xy 355.649022 -52.815998) (xy 355.641933 -52.810414) (xy 355.625018 -52.804166)
			(xy 355.616002 -52.803806) (xy 355.548946 -52.803806) (xy 355.539931 -52.804184) (xy 355.523014 -52.810417)
			(xy 355.515926 -52.815998) (xy 355.515926 -52.816252) (xy 355.515672 -52.816252) (xy 355.494717 -52.833863)
			(xy 355.448752 -52.863581) (xy 355.39901 -52.886423) (xy 355.346514 -52.90192) (xy 355.292342 -52.909755)
			(xy 355.264974 -52.910232) (xy 355.237726 -52.909696) (xy 355.183784 -52.901937) (xy 355.131496 -52.886581)
			(xy 355.081925 -52.863939) (xy 355.036081 -52.834474) (xy 354.994897 -52.798785) (xy 354.95921 -52.757598)
			(xy 354.929748 -52.711752) (xy 354.90711 -52.66218) (xy 354.891757 -52.60989) (xy 354.884002 -52.555948)
			(xy 344.991944 -52.555948) (xy 344.991944 -53.496555) (xy 354.433541 -53.496555) (xy 354.433541 -53.442045)
			(xy 354.441299 -53.388089) (xy 354.456657 -53.335787) (xy 354.479303 -53.286202) (xy 354.508775 -53.240346)
			(xy 354.544474 -53.199151) (xy 354.585672 -53.163456) (xy 354.63153 -53.133988) (xy 354.681117 -53.111346)
			(xy 354.73342 -53.095992) (xy 354.787377 -53.088239) (xy 354.814632 -53.087778) (xy 354.842004 -53.088206)
			(xy 354.896185 -53.09603) (xy 354.94869 -53.111527) (xy 354.998436 -53.134378) (xy 355.0444 -53.164112)
			(xy 355.06533 -53.181758) (xy 355.065584 -53.182012) (xy 355.07267 -53.187599) (xy 355.089587 -53.193845)
			(xy 355.098604 -53.194204) (xy 355.16566 -53.194204) (xy 355.174675 -53.193827) (xy 355.191592 -53.187593)
			(xy 355.19868 -53.182012) (xy 355.19868 -53.181758) (xy 355.198934 -53.181758) (xy 355.219874 -53.164129)
			(xy 355.265846 -53.134417) (xy 355.315591 -53.11158) (xy 355.36809 -53.096086) (xy 355.422264 -53.088254)
			(xy 355.449632 -53.087778) (xy 355.476881 -53.088294) (xy 355.530823 -53.096054) (xy 355.583112 -53.111412)
			(xy 355.632683 -53.134054) (xy 355.678528 -53.16352) (xy 355.719713 -53.19921) (xy 355.755399 -53.240398)
			(xy 355.784862 -53.286245) (xy 355.8075 -53.335818) (xy 355.822852 -53.388108) (xy 355.830608 -53.442051)
			(xy 355.830608 -53.496549) (xy 355.822852 -53.550492) (xy 355.8075 -53.602782) (xy 355.784862 -53.652355)
			(xy 355.755399 -53.698202) (xy 355.719713 -53.73939) (xy 355.678528 -53.77508) (xy 355.632683 -53.804546)
			(xy 355.583112 -53.827188) (xy 355.530823 -53.842546) (xy 355.476881 -53.850306) (xy 355.449632 -53.850794)
			(xy 355.422262 -53.850311) (xy 355.368084 -53.842497) (xy 355.315581 -53.827012) (xy 355.265834 -53.804174)
			(xy 355.219866 -53.774453) (xy 355.198934 -53.756814) (xy 355.19868 -53.75656) (xy 355.191607 -53.750954)
			(xy 355.17468 -53.74472) (xy 355.16566 -53.744368) (xy 355.098604 -53.744368) (xy 355.089588 -53.744734)
			(xy 355.072672 -53.750976) (xy 355.065584 -53.75656) (xy 355.065584 -53.756814) (xy 355.06533 -53.756814)
			(xy 355.044399 -53.774455) (xy 354.998426 -53.804166) (xy 354.948678 -53.827001) (xy 354.896177 -53.842492)
			(xy 354.842001 -53.85032) (xy 354.814632 -53.850794) (xy 354.787377 -53.850361) (xy 354.73342 -53.842608)
			(xy 354.681117 -53.827254) (xy 354.63153 -53.804612) (xy 354.585672 -53.775144) (xy 354.544474 -53.739449)
			(xy 354.508775 -53.698254) (xy 354.479303 -53.652398) (xy 354.456657 -53.602813) (xy 354.441299 -53.550511)
			(xy 354.433541 -53.496555) (xy 344.991944 -53.496555) (xy 344.991944 -54.989055) (xy 352.201145 -54.989055)
			(xy 352.201145 -54.934545) (xy 352.208903 -54.880591) (xy 352.224261 -54.828289) (xy 352.246906 -54.778706)
			(xy 352.276377 -54.73285) (xy 352.312074 -54.691656) (xy 352.353271 -54.655961) (xy 352.399129 -54.626493)
			(xy 352.448714 -54.603851) (xy 352.501016 -54.588497) (xy 352.554971 -54.580743) (xy 352.582226 -54.580282)
			(xy 352.610318 -54.580756) (xy 352.665896 -54.588987) (xy 352.719666 -54.605282) (xy 352.770463 -54.629288)
			(xy 352.81719 -54.660486) (xy 352.858835 -54.698201) (xy 352.894496 -54.741616) (xy 352.909378 -54.765448)
			(xy 352.914712 -54.774338) (xy 352.93173 -54.78653) (xy 353.024948 -54.80685) (xy 353.045522 -54.802532)
			(xy 353.054158 -54.79669) (xy 353.078231 -54.780705) (xy 353.130159 -54.755359) (xy 353.185314 -54.738129)
			(xy 353.242436 -54.729409) (xy 353.271328 -54.728872) (xy 353.298579 -54.729352) (xy 353.352526 -54.737112)
			(xy 353.40482 -54.752469) (xy 353.454396 -54.775112) (xy 353.500245 -54.804579) (xy 353.541434 -54.840271)
			(xy 353.577125 -54.881462) (xy 353.606592 -54.927311) (xy 353.629234 -54.976888) (xy 353.64459 -55.029182)
			(xy 353.652349 -55.083129) (xy 353.652836 -55.11038) (xy 353.652374 -55.137751) (xy 353.644557 -55.19193)
			(xy 353.629068 -55.244434) (xy 353.606225 -55.294181) (xy 353.576499 -55.340147) (xy 353.558856 -55.361078)
			(xy 353.558602 -55.361332) (xy 353.553038 -55.368434) (xy 353.546778 -55.385339) (xy 353.54641 -55.394352)
			(xy 353.54641 -55.461408) (xy 353.546761 -55.470426) (xy 353.553012 -55.487343) (xy 353.558602 -55.494428)
			(xy 353.558856 -55.494428) (xy 353.558856 -55.494682) (xy 353.576478 -55.51563) (xy 353.606205 -55.561595)
			(xy 353.629052 -55.611339) (xy 353.644551 -55.663838) (xy 353.652382 -55.718015) (xy 353.652384 -55.772755)
			(xy 353.644557 -55.826932) (xy 353.629063 -55.879433) (xy 353.606219 -55.929179) (xy 353.576496 -55.975146)
			(xy 353.558856 -55.996078) (xy 353.558602 -55.996332) (xy 353.553038 -56.003434) (xy 353.546778 -56.020339)
			(xy 353.54641 -56.029352) (xy 353.54641 -56.096408) (xy 353.546761 -56.105426) (xy 353.553012 -56.122343)
			(xy 353.558602 -56.129428) (xy 353.558856 -56.129428) (xy 353.558856 -56.129682) (xy 353.576493 -56.150616)
			(xy 353.606207 -56.196587) (xy 353.629044 -56.246334) (xy 353.644535 -56.298835) (xy 353.652363 -56.353011)
			(xy 353.652836 -56.38038) (xy 353.65235 -56.407631) (xy 353.644594 -56.461579) (xy 353.629239 -56.513874)
			(xy 353.606597 -56.563451) (xy 353.577131 -56.609301) (xy 353.54144 -56.650492) (xy 353.500249 -56.686183)
			(xy 353.454399 -56.715649) (xy 353.404822 -56.738291) (xy 353.352527 -56.753646) (xy 353.298579 -56.761402)
			(xy 353.244077 -56.761402) (xy 353.190129 -56.753646) (xy 353.137834 -56.738291) (xy 353.088257 -56.715649)
			(xy 353.042407 -56.686183) (xy 353.001216 -56.650492) (xy 352.965525 -56.609301) (xy 352.936059 -56.563451)
			(xy 352.913417 -56.513874) (xy 352.898062 -56.461579) (xy 352.890306 -56.407631) (xy 352.88982 -56.38038)
			(xy 352.890269 -56.353009) (xy 352.898091 -56.298829) (xy 352.913583 -56.246326) (xy 352.936429 -56.196579)
			(xy 352.966157 -56.150613) (xy 352.9838 -56.129682) (xy 352.984054 -56.129428) (xy 352.989641 -56.122342)
			(xy 352.995886 -56.105425) (xy 352.996246 -56.096408) (xy 352.996246 -56.029352) (xy 352.995876 -56.020336)
			(xy 352.989639 -56.003418) (xy 352.984054 -55.996332) (xy 352.9838 -55.996332) (xy 352.9838 -55.996078)
			(xy 352.966141 -55.975161) (xy 352.936419 -55.929189) (xy 352.913576 -55.879441) (xy 352.898083 -55.826936)
			(xy 352.890257 -55.772756) (xy 352.890259 -55.718014) (xy 352.898089 -55.663834) (xy 352.913587 -55.611331)
			(xy 352.936433 -55.561584) (xy 352.966159 -55.515615) (xy 352.9838 -55.494682) (xy 352.984054 -55.494428)
			(xy 352.989641 -55.487342) (xy 352.995886 -55.470425) (xy 352.996246 -55.461408) (xy 352.996246 -55.394352)
			(xy 352.995876 -55.385336) (xy 352.989639 -55.368418) (xy 352.984054 -55.361332) (xy 352.9838 -55.360824)
			(xy 352.972856 -55.348089) (xy 352.953015 -55.320998) (xy 352.944176 -55.306722) (xy 352.938842 -55.297832)
			(xy 352.921824 -55.28564) (xy 352.828606 -55.26532) (xy 352.808032 -55.269638) (xy 352.799396 -55.27548)
			(xy 352.775333 -55.291482) (xy 352.723402 -55.316825) (xy 352.668243 -55.33405) (xy 352.611119 -55.342764)
			(xy 352.582226 -55.343298) (xy 352.554971 -55.342857) (xy 352.501016 -55.335103) (xy 352.448714 -55.319749)
			(xy 352.399129 -55.297107) (xy 352.353271 -55.267639) (xy 352.312074 -55.231944) (xy 352.276377 -55.19075)
			(xy 352.246906 -55.144894) (xy 352.224261 -55.095311) (xy 352.208903 -55.043009) (xy 352.201145 -54.989055)
			(xy 344.991944 -54.989055) (xy 344.991944 -55.420855) (xy 350.524745 -55.420855) (xy 350.524745 -55.366345)
			(xy 350.532503 -55.312391) (xy 350.547861 -55.260089) (xy 350.570506 -55.210506) (xy 350.599977 -55.16465)
			(xy 350.635674 -55.123456) (xy 350.676871 -55.087761) (xy 350.722729 -55.058293) (xy 350.772314 -55.035651)
			(xy 350.824616 -55.020297) (xy 350.878571 -55.012543) (xy 350.905826 -55.012082) (xy 350.93214 -55.012538)
			(xy 350.984269 -55.019776) (xy 351.034912 -55.034098) (xy 351.083111 -55.055232) (xy 351.127954 -55.08278)
			(xy 351.168593 -55.11622) (xy 351.18675 -55.135272) (xy 351.194255 -55.142694) (xy 351.213547 -55.151208)
			(xy 351.224088 -55.151782) (xy 351.298764 -55.151782) (xy 351.309314 -55.151252) (xy 351.32861 -55.142718)
			(xy 351.336102 -55.135272) (xy 351.354258 -55.116217) (xy 351.394888 -55.082761) (xy 351.439729 -55.055203)
			(xy 351.487929 -55.034064) (xy 351.538576 -55.019747) (xy 351.59071 -55.012521) (xy 351.617026 -55.012082)
			(xy 351.644275 -55.01259) (xy 351.698219 -55.020349) (xy 351.750509 -55.035706) (xy 351.800082 -55.058348)
			(xy 351.845927 -55.087814) (xy 351.887113 -55.123505) (xy 351.922801 -55.164693) (xy 351.952264 -55.210541)
			(xy 351.974903 -55.260115) (xy 351.990256 -55.312407) (xy 351.998012 -55.366351) (xy 351.998012 -55.420849)
			(xy 351.990256 -55.474793) (xy 351.974903 -55.527085) (xy 351.952264 -55.576659) (xy 351.922801 -55.622507)
			(xy 351.887113 -55.663695) (xy 351.845927 -55.699386) (xy 351.800082 -55.728852) (xy 351.750509 -55.751494)
			(xy 351.698219 -55.766851) (xy 351.644275 -55.77461) (xy 351.617026 -55.775098) (xy 351.590713 -55.774614)
			(xy 351.538585 -55.767383) (xy 351.487942 -55.753067) (xy 351.439743 -55.731937) (xy 351.394899 -55.704394)
			(xy 351.354259 -55.670958) (xy 351.336102 -55.651908) (xy 351.32858 -55.644507) (xy 351.3093 -55.635982)
			(xy 351.298764 -55.635398) (xy 351.224088 -55.635398) (xy 351.213536 -55.635908) (xy 351.194241 -55.644457)
			(xy 351.18675 -55.651908) (xy 351.168613 -55.670982) (xy 351.127979 -55.704437) (xy 351.083135 -55.731994)
			(xy 351.034931 -55.753129) (xy 350.98428 -55.767442) (xy 350.932143 -55.774662) (xy 350.905826 -55.775098)
			(xy 350.878571 -55.774657) (xy 350.824616 -55.766903) (xy 350.772314 -55.751549) (xy 350.722729 -55.728907)
			(xy 350.676871 -55.699439) (xy 350.635674 -55.663744) (xy 350.599977 -55.62255) (xy 350.570506 -55.576694)
			(xy 350.547861 -55.527111) (xy 350.532503 -55.474809) (xy 350.524745 -55.420855) (xy 344.991944 -55.420855)
			(xy 344.991944 -57.48528) (xy 352.906074 -57.48528) (xy 352.910145 -57.429658) (xy 352.922271 -57.375221)
			(xy 352.942194 -57.32313) (xy 352.96949 -57.274495) (xy 353.003576 -57.230352) (xy 353.043725 -57.191643)
			(xy 353.089083 -57.159192) (xy 353.138683 -57.133691) (xy 353.191467 -57.115684) (xy 353.24631 -57.105554)
			(xy 353.302044 -57.103517) (xy 353.357481 -57.109617) (xy 353.411438 -57.123723) (xy 353.462767 -57.145535)
			(xy 353.510373 -57.174589) (xy 353.553241 -57.210264) (xy 353.590458 -57.251801) (xy 353.621231 -57.298314)
			(xy 353.644903 -57.348811) (xy 353.660971 -57.402218) (xy 353.669091 -57.457394) (xy 353.6696 -57.48528)
			(xy 353.669091 -57.513166) (xy 353.660971 -57.568342) (xy 353.644903 -57.621749) (xy 353.621231 -57.672246)
			(xy 353.590458 -57.718759) (xy 353.553241 -57.760296) (xy 353.510373 -57.795971) (xy 353.462767 -57.825025)
			(xy 353.411438 -57.846837) (xy 353.357481 -57.860943) (xy 353.302044 -57.867043) (xy 353.24631 -57.865006)
			(xy 353.191467 -57.854876) (xy 353.138683 -57.836869) (xy 353.089083 -57.811368) (xy 353.043725 -57.778917)
			(xy 353.003576 -57.740208) (xy 352.96949 -57.696065) (xy 352.942194 -57.64743) (xy 352.922271 -57.595339)
			(xy 352.910145 -57.540902) (xy 352.906074 -57.48528) (xy 344.991944 -57.48528) (xy 344.991944 -58.076084)
			(xy 353.658168 -58.076084) (xy 353.662239 -58.020462) (xy 353.674365 -57.966025) (xy 353.694288 -57.913934)
			(xy 353.721584 -57.865299) (xy 353.75567 -57.821156) (xy 353.795819 -57.782447) (xy 353.841177 -57.749996)
			(xy 353.890777 -57.724495) (xy 353.943561 -57.706488) (xy 353.998404 -57.696358) (xy 354.054138 -57.694321)
			(xy 354.109575 -57.700421) (xy 354.163532 -57.714527) (xy 354.214861 -57.736339) (xy 354.262467 -57.765393)
			(xy 354.305335 -57.801068) (xy 354.342552 -57.842605) (xy 354.358888 -57.867296) (xy 355.943152 -57.867296)
			(xy 355.947223 -57.811674) (xy 355.959349 -57.757237) (xy 355.979272 -57.705146) (xy 356.006568 -57.656511)
			(xy 356.040654 -57.612368) (xy 356.080803 -57.573659) (xy 356.126161 -57.541208) (xy 356.175761 -57.515707)
			(xy 356.228545 -57.4977) (xy 356.283388 -57.48757) (xy 356.339122 -57.485533) (xy 356.394559 -57.491633)
			(xy 356.448516 -57.505739) (xy 356.499845 -57.527551) (xy 356.547451 -57.556605) (xy 356.590319 -57.59228)
			(xy 356.627536 -57.633817) (xy 356.658309 -57.68033) (xy 356.681981 -57.730827) (xy 356.698049 -57.784234)
			(xy 356.706169 -57.83941) (xy 356.706678 -57.867296) (xy 356.706169 -57.895182) (xy 356.698049 -57.950358)
			(xy 356.681981 -58.003765) (xy 356.658309 -58.054262) (xy 356.627536 -58.100775) (xy 356.590319 -58.142312)
			(xy 356.547451 -58.177987) (xy 356.499845 -58.207041) (xy 356.448516 -58.228853) (xy 356.394559 -58.242959)
			(xy 356.339122 -58.249059) (xy 356.283388 -58.247022) (xy 356.228545 -58.236892) (xy 356.175761 -58.218885)
			(xy 356.126161 -58.193384) (xy 356.080803 -58.160933) (xy 356.040654 -58.122224) (xy 356.006568 -58.078081)
			(xy 355.979272 -58.029446) (xy 355.959349 -57.977355) (xy 355.947223 -57.922918) (xy 355.943152 -57.867296)
			(xy 354.358888 -57.867296) (xy 354.373325 -57.889118) (xy 354.396997 -57.939615) (xy 354.413065 -57.993022)
			(xy 354.421185 -58.048198) (xy 354.421694 -58.076084) (xy 354.421185 -58.10397) (xy 354.413065 -58.159146)
			(xy 354.396997 -58.212553) (xy 354.373325 -58.26305) (xy 354.342552 -58.309563) (xy 354.305335 -58.3511)
			(xy 354.262467 -58.386775) (xy 354.214861 -58.415829) (xy 354.163532 -58.437641) (xy 354.109575 -58.451747)
			(xy 354.054138 -58.457847) (xy 353.998404 -58.45581) (xy 353.943561 -58.44568) (xy 353.890777 -58.427673)
			(xy 353.841177 -58.402172) (xy 353.795819 -58.369721) (xy 353.75567 -58.331012) (xy 353.721584 -58.286869)
			(xy 353.694288 -58.238234) (xy 353.674365 -58.186143) (xy 353.662239 -58.131706) (xy 353.658168 -58.076084)
			(xy 344.991944 -58.076084) (xy 344.991944 -58.561224) (xy 354.862382 -58.561224) (xy 354.866453 -58.505602)
			(xy 354.878579 -58.451165) (xy 354.898502 -58.399074) (xy 354.925798 -58.350439) (xy 354.959884 -58.306296)
			(xy 355.000033 -58.267587) (xy 355.045391 -58.235136) (xy 355.094991 -58.209635) (xy 355.147775 -58.191628)
			(xy 355.202618 -58.181498) (xy 355.258352 -58.179461) (xy 355.313789 -58.185561) (xy 355.367746 -58.199667)
			(xy 355.419075 -58.221479) (xy 355.466681 -58.250533) (xy 355.509549 -58.286208) (xy 355.546766 -58.327745)
			(xy 355.577539 -58.374258) (xy 355.601211 -58.424755) (xy 355.608721 -58.449718) (xy 357.109012 -58.449718)
			(xy 357.113083 -58.394096) (xy 357.125209 -58.339659) (xy 357.145132 -58.287568) (xy 357.172428 -58.238933)
			(xy 357.206514 -58.19479) (xy 357.246663 -58.156081) (xy 357.292021 -58.12363) (xy 357.341621 -58.098129)
			(xy 357.394405 -58.080122) (xy 357.449248 -58.069992) (xy 357.504982 -58.067955) (xy 357.560419 -58.074055)
			(xy 357.614376 -58.088161) (xy 357.665705 -58.109973) (xy 357.713311 -58.139027) (xy 357.756179 -58.174702)
			(xy 357.793396 -58.216239) (xy 357.824169 -58.262752) (xy 357.847841 -58.313249) (xy 357.863909 -58.366656)
			(xy 357.872029 -58.421832) (xy 357.872538 -58.449718) (xy 357.872029 -58.477604) (xy 357.863909 -58.53278)
			(xy 357.847841 -58.586187) (xy 357.824169 -58.636684) (xy 357.793396 -58.683197) (xy 357.756179 -58.724734)
			(xy 357.713311 -58.760409) (xy 357.665705 -58.789463) (xy 357.614376 -58.811275) (xy 357.560419 -58.825381)
			(xy 357.504982 -58.831481) (xy 357.449248 -58.829444) (xy 357.394405 -58.819314) (xy 357.341621 -58.801307)
			(xy 357.292021 -58.775806) (xy 357.246663 -58.743355) (xy 357.206514 -58.704646) (xy 357.172428 -58.660503)
			(xy 357.145132 -58.611868) (xy 357.125209 -58.559777) (xy 357.113083 -58.50534) (xy 357.109012 -58.449718)
			(xy 355.608721 -58.449718) (xy 355.617279 -58.478162) (xy 355.625399 -58.533338) (xy 355.625908 -58.561224)
			(xy 355.625399 -58.58911) (xy 355.617279 -58.644286) (xy 355.601211 -58.697693) (xy 355.577539 -58.74819)
			(xy 355.546766 -58.794703) (xy 355.509549 -58.83624) (xy 355.466681 -58.871915) (xy 355.419075 -58.900969)
			(xy 355.367746 -58.922781) (xy 355.313789 -58.936887) (xy 355.258352 -58.942987) (xy 355.202618 -58.94095)
			(xy 355.147775 -58.93082) (xy 355.094991 -58.912813) (xy 355.045391 -58.887312) (xy 355.000033 -58.854861)
			(xy 354.959884 -58.816152) (xy 354.925798 -58.772009) (xy 354.898502 -58.723374) (xy 354.878579 -58.671283)
			(xy 354.866453 -58.616846) (xy 354.862382 -58.561224) (xy 344.991944 -58.561224) (xy 344.991944 -59.174634)
			(xy 353.393246 -59.174634) (xy 353.397317 -59.119012) (xy 353.409443 -59.064575) (xy 353.429366 -59.012484)
			(xy 353.456662 -58.963849) (xy 353.490748 -58.919706) (xy 353.530897 -58.880997) (xy 353.576255 -58.848546)
			(xy 353.625855 -58.823045) (xy 353.678639 -58.805038) (xy 353.733482 -58.794908) (xy 353.789216 -58.792871)
			(xy 353.844653 -58.798971) (xy 353.89861 -58.813077) (xy 353.949939 -58.834889) (xy 353.997545 -58.863943)
			(xy 354.040413 -58.899618) (xy 354.07763 -58.941155) (xy 354.108403 -58.987668) (xy 354.132075 -59.038165)
			(xy 354.148143 -59.091572) (xy 354.156263 -59.146748) (xy 354.156772 -59.174634) (xy 354.156263 -59.20252)
			(xy 354.148143 -59.257696) (xy 354.132075 -59.311103) (xy 354.108403 -59.3616) (xy 354.07763 -59.408113)
			(xy 354.040413 -59.44965) (xy 353.997545 -59.485325) (xy 353.949939 -59.514379) (xy 353.89861 -59.536191)
			(xy 353.844653 -59.550297) (xy 353.789216 -59.556397) (xy 353.733482 -59.55436) (xy 353.678639 -59.54423)
			(xy 353.625855 -59.526223) (xy 353.576255 -59.500722) (xy 353.530897 -59.468271) (xy 353.490748 -59.429562)
			(xy 353.456662 -59.385419) (xy 353.429366 -59.336784) (xy 353.409443 -59.284693) (xy 353.397317 -59.230256)
			(xy 353.393246 -59.174634) (xy 344.991944 -59.174634) (xy 344.991944 -60.633356) (xy 356.097076 -60.633356)
			(xy 356.101147 -60.577734) (xy 356.113273 -60.523297) (xy 356.133196 -60.471206) (xy 356.160492 -60.422571)
			(xy 356.194578 -60.378428) (xy 356.234727 -60.339719) (xy 356.280085 -60.307268) (xy 356.329685 -60.281767)
			(xy 356.382469 -60.26376) (xy 356.437312 -60.25363) (xy 356.493046 -60.251593) (xy 356.548483 -60.257693)
			(xy 356.60244 -60.271799) (xy 356.653769 -60.293611) (xy 356.701375 -60.322665) (xy 356.744243 -60.35834)
			(xy 356.78146 -60.399877) (xy 356.812233 -60.44639) (xy 356.835905 -60.496887) (xy 356.851973 -60.550294)
			(xy 356.860093 -60.60547) (xy 356.860602 -60.633356) (xy 356.860093 -60.661242) (xy 356.851973 -60.716418)
			(xy 356.835905 -60.769825) (xy 356.812233 -60.820322) (xy 356.78146 -60.866835) (xy 356.744243 -60.908372)
			(xy 356.701375 -60.944047) (xy 356.653769 -60.973101) (xy 356.60244 -60.994913) (xy 356.548483 -61.009019)
			(xy 356.493046 -61.015119) (xy 356.437312 -61.013082) (xy 356.382469 -61.002952) (xy 356.329685 -60.984945)
			(xy 356.280085 -60.959444) (xy 356.234727 -60.926993) (xy 356.194578 -60.888284) (xy 356.160492 -60.844141)
			(xy 356.133196 -60.795506) (xy 356.113273 -60.743415) (xy 356.101147 -60.688978) (xy 356.097076 -60.633356)
			(xy 344.991944 -60.633356) (xy 344.991944 -61.487812) (xy 354.604572 -61.487812) (xy 354.608643 -61.43219)
			(xy 354.620769 -61.377753) (xy 354.640692 -61.325662) (xy 354.667988 -61.277027) (xy 354.702074 -61.232884)
			(xy 354.742223 -61.194175) (xy 354.787581 -61.161724) (xy 354.837181 -61.136223) (xy 354.889965 -61.118216)
			(xy 354.944808 -61.108086) (xy 355.000542 -61.106049) (xy 355.055979 -61.112149) (xy 355.109936 -61.126255)
			(xy 355.161265 -61.148067) (xy 355.208871 -61.177121) (xy 355.251739 -61.212796) (xy 355.288956 -61.254333)
			(xy 355.319729 -61.300846) (xy 355.343401 -61.351343) (xy 355.359469 -61.40475) (xy 355.367589 -61.459926)
			(xy 355.368098 -61.487812) (xy 355.367589 -61.515698) (xy 355.359469 -61.570874) (xy 355.343401 -61.624281)
			(xy 355.319729 -61.674778) (xy 355.288956 -61.721291) (xy 355.251739 -61.762828) (xy 355.208871 -61.798503)
			(xy 355.161265 -61.827557) (xy 355.109936 -61.849369) (xy 355.055979 -61.863475) (xy 355.000542 -61.869575)
			(xy 354.944808 -61.867538) (xy 354.889965 -61.857408) (xy 354.837181 -61.839401) (xy 354.787581 -61.8139)
			(xy 354.742223 -61.781449) (xy 354.702074 -61.74274) (xy 354.667988 -61.698597) (xy 354.640692 -61.649962)
			(xy 354.620769 -61.597871) (xy 354.608643 -61.543434) (xy 354.604572 -61.487812) (xy 344.991944 -61.487812)
			(xy 344.991944 -62.121034) (xy 352.542346 -62.121034) (xy 352.546417 -62.065412) (xy 352.558543 -62.010975)
			(xy 352.578466 -61.958884) (xy 352.605762 -61.910249) (xy 352.639848 -61.866106) (xy 352.679997 -61.827397)
			(xy 352.725355 -61.794946) (xy 352.774955 -61.769445) (xy 352.827739 -61.751438) (xy 352.882582 -61.741308)
			(xy 352.938316 -61.739271) (xy 352.993753 -61.745371) (xy 353.04771 -61.759477) (xy 353.099039 -61.781289)
			(xy 353.146645 -61.810343) (xy 353.189513 -61.846018) (xy 353.22673 -61.887555) (xy 353.257503 -61.934068)
			(xy 353.281175 -61.984565) (xy 353.297243 -62.037972) (xy 353.305363 -62.093148) (xy 353.305872 -62.121034)
			(xy 353.305363 -62.14892) (xy 353.297243 -62.204096) (xy 353.281175 -62.257503) (xy 353.257503 -62.308)
			(xy 353.22673 -62.354513) (xy 353.189513 -62.39605) (xy 353.146645 -62.431725) (xy 353.099039 -62.460779)
			(xy 353.04771 -62.482591) (xy 352.993753 -62.496697) (xy 352.938316 -62.502797) (xy 352.882582 -62.50076)
			(xy 352.827739 -62.49063) (xy 352.774955 -62.472623) (xy 352.725355 -62.447122) (xy 352.679997 -62.414671)
			(xy 352.639848 -62.375962) (xy 352.605762 -62.331819) (xy 352.578466 -62.283184) (xy 352.558543 -62.231093)
			(xy 352.546417 -62.176656) (xy 352.542346 -62.121034) (xy 344.991944 -62.121034) (xy 344.991944 -62.678772)
			(xy 355.966272 -62.678772) (xy 355.974025 -62.624824) (xy 355.989377 -62.572528) (xy 356.012015 -62.52295)
			(xy 356.041478 -62.477097) (xy 356.077166 -62.435905) (xy 356.118354 -62.400211) (xy 356.164202 -62.370741)
			(xy 356.213777 -62.348096) (xy 356.26607 -62.332737) (xy 356.320017 -62.324976) (xy 356.347268 -62.324488)
			(xy 356.370823 -62.324856) (xy 356.417567 -62.330721) (xy 356.440486 -62.336172) (xy 356.454255 -62.339149)
			(xy 356.4824 -62.338306) (xy 356.509246 -62.329811) (xy 356.532752 -62.31431) (xy 356.551133 -62.292979)
			(xy 356.562992 -62.26744) (xy 356.567427 -62.239634) (xy 356.564103 -62.211673) (xy 356.559104 -62.198504)
			(xy 356.549791 -62.175116) (xy 356.536667 -62.126514) (xy 356.530045 -62.076609) (xy 356.52964 -62.051438)
			(xy 356.530037 -62.024184) (xy 356.537789 -61.970231) (xy 356.55314 -61.917929) (xy 356.575778 -61.868345)
			(xy 356.605243 -61.822487) (xy 356.640933 -61.78129) (xy 356.682124 -61.74559) (xy 356.727975 -61.716117)
			(xy 356.777555 -61.693468) (xy 356.829853 -61.678106) (xy 356.883805 -61.670343) (xy 356.938313 -61.670337)
			(xy 356.992266 -61.678088) (xy 357.044568 -61.693439) (xy 357.094152 -61.716077) (xy 357.14001 -61.745541)
			(xy 357.181208 -61.781231) (xy 357.216908 -61.822421) (xy 357.246382 -61.868273) (xy 357.269031 -61.917852)
			(xy 357.284393 -61.97015) (xy 357.292157 -62.024102) (xy 357.292163 -62.078609) (xy 357.284412 -62.132563)
			(xy 357.269062 -62.184864) (xy 357.246425 -62.234449) (xy 357.216961 -62.280307) (xy 357.181271 -62.321506)
			(xy 357.140082 -62.357206) (xy 357.09423 -62.38668) (xy 357.044651 -62.40933) (xy 356.992354 -62.424693)
			(xy 356.938402 -62.432457) (xy 356.911148 -62.432946) (xy 356.887593 -62.432575) (xy 356.840849 -62.426712)
			(xy 356.81793 -62.421262) (xy 356.804165 -62.418255) (xy 356.776013 -62.419093) (xy 356.749159 -62.427588)
			(xy 356.725647 -62.443094) (xy 356.707262 -62.464431) (xy 356.695404 -62.489978) (xy 356.690974 -62.517792)
			(xy 356.694308 -62.545759) (xy 356.699312 -62.55893) (xy 356.708637 -62.582314) (xy 356.721756 -62.630918)
			(xy 356.728373 -62.680824) (xy 356.728776 -62.705996) (xy 356.728327 -62.733247) (xy 356.720571 -62.787195)
			(xy 356.705216 -62.839489) (xy 356.682576 -62.889067) (xy 356.653111 -62.934918) (xy 356.617421 -62.976108)
			(xy 356.576231 -63.011801) (xy 356.530382 -63.041268) (xy 356.480806 -63.06391) (xy 356.428512 -63.079267)
			(xy 356.374564 -63.087025) (xy 356.320062 -63.087027) (xy 356.266114 -63.079273) (xy 356.213819 -63.06392)
			(xy 356.164241 -63.041281) (xy 356.11839 -63.011817) (xy 356.077198 -62.976127) (xy 356.041505 -62.934939)
			(xy 356.012037 -62.88909) (xy 355.989393 -62.839514) (xy 355.974035 -62.787221) (xy 355.966275 -62.733274)
			(xy 355.966272 -62.678772) (xy 344.991944 -62.678772) (xy 344.991944 -63.086234) (xy 349.68764 -63.086234)
			(xy 349.691711 -63.030612) (xy 349.703837 -62.976175) (xy 349.72376 -62.924084) (xy 349.751056 -62.875449)
			(xy 349.785142 -62.831306) (xy 349.825291 -62.792597) (xy 349.870649 -62.760146) (xy 349.920249 -62.734645)
			(xy 349.973033 -62.716638) (xy 350.027876 -62.706508) (xy 350.08361 -62.704471) (xy 350.139047 -62.710571)
			(xy 350.193004 -62.724677) (xy 350.244333 -62.746489) (xy 350.291939 -62.775543) (xy 350.334807 -62.811218)
			(xy 350.372024 -62.852755) (xy 350.402797 -62.899268) (xy 350.426469 -62.949765) (xy 350.442537 -63.003172)
			(xy 350.450657 -63.058348) (xy 350.451166 -63.086234) (xy 350.450657 -63.11412) (xy 350.442537 -63.169296)
			(xy 350.426469 -63.222703) (xy 350.402797 -63.2732) (xy 350.402644 -63.273432) (xy 351.876866 -63.273432)
			(xy 351.880937 -63.21781) (xy 351.893063 -63.163373) (xy 351.912986 -63.111282) (xy 351.940282 -63.062647)
			(xy 351.974368 -63.018504) (xy 352.014517 -62.979795) (xy 352.059875 -62.947344) (xy 352.109475 -62.921843)
			(xy 352.162259 -62.903836) (xy 352.217102 -62.893706) (xy 352.272836 -62.891669) (xy 352.328273 -62.897769)
			(xy 352.38223 -62.911875) (xy 352.433559 -62.933687) (xy 352.481165 -62.962741) (xy 352.524033 -62.998416)
			(xy 352.56125 -63.039953) (xy 352.592023 -63.086466) (xy 352.615695 -63.136963) (xy 352.631763 -63.19037)
			(xy 352.639883 -63.245546) (xy 352.640392 -63.273432) (xy 352.639883 -63.301318) (xy 352.631763 -63.356494)
			(xy 352.615695 -63.409901) (xy 352.592023 -63.460398) (xy 352.56125 -63.506911) (xy 352.524033 -63.548448)
			(xy 352.481165 -63.584123) (xy 352.433559 -63.613177) (xy 352.38223 -63.634989) (xy 352.328273 -63.649095)
			(xy 352.272836 -63.655195) (xy 352.217102 -63.653158) (xy 352.162259 -63.643028) (xy 352.109475 -63.625021)
			(xy 352.059875 -63.59952) (xy 352.014517 -63.567069) (xy 351.974368 -63.52836) (xy 351.940282 -63.484217)
			(xy 351.912986 -63.435582) (xy 351.893063 -63.383491) (xy 351.880937 -63.329054) (xy 351.876866 -63.273432)
			(xy 350.402644 -63.273432) (xy 350.372024 -63.319713) (xy 350.334807 -63.36125) (xy 350.291939 -63.396925)
			(xy 350.244333 -63.425979) (xy 350.193004 -63.447791) (xy 350.139047 -63.461897) (xy 350.08361 -63.467997)
			(xy 350.027876 -63.46596) (xy 349.973033 -63.45583) (xy 349.920249 -63.437823) (xy 349.870649 -63.412322)
			(xy 349.825291 -63.379871) (xy 349.785142 -63.341162) (xy 349.751056 -63.297019) (xy 349.72376 -63.248384)
			(xy 349.703837 -63.196293) (xy 349.691711 -63.141856) (xy 349.68764 -63.086234) (xy 344.991944 -63.086234)
			(xy 344.991944 -65.124076) (xy 354.407468 -65.124076) (xy 354.411539 -65.068454) (xy 354.423665 -65.014017)
			(xy 354.443588 -64.961926) (xy 354.470884 -64.913291) (xy 354.50497 -64.869148) (xy 354.545119 -64.830439)
			(xy 354.590477 -64.797988) (xy 354.640077 -64.772487) (xy 354.692861 -64.75448) (xy 354.747704 -64.74435)
			(xy 354.803438 -64.742313) (xy 354.858875 -64.748413) (xy 354.912832 -64.762519) (xy 354.964161 -64.784331)
			(xy 355.011767 -64.813385) (xy 355.054635 -64.84906) (xy 355.091852 -64.890597) (xy 355.122625 -64.93711)
			(xy 355.146297 -64.987607) (xy 355.162365 -65.041014) (xy 355.170485 -65.09619) (xy 355.170994 -65.124076)
			(xy 355.170485 -65.151962) (xy 355.162365 -65.207138) (xy 355.146297 -65.260545) (xy 355.122625 -65.311042)
			(xy 355.091852 -65.357555) (xy 355.054635 -65.399092) (xy 355.011767 -65.434767) (xy 354.964161 -65.463821)
			(xy 354.912832 -65.485633) (xy 354.858875 -65.499739) (xy 354.803438 -65.505839) (xy 354.747704 -65.503802)
			(xy 354.692861 -65.493672) (xy 354.640077 -65.475665) (xy 354.590477 -65.450164) (xy 354.545119 -65.417713)
			(xy 354.50497 -65.379004) (xy 354.470884 -65.334861) (xy 354.443588 -65.286226) (xy 354.423665 -65.234135)
			(xy 354.411539 -65.179698) (xy 354.407468 -65.124076) (xy 344.991944 -65.124076) (xy 344.991944 -75.299062)
			(xy 344.99238 -75.309126) (xy 345.000115 -75.32771) (xy 345.00693 -75.33513) (xy 347.355414 -77.683614)
			(xy 347.362809 -77.690468) (xy 347.381408 -77.69821) (xy 347.391482 -77.6986) (xy 350.0501 -77.6986)
			(xy 350.053656 -77.698092) (xy 350.074874 -77.695217) (xy 350.117588 -77.69217) (xy 350.139 -77.691996)
			(xy 352.639122 -77.691996) (xy 352.64919 -77.691569) (xy 352.667789 -77.683848) (xy 352.67519 -77.67701)
			(xy 360.04627 -70.30593) (xy 360.053109 -70.298529) (xy 360.060822 -70.279931) (xy 360.061256 -70.269862)
			(xy 360.061256 -41.973754) (xy 360.061274 -41.960211) (xy 360.062418 -41.933149) (xy 360.063542 -41.919652)
			(xy 360.063796 -41.916604) (xy 360.065576 -41.879515) (xy 360.077249 -41.806184) (xy 360.098014 -41.734892)
			(xy 360.127542 -41.666761) (xy 360.16537 -41.602864) (xy 360.210901 -41.544207) (xy 360.23677 -41.51757)
			(xy 363.671358 -38.082982) (xy 363.678724 -38.069266) (xy 363.679994 -38.061646) (xy 363.686894 -38.026466)
			(xy 363.708094 -37.957981) (xy 363.737415 -37.892559) (xy 363.774428 -37.831161) (xy 363.81859 -37.774685)
			(xy 363.84357 -37.748972) (xy 364.19409 -37.398452) (xy 364.21979 -37.373491) (xy 364.276205 -37.329324)
			(xy 364.337547 -37.292306) (xy 364.402917 -37.262979) (xy 364.471353 -37.241775) (xy 364.50651 -37.234876)
			(xy 364.533434 -37.220906) (xy 364.539784 -37.214556) (xy 364.546048 -37.177689) (xy 364.566669 -37.105806)
			(xy 364.596185 -37.037096) (xy 364.634127 -36.972654) (xy 364.679888 -36.913508) (xy 364.7059 -36.886642)
			(xy 365.05642 -36.536122) (xy 365.081062 -36.512155) (xy 365.134982 -36.469514) (xy 365.193491 -36.433425)
			(xy 365.255795 -36.404376) (xy 365.321051 -36.382759) (xy 365.354616 -36.37534) (xy 365.374936 -36.371022)
			(xy 365.389922 -36.361878) (xy 365.395256 -36.355274) (xy 365.395256 -36.0299) (xy 365.386112 -36.000944)
			(xy 365.366153 -35.971229) (xy 365.332787 -35.907896) (xy 365.307326 -35.840992) (xy 365.290144 -35.7715)
			(xy 365.281492 -35.70044) (xy 365.280956 -35.664648) (xy 365.280956 -35.16884) (xy 365.281464 -35.142424)
			(xy 365.28121 -35.136836) (xy 365.280702 -35.128708) (xy 365.280702 -35.125152) (xy 365.279432 -35.087052)
			(xy 365.279432 -34.643314) (xy 365.279715 -34.619581) (xy 365.283654 -34.572278) (xy 365.287306 -34.548826)
			(xy 365.287306 -34.533078) (xy 365.284285 -34.511234) (xy 365.281106 -34.467246) (xy 365.280956 -34.445194)
			(xy 365.280956 -33.992058) (xy 365.280702 -33.98901) (xy 365.280702 -33.988756) (xy 365.279432 -33.950402)
			(xy 365.279432 -33.50641) (xy 365.279913 -33.473351) (xy 365.287428 -33.407661) (xy 365.294418 -33.375346)
			(xy 365.295688 -33.363662) (xy 365.294672 -33.352994) (xy 365.288285 -33.321889) (xy 365.281414 -33.25876)
			(xy 365.280956 -33.22701) (xy 365.280956 -32.854646) (xy 365.280702 -32.851598) (xy 365.280702 -32.851344)
			(xy 365.279432 -32.81299) (xy 365.279432 -32.369252) (xy 365.280223 -32.326786) (xy 365.292589 -32.242758)
			(xy 365.30407 -32.201866) (xy 365.306356 -32.193992) (xy 365.306356 -32.17926) (xy 365.304324 -32.172148)
			(xy 365.293353 -32.131695) (xy 365.28163 -32.048703) (xy 365.280956 -32.006794) (xy 365.280956 -31.717234)
			(xy 365.280702 -31.714186) (xy 365.280702 -31.713932) (xy 365.279432 -31.675578) (xy 365.279432 -31.23184)
			(xy 365.280224 -31.189374) (xy 365.292592 -31.105347) (xy 365.30407 -31.064454) (xy 365.30915 -31.04769)
			(xy 365.30915 -31.047436) (xy 365.31042 -31.04388) (xy 365.310674 -31.043118) (xy 365.311182 -31.041848)
			(xy 365.314738 -31.031942) (xy 365.31677 -31.026608) (xy 365.319646 -31.017958) (xy 365.319771 -30.999741)
			(xy 365.317024 -30.991048) (xy 365.305596 -30.958404) (xy 365.289556 -30.891123) (xy 365.281472 -30.822431)
			(xy 365.280956 -30.787848) (xy 365.280956 -30.579822) (xy 365.280702 -30.576774) (xy 365.280702 -30.57652)
			(xy 365.279432 -30.538166) (xy 365.279432 -30.094428) (xy 365.280225 -30.051962) (xy 365.292594 -29.967936)
			(xy 365.30407 -29.927042) (xy 365.30915 -29.910278) (xy 365.30915 -29.910024) (xy 365.31042 -29.906468)
			(xy 365.310674 -29.905706) (xy 365.311182 -29.904436) (xy 365.314738 -29.89453) (xy 365.319074 -29.88299)
			(xy 365.3286 -29.860248) (xy 365.333788 -29.849064) (xy 365.342424 -29.831284) (xy 365.327777 -29.800673)
			(xy 365.304798 -29.736818) (xy 365.289284 -29.670751) (xy 365.281441 -29.603341) (xy 365.280956 -29.56941)
			(xy 365.280956 -29.44241) (xy 365.280702 -29.439362) (xy 365.280702 -29.439108) (xy 365.279432 -29.400754)
			(xy 365.279432 -28.957016) (xy 365.280226 -28.91455) (xy 365.292597 -28.830524) (xy 365.30407 -28.78963)
			(xy 365.30915 -28.772866) (xy 365.30915 -28.772612) (xy 365.31042 -28.769056) (xy 365.310674 -28.768294)
			(xy 365.311182 -28.767024) (xy 365.314738 -28.757118) (xy 365.319075 -28.745578) (xy 365.328601 -28.722836)
			(xy 365.333788 -28.711652) (xy 365.35106 -28.677362) (xy 365.35741 -28.652978) (xy 365.351314 -28.629102)
			(xy 365.334561 -28.596788) (xy 365.308251 -28.52892) (xy 365.290482 -28.458333) (xy 365.281523 -28.386097)
			(xy 365.280956 -28.349702) (xy 365.280956 -28.304998) (xy 365.280702 -28.30195) (xy 365.280702 -28.301696)
			(xy 365.279432 -28.263342) (xy 365.279432 -27.992578) (xy 365.279025 -27.983299) (xy 365.27237 -27.965977)
			(xy 365.266478 -27.958796) (xy 365.24819 -27.937968) (xy 365.246666 -27.936698) (xy 365.24565 -27.935682)
			(xy 365.242348 -27.932634) (xy 365.223806 -27.930856) (xy 365.190527 -27.927127) (xy 365.125043 -27.913104)
			(xy 365.061565 -27.891764) (xy 365.000907 -27.863384) (xy 364.943848 -27.828326) (xy 364.891119 -27.78704)
			(xy 364.843398 -27.740057) (xy 364.801295 -27.687978) (xy 364.765352 -27.631473) (xy 364.736029 -27.571265)
			(xy 364.713703 -27.508127) (xy 364.69866 -27.44287) (xy 364.691093 -27.37633) (xy 364.69066 -27.342846)
			(xy 364.69066 -27.342338) (xy 364.69111 -27.310077) (xy 364.698175 -27.245941) (xy 364.712182 -27.182956)
			(xy 364.732964 -27.121871) (xy 364.760273 -27.063412) (xy 364.793785 -27.008274) (xy 364.813088 -26.98242)
			(xy 364.818168 -26.975816) (xy 364.823756 -26.960068) (xy 364.823756 -26.864056) (xy 364.821978 -26.850848)
			(xy 364.813088 -26.839672) (xy 364.793761 -26.813834) (xy 364.760232 -26.758702) (xy 364.732915 -26.700242)
			(xy 364.712135 -26.639151) (xy 364.698141 -26.57616) (xy 364.691099 -26.512018) (xy 364.69066 -26.479754)
			(xy 364.69066 -26.479246) (xy 364.691196 -26.443535) (xy 364.699798 -26.372632) (xy 364.716882 -26.303282)
			(xy 364.742198 -26.236497) (xy 364.775379 -26.173249) (xy 364.81594 -26.114461) (xy 364.86329 -26.06099)
			(xy 364.916739 -26.013614) (xy 364.975507 -25.973025) (xy 365.038739 -25.939814) (xy 365.105513 -25.914466)
			(xy 365.174854 -25.897349) (xy 365.245753 -25.888713) (xy 365.281464 -25.888188) (xy 365.314626 -25.888667)
			(xy 365.380531 -25.896119) (xy 365.445187 -25.910901) (xy 365.507783 -25.932826) (xy 365.567532 -25.961619)
			(xy 365.623683 -25.996919) (xy 365.675531 -26.038281) (xy 365.699294 -26.061416) (xy 365.802164 -26.164286)
			(xy 365.809565 -26.171124) (xy 365.828164 -26.178837) (xy 365.838232 -26.179272) (xy 365.910622 -26.179272)
			(xy 365.943777 -26.179737) (xy 366.009669 -26.187159) (xy 366.074318 -26.201907) (xy 366.13691 -26.223796)
			(xy 366.19666 -26.252551) (xy 366.252818 -26.287811) (xy 366.304677 -26.329133) (xy 366.328452 -26.352246)
			(xy 366.337088 -26.360882) (xy 367.389662 -26.360882) (xy 367.393733 -26.30526) (xy 367.405859 -26.250823)
			(xy 367.425782 -26.198732) (xy 367.453078 -26.150097) (xy 367.487164 -26.105954) (xy 367.527313 -26.067245)
			(xy 367.572671 -26.034794) (xy 367.622271 -26.009293) (xy 367.675055 -25.991286) (xy 367.729898 -25.981156)
			(xy 367.785632 -25.979119) (xy 367.841069 -25.985219) (xy 367.895026 -25.999325) (xy 367.946355 -26.021137)
			(xy 367.993961 -26.050191) (xy 368.036829 -26.085866) (xy 368.074046 -26.127403) (xy 368.104819 -26.173916)
			(xy 368.128491 -26.224413) (xy 368.144559 -26.27782) (xy 368.150727 -26.319734) (xy 373.142 -26.319734)
			(xy 373.146071 -26.264112) (xy 373.158197 -26.209675) (xy 373.17812 -26.157584) (xy 373.205416 -26.108949)
			(xy 373.239502 -26.064806) (xy 373.279651 -26.026097) (xy 373.325009 -25.993646) (xy 373.374609 -25.968145)
			(xy 373.427393 -25.950138) (xy 373.482236 -25.940008) (xy 373.53797 -25.937971) (xy 373.593407 -25.944071)
			(xy 373.647364 -25.958177) (xy 373.698693 -25.979989) (xy 373.746299 -26.009043) (xy 373.775964 -26.03373)
			(xy 379.567946 -26.03373) (xy 379.572017 -25.978108) (xy 379.584143 -25.923671) (xy 379.604066 -25.87158)
			(xy 379.631362 -25.822945) (xy 379.665448 -25.778802) (xy 379.705597 -25.740093) (xy 379.750955 -25.707642)
			(xy 379.800555 -25.682141) (xy 379.853339 -25.664134) (xy 379.908182 -25.654004) (xy 379.963916 -25.651967)
			(xy 380.019353 -25.658067) (xy 380.07331 -25.672173) (xy 380.124639 -25.693985) (xy 380.172245 -25.723039)
			(xy 380.215113 -25.758714) (xy 380.25233 -25.800251) (xy 380.283103 -25.846764) (xy 380.306775 -25.897261)
			(xy 380.322843 -25.950668) (xy 380.330963 -26.005844) (xy 380.331472 -26.03373) (xy 380.330963 -26.061616)
			(xy 380.322843 -26.116792) (xy 380.306775 -26.170199) (xy 380.283103 -26.220696) (xy 380.252869 -26.266394)
			(xy 382.820672 -26.266394) (xy 382.821158 -26.239143) (xy 382.828914 -26.185195) (xy 382.844269 -26.1329)
			(xy 382.866911 -26.083323) (xy 382.896377 -26.037473) (xy 382.932068 -25.996282) (xy 382.973259 -25.960591)
			(xy 383.019109 -25.931125) (xy 383.068686 -25.908483) (xy 383.120981 -25.893128) (xy 383.174929 -25.885372)
			(xy 383.229431 -25.885372) (xy 383.283379 -25.893128) (xy 383.335674 -25.908483) (xy 383.385251 -25.931125)
			(xy 383.431101 -25.960591) (xy 383.472292 -25.996282) (xy 383.507983 -26.037473) (xy 383.537449 -26.083323)
			(xy 383.560091 -26.1329) (xy 383.575446 -26.185195) (xy 383.583202 -26.239143) (xy 383.583688 -26.266394)
			(xy 383.583141 -26.295882) (xy 383.574046 -26.354153) (xy 383.556087 -26.410329) (xy 383.529693 -26.463069)
			(xy 383.495493 -26.511117) (xy 383.454303 -26.553326) (xy 383.431034 -26.571448) (xy 383.419887 -26.580314)
			(xy 383.402711 -26.603025) (xy 383.39247 -26.629594) (xy 383.389959 -26.657958) (xy 383.395372 -26.685913)
			(xy 383.40829 -26.711289) (xy 383.427708 -26.732114) (xy 383.43967 -26.73985) (xy 383.4634 -26.754766)
			(xy 383.506636 -26.790428) (xy 383.54419 -26.832033) (xy 383.575251 -26.878686) (xy 383.599152 -26.929381)
			(xy 383.615378 -26.983027) (xy 383.623579 -27.038471) (xy 383.624074 -27.066494) (xy 383.623588 -27.093745)
			(xy 383.615832 -27.147693) (xy 383.600477 -27.199988) (xy 383.577835 -27.249565) (xy 383.548369 -27.295415)
			(xy 383.512678 -27.336606) (xy 383.471487 -27.372297) (xy 383.425637 -27.401763) (xy 383.37606 -27.424405)
			(xy 383.323765 -27.43976) (xy 383.269817 -27.447516) (xy 383.215315 -27.447516) (xy 383.161367 -27.43976)
			(xy 383.109072 -27.424405) (xy 383.059495 -27.401763) (xy 383.013645 -27.372297) (xy 382.972454 -27.336606)
			(xy 382.936763 -27.295415) (xy 382.907297 -27.249565) (xy 382.884655 -27.199988) (xy 382.8693 -27.147693)
			(xy 382.861544 -27.093745) (xy 382.861058 -27.066494) (xy 382.861618 -27.037007) (xy 382.870713 -26.978737)
			(xy 382.888671 -26.922563) (xy 382.915063 -26.869823) (xy 382.949259 -26.821775) (xy 382.990445 -26.779564)
			(xy 383.013712 -26.76144) (xy 383.024776 -26.752476) (xy 383.041961 -26.729791) (xy 383.052215 -26.703243)
			(xy 383.05474 -26.674895) (xy 383.049341 -26.646953) (xy 383.036437 -26.621587) (xy 383.017031 -26.60077)
			(xy 383.005076 -26.593038) (xy 382.981329 -26.57815) (xy 382.938095 -26.542481) (xy 382.900544 -26.50087)
			(xy 382.869486 -26.454213) (xy 382.845588 -26.403514) (xy 382.829365 -26.349864) (xy 382.821166 -26.294418)
			(xy 382.820672 -26.266394) (xy 380.252869 -26.266394) (xy 380.25233 -26.267209) (xy 380.215113 -26.308746)
			(xy 380.172245 -26.344421) (xy 380.124639 -26.373475) (xy 380.07331 -26.395287) (xy 380.019353 -26.409393)
			(xy 379.963916 -26.415493) (xy 379.908182 -26.413456) (xy 379.853339 -26.403326) (xy 379.800555 -26.385319)
			(xy 379.750955 -26.359818) (xy 379.705597 -26.327367) (xy 379.665448 -26.288658) (xy 379.631362 -26.244515)
			(xy 379.604066 -26.19588) (xy 379.584143 -26.143789) (xy 379.572017 -26.089352) (xy 379.567946 -26.03373)
			(xy 373.775964 -26.03373) (xy 373.789167 -26.044718) (xy 373.826384 -26.086255) (xy 373.857157 -26.132768)
			(xy 373.880829 -26.183265) (xy 373.896897 -26.236672) (xy 373.905017 -26.291848) (xy 373.905526 -26.319734)
			(xy 373.905017 -26.34762) (xy 373.896897 -26.402796) (xy 373.880829 -26.456203) (xy 373.857157 -26.5067)
			(xy 373.826384 -26.553213) (xy 373.789167 -26.59475) (xy 373.746299 -26.630425) (xy 373.698693 -26.659479)
			(xy 373.647364 -26.681291) (xy 373.593407 -26.695397) (xy 373.53797 -26.701497) (xy 373.482236 -26.69946)
			(xy 373.427393 -26.68933) (xy 373.374609 -26.671323) (xy 373.325009 -26.645822) (xy 373.279651 -26.613371)
			(xy 373.239502 -26.574662) (xy 373.205416 -26.530519) (xy 373.17812 -26.481884) (xy 373.158197 -26.429793)
			(xy 373.146071 -26.375356) (xy 373.142 -26.319734) (xy 368.150727 -26.319734) (xy 368.152679 -26.332996)
			(xy 368.153188 -26.360882) (xy 368.152679 -26.388768) (xy 368.144559 -26.443944) (xy 368.128491 -26.497351)
			(xy 368.104819 -26.547848) (xy 368.074046 -26.594361) (xy 368.036829 -26.635898) (xy 367.993961 -26.671573)
			(xy 367.946355 -26.700627) (xy 367.895026 -26.722439) (xy 367.841069 -26.736545) (xy 367.785632 -26.742645)
			(xy 367.729898 -26.740608) (xy 367.675055 -26.730478) (xy 367.622271 -26.712471) (xy 367.572671 -26.68697)
			(xy 367.527313 -26.654519) (xy 367.487164 -26.61581) (xy 367.453078 -26.571667) (xy 367.425782 -26.523032)
			(xy 367.405859 -26.470941) (xy 367.393733 -26.416504) (xy 367.389662 -26.360882) (xy 366.337088 -26.360882)
			(xy 366.68583 -26.709624) (xy 366.708942 -26.733402) (xy 366.750278 -26.785254) (xy 366.785549 -26.841407)
			(xy 366.814313 -26.901157) (xy 366.836206 -26.963751) (xy 366.837915 -26.971244) (xy 369.151152 -26.971244)
			(xy 369.155223 -26.915622) (xy 369.167349 -26.861185) (xy 369.187272 -26.809094) (xy 369.214568 -26.760459)
			(xy 369.248654 -26.716316) (xy 369.288803 -26.677607) (xy 369.334161 -26.645156) (xy 369.383761 -26.619655)
			(xy 369.436545 -26.601648) (xy 369.491388 -26.591518) (xy 369.547122 -26.589481) (xy 369.602559 -26.595581)
			(xy 369.656516 -26.609687) (xy 369.707845 -26.631499) (xy 369.755451 -26.660553) (xy 369.798319 -26.696228)
			(xy 369.835536 -26.737765) (xy 369.866309 -26.784278) (xy 369.889981 -26.834775) (xy 369.906049 -26.888182)
			(xy 369.914169 -26.943358) (xy 369.914678 -26.971244) (xy 369.914169 -26.99913) (xy 369.906049 -27.054306)
			(xy 369.889981 -27.107713) (xy 369.866309 -27.15821) (xy 369.835536 -27.204723) (xy 369.798319 -27.24626)
			(xy 369.755451 -27.281935) (xy 369.707845 -27.310989) (xy 369.656516 -27.332801) (xy 369.602559 -27.346907)
			(xy 369.547122 -27.353007) (xy 369.491388 -27.35097) (xy 369.436545 -27.34084) (xy 369.383761 -27.322833)
			(xy 369.334161 -27.297332) (xy 369.288803 -27.264881) (xy 369.248654 -27.226172) (xy 369.214568 -27.182029)
			(xy 369.187272 -27.133394) (xy 369.167349 -27.081303) (xy 369.155223 -27.026866) (xy 369.151152 -26.971244)
			(xy 366.837915 -26.971244) (xy 366.850954 -27.028402) (xy 366.858372 -27.094298) (xy 366.858804 -27.127454)
			(xy 366.858804 -29.114242) (xy 367.147348 -29.114242) (xy 367.147348 -28.250642) (xy 367.147838 -28.220658)
			(xy 367.155666 -28.161202) (xy 367.171187 -28.103277) (xy 367.194136 -28.047873) (xy 367.22412 -27.995939)
			(xy 367.260626 -27.948363) (xy 367.303031 -27.905958) (xy 367.350607 -27.869452) (xy 367.402541 -27.839468)
			(xy 367.457945 -27.816519) (xy 367.51587 -27.800998) (xy 367.575326 -27.79317) (xy 367.635294 -27.79317)
			(xy 367.69475 -27.800998) (xy 367.752675 -27.816519) (xy 367.808079 -27.839468) (xy 367.860013 -27.869452)
			(xy 367.907589 -27.905958) (xy 367.949994 -27.948363) (xy 367.9865 -27.995939) (xy 368.016484 -28.047873)
			(xy 368.039433 -28.103277) (xy 368.054954 -28.161202) (xy 368.062782 -28.220658) (xy 368.063272 -28.250642)
			(xy 368.063272 -28.469082) (xy 372.052594 -28.469082) (xy 372.056665 -28.41346) (xy 372.068791 -28.359023)
			(xy 372.088714 -28.306932) (xy 372.11601 -28.258297) (xy 372.150096 -28.214154) (xy 372.190245 -28.175445)
			(xy 372.235603 -28.142994) (xy 372.285203 -28.117493) (xy 372.337987 -28.099486) (xy 372.39283 -28.089356)
			(xy 372.448564 -28.087319) (xy 372.504001 -28.093419) (xy 372.557958 -28.107525) (xy 372.609287 -28.129337)
			(xy 372.625343 -28.139136) (xy 376.698 -28.139136) (xy 376.702071 -28.083514) (xy 376.714197 -28.029077)
			(xy 376.73412 -27.976986) (xy 376.761416 -27.928351) (xy 376.795502 -27.884208) (xy 376.835651 -27.845499)
			(xy 376.881009 -27.813048) (xy 376.930609 -27.787547) (xy 376.983393 -27.76954) (xy 377.038236 -27.75941)
			(xy 377.09397 -27.757373) (xy 377.149407 -27.763473) (xy 377.203364 -27.777579) (xy 377.254693 -27.799391)
			(xy 377.302299 -27.828445) (xy 377.345167 -27.86412) (xy 377.382384 -27.905657) (xy 377.413157 -27.95217)
			(xy 377.436829 -28.002667) (xy 377.452897 -28.056074) (xy 377.461017 -28.11125) (xy 377.461526 -28.139136)
			(xy 377.968 -28.139136) (xy 377.972071 -28.083514) (xy 377.984197 -28.029077) (xy 378.00412 -27.976986)
			(xy 378.031416 -27.928351) (xy 378.065502 -27.884208) (xy 378.105651 -27.845499) (xy 378.151009 -27.813048)
			(xy 378.200609 -27.787547) (xy 378.253393 -27.76954) (xy 378.308236 -27.75941) (xy 378.36397 -27.757373)
			(xy 378.419407 -27.763473) (xy 378.473364 -27.777579) (xy 378.524693 -27.799391) (xy 378.572299 -27.828445)
			(xy 378.615167 -27.86412) (xy 378.652384 -27.905657) (xy 378.683157 -27.95217) (xy 378.706829 -28.002667)
			(xy 378.722897 -28.056074) (xy 378.731017 -28.11125) (xy 378.731526 -28.139136) (xy 378.731017 -28.167022)
			(xy 378.722897 -28.222198) (xy 378.706829 -28.275605) (xy 378.683157 -28.326102) (xy 378.652384 -28.372615)
			(xy 378.615167 -28.414152) (xy 378.572299 -28.449827) (xy 378.524693 -28.478881) (xy 378.473364 -28.500693)
			(xy 378.419407 -28.514799) (xy 378.36397 -28.520899) (xy 378.308236 -28.518862) (xy 378.253393 -28.508732)
			(xy 378.200609 -28.490725) (xy 378.151009 -28.465224) (xy 378.105651 -28.432773) (xy 378.065502 -28.394064)
			(xy 378.031416 -28.349921) (xy 378.00412 -28.301286) (xy 377.984197 -28.249195) (xy 377.972071 -28.194758)
			(xy 377.968 -28.139136) (xy 377.461526 -28.139136) (xy 377.461017 -28.167022) (xy 377.452897 -28.222198)
			(xy 377.436829 -28.275605) (xy 377.413157 -28.326102) (xy 377.382384 -28.372615) (xy 377.345167 -28.414152)
			(xy 377.302299 -28.449827) (xy 377.254693 -28.478881) (xy 377.203364 -28.500693) (xy 377.149407 -28.514799)
			(xy 377.09397 -28.520899) (xy 377.038236 -28.518862) (xy 376.983393 -28.508732) (xy 376.930609 -28.490725)
			(xy 376.881009 -28.465224) (xy 376.835651 -28.432773) (xy 376.795502 -28.394064) (xy 376.761416 -28.349921)
			(xy 376.73412 -28.301286) (xy 376.714197 -28.249195) (xy 376.702071 -28.194758) (xy 376.698 -28.139136)
			(xy 372.625343 -28.139136) (xy 372.656893 -28.158391) (xy 372.699761 -28.194066) (xy 372.736978 -28.235603)
			(xy 372.767751 -28.282116) (xy 372.791423 -28.332613) (xy 372.807491 -28.38602) (xy 372.815611 -28.441196)
			(xy 372.81612 -28.469082) (xy 372.815611 -28.496968) (xy 372.807491 -28.552144) (xy 372.791423 -28.605551)
			(xy 372.767751 -28.656048) (xy 372.736978 -28.702561) (xy 372.699761 -28.744098) (xy 372.656893 -28.779773)
			(xy 372.609287 -28.808827) (xy 372.557958 -28.830639) (xy 372.504001 -28.844745) (xy 372.448564 -28.850845)
			(xy 372.39283 -28.848808) (xy 372.337987 -28.838678) (xy 372.285203 -28.820671) (xy 372.235603 -28.79517)
			(xy 372.190245 -28.762719) (xy 372.150096 -28.72401) (xy 372.11601 -28.679867) (xy 372.088714 -28.631232)
			(xy 372.068791 -28.579141) (xy 372.056665 -28.524704) (xy 372.052594 -28.469082) (xy 368.063272 -28.469082)
			(xy 368.063272 -29.114242) (xy 368.063139 -29.12237) (xy 382.907032 -29.12237) (xy 382.907032 -28.25877)
			(xy 382.907522 -28.228802) (xy 382.915345 -28.16938) (xy 382.930858 -28.111487) (xy 382.953794 -28.056114)
			(xy 382.983761 -28.004208) (xy 383.020248 -27.956658) (xy 383.062628 -27.914278) (xy 383.110178 -27.877791)
			(xy 383.162084 -27.847824) (xy 383.217457 -27.824888) (xy 383.27535 -27.809375) (xy 383.334772 -27.801552)
			(xy 383.394708 -27.801552) (xy 383.45413 -27.809375) (xy 383.512023 -27.824888) (xy 383.567396 -27.847824)
			(xy 383.619302 -27.877791) (xy 383.666852 -27.914278) (xy 383.709232 -27.956658) (xy 383.745719 -28.004208)
			(xy 383.775686 -28.056114) (xy 383.798622 -28.111487) (xy 383.814135 -28.16938) (xy 383.821958 -28.228802)
			(xy 383.822448 -28.25877) (xy 383.822448 -29.12237) (xy 383.821958 -29.152338) (xy 383.814135 -29.21176)
			(xy 383.798622 -29.269653) (xy 383.775686 -29.325026) (xy 383.745719 -29.376932) (xy 383.709232 -29.424482)
			(xy 383.666852 -29.466862) (xy 383.619302 -29.503349) (xy 383.567396 -29.533316) (xy 383.512023 -29.556252)
			(xy 383.45413 -29.571765) (xy 383.394708 -29.579588) (xy 383.334772 -29.579588) (xy 383.27535 -29.571765)
			(xy 383.217457 -29.556252) (xy 383.162084 -29.533316) (xy 383.110178 -29.503349) (xy 383.062628 -29.466862)
			(xy 383.020248 -29.424482) (xy 382.983761 -29.376932) (xy 382.953794 -29.325026) (xy 382.930858 -29.269653)
			(xy 382.915345 -29.21176) (xy 382.907522 -29.152338) (xy 382.907032 -29.12237) (xy 368.063139 -29.12237)
			(xy 368.062782 -29.144226) (xy 368.054954 -29.203682) (xy 368.039433 -29.261607) (xy 368.016484 -29.317011)
			(xy 367.9865 -29.368945) (xy 367.949994 -29.416521) (xy 367.907589 -29.458926) (xy 367.860013 -29.495432)
			(xy 367.808079 -29.525416) (xy 367.752675 -29.548365) (xy 367.69475 -29.563886) (xy 367.635294 -29.571714)
			(xy 367.575326 -29.571714) (xy 367.51587 -29.563886) (xy 367.457945 -29.548365) (xy 367.402541 -29.525416)
			(xy 367.350607 -29.495432) (xy 367.303031 -29.458926) (xy 367.260626 -29.416521) (xy 367.22412 -29.368945)
			(xy 367.194136 -29.317011) (xy 367.171187 -29.261607) (xy 367.155666 -29.203682) (xy 367.147838 -29.144226)
			(xy 367.147348 -29.114242) (xy 366.858804 -29.114242) (xy 366.858804 -30.92069) (xy 369.789456 -30.92069)
			(xy 369.789456 -30.05709) (xy 369.789946 -30.027106) (xy 369.797774 -29.96765) (xy 369.813295 -29.909725)
			(xy 369.836244 -29.854321) (xy 369.866228 -29.802387) (xy 369.902734 -29.754811) (xy 369.945139 -29.712406)
			(xy 369.992715 -29.6759) (xy 370.044649 -29.645916) (xy 370.100053 -29.622967) (xy 370.157978 -29.607446)
			(xy 370.217434 -29.599618) (xy 370.277402 -29.599618) (xy 370.336858 -29.607446) (xy 370.394783 -29.622967)
			(xy 370.450187 -29.645916) (xy 370.502121 -29.6759) (xy 370.549697 -29.712406) (xy 370.592102 -29.754811)
			(xy 370.628608 -29.802387) (xy 370.658592 -29.854321) (xy 370.681541 -29.909725) (xy 370.697062 -29.96765)
			(xy 370.70489 -30.027106) (xy 370.70538 -30.05709) (xy 370.70538 -30.376876) (xy 375.188988 -30.376876)
			(xy 375.189528 -30.347959) (xy 375.198248 -30.290788) (xy 375.215499 -30.235588) (xy 375.240887 -30.183625)
			(xy 375.273828 -30.136091) (xy 375.313569 -30.094075) (xy 375.336054 -30.075886) (xy 375.344867 -30.068285)
			(xy 375.355045 -30.047379) (xy 375.355612 -30.035754) (xy 375.355612 -29.955998) (xy 375.355056 -29.944368)
			(xy 375.344879 -29.923459) (xy 375.336054 -29.915866) (xy 375.313545 -29.897706) (xy 375.273813 -29.855678)
			(xy 375.240879 -29.808137) (xy 375.215495 -29.756169) (xy 375.198244 -29.700967) (xy 375.18952 -29.643794)
			(xy 375.188988 -29.614876) (xy 375.189474 -29.587625) (xy 375.19723 -29.533677) (xy 375.212585 -29.481382)
			(xy 375.235227 -29.431805) (xy 375.264693 -29.385955) (xy 375.300384 -29.344764) (xy 375.341575 -29.309073)
			(xy 375.387425 -29.279607) (xy 375.437002 -29.256965) (xy 375.489297 -29.24161) (xy 375.543245 -29.233854)
			(xy 375.597747 -29.233854) (xy 375.651695 -29.24161) (xy 375.70399 -29.256965) (xy 375.753567 -29.279607)
			(xy 375.799417 -29.309073) (xy 375.840608 -29.344764) (xy 375.876299 -29.385955) (xy 375.905765 -29.431805)
			(xy 375.928407 -29.481382) (xy 375.943762 -29.533677) (xy 375.951518 -29.587625) (xy 375.952004 -29.614876)
			(xy 375.951505 -29.643794) (xy 375.942777 -29.700968) (xy 375.925518 -29.756169) (xy 375.900123 -29.808131)
			(xy 375.867174 -29.855664) (xy 375.827427 -29.897678) (xy 375.804938 -29.915866) (xy 375.796146 -29.923487)
			(xy 375.785956 -29.944378) (xy 375.78538 -29.955998) (xy 375.78538 -30.035754) (xy 375.785909 -30.047387)
			(xy 375.796106 -30.068296) (xy 375.804938 -30.075886) (xy 375.827423 -30.094075) (xy 375.867156 -30.136097)
			(xy 375.900094 -30.183632) (xy 375.925482 -30.235594) (xy 375.942738 -30.290791) (xy 375.951468 -30.34796)
			(xy 375.952004 -30.376876) (xy 378.229114 -30.376876) (xy 378.229681 -30.347961) (xy 378.238399 -30.290792)
			(xy 378.255647 -30.235594) (xy 378.28103 -30.183632) (xy 378.313965 -30.136096) (xy 378.353698 -30.094077)
			(xy 378.37618 -30.075886) (xy 378.384997 -30.068289) (xy 378.395172 -30.04738) (xy 378.395738 -30.035754)
			(xy 378.395738 -29.955998) (xy 378.395208 -29.944364) (xy 378.385015 -29.923453) (xy 378.37618 -29.915866)
			(xy 378.353676 -29.897699) (xy 378.313943 -29.855674) (xy 378.281007 -29.808134) (xy 378.255622 -29.756168)
			(xy 378.23837 -29.700966) (xy 378.229646 -29.643793) (xy 378.229114 -29.614876) (xy 378.2296 -29.587625)
			(xy 378.237356 -29.533677) (xy 378.252711 -29.481382) (xy 378.275353 -29.431805) (xy 378.304819 -29.385955)
			(xy 378.34051 -29.344764) (xy 378.381701 -29.309073) (xy 378.427551 -29.279607) (xy 378.477128 -29.256965)
			(xy 378.529423 -29.24161) (xy 378.583371 -29.233854) (xy 378.637873 -29.233854) (xy 378.691821 -29.24161)
			(xy 378.744116 -29.256965) (xy 378.793693 -29.279607) (xy 378.839543 -29.309073) (xy 378.880734 -29.344764)
			(xy 378.916425 -29.385955) (xy 378.945891 -29.431805) (xy 378.968533 -29.481382) (xy 378.983888 -29.533677)
			(xy 378.991644 -29.587625) (xy 378.99213 -29.614876) (xy 378.991621 -29.643794) (xy 378.982894 -29.700966)
			(xy 378.965636 -29.756167) (xy 378.940243 -29.808129) (xy 378.907296 -29.855662) (xy 378.867551 -29.897677)
			(xy 378.845064 -29.915866) (xy 378.836276 -29.923492) (xy 378.826083 -29.944379) (xy 378.825506 -29.955998)
			(xy 378.825506 -30.035754) (xy 378.826026 -30.047388) (xy 378.836228 -30.068298) (xy 378.845064 -30.075886)
			(xy 378.867533 -30.094094) (xy 378.907271 -30.136109) (xy 378.940213 -30.18364) (xy 378.965604 -30.235598)
			(xy 378.982863 -30.290793) (xy 378.991594 -30.347961) (xy 378.99213 -30.376876) (xy 378.991644 -30.404127)
			(xy 378.983888 -30.458075) (xy 378.968533 -30.51037) (xy 378.945891 -30.559947) (xy 378.916425 -30.605797)
			(xy 378.880734 -30.646988) (xy 378.839543 -30.682679) (xy 378.793693 -30.712145) (xy 378.744116 -30.734787)
			(xy 378.691821 -30.750142) (xy 378.637873 -30.757898) (xy 378.583371 -30.757898) (xy 378.529423 -30.750142)
			(xy 378.477128 -30.734787) (xy 378.427551 -30.712145) (xy 378.381701 -30.682679) (xy 378.34051 -30.646988)
			(xy 378.304819 -30.605797) (xy 378.275353 -30.559947) (xy 378.252711 -30.51037) (xy 378.237356 -30.458075)
			(xy 378.2296 -30.404127) (xy 378.229114 -30.376876) (xy 375.952004 -30.376876) (xy 375.951518 -30.404127)
			(xy 375.943762 -30.458075) (xy 375.928407 -30.51037) (xy 375.905765 -30.559947) (xy 375.876299 -30.605797)
			(xy 375.840608 -30.646988) (xy 375.799417 -30.682679) (xy 375.753567 -30.712145) (xy 375.70399 -30.734787)
			(xy 375.651695 -30.750142) (xy 375.597747 -30.757898) (xy 375.543245 -30.757898) (xy 375.489297 -30.750142)
			(xy 375.437002 -30.734787) (xy 375.387425 -30.712145) (xy 375.341575 -30.682679) (xy 375.300384 -30.646988)
			(xy 375.264693 -30.605797) (xy 375.235227 -30.559947) (xy 375.212585 -30.51037) (xy 375.19723 -30.458075)
			(xy 375.189474 -30.404127) (xy 375.188988 -30.376876) (xy 370.70538 -30.376876) (xy 370.70538 -30.92069)
			(xy 370.705351 -30.922468) (xy 381.052832 -30.922468) (xy 381.052832 -30.058868) (xy 381.053322 -30.0289)
			(xy 381.061145 -29.969478) (xy 381.076658 -29.911585) (xy 381.099594 -29.856212) (xy 381.129561 -29.804306)
			(xy 381.166048 -29.756756) (xy 381.208428 -29.714376) (xy 381.255978 -29.677889) (xy 381.307884 -29.647922)
			(xy 381.363257 -29.624986) (xy 381.42115 -29.609473) (xy 381.480572 -29.60165) (xy 381.540508 -29.60165)
			(xy 381.59993 -29.609473) (xy 381.657823 -29.624986) (xy 381.713196 -29.647922) (xy 381.765102 -29.677889)
			(xy 381.812652 -29.714376) (xy 381.855032 -29.756756) (xy 381.891519 -29.804306) (xy 381.921486 -29.856212)
			(xy 381.944422 -29.911585) (xy 381.959935 -29.969478) (xy 381.967758 -30.0289) (xy 381.968248 -30.058868)
			(xy 381.968248 -30.922468) (xy 381.967758 -30.952436) (xy 381.959935 -31.011858) (xy 381.944422 -31.069751)
			(xy 381.921486 -31.125124) (xy 381.891519 -31.17703) (xy 381.855032 -31.22458) (xy 381.812652 -31.26696)
			(xy 381.765102 -31.303447) (xy 381.713196 -31.333414) (xy 381.657823 -31.35635) (xy 381.59993 -31.371863)
			(xy 381.540508 -31.379686) (xy 381.480572 -31.379686) (xy 381.42115 -31.371863) (xy 381.363257 -31.35635)
			(xy 381.307884 -31.333414) (xy 381.255978 -31.303447) (xy 381.208428 -31.26696) (xy 381.166048 -31.22458)
			(xy 381.129561 -31.17703) (xy 381.099594 -31.125124) (xy 381.076658 -31.069751) (xy 381.061145 -31.011858)
			(xy 381.053322 -30.952436) (xy 381.052832 -30.922468) (xy 370.705351 -30.922468) (xy 370.70489 -30.950674)
			(xy 370.697062 -31.01013) (xy 370.681541 -31.068055) (xy 370.658592 -31.123459) (xy 370.628608 -31.175393)
			(xy 370.592102 -31.222969) (xy 370.549697 -31.265374) (xy 370.502121 -31.30188) (xy 370.450187 -31.331864)
			(xy 370.394783 -31.354813) (xy 370.336858 -31.370334) (xy 370.277402 -31.378162) (xy 370.217434 -31.378162)
			(xy 370.157978 -31.370334) (xy 370.100053 -31.354813) (xy 370.044649 -31.331864) (xy 369.992715 -31.30188)
			(xy 369.945139 -31.265374) (xy 369.902734 -31.222969) (xy 369.866228 -31.175393) (xy 369.836244 -31.123459)
			(xy 369.813295 -31.068055) (xy 369.797774 -31.01013) (xy 369.789946 -30.950674) (xy 369.789456 -30.92069)
			(xy 366.858804 -30.92069) (xy 366.858804 -32.714184) (xy 367.147348 -32.714184) (xy 367.147348 -31.850584)
			(xy 367.147838 -31.8206) (xy 367.155666 -31.761144) (xy 367.171187 -31.703219) (xy 367.194136 -31.647815)
			(xy 367.22412 -31.595881) (xy 367.260626 -31.548305) (xy 367.303031 -31.5059) (xy 367.350607 -31.469394)
			(xy 367.402541 -31.43941) (xy 367.457945 -31.416461) (xy 367.51587 -31.40094) (xy 367.575326 -31.393112)
			(xy 367.635294 -31.393112) (xy 367.69475 -31.40094) (xy 367.752675 -31.416461) (xy 367.808079 -31.43941)
			(xy 367.860013 -31.469394) (xy 367.907589 -31.5059) (xy 367.949994 -31.548305) (xy 367.965016 -31.567882)
			(xy 375.298714 -31.567882) (xy 375.302785 -31.51226) (xy 375.314911 -31.457823) (xy 375.334834 -31.405732)
			(xy 375.36213 -31.357097) (xy 375.396216 -31.312954) (xy 375.436365 -31.274245) (xy 375.481723 -31.241794)
			(xy 375.531323 -31.216293) (xy 375.584107 -31.198286) (xy 375.63895 -31.188156) (xy 375.694684 -31.186119)
			(xy 375.750121 -31.192219) (xy 375.804078 -31.206325) (xy 375.855407 -31.228137) (xy 375.903013 -31.257191)
			(xy 375.945881 -31.292866) (xy 375.983098 -31.334403) (xy 376.013871 -31.380916) (xy 376.037543 -31.431413)
			(xy 376.053611 -31.48482) (xy 376.061731 -31.539996) (xy 376.06224 -31.567882) (xy 376.061731 -31.595768)
			(xy 376.053611 -31.650944) (xy 376.037543 -31.704351) (xy 376.030551 -31.719266) (xy 376.585478 -31.719266)
			(xy 376.589549 -31.663644) (xy 376.601675 -31.609207) (xy 376.621598 -31.557116) (xy 376.648894 -31.508481)
			(xy 376.68298 -31.464338) (xy 376.723129 -31.425629) (xy 376.768487 -31.393178) (xy 376.818087 -31.367677)
			(xy 376.870871 -31.34967) (xy 376.925714 -31.33954) (xy 376.981448 -31.337503) (xy 377.036885 -31.343603)
			(xy 377.090842 -31.357709) (xy 377.142171 -31.379521) (xy 377.189777 -31.408575) (xy 377.232645 -31.44425)
			(xy 377.269862 -31.485787) (xy 377.300635 -31.5323) (xy 377.324307 -31.582797) (xy 377.340375 -31.636204)
			(xy 377.344525 -31.664402) (xy 377.861066 -31.664402) (xy 377.865137 -31.60878) (xy 377.877263 -31.554343)
			(xy 377.897186 -31.502252) (xy 377.924482 -31.453617) (xy 377.958568 -31.409474) (xy 377.998717 -31.370765)
			(xy 378.044075 -31.338314) (xy 378.093675 -31.312813) (xy 378.146459 -31.294806) (xy 378.201302 -31.284676)
			(xy 378.257036 -31.282639) (xy 378.312473 -31.288739) (xy 378.36643 -31.302845) (xy 378.417759 -31.324657)
			(xy 378.465365 -31.353711) (xy 378.508233 -31.389386) (xy 378.54545 -31.430923) (xy 378.576223 -31.477436)
			(xy 378.599895 -31.527933) (xy 378.615963 -31.58134) (xy 378.624083 -31.636516) (xy 378.624592 -31.664402)
			(xy 378.624083 -31.692288) (xy 378.615963 -31.747464) (xy 378.607023 -31.777178) (xy 379.12624 -31.777178)
			(xy 379.130311 -31.721556) (xy 379.142437 -31.667119) (xy 379.16236 -31.615028) (xy 379.189656 -31.566393)
			(xy 379.223742 -31.52225) (xy 379.263891 -31.483541) (xy 379.309249 -31.45109) (xy 379.358849 -31.425589)
			(xy 379.411633 -31.407582) (xy 379.466476 -31.397452) (xy 379.52221 -31.395415) (xy 379.577647 -31.401515)
			(xy 379.631604 -31.415621) (xy 379.682933 -31.437433) (xy 379.730539 -31.466487) (xy 379.773407 -31.502162)
			(xy 379.810624 -31.543699) (xy 379.841397 -31.590212) (xy 379.865069 -31.640709) (xy 379.881137 -31.694116)
			(xy 379.889257 -31.749292) (xy 379.889766 -31.777178) (xy 379.889257 -31.805064) (xy 379.881137 -31.86024)
			(xy 379.865069 -31.913647) (xy 379.841397 -31.964144) (xy 379.810624 -32.010657) (xy 379.773407 -32.052194)
			(xy 379.730539 -32.087869) (xy 379.682933 -32.116923) (xy 379.631604 -32.138735) (xy 379.577647 -32.152841)
			(xy 379.52221 -32.158941) (xy 379.466476 -32.156904) (xy 379.411633 -32.146774) (xy 379.358849 -32.128767)
			(xy 379.309249 -32.103266) (xy 379.263891 -32.070815) (xy 379.223742 -32.032106) (xy 379.189656 -31.987963)
			(xy 379.16236 -31.939328) (xy 379.142437 -31.887237) (xy 379.130311 -31.8328) (xy 379.12624 -31.777178)
			(xy 378.607023 -31.777178) (xy 378.599895 -31.800871) (xy 378.576223 -31.851368) (xy 378.54545 -31.897881)
			(xy 378.508233 -31.939418) (xy 378.465365 -31.975093) (xy 378.417759 -32.004147) (xy 378.36643 -32.025959)
			(xy 378.312473 -32.040065) (xy 378.257036 -32.046165) (xy 378.201302 -32.044128) (xy 378.146459 -32.033998)
			(xy 378.093675 -32.015991) (xy 378.044075 -31.99049) (xy 377.998717 -31.958039) (xy 377.958568 -31.91933)
			(xy 377.924482 -31.875187) (xy 377.897186 -31.826552) (xy 377.877263 -31.774461) (xy 377.865137 -31.720024)
			(xy 377.861066 -31.664402) (xy 377.344525 -31.664402) (xy 377.348495 -31.69138) (xy 377.349004 -31.719266)
			(xy 377.348495 -31.747152) (xy 377.340375 -31.802328) (xy 377.324307 -31.855735) (xy 377.300635 -31.906232)
			(xy 377.269862 -31.952745) (xy 377.232645 -31.994282) (xy 377.189777 -32.029957) (xy 377.142171 -32.059011)
			(xy 377.090842 -32.080823) (xy 377.036885 -32.094929) (xy 376.981448 -32.101029) (xy 376.925714 -32.098992)
			(xy 376.870871 -32.088862) (xy 376.818087 -32.070855) (xy 376.768487 -32.045354) (xy 376.723129 -32.012903)
			(xy 376.68298 -31.974194) (xy 376.648894 -31.930051) (xy 376.621598 -31.881416) (xy 376.601675 -31.829325)
			(xy 376.589549 -31.774888) (xy 376.585478 -31.719266) (xy 376.030551 -31.719266) (xy 376.013871 -31.754848)
			(xy 375.983098 -31.801361) (xy 375.945881 -31.842898) (xy 375.903013 -31.878573) (xy 375.855407 -31.907627)
			(xy 375.804078 -31.929439) (xy 375.750121 -31.943545) (xy 375.694684 -31.949645) (xy 375.63895 -31.947608)
			(xy 375.584107 -31.937478) (xy 375.531323 -31.919471) (xy 375.481723 -31.89397) (xy 375.436365 -31.861519)
			(xy 375.396216 -31.82281) (xy 375.36213 -31.778667) (xy 375.334834 -31.730032) (xy 375.314911 -31.677941)
			(xy 375.302785 -31.623504) (xy 375.298714 -31.567882) (xy 367.965016 -31.567882) (xy 367.9865 -31.595881)
			(xy 368.016484 -31.647815) (xy 368.039433 -31.703219) (xy 368.054954 -31.761144) (xy 368.062782 -31.8206)
			(xy 368.063272 -31.850584) (xy 368.063272 -32.714184) (xy 368.063139 -32.722312) (xy 382.907032 -32.722312)
			(xy 382.907032 -31.858712) (xy 382.907522 -31.828744) (xy 382.915345 -31.769322) (xy 382.930858 -31.711429)
			(xy 382.953794 -31.656056) (xy 382.983761 -31.60415) (xy 383.020248 -31.5566) (xy 383.062628 -31.51422)
			(xy 383.110178 -31.477733) (xy 383.162084 -31.447766) (xy 383.217457 -31.42483) (xy 383.27535 -31.409317)
			(xy 383.334772 -31.401494) (xy 383.394708 -31.401494) (xy 383.45413 -31.409317) (xy 383.512023 -31.42483)
			(xy 383.567396 -31.447766) (xy 383.619302 -31.477733) (xy 383.666852 -31.51422) (xy 383.709232 -31.5566)
			(xy 383.745719 -31.60415) (xy 383.775686 -31.656056) (xy 383.798622 -31.711429) (xy 383.814135 -31.769322)
			(xy 383.821958 -31.828744) (xy 383.822448 -31.858712) (xy 383.822448 -32.722312) (xy 383.821958 -32.75228)
			(xy 383.814135 -32.811702) (xy 383.798622 -32.869595) (xy 383.775686 -32.924968) (xy 383.745719 -32.976874)
			(xy 383.709232 -33.024424) (xy 383.666852 -33.066804) (xy 383.619302 -33.103291) (xy 383.567396 -33.133258)
			(xy 383.512023 -33.156194) (xy 383.45413 -33.171707) (xy 383.394708 -33.17953) (xy 383.334772 -33.17953)
			(xy 383.27535 -33.171707) (xy 383.217457 -33.156194) (xy 383.162084 -33.133258) (xy 383.110178 -33.103291)
			(xy 383.062628 -33.066804) (xy 383.020248 -33.024424) (xy 382.983761 -32.976874) (xy 382.953794 -32.924968)
			(xy 382.930858 -32.869595) (xy 382.915345 -32.811702) (xy 382.907522 -32.75228) (xy 382.907032 -32.722312)
			(xy 368.063139 -32.722312) (xy 368.062782 -32.744168) (xy 368.054954 -32.803624) (xy 368.039433 -32.861549)
			(xy 368.016484 -32.916953) (xy 367.9865 -32.968887) (xy 367.949994 -33.016463) (xy 367.907589 -33.058868)
			(xy 367.860013 -33.095374) (xy 367.808079 -33.125358) (xy 367.752675 -33.148307) (xy 367.69475 -33.163828)
			(xy 367.635294 -33.171656) (xy 367.575326 -33.171656) (xy 367.51587 -33.163828) (xy 367.457945 -33.148307)
			(xy 367.402541 -33.125358) (xy 367.350607 -33.095374) (xy 367.303031 -33.058868) (xy 367.260626 -33.016463)
			(xy 367.22412 -32.968887) (xy 367.194136 -32.916953) (xy 367.171187 -32.861549) (xy 367.155666 -32.803624)
			(xy 367.147838 -32.744168) (xy 367.147348 -32.714184) (xy 366.858804 -32.714184) (xy 366.858804 -34.520886)
			(xy 369.789456 -34.520886) (xy 369.789456 -33.657286) (xy 369.789946 -33.627302) (xy 369.797774 -33.567846)
			(xy 369.813295 -33.509921) (xy 369.836244 -33.454517) (xy 369.866228 -33.402583) (xy 369.902734 -33.355007)
			(xy 369.945139 -33.312602) (xy 369.992715 -33.276096) (xy 370.044649 -33.246112) (xy 370.100053 -33.223163)
			(xy 370.157978 -33.207642) (xy 370.217434 -33.199814) (xy 370.277402 -33.199814) (xy 370.336858 -33.207642)
			(xy 370.394783 -33.223163) (xy 370.450187 -33.246112) (xy 370.502121 -33.276096) (xy 370.549697 -33.312602)
			(xy 370.592102 -33.355007) (xy 370.628608 -33.402583) (xy 370.658592 -33.454517) (xy 370.681541 -33.509921)
			(xy 370.697062 -33.567846) (xy 370.70489 -33.627302) (xy 370.70538 -33.657286) (xy 370.70538 -34.520886)
			(xy 370.705355 -34.52241) (xy 381.052832 -34.52241) (xy 381.052832 -33.65881) (xy 381.053322 -33.628842)
			(xy 381.061145 -33.56942) (xy 381.076658 -33.511527) (xy 381.099594 -33.456154) (xy 381.129561 -33.404248)
			(xy 381.166048 -33.356698) (xy 381.208428 -33.314318) (xy 381.255978 -33.277831) (xy 381.307884 -33.247864)
			(xy 381.363257 -33.224928) (xy 381.42115 -33.209415) (xy 381.480572 -33.201592) (xy 381.540508 -33.201592)
			(xy 381.59993 -33.209415) (xy 381.657823 -33.224928) (xy 381.713196 -33.247864) (xy 381.765102 -33.277831)
			(xy 381.812652 -33.314318) (xy 381.855032 -33.356698) (xy 381.891519 -33.404248) (xy 381.921486 -33.456154)
			(xy 381.944422 -33.511527) (xy 381.959935 -33.56942) (xy 381.967758 -33.628842) (xy 381.968248 -33.65881)
			(xy 381.968248 -34.52241) (xy 381.967758 -34.552378) (xy 381.959935 -34.6118) (xy 381.944422 -34.669693)
			(xy 381.921486 -34.725066) (xy 381.891519 -34.776972) (xy 381.855032 -34.824522) (xy 381.812652 -34.866902)
			(xy 381.765102 -34.903389) (xy 381.713196 -34.933356) (xy 381.657823 -34.956292) (xy 381.59993 -34.971805)
			(xy 381.540508 -34.979628) (xy 381.480572 -34.979628) (xy 381.42115 -34.971805) (xy 381.363257 -34.956292)
			(xy 381.307884 -34.933356) (xy 381.255978 -34.903389) (xy 381.208428 -34.866902) (xy 381.166048 -34.824522)
			(xy 381.129561 -34.776972) (xy 381.099594 -34.725066) (xy 381.076658 -34.669693) (xy 381.061145 -34.6118)
			(xy 381.053322 -34.552378) (xy 381.052832 -34.52241) (xy 370.705355 -34.52241) (xy 370.70489 -34.55087)
			(xy 370.697062 -34.610326) (xy 370.681541 -34.668251) (xy 370.658592 -34.723655) (xy 370.628608 -34.775589)
			(xy 370.592102 -34.823165) (xy 370.549697 -34.86557) (xy 370.502121 -34.902076) (xy 370.450187 -34.93206)
			(xy 370.394783 -34.955009) (xy 370.336858 -34.97053) (xy 370.277402 -34.978358) (xy 370.217434 -34.978358)
			(xy 370.157978 -34.97053) (xy 370.100053 -34.955009) (xy 370.044649 -34.93206) (xy 369.992715 -34.902076)
			(xy 369.945139 -34.86557) (xy 369.902734 -34.823165) (xy 369.866228 -34.775589) (xy 369.836244 -34.723655)
			(xy 369.813295 -34.668251) (xy 369.797774 -34.610326) (xy 369.789946 -34.55087) (xy 369.789456 -34.520886)
			(xy 366.858804 -34.520886) (xy 366.858804 -35.264852) (xy 378.202442 -35.264852) (xy 378.206513 -35.20923)
			(xy 378.218639 -35.154793) (xy 378.238562 -35.102702) (xy 378.265858 -35.054067) (xy 378.299944 -35.009924)
			(xy 378.340093 -34.971215) (xy 378.385451 -34.938764) (xy 378.435051 -34.913263) (xy 378.487835 -34.895256)
			(xy 378.542678 -34.885126) (xy 378.598412 -34.883089) (xy 378.653849 -34.889189) (xy 378.707806 -34.903295)
			(xy 378.759135 -34.925107) (xy 378.806741 -34.954161) (xy 378.849609 -34.989836) (xy 378.886826 -35.031373)
			(xy 378.917599 -35.077886) (xy 378.941271 -35.128383) (xy 378.957339 -35.18179) (xy 378.965459 -35.236966)
			(xy 378.965968 -35.264852) (xy 378.965459 -35.292738) (xy 378.957339 -35.347914) (xy 378.941271 -35.401321)
			(xy 378.917599 -35.451818) (xy 378.886826 -35.498331) (xy 378.849609 -35.539868) (xy 378.806741 -35.575543)
			(xy 378.759135 -35.604597) (xy 378.707806 -35.626409) (xy 378.653849 -35.640515) (xy 378.598412 -35.646615)
			(xy 378.542678 -35.644578) (xy 378.487835 -35.634448) (xy 378.435051 -35.616441) (xy 378.385451 -35.59094)
			(xy 378.340093 -35.558489) (xy 378.299944 -35.51978) (xy 378.265858 -35.475637) (xy 378.238562 -35.427002)
			(xy 378.218639 -35.374911) (xy 378.206513 -35.320474) (xy 378.202442 -35.264852) (xy 366.858804 -35.264852)
			(xy 366.858804 -35.876738) (xy 367.017298 -35.876738) (xy 367.021369 -35.821116) (xy 367.033495 -35.766679)
			(xy 367.053418 -35.714588) (xy 367.080714 -35.665953) (xy 367.1148 -35.62181) (xy 367.154949 -35.583101)
			(xy 367.200307 -35.55065) (xy 367.249907 -35.525149) (xy 367.302691 -35.507142) (xy 367.357534 -35.497012)
			(xy 367.413268 -35.494975) (xy 367.468705 -35.501075) (xy 367.522662 -35.515181) (xy 367.573991 -35.536993)
			(xy 367.621597 -35.566047) (xy 367.664465 -35.601722) (xy 367.701682 -35.643259) (xy 367.732455 -35.689772)
			(xy 367.756127 -35.740269) (xy 367.772195 -35.793676) (xy 367.780315 -35.848852) (xy 367.780824 -35.876738)
			(xy 371.088918 -35.876738) (xy 371.092989 -35.821116) (xy 371.105115 -35.766679) (xy 371.125038 -35.714588)
			(xy 371.152334 -35.665953) (xy 371.18642 -35.62181) (xy 371.226569 -35.583101) (xy 371.271927 -35.55065)
			(xy 371.321527 -35.525149) (xy 371.374311 -35.507142) (xy 371.429154 -35.497012) (xy 371.484888 -35.494975)
			(xy 371.540325 -35.501075) (xy 371.594282 -35.515181) (xy 371.645611 -35.536993) (xy 371.693217 -35.566047)
			(xy 371.736085 -35.601722) (xy 371.773302 -35.643259) (xy 371.804075 -35.689772) (xy 371.827747 -35.740269)
			(xy 371.843815 -35.793676) (xy 371.851935 -35.848852) (xy 371.852444 -35.876738) (xy 371.851935 -35.904624)
			(xy 371.843815 -35.9598) (xy 371.827747 -36.013207) (xy 371.804075 -36.063704) (xy 371.773302 -36.110217)
			(xy 371.736085 -36.151754) (xy 371.693217 -36.187429) (xy 371.645611 -36.216483) (xy 371.594282 -36.238295)
			(xy 371.540325 -36.252401) (xy 371.484888 -36.258501) (xy 371.429154 -36.256464) (xy 371.374311 -36.246334)
			(xy 371.321527 -36.228327) (xy 371.271927 -36.202826) (xy 371.226569 -36.170375) (xy 371.18642 -36.131666)
			(xy 371.152334 -36.087523) (xy 371.125038 -36.038888) (xy 371.105115 -35.986797) (xy 371.092989 -35.93236)
			(xy 371.088918 -35.876738) (xy 367.780824 -35.876738) (xy 367.780315 -35.904624) (xy 367.772195 -35.9598)
			(xy 367.756127 -36.013207) (xy 367.732455 -36.063704) (xy 367.701682 -36.110217) (xy 367.664465 -36.151754)
			(xy 367.621597 -36.187429) (xy 367.573991 -36.216483) (xy 367.522662 -36.238295) (xy 367.468705 -36.252401)
			(xy 367.413268 -36.258501) (xy 367.357534 -36.256464) (xy 367.302691 -36.246334) (xy 367.249907 -36.228327)
			(xy 367.200307 -36.202826) (xy 367.154949 -36.170375) (xy 367.1148 -36.131666) (xy 367.080714 -36.087523)
			(xy 367.053418 -36.038888) (xy 367.033495 -35.986797) (xy 367.021369 -35.93236) (xy 367.017298 -35.876738)
			(xy 366.858804 -35.876738) (xy 366.858804 -36.50996) (xy 368.913916 -36.50996) (xy 368.917987 -36.454338)
			(xy 368.930113 -36.399901) (xy 368.950036 -36.34781) (xy 368.977332 -36.299175) (xy 369.011418 -36.255032)
			(xy 369.051567 -36.216323) (xy 369.096925 -36.183872) (xy 369.146525 -36.158371) (xy 369.199309 -36.140364)
			(xy 369.254152 -36.130234) (xy 369.309886 -36.128197) (xy 369.365323 -36.134297) (xy 369.41928 -36.148403)
			(xy 369.470609 -36.170215) (xy 369.518215 -36.199269) (xy 369.561083 -36.234944) (xy 369.5983 -36.276481)
			(xy 369.629073 -36.322994) (xy 369.652745 -36.373491) (xy 369.668813 -36.426898) (xy 369.672738 -36.453572)
			(xy 372.228616 -36.453572) (xy 372.232687 -36.39795) (xy 372.244813 -36.343513) (xy 372.264736 -36.291422)
			(xy 372.292032 -36.242787) (xy 372.326118 -36.198644) (xy 372.366267 -36.159935) (xy 372.411625 -36.127484)
			(xy 372.461225 -36.101983) (xy 372.514009 -36.083976) (xy 372.568852 -36.073846) (xy 372.624586 -36.071809)
			(xy 372.680023 -36.077909) (xy 372.73398 -36.092015) (xy 372.785309 -36.113827) (xy 372.832915 -36.142881)
			(xy 372.875783 -36.178556) (xy 372.913 -36.220093) (xy 372.943773 -36.266606) (xy 372.953309 -36.286948)
			(xy 379.500382 -36.286948) (xy 379.504453 -36.231326) (xy 379.516579 -36.176889) (xy 379.536502 -36.124798)
			(xy 379.563798 -36.076163) (xy 379.597884 -36.03202) (xy 379.638033 -35.993311) (xy 379.683391 -35.96086)
			(xy 379.732991 -35.935359) (xy 379.785775 -35.917352) (xy 379.840618 -35.907222) (xy 379.896352 -35.905185)
			(xy 379.951789 -35.911285) (xy 380.005746 -35.925391) (xy 380.057075 -35.947203) (xy 380.104681 -35.976257)
			(xy 380.147549 -36.011932) (xy 380.184766 -36.053469) (xy 380.215539 -36.099982) (xy 380.239211 -36.150479)
			(xy 380.255279 -36.203886) (xy 380.263399 -36.259062) (xy 380.263908 -36.286948) (xy 380.263399 -36.314834)
			(xy 380.255279 -36.37001) (xy 380.239211 -36.423417) (xy 380.215539 -36.473914) (xy 380.187994 -36.515548)
			(xy 381.314196 -36.515548) (xy 381.318267 -36.459926) (xy 381.330393 -36.405489) (xy 381.350316 -36.353398)
			(xy 381.377612 -36.304763) (xy 381.411698 -36.26062) (xy 381.451847 -36.221911) (xy 381.497205 -36.18946)
			(xy 381.546805 -36.163959) (xy 381.599589 -36.145952) (xy 381.654432 -36.135822) (xy 381.710166 -36.133785)
			(xy 381.765603 -36.139885) (xy 381.81956 -36.153991) (xy 381.870889 -36.175803) (xy 381.918495 -36.204857)
			(xy 381.961363 -36.240532) (xy 381.99858 -36.282069) (xy 382.029353 -36.328582) (xy 382.053025 -36.379079)
			(xy 382.069093 -36.432486) (xy 382.077213 -36.487662) (xy 382.077722 -36.515548) (xy 382.077213 -36.543434)
			(xy 382.069093 -36.59861) (xy 382.068636 -36.60013) (xy 386.298193 -36.60013) (xy 386.302198 -36.512222)
			(xy 386.314181 -36.425042) (xy 386.334041 -36.339313) (xy 386.361616 -36.255745) (xy 386.396675 -36.175031)
			(xy 386.438928 -36.097839) (xy 386.488026 -36.02481) (xy 386.543562 -35.956548) (xy 386.605074 -35.893618)
			(xy 386.672055 -35.836544) (xy 386.743948 -35.785796) (xy 386.820157 -35.741796) (xy 386.900052 -35.704909)
			(xy 386.982971 -35.67544) (xy 387.068226 -35.653633) (xy 387.15511 -35.639669) (xy 387.242904 -35.633663)
			(xy 387.330881 -35.635667) (xy 387.418311 -35.645662) (xy 387.50447 -35.663566) (xy 387.588644 -35.68923)
			(xy 387.670135 -35.722443) (xy 387.748269 -35.762929) (xy 387.822397 -35.810351) (xy 387.891905 -35.864318)
			(xy 387.956219 -35.924383) (xy 388.014803 -35.990047) (xy 388.067174 -36.060766) (xy 388.112897 -36.135954)
			(xy 388.151594 -36.214989) (xy 388.182943 -36.297215) (xy 388.206685 -36.381951) (xy 388.222623 -36.468495)
			(xy 388.230625 -36.55613) (xy 388.231126 -36.60013) (xy 388.230625 -36.64413) (xy 388.222623 -36.731765)
			(xy 388.206685 -36.818309) (xy 388.182943 -36.903045) (xy 388.151594 -36.985271) (xy 388.112897 -37.064306)
			(xy 388.067174 -37.139494) (xy 388.014803 -37.210213) (xy 387.956219 -37.275877) (xy 387.891905 -37.335942)
			(xy 387.822397 -37.389909) (xy 387.748269 -37.437331) (xy 387.670135 -37.477817) (xy 387.588644 -37.51103)
			(xy 387.50447 -37.536694) (xy 387.418311 -37.554598) (xy 387.330881 -37.564593) (xy 387.242904 -37.566597)
			(xy 387.15511 -37.560591) (xy 387.068226 -37.546627) (xy 386.982971 -37.52482) (xy 386.900052 -37.495351)
			(xy 386.820157 -37.458464) (xy 386.743948 -37.414464) (xy 386.672055 -37.363716) (xy 386.605074 -37.306642)
			(xy 386.543562 -37.243712) (xy 386.488026 -37.17545) (xy 386.438928 -37.102421) (xy 386.396675 -37.025229)
			(xy 386.361616 -36.944515) (xy 386.334041 -36.860947) (xy 386.314181 -36.775218) (xy 386.302198 -36.688038)
			(xy 386.298193 -36.60013) (xy 382.068636 -36.60013) (xy 382.053025 -36.652017) (xy 382.029353 -36.702514)
			(xy 381.99858 -36.749027) (xy 381.961363 -36.790564) (xy 381.918495 -36.826239) (xy 381.870889 -36.855293)
			(xy 381.81956 -36.877105) (xy 381.765603 -36.891211) (xy 381.710166 -36.897311) (xy 381.654432 -36.895274)
			(xy 381.599589 -36.885144) (xy 381.546805 -36.867137) (xy 381.497205 -36.841636) (xy 381.451847 -36.809185)
			(xy 381.411698 -36.770476) (xy 381.377612 -36.726333) (xy 381.350316 -36.677698) (xy 381.330393 -36.625607)
			(xy 381.318267 -36.57117) (xy 381.314196 -36.515548) (xy 380.187994 -36.515548) (xy 380.184766 -36.520427)
			(xy 380.147549 -36.561964) (xy 380.104681 -36.597639) (xy 380.057075 -36.626693) (xy 380.005746 -36.648505)
			(xy 379.951789 -36.662611) (xy 379.896352 -36.668711) (xy 379.840618 -36.666674) (xy 379.785775 -36.656544)
			(xy 379.732991 -36.638537) (xy 379.683391 -36.613036) (xy 379.638033 -36.580585) (xy 379.597884 -36.541876)
			(xy 379.563798 -36.497733) (xy 379.536502 -36.449098) (xy 379.516579 -36.397007) (xy 379.504453 -36.34257)
			(xy 379.500382 -36.286948) (xy 372.953309 -36.286948) (xy 372.967445 -36.317103) (xy 372.983513 -36.37051)
			(xy 372.991633 -36.425686) (xy 372.992142 -36.453572) (xy 372.991633 -36.481458) (xy 372.983513 -36.536634)
			(xy 372.967445 -36.590041) (xy 372.943773 -36.640538) (xy 372.913 -36.687051) (xy 372.875783 -36.728588)
			(xy 372.832915 -36.764263) (xy 372.785309 -36.793317) (xy 372.73398 -36.815129) (xy 372.680023 -36.829235)
			(xy 372.624586 -36.835335) (xy 372.568852 -36.833298) (xy 372.514009 -36.823168) (xy 372.461225 -36.805161)
			(xy 372.411625 -36.77966) (xy 372.366267 -36.747209) (xy 372.326118 -36.7085) (xy 372.292032 -36.664357)
			(xy 372.264736 -36.615722) (xy 372.244813 -36.563631) (xy 372.232687 -36.509194) (xy 372.228616 -36.453572)
			(xy 369.672738 -36.453572) (xy 369.676933 -36.482074) (xy 369.677442 -36.50996) (xy 369.676933 -36.537846)
			(xy 369.668813 -36.593022) (xy 369.652745 -36.646429) (xy 369.629073 -36.696926) (xy 369.5983 -36.743439)
			(xy 369.561083 -36.784976) (xy 369.518215 -36.820651) (xy 369.470609 -36.849705) (xy 369.41928 -36.871517)
			(xy 369.365323 -36.885623) (xy 369.309886 -36.891723) (xy 369.254152 -36.889686) (xy 369.199309 -36.879556)
			(xy 369.146525 -36.861549) (xy 369.096925 -36.836048) (xy 369.051567 -36.803597) (xy 369.011418 -36.764888)
			(xy 368.977332 -36.720745) (xy 368.950036 -36.67211) (xy 368.930113 -36.620019) (xy 368.917987 -36.565582)
			(xy 368.913916 -36.50996) (xy 366.858804 -36.50996) (xy 366.858804 -36.721034) (xy 366.858349 -36.753722)
			(xy 366.851105 -36.818695) (xy 366.836744 -36.882474) (xy 366.81544 -36.944281) (xy 366.787453 -37.003363)
			(xy 366.753123 -37.059) (xy 366.733328 -37.085016) (xy 366.732312 -37.086286) (xy 366.717072 -37.106098)
			(xy 366.711738 -37.112702) (xy 366.703864 -37.135308) (xy 366.700562 -37.144706) (xy 366.701832 -37.177218)
			(xy 366.70209 -37.181989) (xy 366.704129 -37.191321) (xy 366.705896 -37.19576) (xy 366.709706 -37.204142)
			(xy 366.716564 -37.211) (xy 366.736361 -37.232456) (xy 366.769868 -37.280259) (xy 366.795708 -37.332606)
			(xy 366.813279 -37.388276) (xy 366.822171 -37.445972) (xy 366.822736 -37.47516) (xy 366.822276 -37.502415)
			(xy 366.814524 -37.556372) (xy 366.799171 -37.608677) (xy 366.776532 -37.658264) (xy 366.773901 -37.662358)
			(xy 368.248436 -37.662358) (xy 368.252507 -37.606736) (xy 368.264633 -37.552299) (xy 368.284556 -37.500208)
			(xy 368.311852 -37.451573) (xy 368.345938 -37.40743) (xy 368.386087 -37.368721) (xy 368.431445 -37.33627)
			(xy 368.481045 -37.310769) (xy 368.533829 -37.292762) (xy 368.588672 -37.282632) (xy 368.644406 -37.280595)
			(xy 368.699843 -37.286695) (xy 368.7538 -37.300801) (xy 368.805129 -37.322613) (xy 368.852735 -37.351667)
			(xy 368.895603 -37.387342) (xy 368.93282 -37.428879) (xy 368.963593 -37.475392) (xy 368.987265 -37.525889)
			(xy 369.003333 -37.579296) (xy 369.011453 -37.634472) (xy 369.011962 -37.662358) (xy 369.011453 -37.690244)
			(xy 369.003333 -37.74542) (xy 368.994699 -37.774118) (xy 379.764796 -37.774118) (xy 379.768867 -37.718496)
			(xy 379.780993 -37.664059) (xy 379.800916 -37.611968) (xy 379.828212 -37.563333) (xy 379.862298 -37.51919)
			(xy 379.902447 -37.480481) (xy 379.947805 -37.44803) (xy 379.997405 -37.422529) (xy 380.050189 -37.404522)
			(xy 380.105032 -37.394392) (xy 380.160766 -37.392355) (xy 380.216203 -37.398455) (xy 380.27016 -37.412561)
			(xy 380.321489 -37.434373) (xy 380.369095 -37.463427) (xy 380.411963 -37.499102) (xy 380.44918 -37.540639)
			(xy 380.479953 -37.587152) (xy 380.503625 -37.637649) (xy 380.519693 -37.691056) (xy 380.527813 -37.746232)
			(xy 380.528322 -37.774118) (xy 380.527813 -37.802004) (xy 380.519693 -37.85718) (xy 380.503625 -37.910587)
			(xy 380.479953 -37.961084) (xy 380.44918 -38.007597) (xy 380.411963 -38.049134) (xy 380.369095 -38.084809)
			(xy 380.321489 -38.113863) (xy 380.27016 -38.135675) (xy 380.216203 -38.149781) (xy 380.160766 -38.155881)
			(xy 380.105032 -38.153844) (xy 380.050189 -38.143714) (xy 379.997405 -38.125707) (xy 379.947805 -38.100206)
			(xy 379.902447 -38.067755) (xy 379.862298 -38.029046) (xy 379.828212 -37.984903) (xy 379.800916 -37.936268)
			(xy 379.780993 -37.884177) (xy 379.768867 -37.82974) (xy 379.764796 -37.774118) (xy 368.994699 -37.774118)
			(xy 368.987265 -37.798827) (xy 368.963593 -37.849324) (xy 368.93282 -37.895837) (xy 368.895603 -37.937374)
			(xy 368.852735 -37.973049) (xy 368.805129 -38.002103) (xy 368.7538 -38.023915) (xy 368.699843 -38.038021)
			(xy 368.644406 -38.044121) (xy 368.588672 -38.042084) (xy 368.533829 -38.031954) (xy 368.481045 -38.013947)
			(xy 368.431445 -37.988446) (xy 368.386087 -37.955995) (xy 368.345938 -37.917286) (xy 368.311852 -37.873143)
			(xy 368.284556 -37.824508) (xy 368.264633 -37.772417) (xy 368.252507 -37.71798) (xy 368.248436 -37.662358)
			(xy 366.773901 -37.662358) (xy 366.747065 -37.704124) (xy 366.711372 -37.745324) (xy 366.670178 -37.781024)
			(xy 366.624323 -37.810499) (xy 366.57474 -37.833148) (xy 366.522439 -37.848509) (xy 366.468483 -37.856271)
			(xy 366.441228 -37.856668) (xy 366.440974 -37.856668) (xy 366.414144 -37.856216) (xy 366.361012 -37.848705)
			(xy 366.309458 -37.833819) (xy 366.260499 -37.811854) (xy 366.215103 -37.783243) (xy 366.19434 -37.766244)
			(xy 366.194086 -37.76599) (xy 366.18672 -37.759894) (xy 366.178338 -37.756846) (xy 366.173664 -37.755336)
			(xy 366.163944 -37.753932) (xy 366.159034 -37.754052) (xy 366.127792 -37.755322) (xy 366.127284 -37.755322)
			(xy 366.090454 -37.756846) (xy 366.081012 -37.75761) (xy 366.063661 -37.765182) (xy 366.056672 -37.771578)
			(xy 365.098189 -38.729951) (xy 372.000997 -38.729951) (xy 372.000997 -38.675449) (xy 372.008754 -38.621501)
			(xy 372.02411 -38.569206) (xy 372.046753 -38.519629) (xy 372.076221 -38.473779) (xy 372.111914 -38.43259)
			(xy 372.153106 -38.3969) (xy 372.198959 -38.367437) (xy 372.248538 -38.344798) (xy 372.300834 -38.329447)
			(xy 372.354783 -38.321695) (xy 372.382034 -38.321234) (xy 372.410337 -38.32176) (xy 372.466325 -38.330103)
			(xy 372.520464 -38.346631) (xy 372.571565 -38.37098) (xy 372.618505 -38.402615) (xy 372.660254 -38.440842)
			(xy 372.695892 -38.48482) (xy 372.71071 -38.50894) (xy 372.718328 -38.52096) (xy 372.738943 -38.540561)
			(xy 372.76417 -38.553704) (xy 372.792047 -38.559365) (xy 372.820403 -38.557104) (xy 372.84703 -38.547097)
			(xy 372.869856 -38.530122) (xy 372.878858 -38.5191) (xy 372.897073 -38.496248) (xy 372.93923 -38.455783)
			(xy 372.98706 -38.422212) (xy 373.039446 -38.396321) (xy 373.095165 -38.378714) (xy 373.152917 -38.369801)
			(xy 373.182134 -38.36924) (xy 373.209387 -38.369632) (xy 373.263338 -38.377394) (xy 373.315635 -38.392754)
			(xy 373.365214 -38.4154) (xy 373.411066 -38.44487) (xy 373.452258 -38.480566) (xy 373.48795 -38.521761)
			(xy 373.517417 -38.567616) (xy 373.540058 -38.617197) (xy 373.555414 -38.669495) (xy 373.56317 -38.723447)
			(xy 373.56317 -38.777953) (xy 373.555414 -38.831905) (xy 373.540058 -38.884203) (xy 373.517417 -38.933784)
			(xy 373.48795 -38.979639) (xy 373.452258 -39.020834) (xy 373.411066 -39.05653) (xy 373.365214 -39.086)
			(xy 373.315635 -39.108646) (xy 373.263338 -39.124006) (xy 373.209387 -39.131768) (xy 373.182134 -39.132256)
			(xy 373.15383 -39.13176) (xy 373.097841 -39.123412) (xy 373.043701 -39.10688) (xy 372.992599 -39.082526)
			(xy 372.945659 -39.050885) (xy 372.903912 -39.012654) (xy 372.868275 -38.968672) (xy 372.853458 -38.94455)
			(xy 372.845881 -38.932501) (xy 372.825258 -38.9129) (xy 372.800021 -38.899759) (xy 372.772137 -38.894102)
			(xy 372.743774 -38.896369) (xy 372.717142 -38.906383) (xy 372.694313 -38.923364) (xy 372.68531 -38.93439)
			(xy 372.66711 -38.957255) (xy 372.624951 -38.99772) (xy 372.577118 -39.031289) (xy 372.524728 -39.057178)
			(xy 372.469006 -39.074783) (xy 372.411252 -39.083692) (xy 372.382034 -39.08425) (xy 372.354783 -39.083705)
			(xy 372.300834 -39.075953) (xy 372.248538 -39.060602) (xy 372.198959 -39.037963) (xy 372.153106 -39.0085)
			(xy 372.111914 -38.97281) (xy 372.076221 -38.931621) (xy 372.046753 -38.885771) (xy 372.02411 -38.836194)
			(xy 372.008754 -38.783899) (xy 372.000997 -38.729951) (xy 365.098189 -38.729951) (xy 363.856017 -39.97198)
			(xy 374.195846 -39.97198) (xy 374.199917 -39.916358) (xy 374.212043 -39.861921) (xy 374.231966 -39.80983)
			(xy 374.259262 -39.761195) (xy 374.293348 -39.717052) (xy 374.333497 -39.678343) (xy 374.378855 -39.645892)
			(xy 374.428455 -39.620391) (xy 374.481239 -39.602384) (xy 374.536082 -39.592254) (xy 374.591816 -39.590217)
			(xy 374.647253 -39.596317) (xy 374.70121 -39.610423) (xy 374.752539 -39.632235) (xy 374.800145 -39.661289)
			(xy 374.843013 -39.696964) (xy 374.88023 -39.738501) (xy 374.911003 -39.785014) (xy 374.934675 -39.835511)
			(xy 374.950743 -39.888918) (xy 374.958863 -39.944094) (xy 374.959372 -39.97198) (xy 374.958863 -39.999866)
			(xy 374.950743 -40.055042) (xy 374.934675 -40.108449) (xy 374.911003 -40.158946) (xy 374.88023 -40.205459)
			(xy 374.843013 -40.246996) (xy 374.800145 -40.282671) (xy 374.752539 -40.311725) (xy 374.70121 -40.333537)
			(xy 374.647253 -40.347643) (xy 374.591816 -40.353743) (xy 374.536082 -40.351706) (xy 374.481239 -40.341576)
			(xy 374.428455 -40.323569) (xy 374.378855 -40.298068) (xy 374.333497 -40.265617) (xy 374.293348 -40.226908)
			(xy 374.259262 -40.182765) (xy 374.231966 -40.13413) (xy 374.212043 -40.082039) (xy 374.199917 -40.027602)
			(xy 374.195846 -39.97198) (xy 363.856017 -39.97198) (xy 363.845602 -39.982394) (xy 362.559245 -41.268751)
			(xy 364.14405 -41.268751) (xy 364.14405 -41.214249) (xy 364.151806 -41.160301) (xy 364.167159 -41.108007)
			(xy 364.189799 -41.058429) (xy 364.219263 -41.012578) (xy 364.254952 -40.971386) (xy 364.296139 -40.935691)
			(xy 364.341987 -40.906222) (xy 364.391562 -40.883576) (xy 364.443855 -40.868216) (xy 364.497801 -40.860453)
			(xy 364.525052 -40.859964) (xy 364.553792 -40.860466) (xy 364.61062 -40.869095) (xy 364.66551 -40.886151)
			(xy 364.717221 -40.911247) (xy 364.764583 -40.943816) (xy 364.78591 -40.963088) (xy 364.792768 -40.969692)
			(xy 364.810802 -40.976804) (xy 364.899702 -40.976804) (xy 364.917736 -40.969692) (xy 364.924594 -40.963088)
			(xy 364.945907 -40.943801) (xy 364.993272 -40.911235) (xy 365.044987 -40.886145) (xy 365.099881 -40.869098)
			(xy 365.156712 -40.860481) (xy 365.185452 -40.859964) (xy 365.212705 -40.86048) (xy 365.266657 -40.868231)
			(xy 365.318957 -40.883582) (xy 365.36854 -40.90622) (xy 365.414395 -40.935684) (xy 365.455591 -40.971375)
			(xy 365.491287 -41.012566) (xy 365.520757 -41.058418) (xy 365.543402 -41.107998) (xy 365.558759 -41.160296)
			(xy 365.566517 -41.214247) (xy 365.566517 -41.268753) (xy 365.558759 -41.322704) (xy 365.543402 -41.375002)
			(xy 365.520757 -41.424582) (xy 365.491287 -41.470434) (xy 365.455591 -41.511625) (xy 365.414395 -41.547316)
			(xy 365.36854 -41.57678) (xy 365.318957 -41.599418) (xy 365.266657 -41.614769) (xy 365.212705 -41.62252)
			(xy 365.185452 -41.62298) (xy 365.156713 -41.622464) (xy 365.099886 -41.613836) (xy 365.044996 -41.596783)
			(xy 364.993285 -41.571691) (xy 364.945922 -41.539126) (xy 364.924594 -41.519856) (xy 364.917736 -41.513252)
			(xy 364.899702 -41.50614) (xy 364.810802 -41.50614) (xy 364.792768 -41.513252) (xy 364.78591 -41.519856)
			(xy 364.764602 -41.539149) (xy 364.717235 -41.571712) (xy 364.665518 -41.5968) (xy 364.610623 -41.613846)
			(xy 364.553792 -41.622463) (xy 364.525052 -41.62298) (xy 364.497801 -41.622547) (xy 364.443854 -41.614784)
			(xy 364.391562 -41.599424) (xy 364.341987 -41.576778) (xy 364.296139 -41.547309) (xy 364.254952 -41.511614)
			(xy 364.219263 -41.470422) (xy 364.189799 -41.424571) (xy 364.167159 -41.374993) (xy 364.151806 -41.322699)
			(xy 364.14405 -41.268751) (xy 362.559245 -41.268751) (xy 361.54233 -42.285666) (xy 361.535491 -42.293067)
			(xy 361.527776 -42.311665) (xy 361.527344 -42.321734) (xy 361.527344 -43.305222) (xy 366.607344 -43.305222)
			(xy 366.607812 -43.277852) (xy 366.615628 -43.223672) (xy 366.631116 -43.171169) (xy 366.653957 -43.121422)
			(xy 366.683682 -43.075455) (xy 366.701324 -43.054524) (xy 366.701578 -43.05427) (xy 366.707151 -43.047174)
			(xy 366.713404 -43.030264) (xy 366.71377 -43.02125) (xy 366.71377 -42.954194) (xy 366.713423 -42.945176)
			(xy 366.707169 -42.928259) (xy 366.701578 -42.921174) (xy 366.701324 -42.921174) (xy 366.701324 -42.92092)
			(xy 366.683685 -42.899988) (xy 366.653972 -42.854016) (xy 366.631136 -42.804268) (xy 366.615645 -42.751767)
			(xy 366.607817 -42.697591) (xy 366.607344 -42.670222) (xy 366.607896 -42.641484) (xy 366.616514 -42.584659)
			(xy 366.633558 -42.529769) (xy 366.658643 -42.478057) (xy 366.691201 -42.430692) (xy 366.710468 -42.409364)
			(xy 366.717072 -42.402506) (xy 366.724184 -42.384472) (xy 366.724184 -42.295572) (xy 366.717072 -42.277538)
			(xy 366.710468 -42.27068) (xy 366.691222 -42.249333) (xy 366.65866 -42.201972) (xy 366.633571 -42.150264)
			(xy 366.616522 -42.095376) (xy 366.607899 -42.038553) (xy 366.607896 -41.981079) (xy 366.616515 -41.924255)
			(xy 366.633559 -41.869366) (xy 366.658644 -41.817655) (xy 366.691201 -41.770292) (xy 366.710468 -41.748964)
			(xy 366.717072 -41.742106) (xy 366.724184 -41.724072) (xy 366.724184 -41.635172) (xy 366.717072 -41.617138)
			(xy 366.710468 -41.61028) (xy 366.691213 -41.58894) (xy 366.658643 -41.541582) (xy 366.633547 -41.489874)
			(xy 366.616493 -41.434986) (xy 366.607867 -41.37816) (xy 366.607344 -41.349422) (xy 366.60783 -41.322171)
			(xy 366.615586 -41.268223) (xy 366.630941 -41.215928) (xy 366.653583 -41.166351) (xy 366.683049 -41.120501)
			(xy 366.71874 -41.07931) (xy 366.759931 -41.043619) (xy 366.805781 -41.014153) (xy 366.855358 -40.991511)
			(xy 366.907653 -40.976156) (xy 366.961601 -40.9684) (xy 367.016103 -40.9684) (xy 367.039224 -40.971724)
			(xy 374.894092 -40.971724) (xy 374.898163 -40.916102) (xy 374.910289 -40.861665) (xy 374.930212 -40.809574)
			(xy 374.957508 -40.760939) (xy 374.991594 -40.716796) (xy 375.031743 -40.678087) (xy 375.077101 -40.645636)
			(xy 375.126701 -40.620135) (xy 375.179485 -40.602128) (xy 375.234328 -40.591998) (xy 375.290062 -40.589961)
			(xy 375.345499 -40.596061) (xy 375.399456 -40.610167) (xy 375.450785 -40.631979) (xy 375.498391 -40.661033)
			(xy 375.541259 -40.696708) (xy 375.578476 -40.738245) (xy 375.609249 -40.784758) (xy 375.632921 -40.835255)
			(xy 375.648989 -40.888662) (xy 375.657109 -40.943838) (xy 375.657618 -40.971724) (xy 375.657109 -40.99961)
			(xy 375.648989 -41.054786) (xy 375.632921 -41.108193) (xy 375.609249 -41.15869) (xy 375.578476 -41.205203)
			(xy 375.541259 -41.24674) (xy 375.498391 -41.282415) (xy 375.450785 -41.311469) (xy 375.399456 -41.333281)
			(xy 375.345499 -41.347387) (xy 375.290062 -41.353487) (xy 375.234328 -41.35145) (xy 375.179485 -41.34132)
			(xy 375.126701 -41.323313) (xy 375.077101 -41.297812) (xy 375.031743 -41.265361) (xy 374.991594 -41.226652)
			(xy 374.957508 -41.182509) (xy 374.930212 -41.133874) (xy 374.910289 -41.081783) (xy 374.898163 -41.027346)
			(xy 374.894092 -40.971724) (xy 367.039224 -40.971724) (xy 367.070051 -40.976156) (xy 367.122346 -40.991511)
			(xy 367.171923 -41.014153) (xy 367.217773 -41.043619) (xy 367.258964 -41.07931) (xy 367.294655 -41.120501)
			(xy 367.324121 -41.166351) (xy 367.346763 -41.215928) (xy 367.362118 -41.268223) (xy 367.369874 -41.322171)
			(xy 367.37036 -41.349422) (xy 367.369834 -41.378161) (xy 367.361209 -41.434987) (xy 367.344159 -41.489877)
			(xy 367.319068 -41.541589) (xy 367.286505 -41.588952) (xy 367.267236 -41.61028) (xy 367.260632 -41.617138)
			(xy 367.25352 -41.635172) (xy 367.25352 -41.724072) (xy 367.260632 -41.742106) (xy 367.267236 -41.748964)
			(xy 367.28653 -41.770271) (xy 367.319098 -41.817636) (xy 367.344191 -41.86935) (xy 367.361242 -41.924245)
			(xy 367.369863 -41.981075) (xy 367.369861 -42.038557) (xy 367.361234 -42.095387) (xy 367.34418 -42.150279)
			(xy 367.319082 -42.201992) (xy 367.28651 -42.249354) (xy 367.267236 -42.27068) (xy 367.260632 -42.277538)
			(xy 367.25352 -42.295572) (xy 367.25352 -42.384472) (xy 367.260632 -42.402506) (xy 367.267236 -42.409364)
			(xy 367.286513 -42.430686) (xy 367.319079 -42.478049) (xy 367.344171 -42.529762) (xy 367.36122 -42.584654)
			(xy 367.369841 -42.641483) (xy 367.37036 -42.670222) (xy 367.369917 -42.697593) (xy 367.362095 -42.751774)
			(xy 367.346601 -42.804277) (xy 367.326044 -42.849038) (xy 369.192046 -42.849038) (xy 369.196117 -42.793416)
			(xy 369.208243 -42.738979) (xy 369.228166 -42.686888) (xy 369.255462 -42.638253) (xy 369.289548 -42.59411)
			(xy 369.329697 -42.555401) (xy 369.375055 -42.52295) (xy 369.424655 -42.497449) (xy 369.477439 -42.479442)
			(xy 369.532282 -42.469312) (xy 369.588016 -42.467275) (xy 369.643453 -42.473375) (xy 369.69741 -42.487481)
			(xy 369.748739 -42.509293) (xy 369.796345 -42.538347) (xy 369.839213 -42.574022) (xy 369.87643 -42.615559)
			(xy 369.907203 -42.662072) (xy 369.930875 -42.712569) (xy 369.946943 -42.765976) (xy 369.955063 -42.821152)
			(xy 369.955424 -42.84091) (xy 375.233182 -42.84091) (xy 375.237253 -42.785288) (xy 375.249379 -42.730851)
			(xy 375.269302 -42.67876) (xy 375.296598 -42.630125) (xy 375.330684 -42.585982) (xy 375.370833 -42.547273)
			(xy 375.416191 -42.514822) (xy 375.465791 -42.489321) (xy 375.518575 -42.471314) (xy 375.573418 -42.461184)
			(xy 375.629152 -42.459147) (xy 375.684589 -42.465247) (xy 375.738546 -42.479353) (xy 375.789875 -42.501165)
			(xy 375.837481 -42.530219) (xy 375.880349 -42.565894) (xy 375.917566 -42.607431) (xy 375.948339 -42.653944)
			(xy 375.972011 -42.704441) (xy 375.988079 -42.757848) (xy 375.996199 -42.813024) (xy 375.996708 -42.84091)
			(xy 375.996199 -42.868796) (xy 375.988079 -42.923972) (xy 375.972011 -42.977379) (xy 375.948339 -43.027876)
			(xy 375.917566 -43.074389) (xy 375.880349 -43.115926) (xy 375.837481 -43.151601) (xy 375.789875 -43.180655)
			(xy 375.738546 -43.202467) (xy 375.684589 -43.216573) (xy 375.629152 -43.222673) (xy 375.573418 -43.220636)
			(xy 375.518575 -43.210506) (xy 375.465791 -43.192499) (xy 375.416191 -43.166998) (xy 375.370833 -43.134547)
			(xy 375.330684 -43.095838) (xy 375.296598 -43.051695) (xy 375.269302 -43.00306) (xy 375.249379 -42.950969)
			(xy 375.237253 -42.896532) (xy 375.233182 -42.84091) (xy 369.955424 -42.84091) (xy 369.955572 -42.849038)
			(xy 369.955063 -42.876924) (xy 369.946943 -42.9321) (xy 369.930875 -42.985507) (xy 369.907203 -43.036004)
			(xy 369.87643 -43.082517) (xy 369.839213 -43.124054) (xy 369.796345 -43.159729) (xy 369.748739 -43.188783)
			(xy 369.69741 -43.210595) (xy 369.643453 -43.224701) (xy 369.588016 -43.230801) (xy 369.532282 -43.228764)
			(xy 369.477439 -43.218634) (xy 369.424655 -43.200627) (xy 369.375055 -43.175126) (xy 369.329697 -43.142675)
			(xy 369.289548 -43.103966) (xy 369.255462 -43.059823) (xy 369.228166 -43.011188) (xy 369.208243 -42.959097)
			(xy 369.196117 -42.90466) (xy 369.192046 -42.849038) (xy 367.326044 -42.849038) (xy 367.323754 -42.854024)
			(xy 367.294024 -42.899989) (xy 367.27638 -42.92092) (xy 367.276126 -42.921174) (xy 367.270536 -42.928258)
			(xy 367.264293 -42.945177) (xy 367.263934 -42.954194) (xy 367.263934 -43.02125) (xy 367.264308 -43.030265)
			(xy 367.270543 -43.047183) (xy 367.276126 -43.05427) (xy 367.27638 -43.05427) (xy 367.27638 -43.054524)
			(xy 367.293994 -43.075476) (xy 367.32371 -43.121443) (xy 367.346551 -43.171186) (xy 367.362048 -43.223682)
			(xy 367.369883 -43.277854) (xy 367.37036 -43.305222) (xy 367.369874 -43.332473) (xy 367.362118 -43.386421)
			(xy 367.346763 -43.438716) (xy 367.324121 -43.488293) (xy 367.294655 -43.534143) (xy 367.258964 -43.575334)
			(xy 367.217773 -43.611025) (xy 367.171923 -43.640491) (xy 367.122346 -43.663133) (xy 367.070051 -43.678488)
			(xy 367.016103 -43.686244) (xy 366.961601 -43.686244) (xy 366.907653 -43.678488) (xy 366.855358 -43.663133)
			(xy 366.805781 -43.640491) (xy 366.759931 -43.611025) (xy 366.71874 -43.575334) (xy 366.683049 -43.534143)
			(xy 366.653583 -43.488293) (xy 366.630941 -43.438716) (xy 366.615586 -43.386421) (xy 366.60783 -43.332473)
			(xy 366.607344 -43.305222) (xy 361.527344 -43.305222) (xy 361.527344 -43.73626) (xy 368.513104 -43.73626)
			(xy 368.517175 -43.680638) (xy 368.529301 -43.626201) (xy 368.549224 -43.57411) (xy 368.57652 -43.525475)
			(xy 368.610606 -43.481332) (xy 368.650755 -43.442623) (xy 368.696113 -43.410172) (xy 368.745713 -43.384671)
			(xy 368.798497 -43.366664) (xy 368.85334 -43.356534) (xy 368.909074 -43.354497) (xy 368.964511 -43.360597)
			(xy 369.018468 -43.374703) (xy 369.069797 -43.396515) (xy 369.117403 -43.425569) (xy 369.160271 -43.461244)
			(xy 369.197488 -43.502781) (xy 369.228261 -43.549294) (xy 369.236487 -43.566842) (xy 371.633494 -43.566842)
			(xy 371.637565 -43.51122) (xy 371.649691 -43.456783) (xy 371.669614 -43.404692) (xy 371.69691 -43.356057)
			(xy 371.730996 -43.311914) (xy 371.771145 -43.273205) (xy 371.816503 -43.240754) (xy 371.866103 -43.215253)
			(xy 371.918887 -43.197246) (xy 371.97373 -43.187116) (xy 372.029464 -43.185079) (xy 372.084901 -43.191179)
			(xy 372.138858 -43.205285) (xy 372.190187 -43.227097) (xy 372.237793 -43.256151) (xy 372.280661 -43.291826)
			(xy 372.317878 -43.333363) (xy 372.348651 -43.379876) (xy 372.372323 -43.430373) (xy 372.388391 -43.48378)
			(xy 372.396511 -43.538956) (xy 372.39702 -43.566842) (xy 372.396511 -43.594728) (xy 372.388391 -43.649904)
			(xy 372.372323 -43.703311) (xy 372.348651 -43.753808) (xy 372.317878 -43.800321) (xy 372.280661 -43.841858)
			(xy 372.262574 -43.85691) (xy 373.019826 -43.85691) (xy 373.023897 -43.801288) (xy 373.036023 -43.746851)
			(xy 373.055946 -43.69476) (xy 373.083242 -43.646125) (xy 373.117328 -43.601982) (xy 373.157477 -43.563273)
			(xy 373.202835 -43.530822) (xy 373.252435 -43.505321) (xy 373.305219 -43.487314) (xy 373.360062 -43.477184)
			(xy 373.415796 -43.475147) (xy 373.471233 -43.481247) (xy 373.52519 -43.495353) (xy 373.576519 -43.517165)
			(xy 373.624125 -43.546219) (xy 373.666993 -43.581894) (xy 373.70421 -43.623431) (xy 373.734983 -43.669944)
			(xy 373.758655 -43.720441) (xy 373.774723 -43.773848) (xy 373.782843 -43.829024) (xy 373.783352 -43.85691)
			(xy 373.782843 -43.884796) (xy 373.774723 -43.939972) (xy 373.758655 -43.993379) (xy 373.734983 -44.043876)
			(xy 373.70421 -44.090389) (xy 373.666993 -44.131926) (xy 373.624125 -44.167601) (xy 373.576519 -44.196655)
			(xy 373.52519 -44.218467) (xy 373.471233 -44.232573) (xy 373.415796 -44.238673) (xy 373.360062 -44.236636)
			(xy 373.305219 -44.226506) (xy 373.252435 -44.208499) (xy 373.202835 -44.182998) (xy 373.157477 -44.150547)
			(xy 373.117328 -44.111838) (xy 373.083242 -44.067695) (xy 373.055946 -44.01906) (xy 373.036023 -43.966969)
			(xy 373.023897 -43.912532) (xy 373.019826 -43.85691) (xy 372.262574 -43.85691) (xy 372.237793 -43.877533)
			(xy 372.190187 -43.906587) (xy 372.138858 -43.928399) (xy 372.084901 -43.942505) (xy 372.029464 -43.948605)
			(xy 371.97373 -43.946568) (xy 371.918887 -43.936438) (xy 371.866103 -43.918431) (xy 371.816503 -43.89293)
			(xy 371.771145 -43.860479) (xy 371.730996 -43.82177) (xy 371.69691 -43.777627) (xy 371.669614 -43.728992)
			(xy 371.649691 -43.676901) (xy 371.637565 -43.622464) (xy 371.633494 -43.566842) (xy 369.236487 -43.566842)
			(xy 369.251933 -43.599791) (xy 369.268001 -43.653198) (xy 369.276121 -43.708374) (xy 369.27663 -43.73626)
			(xy 369.276121 -43.764146) (xy 369.268001 -43.819322) (xy 369.251933 -43.872729) (xy 369.228261 -43.923226)
			(xy 369.197488 -43.969739) (xy 369.160271 -44.011276) (xy 369.117403 -44.046951) (xy 369.069797 -44.076005)
			(xy 369.018468 -44.097817) (xy 368.964511 -44.111923) (xy 368.909074 -44.118023) (xy 368.85334 -44.115986)
			(xy 368.798497 -44.105856) (xy 368.745713 -44.087849) (xy 368.696113 -44.062348) (xy 368.650755 -44.029897)
			(xy 368.610606 -43.991188) (xy 368.57652 -43.947045) (xy 368.549224 -43.89841) (xy 368.529301 -43.846319)
			(xy 368.517175 -43.791882) (xy 368.513104 -43.73626) (xy 361.527344 -43.73626) (xy 361.527344 -45.114464)
			(xy 368.36553 -45.114464) (xy 368.369601 -45.058842) (xy 368.381727 -45.004405) (xy 368.40165 -44.952314)
			(xy 368.428946 -44.903679) (xy 368.463032 -44.859536) (xy 368.503181 -44.820827) (xy 368.548539 -44.788376)
			(xy 368.598139 -44.762875) (xy 368.650923 -44.744868) (xy 368.705766 -44.734738) (xy 368.7615 -44.732701)
			(xy 368.816937 -44.738801) (xy 368.870894 -44.752907) (xy 368.922223 -44.774719) (xy 368.969829 -44.803773)
			(xy 369.012697 -44.839448) (xy 369.042679 -44.87291) (xy 375.233182 -44.87291) (xy 375.237253 -44.817288)
			(xy 375.249379 -44.762851) (xy 375.269302 -44.71076) (xy 375.296598 -44.662125) (xy 375.330684 -44.617982)
			(xy 375.370833 -44.579273) (xy 375.416191 -44.546822) (xy 375.465791 -44.521321) (xy 375.518575 -44.503314)
			(xy 375.573418 -44.493184) (xy 375.629152 -44.491147) (xy 375.684589 -44.497247) (xy 375.738546 -44.511353)
			(xy 375.789875 -44.533165) (xy 375.837481 -44.562219) (xy 375.880349 -44.597894) (xy 375.917566 -44.639431)
			(xy 375.948339 -44.685944) (xy 375.972011 -44.736441) (xy 375.988079 -44.789848) (xy 375.996199 -44.845024)
			(xy 375.996708 -44.87291) (xy 375.996199 -44.900796) (xy 375.988079 -44.955972) (xy 375.972011 -45.009379)
			(xy 375.948339 -45.059876) (xy 375.917566 -45.106389) (xy 375.880349 -45.147926) (xy 375.837481 -45.183601)
			(xy 375.789875 -45.212655) (xy 375.738546 -45.234467) (xy 375.684589 -45.248573) (xy 375.629152 -45.254673)
			(xy 375.573418 -45.252636) (xy 375.518575 -45.242506) (xy 375.465791 -45.224499) (xy 375.416191 -45.198998)
			(xy 375.370833 -45.166547) (xy 375.330684 -45.127838) (xy 375.296598 -45.083695) (xy 375.269302 -45.03506)
			(xy 375.249379 -44.982969) (xy 375.237253 -44.928532) (xy 375.233182 -44.87291) (xy 369.042679 -44.87291)
			(xy 369.049914 -44.880985) (xy 369.080687 -44.927498) (xy 369.104359 -44.977995) (xy 369.120427 -45.031402)
			(xy 369.128547 -45.086578) (xy 369.129056 -45.114464) (xy 369.128547 -45.14235) (xy 369.120427 -45.197526)
			(xy 369.104359 -45.250933) (xy 369.080687 -45.30143) (xy 369.049914 -45.347943) (xy 369.044272 -45.35424)
			(xy 373.003824 -45.35424) (xy 373.007895 -45.298618) (xy 373.020021 -45.244181) (xy 373.039944 -45.19209)
			(xy 373.06724 -45.143455) (xy 373.101326 -45.099312) (xy 373.141475 -45.060603) (xy 373.186833 -45.028152)
			(xy 373.236433 -45.002651) (xy 373.289217 -44.984644) (xy 373.34406 -44.974514) (xy 373.399794 -44.972477)
			(xy 373.455231 -44.978577) (xy 373.509188 -44.992683) (xy 373.560517 -45.014495) (xy 373.608123 -45.043549)
			(xy 373.650991 -45.079224) (xy 373.688208 -45.120761) (xy 373.718981 -45.167274) (xy 373.742653 -45.217771)
			(xy 373.758721 -45.271178) (xy 373.766841 -45.326354) (xy 373.76735 -45.35424) (xy 373.766841 -45.382126)
			(xy 373.758721 -45.437302) (xy 373.742653 -45.490709) (xy 373.718981 -45.541206) (xy 373.688208 -45.587719)
			(xy 373.650991 -45.629256) (xy 373.608123 -45.664931) (xy 373.560517 -45.693985) (xy 373.509188 -45.715797)
			(xy 373.455231 -45.729903) (xy 373.399794 -45.736003) (xy 373.34406 -45.733966) (xy 373.289217 -45.723836)
			(xy 373.236433 -45.705829) (xy 373.186833 -45.680328) (xy 373.141475 -45.647877) (xy 373.101326 -45.609168)
			(xy 373.06724 -45.565025) (xy 373.039944 -45.51639) (xy 373.020021 -45.464299) (xy 373.007895 -45.409862)
			(xy 373.003824 -45.35424) (xy 369.044272 -45.35424) (xy 369.012697 -45.38948) (xy 368.969829 -45.425155)
			(xy 368.922223 -45.454209) (xy 368.870894 -45.476021) (xy 368.816937 -45.490127) (xy 368.7615 -45.496227)
			(xy 368.705766 -45.49419) (xy 368.650923 -45.48406) (xy 368.598139 -45.466053) (xy 368.548539 -45.440552)
			(xy 368.503181 -45.408101) (xy 368.463032 -45.369392) (xy 368.428946 -45.325249) (xy 368.40165 -45.276614)
			(xy 368.381727 -45.224523) (xy 368.369601 -45.170086) (xy 368.36553 -45.114464) (xy 361.527344 -45.114464)
			(xy 361.527344 -46.082204) (xy 366.352582 -46.082204) (xy 366.353081 -46.054953) (xy 366.360837 -46.001007)
			(xy 366.376191 -45.948713) (xy 366.398831 -45.899136) (xy 366.428296 -45.853286) (xy 366.463986 -45.812096)
			(xy 366.505175 -45.776405) (xy 366.551024 -45.746938) (xy 366.6006 -45.724296) (xy 366.652893 -45.70894)
			(xy 366.706839 -45.701182) (xy 366.73409 -45.700696) (xy 366.760992 -45.701166) (xy 366.814262 -45.708736)
			(xy 366.86594 -45.723714) (xy 366.915002 -45.745803) (xy 366.960474 -45.774564) (xy 367.001456 -45.809428)
			(xy 367.037134 -45.849703) (xy 367.052352 -45.871892) (xy 367.059464 -45.882814) (xy 367.082324 -45.894752)
			(xy 367.194592 -45.89272) (xy 367.216944 -45.879766) (xy 367.223802 -45.86859) (xy 367.238736 -45.844997)
			(xy 367.274413 -45.802045) (xy 367.315969 -45.764751) (xy 367.362517 -45.733913) (xy 367.413062 -45.710188)
			(xy 367.466526 -45.694084) (xy 367.521766 -45.685944) (xy 367.549684 -45.685456) (xy 367.576677 -45.685926)
			(xy 367.630125 -45.69353) (xy 367.681968 -45.708588) (xy 367.731173 -45.7308) (xy 367.776757 -45.759723)
			(xy 367.797588 -45.776896) (xy 367.805716 -45.784008) (xy 367.82629 -45.790104) (xy 367.911634 -45.779182)
			(xy 367.922185 -45.777434) (xy 367.940465 -45.766361) (xy 367.94694 -45.757846) (xy 367.962275 -45.736602)
			(xy 367.997865 -45.698149) (xy 368.038385 -45.664932) (xy 368.083072 -45.637575) (xy 368.131083 -45.616593)
			(xy 368.181514 -45.602383) (xy 368.233416 -45.595211) (xy 368.259614 -45.594778) (xy 368.286864 -45.595293)
			(xy 368.340808 -45.603051) (xy 368.393099 -45.618407) (xy 368.442672 -45.641048) (xy 368.488519 -45.670513)
			(xy 368.529706 -45.706204) (xy 368.565395 -45.747392) (xy 368.594859 -45.79324) (xy 368.617498 -45.842814)
			(xy 368.632852 -45.895106) (xy 368.640608 -45.94905) (xy 368.640608 -46.00355) (xy 368.632852 -46.057494)
			(xy 368.617498 -46.109786) (xy 368.594859 -46.15936) (xy 368.565395 -46.205208) (xy 368.529706 -46.246396)
			(xy 368.488519 -46.282087) (xy 368.442672 -46.311552) (xy 368.393099 -46.334193) (xy 368.340808 -46.349549)
			(xy 368.286864 -46.357307) (xy 368.259614 -46.357794) (xy 368.232622 -46.357313) (xy 368.179175 -46.34971)
			(xy 368.127332 -46.334654) (xy 368.078127 -46.312445) (xy 368.032542 -46.283525) (xy 368.01171 -46.266354)
			(xy 368.003582 -46.259242) (xy 367.983008 -46.253146) (xy 367.897664 -46.264068) (xy 367.887117 -46.265832)
			(xy 367.868837 -46.276895) (xy 367.862358 -46.285404) (xy 367.844747 -46.309706) (xy 367.80315 -46.352965)
			(xy 367.779554 -46.37151) (xy 367.77168 -46.377352) (xy 367.761266 -46.394878) (xy 367.748058 -46.485302)
			(xy 367.752884 -46.504606) (xy 367.758726 -46.51248) (xy 367.758726 -46.512734) (xy 367.776223 -46.537482)
			(xy 367.804028 -46.591333) (xy 367.822967 -46.648904) (xy 367.83017 -46.693836) (xy 372.976394 -46.693836)
			(xy 372.97688 -46.666585) (xy 372.984636 -46.612637) (xy 372.999991 -46.560342) (xy 373.022633 -46.510765)
			(xy 373.052099 -46.464915) (xy 373.08779 -46.423724) (xy 373.128981 -46.388033) (xy 373.174831 -46.358567)
			(xy 373.224408 -46.335925) (xy 373.276703 -46.32057) (xy 373.330651 -46.312814) (xy 373.385153 -46.312814)
			(xy 373.439101 -46.32057) (xy 373.491396 -46.335925) (xy 373.540973 -46.358567) (xy 373.586823 -46.388033)
			(xy 373.628014 -46.423724) (xy 373.663705 -46.464915) (xy 373.693171 -46.510765) (xy 373.715813 -46.560342)
			(xy 373.731168 -46.612637) (xy 373.738924 -46.666585) (xy 373.73941 -46.693836) (xy 373.738936 -46.720263)
			(xy 373.731627 -46.772611) (xy 373.717154 -46.823446) (xy 373.695795 -46.871793) (xy 373.68226 -46.894496)
			(xy 373.682006 -46.89475) (xy 373.676669 -46.904768) (xy 373.674414 -46.927318) (xy 373.677688 -46.938184)
			(xy 373.70385 -47.01286) (xy 373.708235 -47.023375) (xy 373.724323 -47.039463) (xy 373.734838 -47.043848)
			(xy 373.735092 -47.043848) (xy 373.759611 -47.052892) (xy 373.806062 -47.07684) (xy 373.848813 -47.1069)
			(xy 373.887063 -47.142511) (xy 373.920098 -47.183007) (xy 373.9473 -47.227631) (xy 373.968161 -47.275548)
			(xy 373.98229 -47.325863) (xy 373.989423 -47.377635) (xy 373.989854 -47.403766) (xy 373.989368 -47.431017)
			(xy 373.987845 -47.441612) (xy 375.261884 -47.441612) (xy 375.265955 -47.38599) (xy 375.278081 -47.331553)
			(xy 375.298004 -47.279462) (xy 375.3253 -47.230827) (xy 375.359386 -47.186684) (xy 375.399535 -47.147975)
			(xy 375.444893 -47.115524) (xy 375.494493 -47.090023) (xy 375.547277 -47.072016) (xy 375.60212 -47.061886)
			(xy 375.657854 -47.059849) (xy 375.713291 -47.065949) (xy 375.767248 -47.080055) (xy 375.818577 -47.101867)
			(xy 375.866183 -47.130921) (xy 375.909051 -47.166596) (xy 375.946268 -47.208133) (xy 375.977041 -47.254646)
			(xy 376.000713 -47.305143) (xy 376.016781 -47.35855) (xy 376.024901 -47.413726) (xy 376.02541 -47.441612)
			(xy 376.024901 -47.469498) (xy 376.016781 -47.524674) (xy 376.000713 -47.578081) (xy 375.977041 -47.628578)
			(xy 375.946268 -47.675091) (xy 375.909051 -47.716628) (xy 375.866183 -47.752303) (xy 375.818577 -47.781357)
			(xy 375.767248 -47.803169) (xy 375.713291 -47.817275) (xy 375.657854 -47.823375) (xy 375.60212 -47.821338)
			(xy 375.547277 -47.811208) (xy 375.494493 -47.793201) (xy 375.444893 -47.7677) (xy 375.399535 -47.735249)
			(xy 375.359386 -47.69654) (xy 375.3253 -47.652397) (xy 375.298004 -47.603762) (xy 375.278081 -47.551671)
			(xy 375.265955 -47.497234) (xy 375.261884 -47.441612) (xy 373.987845 -47.441612) (xy 373.981612 -47.484965)
			(xy 373.966257 -47.53726) (xy 373.943615 -47.586837) (xy 373.914149 -47.632687) (xy 373.878458 -47.673878)
			(xy 373.837267 -47.709569) (xy 373.791417 -47.739035) (xy 373.74184 -47.761677) (xy 373.689545 -47.777032)
			(xy 373.635597 -47.784788) (xy 373.581095 -47.784788) (xy 373.527147 -47.777032) (xy 373.474852 -47.761677)
			(xy 373.425275 -47.739035) (xy 373.379425 -47.709569) (xy 373.338234 -47.673878) (xy 373.302543 -47.632687)
			(xy 373.273077 -47.586837) (xy 373.250435 -47.53726) (xy 373.23508 -47.484965) (xy 373.227324 -47.431017)
			(xy 373.226838 -47.403766) (xy 373.227306 -47.377338) (xy 373.234616 -47.324991) (xy 373.249091 -47.274156)
			(xy 373.270452 -47.225809) (xy 373.283988 -47.203106) (xy 373.284242 -47.202852) (xy 373.289577 -47.192833)
			(xy 373.291836 -47.170284) (xy 373.28856 -47.159418) (xy 373.262398 -47.084742) (xy 373.258036 -47.074215)
			(xy 373.241932 -47.058131) (xy 373.23141 -47.053754) (xy 373.231156 -47.053754) (xy 373.206648 -47.044682)
			(xy 373.160196 -47.020739) (xy 373.117444 -46.990684) (xy 373.079192 -46.955077) (xy 373.046155 -46.914585)
			(xy 373.018951 -46.869964) (xy 372.998089 -46.822049) (xy 372.983959 -46.771736) (xy 372.976825 -46.719966)
			(xy 372.976394 -46.693836) (xy 367.83017 -46.693836) (xy 367.83256 -46.708745) (xy 367.833148 -46.739048)
			(xy 367.832667 -46.766299) (xy 367.824905 -46.820244) (xy 367.809546 -46.872537) (xy 367.786902 -46.922112)
			(xy 367.757434 -46.96796) (xy 367.721743 -47.009148) (xy 367.680553 -47.044839) (xy 367.634705 -47.074306)
			(xy 367.585129 -47.096949) (xy 367.532837 -47.112307) (xy 367.478891 -47.120068) (xy 367.45164 -47.120556)
			(xy 367.425606 -47.120136) (xy 367.374022 -47.113041) (xy 367.32388 -47.099005) (xy 367.276109 -47.078289)
			(xy 367.231596 -47.051275) (xy 367.211102 -47.035212) (xy 367.203351 -47.02946) (xy 367.184936 -47.023726)
			(xy 367.175288 -47.024036) (xy 367.095532 -47.030386) (xy 367.077752 -47.039022) (xy 367.071402 -47.046388)
			(xy 367.053243 -47.066055) (xy 367.012331 -47.100575) (xy 366.966997 -47.129042) (xy 366.918131 -47.150895)
			(xy 366.866692 -47.165708) (xy 366.813687 -47.17319) (xy 366.786922 -47.173642) (xy 366.759673 -47.173101)
			(xy 366.705729 -47.165349) (xy 366.653437 -47.149998) (xy 366.603863 -47.127362) (xy 366.558014 -47.097901)
			(xy 366.516824 -47.062216) (xy 366.481132 -47.021031) (xy 366.451665 -46.975187) (xy 366.429021 -46.925615)
			(xy 366.413663 -46.873326) (xy 366.405903 -46.819383) (xy 366.405414 -46.792134) (xy 366.405935 -46.76336)
			(xy 366.414586 -46.706465) (xy 366.431683 -46.651515) (xy 366.456838 -46.599755) (xy 366.489479 -46.552359)
			(xy 366.508792 -46.531022) (xy 366.516158 -46.523148) (xy 366.52327 -46.503336) (xy 366.515904 -46.40707)
			(xy 366.505998 -46.388274) (xy 366.497616 -46.38167) (xy 366.47543 -46.363446) (xy 366.436221 -46.321511)
			(xy 366.403735 -46.274175) (xy 366.378707 -46.222507) (xy 366.361701 -46.167672) (xy 366.3531 -46.110909)
			(xy 366.352582 -46.082204) (xy 361.527344 -46.082204) (xy 361.527344 -48.30699) (xy 372.853964 -48.30699)
			(xy 372.858035 -48.251368) (xy 372.870161 -48.196931) (xy 372.890084 -48.14484) (xy 372.91738 -48.096205)
			(xy 372.951466 -48.052062) (xy 372.991615 -48.013353) (xy 373.036973 -47.980902) (xy 373.086573 -47.955401)
			(xy 373.139357 -47.937394) (xy 373.1942 -47.927264) (xy 373.249934 -47.925227) (xy 373.305371 -47.931327)
			(xy 373.359328 -47.945433) (xy 373.410657 -47.967245) (xy 373.458263 -47.996299) (xy 373.501131 -48.031974)
			(xy 373.538348 -48.073511) (xy 373.569121 -48.120024) (xy 373.592793 -48.170521) (xy 373.608861 -48.223928)
			(xy 373.616981 -48.279104) (xy 373.61749 -48.30699) (xy 373.616981 -48.334876) (xy 373.608861 -48.390052)
			(xy 373.592793 -48.443459) (xy 373.569121 -48.493956) (xy 373.538348 -48.540469) (xy 373.501131 -48.582006)
			(xy 373.458263 -48.617681) (xy 373.410657 -48.646735) (xy 373.359328 -48.668547) (xy 373.305371 -48.682653)
			(xy 373.249934 -48.688753) (xy 373.1942 -48.686716) (xy 373.139357 -48.676586) (xy 373.086573 -48.658579)
			(xy 373.036973 -48.633078) (xy 372.991615 -48.600627) (xy 372.951466 -48.561918) (xy 372.91738 -48.517775)
			(xy 372.890084 -48.46914) (xy 372.870161 -48.417049) (xy 372.858035 -48.362612) (xy 372.853964 -48.30699)
			(xy 361.527344 -48.30699) (xy 361.527344 -48.753014) (xy 369.468398 -48.753014) (xy 369.472469 -48.697392)
			(xy 369.484595 -48.642955) (xy 369.504518 -48.590864) (xy 369.531814 -48.542229) (xy 369.5659 -48.498086)
			(xy 369.606049 -48.459377) (xy 369.651407 -48.426926) (xy 369.701007 -48.401425) (xy 369.753791 -48.383418)
			(xy 369.808634 -48.373288) (xy 369.864368 -48.371251) (xy 369.919805 -48.377351) (xy 369.973762 -48.391457)
			(xy 370.025091 -48.413269) (xy 370.072697 -48.442323) (xy 370.115565 -48.477998) (xy 370.152782 -48.519535)
			(xy 370.183555 -48.566048) (xy 370.207227 -48.616545) (xy 370.223295 -48.669952) (xy 370.231415 -48.725128)
			(xy 370.231924 -48.753014) (xy 370.231415 -48.7809) (xy 370.223295 -48.836076) (xy 370.207227 -48.889483)
			(xy 370.205831 -48.89246) (xy 371.514114 -48.89246) (xy 371.518185 -48.836838) (xy 371.530311 -48.782401)
			(xy 371.550234 -48.73031) (xy 371.57753 -48.681675) (xy 371.611616 -48.637532) (xy 371.651765 -48.598823)
			(xy 371.697123 -48.566372) (xy 371.746723 -48.540871) (xy 371.799507 -48.522864) (xy 371.85435 -48.512734)
			(xy 371.910084 -48.510697) (xy 371.965521 -48.516797) (xy 372.019478 -48.530903) (xy 372.070807 -48.552715)
			(xy 372.118413 -48.581769) (xy 372.161281 -48.617444) (xy 372.198498 -48.658981) (xy 372.229271 -48.705494)
			(xy 372.252943 -48.755991) (xy 372.269011 -48.809398) (xy 372.277131 -48.864574) (xy 372.27764 -48.89246)
			(xy 372.277131 -48.920346) (xy 372.274693 -48.93691) (xy 375.233182 -48.93691) (xy 375.237253 -48.881288)
			(xy 375.249379 -48.826851) (xy 375.269302 -48.77476) (xy 375.296598 -48.726125) (xy 375.330684 -48.681982)
			(xy 375.370833 -48.643273) (xy 375.416191 -48.610822) (xy 375.465791 -48.585321) (xy 375.518575 -48.567314)
			(xy 375.573418 -48.557184) (xy 375.629152 -48.555147) (xy 375.684589 -48.561247) (xy 375.738546 -48.575353)
			(xy 375.789875 -48.597165) (xy 375.837481 -48.626219) (xy 375.880349 -48.661894) (xy 375.917566 -48.703431)
			(xy 375.948339 -48.749944) (xy 375.972011 -48.800441) (xy 375.988079 -48.853848) (xy 375.996199 -48.909024)
			(xy 375.996708 -48.93691) (xy 375.996199 -48.964796) (xy 375.988079 -49.019972) (xy 375.972011 -49.073379)
			(xy 375.948339 -49.123876) (xy 375.917566 -49.170389) (xy 375.880349 -49.211926) (xy 375.837481 -49.247601)
			(xy 375.789875 -49.276655) (xy 375.738546 -49.298467) (xy 375.684589 -49.312573) (xy 375.629152 -49.318673)
			(xy 375.573418 -49.316636) (xy 375.518575 -49.306506) (xy 375.465791 -49.288499) (xy 375.416191 -49.262998)
			(xy 375.370833 -49.230547) (xy 375.330684 -49.191838) (xy 375.296598 -49.147695) (xy 375.269302 -49.09906)
			(xy 375.249379 -49.046969) (xy 375.237253 -48.992532) (xy 375.233182 -48.93691) (xy 372.274693 -48.93691)
			(xy 372.269011 -48.975522) (xy 372.252943 -49.028929) (xy 372.229271 -49.079426) (xy 372.198498 -49.125939)
			(xy 372.161281 -49.167476) (xy 372.118413 -49.203151) (xy 372.070807 -49.232205) (xy 372.019478 -49.254017)
			(xy 371.965521 -49.268123) (xy 371.910084 -49.274223) (xy 371.85435 -49.272186) (xy 371.799507 -49.262056)
			(xy 371.746723 -49.244049) (xy 371.697123 -49.218548) (xy 371.651765 -49.186097) (xy 371.611616 -49.147388)
			(xy 371.57753 -49.103245) (xy 371.550234 -49.05461) (xy 371.530311 -49.002519) (xy 371.518185 -48.948082)
			(xy 371.514114 -48.89246) (xy 370.205831 -48.89246) (xy 370.183555 -48.93998) (xy 370.152782 -48.986493)
			(xy 370.115565 -49.02803) (xy 370.072697 -49.063705) (xy 370.025091 -49.092759) (xy 369.973762 -49.114571)
			(xy 369.919805 -49.128677) (xy 369.864368 -49.134777) (xy 369.808634 -49.13274) (xy 369.753791 -49.12261)
			(xy 369.701007 -49.104603) (xy 369.651407 -49.079102) (xy 369.606049 -49.046651) (xy 369.5659 -49.007942)
			(xy 369.531814 -48.963799) (xy 369.504518 -48.915164) (xy 369.484595 -48.863073) (xy 369.472469 -48.808636)
			(xy 369.468398 -48.753014) (xy 361.527344 -48.753014) (xy 361.527344 -49.95291) (xy 375.233182 -49.95291)
			(xy 375.237253 -49.897288) (xy 375.249379 -49.842851) (xy 375.269302 -49.79076) (xy 375.296598 -49.742125)
			(xy 375.330684 -49.697982) (xy 375.370833 -49.659273) (xy 375.416191 -49.626822) (xy 375.465791 -49.601321)
			(xy 375.518575 -49.583314) (xy 375.573418 -49.573184) (xy 375.629152 -49.571147) (xy 375.684589 -49.577247)
			(xy 375.738546 -49.591353) (xy 375.76349 -49.601953) (xy 380.412959 -49.601953) (xy 380.412959 -49.547447)
			(xy 380.420716 -49.493496) (xy 380.436073 -49.441199) (xy 380.458715 -49.391618) (xy 380.488184 -49.345766)
			(xy 380.523877 -49.304573) (xy 380.56507 -49.26888) (xy 380.610924 -49.239412) (xy 380.660504 -49.21677)
			(xy 380.712802 -49.201415) (xy 380.766753 -49.193659) (xy 380.794006 -49.193196) (xy 380.821376 -49.19366)
			(xy 380.875555 -49.201478) (xy 380.928059 -49.216968) (xy 380.977805 -49.23981) (xy 381.023772 -49.269535)
			(xy 381.044704 -49.287176) (xy 381.044958 -49.28743) (xy 381.05205 -49.293008) (xy 381.068963 -49.299259)
			(xy 381.077978 -49.299622) (xy 381.145034 -49.299622) (xy 381.154052 -49.299277) (xy 381.170969 -49.293021)
			(xy 381.178054 -49.28743) (xy 381.178054 -49.287176) (xy 381.178308 -49.287176) (xy 381.199241 -49.269535)
			(xy 381.245209 -49.239811) (xy 381.294955 -49.216965) (xy 381.347457 -49.201469) (xy 381.401635 -49.19364)
			(xy 381.456377 -49.19364) (xy 381.510555 -49.201469) (xy 381.563057 -49.216965) (xy 381.612803 -49.239811)
			(xy 381.658771 -49.269535) (xy 381.679704 -49.287176) (xy 381.679958 -49.28743) (xy 381.68705 -49.293008)
			(xy 381.703963 -49.299259) (xy 381.712978 -49.299622) (xy 381.780034 -49.299622) (xy 381.789052 -49.299277)
			(xy 381.805969 -49.293021) (xy 381.813054 -49.28743) (xy 381.813054 -49.287176) (xy 381.813308 -49.287176)
			(xy 381.834241 -49.269535) (xy 381.880209 -49.239811) (xy 381.929955 -49.216965) (xy 381.982457 -49.201469)
			(xy 382.036635 -49.19364) (xy 382.091377 -49.19364) (xy 382.145555 -49.201469) (xy 382.198057 -49.216965)
			(xy 382.247803 -49.239811) (xy 382.293771 -49.269535) (xy 382.314704 -49.287176) (xy 382.314958 -49.28743)
			(xy 382.32205 -49.293008) (xy 382.338963 -49.299259) (xy 382.347978 -49.299622) (xy 382.415034 -49.299622)
			(xy 382.424052 -49.299277) (xy 382.440969 -49.293021) (xy 382.448054 -49.28743) (xy 382.448054 -49.287176)
			(xy 382.448308 -49.287176) (xy 382.469223 -49.269516) (xy 382.515201 -49.239808) (xy 382.564953 -49.216977)
			(xy 382.617457 -49.20149) (xy 382.671636 -49.193667) (xy 382.699006 -49.193196) (xy 382.726257 -49.193674)
			(xy 382.780205 -49.201431) (xy 382.832499 -49.216787) (xy 382.882076 -49.239429) (xy 382.927927 -49.268896)
			(xy 382.969117 -49.304588) (xy 383.004808 -49.345778) (xy 383.034274 -49.391629) (xy 383.056915 -49.441206)
			(xy 383.07227 -49.493501) (xy 383.080026 -49.547449) (xy 383.080026 -49.601951) (xy 383.07227 -49.655899)
			(xy 383.056915 -49.708194) (xy 383.034274 -49.757771) (xy 383.004808 -49.803622) (xy 382.969117 -49.844812)
			(xy 382.927927 -49.880504) (xy 382.882076 -49.909971) (xy 382.832499 -49.932613) (xy 382.780205 -49.947969)
			(xy 382.726257 -49.955726) (xy 382.699006 -49.956212) (xy 382.671636 -49.955739) (xy 382.617457 -49.947923)
			(xy 382.564954 -49.932435) (xy 382.515207 -49.909595) (xy 382.46924 -49.879872) (xy 382.448308 -49.862232)
			(xy 382.448054 -49.861978) (xy 382.440958 -49.856405) (xy 382.424048 -49.850151) (xy 382.415034 -49.849786)
			(xy 382.347978 -49.849786) (xy 382.33896 -49.850136) (xy 382.322044 -49.856389) (xy 382.314958 -49.861978)
			(xy 382.314704 -49.862232) (xy 382.293771 -49.879873) (xy 382.247803 -49.909597) (xy 382.198057 -49.932443)
			(xy 382.145555 -49.947939) (xy 382.091377 -49.955768) (xy 382.036635 -49.955768) (xy 381.982457 -49.947939)
			(xy 381.929955 -49.932443) (xy 381.880209 -49.909597) (xy 381.834241 -49.879873) (xy 381.813308 -49.862232)
			(xy 381.813054 -49.861978) (xy 381.805958 -49.856405) (xy 381.789048 -49.850151) (xy 381.780034 -49.849786)
			(xy 381.712978 -49.849786) (xy 381.70396 -49.850136) (xy 381.687044 -49.856389) (xy 381.679958 -49.861978)
			(xy 381.679958 -49.862232) (xy 381.679704 -49.862232) (xy 381.658771 -49.879873) (xy 381.612803 -49.909597)
			(xy 381.563057 -49.932443) (xy 381.510555 -49.947939) (xy 381.456377 -49.955768) (xy 381.401635 -49.955768)
			(xy 381.347457 -49.947939) (xy 381.294955 -49.932443) (xy 381.245209 -49.909597) (xy 381.199241 -49.879873)
			(xy 381.178308 -49.862232) (xy 381.178054 -49.861978) (xy 381.170958 -49.856405) (xy 381.154048 -49.850151)
			(xy 381.145034 -49.849786) (xy 381.077978 -49.849786) (xy 381.06896 -49.850136) (xy 381.052044 -49.856389)
			(xy 381.044958 -49.861978) (xy 381.044958 -49.862232) (xy 381.044704 -49.862232) (xy 381.023785 -49.879888)
			(xy 380.977808 -49.909596) (xy 380.928057 -49.932428) (xy 380.875554 -49.947915) (xy 380.821376 -49.95574)
			(xy 380.794006 -49.956212) (xy 380.766753 -49.955741) (xy 380.712802 -49.947985) (xy 380.660504 -49.93263)
			(xy 380.610924 -49.909988) (xy 380.56507 -49.88052) (xy 380.523877 -49.844827) (xy 380.488184 -49.803634)
			(xy 380.458715 -49.757782) (xy 380.436073 -49.708201) (xy 380.420716 -49.655904) (xy 380.412959 -49.601953)
			(xy 375.76349 -49.601953) (xy 375.789875 -49.613165) (xy 375.837481 -49.642219) (xy 375.880349 -49.677894)
			(xy 375.917566 -49.719431) (xy 375.948339 -49.765944) (xy 375.972011 -49.816441) (xy 375.988079 -49.869848)
			(xy 375.996199 -49.925024) (xy 375.996708 -49.95291) (xy 375.996199 -49.980796) (xy 375.988079 -50.035972)
			(xy 375.972011 -50.089379) (xy 375.948339 -50.139876) (xy 375.917566 -50.186389) (xy 375.880349 -50.227926)
			(xy 375.837481 -50.263601) (xy 375.789875 -50.292655) (xy 375.738546 -50.314467) (xy 375.684589 -50.328573)
			(xy 375.629152 -50.334673) (xy 375.573418 -50.332636) (xy 375.518575 -50.322506) (xy 375.465791 -50.304499)
			(xy 375.416191 -50.278998) (xy 375.370833 -50.246547) (xy 375.330684 -50.207838) (xy 375.296598 -50.163695)
			(xy 375.269302 -50.11506) (xy 375.249379 -50.062969) (xy 375.237253 -50.008532) (xy 375.233182 -49.95291)
			(xy 361.527344 -49.95291) (xy 361.527344 -51.019456) (xy 373.049544 -51.019456) (xy 373.053615 -50.963834)
			(xy 373.065741 -50.909397) (xy 373.085664 -50.857306) (xy 373.11296 -50.808671) (xy 373.147046 -50.764528)
			(xy 373.187195 -50.725819) (xy 373.232553 -50.693368) (xy 373.282153 -50.667867) (xy 373.334937 -50.64986)
			(xy 373.38978 -50.63973) (xy 373.445514 -50.637693) (xy 373.500951 -50.643793) (xy 373.554908 -50.657899)
			(xy 373.606237 -50.679711) (xy 373.653843 -50.708765) (xy 373.696711 -50.74444) (xy 373.733928 -50.785977)
			(xy 373.764701 -50.83249) (xy 373.788373 -50.882987) (xy 373.804441 -50.936394) (xy 373.812561 -50.99157)
			(xy 373.81307 -51.019456) (xy 373.812561 -51.047342) (xy 373.804441 -51.102518) (xy 373.788373 -51.155925)
			(xy 373.764701 -51.206422) (xy 373.739845 -51.243992) (xy 381.43307 -51.243992) (xy 381.433514 -51.216621)
			(xy 381.441335 -51.16244) (xy 381.456828 -51.109936) (xy 381.479675 -51.060189) (xy 381.509406 -51.014224)
			(xy 381.52705 -50.993294) (xy 381.527304 -50.99304) (xy 381.53288 -50.985946) (xy 381.539133 -50.969035)
			(xy 381.539496 -50.96002) (xy 381.539496 -50.892964) (xy 381.539157 -50.883945) (xy 381.532897 -50.867028)
			(xy 381.527304 -50.859944) (xy 381.52705 -50.859944) (xy 381.52705 -50.85969) (xy 381.509401 -50.838766)
			(xy 381.479689 -50.792792) (xy 381.456854 -50.743042) (xy 381.441365 -50.69054) (xy 381.433541 -50.636362)
			(xy 381.43307 -50.608992) (xy 381.43357 -50.581742) (xy 381.441327 -50.527795) (xy 381.456682 -50.475502)
			(xy 381.479323 -50.425927) (xy 381.508788 -50.380077) (xy 381.544478 -50.338888) (xy 381.585666 -50.303196)
			(xy 381.631514 -50.27373) (xy 381.681089 -50.251087) (xy 381.733382 -50.23573) (xy 381.787328 -50.227971)
			(xy 381.814578 -50.227484) (xy 381.843496 -50.227986) (xy 381.900669 -50.236714) (xy 381.95587 -50.253973)
			(xy 382.007832 -50.279368) (xy 382.055365 -50.312316) (xy 382.09738 -50.352062) (xy 382.115568 -50.37455)
			(xy 382.12319 -50.383341) (xy 382.14408 -50.393532) (xy 382.1557 -50.394108) (xy 382.235456 -50.394108)
			(xy 382.24709 -50.393584) (xy 382.267999 -50.383384) (xy 382.275588 -50.37455) (xy 382.293773 -50.352062)
			(xy 382.335796 -50.312329) (xy 382.383332 -50.279392) (xy 382.435294 -50.254005) (xy 382.490492 -50.236749)
			(xy 382.547662 -50.22802) (xy 382.576578 -50.227484) (xy 382.60383 -50.227976) (xy 382.657779 -50.23573)
			(xy 382.710076 -50.251082) (xy 382.759656 -50.273722) (xy 382.805509 -50.303187) (xy 382.846701 -50.338877)
			(xy 382.882395 -50.380067) (xy 382.911864 -50.425918) (xy 382.934507 -50.475496) (xy 382.949864 -50.527791)
			(xy 382.957622 -50.58174) (xy 382.958086 -50.608992) (xy 382.957618 -50.635306) (xy 382.950384 -50.687435)
			(xy 382.936065 -50.738078) (xy 382.914933 -50.786277) (xy 382.887387 -50.83112) (xy 382.853948 -50.87176)
			(xy 382.834896 -50.889916) (xy 382.827485 -50.897429) (xy 382.818966 -50.916716) (xy 382.818386 -50.927254)
			(xy 382.818386 -51.00193) (xy 382.818943 -51.012476) (xy 382.827459 -51.031772) (xy 382.834896 -51.039268)
			(xy 382.853977 -51.057398) (xy 382.887432 -51.098033) (xy 382.914988 -51.142879) (xy 382.936122 -51.191085)
			(xy 382.950433 -51.241737) (xy 382.957651 -51.293874) (xy 382.958086 -51.320192) (xy 382.957637 -51.347446)
			(xy 382.949881 -51.401398) (xy 382.934525 -51.453698) (xy 382.911881 -51.503279) (xy 382.882412 -51.549133)
			(xy 382.846717 -51.590327) (xy 382.805522 -51.626021) (xy 382.759667 -51.655488) (xy 382.710085 -51.678129)
			(xy 382.657785 -51.693484) (xy 382.603832 -51.701238) (xy 382.576578 -51.7017) (xy 382.548912 -51.701205)
			(xy 382.494162 -51.693203) (xy 382.44114 -51.677383) (xy 382.390956 -51.654077) (xy 382.344661 -51.623773)
			(xy 382.303223 -51.587106) (xy 382.267511 -51.544842) (xy 382.252474 -51.521614) (xy 382.245859 -51.511919)
			(xy 382.225982 -51.499486) (xy 382.214374 -51.497738) (xy 382.134364 -51.489864) (xy 382.122725 -51.489214)
			(xy 382.100886 -51.497306) (xy 382.092454 -51.505358) (xy 382.0922 -51.505612) (xy 382.074104 -51.524178)
			(xy 382.033775 -51.556757) (xy 381.989404 -51.583572) (xy 381.941808 -51.604127) (xy 381.891867 -51.618044)
			(xy 381.8405 -51.625066) (xy 381.814578 -51.6255) (xy 381.787326 -51.625043) (xy 381.733377 -51.617283)
			(xy 381.681081 -51.601925) (xy 381.631503 -51.57928) (xy 381.585652 -51.549811) (xy 381.544462 -51.514117)
			(xy 381.508771 -51.472924) (xy 381.479305 -51.427071) (xy 381.456665 -51.377491) (xy 381.441311 -51.325194)
			(xy 381.433555 -51.271244) (xy 381.43307 -51.243992) (xy 373.739845 -51.243992) (xy 373.733928 -51.252935)
			(xy 373.696711 -51.294472) (xy 373.653843 -51.330147) (xy 373.606237 -51.359201) (xy 373.554908 -51.381013)
			(xy 373.500951 -51.395119) (xy 373.445514 -51.401219) (xy 373.38978 -51.399182) (xy 373.334937 -51.389052)
			(xy 373.282153 -51.371045) (xy 373.232553 -51.345544) (xy 373.187195 -51.313093) (xy 373.147046 -51.274384)
			(xy 373.11296 -51.230241) (xy 373.085664 -51.181606) (xy 373.065741 -51.129515) (xy 373.053615 -51.075078)
			(xy 373.049544 -51.019456) (xy 361.527344 -51.019456) (xy 361.527344 -52.035456) (xy 375.24131 -52.035456)
			(xy 375.245381 -51.979834) (xy 375.257507 -51.925397) (xy 375.27743 -51.873306) (xy 375.304726 -51.824671)
			(xy 375.338812 -51.780528) (xy 375.378961 -51.741819) (xy 375.424319 -51.709368) (xy 375.473919 -51.683867)
			(xy 375.526703 -51.66586) (xy 375.581546 -51.65573) (xy 375.63728 -51.653693) (xy 375.692717 -51.659793)
			(xy 375.746674 -51.673899) (xy 375.798003 -51.695711) (xy 375.845609 -51.724765) (xy 375.888477 -51.76044)
			(xy 375.925694 -51.801977) (xy 375.956467 -51.84849) (xy 375.980139 -51.898987) (xy 375.996207 -51.952394)
			(xy 376.004327 -52.00757) (xy 376.004836 -52.035456) (xy 376.004327 -52.063342) (xy 375.996207 -52.118518)
			(xy 375.980139 -52.171925) (xy 375.956467 -52.222422) (xy 375.925694 -52.268935) (xy 375.888477 -52.310472)
			(xy 375.845609 -52.346147) (xy 375.798003 -52.375201) (xy 375.746674 -52.397013) (xy 375.692717 -52.411119)
			(xy 375.63728 -52.417219) (xy 375.581546 -52.415182) (xy 375.526703 -52.405052) (xy 375.473919 -52.387045)
			(xy 375.424319 -52.361544) (xy 375.378961 -52.329093) (xy 375.338812 -52.290384) (xy 375.304726 -52.246241)
			(xy 375.27743 -52.197606) (xy 375.257507 -52.145515) (xy 375.245381 -52.091078) (xy 375.24131 -52.035456)
			(xy 361.527344 -52.035456) (xy 361.527344 -54.731412) (xy 361.820714 -54.731412) (xy 361.821184 -54.704042)
			(xy 361.829 -54.649863) (xy 361.844488 -54.59736) (xy 361.867329 -54.547613) (xy 361.897053 -54.501646)
			(xy 361.914694 -54.480714) (xy 361.914948 -54.48046) (xy 361.920521 -54.473365) (xy 361.926775 -54.456454)
			(xy 361.92714 -54.44744) (xy 361.92714 -54.380384) (xy 361.926803 -54.371365) (xy 361.920543 -54.354447)
			(xy 361.914948 -54.347364) (xy 361.914694 -54.347364) (xy 361.914694 -54.34711) (xy 361.897066 -54.326167)
			(xy 361.867344 -54.2802) (xy 361.8445 -54.230455) (xy 361.829004 -54.177955) (xy 361.821175 -54.123779)
			(xy 361.821174 -54.069039) (xy 361.829 -54.014862) (xy 361.844493 -53.962361) (xy 361.867335 -53.912616)
			(xy 361.897056 -53.866647) (xy 361.914694 -53.845714) (xy 361.914948 -53.84546) (xy 361.920521 -53.838365)
			(xy 361.926775 -53.821454) (xy 361.92714 -53.81244) (xy 361.92714 -53.745384) (xy 361.926803 -53.736365)
			(xy 361.920543 -53.719447) (xy 361.914948 -53.712364) (xy 361.914694 -53.712364) (xy 361.914694 -53.71211)
			(xy 361.897066 -53.691167) (xy 361.867344 -53.6452) (xy 361.8445 -53.595455) (xy 361.829004 -53.542955)
			(xy 361.821175 -53.488779) (xy 361.821174 -53.434039) (xy 361.829 -53.379862) (xy 361.844493 -53.327361)
			(xy 361.867335 -53.277616) (xy 361.897056 -53.231647) (xy 361.914694 -53.210714) (xy 361.914948 -53.21046)
			(xy 361.920521 -53.203365) (xy 361.926775 -53.186454) (xy 361.92714 -53.17744) (xy 361.92714 -53.110384)
			(xy 361.926803 -53.101365) (xy 361.920543 -53.084447) (xy 361.914948 -53.077364) (xy 361.914694 -53.077364)
			(xy 361.914694 -53.07711) (xy 361.897045 -53.056186) (xy 361.867335 -53.010211) (xy 361.844501 -52.960461)
			(xy 361.829012 -52.907959) (xy 361.821187 -52.853782) (xy 361.820714 -52.826412) (xy 361.8212 -52.799161)
			(xy 361.828956 -52.745213) (xy 361.844311 -52.692918) (xy 361.866953 -52.643341) (xy 361.896419 -52.597491)
			(xy 361.93211 -52.5563) (xy 361.973301 -52.520609) (xy 362.019151 -52.491143) (xy 362.068728 -52.468501)
			(xy 362.121023 -52.453146) (xy 362.174971 -52.44539) (xy 362.229473 -52.44539) (xy 362.283421 -52.453146)
			(xy 362.335716 -52.468501) (xy 362.385293 -52.491143) (xy 362.431143 -52.520609) (xy 362.472334 -52.5563)
			(xy 362.508025 -52.597491) (xy 362.537491 -52.643341) (xy 362.560133 -52.692918) (xy 362.575488 -52.745213)
			(xy 362.583244 -52.799161) (xy 362.58373 -52.826412) (xy 362.583288 -52.853783) (xy 362.575467 -52.907964)
			(xy 362.559973 -52.960468) (xy 362.537126 -53.010215) (xy 362.507395 -53.05618) (xy 362.48975 -53.07711)
			(xy 362.489496 -53.077364) (xy 362.483918 -53.084456) (xy 362.477666 -53.101369) (xy 362.477304 -53.110384)
			(xy 362.477304 -53.17744) (xy 362.477641 -53.186459) (xy 362.483903 -53.203376) (xy 362.489496 -53.21046)
			(xy 362.48975 -53.21046) (xy 362.48975 -53.210714) (xy 362.507403 -53.231637) (xy 362.537129 -53.277606)
			(xy 362.559976 -53.327353) (xy 362.575472 -53.379857) (xy 362.5833 -53.434038) (xy 362.583299 -53.48878)
			(xy 362.575468 -53.54296) (xy 362.559969 -53.595463) (xy 362.537121 -53.64521) (xy 362.507392 -53.691178)
			(xy 362.48975 -53.71211) (xy 362.489496 -53.712364) (xy 362.483918 -53.719456) (xy 362.477666 -53.736369)
			(xy 362.477304 -53.745384) (xy 362.477304 -53.81244) (xy 362.477641 -53.821459) (xy 362.483903 -53.838376)
			(xy 362.489496 -53.84546) (xy 362.48975 -53.84546) (xy 362.48975 -53.845714) (xy 362.507403 -53.866637)
			(xy 362.537129 -53.912606) (xy 362.559976 -53.962353) (xy 362.575472 -54.014857) (xy 362.5833 -54.069038)
			(xy 362.583299 -54.12378) (xy 362.575468 -54.17796) (xy 362.559969 -54.230463) (xy 362.537121 -54.28021)
			(xy 362.507392 -54.326178) (xy 362.48975 -54.34711) (xy 362.489496 -54.347364) (xy 362.483918 -54.354456)
			(xy 362.477666 -54.371369) (xy 362.477304 -54.380384) (xy 362.477304 -54.44744) (xy 362.477641 -54.456459)
			(xy 362.483903 -54.473376) (xy 362.489496 -54.48046) (xy 362.48975 -54.48046) (xy 362.48975 -54.480714)
			(xy 362.507354 -54.501674) (xy 362.537073 -54.547638) (xy 362.559917 -54.597379) (xy 362.575416 -54.649873)
			(xy 362.583252 -54.704045) (xy 362.58373 -54.731412) (xy 362.583244 -54.758663) (xy 362.57858 -54.791102)
			(xy 364.476538 -54.791102) (xy 364.476996 -54.763731) (xy 364.484814 -54.709552) (xy 364.500305 -54.657048)
			(xy 364.523149 -54.607301) (xy 364.552875 -54.561335) (xy 364.570518 -54.540404) (xy 364.570772 -54.54015)
			(xy 364.576352 -54.533059) (xy 364.582601 -54.516145) (xy 364.582964 -54.50713) (xy 364.582964 -54.440074)
			(xy 364.582627 -54.431055) (xy 364.576367 -54.414138) (xy 364.570772 -54.407054) (xy 364.570518 -54.407054)
			(xy 364.570518 -54.4068) (xy 364.55288 -54.385865) (xy 364.523155 -54.339898) (xy 364.500311 -54.290152)
			(xy 364.484814 -54.23765) (xy 364.476986 -54.183472) (xy 364.476986 -54.128731) (xy 364.484814 -54.074553)
			(xy 364.500309 -54.022051) (xy 364.523154 -53.972305) (xy 364.552878 -53.926337) (xy 364.570518 -53.905404)
			(xy 364.570772 -53.90515) (xy 364.576352 -53.898059) (xy 364.582601 -53.881145) (xy 364.582964 -53.87213)
			(xy 364.582964 -53.805074) (xy 364.582627 -53.796055) (xy 364.576367 -53.779138) (xy 364.570772 -53.772054)
			(xy 364.570518 -53.772054) (xy 364.570518 -53.7718) (xy 364.55288 -53.750865) (xy 364.523155 -53.704898)
			(xy 364.500311 -53.655152) (xy 364.484814 -53.60265) (xy 364.476986 -53.548472) (xy 364.476986 -53.493731)
			(xy 364.484814 -53.439553) (xy 364.500309 -53.387051) (xy 364.523154 -53.337305) (xy 364.552878 -53.291337)
			(xy 364.570518 -53.270404) (xy 364.570772 -53.27015) (xy 364.576352 -53.263059) (xy 364.582601 -53.246145)
			(xy 364.582964 -53.23713) (xy 364.582964 -53.170074) (xy 364.582627 -53.161055) (xy 364.576367 -53.144138)
			(xy 364.570772 -53.137054) (xy 364.570518 -53.137054) (xy 364.570518 -53.1368) (xy 364.552868 -53.115876)
			(xy 364.523157 -53.069902) (xy 364.500323 -53.020152) (xy 364.484835 -52.967649) (xy 364.47701 -52.913472)
			(xy 364.476538 -52.886102) (xy 364.477024 -52.858851) (xy 364.48478 -52.804903) (xy 364.500135 -52.752608)
			(xy 364.522777 -52.703031) (xy 364.552243 -52.657181) (xy 364.587934 -52.61599) (xy 364.629125 -52.580299)
			(xy 364.674975 -52.550833) (xy 364.724552 -52.528191) (xy 364.776847 -52.512836) (xy 364.830795 -52.50508)
			(xy 364.885297 -52.50508) (xy 364.939245 -52.512836) (xy 364.99154 -52.528191) (xy 365.030649 -52.546052)
			(xy 369.979673 -52.546052) (xy 369.979673 -52.491548) (xy 369.98743 -52.4376) (xy 370.002785 -52.385304)
			(xy 370.025427 -52.335726) (xy 370.054894 -52.289875) (xy 370.090586 -52.248685) (xy 370.131777 -52.212993)
			(xy 370.177628 -52.183526) (xy 370.227206 -52.160885) (xy 370.279502 -52.14553) (xy 370.33345 -52.137773)
			(xy 370.360702 -52.13731) (xy 370.388072 -52.137772) (xy 370.442252 -52.145591) (xy 370.494755 -52.161081)
			(xy 370.544502 -52.183923) (xy 370.590468 -52.213648) (xy 370.6114 -52.23129) (xy 370.611654 -52.231544)
			(xy 370.618746 -52.237123) (xy 370.635659 -52.243373) (xy 370.644674 -52.243736) (xy 370.71173 -52.243736)
			(xy 370.720747 -52.243386) (xy 370.737664 -52.237133) (xy 370.74475 -52.231544) (xy 370.74475 -52.23129)
			(xy 370.745004 -52.23129) (xy 370.765937 -52.213649) (xy 370.811905 -52.183925) (xy 370.861651 -52.161079)
			(xy 370.914153 -52.145583) (xy 370.968331 -52.137754) (xy 371.023073 -52.137754) (xy 371.077251 -52.145583)
			(xy 371.129753 -52.161079) (xy 371.179499 -52.183925) (xy 371.225467 -52.213649) (xy 371.2464 -52.23129)
			(xy 371.246654 -52.231544) (xy 371.253746 -52.237123) (xy 371.270659 -52.243373) (xy 371.279674 -52.243736)
			(xy 371.34673 -52.243736) (xy 371.355747 -52.243386) (xy 371.372664 -52.237133) (xy 371.37975 -52.231544)
			(xy 371.37975 -52.23129) (xy 371.380004 -52.23129) (xy 371.400922 -52.213634) (xy 371.446899 -52.183925)
			(xy 371.49665 -52.161093) (xy 371.549154 -52.145605) (xy 371.603332 -52.137782) (xy 371.630702 -52.13731)
			(xy 371.657954 -52.13776) (xy 371.711905 -52.145517) (xy 371.764201 -52.160873) (xy 371.813781 -52.183515)
			(xy 371.859633 -52.212983) (xy 371.900825 -52.248676) (xy 371.936518 -52.289868) (xy 371.965986 -52.335721)
			(xy 371.988628 -52.3853) (xy 372.003983 -52.437597) (xy 372.01174 -52.491548) (xy 372.01174 -52.546052)
			(xy 372.005795 -52.587398) (xy 373.055386 -52.587398) (xy 373.059457 -52.531776) (xy 373.071583 -52.477339)
			(xy 373.091506 -52.425248) (xy 373.118802 -52.376613) (xy 373.152888 -52.33247) (xy 373.193037 -52.293761)
			(xy 373.238395 -52.26131) (xy 373.287995 -52.235809) (xy 373.340779 -52.217802) (xy 373.395622 -52.207672)
			(xy 373.451356 -52.205635) (xy 373.506793 -52.211735) (xy 373.56075 -52.225841) (xy 373.612079 -52.247653)
			(xy 373.659685 -52.276707) (xy 373.702553 -52.312382) (xy 373.73977 -52.353919) (xy 373.770543 -52.400432)
			(xy 373.794215 -52.450929) (xy 373.810283 -52.504336) (xy 373.817879 -52.555952) (xy 380.883879 -52.555952)
			(xy 380.883879 -52.501448) (xy 380.891636 -52.447498) (xy 380.906993 -52.395202) (xy 380.929635 -52.345624)
			(xy 380.959103 -52.299772) (xy 380.994797 -52.258582) (xy 381.03599 -52.22289) (xy 381.081843 -52.193425)
			(xy 381.131423 -52.170785) (xy 381.18372 -52.155432) (xy 381.23767 -52.147678) (xy 381.264922 -52.147216)
			(xy 381.292293 -52.147665) (xy 381.346473 -52.155487) (xy 381.398976 -52.170979) (xy 381.448723 -52.193825)
			(xy 381.494689 -52.223553) (xy 381.51562 -52.241196) (xy 381.515874 -52.24145) (xy 381.522959 -52.247038)
			(xy 381.539877 -52.253283) (xy 381.548894 -52.253642) (xy 381.61595 -52.253642) (xy 381.624966 -52.253274)
			(xy 381.641884 -52.247035) (xy 381.64897 -52.24145) (xy 381.64897 -52.241196) (xy 381.649224 -52.241196)
			(xy 381.670173 -52.223578) (xy 381.716142 -52.193864) (xy 381.765885 -52.171023) (xy 381.818381 -52.155527)
			(xy 381.872554 -52.147693) (xy 381.899922 -52.147216) (xy 381.927174 -52.147655) (xy 381.981123 -52.155415)
			(xy 382.033418 -52.170773) (xy 382.082996 -52.193417) (xy 382.128846 -52.222885) (xy 382.170036 -52.258579)
			(xy 382.205728 -52.299771) (xy 382.235194 -52.345624) (xy 382.257835 -52.395203) (xy 382.27319 -52.447499)
			(xy 382.280946 -52.501448) (xy 382.280946 -52.555952) (xy 382.27319 -52.609901) (xy 382.257835 -52.662197)
			(xy 382.235194 -52.711776) (xy 382.205728 -52.757629) (xy 382.170036 -52.798821) (xy 382.128846 -52.834515)
			(xy 382.082996 -52.863983) (xy 382.033418 -52.886627) (xy 381.981123 -52.901985) (xy 381.927174 -52.909745)
			(xy 381.899922 -52.910232) (xy 381.872551 -52.90977) (xy 381.818372 -52.901953) (xy 381.765868 -52.886464)
			(xy 381.716121 -52.863621) (xy 381.670155 -52.833895) (xy 381.649224 -52.816252) (xy 381.64897 -52.815998)
			(xy 381.641868 -52.810434) (xy 381.624963 -52.804174) (xy 381.61595 -52.803806) (xy 381.548894 -52.803806)
			(xy 381.539877 -52.804159) (xy 381.52296 -52.810409) (xy 381.515874 -52.815998) (xy 381.515874 -52.816252)
			(xy 381.51562 -52.816252) (xy 381.494685 -52.833888) (xy 381.448714 -52.863602) (xy 381.398967 -52.886439)
			(xy 381.346467 -52.901931) (xy 381.292291 -52.909759) (xy 381.264922 -52.910232) (xy 381.23767 -52.909722)
			(xy 381.18372 -52.901968) (xy 381.131423 -52.886615) (xy 381.081843 -52.863975) (xy 381.03599 -52.83451)
			(xy 380.994797 -52.798818) (xy 380.959103 -52.757628) (xy 380.929635 -52.711776) (xy 380.906993 -52.662198)
			(xy 380.891636 -52.609902) (xy 380.883879 -52.555952) (xy 373.817879 -52.555952) (xy 373.818403 -52.559512)
			(xy 373.818912 -52.587398) (xy 373.818403 -52.615284) (xy 373.810283 -52.67046) (xy 373.794215 -52.723867)
			(xy 373.770543 -52.774364) (xy 373.73977 -52.820877) (xy 373.702553 -52.862414) (xy 373.659685 -52.898089)
			(xy 373.612079 -52.927143) (xy 373.56075 -52.948955) (xy 373.506793 -52.963061) (xy 373.451356 -52.969161)
			(xy 373.395622 -52.967124) (xy 373.340779 -52.956994) (xy 373.287995 -52.938987) (xy 373.238395 -52.913486)
			(xy 373.193037 -52.881035) (xy 373.152888 -52.842326) (xy 373.118802 -52.798183) (xy 373.091506 -52.749548)
			(xy 373.071583 -52.697457) (xy 373.059457 -52.64302) (xy 373.055386 -52.587398) (xy 372.005795 -52.587398)
			(xy 372.003983 -52.600003) (xy 371.988628 -52.6523) (xy 371.965986 -52.701879) (xy 371.936518 -52.747732)
			(xy 371.900825 -52.788924) (xy 371.859633 -52.824617) (xy 371.813781 -52.854085) (xy 371.764201 -52.876727)
			(xy 371.711905 -52.892083) (xy 371.657954 -52.89984) (xy 371.630702 -52.900326) (xy 371.603331 -52.899877)
			(xy 371.54915 -52.892058) (xy 371.496646 -52.876566) (xy 371.4469 -52.85372) (xy 371.400934 -52.82399)
			(xy 371.380004 -52.806346) (xy 371.37975 -52.806092) (xy 371.372654 -52.800519) (xy 371.355744 -52.794265)
			(xy 371.34673 -52.7939) (xy 371.279674 -52.7939) (xy 371.270656 -52.794245) (xy 371.253739 -52.800501)
			(xy 371.246654 -52.806092) (xy 371.2464 -52.806346) (xy 371.225467 -52.823987) (xy 371.179499 -52.853711)
			(xy 371.129753 -52.876557) (xy 371.077251 -52.892053) (xy 371.023073 -52.899882) (xy 370.968331 -52.899882)
			(xy 370.914153 -52.892053) (xy 370.861651 -52.876557) (xy 370.811905 -52.853711) (xy 370.765937 -52.823987)
			(xy 370.745004 -52.806346) (xy 370.74475 -52.806092) (xy 370.737654 -52.800519) (xy 370.720744 -52.794265)
			(xy 370.71173 -52.7939) (xy 370.644674 -52.7939) (xy 370.635656 -52.794245) (xy 370.618739 -52.800501)
			(xy 370.611654 -52.806092) (xy 370.611654 -52.806346) (xy 370.6114 -52.806346) (xy 370.590472 -52.82399)
			(xy 370.544499 -52.853703) (xy 370.49475 -52.876539) (xy 370.442249 -52.892029) (xy 370.388072 -52.899854)
			(xy 370.360702 -52.900326) (xy 370.33345 -52.899827) (xy 370.279502 -52.89207) (xy 370.227206 -52.876715)
			(xy 370.177628 -52.854074) (xy 370.131777 -52.824607) (xy 370.090586 -52.788915) (xy 370.054894 -52.747725)
			(xy 370.025427 -52.701874) (xy 370.002785 -52.652296) (xy 369.98743 -52.6) (xy 369.979673 -52.546052)
			(xy 365.030649 -52.546052) (xy 365.041117 -52.550833) (xy 365.086967 -52.580299) (xy 365.128158 -52.61599)
			(xy 365.163849 -52.657181) (xy 365.193315 -52.703031) (xy 365.215957 -52.752608) (xy 365.231312 -52.804903)
			(xy 365.239068 -52.858851) (xy 365.239554 -52.886102) (xy 365.2391 -52.913473) (xy 365.231281 -52.967653)
			(xy 365.21579 -53.020157) (xy 365.192945 -53.069903) (xy 365.163217 -53.115869) (xy 365.145574 -53.1368)
			(xy 365.14532 -53.137054) (xy 365.139737 -53.144143) (xy 365.13349 -53.161058) (xy 365.133128 -53.170074)
			(xy 365.133128 -53.23713) (xy 365.133465 -53.246149) (xy 365.139726 -53.263066) (xy 365.14532 -53.27015)
			(xy 365.145574 -53.27015) (xy 365.145574 -53.270404) (xy 365.163217 -53.291335) (xy 365.192941 -53.337303)
			(xy 365.215786 -53.38705) (xy 365.231283 -53.439552) (xy 365.239111 -53.493731) (xy 365.239111 -53.548472)
			(xy 365.231282 -53.602651) (xy 365.215785 -53.655153) (xy 365.19294 -53.704899) (xy 365.163215 -53.750867)
			(xy 365.146644 -53.77053) (xy 365.510826 -53.77053) (xy 365.511356 -53.741613) (xy 365.520081 -53.684442)
			(xy 365.537336 -53.629243) (xy 365.562726 -53.577281) (xy 365.595668 -53.529747) (xy 365.635407 -53.48773)
			(xy 365.657892 -53.46954) (xy 365.66667 -53.461904) (xy 365.67687 -53.441025) (xy 365.67745 -53.429408)
			(xy 365.67745 -53.349652) (xy 365.676942 -53.338016) (xy 365.666733 -53.317105) (xy 365.657892 -53.30952)
			(xy 365.635416 -53.29132) (xy 365.595681 -53.249302) (xy 365.562741 -53.201769) (xy 365.537352 -53.149809)
			(xy 365.520094 -53.094613) (xy 365.511362 -53.037445) (xy 365.510826 -53.00853) (xy 365.511283 -52.981276)
			(xy 365.519037 -52.927323) (xy 365.534391 -52.875023) (xy 365.557033 -52.825441) (xy 365.586501 -52.779586)
			(xy 365.622195 -52.738392) (xy 365.663389 -52.702698) (xy 365.709245 -52.673231) (xy 365.758827 -52.65059)
			(xy 365.811127 -52.635236) (xy 365.86508 -52.627483) (xy 365.892334 -52.627022) (xy 365.918649 -52.62746)
			(xy 365.970779 -52.6347) (xy 366.021423 -52.649024) (xy 366.069622 -52.670162) (xy 366.114464 -52.697714)
			(xy 366.155103 -52.731158) (xy 366.173258 -52.750212) (xy 366.180792 -52.757599) (xy 366.200063 -52.766131)
			(xy 366.210596 -52.766722) (xy 366.285272 -52.766722) (xy 366.295821 -52.766185) (xy 366.315115 -52.757654)
			(xy 366.32261 -52.750212) (xy 366.34077 -52.731161) (xy 366.381399 -52.697703) (xy 366.426238 -52.670143)
			(xy 366.474438 -52.649004) (xy 366.525085 -52.634686) (xy 366.577218 -52.627461) (xy 366.603534 -52.627022)
			(xy 366.630787 -52.627446) (xy 366.684739 -52.635208) (xy 366.737037 -52.650569) (xy 366.786616 -52.673216)
			(xy 366.832468 -52.702689) (xy 366.873658 -52.738387) (xy 366.909349 -52.779584) (xy 366.938814 -52.82544)
			(xy 366.961453 -52.875023) (xy 366.976805 -52.927324) (xy 366.984558 -52.981276) (xy 366.985042 -53.00853)
			(xy 366.98458 -53.036197) (xy 366.982349 -53.051456) (xy 375.24131 -53.051456) (xy 375.245381 -52.995834)
			(xy 375.257507 -52.941397) (xy 375.27743 -52.889306) (xy 375.304726 -52.840671) (xy 375.338812 -52.796528)
			(xy 375.378961 -52.757819) (xy 375.424319 -52.725368) (xy 375.473919 -52.699867) (xy 375.526703 -52.68186)
			(xy 375.581546 -52.67173) (xy 375.63728 -52.669693) (xy 375.692717 -52.675793) (xy 375.746674 -52.689899)
			(xy 375.798003 -52.711711) (xy 375.845609 -52.740765) (xy 375.888477 -52.77644) (xy 375.925694 -52.817977)
			(xy 375.956467 -52.86449) (xy 375.980139 -52.914987) (xy 375.996207 -52.968394) (xy 376.004327 -53.02357)
			(xy 376.004836 -53.051456) (xy 376.004327 -53.079342) (xy 375.996207 -53.134518) (xy 375.980139 -53.187925)
			(xy 375.956467 -53.238422) (xy 375.925694 -53.284935) (xy 375.888477 -53.326472) (xy 375.845609 -53.362147)
			(xy 375.798003 -53.391201) (xy 375.746674 -53.413013) (xy 375.692717 -53.427119) (xy 375.63728 -53.433219)
			(xy 375.581546 -53.431182) (xy 375.526703 -53.421052) (xy 375.473919 -53.403045) (xy 375.424319 -53.377544)
			(xy 375.378961 -53.345093) (xy 375.338812 -53.306384) (xy 375.304726 -53.262241) (xy 375.27743 -53.213606)
			(xy 375.257507 -53.161515) (xy 375.245381 -53.107078) (xy 375.24131 -53.051456) (xy 366.982349 -53.051456)
			(xy 366.976575 -53.09095) (xy 366.960752 -53.143974) (xy 366.937441 -53.194159) (xy 366.907131 -53.240454)
			(xy 366.870457 -53.28189) (xy 366.828187 -53.317599) (xy 366.804956 -53.332634) (xy 366.795266 -53.339255)
			(xy 366.782828 -53.359128) (xy 366.78108 -53.370734) (xy 366.773206 -53.450744) (xy 366.772568 -53.462382)
			(xy 366.780654 -53.484219) (xy 366.7887 -53.492654) (xy 366.788954 -53.492908) (xy 366.807513 -53.511012)
			(xy 366.840095 -53.551337) (xy 366.866912 -53.595707) (xy 366.887469 -53.643301) (xy 366.901387 -53.693242)
			(xy 366.908408 -53.744608) (xy 366.908842 -53.77053) (xy 366.90835 -53.79778) (xy 366.90059 -53.851726)
			(xy 366.885233 -53.904019) (xy 366.862591 -53.953594) (xy 366.833125 -53.999442) (xy 366.797434 -54.040631)
			(xy 366.756246 -54.076322) (xy 366.710397 -54.105789) (xy 366.660822 -54.128432) (xy 366.60853 -54.14379)
			(xy 366.554584 -54.15155) (xy 366.527334 -54.152038) (xy 366.499964 -54.151567) (xy 366.445784 -54.143753)
			(xy 366.393281 -54.128266) (xy 366.343534 -54.105425) (xy 366.297567 -54.0757) (xy 366.276636 -54.058058)
			(xy 366.276382 -54.057804) (xy 366.269304 -54.052204) (xy 366.252381 -54.045965) (xy 366.243362 -54.045612)
			(xy 366.176306 -54.045612) (xy 366.167289 -54.045969) (xy 366.150372 -54.052216) (xy 366.143286 -54.057804)
			(xy 366.143286 -54.058058) (xy 366.143032 -54.058058) (xy 366.122093 -54.075689) (xy 366.076123 -54.105404)
			(xy 366.026377 -54.128242) (xy 365.973878 -54.143734) (xy 365.919703 -54.151564) (xy 365.892334 -54.152038)
			(xy 365.865083 -54.151513) (xy 365.811136 -54.143762) (xy 365.758841 -54.128411) (xy 365.709263 -54.105775)
			(xy 365.663411 -54.076313) (xy 365.622219 -54.040626) (xy 365.586525 -53.99944) (xy 365.557056 -53.953593)
			(xy 365.534411 -53.904019) (xy 365.519052 -53.851726) (xy 365.511291 -53.797781) (xy 365.510826 -53.77053)
			(xy 365.146644 -53.77053) (xy 365.145574 -53.7718) (xy 365.14532 -53.772054) (xy 365.139737 -53.779143)
			(xy 365.13349 -53.796058) (xy 365.133128 -53.805074) (xy 365.133128 -53.87213) (xy 365.133465 -53.881149)
			(xy 365.139726 -53.898066) (xy 365.14532 -53.90515) (xy 365.145574 -53.90515) (xy 365.145574 -53.905404)
			(xy 365.163217 -53.926335) (xy 365.192941 -53.972303) (xy 365.215786 -54.02205) (xy 365.231283 -54.074552)
			(xy 365.239111 -54.128731) (xy 365.239111 -54.183472) (xy 365.231282 -54.237651) (xy 365.215785 -54.290153)
			(xy 365.201993 -54.320186) (xy 367.430558 -54.320186) (xy 367.431002 -54.292815) (xy 367.438823 -54.238634)
			(xy 367.454316 -54.18613) (xy 367.477163 -54.136384) (xy 367.506894 -54.090418) (xy 367.524538 -54.069488)
			(xy 367.524792 -54.069234) (xy 367.53037 -54.062141) (xy 367.536622 -54.045229) (xy 367.536984 -54.036214)
			(xy 367.536984 -53.969158) (xy 367.536603 -53.960144) (xy 367.530372 -53.943226) (xy 367.524792 -53.936138)
			(xy 367.524538 -53.936138) (xy 367.524538 -53.935884) (xy 367.506931 -53.914926) (xy 367.477213 -53.868961)
			(xy 367.45437 -53.81922) (xy 367.438872 -53.766725) (xy 367.431036 -53.712554) (xy 367.430558 -53.685186)
			(xy 367.431044 -53.657935) (xy 367.4388 -53.603987) (xy 367.454155 -53.551692) (xy 367.476797 -53.502115)
			(xy 367.506263 -53.456265) (xy 367.541954 -53.415074) (xy 367.583145 -53.379383) (xy 367.628995 -53.349917)
			(xy 367.678572 -53.327275) (xy 367.730867 -53.31192) (xy 367.784815 -53.304164) (xy 367.839317 -53.304164)
			(xy 367.893265 -53.31192) (xy 367.94556 -53.327275) (xy 367.995137 -53.349917) (xy 368.040987 -53.379383)
			(xy 368.082178 -53.415074) (xy 368.117869 -53.456265) (xy 368.143759 -53.496551) (xy 380.433564 -53.496551)
			(xy 380.433564 -53.442049) (xy 380.44132 -53.388101) (xy 380.456675 -53.335806) (xy 380.479315 -53.286228)
			(xy 380.508781 -53.240377) (xy 380.544471 -53.199186) (xy 380.585661 -53.163493) (xy 380.63151 -53.134025)
			(xy 380.681087 -53.111382) (xy 380.733381 -53.096024) (xy 380.787329 -53.088265) (xy 380.81458 -53.087778)
			(xy 380.841951 -53.088237) (xy 380.896131 -53.096053) (xy 380.948635 -53.111543) (xy 380.998382 -53.134387)
			(xy 381.044347 -53.164115) (xy 381.065278 -53.181758) (xy 381.065532 -53.182012) (xy 381.072633 -53.187578)
			(xy 381.089539 -53.193837) (xy 381.098552 -53.194204) (xy 381.165608 -53.194204) (xy 381.174625 -53.19385)
			(xy 381.191542 -53.1876) (xy 381.198628 -53.182012) (xy 381.198628 -53.181758) (xy 381.198882 -53.181758)
			(xy 381.219804 -53.164107) (xy 381.26578 -53.134398) (xy 381.315531 -53.111565) (xy 381.368033 -53.096077)
			(xy 381.42221 -53.088251) (xy 381.44958 -53.087778) (xy 381.476833 -53.088268) (xy 381.530784 -53.096022)
			(xy 381.583082 -53.111376) (xy 381.632663 -53.134017) (xy 381.678517 -53.163483) (xy 381.719711 -53.199175)
			(xy 381.755405 -53.240367) (xy 381.784874 -53.286219) (xy 381.807517 -53.335799) (xy 381.822873 -53.388097)
			(xy 381.830631 -53.442047) (xy 381.830631 -53.496553) (xy 381.822873 -53.550503) (xy 381.807517 -53.602801)
			(xy 381.784874 -53.652381) (xy 381.755405 -53.698233) (xy 381.719711 -53.739425) (xy 381.678517 -53.775117)
			(xy 381.632663 -53.804583) (xy 381.583082 -53.827224) (xy 381.530784 -53.842578) (xy 381.476833 -53.850332)
			(xy 381.44958 -53.850794) (xy 381.422209 -53.850341) (xy 381.36803 -53.84252) (xy 381.315526 -53.827028)
			(xy 381.26578 -53.804184) (xy 381.219813 -53.774456) (xy 381.198882 -53.756814) (xy 381.198628 -53.75656)
			(xy 381.191541 -53.750974) (xy 381.174624 -53.744728) (xy 381.165608 -53.744368) (xy 381.098552 -53.744368)
			(xy 381.089538 -53.744757) (xy 381.072622 -53.750983) (xy 381.065532 -53.75656) (xy 381.065532 -53.756814)
			(xy 381.065278 -53.756814) (xy 381.044329 -53.774432) (xy 380.998361 -53.804147) (xy 380.948617 -53.826986)
			(xy 380.896121 -53.842482) (xy 380.841948 -53.850317) (xy 380.81458 -53.850794) (xy 380.787329 -53.850335)
			(xy 380.733381 -53.842576) (xy 380.681087 -53.827218) (xy 380.63151 -53.804575) (xy 380.585661 -53.775107)
			(xy 380.544471 -53.739414) (xy 380.508781 -53.698223) (xy 380.479315 -53.652372) (xy 380.456675 -53.602794)
			(xy 380.44132 -53.550499) (xy 380.433564 -53.496551) (xy 368.143759 -53.496551) (xy 368.147335 -53.502115)
			(xy 368.169977 -53.551692) (xy 368.185332 -53.603987) (xy 368.193088 -53.657935) (xy 368.193574 -53.685186)
			(xy 368.193106 -53.712556) (xy 368.18529 -53.766735) (xy 368.169801 -53.819239) (xy 368.14696 -53.868986)
			(xy 368.117235 -53.914952) (xy 368.099594 -53.935884) (xy 368.09934 -53.936138) (xy 368.093766 -53.943233)
			(xy 368.087513 -53.960144) (xy 368.087148 -53.969158) (xy 368.087148 -54.036214) (xy 368.087488 -54.045233)
			(xy 368.093746 -54.06215) (xy 368.09934 -54.069234) (xy 368.099594 -54.069234) (xy 368.099594 -54.069488)
			(xy 368.11724 -54.090415) (xy 368.146951 -54.136389) (xy 368.169786 -54.186138) (xy 368.185275 -54.23864)
			(xy 368.193101 -54.292816) (xy 368.193574 -54.320186) (xy 368.193088 -54.347437) (xy 368.185332 -54.401385)
			(xy 368.169977 -54.45368) (xy 368.147335 -54.503257) (xy 368.117869 -54.549107) (xy 368.082178 -54.590298)
			(xy 368.040987 -54.625989) (xy 367.995137 -54.655455) (xy 367.94556 -54.678097) (xy 367.893265 -54.693452)
			(xy 367.839317 -54.701208) (xy 367.784815 -54.701208) (xy 367.730867 -54.693452) (xy 367.678572 -54.678097)
			(xy 367.628995 -54.655455) (xy 367.583145 -54.625989) (xy 367.541954 -54.590298) (xy 367.506263 -54.549107)
			(xy 367.476797 -54.503257) (xy 367.454155 -54.45368) (xy 367.4388 -54.401385) (xy 367.431044 -54.347437)
			(xy 367.430558 -54.320186) (xy 365.201993 -54.320186) (xy 365.19294 -54.339899) (xy 365.163215 -54.385867)
			(xy 365.145574 -54.4068) (xy 365.14532 -54.407054) (xy 365.139737 -54.414143) (xy 365.13349 -54.431058)
			(xy 365.133128 -54.440074) (xy 365.133128 -54.50713) (xy 365.133465 -54.516149) (xy 365.139726 -54.533066)
			(xy 365.14532 -54.54015) (xy 365.145574 -54.54015) (xy 365.145574 -54.540404) (xy 365.163224 -54.561327)
			(xy 365.192935 -54.607302) (xy 365.21577 -54.657052) (xy 365.231258 -54.709555) (xy 365.239082 -54.763732)
			(xy 365.239199 -54.770528) (xy 368.37112 -54.770528) (xy 368.371598 -54.743158) (xy 368.379412 -54.688979)
			(xy 368.394898 -54.636476) (xy 368.417737 -54.586729) (xy 368.44746 -54.540762) (xy 368.4651 -54.51983)
			(xy 368.465354 -54.519576) (xy 368.470963 -54.512505) (xy 368.477195 -54.495576) (xy 368.477546 -54.486556)
			(xy 368.477546 -54.4195) (xy 368.477201 -54.410482) (xy 368.470946 -54.393564) (xy 368.465354 -54.38648)
			(xy 368.4651 -54.38648) (xy 368.4651 -54.386226) (xy 368.44746 -54.365295) (xy 368.417748 -54.319322)
			(xy 368.394912 -54.269574) (xy 368.379422 -54.217073) (xy 368.371594 -54.162897) (xy 368.37112 -54.135528)
			(xy 368.371606 -54.108277) (xy 368.379362 -54.054329) (xy 368.394717 -54.002034) (xy 368.417359 -53.952457)
			(xy 368.446825 -53.906607) (xy 368.482516 -53.865416) (xy 368.523707 -53.829725) (xy 368.569557 -53.800259)
			(xy 368.619134 -53.777617) (xy 368.671429 -53.762262) (xy 368.725377 -53.754506) (xy 368.779879 -53.754506)
			(xy 368.833827 -53.762262) (xy 368.886122 -53.777617) (xy 368.935699 -53.800259) (xy 368.981549 -53.829725)
			(xy 369.02274 -53.865416) (xy 369.058431 -53.906607) (xy 369.087897 -53.952457) (xy 369.092972 -53.96357)
			(xy 373.07215 -53.96357) (xy 373.076221 -53.907948) (xy 373.088347 -53.853511) (xy 373.10827 -53.80142)
			(xy 373.135566 -53.752785) (xy 373.169652 -53.708642) (xy 373.209801 -53.669933) (xy 373.255159 -53.637482)
			(xy 373.304759 -53.611981) (xy 373.357543 -53.593974) (xy 373.412386 -53.583844) (xy 373.46812 -53.581807)
			(xy 373.523557 -53.587907) (xy 373.577514 -53.602013) (xy 373.628843 -53.623825) (xy 373.676449 -53.652879)
			(xy 373.719317 -53.688554) (xy 373.756534 -53.730091) (xy 373.787307 -53.776604) (xy 373.810979 -53.827101)
			(xy 373.827047 -53.880508) (xy 373.835167 -53.935684) (xy 373.835676 -53.96357) (xy 373.835167 -53.991456)
			(xy 373.827047 -54.046632) (xy 373.810979 -54.100039) (xy 373.787307 -54.150536) (xy 373.756534 -54.197049)
			(xy 373.719317 -54.238586) (xy 373.676449 -54.274261) (xy 373.628843 -54.303315) (xy 373.577514 -54.325127)
			(xy 373.523557 -54.339233) (xy 373.46812 -54.345333) (xy 373.412386 -54.343296) (xy 373.357543 -54.333166)
			(xy 373.304759 -54.315159) (xy 373.255159 -54.289658) (xy 373.209801 -54.257207) (xy 373.169652 -54.218498)
			(xy 373.135566 -54.174355) (xy 373.10827 -54.12572) (xy 373.088347 -54.073629) (xy 373.076221 -54.019192)
			(xy 373.07215 -53.96357) (xy 369.092972 -53.96357) (xy 369.110539 -54.002034) (xy 369.125894 -54.054329)
			(xy 369.13365 -54.108277) (xy 369.134136 -54.135528) (xy 369.133702 -54.1629) (xy 369.125879 -54.217081)
			(xy 369.110383 -54.269585) (xy 369.087534 -54.319331) (xy 369.057801 -54.365296) (xy 369.040156 -54.386226)
			(xy 369.039902 -54.38648) (xy 369.034318 -54.393568) (xy 369.02807 -54.410484) (xy 369.02771 -54.4195)
			(xy 369.02771 -54.486556) (xy 369.028086 -54.495571) (xy 369.03432 -54.512488) (xy 369.039902 -54.519576)
			(xy 369.040156 -54.519576) (xy 369.040156 -54.51983) (xy 369.057769 -54.540783) (xy 369.087486 -54.58675)
			(xy 369.110328 -54.636492) (xy 369.125825 -54.688988) (xy 369.133659 -54.74316) (xy 369.134136 -54.770528)
			(xy 369.13365 -54.797779) (xy 369.125894 -54.851727) (xy 369.110539 -54.904022) (xy 369.087897 -54.953599)
			(xy 369.065113 -54.989051) (xy 378.201168 -54.989051) (xy 378.201168 -54.934549) (xy 378.208924 -54.880602)
			(xy 378.224278 -54.828308) (xy 378.246918 -54.778732) (xy 378.276382 -54.732881) (xy 378.312072 -54.691691)
			(xy 378.35326 -54.655998) (xy 378.399109 -54.62653) (xy 378.448684 -54.603887) (xy 378.500977 -54.588529)
			(xy 378.554923 -54.58077) (xy 378.582174 -54.580282) (xy 378.610265 -54.580797) (xy 378.665841 -54.589021)
			(xy 378.71961 -54.605308) (xy 378.770407 -54.629308) (xy 378.817134 -54.660499) (xy 378.85878 -54.698208)
			(xy 378.894443 -54.741619) (xy 378.909326 -54.765448) (xy 378.91466 -54.774338) (xy 378.931678 -54.78653)
			(xy 379.024896 -54.80685) (xy 379.04547 -54.802532) (xy 379.054106 -54.79669) (xy 379.078166 -54.780684)
			(xy 379.130099 -54.755343) (xy 379.185258 -54.738119) (xy 379.242383 -54.729406) (xy 379.271276 -54.728872)
			(xy 379.298527 -54.729378) (xy 379.352476 -54.737131) (xy 379.404772 -54.752483) (xy 379.45435 -54.775121)
			(xy 379.500203 -54.804585) (xy 379.541395 -54.840274) (xy 379.577089 -54.881462) (xy 379.606558 -54.927311)
			(xy 379.629202 -54.976887) (xy 379.64456 -55.029181) (xy 379.652319 -55.083129) (xy 379.652784 -55.11038)
			(xy 379.65231 -55.13775) (xy 379.644495 -55.191929) (xy 379.629008 -55.244432) (xy 379.606168 -55.294179)
			(xy 379.576445 -55.340146) (xy 379.558804 -55.361078) (xy 379.55855 -55.361332) (xy 379.55298 -55.36843)
			(xy 379.546724 -55.385338) (xy 379.546358 -55.394352) (xy 379.546358 -55.461408) (xy 379.546699 -55.470427)
			(xy 379.552956 -55.487344) (xy 379.55855 -55.494428) (xy 379.558804 -55.494428) (xy 379.558804 -55.494682)
			(xy 379.576424 -55.515631) (xy 379.606147 -55.561597) (xy 379.628992 -55.611341) (xy 379.644488 -55.66384)
			(xy 379.652318 -55.718016) (xy 379.65232 -55.772754) (xy 379.644495 -55.826931) (xy 379.629002 -55.879431)
			(xy 379.606162 -55.929177) (xy 379.576442 -55.975145) (xy 379.558804 -55.996078) (xy 379.55855 -55.996332)
			(xy 379.55298 -56.00343) (xy 379.546724 -56.020338) (xy 379.546358 -56.029352) (xy 379.546358 -56.096408)
			(xy 379.546699 -56.105427) (xy 379.552956 -56.122344) (xy 379.55855 -56.129428) (xy 379.558804 -56.129428)
			(xy 379.558804 -56.129682) (xy 379.576449 -56.15061) (xy 379.60616 -56.196584) (xy 379.628994 -56.246332)
			(xy 379.644484 -56.298834) (xy 379.652311 -56.353011) (xy 379.652784 -56.38038) (xy 379.652298 -56.407631)
			(xy 379.644542 -56.461579) (xy 379.629187 -56.513874) (xy 379.606545 -56.563451) (xy 379.577079 -56.609301)
			(xy 379.541388 -56.650492) (xy 379.500197 -56.686183) (xy 379.454347 -56.715649) (xy 379.40477 -56.738291)
			(xy 379.352475 -56.753646) (xy 379.298527 -56.761402) (xy 379.244025 -56.761402) (xy 379.190077 -56.753646)
			(xy 379.137782 -56.738291) (xy 379.088205 -56.715649) (xy 379.042355 -56.686183) (xy 379.001164 -56.650492)
			(xy 378.965473 -56.609301) (xy 378.936007 -56.563451) (xy 378.913365 -56.513874) (xy 378.89801 -56.461579)
			(xy 378.890254 -56.407631) (xy 378.889768 -56.38038) (xy 378.890206 -56.353009) (xy 378.898028 -56.298828)
			(xy 378.913523 -56.246324) (xy 378.936371 -56.196577) (xy 378.966103 -56.150612) (xy 378.983748 -56.129682)
			(xy 378.984002 -56.129428) (xy 378.989583 -56.122338) (xy 378.995833 -56.105424) (xy 378.996194 -56.096408)
			(xy 378.996194 -56.029352) (xy 378.995813 -56.020338) (xy 378.989582 -56.00342) (xy 378.984002 -55.996332)
			(xy 378.983748 -55.996332) (xy 378.983748 -55.996078) (xy 378.966087 -55.975162) (xy 378.936361 -55.929191)
			(xy 378.913516 -55.879443) (xy 378.89802 -55.826938) (xy 378.890193 -55.772757) (xy 378.890195 -55.718013)
			(xy 378.898027 -55.663833) (xy 378.913526 -55.611329) (xy 378.936376 -55.561582) (xy 378.966105 -55.515614)
			(xy 378.983748 -55.494682) (xy 378.984002 -55.494428) (xy 378.989583 -55.487338) (xy 378.995833 -55.470424)
			(xy 378.996194 -55.461408) (xy 378.996194 -55.394352) (xy 378.995813 -55.385338) (xy 378.989582 -55.36842)
			(xy 378.984002 -55.361332) (xy 378.983748 -55.360824) (xy 378.972801 -55.348092) (xy 378.952962 -55.320999)
			(xy 378.944124 -55.306722) (xy 378.93879 -55.297832) (xy 378.921772 -55.28564) (xy 378.828554 -55.26532)
			(xy 378.80798 -55.269638) (xy 378.799344 -55.27548) (xy 378.775268 -55.291461) (xy 378.723341 -55.316809)
			(xy 378.668187 -55.33404) (xy 378.611066 -55.342761) (xy 378.582174 -55.343298) (xy 378.554923 -55.34283)
			(xy 378.500977 -55.335071) (xy 378.448684 -55.319713) (xy 378.399109 -55.29707) (xy 378.35326 -55.267602)
			(xy 378.312072 -55.231909) (xy 378.276382 -55.190719) (xy 378.246918 -55.144868) (xy 378.224278 -55.095292)
			(xy 378.208924 -55.042998) (xy 378.201168 -54.989051) (xy 369.065113 -54.989051) (xy 369.058431 -54.999449)
			(xy 369.02274 -55.04064) (xy 368.981549 -55.076331) (xy 368.935699 -55.105797) (xy 368.886122 -55.128439)
			(xy 368.833827 -55.143794) (xy 368.779879 -55.15155) (xy 368.725377 -55.15155) (xy 368.671429 -55.143794)
			(xy 368.619134 -55.128439) (xy 368.569557 -55.105797) (xy 368.523707 -55.076331) (xy 368.482516 -55.04064)
			(xy 368.446825 -54.999449) (xy 368.417359 -54.953599) (xy 368.394717 -54.904022) (xy 368.379362 -54.851727)
			(xy 368.371606 -54.797779) (xy 368.37112 -54.770528) (xy 365.239199 -54.770528) (xy 365.239554 -54.791102)
			(xy 365.239068 -54.818353) (xy 365.231312 -54.872301) (xy 365.215957 -54.924596) (xy 365.193315 -54.974173)
			(xy 365.163849 -55.020023) (xy 365.128158 -55.061214) (xy 365.086967 -55.096905) (xy 365.041117 -55.126371)
			(xy 364.99154 -55.149013) (xy 364.939245 -55.164368) (xy 364.885297 -55.172124) (xy 364.830795 -55.172124)
			(xy 364.776847 -55.164368) (xy 364.724552 -55.149013) (xy 364.674975 -55.126371) (xy 364.629125 -55.096905)
			(xy 364.587934 -55.061214) (xy 364.552243 -55.020023) (xy 364.522777 -54.974173) (xy 364.500135 -54.924596)
			(xy 364.48478 -54.872301) (xy 364.477024 -54.818353) (xy 364.476538 -54.791102) (xy 362.57858 -54.791102)
			(xy 362.575488 -54.812611) (xy 362.560133 -54.864906) (xy 362.537491 -54.914483) (xy 362.508025 -54.960333)
			(xy 362.472334 -55.001524) (xy 362.431143 -55.037215) (xy 362.385293 -55.066681) (xy 362.335716 -55.089323)
			(xy 362.283421 -55.104678) (xy 362.229473 -55.112434) (xy 362.174971 -55.112434) (xy 362.121023 -55.104678)
			(xy 362.068728 -55.089323) (xy 362.019151 -55.066681) (xy 361.973301 -55.037215) (xy 361.93211 -55.001524)
			(xy 361.896419 -54.960333) (xy 361.866953 -54.914483) (xy 361.844311 -54.864906) (xy 361.828956 -54.812611)
			(xy 361.8212 -54.758663) (xy 361.820714 -54.731412) (xy 361.527344 -54.731412) (xy 361.527344 -55.722266)
			(xy 374.134124 -55.722266) (xy 374.138195 -55.666644) (xy 374.150321 -55.612207) (xy 374.170244 -55.560116)
			(xy 374.19754 -55.511481) (xy 374.231626 -55.467338) (xy 374.271775 -55.428629) (xy 374.317133 -55.396178)
			(xy 374.366733 -55.370677) (xy 374.419517 -55.35267) (xy 374.47436 -55.34254) (xy 374.530094 -55.340503)
			(xy 374.585531 -55.346603) (xy 374.639488 -55.360709) (xy 374.690817 -55.382521) (xy 374.738423 -55.411575)
			(xy 374.749569 -55.420851) (xy 376.524768 -55.420851) (xy 376.524768 -55.366349) (xy 376.532524 -55.312402)
			(xy 376.547878 -55.260108) (xy 376.570518 -55.210532) (xy 376.599982 -55.164681) (xy 376.635672 -55.123491)
			(xy 376.67686 -55.087798) (xy 376.722709 -55.05833) (xy 376.772284 -55.035687) (xy 376.824577 -55.020329)
			(xy 376.878523 -55.01257) (xy 376.905774 -55.012082) (xy 376.932087 -55.012572) (xy 376.984214 -55.019803)
			(xy 377.034856 -55.034118) (xy 377.083055 -55.055247) (xy 377.127899 -55.082788) (xy 377.16854 -55.116223)
			(xy 377.186698 -55.135272) (xy 377.194222 -55.142671) (xy 377.2135 -55.151198) (xy 377.224036 -55.151782)
			(xy 377.298712 -55.151782) (xy 377.309265 -55.151278) (xy 377.32856 -55.142726) (xy 377.33605 -55.135272)
			(xy 377.354183 -55.116194) (xy 377.394818 -55.08274) (xy 377.439663 -55.055184) (xy 377.487868 -55.03405)
			(xy 377.53852 -55.019738) (xy 377.590657 -55.012518) (xy 377.616974 -55.012082) (xy 377.644227 -55.012564)
			(xy 377.69818 -55.020317) (xy 377.750479 -55.035671) (xy 377.800061 -55.058311) (xy 377.845917 -55.087778)
			(xy 377.887111 -55.12347) (xy 377.922807 -55.164663) (xy 377.952276 -55.210516) (xy 377.97492 -55.260096)
			(xy 377.990277 -55.312395) (xy 377.998035 -55.366347) (xy 377.998035 -55.420853) (xy 377.990277 -55.474805)
			(xy 377.97492 -55.527104) (xy 377.952276 -55.576684) (xy 377.922807 -55.622537) (xy 377.887111 -55.66373)
			(xy 377.845917 -55.699422) (xy 377.800061 -55.728889) (xy 377.750479 -55.751529) (xy 377.69818 -55.766883)
			(xy 377.644227 -55.774636) (xy 377.616974 -55.775098) (xy 377.590659 -55.774649) (xy 377.53853 -55.76741)
			(xy 377.487887 -55.753088) (xy 377.439688 -55.731952) (xy 377.394845 -55.704402) (xy 377.354206 -55.670961)
			(xy 377.33605 -55.651908) (xy 377.328548 -55.644484) (xy 377.309253 -55.635972) (xy 377.298712 -55.635398)
			(xy 377.224036 -55.635398) (xy 377.213487 -55.635934) (xy 377.194192 -55.644464) (xy 377.186698 -55.651908)
			(xy 377.168538 -55.670959) (xy 377.127909 -55.704416) (xy 377.08307 -55.731976) (xy 377.03487 -55.753115)
			(xy 376.984223 -55.767433) (xy 376.93209 -55.774659) (xy 376.905774 -55.775098) (xy 376.878523 -55.77463)
			(xy 376.824577 -55.766871) (xy 376.772284 -55.751513) (xy 376.722709 -55.72887) (xy 376.67686 -55.699402)
			(xy 376.635672 -55.663709) (xy 376.599982 -55.622519) (xy 376.570518 -55.576668) (xy 376.547878 -55.527092)
			(xy 376.532524 -55.474798) (xy 376.524768 -55.420851) (xy 374.749569 -55.420851) (xy 374.781291 -55.44725)
			(xy 374.818508 -55.488787) (xy 374.849281 -55.5353) (xy 374.872953 -55.585797) (xy 374.889021 -55.639204)
			(xy 374.897141 -55.69438) (xy 374.89765 -55.722266) (xy 374.897141 -55.750152) (xy 374.889021 -55.805328)
			(xy 374.872953 -55.858735) (xy 374.849281 -55.909232) (xy 374.818508 -55.955745) (xy 374.781291 -55.997282)
			(xy 374.738423 -56.032957) (xy 374.690817 -56.062011) (xy 374.639488 -56.083823) (xy 374.585531 -56.097929)
			(xy 374.530094 -56.104029) (xy 374.47436 -56.101992) (xy 374.419517 -56.091862) (xy 374.366733 -56.073855)
			(xy 374.317133 -56.048354) (xy 374.271775 -56.015903) (xy 374.231626 -55.977194) (xy 374.19754 -55.933051)
			(xy 374.170244 -55.884416) (xy 374.150321 -55.832325) (xy 374.138195 -55.777888) (xy 374.134124 -55.722266)
			(xy 361.527344 -55.722266) (xy 361.527344 -57.002934) (xy 369.863624 -57.002934) (xy 369.864125 -56.974842)
			(xy 369.872349 -56.919265) (xy 369.888637 -56.865495) (xy 369.912638 -56.814697) (xy 369.943833 -56.76797)
			(xy 369.981545 -56.726325) (xy 370.024959 -56.690664) (xy 370.04879 -56.675782) (xy 370.05768 -56.670448)
			(xy 370.069872 -56.65343) (xy 370.090192 -56.560212) (xy 370.085874 -56.539638) (xy 370.080032 -56.531002)
			(xy 370.064034 -56.506937) (xy 370.03869 -56.455006) (xy 370.021464 -56.399848) (xy 370.012748 -56.342724)
			(xy 370.012214 -56.313832) (xy 370.012685 -56.286579) (xy 370.020438 -56.232627) (xy 370.035791 -56.180328)
			(xy 370.058432 -56.130747) (xy 370.087899 -56.084892) (xy 370.123592 -56.043699) (xy 370.164784 -56.008005)
			(xy 370.210638 -55.978537) (xy 370.260219 -55.955895) (xy 370.312517 -55.94054) (xy 370.366469 -55.932786)
			(xy 370.393722 -55.932324) (xy 370.421093 -55.932771) (xy 370.475273 -55.940593) (xy 370.527777 -55.956086)
			(xy 370.577523 -55.978932) (xy 370.623489 -56.008661) (xy 370.64442 -56.026304) (xy 370.644674 -56.026558)
			(xy 370.651759 -56.032147) (xy 370.668677 -56.038391) (xy 370.677694 -56.03875) (xy 370.74475 -56.03875)
			(xy 370.753766 -56.03838) (xy 370.770683 -56.032143) (xy 370.77777 -56.026558) (xy 370.77777 -56.026304)
			(xy 370.778024 -56.026304) (xy 370.798957 -56.008663) (xy 370.844925 -55.978939) (xy 370.894671 -55.956093)
			(xy 370.947173 -55.940597) (xy 371.001351 -55.932768) (xy 371.056093 -55.932768) (xy 371.110271 -55.940597)
			(xy 371.162773 -55.956093) (xy 371.212519 -55.978939) (xy 371.258487 -56.008663) (xy 371.27942 -56.026304)
			(xy 371.279674 -56.026558) (xy 371.286759 -56.032147) (xy 371.303677 -56.038391) (xy 371.312694 -56.03875)
			(xy 371.37975 -56.03875) (xy 371.388766 -56.03838) (xy 371.405683 -56.032143) (xy 371.41277 -56.026558)
			(xy 371.41277 -56.026304) (xy 371.413024 -56.026304) (xy 371.433974 -56.008688) (xy 371.479942 -55.978972)
			(xy 371.529685 -55.956132) (xy 371.582182 -55.940635) (xy 371.636354 -55.932801) (xy 371.663722 -55.932324)
			(xy 371.690975 -55.932747) (xy 371.744924 -55.940507) (xy 371.797221 -55.955865) (xy 371.846799 -55.97851)
			(xy 371.892651 -56.007979) (xy 371.933842 -56.043674) (xy 371.969534 -56.084867) (xy 371.999001 -56.13072)
			(xy 372.021642 -56.1803) (xy 372.036998 -56.232597) (xy 372.044754 -56.286547) (xy 372.044754 -56.297068)
			(xy 372.386604 -56.297068) (xy 372.390675 -56.241446) (xy 372.402801 -56.187009) (xy 372.422724 -56.134918)
			(xy 372.45002 -56.086283) (xy 372.484106 -56.04214) (xy 372.524255 -56.003431) (xy 372.569613 -55.97098)
			(xy 372.619213 -55.945479) (xy 372.671997 -55.927472) (xy 372.72684 -55.917342) (xy 372.782574 -55.915305)
			(xy 372.838011 -55.921405) (xy 372.891968 -55.935511) (xy 372.943297 -55.957323) (xy 372.990903 -55.986377)
			(xy 373.033771 -56.022052) (xy 373.070988 -56.063589) (xy 373.101761 -56.110102) (xy 373.125433 -56.160599)
			(xy 373.141501 -56.214006) (xy 373.149621 -56.269182) (xy 373.15013 -56.297068) (xy 373.149621 -56.324954)
			(xy 373.141501 -56.38013) (xy 373.125433 -56.433537) (xy 373.101761 -56.484034) (xy 373.070988 -56.530547)
			(xy 373.033771 -56.572084) (xy 372.990903 -56.607759) (xy 372.943297 -56.636813) (xy 372.891968 -56.658625)
			(xy 372.838011 -56.672731) (xy 372.782574 -56.678831) (xy 372.72684 -56.676794) (xy 372.671997 -56.666664)
			(xy 372.619213 -56.648657) (xy 372.569613 -56.623156) (xy 372.524255 -56.590705) (xy 372.484106 -56.551996)
			(xy 372.45002 -56.507853) (xy 372.422724 -56.459218) (xy 372.402801 -56.407127) (xy 372.390675 -56.35269)
			(xy 372.386604 -56.297068) (xy 372.044754 -56.297068) (xy 372.044754 -56.341053) (xy 372.036998 -56.395003)
			(xy 372.021642 -56.4473) (xy 371.999001 -56.49688) (xy 371.969534 -56.542733) (xy 371.933842 -56.583926)
			(xy 371.892651 -56.619621) (xy 371.846799 -56.64909) (xy 371.797221 -56.671735) (xy 371.744924 -56.687093)
			(xy 371.690975 -56.694853) (xy 371.663722 -56.69534) (xy 371.636352 -56.694876) (xy 371.582172 -56.68706)
			(xy 371.529668 -56.671571) (xy 371.479921 -56.648728) (xy 371.433955 -56.619002) (xy 371.413024 -56.60136)
			(xy 371.41277 -56.601106) (xy 371.405667 -56.595543) (xy 371.388763 -56.589282) (xy 371.37975 -56.588914)
			(xy 371.312694 -56.588914) (xy 371.303676 -56.589265) (xy 371.286759 -56.595516) (xy 371.279674 -56.601106)
			(xy 371.279674 -56.60136) (xy 371.27942 -56.60136) (xy 371.258487 -56.619001) (xy 371.212519 -56.648725)
			(xy 371.162773 -56.671571) (xy 371.110271 -56.687067) (xy 371.056093 -56.694896) (xy 371.001351 -56.694896)
			(xy 370.947173 -56.687067) (xy 370.894671 -56.671571) (xy 370.844925 -56.648725) (xy 370.798957 -56.619001)
			(xy 370.778024 -56.60136) (xy 370.77777 -56.601106) (xy 370.770667 -56.595543) (xy 370.753763 -56.589282)
			(xy 370.74475 -56.588914) (xy 370.677694 -56.588914) (xy 370.668676 -56.589265) (xy 370.651759 -56.595516)
			(xy 370.644674 -56.601106) (xy 370.644166 -56.60136) (xy 370.631431 -56.612304) (xy 370.60434 -56.632145)
			(xy 370.590064 -56.640984) (xy 370.581174 -56.646318) (xy 370.568982 -56.663336) (xy 370.548662 -56.756554)
			(xy 370.55298 -56.777128) (xy 370.558822 -56.785764) (xy 370.574811 -56.809834) (xy 370.600156 -56.861764)
			(xy 370.617384 -56.91692) (xy 370.626103 -56.974042) (xy 370.62664 -57.002934) (xy 370.626154 -57.030185)
			(xy 370.618398 -57.084133) (xy 370.603043 -57.136428) (xy 370.580401 -57.186005) (xy 370.550935 -57.231855)
			(xy 370.515244 -57.273046) (xy 370.474053 -57.308737) (xy 370.428203 -57.338203) (xy 370.378626 -57.360845)
			(xy 370.326331 -57.3762) (xy 370.272383 -57.383956) (xy 370.217881 -57.383956) (xy 370.163933 -57.3762)
			(xy 370.111638 -57.360845) (xy 370.062061 -57.338203) (xy 370.016211 -57.308737) (xy 369.97502 -57.273046)
			(xy 369.939329 -57.231855) (xy 369.909863 -57.186005) (xy 369.887221 -57.136428) (xy 369.871866 -57.084133)
			(xy 369.86411 -57.030185) (xy 369.863624 -57.002934) (xy 361.527344 -57.002934) (xy 361.527344 -57.48528)
			(xy 378.906022 -57.48528) (xy 378.910093 -57.429658) (xy 378.922219 -57.375221) (xy 378.942142 -57.32313)
			(xy 378.969438 -57.274495) (xy 379.003524 -57.230352) (xy 379.043673 -57.191643) (xy 379.089031 -57.159192)
			(xy 379.138631 -57.133691) (xy 379.191415 -57.115684) (xy 379.246258 -57.105554) (xy 379.301992 -57.103517)
			(xy 379.357429 -57.109617) (xy 379.411386 -57.123723) (xy 379.462715 -57.145535) (xy 379.510321 -57.174589)
			(xy 379.553189 -57.210264) (xy 379.590406 -57.251801) (xy 379.621179 -57.298314) (xy 379.644851 -57.348811)
			(xy 379.660919 -57.402218) (xy 379.669039 -57.457394) (xy 379.669548 -57.48528) (xy 379.669039 -57.513166)
			(xy 379.660919 -57.568342) (xy 379.644851 -57.621749) (xy 379.621179 -57.672246) (xy 379.590406 -57.718759)
			(xy 379.553189 -57.760296) (xy 379.510321 -57.795971) (xy 379.462715 -57.825025) (xy 379.411386 -57.846837)
			(xy 379.357429 -57.860943) (xy 379.301992 -57.867043) (xy 379.246258 -57.865006) (xy 379.191415 -57.854876)
			(xy 379.138631 -57.836869) (xy 379.089031 -57.811368) (xy 379.043673 -57.778917) (xy 379.003524 -57.740208)
			(xy 378.969438 -57.696065) (xy 378.942142 -57.64743) (xy 378.922219 -57.595339) (xy 378.910093 -57.540902)
			(xy 378.906022 -57.48528) (xy 361.527344 -57.48528) (xy 361.527344 -58.679334) (xy 370.295424 -58.679334)
			(xy 370.29584 -58.653018) (xy 370.303084 -58.600887) (xy 370.317413 -58.550243) (xy 370.338555 -58.502044)
			(xy 370.36611 -58.457202) (xy 370.399558 -58.416565) (xy 370.418614 -58.39841) (xy 370.426015 -58.390889)
			(xy 370.43454 -58.371608) (xy 370.435124 -58.361072) (xy 370.435124 -58.286396) (xy 370.434603 -58.275846)
			(xy 370.426061 -58.256551) (xy 370.418614 -58.249058) (xy 370.399548 -58.230913) (xy 370.366091 -58.190281)
			(xy 370.338533 -58.145439) (xy 370.317396 -58.097236) (xy 370.303082 -58.046587) (xy 370.29586 -57.994451)
			(xy 370.295424 -57.968134) (xy 370.29591 -57.940883) (xy 370.303666 -57.886935) (xy 370.319021 -57.83464)
			(xy 370.341663 -57.785063) (xy 370.371129 -57.739213) (xy 370.40682 -57.698022) (xy 370.448011 -57.662331)
			(xy 370.493861 -57.632865) (xy 370.543438 -57.610223) (xy 370.595733 -57.594868) (xy 370.649681 -57.587112)
			(xy 370.704183 -57.587112) (xy 370.758131 -57.594868) (xy 370.810426 -57.610223) (xy 370.860003 -57.632865)
			(xy 370.905853 -57.662331) (xy 370.947044 -57.698022) (xy 370.982735 -57.739213) (xy 371.012201 -57.785063)
			(xy 371.034843 -57.83464) (xy 371.050198 -57.886935) (xy 371.057954 -57.940883) (xy 371.05844 -57.968134)
			(xy 371.058014 -57.99445) (xy 371.050774 -58.046581) (xy 371.043506 -58.072274) (xy 374.293636 -58.072274)
			(xy 374.297707 -58.016652) (xy 374.309833 -57.962215) (xy 374.329756 -57.910124) (xy 374.357052 -57.861489)
			(xy 374.391138 -57.817346) (xy 374.431287 -57.778637) (xy 374.476645 -57.746186) (xy 374.526245 -57.720685)
			(xy 374.579029 -57.702678) (xy 374.633872 -57.692548) (xy 374.689606 -57.690511) (xy 374.745043 -57.696611)
			(xy 374.799 -57.710717) (xy 374.850329 -57.732529) (xy 374.897935 -57.761583) (xy 374.940803 -57.797258)
			(xy 374.97802 -57.838795) (xy 375.008793 -57.885308) (xy 375.032465 -57.935805) (xy 375.048533 -57.989212)
			(xy 375.056653 -58.044388) (xy 375.057162 -58.072274) (xy 375.057092 -58.076084) (xy 379.658116 -58.076084)
			(xy 379.662187 -58.020462) (xy 379.674313 -57.966025) (xy 379.694236 -57.913934) (xy 379.721532 -57.865299)
			(xy 379.755618 -57.821156) (xy 379.795767 -57.782447) (xy 379.841125 -57.749996) (xy 379.890725 -57.724495)
			(xy 379.943509 -57.706488) (xy 379.998352 -57.696358) (xy 380.054086 -57.694321) (xy 380.109523 -57.700421)
			(xy 380.16348 -57.714527) (xy 380.214809 -57.736339) (xy 380.262415 -57.765393) (xy 380.305283 -57.801068)
			(xy 380.3425 -57.842605) (xy 380.358836 -57.867296) (xy 381.9431 -57.867296) (xy 381.947171 -57.811674)
			(xy 381.959297 -57.757237) (xy 381.97922 -57.705146) (xy 382.006516 -57.656511) (xy 382.040602 -57.612368)
			(xy 382.080751 -57.573659) (xy 382.126109 -57.541208) (xy 382.175709 -57.515707) (xy 382.228493 -57.4977)
			(xy 382.283336 -57.48757) (xy 382.33907 -57.485533) (xy 382.394507 -57.491633) (xy 382.448464 -57.505739)
			(xy 382.499793 -57.527551) (xy 382.547399 -57.556605) (xy 382.590267 -57.59228) (xy 382.627484 -57.633817)
			(xy 382.658257 -57.68033) (xy 382.681929 -57.730827) (xy 382.697997 -57.784234) (xy 382.706117 -57.83941)
			(xy 382.706626 -57.867296) (xy 382.706117 -57.895182) (xy 382.697997 -57.950358) (xy 382.681929 -58.003765)
			(xy 382.658257 -58.054262) (xy 382.627484 -58.100775) (xy 382.590267 -58.142312) (xy 382.547399 -58.177987)
			(xy 382.499793 -58.207041) (xy 382.448464 -58.228853) (xy 382.394507 -58.242959) (xy 382.33907 -58.249059)
			(xy 382.283336 -58.247022) (xy 382.228493 -58.236892) (xy 382.175709 -58.218885) (xy 382.126109 -58.193384)
			(xy 382.080751 -58.160933) (xy 382.040602 -58.122224) (xy 382.006516 -58.078081) (xy 381.97922 -58.029446)
			(xy 381.959297 -57.977355) (xy 381.947171 -57.922918) (xy 381.9431 -57.867296) (xy 380.358836 -57.867296)
			(xy 380.373273 -57.889118) (xy 380.396945 -57.939615) (xy 380.413013 -57.993022) (xy 380.421133 -58.048198)
			(xy 380.421642 -58.076084) (xy 380.421133 -58.10397) (xy 380.413013 -58.159146) (xy 380.396945 -58.212553)
			(xy 380.373273 -58.26305) (xy 380.3425 -58.309563) (xy 380.305283 -58.3511) (xy 380.262415 -58.386775)
			(xy 380.214809 -58.415829) (xy 380.16348 -58.437641) (xy 380.109523 -58.451747) (xy 380.054086 -58.457847)
			(xy 379.998352 -58.45581) (xy 379.943509 -58.44568) (xy 379.890725 -58.427673) (xy 379.841125 -58.402172)
			(xy 379.795767 -58.369721) (xy 379.755618 -58.331012) (xy 379.721532 -58.286869) (xy 379.694236 -58.238234)
			(xy 379.674313 -58.186143) (xy 379.662187 -58.131706) (xy 379.658116 -58.076084) (xy 375.057092 -58.076084)
			(xy 375.056653 -58.10016) (xy 375.048533 -58.155336) (xy 375.032465 -58.208743) (xy 375.008793 -58.25924)
			(xy 374.97802 -58.305753) (xy 374.940803 -58.34729) (xy 374.897935 -58.382965) (xy 374.850329 -58.412019)
			(xy 374.799 -58.433831) (xy 374.745043 -58.447937) (xy 374.689606 -58.454037) (xy 374.633872 -58.452)
			(xy 374.579029 -58.44187) (xy 374.526245 -58.423863) (xy 374.476645 -58.398362) (xy 374.431287 -58.365911)
			(xy 374.391138 -58.327202) (xy 374.357052 -58.283059) (xy 374.329756 -58.234424) (xy 374.309833 -58.182333)
			(xy 374.297707 -58.127896) (xy 374.293636 -58.072274) (xy 371.043506 -58.072274) (xy 371.036448 -58.097225)
			(xy 371.015308 -58.145424) (xy 370.987753 -58.190267) (xy 370.954306 -58.230903) (xy 370.93525 -58.249058)
			(xy 370.927872 -58.2566) (xy 370.919333 -58.275864) (xy 370.91874 -58.286396) (xy 370.91874 -58.361072)
			(xy 370.919259 -58.371623) (xy 370.9278 -58.390919) (xy 370.93525 -58.39841) (xy 370.954313 -58.416558)
			(xy 370.987767 -58.45719) (xy 371.015324 -58.502033) (xy 371.036461 -58.550235) (xy 371.039567 -58.561224)
			(xy 380.86233 -58.561224) (xy 380.866401 -58.505602) (xy 380.878527 -58.451165) (xy 380.89845 -58.399074)
			(xy 380.925746 -58.350439) (xy 380.959832 -58.306296) (xy 380.999981 -58.267587) (xy 381.045339 -58.235136)
			(xy 381.094939 -58.209635) (xy 381.147723 -58.191628) (xy 381.202566 -58.181498) (xy 381.2583 -58.179461)
			(xy 381.313737 -58.185561) (xy 381.367694 -58.199667) (xy 381.419023 -58.221479) (xy 381.466629 -58.250533)
			(xy 381.509497 -58.286208) (xy 381.546714 -58.327745) (xy 381.577487 -58.374258) (xy 381.601159 -58.424755)
			(xy 381.608669 -58.449718) (xy 383.10896 -58.449718) (xy 383.113031 -58.394096) (xy 383.125157 -58.339659)
			(xy 383.14508 -58.287568) (xy 383.172376 -58.238933) (xy 383.206462 -58.19479) (xy 383.246611 -58.156081)
			(xy 383.291969 -58.12363) (xy 383.341569 -58.098129) (xy 383.394353 -58.080122) (xy 383.449196 -58.069992)
			(xy 383.50493 -58.067955) (xy 383.560367 -58.074055) (xy 383.614324 -58.088161) (xy 383.665653 -58.109973)
			(xy 383.713259 -58.139027) (xy 383.756127 -58.174702) (xy 383.793344 -58.216239) (xy 383.824117 -58.262752)
			(xy 383.847789 -58.313249) (xy 383.863857 -58.366656) (xy 383.871977 -58.421832) (xy 383.872486 -58.449718)
			(xy 383.871977 -58.477604) (xy 383.863857 -58.53278) (xy 383.847789 -58.586187) (xy 383.824117 -58.636684)
			(xy 383.793344 -58.683197) (xy 383.756127 -58.724734) (xy 383.713259 -58.760409) (xy 383.665653 -58.789463)
			(xy 383.614324 -58.811275) (xy 383.560367 -58.825381) (xy 383.50493 -58.831481) (xy 383.449196 -58.829444)
			(xy 383.394353 -58.819314) (xy 383.341569 -58.801307) (xy 383.291969 -58.775806) (xy 383.246611 -58.743355)
			(xy 383.206462 -58.704646) (xy 383.172376 -58.660503) (xy 383.14508 -58.611868) (xy 383.125157 -58.559777)
			(xy 383.113031 -58.50534) (xy 383.10896 -58.449718) (xy 381.608669 -58.449718) (xy 381.617227 -58.478162)
			(xy 381.625347 -58.533338) (xy 381.625856 -58.561224) (xy 381.625347 -58.58911) (xy 381.617227 -58.644286)
			(xy 381.601159 -58.697693) (xy 381.577487 -58.74819) (xy 381.546714 -58.794703) (xy 381.509497 -58.83624)
			(xy 381.466629 -58.871915) (xy 381.419023 -58.900969) (xy 381.367694 -58.922781) (xy 381.313737 -58.936887)
			(xy 381.2583 -58.942987) (xy 381.202566 -58.94095) (xy 381.147723 -58.93082) (xy 381.094939 -58.912813)
			(xy 381.045339 -58.887312) (xy 380.999981 -58.854861) (xy 380.959832 -58.816152) (xy 380.925746 -58.772009)
			(xy 380.89845 -58.723374) (xy 380.878527 -58.671283) (xy 380.866401 -58.616846) (xy 380.86233 -58.561224)
			(xy 371.039567 -58.561224) (xy 371.050777 -58.600883) (xy 371.058002 -58.653018) (xy 371.05844 -58.679334)
			(xy 371.057954 -58.706585) (xy 371.050198 -58.760533) (xy 371.034843 -58.812828) (xy 371.012201 -58.862405)
			(xy 370.982735 -58.908255) (xy 370.947044 -58.949446) (xy 370.905853 -58.985137) (xy 370.860003 -59.014603)
			(xy 370.810426 -59.037245) (xy 370.758131 -59.0526) (xy 370.704183 -59.060356) (xy 370.649681 -59.060356)
			(xy 370.595733 -59.0526) (xy 370.543438 -59.037245) (xy 370.493861 -59.014603) (xy 370.448011 -58.985137)
			(xy 370.40682 -58.949446) (xy 370.371129 -58.908255) (xy 370.341663 -58.862405) (xy 370.319021 -58.812828)
			(xy 370.303666 -58.760533) (xy 370.29591 -58.706585) (xy 370.295424 -58.679334) (xy 361.527344 -58.679334)
			(xy 361.527344 -59.174634) (xy 379.393194 -59.174634) (xy 379.397265 -59.119012) (xy 379.409391 -59.064575)
			(xy 379.429314 -59.012484) (xy 379.45661 -58.963849) (xy 379.490696 -58.919706) (xy 379.530845 -58.880997)
			(xy 379.576203 -58.848546) (xy 379.625803 -58.823045) (xy 379.678587 -58.805038) (xy 379.73343 -58.794908)
			(xy 379.789164 -58.792871) (xy 379.844601 -58.798971) (xy 379.898558 -58.813077) (xy 379.949887 -58.834889)
			(xy 379.997493 -58.863943) (xy 380.040361 -58.899618) (xy 380.077578 -58.941155) (xy 380.108351 -58.987668)
			(xy 380.132023 -59.038165) (xy 380.148091 -59.091572) (xy 380.156211 -59.146748) (xy 380.15672 -59.174634)
			(xy 380.156211 -59.20252) (xy 380.148091 -59.257696) (xy 380.132023 -59.311103) (xy 380.108351 -59.3616)
			(xy 380.077578 -59.408113) (xy 380.040361 -59.44965) (xy 379.997493 -59.485325) (xy 379.949887 -59.514379)
			(xy 379.898558 -59.536191) (xy 379.844601 -59.550297) (xy 379.789164 -59.556397) (xy 379.73343 -59.55436)
			(xy 379.678587 -59.54423) (xy 379.625803 -59.526223) (xy 379.576203 -59.500722) (xy 379.530845 -59.468271)
			(xy 379.490696 -59.429562) (xy 379.45661 -59.385419) (xy 379.429314 -59.336784) (xy 379.409391 -59.284693)
			(xy 379.397265 -59.230256) (xy 379.393194 -59.174634) (xy 361.527344 -59.174634) (xy 361.527344 -60.01925)
			(xy 370.435884 -60.01925) (xy 370.435884 -59.96475) (xy 370.44364 -59.910804) (xy 370.458994 -59.858511)
			(xy 370.481634 -59.808936) (xy 370.511098 -59.763087) (xy 370.546788 -59.721898) (xy 370.587976 -59.686207)
			(xy 370.633824 -59.65674) (xy 370.683398 -59.634099) (xy 370.73569 -59.618743) (xy 370.789636 -59.610985)
			(xy 370.816886 -59.610498) (xy 370.844256 -59.610973) (xy 370.898435 -59.618789) (xy 370.950938 -59.634276)
			(xy 371.000685 -59.657115) (xy 371.046652 -59.686838) (xy 371.067584 -59.704478) (xy 371.067838 -59.704732)
			(xy 371.074936 -59.710302) (xy 371.091844 -59.716558) (xy 371.100858 -59.716924) (xy 371.167914 -59.716924)
			(xy 371.176931 -59.716568) (xy 371.193847 -59.710319) (xy 371.200934 -59.704732) (xy 371.200934 -59.704478)
			(xy 371.201188 -59.704478) (xy 371.222121 -59.686837) (xy 371.268089 -59.657113) (xy 371.317835 -59.634267)
			(xy 371.370337 -59.618771) (xy 371.424515 -59.610942) (xy 371.479257 -59.610942) (xy 371.533435 -59.618771)
			(xy 371.585937 -59.634267) (xy 371.635683 -59.657113) (xy 371.681651 -59.686837) (xy 371.702584 -59.704478)
			(xy 371.702838 -59.704732) (xy 371.709936 -59.710302) (xy 371.726844 -59.716558) (xy 371.735858 -59.716924)
			(xy 371.802914 -59.716924) (xy 371.811931 -59.716568) (xy 371.828847 -59.710319) (xy 371.835934 -59.704732)
			(xy 371.835934 -59.704478) (xy 371.836188 -59.704478) (xy 371.857111 -59.686828) (xy 371.903087 -59.657118)
			(xy 371.952836 -59.634285) (xy 372.005339 -59.618796) (xy 372.059516 -59.610971) (xy 372.086886 -59.610498)
			(xy 372.11414 -59.610948) (xy 372.168093 -59.618704) (xy 372.220394 -59.634059) (xy 372.269976 -59.656701)
			(xy 372.315832 -59.686169) (xy 372.357027 -59.721863) (xy 372.392723 -59.763057) (xy 372.422192 -59.808911)
			(xy 372.444836 -59.858493) (xy 372.460193 -59.910793) (xy 372.467951 -59.964746) (xy 372.467951 -60.019254)
			(xy 372.460193 -60.073207) (xy 372.444836 -60.125507) (xy 372.422192 -60.175089) (xy 372.392723 -60.220943)
			(xy 372.357027 -60.262137) (xy 372.315832 -60.297831) (xy 372.269976 -60.327299) (xy 372.220394 -60.349941)
			(xy 372.168093 -60.365296) (xy 372.11414 -60.373052) (xy 372.086886 -60.373514) (xy 372.059516 -60.373053)
			(xy 372.005336 -60.365233) (xy 371.952833 -60.349743) (xy 371.903087 -60.3269) (xy 371.85712 -60.297175)
			(xy 371.836188 -60.279534) (xy 371.835934 -60.27928) (xy 371.828844 -60.273699) (xy 371.81193 -60.26745)
			(xy 371.802914 -60.267088) (xy 371.735858 -60.267088) (xy 371.726844 -60.267476) (xy 371.709927 -60.273702)
			(xy 371.702838 -60.27928) (xy 371.702584 -60.279534) (xy 371.681651 -60.297175) (xy 371.635683 -60.326899)
			(xy 371.585937 -60.349745) (xy 371.533435 -60.365241) (xy 371.479257 -60.37307) (xy 371.424515 -60.37307)
			(xy 371.370337 -60.365241) (xy 371.317835 -60.349745) (xy 371.268089 -60.326899) (xy 371.222121 -60.297175)
			(xy 371.201188 -60.279534) (xy 371.200934 -60.27928) (xy 371.193844 -60.273699) (xy 371.17693 -60.26745)
			(xy 371.167914 -60.267088) (xy 371.100858 -60.267088) (xy 371.091844 -60.267476) (xy 371.074927 -60.273702)
			(xy 371.067838 -60.27928) (xy 371.067838 -60.279534) (xy 371.067584 -60.279534) (xy 371.046635 -60.297152)
			(xy 371.000667 -60.326866) (xy 370.950923 -60.349706) (xy 370.898426 -60.365202) (xy 370.844254 -60.373036)
			(xy 370.816886 -60.373514) (xy 370.789636 -60.373015) (xy 370.73569 -60.365257) (xy 370.683398 -60.349901)
			(xy 370.633824 -60.32726) (xy 370.587976 -60.297793) (xy 370.546788 -60.262102) (xy 370.511098 -60.220913)
			(xy 370.481634 -60.175064) (xy 370.458994 -60.125489) (xy 370.44364 -60.073196) (xy 370.435884 -60.01925)
			(xy 361.527344 -60.01925) (xy 361.527344 -60.633356) (xy 382.097024 -60.633356) (xy 382.101095 -60.577734)
			(xy 382.113221 -60.523297) (xy 382.133144 -60.471206) (xy 382.16044 -60.422571) (xy 382.194526 -60.378428)
			(xy 382.234675 -60.339719) (xy 382.280033 -60.307268) (xy 382.329633 -60.281767) (xy 382.382417 -60.26376)
			(xy 382.43726 -60.25363) (xy 382.492994 -60.251593) (xy 382.548431 -60.257693) (xy 382.602388 -60.271799)
			(xy 382.653717 -60.293611) (xy 382.701323 -60.322665) (xy 382.744191 -60.35834) (xy 382.781408 -60.399877)
			(xy 382.812181 -60.44639) (xy 382.835853 -60.496887) (xy 382.851921 -60.550294) (xy 382.860041 -60.60547)
			(xy 382.86055 -60.633356) (xy 382.860041 -60.661242) (xy 382.851921 -60.716418) (xy 382.835853 -60.769825)
			(xy 382.812181 -60.820322) (xy 382.781408 -60.866835) (xy 382.744191 -60.908372) (xy 382.701323 -60.944047)
			(xy 382.653717 -60.973101) (xy 382.602388 -60.994913) (xy 382.548431 -61.009019) (xy 382.492994 -61.015119)
			(xy 382.43726 -61.013082) (xy 382.382417 -61.002952) (xy 382.329633 -60.984945) (xy 382.280033 -60.959444)
			(xy 382.234675 -60.926993) (xy 382.194526 -60.888284) (xy 382.16044 -60.844141) (xy 382.133144 -60.795506)
			(xy 382.113221 -60.743415) (xy 382.101095 -60.688978) (xy 382.097024 -60.633356) (xy 361.527344 -60.633356)
			(xy 361.527344 -61.487812) (xy 380.60452 -61.487812) (xy 380.608591 -61.43219) (xy 380.620717 -61.377753)
			(xy 380.64064 -61.325662) (xy 380.667936 -61.277027) (xy 380.702022 -61.232884) (xy 380.742171 -61.194175)
			(xy 380.787529 -61.161724) (xy 380.837129 -61.136223) (xy 380.889913 -61.118216) (xy 380.944756 -61.108086)
			(xy 381.00049 -61.106049) (xy 381.055927 -61.112149) (xy 381.109884 -61.126255) (xy 381.161213 -61.148067)
			(xy 381.208819 -61.177121) (xy 381.251687 -61.212796) (xy 381.288904 -61.254333) (xy 381.319677 -61.300846)
			(xy 381.343349 -61.351343) (xy 381.359417 -61.40475) (xy 381.367537 -61.459926) (xy 381.368046 -61.487812)
			(xy 381.367537 -61.515698) (xy 381.359417 -61.570874) (xy 381.343349 -61.624281) (xy 381.319677 -61.674778)
			(xy 381.288904 -61.721291) (xy 381.251687 -61.762828) (xy 381.208819 -61.798503) (xy 381.161213 -61.827557)
			(xy 381.109884 -61.849369) (xy 381.055927 -61.863475) (xy 381.00049 -61.869575) (xy 380.944756 -61.867538)
			(xy 380.889913 -61.857408) (xy 380.837129 -61.839401) (xy 380.787529 -61.8139) (xy 380.742171 -61.781449)
			(xy 380.702022 -61.74274) (xy 380.667936 -61.698597) (xy 380.64064 -61.649962) (xy 380.620717 -61.597871)
			(xy 380.608591 -61.543434) (xy 380.60452 -61.487812) (xy 361.527344 -61.487812) (xy 361.527344 -62.121034)
			(xy 378.542294 -62.121034) (xy 378.546365 -62.065412) (xy 378.558491 -62.010975) (xy 378.578414 -61.958884)
			(xy 378.60571 -61.910249) (xy 378.639796 -61.866106) (xy 378.679945 -61.827397) (xy 378.725303 -61.794946)
			(xy 378.774903 -61.769445) (xy 378.827687 -61.751438) (xy 378.88253 -61.741308) (xy 378.938264 -61.739271)
			(xy 378.993701 -61.745371) (xy 379.047658 -61.759477) (xy 379.098987 -61.781289) (xy 379.146593 -61.810343)
			(xy 379.189461 -61.846018) (xy 379.226678 -61.887555) (xy 379.257451 -61.934068) (xy 379.281123 -61.984565)
			(xy 379.297191 -62.037972) (xy 379.305311 -62.093148) (xy 379.30582 -62.121034) (xy 379.305311 -62.14892)
			(xy 379.297191 -62.204096) (xy 379.281123 -62.257503) (xy 379.257451 -62.308) (xy 379.226678 -62.354513)
			(xy 379.189461 -62.39605) (xy 379.146593 -62.431725) (xy 379.098987 -62.460779) (xy 379.047658 -62.482591)
			(xy 378.993701 -62.496697) (xy 378.938264 -62.502797) (xy 378.88253 -62.50076) (xy 378.827687 -62.49063)
			(xy 378.774903 -62.472623) (xy 378.725303 -62.447122) (xy 378.679945 -62.414671) (xy 378.639796 -62.375962)
			(xy 378.60571 -62.331819) (xy 378.578414 -62.283184) (xy 378.558491 -62.231093) (xy 378.546365 -62.176656)
			(xy 378.542294 -62.121034) (xy 361.527344 -62.121034) (xy 361.527344 -63.21355) (xy 370.420888 -63.21355)
			(xy 370.420888 -63.15905) (xy 370.428645 -63.105103) (xy 370.443999 -63.05281) (xy 370.46664 -63.003234)
			(xy 370.496105 -62.957385) (xy 370.531796 -62.916196) (xy 370.572985 -62.880505) (xy 370.618834 -62.85104)
			(xy 370.66841 -62.828399) (xy 370.720703 -62.813045) (xy 370.77465 -62.805288) (xy 370.8019 -62.804802)
			(xy 370.82927 -62.805268) (xy 370.883449 -62.813085) (xy 370.935953 -62.828575) (xy 370.985699 -62.851416)
			(xy 371.031666 -62.881141) (xy 371.052598 -62.898782) (xy 371.052852 -62.899036) (xy 371.059945 -62.904613)
			(xy 371.076857 -62.910864) (xy 371.085872 -62.911228) (xy 371.152928 -62.911228) (xy 371.161946 -62.910878)
			(xy 371.178862 -62.904625) (xy 371.185948 -62.899036) (xy 371.185948 -62.898782) (xy 371.186202 -62.898782)
			(xy 371.207135 -62.881141) (xy 371.253103 -62.851417) (xy 371.302849 -62.828571) (xy 371.355351 -62.813075)
			(xy 371.409529 -62.805246) (xy 371.464271 -62.805246) (xy 371.518449 -62.813075) (xy 371.570951 -62.828571)
			(xy 371.620697 -62.851417) (xy 371.666665 -62.881141) (xy 371.687598 -62.898782) (xy 371.687852 -62.899036)
			(xy 371.694945 -62.904613) (xy 371.711857 -62.910864) (xy 371.720872 -62.911228) (xy 371.787928 -62.911228)
			(xy 371.796946 -62.910878) (xy 371.813862 -62.904625) (xy 371.820948 -62.899036) (xy 371.820948 -62.898782)
			(xy 371.821202 -62.898782) (xy 371.84212 -62.881126) (xy 371.888097 -62.851417) (xy 371.937848 -62.828585)
			(xy 371.990352 -62.813098) (xy 372.04453 -62.805274) (xy 372.0719 -62.804802) (xy 372.099152 -62.805268)
			(xy 372.153101 -62.813025) (xy 372.205397 -62.82838) (xy 372.254976 -62.851022) (xy 372.300827 -62.880489)
			(xy 372.342019 -62.916181) (xy 372.377711 -62.957373) (xy 372.407178 -63.003224) (xy 372.42982 -63.052803)
			(xy 372.439636 -63.086234) (xy 375.687588 -63.086234) (xy 375.691659 -63.030612) (xy 375.703785 -62.976175)
			(xy 375.723708 -62.924084) (xy 375.751004 -62.875449) (xy 375.78509 -62.831306) (xy 375.825239 -62.792597)
			(xy 375.870597 -62.760146) (xy 375.920197 -62.734645) (xy 375.972981 -62.716638) (xy 376.027824 -62.706508)
			(xy 376.083558 -62.704471) (xy 376.138995 -62.710571) (xy 376.192952 -62.724677) (xy 376.213112 -62.733244)
			(xy 381.966151 -62.733244) (xy 381.966152 -62.678737) (xy 381.973911 -62.624785) (xy 381.989268 -62.572487)
			(xy 382.011913 -62.522906) (xy 382.041383 -62.477053) (xy 382.077079 -62.435861) (xy 382.118273 -62.400168)
			(xy 382.164129 -62.370701) (xy 382.213711 -62.34806) (xy 382.26601 -62.332705) (xy 382.319963 -62.32495)
			(xy 382.347216 -62.324488) (xy 382.370771 -62.324865) (xy 382.417515 -62.330724) (xy 382.440434 -62.336172)
			(xy 382.454192 -62.339197) (xy 382.482341 -62.338344) (xy 382.509188 -62.32984) (xy 382.532695 -62.314331)
			(xy 382.551076 -62.292995) (xy 382.562935 -62.267451) (xy 382.567372 -62.239641) (xy 382.564049 -62.211676)
			(xy 382.559052 -62.198504) (xy 382.549741 -62.175115) (xy 382.536616 -62.126514) (xy 382.529993 -62.076609)
			(xy 382.529588 -62.051438) (xy 382.530014 -62.024182) (xy 382.537767 -61.970223) (xy 382.55312 -61.917918)
			(xy 382.575761 -61.868329) (xy 382.605229 -61.822468) (xy 382.640923 -61.781267) (xy 382.682118 -61.745566)
			(xy 382.727975 -61.716091) (xy 382.777559 -61.693442) (xy 382.829863 -61.67808) (xy 382.88382 -61.670319)
			(xy 382.938332 -61.670315) (xy 382.99229 -61.67807) (xy 383.044596 -61.693425) (xy 383.094183 -61.716068)
			(xy 383.140043 -61.745537) (xy 383.181243 -61.781233) (xy 383.216943 -61.822429) (xy 383.246416 -61.868287)
			(xy 383.269063 -61.917873) (xy 383.284423 -61.970176) (xy 383.292182 -62.024134) (xy 383.292184 -62.078646)
			(xy 383.284427 -62.132604) (xy 383.26907 -62.184909) (xy 383.246426 -62.234495) (xy 383.216955 -62.280355)
			(xy 383.181257 -62.321553) (xy 383.140059 -62.357251) (xy 383.094201 -62.386723) (xy 383.044614 -62.409368)
			(xy 382.99231 -62.424726) (xy 382.938352 -62.432483) (xy 382.911096 -62.432946) (xy 382.887541 -62.432566)
			(xy 382.840797 -62.426709) (xy 382.817878 -62.421262) (xy 382.804124 -62.418202) (xy 382.775968 -62.419052)
			(xy 382.749113 -62.427557) (xy 382.7256 -62.44307) (xy 382.707216 -62.464414) (xy 382.695357 -62.489966)
			(xy 382.690925 -62.517784) (xy 382.694257 -62.545756) (xy 382.69926 -62.55893) (xy 382.708582 -62.582315)
			(xy 382.721703 -62.630918) (xy 382.728321 -62.680825) (xy 382.728724 -62.705996) (xy 382.728249 -62.733249)
			(xy 382.720492 -62.787202) (xy 382.705136 -62.839501) (xy 382.682494 -62.889082) (xy 382.653025 -62.934936)
			(xy 382.617331 -62.97613) (xy 382.576137 -63.011824) (xy 382.530283 -63.041293) (xy 382.480702 -63.063936)
			(xy 382.428403 -63.079292) (xy 382.374451 -63.087049) (xy 382.319944 -63.087048) (xy 382.265992 -63.079291)
			(xy 382.213693 -63.063934) (xy 382.164112 -63.04129) (xy 382.118258 -63.011821) (xy 382.077065 -62.976126)
			(xy 382.041372 -62.934932) (xy 382.011904 -62.889077) (xy 381.989262 -62.839496) (xy 381.973907 -62.787196)
			(xy 381.966151 -62.733244) (xy 376.213112 -62.733244) (xy 376.244281 -62.746489) (xy 376.291887 -62.775543)
			(xy 376.334755 -62.811218) (xy 376.371972 -62.852755) (xy 376.402745 -62.899268) (xy 376.426417 -62.949765)
			(xy 376.442485 -63.003172) (xy 376.450605 -63.058348) (xy 376.451114 -63.086234) (xy 376.450605 -63.11412)
			(xy 376.442485 -63.169296) (xy 376.426417 -63.222703) (xy 376.402745 -63.2732) (xy 376.402592 -63.273432)
			(xy 377.876814 -63.273432) (xy 377.880885 -63.21781) (xy 377.893011 -63.163373) (xy 377.912934 -63.111282)
			(xy 377.94023 -63.062647) (xy 377.974316 -63.018504) (xy 378.014465 -62.979795) (xy 378.059823 -62.947344)
			(xy 378.109423 -62.921843) (xy 378.162207 -62.903836) (xy 378.21705 -62.893706) (xy 378.272784 -62.891669)
			(xy 378.328221 -62.897769) (xy 378.382178 -62.911875) (xy 378.433507 -62.933687) (xy 378.481113 -62.962741)
			(xy 378.523981 -62.998416) (xy 378.561198 -63.039953) (xy 378.591971 -63.086466) (xy 378.615643 -63.136963)
			(xy 378.631711 -63.19037) (xy 378.639831 -63.245546) (xy 378.64034 -63.273432) (xy 378.639831 -63.301318)
			(xy 378.631711 -63.356494) (xy 378.615643 -63.409901) (xy 378.591971 -63.460398) (xy 378.561198 -63.506911)
			(xy 378.523981 -63.548448) (xy 378.481113 -63.584123) (xy 378.433507 -63.613177) (xy 378.382178 -63.634989)
			(xy 378.328221 -63.649095) (xy 378.272784 -63.655195) (xy 378.21705 -63.653158) (xy 378.162207 -63.643028)
			(xy 378.109423 -63.625021) (xy 378.059823 -63.59952) (xy 378.014465 -63.567069) (xy 377.974316 -63.52836)
			(xy 377.94023 -63.484217) (xy 377.912934 -63.435582) (xy 377.893011 -63.383491) (xy 377.880885 -63.329054)
			(xy 377.876814 -63.273432) (xy 376.402592 -63.273432) (xy 376.371972 -63.319713) (xy 376.334755 -63.36125)
			(xy 376.291887 -63.396925) (xy 376.244281 -63.425979) (xy 376.192952 -63.447791) (xy 376.138995 -63.461897)
			(xy 376.083558 -63.467997) (xy 376.027824 -63.46596) (xy 375.972981 -63.45583) (xy 375.920197 -63.437823)
			(xy 375.870597 -63.412322) (xy 375.825239 -63.379871) (xy 375.78509 -63.341162) (xy 375.751004 -63.297019)
			(xy 375.723708 -63.248384) (xy 375.703785 -63.196293) (xy 375.691659 -63.141856) (xy 375.687588 -63.086234)
			(xy 372.439636 -63.086234) (xy 372.445175 -63.105099) (xy 372.452932 -63.159048) (xy 372.452932 -63.213552)
			(xy 372.445175 -63.267501) (xy 372.42982 -63.319797) (xy 372.407178 -63.369376) (xy 372.377711 -63.415227)
			(xy 372.342019 -63.456419) (xy 372.300827 -63.492111) (xy 372.254976 -63.521578) (xy 372.205397 -63.54422)
			(xy 372.153101 -63.559575) (xy 372.099152 -63.567332) (xy 372.0719 -63.567818) (xy 372.044529 -63.567372)
			(xy 371.990348 -63.559552) (xy 371.937844 -63.54406) (xy 371.888097 -63.521213) (xy 371.842132 -63.491482)
			(xy 371.821202 -63.473838) (xy 371.820948 -63.473584) (xy 371.813853 -63.46801) (xy 371.796943 -63.461756)
			(xy 371.787928 -63.461392) (xy 371.720872 -63.461392) (xy 371.711854 -63.461738) (xy 371.694937 -63.467993)
			(xy 371.687852 -63.473584) (xy 371.687598 -63.473838) (xy 371.666665 -63.491479) (xy 371.620697 -63.521203)
			(xy 371.570951 -63.544049) (xy 371.518449 -63.559545) (xy 371.464271 -63.567374) (xy 371.409529 -63.567374)
			(xy 371.355351 -63.559545) (xy 371.302849 -63.544049) (xy 371.253103 -63.521203) (xy 371.207135 -63.491479)
			(xy 371.186202 -63.473838) (xy 371.185948 -63.473584) (xy 371.178853 -63.46801) (xy 371.161943 -63.461756)
			(xy 371.152928 -63.461392) (xy 371.085872 -63.461392) (xy 371.076854 -63.461738) (xy 371.059937 -63.467993)
			(xy 371.052852 -63.473584) (xy 371.052852 -63.473838) (xy 371.052598 -63.473838) (xy 371.031683 -63.491498)
			(xy 370.985705 -63.521205) (xy 370.935953 -63.544037) (xy 370.883449 -63.559523) (xy 370.82927 -63.567347)
			(xy 370.8019 -63.567818) (xy 370.77465 -63.567312) (xy 370.720703 -63.559555) (xy 370.66841 -63.544201)
			(xy 370.618834 -63.52156) (xy 370.572985 -63.492095) (xy 370.531796 -63.456404) (xy 370.496105 -63.415215)
			(xy 370.46664 -63.369366) (xy 370.443999 -63.31979) (xy 370.428645 -63.267497) (xy 370.420888 -63.21355)
			(xy 361.527344 -63.21355) (xy 361.527344 -65.100962) (xy 368.432586 -65.100962) (xy 368.436657 -65.04534)
			(xy 368.448783 -64.990903) (xy 368.468706 -64.938812) (xy 368.496002 -64.890177) (xy 368.530088 -64.846034)
			(xy 368.570237 -64.807325) (xy 368.615595 -64.774874) (xy 368.665195 -64.749373) (xy 368.717979 -64.731366)
			(xy 368.772822 -64.721236) (xy 368.828556 -64.719199) (xy 368.883993 -64.725299) (xy 368.93795 -64.739405)
			(xy 368.989279 -64.761217) (xy 369.036885 -64.790271) (xy 369.079753 -64.825946) (xy 369.11697 -64.867483)
			(xy 369.147743 -64.913996) (xy 369.171415 -64.964493) (xy 369.187483 -65.0179) (xy 369.195603 -65.073076)
			(xy 369.196112 -65.100962) (xy 369.19569 -65.124076) (xy 380.407416 -65.124076) (xy 380.411487 -65.068454)
			(xy 380.423613 -65.014017) (xy 380.443536 -64.961926) (xy 380.470832 -64.913291) (xy 380.504918 -64.869148)
			(xy 380.545067 -64.830439) (xy 380.590425 -64.797988) (xy 380.640025 -64.772487) (xy 380.692809 -64.75448)
			(xy 380.747652 -64.74435) (xy 380.803386 -64.742313) (xy 380.858823 -64.748413) (xy 380.91278 -64.762519)
			(xy 380.964109 -64.784331) (xy 381.011715 -64.813385) (xy 381.054583 -64.84906) (xy 381.0918 -64.890597)
			(xy 381.122573 -64.93711) (xy 381.146245 -64.987607) (xy 381.162313 -65.041014) (xy 381.170433 -65.09619)
			(xy 381.170942 -65.124076) (xy 381.170433 -65.151962) (xy 381.162313 -65.207138) (xy 381.146245 -65.260545)
			(xy 381.122573 -65.311042) (xy 381.0918 -65.357555) (xy 381.054583 -65.399092) (xy 381.011715 -65.434767)
			(xy 380.964109 -65.463821) (xy 380.91278 -65.485633) (xy 380.858823 -65.499739) (xy 380.803386 -65.505839)
			(xy 380.747652 -65.503802) (xy 380.692809 -65.493672) (xy 380.640025 -65.475665) (xy 380.590425 -65.450164)
			(xy 380.545067 -65.417713) (xy 380.504918 -65.379004) (xy 380.470832 -65.334861) (xy 380.443536 -65.286226)
			(xy 380.423613 -65.234135) (xy 380.411487 -65.179698) (xy 380.407416 -65.124076) (xy 369.19569 -65.124076)
			(xy 369.195603 -65.128848) (xy 369.187483 -65.184024) (xy 369.171415 -65.237431) (xy 369.147743 -65.287928)
			(xy 369.11697 -65.334441) (xy 369.079753 -65.375978) (xy 369.036885 -65.411653) (xy 368.989279 -65.440707)
			(xy 368.93795 -65.462519) (xy 368.883993 -65.476625) (xy 368.828556 -65.482725) (xy 368.772822 -65.480688)
			(xy 368.717979 -65.470558) (xy 368.665195 -65.452551) (xy 368.615595 -65.42705) (xy 368.570237 -65.394599)
			(xy 368.530088 -65.35589) (xy 368.496002 -65.311747) (xy 368.468706 -65.263112) (xy 368.448783 -65.211021)
			(xy 368.436657 -65.156584) (xy 368.432586 -65.100962) (xy 361.527344 -65.100962) (xy 361.527344 -65.75552)
			(xy 362.64672 -65.75552) (xy 362.650791 -65.699898) (xy 362.662917 -65.645461) (xy 362.68284 -65.59337)
			(xy 362.710136 -65.544735) (xy 362.744222 -65.500592) (xy 362.784371 -65.461883) (xy 362.829729 -65.429432)
			(xy 362.879329 -65.403931) (xy 362.932113 -65.385924) (xy 362.986956 -65.375794) (xy 363.04269 -65.373757)
			(xy 363.098127 -65.379857) (xy 363.152084 -65.393963) (xy 363.203413 -65.415775) (xy 363.251019 -65.444829)
			(xy 363.293887 -65.480504) (xy 363.331104 -65.522041) (xy 363.361877 -65.568554) (xy 363.385549 -65.619051)
			(xy 363.401617 -65.672458) (xy 363.409737 -65.727634) (xy 363.410246 -65.75552) (xy 363.409737 -65.783406)
			(xy 363.401617 -65.838582) (xy 363.385549 -65.891989) (xy 363.361877 -65.942486) (xy 363.331104 -65.988999)
			(xy 363.293887 -66.030536) (xy 363.251019 -66.066211) (xy 363.203413 -66.095265) (xy 363.152084 -66.117077)
			(xy 363.098127 -66.131183) (xy 363.04269 -66.137283) (xy 362.986956 -66.135246) (xy 362.932113 -66.125116)
			(xy 362.879329 -66.107109) (xy 362.829729 -66.081608) (xy 362.784371 -66.049157) (xy 362.744222 -66.010448)
			(xy 362.710136 -65.966305) (xy 362.68284 -65.91767) (xy 362.662917 -65.865579) (xy 362.650791 -65.811142)
			(xy 362.64672 -65.75552) (xy 361.527344 -65.75552) (xy 361.527344 -67.128949) (xy 362.666798 -67.128949)
			(xy 362.666798 -67.074451) (xy 362.674554 -67.020507) (xy 362.689908 -66.968216) (xy 362.712547 -66.918642)
			(xy 362.74201 -66.872795) (xy 362.777699 -66.831607) (xy 362.818885 -66.795918) (xy 362.864732 -66.766452)
			(xy 362.914305 -66.743812) (xy 362.966595 -66.728457) (xy 363.020539 -66.720699) (xy 363.047788 -66.720212)
			(xy 363.075158 -66.720682) (xy 363.129337 -66.728499) (xy 363.18184 -66.743987) (xy 363.231587 -66.766827)
			(xy 363.277554 -66.796551) (xy 363.298486 -66.814192) (xy 363.29874 -66.814446) (xy 363.305836 -66.820019)
			(xy 363.322746 -66.826273) (xy 363.33176 -66.826638) (xy 363.398816 -66.826638) (xy 363.407833 -66.826281)
			(xy 363.424749 -66.820032) (xy 363.431836 -66.814446) (xy 363.431836 -66.814192) (xy 363.43209 -66.814192)
			(xy 363.453014 -66.796543) (xy 363.498989 -66.766833) (xy 363.548739 -66.743999) (xy 363.601241 -66.72851)
			(xy 363.655418 -66.720685) (xy 363.682788 -66.720212) (xy 363.710043 -66.720634) (xy 363.763998 -66.72839)
			(xy 363.8163 -66.743746) (xy 363.865884 -66.766389) (xy 363.911741 -66.795858) (xy 363.952938 -66.831554)
			(xy 363.988635 -66.872749) (xy 364.018105 -66.918605) (xy 364.04075 -66.968189) (xy 364.056107 -67.02049)
			(xy 364.063865 -67.074445) (xy 364.063865 -67.128955) (xy 364.056107 -67.18291) (xy 364.04075 -67.235211)
			(xy 364.018105 -67.284795) (xy 363.988635 -67.330651) (xy 363.952938 -67.371846) (xy 363.911741 -67.407542)
			(xy 363.865884 -67.437011) (xy 363.8163 -67.459654) (xy 363.763998 -67.47501) (xy 363.710043 -67.482766)
			(xy 363.682788 -67.483228) (xy 363.655417 -67.482787) (xy 363.601236 -67.474965) (xy 363.548732 -67.459472)
			(xy 363.498985 -67.436624) (xy 363.45302 -67.406893) (xy 363.43209 -67.389248) (xy 363.431836 -67.388994)
			(xy 363.424744 -67.383416) (xy 363.407831 -67.377164) (xy 363.398816 -67.376802) (xy 363.33176 -67.376802)
			(xy 363.322741 -67.37714) (xy 363.305824 -67.383401) (xy 363.29874 -67.388994) (xy 363.29874 -67.389248)
			(xy 363.298486 -67.389248) (xy 363.277526 -67.406852) (xy 363.231561 -67.436571) (xy 363.181821 -67.459415)
			(xy 363.129326 -67.474914) (xy 363.075155 -67.48275) (xy 363.047788 -67.483228) (xy 363.020539 -67.482701)
			(xy 362.966595 -67.474943) (xy 362.914305 -67.459588) (xy 362.864732 -67.436948) (xy 362.818885 -67.407482)
			(xy 362.777699 -67.371793) (xy 362.74201 -67.330605) (xy 362.712547 -67.284758) (xy 362.689908 -67.235184)
			(xy 362.674554 -67.182893) (xy 362.666798 -67.128949) (xy 361.527344 -67.128949) (xy 361.527344 -67.488054)
			(xy 367.079274 -67.488054) (xy 367.083345 -67.432432) (xy 367.095471 -67.377995) (xy 367.115394 -67.325904)
			(xy 367.14269 -67.277269) (xy 367.176776 -67.233126) (xy 367.216925 -67.194417) (xy 367.262283 -67.161966)
			(xy 367.311883 -67.136465) (xy 367.364667 -67.118458) (xy 367.41951 -67.108328) (xy 367.475244 -67.106291)
			(xy 367.530681 -67.112391) (xy 367.584638 -67.126497) (xy 367.635967 -67.148309) (xy 367.683573 -67.177363)
			(xy 367.726441 -67.213038) (xy 367.763658 -67.254575) (xy 367.794431 -67.301088) (xy 367.818103 -67.351585)
			(xy 367.834171 -67.404992) (xy 367.842291 -67.460168) (xy 367.8428 -67.488054) (xy 367.842291 -67.51594)
			(xy 367.839106 -67.537584) (xy 368.371372 -67.537584) (xy 368.375443 -67.481962) (xy 368.387569 -67.427525)
			(xy 368.407492 -67.375434) (xy 368.434788 -67.326799) (xy 368.468874 -67.282656) (xy 368.509023 -67.243947)
			(xy 368.554381 -67.211496) (xy 368.603981 -67.185995) (xy 368.656765 -67.167988) (xy 368.711608 -67.157858)
			(xy 368.767342 -67.155821) (xy 368.822779 -67.161921) (xy 368.876736 -67.176027) (xy 368.928065 -67.197839)
			(xy 368.975671 -67.226893) (xy 369.018539 -67.262568) (xy 369.055756 -67.304105) (xy 369.086529 -67.350618)
			(xy 369.110201 -67.401115) (xy 369.126269 -67.454522) (xy 369.134389 -67.509698) (xy 369.134898 -67.537584)
			(xy 369.134389 -67.56547) (xy 369.130344 -67.592956) (xy 369.645436 -67.592956) (xy 369.649507 -67.537334)
			(xy 369.661633 -67.482897) (xy 369.681556 -67.430806) (xy 369.708852 -67.382171) (xy 369.742938 -67.338028)
			(xy 369.783087 -67.299319) (xy 369.828445 -67.266868) (xy 369.878045 -67.241367) (xy 369.930829 -67.22336)
			(xy 369.985672 -67.21323) (xy 370.041406 -67.211193) (xy 370.096843 -67.217293) (xy 370.1508 -67.231399)
			(xy 370.202129 -67.253211) (xy 370.249735 -67.282265) (xy 370.292603 -67.31794) (xy 370.32982 -67.359477)
			(xy 370.360593 -67.40599) (xy 370.384265 -67.456487) (xy 370.400333 -67.509894) (xy 370.40845 -67.565048)
			(xy 372.746816 -67.565048) (xy 372.746816 -67.510553) (xy 372.754571 -67.456612) (xy 372.769924 -67.404324)
			(xy 372.792561 -67.354754) (xy 372.822022 -67.308909) (xy 372.857708 -67.267723) (xy 372.898891 -67.232035)
			(xy 372.944734 -67.202572) (xy 372.994304 -67.179931) (xy 373.046591 -67.164576) (xy 373.100531 -67.156818)
			(xy 373.127778 -67.15633) (xy 373.155148 -67.156802) (xy 373.209327 -67.164617) (xy 373.261831 -67.180104)
			(xy 373.311578 -67.202945) (xy 373.357544 -67.232669) (xy 373.378476 -67.25031) (xy 373.37873 -67.250564)
			(xy 373.385827 -67.256135) (xy 373.402736 -67.262389) (xy 373.41175 -67.262756) (xy 373.478806 -67.262756)
			(xy 373.487824 -67.262411) (xy 373.504742 -67.256156) (xy 373.511826 -67.250564) (xy 373.511826 -67.25031)
			(xy 373.51208 -67.25031) (xy 373.53301 -67.232668) (xy 373.578983 -67.202957) (xy 373.628731 -67.180121)
			(xy 373.681232 -67.164631) (xy 373.735409 -67.156803) (xy 373.762778 -67.15633) (xy 373.790035 -67.156715)
			(xy 373.843993 -67.164471) (xy 373.896299 -67.179826) (xy 373.945887 -67.20247) (xy 373.991748 -67.23194)
			(xy 374.032947 -67.267637) (xy 374.068647 -67.308835) (xy 374.09812 -67.354694) (xy 374.120766 -67.40428)
			(xy 374.136125 -67.456585) (xy 374.143883 -67.510543) (xy 374.143883 -67.565057) (xy 374.136125 -67.619015)
			(xy 374.120766 -67.67132) (xy 374.09812 -67.720906) (xy 374.068647 -67.766765) (xy 374.032947 -67.807963)
			(xy 373.991748 -67.84366) (xy 373.945887 -67.87313) (xy 373.896299 -67.895774) (xy 373.843993 -67.911129)
			(xy 373.790035 -67.918885) (xy 373.762778 -67.919346) (xy 373.735407 -67.918906) (xy 373.681226 -67.911084)
			(xy 373.628722 -67.895589) (xy 373.578976 -67.872742) (xy 373.53301 -67.843011) (xy 373.51208 -67.825366)
			(xy 373.511826 -67.825112) (xy 373.504735 -67.819532) (xy 373.487822 -67.813281) (xy 373.478806 -67.81292)
			(xy 373.41175 -67.81292) (xy 373.402735 -67.813297) (xy 373.385818 -67.81953) (xy 373.37873 -67.825112)
			(xy 373.37873 -67.825366) (xy 373.378476 -67.825366) (xy 373.357522 -67.842978) (xy 373.311556 -67.872695)
			(xy 373.261814 -67.895537) (xy 373.209318 -67.911034) (xy 373.155146 -67.918869) (xy 373.127778 -67.919346)
			(xy 373.100531 -67.918782) (xy 373.046591 -67.911024) (xy 372.994304 -67.895669) (xy 372.944734 -67.873028)
			(xy 372.898891 -67.843565) (xy 372.857708 -67.807877) (xy 372.822022 -67.766691) (xy 372.792561 -67.720846)
			(xy 372.769924 -67.671276) (xy 372.754571 -67.618988) (xy 372.746816 -67.565048) (xy 370.40845 -67.565048)
			(xy 370.408453 -67.56507) (xy 370.408962 -67.592956) (xy 370.408453 -67.620842) (xy 370.400333 -67.676018)
			(xy 370.384265 -67.729425) (xy 370.360593 -67.779922) (xy 370.32982 -67.826435) (xy 370.292603 -67.867972)
			(xy 370.249735 -67.903647) (xy 370.202129 -67.932701) (xy 370.1508 -67.954513) (xy 370.096843 -67.968619)
			(xy 370.041406 -67.974719) (xy 369.985672 -67.972682) (xy 369.930829 -67.962552) (xy 369.878045 -67.944545)
			(xy 369.828445 -67.919044) (xy 369.783087 -67.886593) (xy 369.742938 -67.847884) (xy 369.708852 -67.803741)
			(xy 369.681556 -67.755106) (xy 369.661633 -67.703015) (xy 369.649507 -67.648578) (xy 369.645436 -67.592956)
			(xy 369.130344 -67.592956) (xy 369.126269 -67.620646) (xy 369.110201 -67.674053) (xy 369.086529 -67.72455)
			(xy 369.055756 -67.771063) (xy 369.018539 -67.8126) (xy 368.975671 -67.848275) (xy 368.928065 -67.877329)
			(xy 368.876736 -67.899141) (xy 368.822779 -67.913247) (xy 368.767342 -67.919347) (xy 368.711608 -67.91731)
			(xy 368.656765 -67.90718) (xy 368.603981 -67.889173) (xy 368.554381 -67.863672) (xy 368.509023 -67.831221)
			(xy 368.468874 -67.792512) (xy 368.434788 -67.748369) (xy 368.407492 -67.699734) (xy 368.387569 -67.647643)
			(xy 368.375443 -67.593206) (xy 368.371372 -67.537584) (xy 367.839106 -67.537584) (xy 367.834171 -67.571116)
			(xy 367.818103 -67.624523) (xy 367.794431 -67.67502) (xy 367.763658 -67.721533) (xy 367.726441 -67.76307)
			(xy 367.683573 -67.798745) (xy 367.635967 -67.827799) (xy 367.584638 -67.849611) (xy 367.530681 -67.863717)
			(xy 367.475244 -67.869817) (xy 367.41951 -67.86778) (xy 367.364667 -67.85765) (xy 367.311883 -67.839643)
			(xy 367.262283 -67.814142) (xy 367.216925 -67.781691) (xy 367.176776 -67.742982) (xy 367.14269 -67.698839)
			(xy 367.115394 -67.650204) (xy 367.095471 -67.598113) (xy 367.083345 -67.543676) (xy 367.079274 -67.488054)
			(xy 361.527344 -67.488054) (xy 361.527344 -68.586604) (xy 364.925356 -68.586604) (xy 364.925811 -68.559233)
			(xy 364.933629 -68.505053) (xy 364.94912 -68.452549) (xy 364.971965 -68.402803) (xy 365.001693 -68.356837)
			(xy 365.019336 -68.335906) (xy 365.01959 -68.335652) (xy 365.02516 -68.328554) (xy 365.031417 -68.311646)
			(xy 365.031782 -68.302632) (xy 365.031782 -68.235576) (xy 365.03144 -68.226557) (xy 365.025183 -68.20964)
			(xy 365.01959 -68.202556) (xy 365.019336 -68.202556) (xy 365.019336 -68.202302) (xy 365.00169 -68.181375)
			(xy 364.971978 -68.135402) (xy 364.949143 -68.085653) (xy 364.933653 -68.033151) (xy 364.925828 -67.978974)
			(xy 364.925356 -67.951604) (xy 364.925881 -67.924354) (xy 364.933636 -67.87041) (xy 364.948989 -67.818118)
			(xy 364.971627 -67.768543) (xy 365.00109 -67.722695) (xy 365.036777 -67.681505) (xy 365.077963 -67.645814)
			(xy 365.123808 -67.616346) (xy 365.173381 -67.593703) (xy 365.225671 -67.578345) (xy 365.279615 -67.570584)
			(xy 365.306864 -67.570096) (xy 365.333179 -67.570522) (xy 365.38531 -67.577766) (xy 365.435953 -67.592093)
			(xy 365.484152 -67.613233) (xy 365.528994 -67.640786) (xy 365.569632 -67.674231) (xy 365.587788 -67.693286)
			(xy 365.595314 -67.700682) (xy 365.614591 -67.70921) (xy 365.625126 -67.709796) (xy 365.699802 -67.709796)
			(xy 365.710354 -67.709282) (xy 365.729649 -67.700736) (xy 365.73714 -67.693286) (xy 365.75528 -67.674215)
			(xy 365.795914 -67.64076) (xy 365.840757 -67.613203) (xy 365.888961 -67.592068) (xy 365.939611 -67.577754)
			(xy 365.991747 -67.570533) (xy 366.018064 -67.570096) (xy 366.045433 -67.570584) (xy 366.099612 -67.578397)
			(xy 366.152114 -67.593881) (xy 366.201862 -67.616718) (xy 366.247829 -67.646437) (xy 366.268762 -67.664076)
			(xy 366.269016 -67.66433) (xy 366.276091 -67.669933) (xy 366.293017 -67.676169) (xy 366.302036 -67.676522)
			(xy 366.369092 -67.676522) (xy 366.378108 -67.676156) (xy 366.395025 -67.669914) (xy 366.402112 -67.66433)
			(xy 366.402112 -67.664076) (xy 366.402366 -67.664076) (xy 366.423297 -67.646436) (xy 366.46927 -67.616725)
			(xy 366.519018 -67.59389) (xy 366.571519 -67.578399) (xy 366.625695 -67.57057) (xy 366.653064 -67.570096)
			(xy 366.680316 -67.570589) (xy 366.734266 -67.578341) (xy 366.786564 -67.593693) (xy 366.836144 -67.616331)
			(xy 366.881998 -67.645796) (xy 366.923191 -67.681487) (xy 366.958885 -67.722677) (xy 366.988353 -67.768528)
			(xy 367.010996 -67.818106) (xy 367.026352 -67.870402) (xy 367.034109 -67.924352) (xy 367.034572 -67.951604)
			(xy 367.034115 -67.978975) (xy 367.026296 -68.033154) (xy 367.010805 -68.085658) (xy 366.987961 -68.135405)
			(xy 366.958234 -68.181371) (xy 366.940592 -68.202302) (xy 366.940338 -68.202556) (xy 366.934756 -68.209646)
			(xy 366.928508 -68.22656) (xy 366.928146 -68.235576) (xy 366.928146 -68.302632) (xy 366.928478 -68.311652)
			(xy 366.934742 -68.328569) (xy 366.940338 -68.335652) (xy 366.940592 -68.335652) (xy 366.940592 -68.335906)
			(xy 366.958246 -68.356826) (xy 366.987956 -68.402802) (xy 367.010789 -68.452553) (xy 367.026277 -68.505056)
			(xy 367.0341 -68.559234) (xy 367.034572 -68.586604) (xy 367.034148 -68.613859) (xy 367.02639 -68.667813)
			(xy 367.011031 -68.720114) (xy 366.994399 -68.75653) (xy 370.47043 -68.75653) (xy 370.470906 -68.72916)
			(xy 370.478721 -68.674981) (xy 370.494207 -68.622478) (xy 370.517046 -68.572731) (xy 370.546769 -68.526764)
			(xy 370.56441 -68.505832) (xy 370.564664 -68.505578) (xy 370.570273 -68.498507) (xy 370.576505 -68.481578)
			(xy 370.576856 -68.472558) (xy 370.576856 -68.405502) (xy 370.576507 -68.396484) (xy 370.570255 -68.379567)
			(xy 370.564664 -68.372482) (xy 370.56441 -68.372482) (xy 370.56441 -68.372228) (xy 370.546772 -68.351295)
			(xy 370.51706 -68.305323) (xy 370.494223 -68.255575) (xy 370.478732 -68.203075) (xy 370.470904 -68.148899)
			(xy 370.47043 -68.12153) (xy 370.470883 -68.094276) (xy 370.478637 -68.040323) (xy 370.493991 -67.988023)
			(xy 370.516633 -67.93844) (xy 370.546102 -67.892585) (xy 370.581797 -67.851391) (xy 370.622991 -67.815697)
			(xy 370.668847 -67.786229) (xy 370.71843 -67.763589) (xy 370.770731 -67.748236) (xy 370.824684 -67.740483)
			(xy 370.851938 -67.740022) (xy 370.879307 -67.740519) (xy 370.933485 -67.748329) (xy 370.985988 -67.76381)
			(xy 371.035736 -67.786645) (xy 371.081704 -67.816364) (xy 371.102636 -67.834002) (xy 371.10289 -67.834256)
			(xy 371.10997 -67.839851) (xy 371.126892 -67.846091) (xy 371.13591 -67.846448) (xy 371.202966 -67.846448)
			(xy 371.211983 -67.846086) (xy 371.2289 -67.839843) (xy 371.235986 -67.834256) (xy 371.235986 -67.834002)
			(xy 371.23624 -67.834002) (xy 371.257184 -67.816378) (xy 371.303154 -67.786664) (xy 371.352898 -67.763825)
			(xy 371.405396 -67.74833) (xy 371.45957 -67.740498) (xy 371.486938 -67.740022) (xy 371.513253 -67.740457)
			(xy 371.565383 -67.747698) (xy 371.616027 -67.762023) (xy 371.664226 -67.783161) (xy 371.709069 -67.810713)
			(xy 371.749707 -67.844158) (xy 371.767862 -67.863212) (xy 371.775394 -67.870601) (xy 371.794666 -67.879132)
			(xy 371.8052 -67.879722) (xy 371.879876 -67.879722) (xy 371.890425 -67.879187) (xy 371.90972 -67.870655)
			(xy 371.917214 -67.863212) (xy 371.935372 -67.844159) (xy 371.976001 -67.810701) (xy 372.020841 -67.783141)
			(xy 372.069041 -67.762002) (xy 372.119688 -67.747685) (xy 372.171822 -67.74046) (xy 372.198138 -67.740022)
			(xy 372.225392 -67.740443) (xy 372.279343 -67.748205) (xy 372.331641 -67.763566) (xy 372.38122 -67.786214)
			(xy 372.427072 -67.815687) (xy 372.468263 -67.851386) (xy 372.503954 -67.892583) (xy 372.533418 -67.938439)
			(xy 372.556057 -67.988023) (xy 372.571409 -68.040323) (xy 372.579162 -68.094276) (xy 372.579646 -68.12153)
			(xy 372.579211 -68.148901) (xy 372.571387 -68.203082) (xy 372.555892 -68.255586) (xy 372.533043 -68.305333)
			(xy 372.503311 -68.351298) (xy 372.485666 -68.372228) (xy 372.485412 -68.372482) (xy 372.479828 -68.379571)
			(xy 372.473579 -68.396486) (xy 372.47322 -68.405502) (xy 372.47322 -68.472558) (xy 372.473593 -68.481573)
			(xy 372.479829 -68.498491) (xy 372.485412 -68.505578) (xy 372.485666 -68.505578) (xy 372.485666 -68.505832)
			(xy 372.503281 -68.526783) (xy 372.532998 -68.57275) (xy 372.555839 -68.622493) (xy 372.571336 -68.674989)
			(xy 372.579169 -68.729162) (xy 372.579646 -68.75653) (xy 372.57915 -68.78378) (xy 372.571391 -68.837726)
			(xy 372.556034 -68.890018) (xy 372.533392 -68.939593) (xy 372.503926 -68.985441) (xy 372.468236 -69.02663)
			(xy 372.427048 -69.062321) (xy 372.3812 -69.091788) (xy 372.331625 -69.114431) (xy 372.279333 -69.129789)
			(xy 372.225388 -69.13755) (xy 372.198138 -69.138038) (xy 372.171822 -69.137632) (xy 372.11969 -69.130387)
			(xy 372.069045 -69.116057) (xy 372.020846 -69.094914) (xy 371.976004 -69.067356) (xy 371.935368 -69.033905)
			(xy 371.917214 -69.014848) (xy 371.909683 -69.007458) (xy 371.89041 -68.998925) (xy 371.879876 -68.998338)
			(xy 371.8052 -68.998338) (xy 371.794647 -68.998842) (xy 371.775351 -69.007394) (xy 371.767862 -69.014848)
			(xy 371.749727 -69.033924) (xy 371.709092 -69.067378) (xy 371.664247 -69.094933) (xy 371.616042 -69.116067)
			(xy 371.565392 -69.130381) (xy 371.513255 -69.137601) (xy 371.486938 -69.138038) (xy 371.459568 -69.137565)
			(xy 371.405388 -69.129751) (xy 371.352885 -69.114264) (xy 371.303138 -69.091424) (xy 371.257171 -69.061699)
			(xy 371.23624 -69.044058) (xy 371.235986 -69.043804) (xy 371.228907 -69.038206) (xy 371.211985 -69.031966)
			(xy 371.202966 -69.031612) (xy 371.13591 -69.031612) (xy 371.126893 -69.031971) (xy 371.109976 -69.038217)
			(xy 371.10289 -69.043804) (xy 371.10289 -69.044058) (xy 371.102636 -69.044058) (xy 371.081696 -69.061687)
			(xy 371.035726 -69.091402) (xy 370.985981 -69.11424) (xy 370.933481 -69.129734) (xy 370.879307 -69.137563)
			(xy 370.851938 -69.138038) (xy 370.824687 -69.137509) (xy 370.77074 -69.129758) (xy 370.718446 -69.114409)
			(xy 370.668868 -69.091773) (xy 370.623016 -69.062312) (xy 370.581823 -69.026625) (xy 370.546129 -68.985439)
			(xy 370.51666 -68.939592) (xy 370.494015 -68.890018) (xy 370.478656 -68.837726) (xy 370.470895 -68.78378)
			(xy 370.47043 -68.75653) (xy 366.994399 -68.75653) (xy 366.988386 -68.769696) (xy 366.958914 -68.815551)
			(xy 366.923216 -68.856745) (xy 366.882019 -68.892438) (xy 366.836161 -68.921905) (xy 366.786576 -68.944545)
			(xy 366.734274 -68.959898) (xy 366.680319 -68.967651) (xy 366.653064 -68.968112) (xy 366.625693 -68.967664)
			(xy 366.571513 -68.959841) (xy 366.51901 -68.944348) (xy 366.469264 -68.921502) (xy 366.423297 -68.891775)
			(xy 366.402366 -68.874132) (xy 366.402112 -68.873878) (xy 366.395028 -68.868288) (xy 366.378109 -68.862044)
			(xy 366.369092 -68.861686) (xy 366.302036 -68.861686) (xy 366.293021 -68.862063) (xy 366.276104 -68.868297)
			(xy 366.269016 -68.873878) (xy 366.269016 -68.874132) (xy 366.268762 -68.874132) (xy 366.247821 -68.89176)
			(xy 366.20185 -68.921473) (xy 366.152105 -68.94431) (xy 366.099606 -68.959804) (xy 366.045433 -68.967636)
			(xy 366.018064 -68.968112) (xy 365.991749 -68.967665) (xy 365.93962 -68.960425) (xy 365.888977 -68.946102)
			(xy 365.840778 -68.924966) (xy 365.795935 -68.897416) (xy 365.755296 -68.863975) (xy 365.73714 -68.844922)
			(xy 365.729603 -68.837539) (xy 365.710335 -68.829003) (xy 365.699802 -68.828412) (xy 365.625126 -68.828412)
			(xy 365.614576 -68.828938) (xy 365.59528 -68.837475) (xy 365.587788 -68.844922) (xy 365.569636 -68.863981)
			(xy 365.529005 -68.897437) (xy 365.484164 -68.924995) (xy 365.435962 -68.946132) (xy 365.385314 -68.960449)
			(xy 365.33318 -68.967674) (xy 365.306864 -68.968112) (xy 365.279612 -68.967656) (xy 365.225663 -68.959894)
			(xy 365.173368 -68.944535) (xy 365.123791 -68.92189) (xy 365.077941 -68.89242) (xy 365.036752 -68.856726)
			(xy 365.001061 -68.815533) (xy 364.971595 -68.769681) (xy 364.948954 -68.720102) (xy 364.933599 -68.667805)
			(xy 364.925842 -68.613856) (xy 364.925356 -68.586604) (xy 361.527344 -68.586604) (xy 361.527344 -70.65264)
			(xy 361.527025 -70.681899) (xy 361.521317 -70.740136) (xy 361.50988 -70.797523) (xy 361.50169 -70.825614)
			(xy 361.499404 -70.832726) (xy 361.499404 -71.555864) (xy 367.494564 -71.555864) (xy 367.498635 -71.500242)
			(xy 367.510761 -71.445805) (xy 367.530684 -71.393714) (xy 367.55798 -71.345079) (xy 367.592066 -71.300936)
			(xy 367.632215 -71.262227) (xy 367.677573 -71.229776) (xy 367.727173 -71.204275) (xy 367.779957 -71.186268)
			(xy 367.8348 -71.176138) (xy 367.890534 -71.174101) (xy 367.945971 -71.180201) (xy 367.999928 -71.194307)
			(xy 368.051257 -71.216119) (xy 368.098863 -71.245173) (xy 368.141731 -71.280848) (xy 368.178948 -71.322385)
			(xy 368.209721 -71.368898) (xy 368.233393 -71.419395) (xy 368.249461 -71.472802) (xy 368.257581 -71.527978)
			(xy 368.25809 -71.555864) (xy 368.257581 -71.58375) (xy 368.251742 -71.623428) (xy 369.003578 -71.623428)
			(xy 369.007649 -71.567806) (xy 369.019775 -71.513369) (xy 369.039698 -71.461278) (xy 369.066994 -71.412643)
			(xy 369.10108 -71.3685) (xy 369.141229 -71.329791) (xy 369.186587 -71.29734) (xy 369.236187 -71.271839)
			(xy 369.288971 -71.253832) (xy 369.343814 -71.243702) (xy 369.399548 -71.241665) (xy 369.454985 -71.247765)
			(xy 369.508942 -71.261871) (xy 369.560271 -71.283683) (xy 369.607877 -71.312737) (xy 369.650745 -71.348412)
			(xy 369.687962 -71.389949) (xy 369.718735 -71.436462) (xy 369.742407 -71.486959) (xy 369.758475 -71.540366)
			(xy 369.766595 -71.595542) (xy 369.767104 -71.623428) (xy 369.766595 -71.651314) (xy 369.758475 -71.70649)
			(xy 369.742407 -71.759897) (xy 369.718735 -71.810394) (xy 369.687962 -71.856907) (xy 369.650745 -71.898444)
			(xy 369.607877 -71.934119) (xy 369.560271 -71.963173) (xy 369.508942 -71.984985) (xy 369.454985 -71.999091)
			(xy 369.399548 -72.005191) (xy 369.343814 -72.003154) (xy 369.288971 -71.993024) (xy 369.236187 -71.975017)
			(xy 369.186587 -71.949516) (xy 369.141229 -71.917065) (xy 369.10108 -71.878356) (xy 369.066994 -71.834213)
			(xy 369.039698 -71.785578) (xy 369.019775 -71.733487) (xy 369.007649 -71.67905) (xy 369.003578 -71.623428)
			(xy 368.251742 -71.623428) (xy 368.249461 -71.638926) (xy 368.233393 -71.692333) (xy 368.209721 -71.74283)
			(xy 368.178948 -71.789343) (xy 368.141731 -71.83088) (xy 368.098863 -71.866555) (xy 368.051257 -71.895609)
			(xy 367.999928 -71.917421) (xy 367.945971 -71.931527) (xy 367.890534 -71.937627) (xy 367.8348 -71.93559)
			(xy 367.779957 -71.92546) (xy 367.727173 -71.907453) (xy 367.677573 -71.881952) (xy 367.632215 -71.849501)
			(xy 367.592066 -71.810792) (xy 367.55798 -71.766649) (xy 367.530684 -71.718014) (xy 367.510761 -71.665923)
			(xy 367.498635 -71.611486) (xy 367.494564 -71.555864) (xy 361.499404 -71.555864) (xy 361.499404 -74.483722)
			(xy 361.499831 -74.49379) (xy 361.507552 -74.512389) (xy 361.51439 -74.51979) (xy 361.909614 -74.915014)
			(xy 361.917009 -74.921868) (xy 361.935608 -74.92961) (xy 361.945682 -74.93) (xy 364.446058 -74.93)
			(xy 364.456123 -74.929566) (xy 364.474713 -74.921837) (xy 364.482126 -74.915014) (xy 364.55477 -74.84237)
			(xy 364.578548 -74.81926) (xy 364.630401 -74.777928) (xy 364.686556 -74.742661) (xy 364.746306 -74.713902)
			(xy 364.808899 -74.692014) (xy 364.87355 -74.677271) (xy 364.939445 -74.669858) (xy 364.9726 -74.669396)
			(xy 374.917462 -74.669396) (xy 374.927527 -74.668961) (xy 374.946115 -74.661231) (xy 374.95353 -74.65441)
			(xy 385.34467 -64.26327) (xy 385.351515 -64.255871) (xy 385.359243 -64.237273) (xy 385.359656 -64.227202)
			(xy 385.359656 -54.365398) (xy 385.17957 -51.366928) (xy 385.179316 -51.364896) (xy 385.179316 -51.363372)
			(xy 385.155186 -51.227736) (xy 385.145026 -51.17084) (xy 385.144518 -51.167792) (xy 385.144264 -51.166776)
			(xy 385.143756 -51.163982) (xy 385.143756 -51.162966) (xy 385.14274 -51.155092) (xy 385.139674 -51.133569)
			(xy 385.136367 -51.090217) (xy 385.136136 -51.068478) (xy 385.136136 -51.068224) (xy 385.13639 -51.048412)
			(xy 385.160774 -50.327306) (xy 385.19735 -49.24933) (xy 385.359656 -44.467018) (xy 385.359656 -43.85818)
			(xy 385.360289 -43.819504) (xy 385.370386 -43.742814) (xy 385.390404 -43.668097) (xy 385.404614 -43.63212)
			(xy 386.25399 -41.581324) (xy 386.269331 -41.545797) (xy 386.307987 -41.478756) (xy 386.355078 -41.417347)
			(xy 386.382006 -41.389554) (xy 389.632698 -38.138862) (xy 389.640064 -38.125146) (xy 389.641334 -38.117526)
			(xy 389.648235 -38.082347) (xy 389.669438 -38.013864) (xy 389.698763 -37.948445) (xy 389.735779 -37.88705)
			(xy 389.779944 -37.830578) (xy 389.80491 -37.804852) (xy 390.15543 -37.454332) (xy 390.183852 -37.426852)
			(xy 390.246706 -37.378899) (xy 390.315382 -37.339735) (xy 390.351772 -37.324284) (xy 390.378442 -37.299138)
			(xy 390.397485 -37.261146) (xy 390.444914 -37.190631) (xy 390.47293 -37.158676) (xy 390.497568 -37.133276)
			(xy 390.498076 -37.132768) (xy 390.584436 -37.046408) (xy 390.58723 -37.041836) (xy 390.604838 -37.015168)
			(xy 390.64493 -36.965402) (xy 390.66724 -36.942522) (xy 391.01776 -36.592002) (xy 391.044603 -36.56596)
			(xy 391.103732 -36.520163) (xy 391.168174 -36.482204) (xy 391.236895 -36.45269) (xy 391.308794 -36.432096)
			(xy 391.345674 -36.425886) (xy 391.348976 -36.422584) (xy 391.356596 -36.404042) (xy 391.356596 -35.9791)
			(xy 391.347452 -35.950144) (xy 391.327491 -35.920429) (xy 391.294123 -35.857097) (xy 391.268661 -35.790193)
			(xy 391.251477 -35.720701) (xy 391.242825 -35.649641) (xy 391.242296 -35.613848) (xy 391.242296 -35.14725)
			(xy 391.241788 -35.144456) (xy 391.24128 -35.142424) (xy 391.241026 -35.140392) (xy 391.240772 -35.138614)
			(xy 391.240772 -35.137852) (xy 391.24001 -35.133788) (xy 391.234676 -35.091624) (xy 391.233914 -35.081972)
			(xy 391.233914 -35.078416) (xy 391.232644 -35.040316) (xy 391.232644 -34.596832) (xy 391.233021 -34.566701)
			(xy 391.239254 -34.506761) (xy 391.24509 -34.477198) (xy 391.246106 -34.466784) (xy 391.245852 -34.461196)
			(xy 391.244134 -34.44455) (xy 391.242357 -34.411129) (xy 391.242296 -34.394394) (xy 391.242296 -34.008822)
			(xy 391.241788 -34.006028) (xy 391.24128 -34.003742) (xy 391.237255 -33.979046) (xy 391.232933 -33.929194)
			(xy 391.232644 -33.904174) (xy 391.232644 -33.459674) (xy 391.23326 -33.421897) (xy 391.243065 -33.346982)
			(xy 391.252202 -33.310322) (xy 391.253509 -33.304762) (xy 391.253904 -33.293349) (xy 391.252964 -33.287716)
			(xy 391.247935 -33.259859) (xy 391.242589 -33.2035) (xy 391.242296 -33.175194) (xy 391.242296 -32.87141)
			(xy 391.241788 -32.868616) (xy 391.24128 -32.86633) (xy 391.237252 -32.841635) (xy 391.232926 -32.791782)
			(xy 391.232644 -32.766762) (xy 391.232644 -32.322516) (xy 391.233438 -32.28005) (xy 391.245809 -32.196024)
			(xy 391.257282 -32.15513) (xy 391.262362 -32.13862) (xy 391.262362 -32.138112) (xy 391.264394 -32.131254)
			(xy 391.264648 -32.117538) (xy 391.262616 -32.110426) (xy 391.253061 -32.072537) (xy 391.242865 -31.995065)
			(xy 391.242296 -31.955994) (xy 391.242296 -31.733998) (xy 391.241788 -31.731204) (xy 391.24128 -31.728918)
			(xy 391.237252 -31.704223) (xy 391.232927 -31.65437) (xy 391.232644 -31.62935) (xy 391.232644 -31.185104)
			(xy 391.233438 -31.142639) (xy 391.245812 -31.058613) (xy 391.257282 -31.017718) (xy 391.262362 -31.000954)
			(xy 391.262362 -31.0007) (xy 391.263632 -30.997144) (xy 391.263886 -30.996382) (xy 391.264394 -30.995112)
			(xy 391.26795 -30.985206) (xy 391.274554 -30.968188) (xy 391.277695 -30.95948) (xy 391.278218 -30.94099)
			(xy 391.27557 -30.93212) (xy 391.265026 -30.900735) (xy 391.250229 -30.836197) (xy 391.242755 -30.770408)
			(xy 391.242296 -30.737302) (xy 391.242296 -30.596586) (xy 391.241788 -30.593792) (xy 391.24128 -30.591506)
			(xy 391.237253 -30.566811) (xy 391.232929 -30.516958) (xy 391.232644 -30.491938) (xy 391.232644 -30.047692)
			(xy 391.233432 -30.005226) (xy 391.245793 -29.921196) (xy 391.257282 -29.880306) (xy 391.262362 -29.863542)
			(xy 391.262362 -29.863288) (xy 391.263632 -29.859732) (xy 391.263886 -29.85897) (xy 391.264394 -29.8577)
			(xy 391.26795 -29.847794) (xy 391.272287 -29.836254) (xy 391.281815 -29.813513) (xy 391.287 -29.802328)
			(xy 391.290302 -29.795216) (xy 391.295382 -29.773372) (xy 391.291064 -29.753052) (xy 391.2794 -29.725181)
			(xy 391.261152 -29.667579) (xy 391.24887 -29.608418) (xy 391.242682 -29.548313) (xy 391.242296 -29.518102)
			(xy 391.242296 -29.459174) (xy 391.241788 -29.45638) (xy 391.24128 -29.454094) (xy 391.237253 -29.429399)
			(xy 391.23293 -29.379546) (xy 391.232644 -29.354526) (xy 391.232644 -28.91028) (xy 391.233433 -28.867814)
			(xy 391.245796 -28.783785) (xy 391.257282 -28.742894) (xy 391.262362 -28.72613) (xy 391.262362 -28.725876)
			(xy 391.263632 -28.72232) (xy 391.263886 -28.721558) (xy 391.264394 -28.720288) (xy 391.26795 -28.710382)
			(xy 391.272287 -28.698842) (xy 391.281815 -28.676101) (xy 391.287 -28.664916) (xy 391.29213 -28.653986)
			(xy 391.303181 -28.632515) (xy 391.309098 -28.62199) (xy 391.315956 -28.59659) (xy 391.310114 -28.573222)
			(xy 391.295576 -28.544651) (xy 391.272078 -28.485003) (xy 391.255181 -28.423161) (xy 391.245085 -28.359852)
			(xy 391.243058 -28.327858) (xy 391.242296 -28.321254) (xy 391.237795 -28.295262) (xy 391.232959 -28.242729)
			(xy 391.232644 -28.216352) (xy 391.232644 -27.967686) (xy 391.232283 -27.95867) (xy 391.226037 -27.941754)
			(xy 391.220452 -27.934666) (xy 391.216642 -27.930094) (xy 391.183685 -27.926006) (xy 391.118905 -27.911368)
			(xy 391.056175 -27.889558) (xy 390.996288 -27.86085) (xy 390.939997 -27.825606) (xy 390.888015 -27.784272)
			(xy 390.840996 -27.737368) (xy 390.799534 -27.685487) (xy 390.764153 -27.629284) (xy 390.735297 -27.569467)
			(xy 390.713333 -27.506791) (xy 390.698536 -27.442047) (xy 390.691094 -27.376053) (xy 390.690608 -27.342846)
			(xy 390.690608 -27.342338) (xy 390.691059 -27.310077) (xy 390.698124 -27.245942) (xy 390.712132 -27.182957)
			(xy 390.732915 -27.121873) (xy 390.760226 -27.063415) (xy 390.79374 -27.008279) (xy 390.813036 -26.98242)
			(xy 390.818116 -26.975816) (xy 390.823704 -26.960068) (xy 390.823704 -26.864056) (xy 390.821926 -26.850848)
			(xy 390.813036 -26.839672) (xy 390.793707 -26.813835) (xy 390.760176 -26.758703) (xy 390.732857 -26.700243)
			(xy 390.712075 -26.639153) (xy 390.69808 -26.576161) (xy 390.691037 -26.512018) (xy 390.690608 -26.479754)
			(xy 390.690608 -26.479246) (xy 390.691144 -26.443533) (xy 390.699746 -26.372628) (xy 390.716829 -26.303276)
			(xy 390.742145 -26.236488) (xy 390.775325 -26.173238) (xy 390.815885 -26.114446) (xy 390.863235 -26.060971)
			(xy 390.916683 -26.013592) (xy 390.975451 -25.972998) (xy 391.038683 -25.939782) (xy 391.105457 -25.914429)
			(xy 391.174799 -25.897306) (xy 391.2457 -25.888664) (xy 391.281412 -25.888188) (xy 391.314573 -25.88867)
			(xy 391.380475 -25.896127) (xy 391.445129 -25.910913) (xy 391.507721 -25.932842) (xy 391.567466 -25.961638)
			(xy 391.623613 -25.99694) (xy 391.675457 -26.038304) (xy 391.699242 -26.061416) (xy 391.802112 -26.164286)
			(xy 391.809511 -26.171132) (xy 391.828109 -26.178864) (xy 391.83818 -26.179272) (xy 391.922762 -26.179272)
			(xy 391.955916 -26.179739) (xy 392.021806 -26.187165) (xy 392.086452 -26.201917) (xy 392.149042 -26.223809)
			(xy 392.208789 -26.252567) (xy 392.264943 -26.287829) (xy 392.316799 -26.329152) (xy 392.340592 -26.352246)
			(xy 392.349228 -26.360882) (xy 393.38961 -26.360882) (xy 393.393681 -26.30526) (xy 393.405807 -26.250823)
			(xy 393.42573 -26.198732) (xy 393.453026 -26.150097) (xy 393.487112 -26.105954) (xy 393.527261 -26.067245)
			(xy 393.572619 -26.034794) (xy 393.622219 -26.009293) (xy 393.675003 -25.991286) (xy 393.729846 -25.981156)
			(xy 393.78558 -25.979119) (xy 393.841017 -25.985219) (xy 393.894974 -25.999325) (xy 393.946303 -26.021137)
			(xy 393.993909 -26.050191) (xy 394.036777 -26.085866) (xy 394.073994 -26.127403) (xy 394.104767 -26.173916)
			(xy 394.128439 -26.224413) (xy 394.144507 -26.27782) (xy 394.150675 -26.319734) (xy 399.141948 -26.319734)
			(xy 399.146019 -26.264112) (xy 399.158145 -26.209675) (xy 399.178068 -26.157584) (xy 399.205364 -26.108949)
			(xy 399.23945 -26.064806) (xy 399.279599 -26.026097) (xy 399.324957 -25.993646) (xy 399.374557 -25.968145)
			(xy 399.427341 -25.950138) (xy 399.482184 -25.940008) (xy 399.537918 -25.937971) (xy 399.593355 -25.944071)
			(xy 399.647312 -25.958177) (xy 399.698641 -25.979989) (xy 399.746247 -26.009043) (xy 399.775912 -26.03373)
			(xy 405.567894 -26.03373) (xy 405.571965 -25.978108) (xy 405.584091 -25.923671) (xy 405.604014 -25.87158)
			(xy 405.63131 -25.822945) (xy 405.665396 -25.778802) (xy 405.705545 -25.740093) (xy 405.750903 -25.707642)
			(xy 405.800503 -25.682141) (xy 405.853287 -25.664134) (xy 405.90813 -25.654004) (xy 405.963864 -25.651967)
			(xy 406.019301 -25.658067) (xy 406.073258 -25.672173) (xy 406.124587 -25.693985) (xy 406.172193 -25.723039)
			(xy 406.215061 -25.758714) (xy 406.252278 -25.800251) (xy 406.283051 -25.846764) (xy 406.306723 -25.897261)
			(xy 406.322791 -25.950668) (xy 406.330911 -26.005844) (xy 406.33142 -26.03373) (xy 406.330911 -26.061616)
			(xy 406.322791 -26.116792) (xy 406.306723 -26.170199) (xy 406.283051 -26.220696) (xy 406.252817 -26.266394)
			(xy 408.82062 -26.266394) (xy 408.821106 -26.239143) (xy 408.828862 -26.185195) (xy 408.844217 -26.1329)
			(xy 408.866859 -26.083323) (xy 408.896325 -26.037473) (xy 408.932016 -25.996282) (xy 408.973207 -25.960591)
			(xy 409.019057 -25.931125) (xy 409.068634 -25.908483) (xy 409.120929 -25.893128) (xy 409.174877 -25.885372)
			(xy 409.229379 -25.885372) (xy 409.283327 -25.893128) (xy 409.335622 -25.908483) (xy 409.385199 -25.931125)
			(xy 409.431049 -25.960591) (xy 409.47224 -25.996282) (xy 409.507931 -26.037473) (xy 409.537397 -26.083323)
			(xy 409.560039 -26.1329) (xy 409.575394 -26.185195) (xy 409.58315 -26.239143) (xy 409.583636 -26.266394)
			(xy 409.58307 -26.295881) (xy 409.573976 -26.35415) (xy 409.55602 -26.410325) (xy 409.529629 -26.463065)
			(xy 409.495434 -26.511113) (xy 409.454248 -26.553324) (xy 409.430982 -26.571448) (xy 409.419828 -26.580308)
			(xy 409.402643 -26.603018) (xy 409.392397 -26.62959) (xy 409.389884 -26.657958) (xy 409.3953 -26.685917)
			(xy 409.408224 -26.711294) (xy 409.427652 -26.732118) (xy 409.439618 -26.73985) (xy 409.463359 -26.754748)
			(xy 409.506593 -26.790416) (xy 409.544144 -26.832025) (xy 409.575203 -26.87868) (xy 409.599102 -26.929377)
			(xy 409.615326 -26.983025) (xy 409.623527 -27.03847) (xy 409.624022 -27.066494) (xy 409.623536 -27.093745)
			(xy 409.61578 -27.147693) (xy 409.600425 -27.199988) (xy 409.577783 -27.249565) (xy 409.548317 -27.295415)
			(xy 409.512626 -27.336606) (xy 409.471435 -27.372297) (xy 409.425585 -27.401763) (xy 409.376008 -27.424405)
			(xy 409.323713 -27.43976) (xy 409.269765 -27.447516) (xy 409.215263 -27.447516) (xy 409.161315 -27.43976)
			(xy 409.10902 -27.424405) (xy 409.059443 -27.401763) (xy 409.013593 -27.372297) (xy 408.972402 -27.336606)
			(xy 408.936711 -27.295415) (xy 408.907245 -27.249565) (xy 408.884603 -27.199988) (xy 408.869248 -27.147693)
			(xy 408.861492 -27.093745) (xy 408.861006 -27.066494) (xy 408.861547 -27.037006) (xy 408.870644 -26.978735)
			(xy 408.888604 -26.922559) (xy 408.914999 -26.869819) (xy 408.9492 -26.821771) (xy 408.990391 -26.779562)
			(xy 409.01366 -26.76144) (xy 409.024718 -26.75247) (xy 409.041894 -26.729784) (xy 409.052142 -26.703238)
			(xy 409.054665 -26.674896) (xy 409.049269 -26.646957) (xy 409.036371 -26.621593) (xy 409.016975 -26.600773)
			(xy 409.005024 -26.593038) (xy 408.981288 -26.578133) (xy 408.938051 -26.542468) (xy 408.900499 -26.500861)
			(xy 408.869438 -26.454207) (xy 408.845538 -26.40351) (xy 408.829314 -26.349862) (xy 408.821114 -26.294418)
			(xy 408.82062 -26.266394) (xy 406.252817 -26.266394) (xy 406.252278 -26.267209) (xy 406.215061 -26.308746)
			(xy 406.172193 -26.344421) (xy 406.124587 -26.373475) (xy 406.073258 -26.395287) (xy 406.019301 -26.409393)
			(xy 405.963864 -26.415493) (xy 405.90813 -26.413456) (xy 405.853287 -26.403326) (xy 405.800503 -26.385319)
			(xy 405.750903 -26.359818) (xy 405.705545 -26.327367) (xy 405.665396 -26.288658) (xy 405.63131 -26.244515)
			(xy 405.604014 -26.19588) (xy 405.584091 -26.143789) (xy 405.571965 -26.089352) (xy 405.567894 -26.03373)
			(xy 399.775912 -26.03373) (xy 399.789115 -26.044718) (xy 399.826332 -26.086255) (xy 399.857105 -26.132768)
			(xy 399.880777 -26.183265) (xy 399.896845 -26.236672) (xy 399.904965 -26.291848) (xy 399.905474 -26.319734)
			(xy 399.904965 -26.34762) (xy 399.896845 -26.402796) (xy 399.880777 -26.456203) (xy 399.857105 -26.5067)
			(xy 399.826332 -26.553213) (xy 399.789115 -26.59475) (xy 399.746247 -26.630425) (xy 399.698641 -26.659479)
			(xy 399.647312 -26.681291) (xy 399.593355 -26.695397) (xy 399.537918 -26.701497) (xy 399.482184 -26.69946)
			(xy 399.427341 -26.68933) (xy 399.374557 -26.671323) (xy 399.324957 -26.645822) (xy 399.279599 -26.613371)
			(xy 399.23945 -26.574662) (xy 399.205364 -26.530519) (xy 399.178068 -26.481884) (xy 399.158145 -26.429793)
			(xy 399.146019 -26.375356) (xy 399.141948 -26.319734) (xy 394.150675 -26.319734) (xy 394.152627 -26.332996)
			(xy 394.153136 -26.360882) (xy 394.152627 -26.388768) (xy 394.144507 -26.443944) (xy 394.128439 -26.497351)
			(xy 394.104767 -26.547848) (xy 394.073994 -26.594361) (xy 394.036777 -26.635898) (xy 393.993909 -26.671573)
			(xy 393.946303 -26.700627) (xy 393.894974 -26.722439) (xy 393.841017 -26.736545) (xy 393.78558 -26.742645)
			(xy 393.729846 -26.740608) (xy 393.675003 -26.730478) (xy 393.622219 -26.712471) (xy 393.572619 -26.68697)
			(xy 393.527261 -26.654519) (xy 393.487112 -26.61581) (xy 393.453026 -26.571667) (xy 393.42573 -26.523032)
			(xy 393.405807 -26.470941) (xy 393.393681 -26.416504) (xy 393.38961 -26.360882) (xy 392.349228 -26.360882)
			(xy 392.64717 -26.658824) (xy 392.670281 -26.682602) (xy 392.711614 -26.734455) (xy 392.746883 -26.79061)
			(xy 392.775644 -26.850359) (xy 392.797536 -26.912952) (xy 392.810833 -26.971244) (xy 395.1511 -26.971244)
			(xy 395.155171 -26.915622) (xy 395.167297 -26.861185) (xy 395.18722 -26.809094) (xy 395.214516 -26.760459)
			(xy 395.248602 -26.716316) (xy 395.288751 -26.677607) (xy 395.334109 -26.645156) (xy 395.383709 -26.619655)
			(xy 395.436493 -26.601648) (xy 395.491336 -26.591518) (xy 395.54707 -26.589481) (xy 395.602507 -26.595581)
			(xy 395.656464 -26.609687) (xy 395.707793 -26.631499) (xy 395.755399 -26.660553) (xy 395.798267 -26.696228)
			(xy 395.835484 -26.737765) (xy 395.866257 -26.784278) (xy 395.889929 -26.834775) (xy 395.905997 -26.888182)
			(xy 395.914117 -26.943358) (xy 395.914626 -26.971244) (xy 395.914117 -26.99913) (xy 395.905997 -27.054306)
			(xy 395.889929 -27.107713) (xy 395.866257 -27.15821) (xy 395.835484 -27.204723) (xy 395.798267 -27.24626)
			(xy 395.755399 -27.281935) (xy 395.707793 -27.310989) (xy 395.656464 -27.332801) (xy 395.602507 -27.346907)
			(xy 395.54707 -27.353007) (xy 395.491336 -27.35097) (xy 395.436493 -27.34084) (xy 395.383709 -27.322833)
			(xy 395.334109 -27.297332) (xy 395.288751 -27.264881) (xy 395.248602 -27.226172) (xy 395.214516 -27.182029)
			(xy 395.18722 -27.133394) (xy 395.167297 -27.081303) (xy 395.155171 -27.026866) (xy 395.1511 -26.971244)
			(xy 392.810833 -26.971244) (xy 392.812283 -26.977603) (xy 392.8197 -27.043498) (xy 392.820144 -27.076654)
			(xy 392.820144 -29.114242) (xy 393.147296 -29.114242) (xy 393.147296 -28.250642) (xy 393.147786 -28.220658)
			(xy 393.155614 -28.161202) (xy 393.171135 -28.103277) (xy 393.194084 -28.047873) (xy 393.224068 -27.995939)
			(xy 393.260574 -27.948363) (xy 393.302979 -27.905958) (xy 393.350555 -27.869452) (xy 393.402489 -27.839468)
			(xy 393.457893 -27.816519) (xy 393.515818 -27.800998) (xy 393.575274 -27.79317) (xy 393.635242 -27.79317)
			(xy 393.694698 -27.800998) (xy 393.752623 -27.816519) (xy 393.808027 -27.839468) (xy 393.859961 -27.869452)
			(xy 393.907537 -27.905958) (xy 393.949942 -27.948363) (xy 393.986448 -27.995939) (xy 394.016432 -28.047873)
			(xy 394.039381 -28.103277) (xy 394.054902 -28.161202) (xy 394.06273 -28.220658) (xy 394.06322 -28.250642)
			(xy 394.06322 -28.469082) (xy 398.052542 -28.469082) (xy 398.056613 -28.41346) (xy 398.068739 -28.359023)
			(xy 398.088662 -28.306932) (xy 398.115958 -28.258297) (xy 398.150044 -28.214154) (xy 398.190193 -28.175445)
			(xy 398.235551 -28.142994) (xy 398.285151 -28.117493) (xy 398.337935 -28.099486) (xy 398.392778 -28.089356)
			(xy 398.448512 -28.087319) (xy 398.503949 -28.093419) (xy 398.557906 -28.107525) (xy 398.609235 -28.129337)
			(xy 398.625291 -28.139136) (xy 402.697948 -28.139136) (xy 402.702019 -28.083514) (xy 402.714145 -28.029077)
			(xy 402.734068 -27.976986) (xy 402.761364 -27.928351) (xy 402.79545 -27.884208) (xy 402.835599 -27.845499)
			(xy 402.880957 -27.813048) (xy 402.930557 -27.787547) (xy 402.983341 -27.76954) (xy 403.038184 -27.75941)
			(xy 403.093918 -27.757373) (xy 403.149355 -27.763473) (xy 403.203312 -27.777579) (xy 403.254641 -27.799391)
			(xy 403.302247 -27.828445) (xy 403.345115 -27.86412) (xy 403.382332 -27.905657) (xy 403.413105 -27.95217)
			(xy 403.436777 -28.002667) (xy 403.452845 -28.056074) (xy 403.460965 -28.11125) (xy 403.461474 -28.139136)
			(xy 403.967948 -28.139136) (xy 403.972019 -28.083514) (xy 403.984145 -28.029077) (xy 404.004068 -27.976986)
			(xy 404.031364 -27.928351) (xy 404.06545 -27.884208) (xy 404.105599 -27.845499) (xy 404.150957 -27.813048)
			(xy 404.200557 -27.787547) (xy 404.253341 -27.76954) (xy 404.308184 -27.75941) (xy 404.363918 -27.757373)
			(xy 404.419355 -27.763473) (xy 404.473312 -27.777579) (xy 404.524641 -27.799391) (xy 404.572247 -27.828445)
			(xy 404.615115 -27.86412) (xy 404.652332 -27.905657) (xy 404.683105 -27.95217) (xy 404.706777 -28.002667)
			(xy 404.722845 -28.056074) (xy 404.730965 -28.11125) (xy 404.731474 -28.139136) (xy 404.730965 -28.167022)
			(xy 404.722845 -28.222198) (xy 404.706777 -28.275605) (xy 404.683105 -28.326102) (xy 404.652332 -28.372615)
			(xy 404.615115 -28.414152) (xy 404.572247 -28.449827) (xy 404.524641 -28.478881) (xy 404.473312 -28.500693)
			(xy 404.419355 -28.514799) (xy 404.363918 -28.520899) (xy 404.308184 -28.518862) (xy 404.253341 -28.508732)
			(xy 404.200557 -28.490725) (xy 404.150957 -28.465224) (xy 404.105599 -28.432773) (xy 404.06545 -28.394064)
			(xy 404.031364 -28.349921) (xy 404.004068 -28.301286) (xy 403.984145 -28.249195) (xy 403.972019 -28.194758)
			(xy 403.967948 -28.139136) (xy 403.461474 -28.139136) (xy 403.460965 -28.167022) (xy 403.452845 -28.222198)
			(xy 403.436777 -28.275605) (xy 403.413105 -28.326102) (xy 403.382332 -28.372615) (xy 403.345115 -28.414152)
			(xy 403.302247 -28.449827) (xy 403.254641 -28.478881) (xy 403.203312 -28.500693) (xy 403.149355 -28.514799)
			(xy 403.093918 -28.520899) (xy 403.038184 -28.518862) (xy 402.983341 -28.508732) (xy 402.930557 -28.490725)
			(xy 402.880957 -28.465224) (xy 402.835599 -28.432773) (xy 402.79545 -28.394064) (xy 402.761364 -28.349921)
			(xy 402.734068 -28.301286) (xy 402.714145 -28.249195) (xy 402.702019 -28.194758) (xy 402.697948 -28.139136)
			(xy 398.625291 -28.139136) (xy 398.656841 -28.158391) (xy 398.699709 -28.194066) (xy 398.736926 -28.235603)
			(xy 398.767699 -28.282116) (xy 398.791371 -28.332613) (xy 398.807439 -28.38602) (xy 398.815559 -28.441196)
			(xy 398.816068 -28.469082) (xy 398.815559 -28.496968) (xy 398.807439 -28.552144) (xy 398.791371 -28.605551)
			(xy 398.767699 -28.656048) (xy 398.736926 -28.702561) (xy 398.699709 -28.744098) (xy 398.656841 -28.779773)
			(xy 398.609235 -28.808827) (xy 398.557906 -28.830639) (xy 398.503949 -28.844745) (xy 398.448512 -28.850845)
			(xy 398.392778 -28.848808) (xy 398.337935 -28.838678) (xy 398.285151 -28.820671) (xy 398.235551 -28.79517)
			(xy 398.190193 -28.762719) (xy 398.150044 -28.72401) (xy 398.115958 -28.679867) (xy 398.088662 -28.631232)
			(xy 398.068739 -28.579141) (xy 398.056613 -28.524704) (xy 398.052542 -28.469082) (xy 394.06322 -28.469082)
			(xy 394.06322 -29.114242) (xy 394.063087 -29.12237) (xy 408.90698 -29.12237) (xy 408.90698 -28.25877)
			(xy 408.90747 -28.228802) (xy 408.915293 -28.16938) (xy 408.930806 -28.111487) (xy 408.953742 -28.056114)
			(xy 408.983709 -28.004208) (xy 409.020196 -27.956658) (xy 409.062576 -27.914278) (xy 409.110126 -27.877791)
			(xy 409.162032 -27.847824) (xy 409.217405 -27.824888) (xy 409.275298 -27.809375) (xy 409.33472 -27.801552)
			(xy 409.394656 -27.801552) (xy 409.454078 -27.809375) (xy 409.511971 -27.824888) (xy 409.567344 -27.847824)
			(xy 409.61925 -27.877791) (xy 409.6668 -27.914278) (xy 409.70918 -27.956658) (xy 409.745667 -28.004208)
			(xy 409.775634 -28.056114) (xy 409.79857 -28.111487) (xy 409.814083 -28.16938) (xy 409.821906 -28.228802)
			(xy 409.822396 -28.25877) (xy 409.822396 -29.12237) (xy 409.821906 -29.152338) (xy 409.814083 -29.21176)
			(xy 409.79857 -29.269653) (xy 409.775634 -29.325026) (xy 409.745667 -29.376932) (xy 409.70918 -29.424482)
			(xy 409.6668 -29.466862) (xy 409.61925 -29.503349) (xy 409.567344 -29.533316) (xy 409.511971 -29.556252)
			(xy 409.454078 -29.571765) (xy 409.394656 -29.579588) (xy 409.33472 -29.579588) (xy 409.275298 -29.571765)
			(xy 409.217405 -29.556252) (xy 409.162032 -29.533316) (xy 409.110126 -29.503349) (xy 409.062576 -29.466862)
			(xy 409.020196 -29.424482) (xy 408.983709 -29.376932) (xy 408.953742 -29.325026) (xy 408.930806 -29.269653)
			(xy 408.915293 -29.21176) (xy 408.90747 -29.152338) (xy 408.90698 -29.12237) (xy 394.063087 -29.12237)
			(xy 394.06273 -29.144226) (xy 394.054902 -29.203682) (xy 394.039381 -29.261607) (xy 394.016432 -29.317011)
			(xy 393.986448 -29.368945) (xy 393.949942 -29.416521) (xy 393.907537 -29.458926) (xy 393.859961 -29.495432)
			(xy 393.808027 -29.525416) (xy 393.752623 -29.548365) (xy 393.694698 -29.563886) (xy 393.635242 -29.571714)
			(xy 393.575274 -29.571714) (xy 393.515818 -29.563886) (xy 393.457893 -29.548365) (xy 393.402489 -29.525416)
			(xy 393.350555 -29.495432) (xy 393.302979 -29.458926) (xy 393.260574 -29.416521) (xy 393.224068 -29.368945)
			(xy 393.194084 -29.317011) (xy 393.171135 -29.261607) (xy 393.155614 -29.203682) (xy 393.147786 -29.144226)
			(xy 393.147296 -29.114242) (xy 392.820144 -29.114242) (xy 392.820144 -30.92069) (xy 395.789404 -30.92069)
			(xy 395.789404 -30.05709) (xy 395.789894 -30.027106) (xy 395.797722 -29.96765) (xy 395.813243 -29.909725)
			(xy 395.836192 -29.854321) (xy 395.866176 -29.802387) (xy 395.902682 -29.754811) (xy 395.945087 -29.712406)
			(xy 395.992663 -29.6759) (xy 396.044597 -29.645916) (xy 396.100001 -29.622967) (xy 396.157926 -29.607446)
			(xy 396.217382 -29.599618) (xy 396.27735 -29.599618) (xy 396.336806 -29.607446) (xy 396.394731 -29.622967)
			(xy 396.450135 -29.645916) (xy 396.502069 -29.6759) (xy 396.549645 -29.712406) (xy 396.59205 -29.754811)
			(xy 396.628556 -29.802387) (xy 396.65854 -29.854321) (xy 396.681489 -29.909725) (xy 396.69701 -29.96765)
			(xy 396.704838 -30.027106) (xy 396.705328 -30.05709) (xy 396.705328 -30.376876) (xy 401.188936 -30.376876)
			(xy 401.189496 -30.34796) (xy 401.198214 -30.290791) (xy 401.215463 -30.235592) (xy 401.240847 -30.18363)
			(xy 401.273784 -30.136095) (xy 401.313519 -30.094077) (xy 401.336002 -30.075886) (xy 401.344806 -30.068275)
			(xy 401.354991 -30.047377) (xy 401.35556 -30.035754) (xy 401.35556 -29.955998) (xy 401.355022 -29.944366)
			(xy 401.344834 -29.923455) (xy 401.336002 -29.915866) (xy 401.313503 -29.897694) (xy 401.273768 -29.85567)
			(xy 401.240831 -29.808131) (xy 401.215445 -29.756166) (xy 401.198193 -29.700965) (xy 401.189468 -29.643793)
			(xy 401.188936 -29.614876) (xy 401.189422 -29.587625) (xy 401.197178 -29.533677) (xy 401.212533 -29.481382)
			(xy 401.235175 -29.431805) (xy 401.264641 -29.385955) (xy 401.300332 -29.344764) (xy 401.341523 -29.309073)
			(xy 401.387373 -29.279607) (xy 401.43695 -29.256965) (xy 401.489245 -29.24161) (xy 401.543193 -29.233854)
			(xy 401.597695 -29.233854) (xy 401.651643 -29.24161) (xy 401.703938 -29.256965) (xy 401.753515 -29.279607)
			(xy 401.799365 -29.309073) (xy 401.840556 -29.344764) (xy 401.876247 -29.385955) (xy 401.905713 -29.431805)
			(xy 401.928355 -29.481382) (xy 401.94371 -29.533677) (xy 401.951466 -29.587625) (xy 401.951952 -29.614876)
			(xy 401.951435 -29.643793) (xy 401.942708 -29.700965) (xy 401.925451 -29.756165) (xy 401.900059 -29.808127)
			(xy 401.867115 -29.855661) (xy 401.827372 -29.897677) (xy 401.804886 -29.915866) (xy 401.796102 -29.923496)
			(xy 401.785906 -29.944379) (xy 401.785328 -29.955998) (xy 401.785328 -30.035754) (xy 401.785841 -30.047389)
			(xy 401.796047 -30.068299) (xy 401.804886 -30.075886) (xy 401.82736 -30.094088) (xy 401.867096 -30.136105)
			(xy 401.900037 -30.183638) (xy 401.925427 -30.235597) (xy 401.942685 -30.290793) (xy 401.951416 -30.347961)
			(xy 401.951952 -30.376876) (xy 404.229062 -30.376876) (xy 404.229612 -30.34796) (xy 404.238331 -30.290789)
			(xy 404.255581 -30.23559) (xy 404.280967 -30.183628) (xy 404.313906 -30.136093) (xy 404.353644 -30.094076)
			(xy 404.376128 -30.075886) (xy 404.384936 -30.06828) (xy 404.395118 -30.047378) (xy 404.395686 -30.035754)
			(xy 404.395686 -29.955998) (xy 404.395138 -29.944367) (xy 404.384956 -29.923457) (xy 404.376128 -29.915866)
			(xy 404.353634 -29.897687) (xy 404.313898 -29.855666) (xy 404.28096 -29.808129) (xy 404.255573 -29.756165)
			(xy 404.238319 -29.700965) (xy 404.229594 -29.643793) (xy 404.229062 -29.614876) (xy 404.229548 -29.587625)
			(xy 404.237304 -29.533677) (xy 404.252659 -29.481382) (xy 404.275301 -29.431805) (xy 404.304767 -29.385955)
			(xy 404.340458 -29.344764) (xy 404.381649 -29.309073) (xy 404.427499 -29.279607) (xy 404.477076 -29.256965)
			(xy 404.529371 -29.24161) (xy 404.583319 -29.233854) (xy 404.637821 -29.233854) (xy 404.691769 -29.24161)
			(xy 404.744064 -29.256965) (xy 404.793641 -29.279607) (xy 404.839491 -29.309073) (xy 404.880682 -29.344764)
			(xy 404.916373 -29.385955) (xy 404.945839 -29.431805) (xy 404.968481 -29.481382) (xy 404.983836 -29.533677)
			(xy 404.991592 -29.587625) (xy 404.992078 -29.614876) (xy 404.991551 -29.643793) (xy 404.982825 -29.700964)
			(xy 404.965569 -29.756163) (xy 404.940179 -29.808125) (xy 404.907237 -29.855659) (xy 404.867497 -29.897676)
			(xy 404.845012 -29.915866) (xy 404.836232 -29.9235) (xy 404.826033 -29.94438) (xy 404.825454 -29.955998)
			(xy 404.825454 -30.035754) (xy 404.825957 -30.047391) (xy 404.83617 -30.068301) (xy 404.845012 -30.075886)
			(xy 404.867491 -30.094082) (xy 404.907226 -30.136101) (xy 404.940165 -30.183635) (xy 404.965554 -30.235595)
			(xy 404.982812 -30.290792) (xy 404.991542 -30.34796) (xy 404.992078 -30.376876) (xy 404.991592 -30.404127)
			(xy 404.983836 -30.458075) (xy 404.968481 -30.51037) (xy 404.945839 -30.559947) (xy 404.916373 -30.605797)
			(xy 404.880682 -30.646988) (xy 404.839491 -30.682679) (xy 404.793641 -30.712145) (xy 404.744064 -30.734787)
			(xy 404.691769 -30.750142) (xy 404.637821 -30.757898) (xy 404.583319 -30.757898) (xy 404.529371 -30.750142)
			(xy 404.477076 -30.734787) (xy 404.427499 -30.712145) (xy 404.381649 -30.682679) (xy 404.340458 -30.646988)
			(xy 404.304767 -30.605797) (xy 404.275301 -30.559947) (xy 404.252659 -30.51037) (xy 404.237304 -30.458075)
			(xy 404.229548 -30.404127) (xy 404.229062 -30.376876) (xy 401.951952 -30.376876) (xy 401.951466 -30.404127)
			(xy 401.94371 -30.458075) (xy 401.928355 -30.51037) (xy 401.905713 -30.559947) (xy 401.876247 -30.605797)
			(xy 401.840556 -30.646988) (xy 401.799365 -30.682679) (xy 401.753515 -30.712145) (xy 401.703938 -30.734787)
			(xy 401.651643 -30.750142) (xy 401.597695 -30.757898) (xy 401.543193 -30.757898) (xy 401.489245 -30.750142)
			(xy 401.43695 -30.734787) (xy 401.387373 -30.712145) (xy 401.341523 -30.682679) (xy 401.300332 -30.646988)
			(xy 401.264641 -30.605797) (xy 401.235175 -30.559947) (xy 401.212533 -30.51037) (xy 401.197178 -30.458075)
			(xy 401.189422 -30.404127) (xy 401.188936 -30.376876) (xy 396.705328 -30.376876) (xy 396.705328 -30.92069)
			(xy 396.705299 -30.922468) (xy 407.05278 -30.922468) (xy 407.05278 -30.058868) (xy 407.05327 -30.0289)
			(xy 407.061093 -29.969478) (xy 407.076606 -29.911585) (xy 407.099542 -29.856212) (xy 407.129509 -29.804306)
			(xy 407.165996 -29.756756) (xy 407.208376 -29.714376) (xy 407.255926 -29.677889) (xy 407.307832 -29.647922)
			(xy 407.363205 -29.624986) (xy 407.421098 -29.609473) (xy 407.48052 -29.60165) (xy 407.540456 -29.60165)
			(xy 407.599878 -29.609473) (xy 407.657771 -29.624986) (xy 407.713144 -29.647922) (xy 407.76505 -29.677889)
			(xy 407.8126 -29.714376) (xy 407.85498 -29.756756) (xy 407.891467 -29.804306) (xy 407.921434 -29.856212)
			(xy 407.94437 -29.911585) (xy 407.959883 -29.969478) (xy 407.967706 -30.0289) (xy 407.968196 -30.058868)
			(xy 407.968196 -30.922468) (xy 407.967706 -30.952436) (xy 407.959883 -31.011858) (xy 407.94437 -31.069751)
			(xy 407.921434 -31.125124) (xy 407.891467 -31.17703) (xy 407.85498 -31.22458) (xy 407.8126 -31.26696)
			(xy 407.76505 -31.303447) (xy 407.713144 -31.333414) (xy 407.657771 -31.35635) (xy 407.599878 -31.371863)
			(xy 407.540456 -31.379686) (xy 407.48052 -31.379686) (xy 407.421098 -31.371863) (xy 407.363205 -31.35635)
			(xy 407.307832 -31.333414) (xy 407.255926 -31.303447) (xy 407.208376 -31.26696) (xy 407.165996 -31.22458)
			(xy 407.129509 -31.17703) (xy 407.099542 -31.125124) (xy 407.076606 -31.069751) (xy 407.061093 -31.011858)
			(xy 407.05327 -30.952436) (xy 407.05278 -30.922468) (xy 396.705299 -30.922468) (xy 396.704838 -30.950674)
			(xy 396.69701 -31.01013) (xy 396.681489 -31.068055) (xy 396.65854 -31.123459) (xy 396.628556 -31.175393)
			(xy 396.59205 -31.222969) (xy 396.549645 -31.265374) (xy 396.502069 -31.30188) (xy 396.450135 -31.331864)
			(xy 396.394731 -31.354813) (xy 396.336806 -31.370334) (xy 396.27735 -31.378162) (xy 396.217382 -31.378162)
			(xy 396.157926 -31.370334) (xy 396.100001 -31.354813) (xy 396.044597 -31.331864) (xy 395.992663 -31.30188)
			(xy 395.945087 -31.265374) (xy 395.902682 -31.222969) (xy 395.866176 -31.175393) (xy 395.836192 -31.123459)
			(xy 395.813243 -31.068055) (xy 395.797722 -31.01013) (xy 395.789894 -30.950674) (xy 395.789404 -30.92069)
			(xy 392.820144 -30.92069) (xy 392.820144 -32.714184) (xy 393.147296 -32.714184) (xy 393.147296 -31.850584)
			(xy 393.147786 -31.8206) (xy 393.155614 -31.761144) (xy 393.171135 -31.703219) (xy 393.194084 -31.647815)
			(xy 393.224068 -31.595881) (xy 393.260574 -31.548305) (xy 393.302979 -31.5059) (xy 393.350555 -31.469394)
			(xy 393.402489 -31.43941) (xy 393.457893 -31.416461) (xy 393.515818 -31.40094) (xy 393.575274 -31.393112)
			(xy 393.635242 -31.393112) (xy 393.694698 -31.40094) (xy 393.752623 -31.416461) (xy 393.808027 -31.43941)
			(xy 393.859961 -31.469394) (xy 393.907537 -31.5059) (xy 393.949942 -31.548305) (xy 393.964964 -31.567882)
			(xy 401.298662 -31.567882) (xy 401.302733 -31.51226) (xy 401.314859 -31.457823) (xy 401.334782 -31.405732)
			(xy 401.362078 -31.357097) (xy 401.396164 -31.312954) (xy 401.436313 -31.274245) (xy 401.481671 -31.241794)
			(xy 401.531271 -31.216293) (xy 401.584055 -31.198286) (xy 401.638898 -31.188156) (xy 401.694632 -31.186119)
			(xy 401.750069 -31.192219) (xy 401.804026 -31.206325) (xy 401.855355 -31.228137) (xy 401.902961 -31.257191)
			(xy 401.945829 -31.292866) (xy 401.983046 -31.334403) (xy 402.013819 -31.380916) (xy 402.037491 -31.431413)
			(xy 402.053559 -31.48482) (xy 402.061679 -31.539996) (xy 402.062188 -31.567882) (xy 402.061679 -31.595768)
			(xy 402.053559 -31.650944) (xy 402.037491 -31.704351) (xy 402.030499 -31.719266) (xy 402.585426 -31.719266)
			(xy 402.589497 -31.663644) (xy 402.601623 -31.609207) (xy 402.621546 -31.557116) (xy 402.648842 -31.508481)
			(xy 402.682928 -31.464338) (xy 402.723077 -31.425629) (xy 402.768435 -31.393178) (xy 402.818035 -31.367677)
			(xy 402.870819 -31.34967) (xy 402.925662 -31.33954) (xy 402.981396 -31.337503) (xy 403.036833 -31.343603)
			(xy 403.09079 -31.357709) (xy 403.142119 -31.379521) (xy 403.189725 -31.408575) (xy 403.232593 -31.44425)
			(xy 403.26981 -31.485787) (xy 403.300583 -31.5323) (xy 403.324255 -31.582797) (xy 403.340323 -31.636204)
			(xy 403.344473 -31.664402) (xy 403.861014 -31.664402) (xy 403.865085 -31.60878) (xy 403.877211 -31.554343)
			(xy 403.897134 -31.502252) (xy 403.92443 -31.453617) (xy 403.958516 -31.409474) (xy 403.998665 -31.370765)
			(xy 404.044023 -31.338314) (xy 404.093623 -31.312813) (xy 404.146407 -31.294806) (xy 404.20125 -31.284676)
			(xy 404.256984 -31.282639) (xy 404.312421 -31.288739) (xy 404.366378 -31.302845) (xy 404.417707 -31.324657)
			(xy 404.465313 -31.353711) (xy 404.508181 -31.389386) (xy 404.545398 -31.430923) (xy 404.576171 -31.477436)
			(xy 404.599843 -31.527933) (xy 404.615911 -31.58134) (xy 404.624031 -31.636516) (xy 404.62454 -31.664402)
			(xy 404.624031 -31.692288) (xy 404.615911 -31.747464) (xy 404.606971 -31.777178) (xy 405.126188 -31.777178)
			(xy 405.130259 -31.721556) (xy 405.142385 -31.667119) (xy 405.162308 -31.615028) (xy 405.189604 -31.566393)
			(xy 405.22369 -31.52225) (xy 405.263839 -31.483541) (xy 405.309197 -31.45109) (xy 405.358797 -31.425589)
			(xy 405.411581 -31.407582) (xy 405.466424 -31.397452) (xy 405.522158 -31.395415) (xy 405.577595 -31.401515)
			(xy 405.631552 -31.415621) (xy 405.682881 -31.437433) (xy 405.730487 -31.466487) (xy 405.773355 -31.502162)
			(xy 405.810572 -31.543699) (xy 405.841345 -31.590212) (xy 405.865017 -31.640709) (xy 405.881085 -31.694116)
			(xy 405.889205 -31.749292) (xy 405.889714 -31.777178) (xy 405.889205 -31.805064) (xy 405.881085 -31.86024)
			(xy 405.865017 -31.913647) (xy 405.841345 -31.964144) (xy 405.810572 -32.010657) (xy 405.773355 -32.052194)
			(xy 405.730487 -32.087869) (xy 405.682881 -32.116923) (xy 405.631552 -32.138735) (xy 405.577595 -32.152841)
			(xy 405.522158 -32.158941) (xy 405.466424 -32.156904) (xy 405.411581 -32.146774) (xy 405.358797 -32.128767)
			(xy 405.309197 -32.103266) (xy 405.263839 -32.070815) (xy 405.22369 -32.032106) (xy 405.189604 -31.987963)
			(xy 405.162308 -31.939328) (xy 405.142385 -31.887237) (xy 405.130259 -31.8328) (xy 405.126188 -31.777178)
			(xy 404.606971 -31.777178) (xy 404.599843 -31.800871) (xy 404.576171 -31.851368) (xy 404.545398 -31.897881)
			(xy 404.508181 -31.939418) (xy 404.465313 -31.975093) (xy 404.417707 -32.004147) (xy 404.366378 -32.025959)
			(xy 404.312421 -32.040065) (xy 404.256984 -32.046165) (xy 404.20125 -32.044128) (xy 404.146407 -32.033998)
			(xy 404.093623 -32.015991) (xy 404.044023 -31.99049) (xy 403.998665 -31.958039) (xy 403.958516 -31.91933)
			(xy 403.92443 -31.875187) (xy 403.897134 -31.826552) (xy 403.877211 -31.774461) (xy 403.865085 -31.720024)
			(xy 403.861014 -31.664402) (xy 403.344473 -31.664402) (xy 403.348443 -31.69138) (xy 403.348952 -31.719266)
			(xy 403.348443 -31.747152) (xy 403.340323 -31.802328) (xy 403.324255 -31.855735) (xy 403.300583 -31.906232)
			(xy 403.26981 -31.952745) (xy 403.232593 -31.994282) (xy 403.189725 -32.029957) (xy 403.142119 -32.059011)
			(xy 403.09079 -32.080823) (xy 403.036833 -32.094929) (xy 402.981396 -32.101029) (xy 402.925662 -32.098992)
			(xy 402.870819 -32.088862) (xy 402.818035 -32.070855) (xy 402.768435 -32.045354) (xy 402.723077 -32.012903)
			(xy 402.682928 -31.974194) (xy 402.648842 -31.930051) (xy 402.621546 -31.881416) (xy 402.601623 -31.829325)
			(xy 402.589497 -31.774888) (xy 402.585426 -31.719266) (xy 402.030499 -31.719266) (xy 402.013819 -31.754848)
			(xy 401.983046 -31.801361) (xy 401.945829 -31.842898) (xy 401.902961 -31.878573) (xy 401.855355 -31.907627)
			(xy 401.804026 -31.929439) (xy 401.750069 -31.943545) (xy 401.694632 -31.949645) (xy 401.638898 -31.947608)
			(xy 401.584055 -31.937478) (xy 401.531271 -31.919471) (xy 401.481671 -31.89397) (xy 401.436313 -31.861519)
			(xy 401.396164 -31.82281) (xy 401.362078 -31.778667) (xy 401.334782 -31.730032) (xy 401.314859 -31.677941)
			(xy 401.302733 -31.623504) (xy 401.298662 -31.567882) (xy 393.964964 -31.567882) (xy 393.986448 -31.595881)
			(xy 394.016432 -31.647815) (xy 394.039381 -31.703219) (xy 394.054902 -31.761144) (xy 394.06273 -31.8206)
			(xy 394.06322 -31.850584) (xy 394.06322 -32.714184) (xy 394.063087 -32.722312) (xy 408.90698 -32.722312)
			(xy 408.90698 -31.858712) (xy 408.90747 -31.828744) (xy 408.915293 -31.769322) (xy 408.930806 -31.711429)
			(xy 408.953742 -31.656056) (xy 408.983709 -31.60415) (xy 409.020196 -31.5566) (xy 409.062576 -31.51422)
			(xy 409.110126 -31.477733) (xy 409.162032 -31.447766) (xy 409.217405 -31.42483) (xy 409.275298 -31.409317)
			(xy 409.33472 -31.401494) (xy 409.394656 -31.401494) (xy 409.454078 -31.409317) (xy 409.511971 -31.42483)
			(xy 409.567344 -31.447766) (xy 409.61925 -31.477733) (xy 409.6668 -31.51422) (xy 409.70918 -31.5566)
			(xy 409.745667 -31.60415) (xy 409.775634 -31.656056) (xy 409.79857 -31.711429) (xy 409.814083 -31.769322)
			(xy 409.821906 -31.828744) (xy 409.822396 -31.858712) (xy 409.822396 -32.722312) (xy 409.821906 -32.75228)
			(xy 409.814083 -32.811702) (xy 409.79857 -32.869595) (xy 409.775634 -32.924968) (xy 409.745667 -32.976874)
			(xy 409.70918 -33.024424) (xy 409.6668 -33.066804) (xy 409.61925 -33.103291) (xy 409.567344 -33.133258)
			(xy 409.511971 -33.156194) (xy 409.454078 -33.171707) (xy 409.394656 -33.17953) (xy 409.33472 -33.17953)
			(xy 409.275298 -33.171707) (xy 409.217405 -33.156194) (xy 409.162032 -33.133258) (xy 409.110126 -33.103291)
			(xy 409.062576 -33.066804) (xy 409.020196 -33.024424) (xy 408.983709 -32.976874) (xy 408.953742 -32.924968)
			(xy 408.930806 -32.869595) (xy 408.915293 -32.811702) (xy 408.90747 -32.75228) (xy 408.90698 -32.722312)
			(xy 394.063087 -32.722312) (xy 394.06273 -32.744168) (xy 394.054902 -32.803624) (xy 394.039381 -32.861549)
			(xy 394.016432 -32.916953) (xy 393.986448 -32.968887) (xy 393.949942 -33.016463) (xy 393.907537 -33.058868)
			(xy 393.859961 -33.095374) (xy 393.808027 -33.125358) (xy 393.752623 -33.148307) (xy 393.694698 -33.163828)
			(xy 393.635242 -33.171656) (xy 393.575274 -33.171656) (xy 393.515818 -33.163828) (xy 393.457893 -33.148307)
			(xy 393.402489 -33.125358) (xy 393.350555 -33.095374) (xy 393.302979 -33.058868) (xy 393.260574 -33.016463)
			(xy 393.224068 -32.968887) (xy 393.194084 -32.916953) (xy 393.171135 -32.861549) (xy 393.155614 -32.803624)
			(xy 393.147786 -32.744168) (xy 393.147296 -32.714184) (xy 392.820144 -32.714184) (xy 392.820144 -34.520886)
			(xy 395.789404 -34.520886) (xy 395.789404 -33.657286) (xy 395.789894 -33.627302) (xy 395.797722 -33.567846)
			(xy 395.813243 -33.509921) (xy 395.836192 -33.454517) (xy 395.866176 -33.402583) (xy 395.902682 -33.355007)
			(xy 395.945087 -33.312602) (xy 395.992663 -33.276096) (xy 396.044597 -33.246112) (xy 396.100001 -33.223163)
			(xy 396.157926 -33.207642) (xy 396.217382 -33.199814) (xy 396.27735 -33.199814) (xy 396.336806 -33.207642)
			(xy 396.394731 -33.223163) (xy 396.450135 -33.246112) (xy 396.502069 -33.276096) (xy 396.549645 -33.312602)
			(xy 396.59205 -33.355007) (xy 396.628556 -33.402583) (xy 396.65854 -33.454517) (xy 396.681489 -33.509921)
			(xy 396.69701 -33.567846) (xy 396.704838 -33.627302) (xy 396.705328 -33.657286) (xy 396.705328 -34.520886)
			(xy 396.705303 -34.52241) (xy 407.05278 -34.52241) (xy 407.05278 -33.65881) (xy 407.05327 -33.628842)
			(xy 407.061093 -33.56942) (xy 407.076606 -33.511527) (xy 407.099542 -33.456154) (xy 407.129509 -33.404248)
			(xy 407.165996 -33.356698) (xy 407.208376 -33.314318) (xy 407.255926 -33.277831) (xy 407.307832 -33.247864)
			(xy 407.363205 -33.224928) (xy 407.421098 -33.209415) (xy 407.48052 -33.201592) (xy 407.540456 -33.201592)
			(xy 407.599878 -33.209415) (xy 407.657771 -33.224928) (xy 407.713144 -33.247864) (xy 407.76505 -33.277831)
			(xy 407.8126 -33.314318) (xy 407.85498 -33.356698) (xy 407.891467 -33.404248) (xy 407.921434 -33.456154)
			(xy 407.94437 -33.511527) (xy 407.959883 -33.56942) (xy 407.967706 -33.628842) (xy 407.968196 -33.65881)
			(xy 407.968196 -34.52241) (xy 407.967706 -34.552378) (xy 407.959883 -34.6118) (xy 407.94437 -34.669693)
			(xy 407.921434 -34.725066) (xy 407.891467 -34.776972) (xy 407.85498 -34.824522) (xy 407.8126 -34.866902)
			(xy 407.76505 -34.903389) (xy 407.713144 -34.933356) (xy 407.657771 -34.956292) (xy 407.599878 -34.971805)
			(xy 407.540456 -34.979628) (xy 407.48052 -34.979628) (xy 407.421098 -34.971805) (xy 407.363205 -34.956292)
			(xy 407.307832 -34.933356) (xy 407.255926 -34.903389) (xy 407.208376 -34.866902) (xy 407.165996 -34.824522)
			(xy 407.129509 -34.776972) (xy 407.099542 -34.725066) (xy 407.076606 -34.669693) (xy 407.061093 -34.6118)
			(xy 407.05327 -34.552378) (xy 407.05278 -34.52241) (xy 396.705303 -34.52241) (xy 396.704838 -34.55087)
			(xy 396.69701 -34.610326) (xy 396.681489 -34.668251) (xy 396.65854 -34.723655) (xy 396.628556 -34.775589)
			(xy 396.59205 -34.823165) (xy 396.549645 -34.86557) (xy 396.502069 -34.902076) (xy 396.450135 -34.93206)
			(xy 396.394731 -34.955009) (xy 396.336806 -34.97053) (xy 396.27735 -34.978358) (xy 396.217382 -34.978358)
			(xy 396.157926 -34.97053) (xy 396.100001 -34.955009) (xy 396.044597 -34.93206) (xy 395.992663 -34.902076)
			(xy 395.945087 -34.86557) (xy 395.902682 -34.823165) (xy 395.866176 -34.775589) (xy 395.836192 -34.723655)
			(xy 395.813243 -34.668251) (xy 395.797722 -34.610326) (xy 395.789894 -34.55087) (xy 395.789404 -34.520886)
			(xy 392.820144 -34.520886) (xy 392.820144 -35.264852) (xy 404.20239 -35.264852) (xy 404.206461 -35.20923)
			(xy 404.218587 -35.154793) (xy 404.23851 -35.102702) (xy 404.265806 -35.054067) (xy 404.299892 -35.009924)
			(xy 404.340041 -34.971215) (xy 404.385399 -34.938764) (xy 404.434999 -34.913263) (xy 404.487783 -34.895256)
			(xy 404.542626 -34.885126) (xy 404.59836 -34.883089) (xy 404.653797 -34.889189) (xy 404.707754 -34.903295)
			(xy 404.759083 -34.925107) (xy 404.806689 -34.954161) (xy 404.849557 -34.989836) (xy 404.886774 -35.031373)
			(xy 404.917547 -35.077886) (xy 404.941219 -35.128383) (xy 404.957287 -35.18179) (xy 404.965407 -35.236966)
			(xy 404.965916 -35.264852) (xy 404.965407 -35.292738) (xy 404.957287 -35.347914) (xy 404.941219 -35.401321)
			(xy 404.917547 -35.451818) (xy 404.886774 -35.498331) (xy 404.849557 -35.539868) (xy 404.806689 -35.575543)
			(xy 404.759083 -35.604597) (xy 404.707754 -35.626409) (xy 404.653797 -35.640515) (xy 404.59836 -35.646615)
			(xy 404.542626 -35.644578) (xy 404.487783 -35.634448) (xy 404.434999 -35.616441) (xy 404.385399 -35.59094)
			(xy 404.340041 -35.558489) (xy 404.299892 -35.51978) (xy 404.265806 -35.475637) (xy 404.23851 -35.427002)
			(xy 404.218587 -35.374911) (xy 404.206461 -35.320474) (xy 404.20239 -35.264852) (xy 392.820144 -35.264852)
			(xy 392.820144 -35.876738) (xy 393.017246 -35.876738) (xy 393.021317 -35.821116) (xy 393.033443 -35.766679)
			(xy 393.053366 -35.714588) (xy 393.080662 -35.665953) (xy 393.114748 -35.62181) (xy 393.154897 -35.583101)
			(xy 393.200255 -35.55065) (xy 393.249855 -35.525149) (xy 393.302639 -35.507142) (xy 393.357482 -35.497012)
			(xy 393.413216 -35.494975) (xy 393.468653 -35.501075) (xy 393.52261 -35.515181) (xy 393.573939 -35.536993)
			(xy 393.621545 -35.566047) (xy 393.664413 -35.601722) (xy 393.70163 -35.643259) (xy 393.732403 -35.689772)
			(xy 393.756075 -35.740269) (xy 393.772143 -35.793676) (xy 393.780263 -35.848852) (xy 393.780772 -35.876738)
			(xy 397.088866 -35.876738) (xy 397.092937 -35.821116) (xy 397.105063 -35.766679) (xy 397.124986 -35.714588)
			(xy 397.152282 -35.665953) (xy 397.186368 -35.62181) (xy 397.226517 -35.583101) (xy 397.271875 -35.55065)
			(xy 397.321475 -35.525149) (xy 397.374259 -35.507142) (xy 397.429102 -35.497012) (xy 397.484836 -35.494975)
			(xy 397.540273 -35.501075) (xy 397.59423 -35.515181) (xy 397.645559 -35.536993) (xy 397.693165 -35.566047)
			(xy 397.736033 -35.601722) (xy 397.77325 -35.643259) (xy 397.804023 -35.689772) (xy 397.827695 -35.740269)
			(xy 397.843763 -35.793676) (xy 397.851883 -35.848852) (xy 397.852392 -35.876738) (xy 397.851883 -35.904624)
			(xy 397.843763 -35.9598) (xy 397.827695 -36.013207) (xy 397.804023 -36.063704) (xy 397.77325 -36.110217)
			(xy 397.736033 -36.151754) (xy 397.693165 -36.187429) (xy 397.645559 -36.216483) (xy 397.59423 -36.238295)
			(xy 397.540273 -36.252401) (xy 397.484836 -36.258501) (xy 397.429102 -36.256464) (xy 397.374259 -36.246334)
			(xy 397.321475 -36.228327) (xy 397.271875 -36.202826) (xy 397.226517 -36.170375) (xy 397.186368 -36.131666)
			(xy 397.152282 -36.087523) (xy 397.124986 -36.038888) (xy 397.105063 -35.986797) (xy 397.092937 -35.93236)
			(xy 397.088866 -35.876738) (xy 393.780772 -35.876738) (xy 393.780263 -35.904624) (xy 393.772143 -35.9598)
			(xy 393.756075 -36.013207) (xy 393.732403 -36.063704) (xy 393.70163 -36.110217) (xy 393.664413 -36.151754)
			(xy 393.621545 -36.187429) (xy 393.573939 -36.216483) (xy 393.52261 -36.238295) (xy 393.468653 -36.252401)
			(xy 393.413216 -36.258501) (xy 393.357482 -36.256464) (xy 393.302639 -36.246334) (xy 393.249855 -36.228327)
			(xy 393.200255 -36.202826) (xy 393.154897 -36.170375) (xy 393.114748 -36.131666) (xy 393.080662 -36.087523)
			(xy 393.053366 -36.038888) (xy 393.033443 -35.986797) (xy 393.021317 -35.93236) (xy 393.017246 -35.876738)
			(xy 392.820144 -35.876738) (xy 392.820144 -36.50996) (xy 394.913864 -36.50996) (xy 394.917935 -36.454338)
			(xy 394.930061 -36.399901) (xy 394.949984 -36.34781) (xy 394.97728 -36.299175) (xy 395.011366 -36.255032)
			(xy 395.051515 -36.216323) (xy 395.096873 -36.183872) (xy 395.146473 -36.158371) (xy 395.199257 -36.140364)
			(xy 395.2541 -36.130234) (xy 395.309834 -36.128197) (xy 395.365271 -36.134297) (xy 395.419228 -36.148403)
			(xy 395.470557 -36.170215) (xy 395.518163 -36.199269) (xy 395.561031 -36.234944) (xy 395.598248 -36.276481)
			(xy 395.629021 -36.322994) (xy 395.652693 -36.373491) (xy 395.668761 -36.426898) (xy 395.672686 -36.453572)
			(xy 398.228564 -36.453572) (xy 398.232635 -36.39795) (xy 398.244761 -36.343513) (xy 398.264684 -36.291422)
			(xy 398.29198 -36.242787) (xy 398.326066 -36.198644) (xy 398.366215 -36.159935) (xy 398.411573 -36.127484)
			(xy 398.461173 -36.101983) (xy 398.513957 -36.083976) (xy 398.5688 -36.073846) (xy 398.624534 -36.071809)
			(xy 398.679971 -36.077909) (xy 398.733928 -36.092015) (xy 398.785257 -36.113827) (xy 398.832863 -36.142881)
			(xy 398.875731 -36.178556) (xy 398.912948 -36.220093) (xy 398.943721 -36.266606) (xy 398.953257 -36.286948)
			(xy 405.50033 -36.286948) (xy 405.504401 -36.231326) (xy 405.516527 -36.176889) (xy 405.53645 -36.124798)
			(xy 405.563746 -36.076163) (xy 405.597832 -36.03202) (xy 405.637981 -35.993311) (xy 405.683339 -35.96086)
			(xy 405.732939 -35.935359) (xy 405.785723 -35.917352) (xy 405.840566 -35.907222) (xy 405.8963 -35.905185)
			(xy 405.951737 -35.911285) (xy 406.005694 -35.925391) (xy 406.057023 -35.947203) (xy 406.104629 -35.976257)
			(xy 406.147497 -36.011932) (xy 406.184714 -36.053469) (xy 406.215487 -36.099982) (xy 406.239159 -36.150479)
			(xy 406.255227 -36.203886) (xy 406.263347 -36.259062) (xy 406.263856 -36.286948) (xy 406.263347 -36.314834)
			(xy 406.255227 -36.37001) (xy 406.239159 -36.423417) (xy 406.215487 -36.473914) (xy 406.187942 -36.515548)
			(xy 407.314144 -36.515548) (xy 407.318215 -36.459926) (xy 407.330341 -36.405489) (xy 407.350264 -36.353398)
			(xy 407.37756 -36.304763) (xy 407.411646 -36.26062) (xy 407.451795 -36.221911) (xy 407.497153 -36.18946)
			(xy 407.546753 -36.163959) (xy 407.599537 -36.145952) (xy 407.65438 -36.135822) (xy 407.710114 -36.133785)
			(xy 407.765551 -36.139885) (xy 407.819508 -36.153991) (xy 407.870837 -36.175803) (xy 407.918443 -36.204857)
			(xy 407.961311 -36.240532) (xy 407.998528 -36.282069) (xy 408.029301 -36.328582) (xy 408.052973 -36.379079)
			(xy 408.069041 -36.432486) (xy 408.077161 -36.487662) (xy 408.07767 -36.515548) (xy 408.077161 -36.543434)
			(xy 408.069041 -36.59861) (xy 408.068584 -36.60013) (xy 412.298649 -36.60013) (xy 412.302653 -36.512245)
			(xy 412.314633 -36.425088) (xy 412.334488 -36.339381) (xy 412.362055 -36.255836) (xy 412.397105 -36.175143)
			(xy 412.439347 -36.097971) (xy 412.488432 -36.024961) (xy 412.543953 -35.956717) (xy 412.60545 -35.893804)
			(xy 412.672412 -35.836744) (xy 412.744286 -35.78601) (xy 412.820476 -35.742022) (xy 412.90035 -35.705144)
			(xy 412.983247 -35.675683) (xy 413.068479 -35.653881) (xy 413.155341 -35.639921) (xy 413.243112 -35.633917)
			(xy 413.331066 -35.63592) (xy 413.418473 -35.645912) (xy 413.504609 -35.663812) (xy 413.588761 -35.68947)
			(xy 413.670231 -35.722674) (xy 413.748344 -35.763148) (xy 413.822452 -35.810559) (xy 413.891943 -35.864512)
			(xy 413.956239 -35.92456) (xy 414.014808 -35.990207) (xy 414.067165 -36.060907) (xy 414.112877 -36.136076)
			(xy 414.151563 -36.21509) (xy 414.182904 -36.297295) (xy 414.206639 -36.382009) (xy 414.222573 -36.46853)
			(xy 414.230573 -36.556142) (xy 414.231074 -36.60013) (xy 414.230573 -36.644118) (xy 414.222573 -36.73173)
			(xy 414.206639 -36.818251) (xy 414.182904 -36.902965) (xy 414.151563 -36.98517) (xy 414.112877 -37.064184)
			(xy 414.067165 -37.139353) (xy 414.014808 -37.210053) (xy 413.956239 -37.2757) (xy 413.891943 -37.335748)
			(xy 413.822452 -37.389701) (xy 413.748344 -37.437112) (xy 413.670231 -37.477586) (xy 413.588761 -37.51079)
			(xy 413.504609 -37.536448) (xy 413.418473 -37.554348) (xy 413.331066 -37.56434) (xy 413.243112 -37.566343)
			(xy 413.155341 -37.560339) (xy 413.068479 -37.546379) (xy 412.983247 -37.524577) (xy 412.90035 -37.495116)
			(xy 412.820476 -37.458238) (xy 412.744286 -37.41425) (xy 412.672412 -37.363516) (xy 412.60545 -37.306456)
			(xy 412.543953 -37.243543) (xy 412.488432 -37.175299) (xy 412.439347 -37.102289) (xy 412.397105 -37.025117)
			(xy 412.362055 -36.944424) (xy 412.334488 -36.860879) (xy 412.314633 -36.775172) (xy 412.302653 -36.688015)
			(xy 412.298649 -36.60013) (xy 408.068584 -36.60013) (xy 408.052973 -36.652017) (xy 408.029301 -36.702514)
			(xy 407.998528 -36.749027) (xy 407.961311 -36.790564) (xy 407.918443 -36.826239) (xy 407.870837 -36.855293)
			(xy 407.819508 -36.877105) (xy 407.765551 -36.891211) (xy 407.710114 -36.897311) (xy 407.65438 -36.895274)
			(xy 407.599537 -36.885144) (xy 407.546753 -36.867137) (xy 407.497153 -36.841636) (xy 407.451795 -36.809185)
			(xy 407.411646 -36.770476) (xy 407.37756 -36.726333) (xy 407.350264 -36.677698) (xy 407.330341 -36.625607)
			(xy 407.318215 -36.57117) (xy 407.314144 -36.515548) (xy 406.187942 -36.515548) (xy 406.184714 -36.520427)
			(xy 406.147497 -36.561964) (xy 406.104629 -36.597639) (xy 406.057023 -36.626693) (xy 406.005694 -36.648505)
			(xy 405.951737 -36.662611) (xy 405.8963 -36.668711) (xy 405.840566 -36.666674) (xy 405.785723 -36.656544)
			(xy 405.732939 -36.638537) (xy 405.683339 -36.613036) (xy 405.637981 -36.580585) (xy 405.597832 -36.541876)
			(xy 405.563746 -36.497733) (xy 405.53645 -36.449098) (xy 405.516527 -36.397007) (xy 405.504401 -36.34257)
			(xy 405.50033 -36.286948) (xy 398.953257 -36.286948) (xy 398.967393 -36.317103) (xy 398.983461 -36.37051)
			(xy 398.991581 -36.425686) (xy 398.99209 -36.453572) (xy 398.991581 -36.481458) (xy 398.983461 -36.536634)
			(xy 398.967393 -36.590041) (xy 398.943721 -36.640538) (xy 398.912948 -36.687051) (xy 398.875731 -36.728588)
			(xy 398.832863 -36.764263) (xy 398.785257 -36.793317) (xy 398.733928 -36.815129) (xy 398.679971 -36.829235)
			(xy 398.624534 -36.835335) (xy 398.5688 -36.833298) (xy 398.513957 -36.823168) (xy 398.461173 -36.805161)
			(xy 398.411573 -36.77966) (xy 398.366215 -36.747209) (xy 398.326066 -36.7085) (xy 398.29198 -36.664357)
			(xy 398.264684 -36.615722) (xy 398.244761 -36.563631) (xy 398.232635 -36.509194) (xy 398.228564 -36.453572)
			(xy 395.672686 -36.453572) (xy 395.676881 -36.482074) (xy 395.67739 -36.50996) (xy 395.676881 -36.537846)
			(xy 395.668761 -36.593022) (xy 395.652693 -36.646429) (xy 395.629021 -36.696926) (xy 395.598248 -36.743439)
			(xy 395.561031 -36.784976) (xy 395.518163 -36.820651) (xy 395.470557 -36.849705) (xy 395.419228 -36.871517)
			(xy 395.365271 -36.885623) (xy 395.309834 -36.891723) (xy 395.2541 -36.889686) (xy 395.199257 -36.879556)
			(xy 395.146473 -36.861549) (xy 395.096873 -36.836048) (xy 395.051515 -36.803597) (xy 395.011366 -36.764888)
			(xy 394.97728 -36.720745) (xy 394.949984 -36.67211) (xy 394.930061 -36.620019) (xy 394.917935 -36.565582)
			(xy 394.913864 -36.50996) (xy 392.820144 -36.50996) (xy 392.820144 -36.777168) (xy 392.819697 -36.809082)
			(xy 392.812783 -36.872535) (xy 392.799076 -36.934874) (xy 392.778734 -36.995375) (xy 392.751994 -37.053332)
			(xy 392.719168 -37.108073) (xy 392.700256 -37.133784) (xy 392.69797 -37.143182) (xy 392.70051 -37.165788)
			(xy 392.70051 -37.166296) (xy 392.702542 -37.183314) (xy 392.705844 -37.19449) (xy 392.710416 -37.20465)
			(xy 392.716512 -37.211) (xy 392.736307 -37.232457) (xy 392.76981 -37.280262) (xy 392.795646 -37.332608)
			(xy 392.813215 -37.388278) (xy 392.822106 -37.445972) (xy 392.822684 -37.47516) (xy 392.822223 -37.502414)
			(xy 392.814471 -37.556368) (xy 392.799118 -37.608669) (xy 392.776478 -37.658253) (xy 392.77384 -37.662358)
			(xy 394.248384 -37.662358) (xy 394.252455 -37.606736) (xy 394.264581 -37.552299) (xy 394.284504 -37.500208)
			(xy 394.3118 -37.451573) (xy 394.345886 -37.40743) (xy 394.386035 -37.368721) (xy 394.431393 -37.33627)
			(xy 394.480993 -37.310769) (xy 394.533777 -37.292762) (xy 394.58862 -37.282632) (xy 394.644354 -37.280595)
			(xy 394.699791 -37.286695) (xy 394.753748 -37.300801) (xy 394.805077 -37.322613) (xy 394.852683 -37.351667)
			(xy 394.895551 -37.387342) (xy 394.932768 -37.428879) (xy 394.963541 -37.475392) (xy 394.987213 -37.525889)
			(xy 395.003281 -37.579296) (xy 395.011401 -37.634472) (xy 395.01191 -37.662358) (xy 395.011401 -37.690244)
			(xy 395.003281 -37.74542) (xy 394.994647 -37.774118) (xy 405.764744 -37.774118) (xy 405.768815 -37.718496)
			(xy 405.780941 -37.664059) (xy 405.800864 -37.611968) (xy 405.82816 -37.563333) (xy 405.862246 -37.51919)
			(xy 405.902395 -37.480481) (xy 405.947753 -37.44803) (xy 405.997353 -37.422529) (xy 406.050137 -37.404522)
			(xy 406.10498 -37.394392) (xy 406.160714 -37.392355) (xy 406.216151 -37.398455) (xy 406.270108 -37.412561)
			(xy 406.321437 -37.434373) (xy 406.369043 -37.463427) (xy 406.411911 -37.499102) (xy 406.449128 -37.540639)
			(xy 406.479901 -37.587152) (xy 406.503573 -37.637649) (xy 406.519641 -37.691056) (xy 406.527761 -37.746232)
			(xy 406.52827 -37.774118) (xy 406.527761 -37.802004) (xy 406.519641 -37.85718) (xy 406.503573 -37.910587)
			(xy 406.479901 -37.961084) (xy 406.449128 -38.007597) (xy 406.411911 -38.049134) (xy 406.369043 -38.084809)
			(xy 406.321437 -38.113863) (xy 406.270108 -38.135675) (xy 406.216151 -38.149781) (xy 406.160714 -38.155881)
			(xy 406.10498 -38.153844) (xy 406.050137 -38.143714) (xy 405.997353 -38.125707) (xy 405.947753 -38.100206)
			(xy 405.902395 -38.067755) (xy 405.862246 -38.029046) (xy 405.82816 -37.984903) (xy 405.800864 -37.936268)
			(xy 405.780941 -37.884177) (xy 405.768815 -37.82974) (xy 405.764744 -37.774118) (xy 394.994647 -37.774118)
			(xy 394.987213 -37.798827) (xy 394.963541 -37.849324) (xy 394.932768 -37.895837) (xy 394.895551 -37.937374)
			(xy 394.852683 -37.973049) (xy 394.805077 -38.002103) (xy 394.753748 -38.023915) (xy 394.699791 -38.038021)
			(xy 394.644354 -38.044121) (xy 394.58862 -38.042084) (xy 394.533777 -38.031954) (xy 394.480993 -38.013947)
			(xy 394.431393 -37.988446) (xy 394.386035 -37.955995) (xy 394.345886 -37.917286) (xy 394.3118 -37.873143)
			(xy 394.284504 -37.824508) (xy 394.264581 -37.772417) (xy 394.252455 -37.71798) (xy 394.248384 -37.662358)
			(xy 392.77384 -37.662358) (xy 392.74701 -37.704109) (xy 392.711316 -37.745305) (xy 392.670122 -37.781001)
			(xy 392.624267 -37.81047) (xy 392.574684 -37.833112) (xy 392.522384 -37.848467) (xy 392.46843 -37.856222)
			(xy 392.441176 -37.856668) (xy 392.411232 -37.856088) (xy 392.352077 -37.846738) (xy 392.295112 -37.828257)
			(xy 392.241735 -37.801099) (xy 392.19326 -37.765931) (xy 392.171682 -37.745162) (xy 392.171428 -37.744908)
			(xy 392.163983 -37.738263) (xy 392.145519 -37.730746) (xy 392.125583 -37.730805) (xy 392.107164 -37.738431)
			(xy 392.0998 -37.745162) (xy 391.115015 -38.729947) (xy 398.00102 -38.729947) (xy 398.00102 -38.675453)
			(xy 398.008775 -38.621512) (xy 398.024128 -38.569225) (xy 398.046765 -38.519654) (xy 398.076226 -38.47381)
			(xy 398.111912 -38.432625) (xy 398.153096 -38.396937) (xy 398.198939 -38.367474) (xy 398.248508 -38.344834)
			(xy 398.300795 -38.329479) (xy 398.354735 -38.321721) (xy 398.381982 -38.321234) (xy 398.410286 -38.321722)
			(xy 398.466276 -38.330072) (xy 398.520416 -38.346607) (xy 398.571517 -38.370962) (xy 398.618457 -38.402603)
			(xy 398.660204 -38.440835) (xy 398.695841 -38.484818) (xy 398.710658 -38.50894) (xy 398.718214 -38.521004)
			(xy 398.738841 -38.540607) (xy 398.764082 -38.553749) (xy 398.791972 -38.559405) (xy 398.820338 -38.557135)
			(xy 398.846973 -38.547117) (xy 398.869804 -38.530129) (xy 398.878806 -38.5191) (xy 398.896994 -38.496225)
			(xy 398.939156 -38.455761) (xy 398.986992 -38.422194) (xy 399.039383 -38.396306) (xy 399.095108 -38.378704)
			(xy 399.152863 -38.369797) (xy 399.182082 -38.36924) (xy 399.209339 -38.369606) (xy 399.263299 -38.377362)
			(xy 399.315606 -38.392718) (xy 399.365194 -38.415362) (xy 399.411055 -38.444834) (xy 399.452255 -38.480532)
			(xy 399.487956 -38.52173) (xy 399.517429 -38.56759) (xy 399.540076 -38.617178) (xy 399.555435 -38.669484)
			(xy 399.563193 -38.723443) (xy 399.563193 -38.777957) (xy 399.555435 -38.831916) (xy 399.540076 -38.884222)
			(xy 399.517429 -38.93381) (xy 399.487956 -38.97967) (xy 399.452255 -39.020868) (xy 399.411055 -39.056566)
			(xy 399.365194 -39.086038) (xy 399.315606 -39.108682) (xy 399.263299 -39.124038) (xy 399.209339 -39.131794)
			(xy 399.182082 -39.132256) (xy 399.153779 -39.131722) (xy 399.097792 -39.123381) (xy 399.043653 -39.106855)
			(xy 398.992551 -39.082508) (xy 398.945611 -39.050873) (xy 398.903862 -39.012647) (xy 398.868223 -38.968669)
			(xy 398.853406 -38.94455) (xy 398.845767 -38.932544) (xy 398.825156 -38.912946) (xy 398.799933 -38.899804)
			(xy 398.772061 -38.894142) (xy 398.743709 -38.8964) (xy 398.717085 -38.906403) (xy 398.69426 -38.923371)
			(xy 398.685258 -38.93439) (xy 398.667088 -38.95728) (xy 398.624922 -38.997743) (xy 398.577083 -39.03131)
			(xy 398.524688 -39.057194) (xy 398.46896 -39.074793) (xy 398.411202 -39.083695) (xy 398.381982 -39.08425)
			(xy 398.354735 -39.083679) (xy 398.300795 -39.075921) (xy 398.248508 -39.060566) (xy 398.198939 -39.037926)
			(xy 398.153096 -39.008463) (xy 398.111912 -38.972775) (xy 398.076226 -38.93159) (xy 398.046765 -38.885746)
			(xy 398.024128 -38.836175) (xy 398.008775 -38.783888) (xy 398.00102 -38.729947) (xy 391.115015 -38.729947)
			(xy 389.872982 -39.97198) (xy 400.195794 -39.97198) (xy 400.199865 -39.916358) (xy 400.211991 -39.861921)
			(xy 400.231914 -39.80983) (xy 400.25921 -39.761195) (xy 400.293296 -39.717052) (xy 400.333445 -39.678343)
			(xy 400.378803 -39.645892) (xy 400.428403 -39.620391) (xy 400.481187 -39.602384) (xy 400.53603 -39.592254)
			(xy 400.591764 -39.590217) (xy 400.647201 -39.596317) (xy 400.701158 -39.610423) (xy 400.752487 -39.632235)
			(xy 400.800093 -39.661289) (xy 400.842961 -39.696964) (xy 400.880178 -39.738501) (xy 400.910951 -39.785014)
			(xy 400.934623 -39.835511) (xy 400.950691 -39.888918) (xy 400.958811 -39.944094) (xy 400.95932 -39.97198)
			(xy 400.958811 -39.999866) (xy 400.950691 -40.055042) (xy 400.934623 -40.108449) (xy 400.910951 -40.158946)
			(xy 400.880178 -40.205459) (xy 400.842961 -40.246996) (xy 400.800093 -40.282671) (xy 400.752487 -40.311725)
			(xy 400.701158 -40.333537) (xy 400.647201 -40.347643) (xy 400.591764 -40.353743) (xy 400.53603 -40.351706)
			(xy 400.481187 -40.341576) (xy 400.428403 -40.323569) (xy 400.378803 -40.298068) (xy 400.333445 -40.265617)
			(xy 400.293296 -40.226908) (xy 400.25921 -40.182765) (xy 400.231914 -40.13413) (xy 400.211991 -40.082039)
			(xy 400.199865 -40.027602) (xy 400.195794 -39.97198) (xy 389.872982 -39.97198) (xy 388.576209 -41.268753)
			(xy 390.14395 -41.268753) (xy 390.14395 -41.214247) (xy 390.151707 -41.160295) (xy 390.167063 -41.107996)
			(xy 390.189706 -41.058416) (xy 390.219174 -41.012562) (xy 390.254869 -40.971369) (xy 390.296062 -40.935674)
			(xy 390.341916 -40.906206) (xy 390.391496 -40.883563) (xy 390.443795 -40.868207) (xy 390.497747 -40.86045)
			(xy 390.525 -40.859964) (xy 390.553738 -40.860497) (xy 390.610565 -40.869119) (xy 390.665455 -40.886167)
			(xy 390.717167 -40.911257) (xy 390.76453 -40.943819) (xy 390.785858 -40.963088) (xy 390.792716 -40.969692)
			(xy 390.81075 -40.976804) (xy 390.89965 -40.976804) (xy 390.917684 -40.969692) (xy 390.924542 -40.963088)
			(xy 390.945876 -40.943826) (xy 390.993235 -40.911256) (xy 391.044945 -40.886161) (xy 391.099835 -40.869109)
			(xy 391.156661 -40.860485) (xy 391.1854 -40.859964) (xy 391.212649 -40.860506) (xy 391.266593 -40.868262)
			(xy 391.318884 -40.883616) (xy 391.368457 -40.906256) (xy 391.414304 -40.93572) (xy 391.455491 -40.971409)
			(xy 391.49118 -41.012596) (xy 391.520644 -41.058443) (xy 391.543284 -41.108016) (xy 391.558638 -41.160307)
			(xy 391.566394 -41.214251) (xy 391.566394 -41.268749) (xy 391.558638 -41.322693) (xy 391.543284 -41.374984)
			(xy 391.520644 -41.424557) (xy 391.49118 -41.470404) (xy 391.455491 -41.511591) (xy 391.414304 -41.54728)
			(xy 391.368457 -41.576744) (xy 391.318884 -41.599384) (xy 391.266593 -41.614738) (xy 391.212649 -41.622494)
			(xy 391.1854 -41.62298) (xy 391.156662 -41.622435) (xy 391.099837 -41.613814) (xy 391.044947 -41.596768)
			(xy 390.993235 -41.571682) (xy 390.945871 -41.539123) (xy 390.924542 -41.519856) (xy 390.917684 -41.513252)
			(xy 390.89965 -41.50614) (xy 390.81075 -41.50614) (xy 390.792716 -41.513252) (xy 390.785858 -41.519856)
			(xy 390.76453 -41.539126) (xy 390.717168 -41.571692) (xy 390.665457 -41.596785) (xy 390.610566 -41.613836)
			(xy 390.553739 -41.622459) (xy 390.525 -41.62298) (xy 390.497747 -41.62255) (xy 390.443795 -41.614793)
			(xy 390.391496 -41.599437) (xy 390.341916 -41.576794) (xy 390.296062 -41.547326) (xy 390.254869 -41.511631)
			(xy 390.219174 -41.470438) (xy 390.189706 -41.424584) (xy 390.167063 -41.375004) (xy 390.151707 -41.322705)
			(xy 390.14395 -41.268753) (xy 388.576209 -41.268753) (xy 387.567678 -42.277284) (xy 387.564391 -42.280764)
			(xy 387.559025 -42.28869) (xy 387.55701 -42.293032) (xy 387.483858 -42.461434) (xy 387.415786 -42.618152)
			(xy 387.283452 -42.923206) (xy 387.263386 -42.969942) (xy 387.262878 -42.97045) (xy 387.124184 -43.305222)
			(xy 392.607292 -43.305222) (xy 392.607773 -43.277852) (xy 392.615587 -43.223674) (xy 392.631073 -43.171171)
			(xy 392.653912 -43.121424) (xy 392.683633 -43.075456) (xy 392.701272 -43.054524) (xy 392.701526 -43.05427)
			(xy 392.707092 -43.04717) (xy 392.71335 -43.030263) (xy 392.713718 -43.02125) (xy 392.713718 -42.954194)
			(xy 392.71336 -42.945177) (xy 392.707113 -42.928261) (xy 392.701526 -42.921174) (xy 392.701272 -42.921174)
			(xy 392.701272 -42.92092) (xy 392.683624 -42.899995) (xy 392.653915 -42.85402) (xy 392.631081 -42.80427)
			(xy 392.615592 -42.751768) (xy 392.607765 -42.697592) (xy 392.607292 -42.670222) (xy 392.607831 -42.641484)
			(xy 392.61645 -42.584657) (xy 392.633497 -42.529767) (xy 392.658585 -42.478055) (xy 392.691147 -42.430691)
			(xy 392.710416 -42.409364) (xy 392.71702 -42.402506) (xy 392.724132 -42.384472) (xy 392.724132 -42.295572)
			(xy 392.71702 -42.277538) (xy 392.710416 -42.27068) (xy 392.691167 -42.249334) (xy 392.658602 -42.201975)
			(xy 392.63351 -42.150266) (xy 392.616459 -42.095378) (xy 392.607834 -42.038554) (xy 392.607832 -41.981078)
			(xy 392.616451 -41.924253) (xy 392.633498 -41.869364) (xy 392.658586 -41.817653) (xy 392.691147 -41.770291)
			(xy 392.710416 -41.748964) (xy 392.71702 -41.742106) (xy 392.724132 -41.724072) (xy 392.724132 -41.635172)
			(xy 392.71702 -41.617138) (xy 392.710416 -41.61028) (xy 392.691152 -41.588947) (xy 392.658586 -41.541586)
			(xy 392.633492 -41.489876) (xy 392.61644 -41.434987) (xy 392.607815 -41.378161) (xy 392.607292 -41.349422)
			(xy 392.607778 -41.322171) (xy 392.615534 -41.268223) (xy 392.630889 -41.215928) (xy 392.653531 -41.166351)
			(xy 392.682997 -41.120501) (xy 392.718688 -41.07931) (xy 392.759879 -41.043619) (xy 392.805729 -41.014153)
			(xy 392.855306 -40.991511) (xy 392.907601 -40.976156) (xy 392.961549 -40.9684) (xy 393.016051 -40.9684)
			(xy 393.039172 -40.971724) (xy 400.89404 -40.971724) (xy 400.898111 -40.916102) (xy 400.910237 -40.861665)
			(xy 400.93016 -40.809574) (xy 400.957456 -40.760939) (xy 400.991542 -40.716796) (xy 401.031691 -40.678087)
			(xy 401.077049 -40.645636) (xy 401.126649 -40.620135) (xy 401.179433 -40.602128) (xy 401.234276 -40.591998)
			(xy 401.29001 -40.589961) (xy 401.345447 -40.596061) (xy 401.399404 -40.610167) (xy 401.450733 -40.631979)
			(xy 401.498339 -40.661033) (xy 401.541207 -40.696708) (xy 401.578424 -40.738245) (xy 401.609197 -40.784758)
			(xy 401.632869 -40.835255) (xy 401.648937 -40.888662) (xy 401.657057 -40.943838) (xy 401.657566 -40.971724)
			(xy 401.657057 -40.99961) (xy 401.648937 -41.054786) (xy 401.632869 -41.108193) (xy 401.609197 -41.15869)
			(xy 401.578424 -41.205203) (xy 401.541207 -41.24674) (xy 401.498339 -41.282415) (xy 401.450733 -41.311469)
			(xy 401.399404 -41.333281) (xy 401.345447 -41.347387) (xy 401.29001 -41.353487) (xy 401.234276 -41.35145)
			(xy 401.179433 -41.34132) (xy 401.126649 -41.323313) (xy 401.077049 -41.297812) (xy 401.031691 -41.265361)
			(xy 400.991542 -41.226652) (xy 400.957456 -41.182509) (xy 400.93016 -41.133874) (xy 400.910237 -41.081783)
			(xy 400.898111 -41.027346) (xy 400.89404 -40.971724) (xy 393.039172 -40.971724) (xy 393.069999 -40.976156)
			(xy 393.122294 -40.991511) (xy 393.171871 -41.014153) (xy 393.217721 -41.043619) (xy 393.258912 -41.07931)
			(xy 393.294603 -41.120501) (xy 393.324069 -41.166351) (xy 393.346711 -41.215928) (xy 393.362066 -41.268223)
			(xy 393.369822 -41.322171) (xy 393.370308 -41.349422) (xy 393.369796 -41.378161) (xy 393.36117 -41.434989)
			(xy 393.344117 -41.48988) (xy 393.319023 -41.541591) (xy 393.286456 -41.588953) (xy 393.267184 -41.61028)
			(xy 393.26058 -41.617138) (xy 393.253468 -41.635172) (xy 393.253468 -41.724072) (xy 393.26058 -41.742106)
			(xy 393.267184 -41.748964) (xy 393.286476 -41.770272) (xy 393.31904 -41.817638) (xy 393.34413 -41.869353)
			(xy 393.361178 -41.924246) (xy 393.369798 -41.981076) (xy 393.369796 -42.038556) (xy 393.361171 -42.095385)
			(xy 393.344118 -42.150277) (xy 393.319024 -42.20199) (xy 393.286456 -42.249353) (xy 393.267184 -42.27068)
			(xy 393.26058 -42.277538) (xy 393.253468 -42.295572) (xy 393.253468 -42.384472) (xy 393.26058 -42.402506)
			(xy 393.267184 -42.409364) (xy 393.286469 -42.430679) (xy 393.319032 -42.478045) (xy 393.344122 -42.529759)
			(xy 393.361169 -42.584653) (xy 393.369789 -42.641482) (xy 393.370308 -42.670222) (xy 393.369853 -42.697593)
			(xy 393.362032 -42.751772) (xy 393.34654 -42.804275) (xy 393.325985 -42.849038) (xy 395.191994 -42.849038)
			(xy 395.196065 -42.793416) (xy 395.208191 -42.738979) (xy 395.228114 -42.686888) (xy 395.25541 -42.638253)
			(xy 395.289496 -42.59411) (xy 395.329645 -42.555401) (xy 395.375003 -42.52295) (xy 395.424603 -42.497449)
			(xy 395.477387 -42.479442) (xy 395.53223 -42.469312) (xy 395.587964 -42.467275) (xy 395.643401 -42.473375)
			(xy 395.697358 -42.487481) (xy 395.748687 -42.509293) (xy 395.796293 -42.538347) (xy 395.839161 -42.574022)
			(xy 395.876378 -42.615559) (xy 395.907151 -42.662072) (xy 395.930823 -42.712569) (xy 395.946891 -42.765976)
			(xy 395.955011 -42.821152) (xy 395.955372 -42.84091) (xy 401.23313 -42.84091) (xy 401.237201 -42.785288)
			(xy 401.249327 -42.730851) (xy 401.26925 -42.67876) (xy 401.296546 -42.630125) (xy 401.330632 -42.585982)
			(xy 401.370781 -42.547273) (xy 401.416139 -42.514822) (xy 401.465739 -42.489321) (xy 401.518523 -42.471314)
			(xy 401.573366 -42.461184) (xy 401.6291 -42.459147) (xy 401.684537 -42.465247) (xy 401.738494 -42.479353)
			(xy 401.789823 -42.501165) (xy 401.837429 -42.530219) (xy 401.880297 -42.565894) (xy 401.917514 -42.607431)
			(xy 401.948287 -42.653944) (xy 401.971959 -42.704441) (xy 401.988027 -42.757848) (xy 401.996147 -42.813024)
			(xy 401.996656 -42.84091) (xy 401.996147 -42.868796) (xy 401.988027 -42.923972) (xy 401.971959 -42.977379)
			(xy 401.948287 -43.027876) (xy 401.917514 -43.074389) (xy 401.880297 -43.115926) (xy 401.837429 -43.151601)
			(xy 401.789823 -43.180655) (xy 401.738494 -43.202467) (xy 401.684537 -43.216573) (xy 401.6291 -43.222673)
			(xy 401.573366 -43.220636) (xy 401.518523 -43.210506) (xy 401.465739 -43.192499) (xy 401.416139 -43.166998)
			(xy 401.370781 -43.134547) (xy 401.330632 -43.095838) (xy 401.296546 -43.051695) (xy 401.26925 -43.00306)
			(xy 401.249327 -42.950969) (xy 401.237201 -42.896532) (xy 401.23313 -42.84091) (xy 395.955372 -42.84091)
			(xy 395.95552 -42.849038) (xy 395.955011 -42.876924) (xy 395.946891 -42.9321) (xy 395.930823 -42.985507)
			(xy 395.907151 -43.036004) (xy 395.876378 -43.082517) (xy 395.839161 -43.124054) (xy 395.796293 -43.159729)
			(xy 395.748687 -43.188783) (xy 395.697358 -43.210595) (xy 395.643401 -43.224701) (xy 395.587964 -43.230801)
			(xy 395.53223 -43.228764) (xy 395.477387 -43.218634) (xy 395.424603 -43.200627) (xy 395.375003 -43.175126)
			(xy 395.329645 -43.142675) (xy 395.289496 -43.103966) (xy 395.25541 -43.059823) (xy 395.228114 -43.011188)
			(xy 395.208191 -42.959097) (xy 395.196065 -42.90466) (xy 395.191994 -42.849038) (xy 393.325985 -42.849038)
			(xy 393.323696 -42.854022) (xy 393.29397 -42.899988) (xy 393.276328 -42.92092) (xy 393.276074 -42.921174)
			(xy 393.270489 -42.928262) (xy 393.264242 -42.945178) (xy 393.263882 -42.954194) (xy 393.263882 -43.02125)
			(xy 393.264267 -43.030264) (xy 393.270495 -43.047181) (xy 393.276074 -43.05427) (xy 393.276328 -43.05427)
			(xy 393.276328 -43.054524) (xy 393.293949 -43.07547) (xy 393.323663 -43.12144) (xy 393.346502 -43.171184)
			(xy 393.361997 -43.223681) (xy 393.369831 -43.277854) (xy 393.370308 -43.305222) (xy 393.369822 -43.332473)
			(xy 393.362066 -43.386421) (xy 393.346711 -43.438716) (xy 393.324069 -43.488293) (xy 393.294603 -43.534143)
			(xy 393.258912 -43.575334) (xy 393.217721 -43.611025) (xy 393.171871 -43.640491) (xy 393.122294 -43.663133)
			(xy 393.069999 -43.678488) (xy 393.016051 -43.686244) (xy 392.961549 -43.686244) (xy 392.907601 -43.678488)
			(xy 392.855306 -43.663133) (xy 392.805729 -43.640491) (xy 392.759879 -43.611025) (xy 392.718688 -43.575334)
			(xy 392.682997 -43.534143) (xy 392.653531 -43.488293) (xy 392.630889 -43.438716) (xy 392.615534 -43.386421)
			(xy 392.607778 -43.332473) (xy 392.607292 -43.305222) (xy 387.124184 -43.305222) (xy 386.945608 -43.73626)
			(xy 394.513052 -43.73626) (xy 394.517123 -43.680638) (xy 394.529249 -43.626201) (xy 394.549172 -43.57411)
			(xy 394.576468 -43.525475) (xy 394.610554 -43.481332) (xy 394.650703 -43.442623) (xy 394.696061 -43.410172)
			(xy 394.745661 -43.384671) (xy 394.798445 -43.366664) (xy 394.853288 -43.356534) (xy 394.909022 -43.354497)
			(xy 394.964459 -43.360597) (xy 395.018416 -43.374703) (xy 395.069745 -43.396515) (xy 395.117351 -43.425569)
			(xy 395.160219 -43.461244) (xy 395.197436 -43.502781) (xy 395.228209 -43.549294) (xy 395.236435 -43.566842)
			(xy 397.633442 -43.566842) (xy 397.637513 -43.51122) (xy 397.649639 -43.456783) (xy 397.669562 -43.404692)
			(xy 397.696858 -43.356057) (xy 397.730944 -43.311914) (xy 397.771093 -43.273205) (xy 397.816451 -43.240754)
			(xy 397.866051 -43.215253) (xy 397.918835 -43.197246) (xy 397.973678 -43.187116) (xy 398.029412 -43.185079)
			(xy 398.084849 -43.191179) (xy 398.138806 -43.205285) (xy 398.190135 -43.227097) (xy 398.237741 -43.256151)
			(xy 398.280609 -43.291826) (xy 398.317826 -43.333363) (xy 398.348599 -43.379876) (xy 398.372271 -43.430373)
			(xy 398.388339 -43.48378) (xy 398.396459 -43.538956) (xy 398.396968 -43.566842) (xy 398.396459 -43.594728)
			(xy 398.388339 -43.649904) (xy 398.372271 -43.703311) (xy 398.348599 -43.753808) (xy 398.317826 -43.800321)
			(xy 398.280609 -43.841858) (xy 398.262522 -43.85691) (xy 399.019774 -43.85691) (xy 399.023845 -43.801288)
			(xy 399.035971 -43.746851) (xy 399.055894 -43.69476) (xy 399.08319 -43.646125) (xy 399.117276 -43.601982)
			(xy 399.157425 -43.563273) (xy 399.202783 -43.530822) (xy 399.252383 -43.505321) (xy 399.305167 -43.487314)
			(xy 399.36001 -43.477184) (xy 399.415744 -43.475147) (xy 399.471181 -43.481247) (xy 399.525138 -43.495353)
			(xy 399.576467 -43.517165) (xy 399.624073 -43.546219) (xy 399.666941 -43.581894) (xy 399.704158 -43.623431)
			(xy 399.734931 -43.669944) (xy 399.758603 -43.720441) (xy 399.774671 -43.773848) (xy 399.782791 -43.829024)
			(xy 399.7833 -43.85691) (xy 399.782791 -43.884796) (xy 399.774671 -43.939972) (xy 399.758603 -43.993379)
			(xy 399.734931 -44.043876) (xy 399.704158 -44.090389) (xy 399.666941 -44.131926) (xy 399.624073 -44.167601)
			(xy 399.576467 -44.196655) (xy 399.525138 -44.218467) (xy 399.471181 -44.232573) (xy 399.415744 -44.238673)
			(xy 399.36001 -44.236636) (xy 399.305167 -44.226506) (xy 399.252383 -44.208499) (xy 399.202783 -44.182998)
			(xy 399.157425 -44.150547) (xy 399.117276 -44.111838) (xy 399.08319 -44.067695) (xy 399.055894 -44.01906)
			(xy 399.035971 -43.966969) (xy 399.023845 -43.912532) (xy 399.019774 -43.85691) (xy 398.262522 -43.85691)
			(xy 398.237741 -43.877533) (xy 398.190135 -43.906587) (xy 398.138806 -43.928399) (xy 398.084849 -43.942505)
			(xy 398.029412 -43.948605) (xy 397.973678 -43.946568) (xy 397.918835 -43.936438) (xy 397.866051 -43.918431)
			(xy 397.816451 -43.89293) (xy 397.771093 -43.860479) (xy 397.730944 -43.82177) (xy 397.696858 -43.777627)
			(xy 397.669562 -43.728992) (xy 397.649639 -43.676901) (xy 397.637513 -43.622464) (xy 397.633442 -43.566842)
			(xy 395.236435 -43.566842) (xy 395.251881 -43.599791) (xy 395.267949 -43.653198) (xy 395.276069 -43.708374)
			(xy 395.276578 -43.73626) (xy 395.276069 -43.764146) (xy 395.267949 -43.819322) (xy 395.251881 -43.872729)
			(xy 395.228209 -43.923226) (xy 395.197436 -43.969739) (xy 395.160219 -44.011276) (xy 395.117351 -44.046951)
			(xy 395.069745 -44.076005) (xy 395.018416 -44.097817) (xy 394.964459 -44.111923) (xy 394.909022 -44.118023)
			(xy 394.853288 -44.115986) (xy 394.798445 -44.105856) (xy 394.745661 -44.087849) (xy 394.696061 -44.062348)
			(xy 394.650703 -44.029897) (xy 394.610554 -43.991188) (xy 394.576468 -43.947045) (xy 394.549172 -43.89841)
			(xy 394.529249 -43.846319) (xy 394.517123 -43.791882) (xy 394.513052 -43.73626) (xy 386.945608 -43.73626)
			(xy 386.827014 -44.022518) (xy 386.825217 -44.027205) (xy 386.823302 -44.037057) (xy 386.823204 -44.042076)
			(xy 386.823204 -45.114464) (xy 394.365478 -45.114464) (xy 394.369549 -45.058842) (xy 394.381675 -45.004405)
			(xy 394.401598 -44.952314) (xy 394.428894 -44.903679) (xy 394.46298 -44.859536) (xy 394.503129 -44.820827)
			(xy 394.548487 -44.788376) (xy 394.598087 -44.762875) (xy 394.650871 -44.744868) (xy 394.705714 -44.734738)
			(xy 394.761448 -44.732701) (xy 394.816885 -44.738801) (xy 394.870842 -44.752907) (xy 394.922171 -44.774719)
			(xy 394.969777 -44.803773) (xy 395.012645 -44.839448) (xy 395.042627 -44.87291) (xy 401.23313 -44.87291)
			(xy 401.237201 -44.817288) (xy 401.249327 -44.762851) (xy 401.26925 -44.71076) (xy 401.296546 -44.662125)
			(xy 401.330632 -44.617982) (xy 401.370781 -44.579273) (xy 401.416139 -44.546822) (xy 401.465739 -44.521321)
			(xy 401.518523 -44.503314) (xy 401.573366 -44.493184) (xy 401.6291 -44.491147) (xy 401.684537 -44.497247)
			(xy 401.738494 -44.511353) (xy 401.789823 -44.533165) (xy 401.837429 -44.562219) (xy 401.880297 -44.597894)
			(xy 401.917514 -44.639431) (xy 401.948287 -44.685944) (xy 401.971959 -44.736441) (xy 401.988027 -44.789848)
			(xy 401.996147 -44.845024) (xy 401.996656 -44.87291) (xy 401.996147 -44.900796) (xy 401.988027 -44.955972)
			(xy 401.971959 -45.009379) (xy 401.948287 -45.059876) (xy 401.917514 -45.106389) (xy 401.880297 -45.147926)
			(xy 401.837429 -45.183601) (xy 401.789823 -45.212655) (xy 401.738494 -45.234467) (xy 401.684537 -45.248573)
			(xy 401.6291 -45.254673) (xy 401.573366 -45.252636) (xy 401.518523 -45.242506) (xy 401.465739 -45.224499)
			(xy 401.416139 -45.198998) (xy 401.370781 -45.166547) (xy 401.330632 -45.127838) (xy 401.296546 -45.083695)
			(xy 401.26925 -45.03506) (xy 401.249327 -44.982969) (xy 401.237201 -44.928532) (xy 401.23313 -44.87291)
			(xy 395.042627 -44.87291) (xy 395.049862 -44.880985) (xy 395.080635 -44.927498) (xy 395.104307 -44.977995)
			(xy 395.120375 -45.031402) (xy 395.128495 -45.086578) (xy 395.129004 -45.114464) (xy 395.128495 -45.14235)
			(xy 395.120375 -45.197526) (xy 395.104307 -45.250933) (xy 395.080635 -45.30143) (xy 395.049862 -45.347943)
			(xy 395.04422 -45.35424) (xy 399.003772 -45.35424) (xy 399.007843 -45.298618) (xy 399.019969 -45.244181)
			(xy 399.039892 -45.19209) (xy 399.067188 -45.143455) (xy 399.101274 -45.099312) (xy 399.141423 -45.060603)
			(xy 399.186781 -45.028152) (xy 399.236381 -45.002651) (xy 399.289165 -44.984644) (xy 399.344008 -44.974514)
			(xy 399.399742 -44.972477) (xy 399.455179 -44.978577) (xy 399.509136 -44.992683) (xy 399.560465 -45.014495)
			(xy 399.608071 -45.043549) (xy 399.650939 -45.079224) (xy 399.688156 -45.120761) (xy 399.718929 -45.167274)
			(xy 399.742601 -45.217771) (xy 399.758669 -45.271178) (xy 399.766789 -45.326354) (xy 399.767298 -45.35424)
			(xy 399.766789 -45.382126) (xy 399.758669 -45.437302) (xy 399.742601 -45.490709) (xy 399.718929 -45.541206)
			(xy 399.688156 -45.587719) (xy 399.650939 -45.629256) (xy 399.608071 -45.664931) (xy 399.560465 -45.693985)
			(xy 399.509136 -45.715797) (xy 399.455179 -45.729903) (xy 399.399742 -45.736003) (xy 399.344008 -45.733966)
			(xy 399.289165 -45.723836) (xy 399.236381 -45.705829) (xy 399.186781 -45.680328) (xy 399.141423 -45.647877)
			(xy 399.101274 -45.609168) (xy 399.067188 -45.565025) (xy 399.039892 -45.51639) (xy 399.019969 -45.464299)
			(xy 399.007843 -45.409862) (xy 399.003772 -45.35424) (xy 395.04422 -45.35424) (xy 395.012645 -45.38948)
			(xy 394.969777 -45.425155) (xy 394.922171 -45.454209) (xy 394.870842 -45.476021) (xy 394.816885 -45.490127)
			(xy 394.761448 -45.496227) (xy 394.705714 -45.49419) (xy 394.650871 -45.48406) (xy 394.598087 -45.466053)
			(xy 394.548487 -45.440552) (xy 394.503129 -45.408101) (xy 394.46298 -45.369392) (xy 394.428894 -45.325249)
			(xy 394.401598 -45.276614) (xy 394.381675 -45.224523) (xy 394.369549 -45.170086) (xy 394.365478 -45.114464)
			(xy 386.823204 -45.114464) (xy 386.823204 -46.082204) (xy 392.35253 -46.082204) (xy 392.352959 -46.05495)
			(xy 392.360717 -46.000995) (xy 392.376074 -45.948695) (xy 392.398719 -45.899112) (xy 392.42819 -45.853257)
			(xy 392.463887 -45.812063) (xy 392.505084 -45.77637) (xy 392.550942 -45.746903) (xy 392.600526 -45.724262)
			(xy 392.652829 -45.708909) (xy 392.706783 -45.701157) (xy 392.734038 -45.700696) (xy 392.760942 -45.701129)
			(xy 392.814213 -45.708706) (xy 392.865892 -45.723691) (xy 392.914954 -45.745785) (xy 392.960426 -45.774552)
			(xy 393.001406 -45.809421) (xy 393.037083 -45.8497) (xy 393.0523 -45.871892) (xy 393.059412 -45.882814)
			(xy 393.082272 -45.894752) (xy 393.19454 -45.89272) (xy 393.216892 -45.879766) (xy 393.22375 -45.86859)
			(xy 393.238651 -45.844975) (xy 393.274333 -45.802023) (xy 393.315895 -45.764731) (xy 393.362449 -45.733895)
			(xy 393.413 -45.710174) (xy 393.466468 -45.694074) (xy 393.521712 -45.68594) (xy 393.549632 -45.685456)
			(xy 393.576626 -45.685899) (xy 393.630075 -45.693509) (xy 393.681919 -45.708574) (xy 393.731123 -45.730792)
			(xy 393.776706 -45.75972) (xy 393.797536 -45.776896) (xy 393.805664 -45.784008) (xy 393.826238 -45.790104)
			(xy 393.911582 -45.779182) (xy 393.922127 -45.777409) (xy 393.94041 -45.766354) (xy 393.946888 -45.757846)
			(xy 393.962255 -45.736626) (xy 393.99784 -45.698173) (xy 394.038355 -45.664953) (xy 394.083035 -45.637594)
			(xy 394.131041 -45.616608) (xy 394.181468 -45.602393) (xy 394.233366 -45.595215) (xy 394.259562 -45.594778)
			(xy 394.286816 -45.595267) (xy 394.340769 -45.603019) (xy 394.393069 -45.618371) (xy 394.442652 -45.641011)
			(xy 394.488508 -45.670477) (xy 394.529704 -45.706169) (xy 394.565401 -45.747361) (xy 394.594871 -45.793214)
			(xy 394.617516 -45.842795) (xy 394.632873 -45.895094) (xy 394.640631 -45.949046) (xy 394.640631 -46.003554)
			(xy 394.632873 -46.057506) (xy 394.617516 -46.109805) (xy 394.594871 -46.159386) (xy 394.565401 -46.205239)
			(xy 394.529704 -46.246431) (xy 394.488508 -46.282123) (xy 394.442652 -46.311589) (xy 394.393069 -46.334229)
			(xy 394.340769 -46.349581) (xy 394.286816 -46.357333) (xy 394.259562 -46.357794) (xy 394.232568 -46.357343)
			(xy 394.17912 -46.349733) (xy 394.127277 -46.33467) (xy 394.078073 -46.312454) (xy 394.032489 -46.283528)
			(xy 394.011658 -46.266354) (xy 394.00353 -46.259242) (xy 393.982956 -46.253146) (xy 393.897612 -46.264068)
			(xy 393.887071 -46.265856) (xy 393.868788 -46.276902) (xy 393.862306 -46.285404) (xy 393.844689 -46.309701)
			(xy 393.803096 -46.352963) (xy 393.779502 -46.37151) (xy 393.771628 -46.377352) (xy 393.761214 -46.394878)
			(xy 393.748006 -46.485302) (xy 393.752832 -46.504606) (xy 393.758674 -46.51248) (xy 393.758674 -46.512734)
			(xy 393.776177 -46.537478) (xy 393.80398 -46.591331) (xy 393.822916 -46.648903) (xy 393.830119 -46.693836)
			(xy 398.976342 -46.693836) (xy 398.976828 -46.666585) (xy 398.984584 -46.612637) (xy 398.999939 -46.560342)
			(xy 399.022581 -46.510765) (xy 399.052047 -46.464915) (xy 399.087738 -46.423724) (xy 399.128929 -46.388033)
			(xy 399.174779 -46.358567) (xy 399.224356 -46.335925) (xy 399.276651 -46.32057) (xy 399.330599 -46.312814)
			(xy 399.385101 -46.312814) (xy 399.439049 -46.32057) (xy 399.491344 -46.335925) (xy 399.540921 -46.358567)
			(xy 399.586771 -46.388033) (xy 399.627962 -46.423724) (xy 399.663653 -46.464915) (xy 399.693119 -46.510765)
			(xy 399.715761 -46.560342) (xy 399.731116 -46.612637) (xy 399.738872 -46.666585) (xy 399.739358 -46.693836)
			(xy 399.738891 -46.720264) (xy 399.731581 -46.772612) (xy 399.717106 -46.823447) (xy 399.695744 -46.871793)
			(xy 399.682208 -46.894496) (xy 399.681954 -46.89475) (xy 399.676617 -46.904768) (xy 399.67436 -46.927318)
			(xy 399.677636 -46.938184) (xy 399.703798 -47.01286) (xy 399.708161 -47.023386) (xy 399.724264 -47.03947)
			(xy 399.734786 -47.043848) (xy 399.73504 -47.043848) (xy 399.759547 -47.052921) (xy 399.806 -47.076863)
			(xy 399.848752 -47.106918) (xy 399.887004 -47.142525) (xy 399.920041 -47.183017) (xy 399.947245 -47.227638)
			(xy 399.968107 -47.275553) (xy 399.982237 -47.325866) (xy 399.989371 -47.377636) (xy 399.989802 -47.403766)
			(xy 399.989316 -47.431017) (xy 399.987793 -47.441612) (xy 401.261832 -47.441612) (xy 401.265903 -47.38599)
			(xy 401.278029 -47.331553) (xy 401.297952 -47.279462) (xy 401.325248 -47.230827) (xy 401.359334 -47.186684)
			(xy 401.399483 -47.147975) (xy 401.444841 -47.115524) (xy 401.494441 -47.090023) (xy 401.547225 -47.072016)
			(xy 401.602068 -47.061886) (xy 401.657802 -47.059849) (xy 401.713239 -47.065949) (xy 401.767196 -47.080055)
			(xy 401.818525 -47.101867) (xy 401.866131 -47.130921) (xy 401.908999 -47.166596) (xy 401.946216 -47.208133)
			(xy 401.976989 -47.254646) (xy 402.000661 -47.305143) (xy 402.016729 -47.35855) (xy 402.024849 -47.413726)
			(xy 402.025358 -47.441612) (xy 402.024849 -47.469498) (xy 402.016729 -47.524674) (xy 402.000661 -47.578081)
			(xy 401.976989 -47.628578) (xy 401.946216 -47.675091) (xy 401.908999 -47.716628) (xy 401.866131 -47.752303)
			(xy 401.818525 -47.781357) (xy 401.767196 -47.803169) (xy 401.713239 -47.817275) (xy 401.657802 -47.823375)
			(xy 401.602068 -47.821338) (xy 401.547225 -47.811208) (xy 401.494441 -47.793201) (xy 401.444841 -47.7677)
			(xy 401.399483 -47.735249) (xy 401.359334 -47.69654) (xy 401.325248 -47.652397) (xy 401.297952 -47.603762)
			(xy 401.278029 -47.551671) (xy 401.265903 -47.497234) (xy 401.261832 -47.441612) (xy 399.987793 -47.441612)
			(xy 399.98156 -47.484965) (xy 399.966205 -47.53726) (xy 399.943563 -47.586837) (xy 399.914097 -47.632687)
			(xy 399.878406 -47.673878) (xy 399.837215 -47.709569) (xy 399.791365 -47.739035) (xy 399.741788 -47.761677)
			(xy 399.689493 -47.777032) (xy 399.635545 -47.784788) (xy 399.581043 -47.784788) (xy 399.527095 -47.777032)
			(xy 399.4748 -47.761677) (xy 399.425223 -47.739035) (xy 399.379373 -47.709569) (xy 399.338182 -47.673878)
			(xy 399.302491 -47.632687) (xy 399.273025 -47.586837) (xy 399.250383 -47.53726) (xy 399.235028 -47.484965)
			(xy 399.227272 -47.431017) (xy 399.226786 -47.403766) (xy 399.227262 -47.377339) (xy 399.23457 -47.324991)
			(xy 399.249043 -47.274156) (xy 399.270402 -47.225809) (xy 399.283936 -47.203106) (xy 399.28419 -47.202852)
			(xy 399.289525 -47.192834) (xy 399.291782 -47.170284) (xy 399.288508 -47.159418) (xy 399.262346 -47.084742)
			(xy 399.257962 -47.074227) (xy 399.241873 -47.058138) (xy 399.231358 -47.053754) (xy 399.231104 -47.053754)
			(xy 399.206585 -47.044711) (xy 399.160134 -47.020763) (xy 399.117384 -46.990702) (xy 399.079133 -46.955091)
			(xy 399.046099 -46.914595) (xy 399.018897 -46.869971) (xy 398.998036 -46.822054) (xy 398.983907 -46.771739)
			(xy 398.976773 -46.719967) (xy 398.976342 -46.693836) (xy 393.830119 -46.693836) (xy 393.832509 -46.708745)
			(xy 393.833096 -46.739048) (xy 393.832667 -46.766301) (xy 393.824903 -46.820251) (xy 393.809542 -46.872548)
			(xy 393.786894 -46.922126) (xy 393.757422 -46.967977) (xy 393.721724 -47.009167) (xy 393.680529 -47.044858)
			(xy 393.634673 -47.074323) (xy 393.585092 -47.096963) (xy 393.532793 -47.112316) (xy 393.478841 -47.120071)
			(xy 393.451588 -47.120556) (xy 393.425554 -47.120109) (xy 393.373972 -47.113021) (xy 393.32383 -47.098991)
			(xy 393.276059 -47.07828) (xy 393.231544 -47.051272) (xy 393.21105 -47.035212) (xy 393.203285 -47.029483)
			(xy 393.184881 -47.023734) (xy 393.175236 -47.024036) (xy 393.09548 -47.030386) (xy 393.0777 -47.039022)
			(xy 393.07135 -47.046388) (xy 393.053167 -47.066032) (xy 393.01226 -47.100554) (xy 392.966931 -47.129023)
			(xy 392.91807 -47.150881) (xy 392.866635 -47.165699) (xy 392.813634 -47.173186) (xy 392.78687 -47.173642)
			(xy 392.75962 -47.17315) (xy 392.705674 -47.16539) (xy 392.653381 -47.150033) (xy 392.603806 -47.127391)
			(xy 392.557958 -47.097925) (xy 392.516769 -47.062234) (xy 392.481078 -47.021046) (xy 392.451611 -46.975197)
			(xy 392.428968 -46.925622) (xy 392.41361 -46.87333) (xy 392.40585 -46.819384) (xy 392.405362 -46.792134)
			(xy 392.405897 -46.76336) (xy 392.414547 -46.706467) (xy 392.431641 -46.651517) (xy 392.456792 -46.599757)
			(xy 392.48943 -46.55236) (xy 392.50874 -46.531022) (xy 392.516106 -46.523148) (xy 392.523218 -46.503336)
			(xy 392.515852 -46.40707) (xy 392.505946 -46.388274) (xy 392.497564 -46.38167) (xy 392.475388 -46.363434)
			(xy 392.436176 -46.321503) (xy 392.403688 -46.27417) (xy 392.378657 -46.222504) (xy 392.36165 -46.167671)
			(xy 392.353048 -46.110909) (xy 392.35253 -46.082204) (xy 386.823204 -46.082204) (xy 386.823204 -48.30699)
			(xy 398.853912 -48.30699) (xy 398.857983 -48.251368) (xy 398.870109 -48.196931) (xy 398.890032 -48.14484)
			(xy 398.917328 -48.096205) (xy 398.951414 -48.052062) (xy 398.991563 -48.013353) (xy 399.036921 -47.980902)
			(xy 399.086521 -47.955401) (xy 399.139305 -47.937394) (xy 399.194148 -47.927264) (xy 399.249882 -47.925227)
			(xy 399.305319 -47.931327) (xy 399.359276 -47.945433) (xy 399.410605 -47.967245) (xy 399.458211 -47.996299)
			(xy 399.501079 -48.031974) (xy 399.538296 -48.073511) (xy 399.569069 -48.120024) (xy 399.592741 -48.170521)
			(xy 399.608809 -48.223928) (xy 399.616929 -48.279104) (xy 399.617438 -48.30699) (xy 399.616929 -48.334876)
			(xy 399.608809 -48.390052) (xy 399.592741 -48.443459) (xy 399.569069 -48.493956) (xy 399.538296 -48.540469)
			(xy 399.501079 -48.582006) (xy 399.458211 -48.617681) (xy 399.410605 -48.646735) (xy 399.359276 -48.668547)
			(xy 399.305319 -48.682653) (xy 399.249882 -48.688753) (xy 399.194148 -48.686716) (xy 399.139305 -48.676586)
			(xy 399.086521 -48.658579) (xy 399.036921 -48.633078) (xy 398.991563 -48.600627) (xy 398.951414 -48.561918)
			(xy 398.917328 -48.517775) (xy 398.890032 -48.46914) (xy 398.870109 -48.417049) (xy 398.857983 -48.362612)
			(xy 398.853912 -48.30699) (xy 386.823204 -48.30699) (xy 386.823204 -48.753014) (xy 395.468346 -48.753014)
			(xy 395.472417 -48.697392) (xy 395.484543 -48.642955) (xy 395.504466 -48.590864) (xy 395.531762 -48.542229)
			(xy 395.565848 -48.498086) (xy 395.605997 -48.459377) (xy 395.651355 -48.426926) (xy 395.700955 -48.401425)
			(xy 395.753739 -48.383418) (xy 395.808582 -48.373288) (xy 395.864316 -48.371251) (xy 395.919753 -48.377351)
			(xy 395.97371 -48.391457) (xy 396.025039 -48.413269) (xy 396.072645 -48.442323) (xy 396.115513 -48.477998)
			(xy 396.15273 -48.519535) (xy 396.183503 -48.566048) (xy 396.207175 -48.616545) (xy 396.223243 -48.669952)
			(xy 396.231363 -48.725128) (xy 396.231872 -48.753014) (xy 396.231363 -48.7809) (xy 396.223243 -48.836076)
			(xy 396.207175 -48.889483) (xy 396.205779 -48.89246) (xy 397.514062 -48.89246) (xy 397.518133 -48.836838)
			(xy 397.530259 -48.782401) (xy 397.550182 -48.73031) (xy 397.577478 -48.681675) (xy 397.611564 -48.637532)
			(xy 397.651713 -48.598823) (xy 397.697071 -48.566372) (xy 397.746671 -48.540871) (xy 397.799455 -48.522864)
			(xy 397.854298 -48.512734) (xy 397.910032 -48.510697) (xy 397.965469 -48.516797) (xy 398.019426 -48.530903)
			(xy 398.070755 -48.552715) (xy 398.118361 -48.581769) (xy 398.161229 -48.617444) (xy 398.198446 -48.658981)
			(xy 398.229219 -48.705494) (xy 398.252891 -48.755991) (xy 398.268959 -48.809398) (xy 398.277079 -48.864574)
			(xy 398.277588 -48.89246) (xy 398.277079 -48.920346) (xy 398.274641 -48.93691) (xy 401.23313 -48.93691)
			(xy 401.237201 -48.881288) (xy 401.249327 -48.826851) (xy 401.26925 -48.77476) (xy 401.296546 -48.726125)
			(xy 401.330632 -48.681982) (xy 401.370781 -48.643273) (xy 401.416139 -48.610822) (xy 401.465739 -48.585321)
			(xy 401.518523 -48.567314) (xy 401.573366 -48.557184) (xy 401.6291 -48.555147) (xy 401.684537 -48.561247)
			(xy 401.738494 -48.575353) (xy 401.789823 -48.597165) (xy 401.837429 -48.626219) (xy 401.880297 -48.661894)
			(xy 401.917514 -48.703431) (xy 401.948287 -48.749944) (xy 401.971959 -48.800441) (xy 401.988027 -48.853848)
			(xy 401.996147 -48.909024) (xy 401.996656 -48.93691) (xy 401.996147 -48.964796) (xy 401.988027 -49.019972)
			(xy 401.971959 -49.073379) (xy 401.948287 -49.123876) (xy 401.917514 -49.170389) (xy 401.880297 -49.211926)
			(xy 401.837429 -49.247601) (xy 401.789823 -49.276655) (xy 401.738494 -49.298467) (xy 401.684537 -49.312573)
			(xy 401.6291 -49.318673) (xy 401.573366 -49.316636) (xy 401.518523 -49.306506) (xy 401.465739 -49.288499)
			(xy 401.416139 -49.262998) (xy 401.370781 -49.230547) (xy 401.330632 -49.191838) (xy 401.296546 -49.147695)
			(xy 401.26925 -49.09906) (xy 401.249327 -49.046969) (xy 401.237201 -48.992532) (xy 401.23313 -48.93691)
			(xy 398.274641 -48.93691) (xy 398.268959 -48.975522) (xy 398.252891 -49.028929) (xy 398.229219 -49.079426)
			(xy 398.198446 -49.125939) (xy 398.161229 -49.167476) (xy 398.118361 -49.203151) (xy 398.070755 -49.232205)
			(xy 398.019426 -49.254017) (xy 397.965469 -49.268123) (xy 397.910032 -49.274223) (xy 397.854298 -49.272186)
			(xy 397.799455 -49.262056) (xy 397.746671 -49.244049) (xy 397.697071 -49.218548) (xy 397.651713 -49.186097)
			(xy 397.611564 -49.147388) (xy 397.577478 -49.103245) (xy 397.550182 -49.05461) (xy 397.530259 -49.002519)
			(xy 397.518133 -48.948082) (xy 397.514062 -48.89246) (xy 396.205779 -48.89246) (xy 396.183503 -48.93998)
			(xy 396.15273 -48.986493) (xy 396.115513 -49.02803) (xy 396.072645 -49.063705) (xy 396.025039 -49.092759)
			(xy 395.97371 -49.114571) (xy 395.919753 -49.128677) (xy 395.864316 -49.134777) (xy 395.808582 -49.13274)
			(xy 395.753739 -49.12261) (xy 395.700955 -49.104603) (xy 395.651355 -49.079102) (xy 395.605997 -49.046651)
			(xy 395.565848 -49.007942) (xy 395.531762 -48.963799) (xy 395.504466 -48.915164) (xy 395.484543 -48.863073)
			(xy 395.472417 -48.808636) (xy 395.468346 -48.753014) (xy 386.823204 -48.753014) (xy 386.823204 -49.95291)
			(xy 401.23313 -49.95291) (xy 401.237201 -49.897288) (xy 401.249327 -49.842851) (xy 401.26925 -49.79076)
			(xy 401.296546 -49.742125) (xy 401.330632 -49.697982) (xy 401.370781 -49.659273) (xy 401.416139 -49.626822)
			(xy 401.465739 -49.601321) (xy 401.518523 -49.583314) (xy 401.573366 -49.573184) (xy 401.6291 -49.571147)
			(xy 401.684537 -49.577247) (xy 401.738494 -49.591353) (xy 401.763429 -49.601949) (xy 406.412982 -49.601949)
			(xy 406.412982 -49.547451) (xy 406.420737 -49.493508) (xy 406.43609 -49.441217) (xy 406.458727 -49.391644)
			(xy 406.488189 -49.345796) (xy 406.523875 -49.304608) (xy 406.565059 -49.268916) (xy 406.610903 -49.239449)
			(xy 406.660474 -49.216806) (xy 406.712763 -49.201447) (xy 406.766705 -49.193685) (xy 406.793954 -49.193196)
			(xy 406.821323 -49.19369) (xy 406.875501 -49.201501) (xy 406.928004 -49.216984) (xy 406.977751 -49.239819)
			(xy 407.023719 -49.269538) (xy 407.044652 -49.287176) (xy 407.044906 -49.28743) (xy 407.051984 -49.293029)
			(xy 407.068908 -49.299267) (xy 407.077926 -49.299622) (xy 407.144982 -49.299622) (xy 407.153997 -49.299252)
			(xy 407.170914 -49.293013) (xy 407.178002 -49.28743) (xy 407.178002 -49.287176) (xy 407.178256 -49.287176)
			(xy 407.199189 -49.269535) (xy 407.245157 -49.239811) (xy 407.294903 -49.216965) (xy 407.347405 -49.201469)
			(xy 407.401583 -49.19364) (xy 407.456325 -49.19364) (xy 407.510503 -49.201469) (xy 407.563005 -49.216965)
			(xy 407.612751 -49.239811) (xy 407.658719 -49.269535) (xy 407.679652 -49.287176) (xy 407.679906 -49.28743)
			(xy 407.686984 -49.293029) (xy 407.703908 -49.299267) (xy 407.712926 -49.299622) (xy 407.779982 -49.299622)
			(xy 407.788997 -49.299252) (xy 407.805914 -49.293013) (xy 407.813002 -49.28743) (xy 407.813002 -49.287176)
			(xy 407.813256 -49.287176) (xy 407.834189 -49.269535) (xy 407.880157 -49.239811) (xy 407.929903 -49.216965)
			(xy 407.982405 -49.201469) (xy 408.036583 -49.19364) (xy 408.091325 -49.19364) (xy 408.145503 -49.201469)
			(xy 408.198005 -49.216965) (xy 408.247751 -49.239811) (xy 408.293719 -49.269535) (xy 408.314652 -49.287176)
			(xy 408.314906 -49.28743) (xy 408.321984 -49.293029) (xy 408.338908 -49.299267) (xy 408.347926 -49.299622)
			(xy 408.414982 -49.299622) (xy 408.423997 -49.299252) (xy 408.440914 -49.293013) (xy 408.448002 -49.28743)
			(xy 408.448002 -49.287176) (xy 408.448256 -49.287176) (xy 408.469191 -49.26954) (xy 408.515163 -49.239829)
			(xy 408.56491 -49.216993) (xy 408.61741 -49.201501) (xy 408.671585 -49.193671) (xy 408.698954 -49.193196)
			(xy 408.726209 -49.193648) (xy 408.780166 -49.2014) (xy 408.83247 -49.216752) (xy 408.882056 -49.239392)
			(xy 408.927915 -49.268859) (xy 408.969114 -49.304553) (xy 409.004813 -49.345748) (xy 409.034286 -49.391603)
			(xy 409.056932 -49.441187) (xy 409.07229 -49.493489) (xy 409.080049 -49.547445) (xy 409.080049 -49.601955)
			(xy 409.07229 -49.655911) (xy 409.056932 -49.708213) (xy 409.034286 -49.757797) (xy 409.004813 -49.803652)
			(xy 408.969114 -49.844847) (xy 408.927915 -49.880541) (xy 408.882056 -49.910008) (xy 408.83247 -49.932648)
			(xy 408.780166 -49.948) (xy 408.726209 -49.955752) (xy 408.698954 -49.956212) (xy 408.671585 -49.955711)
			(xy 408.617408 -49.947901) (xy 408.564905 -49.93242) (xy 408.515158 -49.909586) (xy 408.469189 -49.87987)
			(xy 408.448256 -49.862232) (xy 408.448002 -49.861978) (xy 408.440921 -49.856384) (xy 408.424 -49.850142)
			(xy 408.414982 -49.849786) (xy 408.347926 -49.849786) (xy 408.338911 -49.850158) (xy 408.321994 -49.856396)
			(xy 408.314906 -49.861978) (xy 408.314652 -49.862232) (xy 408.293719 -49.879873) (xy 408.247751 -49.909597)
			(xy 408.198005 -49.932443) (xy 408.145503 -49.947939) (xy 408.091325 -49.955768) (xy 408.036583 -49.955768)
			(xy 407.982405 -49.947939) (xy 407.929903 -49.932443) (xy 407.880157 -49.909597) (xy 407.834189 -49.879873)
			(xy 407.813256 -49.862232) (xy 407.813002 -49.861978) (xy 407.805921 -49.856384) (xy 407.789 -49.850142)
			(xy 407.779982 -49.849786) (xy 407.712926 -49.849786) (xy 407.703911 -49.850158) (xy 407.686994 -49.856396)
			(xy 407.679906 -49.861978) (xy 407.679906 -49.862232) (xy 407.679652 -49.862232) (xy 407.658719 -49.879873)
			(xy 407.612751 -49.909597) (xy 407.563005 -49.932443) (xy 407.510503 -49.947939) (xy 407.456325 -49.955768)
			(xy 407.401583 -49.955768) (xy 407.347405 -49.947939) (xy 407.294903 -49.932443) (xy 407.245157 -49.909597)
			(xy 407.199189 -49.879873) (xy 407.178256 -49.862232) (xy 407.178002 -49.861978) (xy 407.170921 -49.856384)
			(xy 407.154 -49.850142) (xy 407.144982 -49.849786) (xy 407.077926 -49.849786) (xy 407.068911 -49.850158)
			(xy 407.051994 -49.856396) (xy 407.044906 -49.861978) (xy 407.044906 -49.862232) (xy 407.044652 -49.862232)
			(xy 407.023715 -49.879865) (xy 406.977743 -49.909577) (xy 406.927997 -49.932413) (xy 406.875497 -49.947906)
			(xy 406.821323 -49.955736) (xy 406.793954 -49.956212) (xy 406.766705 -49.955715) (xy 406.712763 -49.947953)
			(xy 406.660474 -49.932594) (xy 406.610903 -49.909951) (xy 406.565059 -49.880484) (xy 406.523875 -49.844792)
			(xy 406.488189 -49.803604) (xy 406.458727 -49.757756) (xy 406.43609 -49.708183) (xy 406.420737 -49.655892)
			(xy 406.412982 -49.601949) (xy 401.763429 -49.601949) (xy 401.789823 -49.613165) (xy 401.837429 -49.642219)
			(xy 401.880297 -49.677894) (xy 401.917514 -49.719431) (xy 401.948287 -49.765944) (xy 401.971959 -49.816441)
			(xy 401.988027 -49.869848) (xy 401.996147 -49.925024) (xy 401.996656 -49.95291) (xy 401.996147 -49.980796)
			(xy 401.988027 -50.035972) (xy 401.971959 -50.089379) (xy 401.948287 -50.139876) (xy 401.917514 -50.186389)
			(xy 401.880297 -50.227926) (xy 401.837429 -50.263601) (xy 401.789823 -50.292655) (xy 401.738494 -50.314467)
			(xy 401.684537 -50.328573) (xy 401.6291 -50.334673) (xy 401.573366 -50.332636) (xy 401.518523 -50.322506)
			(xy 401.465739 -50.304499) (xy 401.416139 -50.278998) (xy 401.370781 -50.246547) (xy 401.330632 -50.207838)
			(xy 401.296546 -50.163695) (xy 401.26925 -50.11506) (xy 401.249327 -50.062969) (xy 401.237201 -50.008532)
			(xy 401.23313 -49.95291) (xy 386.823204 -49.95291) (xy 386.823204 -51.019456) (xy 399.049492 -51.019456)
			(xy 399.053563 -50.963834) (xy 399.065689 -50.909397) (xy 399.085612 -50.857306) (xy 399.112908 -50.808671)
			(xy 399.146994 -50.764528) (xy 399.187143 -50.725819) (xy 399.232501 -50.693368) (xy 399.282101 -50.667867)
			(xy 399.334885 -50.64986) (xy 399.389728 -50.63973) (xy 399.445462 -50.637693) (xy 399.500899 -50.643793)
			(xy 399.554856 -50.657899) (xy 399.606185 -50.679711) (xy 399.653791 -50.708765) (xy 399.696659 -50.74444)
			(xy 399.733876 -50.785977) (xy 399.764649 -50.83249) (xy 399.788321 -50.882987) (xy 399.804389 -50.936394)
			(xy 399.812509 -50.99157) (xy 399.813018 -51.019456) (xy 399.812509 -51.047342) (xy 399.804389 -51.102518)
			(xy 399.788321 -51.155925) (xy 399.764649 -51.206422) (xy 399.739793 -51.243992) (xy 407.433018 -51.243992)
			(xy 407.433475 -51.216621) (xy 407.441294 -51.162442) (xy 407.456785 -51.109938) (xy 407.479629 -51.060192)
			(xy 407.509356 -51.014225) (xy 407.526998 -50.993294) (xy 407.527252 -50.99304) (xy 407.532834 -50.985951)
			(xy 407.539082 -50.969036) (xy 407.539444 -50.96002) (xy 407.539444 -50.892964) (xy 407.539117 -50.883944)
			(xy 407.53285 -50.867026) (xy 407.527252 -50.859944) (xy 407.526998 -50.859944) (xy 407.526998 -50.85969)
			(xy 407.50934 -50.838773) (xy 407.479631 -50.792796) (xy 407.456799 -50.743045) (xy 407.441312 -50.690541)
			(xy 407.433489 -50.636362) (xy 407.433018 -50.608992) (xy 407.433448 -50.581738) (xy 407.441207 -50.527784)
			(xy 407.456565 -50.475484) (xy 407.47921 -50.425902) (xy 407.508682 -50.380048) (xy 407.544379 -50.338855)
			(xy 407.585575 -50.303161) (xy 407.631432 -50.273694) (xy 407.681016 -50.251053) (xy 407.733318 -50.235699)
			(xy 407.787272 -50.227946) (xy 407.814526 -50.227484) (xy 407.843443 -50.228024) (xy 407.900614 -50.236744)
			(xy 407.955814 -50.253995) (xy 408.007776 -50.279383) (xy 408.055311 -50.312324) (xy 408.097326 -50.352065)
			(xy 408.115516 -50.37455) (xy 408.123117 -50.383363) (xy 408.144023 -50.393542) (xy 408.155648 -50.394108)
			(xy 408.235404 -50.394108) (xy 408.247034 -50.393554) (xy 408.267943 -50.383375) (xy 408.275536 -50.37455)
			(xy 408.293694 -50.352039) (xy 408.335722 -50.312308) (xy 408.383264 -50.279373) (xy 408.435232 -50.25399)
			(xy 408.490435 -50.236739) (xy 408.547608 -50.228016) (xy 408.576526 -50.227484) (xy 408.603778 -50.227954)
			(xy 408.657725 -50.235713) (xy 408.71002 -50.251071) (xy 408.759597 -50.273715) (xy 408.805447 -50.303183)
			(xy 408.846636 -50.338876) (xy 408.882328 -50.380068) (xy 408.911794 -50.425919) (xy 408.934435 -50.475497)
			(xy 408.94979 -50.527792) (xy 408.957548 -50.58174) (xy 408.958034 -50.608992) (xy 408.95755 -50.635305)
			(xy 408.950317 -50.687433) (xy 408.936001 -50.738075) (xy 408.914871 -50.786273) (xy 408.887329 -50.831117)
			(xy 408.853894 -50.871758) (xy 408.834844 -50.889916) (xy 408.82744 -50.897436) (xy 408.818916 -50.916717)
			(xy 408.818334 -50.927254) (xy 408.818334 -51.00193) (xy 408.818877 -51.012478) (xy 408.827401 -51.031774)
			(xy 408.834844 -51.039268) (xy 408.853934 -51.057389) (xy 408.887386 -51.098027) (xy 408.91494 -51.142875)
			(xy 408.936072 -51.191082) (xy 408.950382 -51.241735) (xy 408.957599 -51.293874) (xy 408.958034 -51.320192)
			(xy 408.957515 -51.347442) (xy 408.94976 -51.401387) (xy 408.934407 -51.45368) (xy 408.911769 -51.503255)
			(xy 408.882306 -51.549104) (xy 408.846618 -51.590294) (xy 408.805432 -51.625986) (xy 408.759585 -51.655453)
			(xy 408.710012 -51.678095) (xy 408.65772 -51.693453) (xy 408.603776 -51.701212) (xy 408.576526 -51.7017)
			(xy 408.548862 -51.701167) (xy 408.494113 -51.693172) (xy 408.441092 -51.677358) (xy 408.390908 -51.654059)
			(xy 408.344612 -51.623761) (xy 408.303174 -51.587098) (xy 408.26746 -51.54484) (xy 408.252422 -51.521614)
			(xy 408.245785 -51.511938) (xy 408.225924 -51.499495) (xy 408.214322 -51.497738) (xy 408.134312 -51.489864)
			(xy 408.122674 -51.489243) (xy 408.100837 -51.497315) (xy 408.092402 -51.505358) (xy 408.092148 -51.505612)
			(xy 408.074077 -51.524203) (xy 408.033742 -51.55678) (xy 407.989366 -51.583591) (xy 407.941766 -51.604142)
			(xy 407.89182 -51.618054) (xy 407.84045 -51.625069) (xy 407.814526 -51.6255) (xy 407.787273 -51.62502)
			(xy 407.733323 -51.617267) (xy 407.681025 -51.601914) (xy 407.631444 -51.579274) (xy 407.58559 -51.549808)
			(xy 407.544397 -51.514116) (xy 407.508703 -51.472924) (xy 407.479235 -51.427072) (xy 407.456593 -51.377492)
			(xy 407.441237 -51.325195) (xy 407.433481 -51.271245) (xy 407.433018 -51.243992) (xy 399.739793 -51.243992)
			(xy 399.733876 -51.252935) (xy 399.696659 -51.294472) (xy 399.653791 -51.330147) (xy 399.606185 -51.359201)
			(xy 399.554856 -51.381013) (xy 399.500899 -51.395119) (xy 399.445462 -51.401219) (xy 399.389728 -51.399182)
			(xy 399.334885 -51.389052) (xy 399.282101 -51.371045) (xy 399.232501 -51.345544) (xy 399.187143 -51.313093)
			(xy 399.146994 -51.274384) (xy 399.112908 -51.230241) (xy 399.085612 -51.181606) (xy 399.065689 -51.129515)
			(xy 399.053563 -51.075078) (xy 399.049492 -51.019456) (xy 386.823204 -51.019456) (xy 386.823204 -52.035456)
			(xy 401.241258 -52.035456) (xy 401.245329 -51.979834) (xy 401.257455 -51.925397) (xy 401.277378 -51.873306)
			(xy 401.304674 -51.824671) (xy 401.33876 -51.780528) (xy 401.378909 -51.741819) (xy 401.424267 -51.709368)
			(xy 401.473867 -51.683867) (xy 401.526651 -51.66586) (xy 401.581494 -51.65573) (xy 401.637228 -51.653693)
			(xy 401.692665 -51.659793) (xy 401.746622 -51.673899) (xy 401.797951 -51.695711) (xy 401.845557 -51.724765)
			(xy 401.888425 -51.76044) (xy 401.925642 -51.801977) (xy 401.956415 -51.84849) (xy 401.980087 -51.898987)
			(xy 401.996155 -51.952394) (xy 402.004275 -52.00757) (xy 402.004784 -52.035456) (xy 402.004275 -52.063342)
			(xy 401.996155 -52.118518) (xy 401.980087 -52.171925) (xy 401.956415 -52.222422) (xy 401.925642 -52.268935)
			(xy 401.888425 -52.310472) (xy 401.845557 -52.346147) (xy 401.797951 -52.375201) (xy 401.746622 -52.397013)
			(xy 401.692665 -52.411119) (xy 401.637228 -52.417219) (xy 401.581494 -52.415182) (xy 401.526651 -52.405052)
			(xy 401.473867 -52.387045) (xy 401.424267 -52.361544) (xy 401.378909 -52.329093) (xy 401.33876 -52.290384)
			(xy 401.304674 -52.246241) (xy 401.277378 -52.197606) (xy 401.257455 -52.145515) (xy 401.245329 -52.091078)
			(xy 401.241258 -52.035456) (xy 386.823204 -52.035456) (xy 386.823204 -54.731412) (xy 387.820662 -54.731412)
			(xy 387.82112 -54.704041) (xy 387.828937 -54.649861) (xy 387.844428 -54.597357) (xy 387.867272 -54.547611)
			(xy 387.896999 -54.501645) (xy 387.914642 -54.480714) (xy 387.914896 -54.48046) (xy 387.920463 -54.47336)
			(xy 387.926722 -54.456454) (xy 387.927088 -54.44744) (xy 387.927088 -54.380384) (xy 387.926741 -54.371366)
			(xy 387.920487 -54.354449) (xy 387.914896 -54.347364) (xy 387.914642 -54.347364) (xy 387.914642 -54.34711)
			(xy 387.897012 -54.326168) (xy 387.867286 -54.280202) (xy 387.844439 -54.230458) (xy 387.828941 -54.177957)
			(xy 387.821111 -54.123779) (xy 387.82111 -54.069039) (xy 387.828937 -54.014861) (xy 387.844433 -53.962359)
			(xy 387.867277 -53.912614) (xy 387.897002 -53.866646) (xy 387.914642 -53.845714) (xy 387.914896 -53.84546)
			(xy 387.920463 -53.83836) (xy 387.926722 -53.821454) (xy 387.927088 -53.81244) (xy 387.927088 -53.745384)
			(xy 387.926741 -53.736366) (xy 387.920487 -53.719449) (xy 387.914896 -53.712364) (xy 387.914642 -53.712364)
			(xy 387.914642 -53.71211) (xy 387.897012 -53.691168) (xy 387.867286 -53.645202) (xy 387.844439 -53.595458)
			(xy 387.828941 -53.542957) (xy 387.821111 -53.488779) (xy 387.82111 -53.434039) (xy 387.828937 -53.379861)
			(xy 387.844433 -53.327359) (xy 387.867277 -53.277614) (xy 387.897002 -53.231646) (xy 387.914642 -53.210714)
			(xy 387.914896 -53.21046) (xy 387.920463 -53.20336) (xy 387.926722 -53.186454) (xy 387.927088 -53.17744)
			(xy 387.927088 -53.110384) (xy 387.926741 -53.101366) (xy 387.920487 -53.084449) (xy 387.914896 -53.077364)
			(xy 387.914642 -53.077364) (xy 387.914642 -53.07711) (xy 387.897001 -53.05618) (xy 387.867288 -53.010207)
			(xy 387.844452 -52.960459) (xy 387.828961 -52.907958) (xy 387.821135 -52.853781) (xy 387.820662 -52.826412)
			(xy 387.821148 -52.799161) (xy 387.828904 -52.745213) (xy 387.844259 -52.692918) (xy 387.866901 -52.643341)
			(xy 387.896367 -52.597491) (xy 387.932058 -52.5563) (xy 387.973249 -52.520609) (xy 388.019099 -52.491143)
			(xy 388.068676 -52.468501) (xy 388.120971 -52.453146) (xy 388.174919 -52.44539) (xy 388.229421 -52.44539)
			(xy 388.283369 -52.453146) (xy 388.335664 -52.468501) (xy 388.385241 -52.491143) (xy 388.431091 -52.520609)
			(xy 388.472282 -52.5563) (xy 388.507973 -52.597491) (xy 388.537439 -52.643341) (xy 388.560081 -52.692918)
			(xy 388.575436 -52.745213) (xy 388.583192 -52.799161) (xy 388.583678 -52.826412) (xy 388.583224 -52.853783)
			(xy 388.575404 -52.907963) (xy 388.559913 -52.960466) (xy 388.537068 -53.010213) (xy 388.507341 -53.056179)
			(xy 388.489698 -53.07711) (xy 388.489444 -53.077364) (xy 388.48386 -53.084452) (xy 388.477613 -53.101368)
			(xy 388.477252 -53.110384) (xy 388.477252 -53.17744) (xy 388.477578 -53.18646) (xy 388.483846 -53.203378)
			(xy 388.489444 -53.21046) (xy 388.489698 -53.21046) (xy 388.489698 -53.210714) (xy 388.507349 -53.231638)
			(xy 388.537072 -53.277608) (xy 388.559915 -53.327356) (xy 388.575409 -53.379859) (xy 388.583236 -53.434038)
			(xy 388.583235 -53.48878) (xy 388.575405 -53.542959) (xy 388.559909 -53.595461) (xy 388.537063 -53.645208)
			(xy 388.507338 -53.691177) (xy 388.489698 -53.71211) (xy 388.489444 -53.712364) (xy 388.48386 -53.719452)
			(xy 388.477613 -53.736368) (xy 388.477252 -53.745384) (xy 388.477252 -53.81244) (xy 388.477578 -53.82146)
			(xy 388.483846 -53.838378) (xy 388.489444 -53.84546) (xy 388.489698 -53.84546) (xy 388.489698 -53.845714)
			(xy 388.507349 -53.866638) (xy 388.537072 -53.912608) (xy 388.559915 -53.962356) (xy 388.575409 -54.014859)
			(xy 388.583236 -54.069038) (xy 388.583235 -54.12378) (xy 388.575405 -54.177959) (xy 388.559909 -54.230461)
			(xy 388.537063 -54.280208) (xy 388.507338 -54.326177) (xy 388.489698 -54.34711) (xy 388.489444 -54.347364)
			(xy 388.48386 -54.354452) (xy 388.477613 -54.371368) (xy 388.477252 -54.380384) (xy 388.477252 -54.44744)
			(xy 388.477578 -54.45646) (xy 388.483846 -54.473378) (xy 388.489444 -54.48046) (xy 388.489698 -54.48046)
			(xy 388.489698 -54.480714) (xy 388.50731 -54.501668) (xy 388.537026 -54.547635) (xy 388.559867 -54.597377)
			(xy 388.575365 -54.649872) (xy 388.5832 -54.704044) (xy 388.583678 -54.731412) (xy 388.583192 -54.758663)
			(xy 388.578528 -54.791102) (xy 390.476486 -54.791102) (xy 390.476957 -54.763732) (xy 390.484774 -54.709553)
			(xy 390.500262 -54.65705) (xy 390.523103 -54.607303) (xy 390.552826 -54.561336) (xy 390.570466 -54.540404)
			(xy 390.57072 -54.54015) (xy 390.576294 -54.533055) (xy 390.582548 -54.516145) (xy 390.582912 -54.50713)
			(xy 390.582912 -54.440074) (xy 390.582565 -54.431056) (xy 390.57631 -54.41414) (xy 390.57072 -54.407054)
			(xy 390.570466 -54.407054) (xy 390.570466 -54.4068) (xy 390.552826 -54.385866) (xy 390.523098 -54.3399)
			(xy 390.50025 -54.290154) (xy 390.484752 -54.237652) (xy 390.476922 -54.183472) (xy 390.476922 -54.128731)
			(xy 390.484751 -54.074551) (xy 390.500249 -54.022049) (xy 390.523096 -53.972303) (xy 390.552824 -53.926336)
			(xy 390.570466 -53.905404) (xy 390.57072 -53.90515) (xy 390.576294 -53.898055) (xy 390.582548 -53.881145)
			(xy 390.582912 -53.87213) (xy 390.582912 -53.805074) (xy 390.582565 -53.796056) (xy 390.57631 -53.77914)
			(xy 390.57072 -53.772054) (xy 390.570466 -53.772054) (xy 390.570466 -53.7718) (xy 390.552826 -53.750866)
			(xy 390.523098 -53.7049) (xy 390.50025 -53.655154) (xy 390.484752 -53.602652) (xy 390.476922 -53.548472)
			(xy 390.476922 -53.493731) (xy 390.484751 -53.439551) (xy 390.500249 -53.387049) (xy 390.523096 -53.337303)
			(xy 390.552824 -53.291336) (xy 390.570466 -53.270404) (xy 390.57072 -53.27015) (xy 390.576294 -53.263055)
			(xy 390.582548 -53.246145) (xy 390.582912 -53.23713) (xy 390.582912 -53.170074) (xy 390.582565 -53.161056)
			(xy 390.57631 -53.14414) (xy 390.57072 -53.137054) (xy 390.570466 -53.137054) (xy 390.570466 -53.1368)
			(xy 390.552808 -53.115883) (xy 390.5231 -53.069906) (xy 390.500269 -53.020154) (xy 390.484782 -52.96765)
			(xy 390.476958 -52.913472) (xy 390.476486 -52.886102) (xy 390.476972 -52.858851) (xy 390.484728 -52.804903)
			(xy 390.500083 -52.752608) (xy 390.522725 -52.703031) (xy 390.552191 -52.657181) (xy 390.587882 -52.61599)
			(xy 390.629073 -52.580299) (xy 390.674923 -52.550833) (xy 390.7245 -52.528191) (xy 390.776795 -52.512836)
			(xy 390.830743 -52.50508) (xy 390.885245 -52.50508) (xy 390.939193 -52.512836) (xy 390.991488 -52.528191)
			(xy 391.030588 -52.546048) (xy 395.979696 -52.546048) (xy 395.979696 -52.491552) (xy 395.987451 -52.437612)
			(xy 396.002803 -52.385323) (xy 396.025439 -52.335752) (xy 396.054899 -52.289906) (xy 396.090584 -52.248719)
			(xy 396.131766 -52.213029) (xy 396.177608 -52.183563) (xy 396.227176 -52.16092) (xy 396.279463 -52.145562)
			(xy 396.333402 -52.1378) (xy 396.36065 -52.13731) (xy 396.388019 -52.137803) (xy 396.442197 -52.145614)
			(xy 396.4947 -52.161097) (xy 396.544448 -52.183932) (xy 396.590415 -52.213651) (xy 396.611348 -52.23129)
			(xy 396.611602 -52.231544) (xy 396.61868 -52.237143) (xy 396.635604 -52.243381) (xy 396.644622 -52.243736)
			(xy 396.711678 -52.243736) (xy 396.720693 -52.243361) (xy 396.737609 -52.237125) (xy 396.744698 -52.231544)
			(xy 396.744698 -52.23129) (xy 396.744952 -52.23129) (xy 396.765885 -52.213649) (xy 396.811853 -52.183925)
			(xy 396.861599 -52.161079) (xy 396.914101 -52.145583) (xy 396.968279 -52.137754) (xy 397.023021 -52.137754)
			(xy 397.077199 -52.145583) (xy 397.129701 -52.161079) (xy 397.179447 -52.183925) (xy 397.225415 -52.213649)
			(xy 397.246348 -52.23129) (xy 397.246602 -52.231544) (xy 397.25368 -52.237143) (xy 397.270604 -52.243381)
			(xy 397.279622 -52.243736) (xy 397.346678 -52.243736) (xy 397.355693 -52.243361) (xy 397.372609 -52.237125)
			(xy 397.379698 -52.231544) (xy 397.379698 -52.23129) (xy 397.379952 -52.23129) (xy 397.40089 -52.213658)
			(xy 397.446861 -52.183946) (xy 397.496607 -52.161109) (xy 397.549107 -52.145616) (xy 397.603281 -52.137785)
			(xy 397.63065 -52.13731) (xy 397.657906 -52.137733) (xy 397.711865 -52.145485) (xy 397.764172 -52.160837)
			(xy 397.813761 -52.183478) (xy 397.859622 -52.212946) (xy 397.900823 -52.248642) (xy 397.936524 -52.289838)
			(xy 397.965998 -52.335695) (xy 397.988645 -52.385281) (xy 398.004004 -52.437586) (xy 398.011763 -52.491544)
			(xy 398.011763 -52.546056) (xy 398.005818 -52.587398) (xy 399.055334 -52.587398) (xy 399.059405 -52.531776)
			(xy 399.071531 -52.477339) (xy 399.091454 -52.425248) (xy 399.11875 -52.376613) (xy 399.152836 -52.33247)
			(xy 399.192985 -52.293761) (xy 399.238343 -52.26131) (xy 399.287943 -52.235809) (xy 399.340727 -52.217802)
			(xy 399.39557 -52.207672) (xy 399.451304 -52.205635) (xy 399.506741 -52.211735) (xy 399.560698 -52.225841)
			(xy 399.612027 -52.247653) (xy 399.659633 -52.276707) (xy 399.702501 -52.312382) (xy 399.739718 -52.353919)
			(xy 399.770491 -52.400432) (xy 399.794163 -52.450929) (xy 399.810231 -52.504336) (xy 399.817827 -52.555948)
			(xy 406.883902 -52.555948) (xy 406.883902 -52.501452) (xy 406.891657 -52.44751) (xy 406.90701 -52.395221)
			(xy 406.929647 -52.345649) (xy 406.959109 -52.299803) (xy 406.994795 -52.258616) (xy 407.035979 -52.222927)
			(xy 407.081823 -52.193462) (xy 407.131393 -52.17082) (xy 407.183681 -52.155464) (xy 407.237622 -52.147704)
			(xy 407.26487 -52.147216) (xy 407.29224 -52.147696) (xy 407.346418 -52.15551) (xy 407.398922 -52.170995)
			(xy 407.448669 -52.193834) (xy 407.494636 -52.223556) (xy 407.515568 -52.241196) (xy 407.515822 -52.24145)
			(xy 407.522894 -52.247058) (xy 407.539822 -52.253291) (xy 407.548842 -52.253642) (xy 407.615898 -52.253642)
			(xy 407.624916 -52.253296) (xy 407.641834 -52.247042) (xy 407.648918 -52.24145) (xy 407.648918 -52.241196)
			(xy 407.649172 -52.241196) (xy 407.670103 -52.223556) (xy 407.716076 -52.193844) (xy 407.765824 -52.171009)
			(xy 407.818325 -52.155518) (xy 407.872501 -52.14769) (xy 407.89987 -52.147216) (xy 407.927126 -52.147629)
			(xy 407.981084 -52.155383) (xy 408.033388 -52.170737) (xy 408.082976 -52.19338) (xy 408.128835 -52.222849)
			(xy 408.170034 -52.258545) (xy 408.205733 -52.299741) (xy 408.235206 -52.345598) (xy 408.257852 -52.395183)
			(xy 408.273211 -52.447487) (xy 408.280969 -52.501444) (xy 408.280969 -52.555956) (xy 408.273211 -52.609913)
			(xy 408.257852 -52.662217) (xy 408.235206 -52.711802) (xy 408.205733 -52.757659) (xy 408.170034 -52.798855)
			(xy 408.128835 -52.834551) (xy 408.082976 -52.86402) (xy 408.033388 -52.886663) (xy 407.981084 -52.902017)
			(xy 407.927126 -52.909771) (xy 407.89987 -52.910232) (xy 407.872498 -52.9098) (xy 407.818317 -52.901977)
			(xy 407.765813 -52.88648) (xy 407.716067 -52.863631) (xy 407.670102 -52.833898) (xy 407.649172 -52.816252)
			(xy 407.648918 -52.815998) (xy 407.641831 -52.810413) (xy 407.624914 -52.804165) (xy 407.615898 -52.803806)
			(xy 407.548842 -52.803806) (xy 407.539827 -52.804182) (xy 407.52291 -52.810416) (xy 407.515822 -52.815998)
			(xy 407.515822 -52.816252) (xy 407.515568 -52.816252) (xy 407.494615 -52.833865) (xy 407.448649 -52.863583)
			(xy 407.398907 -52.886424) (xy 407.34641 -52.901921) (xy 407.292238 -52.909755) (xy 407.26487 -52.910232)
			(xy 407.237622 -52.909696) (xy 407.183681 -52.901936) (xy 407.131393 -52.88658) (xy 407.081823 -52.863938)
			(xy 407.035979 -52.834473) (xy 406.994795 -52.798784) (xy 406.959109 -52.757597) (xy 406.929647 -52.711751)
			(xy 406.90701 -52.662179) (xy 406.891657 -52.60989) (xy 406.883902 -52.555948) (xy 399.817827 -52.555948)
			(xy 399.818351 -52.559512) (xy 399.81886 -52.587398) (xy 399.818351 -52.615284) (xy 399.810231 -52.67046)
			(xy 399.794163 -52.723867) (xy 399.770491 -52.774364) (xy 399.739718 -52.820877) (xy 399.702501 -52.862414)
			(xy 399.659633 -52.898089) (xy 399.612027 -52.927143) (xy 399.560698 -52.948955) (xy 399.506741 -52.963061)
			(xy 399.451304 -52.969161) (xy 399.39557 -52.967124) (xy 399.340727 -52.956994) (xy 399.287943 -52.938987)
			(xy 399.238343 -52.913486) (xy 399.192985 -52.881035) (xy 399.152836 -52.842326) (xy 399.11875 -52.798183)
			(xy 399.091454 -52.749548) (xy 399.071531 -52.697457) (xy 399.059405 -52.64302) (xy 399.055334 -52.587398)
			(xy 398.005818 -52.587398) (xy 398.004004 -52.600014) (xy 397.988645 -52.652319) (xy 397.965998 -52.701905)
			(xy 397.936524 -52.747762) (xy 397.900823 -52.788958) (xy 397.859622 -52.824654) (xy 397.813761 -52.854122)
			(xy 397.764172 -52.876763) (xy 397.711865 -52.892115) (xy 397.657907 -52.899867) (xy 397.63065 -52.900326)
			(xy 397.60328 -52.899849) (xy 397.549101 -52.892036) (xy 397.496597 -52.876551) (xy 397.44685 -52.853711)
			(xy 397.400883 -52.823987) (xy 397.379952 -52.806346) (xy 397.379698 -52.806092) (xy 397.372617 -52.800498)
			(xy 397.355696 -52.794256) (xy 397.346678 -52.7939) (xy 397.279622 -52.7939) (xy 397.270606 -52.794267)
			(xy 397.253689 -52.800508) (xy 397.246602 -52.806092) (xy 397.246348 -52.806346) (xy 397.225415 -52.823987)
			(xy 397.179447 -52.853711) (xy 397.129701 -52.876557) (xy 397.077199 -52.892053) (xy 397.023021 -52.899882)
			(xy 396.968279 -52.899882) (xy 396.914101 -52.892053) (xy 396.861599 -52.876557) (xy 396.811853 -52.853711)
			(xy 396.765885 -52.823987) (xy 396.744952 -52.806346) (xy 396.744698 -52.806092) (xy 396.737617 -52.800498)
			(xy 396.720696 -52.794256) (xy 396.711678 -52.7939) (xy 396.644622 -52.7939) (xy 396.635606 -52.794267)
			(xy 396.618689 -52.800508) (xy 396.611602 -52.806092) (xy 396.611602 -52.806346) (xy 396.611348 -52.806346)
			(xy 396.590402 -52.823968) (xy 396.544434 -52.853684) (xy 396.49469 -52.876524) (xy 396.442192 -52.892019)
			(xy 396.388018 -52.899851) (xy 396.36065 -52.900326) (xy 396.333402 -52.8998) (xy 396.279463 -52.892038)
			(xy 396.227176 -52.87668) (xy 396.177608 -52.854037) (xy 396.131766 -52.824571) (xy 396.090584 -52.788881)
			(xy 396.054899 -52.747694) (xy 396.025439 -52.701848) (xy 396.002803 -52.652277) (xy 395.987451 -52.599988)
			(xy 395.979696 -52.546048) (xy 391.030588 -52.546048) (xy 391.041065 -52.550833) (xy 391.086915 -52.580299)
			(xy 391.128106 -52.61599) (xy 391.163797 -52.657181) (xy 391.193263 -52.703031) (xy 391.215905 -52.752608)
			(xy 391.23126 -52.804903) (xy 391.239016 -52.858851) (xy 391.239502 -52.886102) (xy 391.239037 -52.913472)
			(xy 391.231219 -52.967651) (xy 391.215729 -53.020154) (xy 391.192887 -53.069901) (xy 391.163163 -53.115868)
			(xy 391.145522 -53.1368) (xy 391.145268 -53.137054) (xy 391.139691 -53.144147) (xy 391.13344 -53.161059)
			(xy 391.133076 -53.170074) (xy 391.133076 -53.23713) (xy 391.133424 -53.246148) (xy 391.139678 -53.263064)
			(xy 391.145268 -53.27015) (xy 391.145522 -53.27015) (xy 391.145522 -53.270404) (xy 391.163163 -53.291336)
			(xy 391.192884 -53.337305) (xy 391.215726 -53.387052) (xy 391.23122 -53.439554) (xy 391.239047 -53.493731)
			(xy 391.239047 -53.548472) (xy 391.231219 -53.602649) (xy 391.215725 -53.655151) (xy 391.192882 -53.704897)
			(xy 391.163161 -53.750866) (xy 391.146592 -53.77053) (xy 391.510774 -53.77053) (xy 391.511286 -53.741612)
			(xy 391.520012 -53.68444) (xy 391.537269 -53.62924) (xy 391.562662 -53.577277) (xy 391.595608 -53.529744)
			(xy 391.635353 -53.487729) (xy 391.65784 -53.46954) (xy 391.666626 -53.461912) (xy 391.676819 -53.441027)
			(xy 391.677398 -53.429408) (xy 391.677398 -53.349652) (xy 391.676873 -53.338018) (xy 391.666674 -53.317109)
			(xy 391.65784 -53.30952) (xy 391.635374 -53.291308) (xy 391.595636 -53.249293) (xy 391.562694 -53.201763)
			(xy 391.537302 -53.149806) (xy 391.520043 -53.094612) (xy 391.51131 -53.037445) (xy 391.510774 -53.00853)
			(xy 391.511283 -52.981279) (xy 391.519036 -52.92733) (xy 391.534387 -52.875034) (xy 391.557025 -52.825456)
			(xy 391.586488 -52.779603) (xy 391.622177 -52.738411) (xy 391.663365 -52.702717) (xy 391.709213 -52.673248)
			(xy 391.758789 -52.650604) (xy 391.811083 -52.635246) (xy 391.865031 -52.627487) (xy 391.892282 -52.627022)
			(xy 391.918596 -52.627494) (xy 391.970724 -52.634727) (xy 392.021367 -52.649045) (xy 392.069567 -52.670176)
			(xy 392.11441 -52.697722) (xy 392.15505 -52.73116) (xy 392.173206 -52.750212) (xy 392.180722 -52.75762)
			(xy 392.200006 -52.766141) (xy 392.210544 -52.766722) (xy 392.28522 -52.766722) (xy 392.295765 -52.766157)
			(xy 392.315061 -52.757646) (xy 392.322558 -52.750212) (xy 392.340695 -52.731138) (xy 392.381328 -52.697682)
			(xy 392.426172 -52.670125) (xy 392.474377 -52.64899) (xy 392.525028 -52.634677) (xy 392.577165 -52.627457)
			(xy 392.603482 -52.627022) (xy 392.630736 -52.627472) (xy 392.684689 -52.635227) (xy 392.736989 -52.650583)
			(xy 392.786571 -52.673225) (xy 392.832425 -52.702694) (xy 392.873619 -52.738389) (xy 392.909313 -52.779584)
			(xy 392.93878 -52.82544) (xy 392.961421 -52.875023) (xy 392.976775 -52.927323) (xy 392.984529 -52.981276)
			(xy 392.98499 -53.00853) (xy 392.984506 -53.036196) (xy 392.982275 -53.051456) (xy 401.241258 -53.051456)
			(xy 401.245329 -52.995834) (xy 401.257455 -52.941397) (xy 401.277378 -52.889306) (xy 401.304674 -52.840671)
			(xy 401.33876 -52.796528) (xy 401.378909 -52.757819) (xy 401.424267 -52.725368) (xy 401.473867 -52.699867)
			(xy 401.526651 -52.68186) (xy 401.581494 -52.67173) (xy 401.637228 -52.669693) (xy 401.692665 -52.675793)
			(xy 401.746622 -52.689899) (xy 401.797951 -52.711711) (xy 401.845557 -52.740765) (xy 401.888425 -52.77644)
			(xy 401.925642 -52.817977) (xy 401.956415 -52.86449) (xy 401.980087 -52.914987) (xy 401.996155 -52.968394)
			(xy 402.004275 -53.02357) (xy 402.004784 -53.051456) (xy 402.004275 -53.079342) (xy 401.996155 -53.134518)
			(xy 401.980087 -53.187925) (xy 401.956415 -53.238422) (xy 401.925642 -53.284935) (xy 401.888425 -53.326472)
			(xy 401.845557 -53.362147) (xy 401.797951 -53.391201) (xy 401.746622 -53.413013) (xy 401.692665 -53.427119)
			(xy 401.637228 -53.433219) (xy 401.581494 -53.431182) (xy 401.526651 -53.421052) (xy 401.473867 -53.403045)
			(xy 401.424267 -53.377544) (xy 401.378909 -53.345093) (xy 401.33876 -53.306384) (xy 401.304674 -53.262241)
			(xy 401.277378 -53.213606) (xy 401.257455 -53.161515) (xy 401.245329 -53.107078) (xy 401.241258 -53.051456)
			(xy 392.982275 -53.051456) (xy 392.976502 -53.090947) (xy 392.960681 -53.143969) (xy 392.937373 -53.194154)
			(xy 392.907068 -53.240449) (xy 392.870398 -53.281886) (xy 392.828133 -53.317598) (xy 392.804904 -53.332634)
			(xy 392.795223 -53.339267) (xy 392.782779 -53.35913) (xy 392.781028 -53.370734) (xy 392.773154 -53.450744)
			(xy 392.772501 -53.462383) (xy 392.780596 -53.484222) (xy 392.788648 -53.492654) (xy 392.788902 -53.492908)
			(xy 392.80747 -53.511002) (xy 392.840049 -53.551331) (xy 392.866864 -53.595703) (xy 392.887419 -53.643299)
			(xy 392.901335 -53.693241) (xy 392.908356 -53.744608) (xy 392.90879 -53.77053) (xy 392.90835 -53.797783)
			(xy 392.900589 -53.851733) (xy 392.885229 -53.90403) (xy 392.862583 -53.953608) (xy 392.833112 -53.999459)
			(xy 392.797416 -54.04065) (xy 392.756221 -54.076341) (xy 392.710366 -54.105806) (xy 392.660785 -54.128446)
			(xy 392.608486 -54.143799) (xy 392.554535 -54.151553) (xy 392.527282 -54.152038) (xy 392.499911 -54.151598)
			(xy 392.44573 -54.143776) (xy 392.393226 -54.128282) (xy 392.343479 -54.105434) (xy 392.297514 -54.075703)
			(xy 392.276584 -54.058058) (xy 392.27633 -54.057804) (xy 392.269239 -54.052224) (xy 392.252326 -54.045973)
			(xy 392.24331 -54.045612) (xy 392.176254 -54.045612) (xy 392.167239 -54.045992) (xy 392.150322 -54.052224)
			(xy 392.143234 -54.057804) (xy 392.143234 -54.058058) (xy 392.14298 -54.058058) (xy 392.122023 -54.075667)
			(xy 392.076058 -54.105384) (xy 392.026317 -54.128227) (xy 391.973821 -54.143725) (xy 391.91965 -54.15156)
			(xy 391.892282 -54.152038) (xy 391.865032 -54.151539) (xy 391.811086 -54.143781) (xy 391.758793 -54.128425)
			(xy 391.709218 -54.105784) (xy 391.663369 -54.076319) (xy 391.62218 -54.040629) (xy 391.586489 -53.99944)
			(xy 391.557022 -53.953593) (xy 391.534379 -53.904018) (xy 391.519022 -53.851726) (xy 391.511262 -53.79778)
			(xy 391.510774 -53.77053) (xy 391.146592 -53.77053) (xy 391.145522 -53.7718) (xy 391.145268 -53.772054)
			(xy 391.139691 -53.779147) (xy 391.13344 -53.796059) (xy 391.133076 -53.805074) (xy 391.133076 -53.87213)
			(xy 391.133424 -53.881148) (xy 391.139678 -53.898064) (xy 391.145268 -53.90515) (xy 391.145522 -53.90515)
			(xy 391.145522 -53.905404) (xy 391.163163 -53.926336) (xy 391.192884 -53.972305) (xy 391.215726 -54.022052)
			(xy 391.23122 -54.074554) (xy 391.239047 -54.128731) (xy 391.239047 -54.183472) (xy 391.231219 -54.237649)
			(xy 391.215725 -54.290151) (xy 391.201933 -54.320186) (xy 393.430506 -54.320186) (xy 393.430962 -54.292815)
			(xy 393.438782 -54.238636) (xy 393.454274 -54.186133) (xy 393.477117 -54.136386) (xy 393.506844 -54.090419)
			(xy 393.524486 -54.069488) (xy 393.52474 -54.069234) (xy 393.530323 -54.062145) (xy 393.536571 -54.04523)
			(xy 393.536932 -54.036214) (xy 393.536932 -53.969158) (xy 393.53654 -53.960145) (xy 393.530316 -53.943228)
			(xy 393.52474 -53.936138) (xy 393.524486 -53.936138) (xy 393.524486 -53.935884) (xy 393.506871 -53.914933)
			(xy 393.477156 -53.868965) (xy 393.454315 -53.819222) (xy 393.438819 -53.766726) (xy 393.430984 -53.712554)
			(xy 393.430506 -53.685186) (xy 393.430992 -53.657935) (xy 393.438748 -53.603987) (xy 393.454103 -53.551692)
			(xy 393.476745 -53.502115) (xy 393.506211 -53.456265) (xy 393.541902 -53.415074) (xy 393.583093 -53.379383)
			(xy 393.628943 -53.349917) (xy 393.67852 -53.327275) (xy 393.730815 -53.31192) (xy 393.784763 -53.304164)
			(xy 393.839265 -53.304164) (xy 393.893213 -53.31192) (xy 393.945508 -53.327275) (xy 393.995085 -53.349917)
			(xy 394.040935 -53.379383) (xy 394.082126 -53.415074) (xy 394.117817 -53.456265) (xy 394.14371 -53.496555)
			(xy 406.433441 -53.496555) (xy 406.433441 -53.442045) (xy 406.441199 -53.388089) (xy 406.456557 -53.335787)
			(xy 406.479202 -53.286203) (xy 406.508674 -53.240347) (xy 406.544372 -53.199152) (xy 406.58557 -53.163457)
			(xy 406.631428 -53.133989) (xy 406.681014 -53.111347) (xy 406.733317 -53.095993) (xy 406.787273 -53.088239)
			(xy 406.814528 -53.087778) (xy 406.8419 -53.088209) (xy 406.896081 -53.096032) (xy 406.948585 -53.111528)
			(xy 406.998332 -53.134379) (xy 407.044296 -53.164112) (xy 407.065226 -53.181758) (xy 407.06548 -53.182012)
			(xy 407.072567 -53.187598) (xy 407.089484 -53.193845) (xy 407.0985 -53.194204) (xy 407.165556 -53.194204)
			(xy 407.174571 -53.193825) (xy 407.191488 -53.187593) (xy 407.198576 -53.182012) (xy 407.198576 -53.181758)
			(xy 407.19883 -53.181758) (xy 407.219772 -53.164131) (xy 407.265743 -53.134419) (xy 407.315488 -53.111581)
			(xy 407.367986 -53.096087) (xy 407.42216 -53.088254) (xy 407.449528 -53.087778) (xy 407.476777 -53.088294)
			(xy 407.53072 -53.096054) (xy 407.583009 -53.111411) (xy 407.632581 -53.134052) (xy 407.678426 -53.163518)
			(xy 407.719611 -53.199209) (xy 407.755298 -53.240396) (xy 407.784761 -53.286244) (xy 407.807399 -53.335817)
			(xy 407.822752 -53.388108) (xy 407.830508 -53.442051) (xy 407.830508 -53.496549) (xy 407.822752 -53.550492)
			(xy 407.807399 -53.602783) (xy 407.784761 -53.652356) (xy 407.755298 -53.698204) (xy 407.719611 -53.739391)
			(xy 407.678426 -53.775082) (xy 407.632581 -53.804548) (xy 407.583009 -53.827189) (xy 407.53072 -53.842546)
			(xy 407.476777 -53.850306) (xy 407.449528 -53.850794) (xy 407.422158 -53.850313) (xy 407.36798 -53.842499)
			(xy 407.315477 -53.827013) (xy 407.26573 -53.804175) (xy 407.219762 -53.774454) (xy 407.19883 -53.756814)
			(xy 407.198576 -53.75656) (xy 407.191504 -53.750952) (xy 407.174576 -53.744719) (xy 407.165556 -53.744368)
			(xy 407.0985 -53.744368) (xy 407.089484 -53.744732) (xy 407.072567 -53.750976) (xy 407.06548 -53.75656)
			(xy 407.06548 -53.756814) (xy 407.065226 -53.756814) (xy 407.044297 -53.774457) (xy 406.998323 -53.804167)
			(xy 406.948575 -53.827002) (xy 406.896073 -53.842493) (xy 406.841897 -53.85032) (xy 406.814528 -53.850794)
			(xy 406.787273 -53.850361) (xy 406.733317 -53.842607) (xy 406.681014 -53.827253) (xy 406.631428 -53.804611)
			(xy 406.58557 -53.775143) (xy 406.544372 -53.739448) (xy 406.508674 -53.698253) (xy 406.479202 -53.652397)
			(xy 406.456557 -53.602813) (xy 406.441199 -53.550511) (xy 406.433441 -53.496555) (xy 394.14371 -53.496555)
			(xy 394.147283 -53.502115) (xy 394.169925 -53.551692) (xy 394.18528 -53.603987) (xy 394.193036 -53.657935)
			(xy 394.193522 -53.685186) (xy 394.193067 -53.712557) (xy 394.185249 -53.766737) (xy 394.169759 -53.819241)
			(xy 394.146914 -53.868988) (xy 394.117186 -53.914953) (xy 394.099542 -53.935884) (xy 394.099288 -53.936138)
			(xy 394.09372 -53.943237) (xy 394.087462 -53.960144) (xy 394.087096 -53.969158) (xy 394.087096 -54.036214)
			(xy 394.087447 -54.045231) (xy 394.093699 -54.062148) (xy 394.099288 -54.069234) (xy 394.099542 -54.069234)
			(xy 394.099542 -54.069488) (xy 394.117196 -54.090408) (xy 394.146904 -54.136385) (xy 394.169737 -54.186135)
			(xy 394.185225 -54.238639) (xy 394.19305 -54.292816) (xy 394.193522 -54.320186) (xy 394.193036 -54.347437)
			(xy 394.18528 -54.401385) (xy 394.169925 -54.45368) (xy 394.147283 -54.503257) (xy 394.117817 -54.549107)
			(xy 394.082126 -54.590298) (xy 394.040935 -54.625989) (xy 393.995085 -54.655455) (xy 393.945508 -54.678097)
			(xy 393.893213 -54.693452) (xy 393.839265 -54.701208) (xy 393.784763 -54.701208) (xy 393.730815 -54.693452)
			(xy 393.67852 -54.678097) (xy 393.628943 -54.655455) (xy 393.583093 -54.625989) (xy 393.541902 -54.590298)
			(xy 393.506211 -54.549107) (xy 393.476745 -54.503257) (xy 393.454103 -54.45368) (xy 393.438748 -54.401385)
			(xy 393.430992 -54.347437) (xy 393.430506 -54.320186) (xy 391.201933 -54.320186) (xy 391.192882 -54.339897)
			(xy 391.163161 -54.385866) (xy 391.145522 -54.4068) (xy 391.145268 -54.407054) (xy 391.139691 -54.414147)
			(xy 391.13344 -54.431059) (xy 391.133076 -54.440074) (xy 391.133076 -54.50713) (xy 391.133424 -54.516148)
			(xy 391.139678 -54.533064) (xy 391.145268 -54.54015) (xy 391.145522 -54.54015) (xy 391.145522 -54.540404)
			(xy 391.16318 -54.561321) (xy 391.192888 -54.607298) (xy 391.21572 -54.65705) (xy 391.231207 -54.709554)
			(xy 391.23903 -54.763732) (xy 391.239147 -54.770528) (xy 394.371068 -54.770528) (xy 394.371534 -54.743158)
			(xy 394.379349 -54.688978) (xy 394.394837 -54.636474) (xy 394.41768 -54.586727) (xy 394.447406 -54.540761)
			(xy 394.465048 -54.51983) (xy 394.465302 -54.519576) (xy 394.470905 -54.512501) (xy 394.477142 -54.495575)
			(xy 394.477494 -54.486556) (xy 394.477494 -54.4195) (xy 394.477138 -54.410483) (xy 394.47089 -54.393566)
			(xy 394.465302 -54.38648) (xy 394.465048 -54.38648) (xy 394.465048 -54.386226) (xy 394.447415 -54.365289)
			(xy 394.417701 -54.319318) (xy 394.394863 -54.269572) (xy 394.37937 -54.217072) (xy 394.371542 -54.162897)
			(xy 394.371068 -54.135528) (xy 394.371554 -54.108277) (xy 394.37931 -54.054329) (xy 394.394665 -54.002034)
			(xy 394.417307 -53.952457) (xy 394.446773 -53.906607) (xy 394.482464 -53.865416) (xy 394.523655 -53.829725)
			(xy 394.569505 -53.800259) (xy 394.619082 -53.777617) (xy 394.671377 -53.762262) (xy 394.725325 -53.754506)
			(xy 394.779827 -53.754506) (xy 394.833775 -53.762262) (xy 394.88607 -53.777617) (xy 394.935647 -53.800259)
			(xy 394.981497 -53.829725) (xy 395.022688 -53.865416) (xy 395.058379 -53.906607) (xy 395.087845 -53.952457)
			(xy 395.09292 -53.96357) (xy 399.072098 -53.96357) (xy 399.076169 -53.907948) (xy 399.088295 -53.853511)
			(xy 399.108218 -53.80142) (xy 399.135514 -53.752785) (xy 399.1696 -53.708642) (xy 399.209749 -53.669933)
			(xy 399.255107 -53.637482) (xy 399.304707 -53.611981) (xy 399.357491 -53.593974) (xy 399.412334 -53.583844)
			(xy 399.468068 -53.581807) (xy 399.523505 -53.587907) (xy 399.577462 -53.602013) (xy 399.628791 -53.623825)
			(xy 399.676397 -53.652879) (xy 399.719265 -53.688554) (xy 399.756482 -53.730091) (xy 399.787255 -53.776604)
			(xy 399.810927 -53.827101) (xy 399.826995 -53.880508) (xy 399.835115 -53.935684) (xy 399.835624 -53.96357)
			(xy 399.835115 -53.991456) (xy 399.826995 -54.046632) (xy 399.810927 -54.100039) (xy 399.787255 -54.150536)
			(xy 399.756482 -54.197049) (xy 399.719265 -54.238586) (xy 399.676397 -54.274261) (xy 399.628791 -54.303315)
			(xy 399.577462 -54.325127) (xy 399.523505 -54.339233) (xy 399.468068 -54.345333) (xy 399.412334 -54.343296)
			(xy 399.357491 -54.333166) (xy 399.304707 -54.315159) (xy 399.255107 -54.289658) (xy 399.209749 -54.257207)
			(xy 399.1696 -54.218498) (xy 399.135514 -54.174355) (xy 399.108218 -54.12572) (xy 399.088295 -54.073629)
			(xy 399.076169 -54.019192) (xy 399.072098 -53.96357) (xy 395.09292 -53.96357) (xy 395.110487 -54.002034)
			(xy 395.125842 -54.054329) (xy 395.133598 -54.108277) (xy 395.134084 -54.135528) (xy 395.133638 -54.162899)
			(xy 395.125816 -54.217079) (xy 395.110322 -54.269583) (xy 395.087476 -54.319329) (xy 395.057747 -54.365295)
			(xy 395.040104 -54.386226) (xy 395.03985 -54.38648) (xy 395.03426 -54.393564) (xy 395.028016 -54.410483)
			(xy 395.027658 -54.4195) (xy 395.027658 -54.486556) (xy 395.028023 -54.495572) (xy 395.034264 -54.51249)
			(xy 395.03985 -54.519576) (xy 395.040104 -54.519576) (xy 395.040104 -54.51983) (xy 395.057724 -54.540777)
			(xy 395.087439 -54.586746) (xy 395.110278 -54.63649) (xy 395.125774 -54.688987) (xy 395.133607 -54.74316)
			(xy 395.134084 -54.770528) (xy 395.133598 -54.797779) (xy 395.125842 -54.851727) (xy 395.110487 -54.904022)
			(xy 395.087845 -54.953599) (xy 395.065059 -54.989055) (xy 404.201045 -54.989055) (xy 404.201045 -54.934545)
			(xy 404.208803 -54.880591) (xy 404.22416 -54.82829) (xy 404.246805 -54.778707) (xy 404.276276 -54.732852)
			(xy 404.311973 -54.691657) (xy 404.353169 -54.655963) (xy 404.399026 -54.626494) (xy 404.448611 -54.603853)
			(xy 404.500913 -54.588498) (xy 404.554867 -54.580743) (xy 404.582122 -54.580282) (xy 404.610214 -54.580759)
			(xy 404.665792 -54.58899) (xy 404.719562 -54.605284) (xy 404.770359 -54.629289) (xy 404.817086 -54.660487)
			(xy 404.85873 -54.698201) (xy 404.894392 -54.741616) (xy 404.909274 -54.765448) (xy 404.914608 -54.774338)
			(xy 404.931626 -54.78653) (xy 405.024844 -54.80685) (xy 405.045418 -54.802532) (xy 405.054054 -54.79669)
			(xy 405.078128 -54.780706) (xy 405.130056 -54.75536) (xy 405.185211 -54.73813) (xy 405.242332 -54.72941)
			(xy 405.271224 -54.728872) (xy 405.298475 -54.729355) (xy 405.352422 -54.737115) (xy 405.404715 -54.752472)
			(xy 405.454291 -54.775114) (xy 405.500141 -54.804581) (xy 405.54133 -54.840273) (xy 405.577021 -54.881463)
			(xy 405.606488 -54.927312) (xy 405.62913 -54.976888) (xy 405.644486 -55.029182) (xy 405.652245 -55.083129)
			(xy 405.652732 -55.11038) (xy 405.652271 -55.137751) (xy 405.644454 -55.191931) (xy 405.628965 -55.244434)
			(xy 405.606122 -55.294181) (xy 405.576395 -55.340147) (xy 405.558752 -55.361078) (xy 405.558498 -55.361332)
			(xy 405.552934 -55.368434) (xy 405.546674 -55.385339) (xy 405.546306 -55.394352) (xy 405.546306 -55.461408)
			(xy 405.546658 -55.470425) (xy 405.552909 -55.487342) (xy 405.558498 -55.494428) (xy 405.558752 -55.494428)
			(xy 405.558752 -55.494682) (xy 405.576374 -55.51563) (xy 405.606101 -55.561595) (xy 405.628949 -55.611338)
			(xy 405.644448 -55.663838) (xy 405.652279 -55.718015) (xy 405.652281 -55.772755) (xy 405.644454 -55.826932)
			(xy 405.62896 -55.879433) (xy 405.606116 -55.929179) (xy 405.576392 -55.975146) (xy 405.558752 -55.996078)
			(xy 405.558498 -55.996332) (xy 405.552934 -56.003434) (xy 405.546674 -56.020339) (xy 405.546306 -56.029352)
			(xy 405.546306 -56.096408) (xy 405.546658 -56.105425) (xy 405.552909 -56.122342) (xy 405.558498 -56.129428)
			(xy 405.558752 -56.129428) (xy 405.558752 -56.129682) (xy 405.576389 -56.150616) (xy 405.606103 -56.196588)
			(xy 405.62894 -56.246335) (xy 405.644431 -56.298835) (xy 405.652259 -56.353011) (xy 405.652732 -56.38038)
			(xy 405.652246 -56.407631) (xy 405.64449 -56.461579) (xy 405.629135 -56.513874) (xy 405.606493 -56.563451)
			(xy 405.577027 -56.609301) (xy 405.541336 -56.650492) (xy 405.500145 -56.686183) (xy 405.454295 -56.715649)
			(xy 405.404718 -56.738291) (xy 405.352423 -56.753646) (xy 405.298475 -56.761402) (xy 405.243973 -56.761402)
			(xy 405.190025 -56.753646) (xy 405.13773 -56.738291) (xy 405.088153 -56.715649) (xy 405.042303 -56.686183)
			(xy 405.001112 -56.650492) (xy 404.965421 -56.609301) (xy 404.935955 -56.563451) (xy 404.913313 -56.513874)
			(xy 404.897958 -56.461579) (xy 404.890202 -56.407631) (xy 404.889716 -56.38038) (xy 404.890166 -56.353009)
			(xy 404.897987 -56.298829) (xy 404.91348 -56.246326) (xy 404.936325 -56.196579) (xy 404.966053 -56.150613)
			(xy 404.983696 -56.129682) (xy 404.98395 -56.129428) (xy 404.989537 -56.122342) (xy 404.995782 -56.105425)
			(xy 404.996142 -56.096408) (xy 404.996142 -56.029352) (xy 404.995773 -56.020336) (xy 404.989535 -56.003418)
			(xy 404.98395 -55.996332) (xy 404.983696 -55.996332) (xy 404.983696 -55.996078) (xy 404.966037 -55.975161)
			(xy 404.936315 -55.929189) (xy 404.913473 -55.87944) (xy 404.89798 -55.826936) (xy 404.890154 -55.772756)
			(xy 404.890156 -55.718014) (xy 404.897986 -55.663834) (xy 404.913484 -55.611331) (xy 404.93633 -55.561584)
			(xy 404.966055 -55.515615) (xy 404.983696 -55.494682) (xy 404.98395 -55.494428) (xy 404.989537 -55.487342)
			(xy 404.995782 -55.470425) (xy 404.996142 -55.461408) (xy 404.996142 -55.394352) (xy 404.995773 -55.385336)
			(xy 404.989535 -55.368418) (xy 404.98395 -55.361332) (xy 404.983696 -55.360824) (xy 404.972752 -55.348089)
			(xy 404.952911 -55.320998) (xy 404.944072 -55.306722) (xy 404.938738 -55.297832) (xy 404.92172 -55.28564)
			(xy 404.828502 -55.26532) (xy 404.807928 -55.269638) (xy 404.799292 -55.27548) (xy 404.77523 -55.291483)
			(xy 404.723298 -55.316826) (xy 404.66814 -55.334051) (xy 404.611015 -55.342764) (xy 404.582122 -55.343298)
			(xy 404.554867 -55.342857) (xy 404.500913 -55.335102) (xy 404.448611 -55.319747) (xy 404.399026 -55.297106)
			(xy 404.353169 -55.267637) (xy 404.311973 -55.231943) (xy 404.276276 -55.190748) (xy 404.246805 -55.144893)
			(xy 404.22416 -55.09531) (xy 404.208803 -55.043009) (xy 404.201045 -54.989055) (xy 395.065059 -54.989055)
			(xy 395.058379 -54.999449) (xy 395.022688 -55.04064) (xy 394.981497 -55.076331) (xy 394.935647 -55.105797)
			(xy 394.88607 -55.128439) (xy 394.833775 -55.143794) (xy 394.779827 -55.15155) (xy 394.725325 -55.15155)
			(xy 394.671377 -55.143794) (xy 394.619082 -55.128439) (xy 394.569505 -55.105797) (xy 394.523655 -55.076331)
			(xy 394.482464 -55.04064) (xy 394.446773 -54.999449) (xy 394.417307 -54.953599) (xy 394.394665 -54.904022)
			(xy 394.37931 -54.851727) (xy 394.371554 -54.797779) (xy 394.371068 -54.770528) (xy 391.239147 -54.770528)
			(xy 391.239502 -54.791102) (xy 391.239016 -54.818353) (xy 391.23126 -54.872301) (xy 391.215905 -54.924596)
			(xy 391.193263 -54.974173) (xy 391.163797 -55.020023) (xy 391.128106 -55.061214) (xy 391.086915 -55.096905)
			(xy 391.041065 -55.126371) (xy 390.991488 -55.149013) (xy 390.939193 -55.164368) (xy 390.885245 -55.172124)
			(xy 390.830743 -55.172124) (xy 390.776795 -55.164368) (xy 390.7245 -55.149013) (xy 390.674923 -55.126371)
			(xy 390.629073 -55.096905) (xy 390.587882 -55.061214) (xy 390.552191 -55.020023) (xy 390.522725 -54.974173)
			(xy 390.500083 -54.924596) (xy 390.484728 -54.872301) (xy 390.476972 -54.818353) (xy 390.476486 -54.791102)
			(xy 388.578528 -54.791102) (xy 388.575436 -54.812611) (xy 388.560081 -54.864906) (xy 388.537439 -54.914483)
			(xy 388.507973 -54.960333) (xy 388.472282 -55.001524) (xy 388.431091 -55.037215) (xy 388.385241 -55.066681)
			(xy 388.335664 -55.089323) (xy 388.283369 -55.104678) (xy 388.229421 -55.112434) (xy 388.174919 -55.112434)
			(xy 388.120971 -55.104678) (xy 388.068676 -55.089323) (xy 388.019099 -55.066681) (xy 387.973249 -55.037215)
			(xy 387.932058 -55.001524) (xy 387.896367 -54.960333) (xy 387.866901 -54.914483) (xy 387.844259 -54.864906)
			(xy 387.828904 -54.812611) (xy 387.821148 -54.758663) (xy 387.820662 -54.731412) (xy 386.823204 -54.731412)
			(xy 386.823204 -54.738778) (xy 386.882256 -55.722266) (xy 400.134072 -55.722266) (xy 400.138143 -55.666644)
			(xy 400.150269 -55.612207) (xy 400.170192 -55.560116) (xy 400.197488 -55.511481) (xy 400.231574 -55.467338)
			(xy 400.271723 -55.428629) (xy 400.317081 -55.396178) (xy 400.366681 -55.370677) (xy 400.419465 -55.35267)
			(xy 400.474308 -55.34254) (xy 400.530042 -55.340503) (xy 400.585479 -55.346603) (xy 400.639436 -55.360709)
			(xy 400.690765 -55.382521) (xy 400.738371 -55.411575) (xy 400.749522 -55.420855) (xy 402.524645 -55.420855)
			(xy 402.524645 -55.366345) (xy 402.532403 -55.312391) (xy 402.54776 -55.26009) (xy 402.570405 -55.210507)
			(xy 402.599876 -55.164652) (xy 402.635573 -55.123457) (xy 402.676769 -55.087763) (xy 402.722626 -55.058294)
			(xy 402.772211 -55.035653) (xy 402.824513 -55.020298) (xy 402.878467 -55.012543) (xy 402.905722 -55.012082)
			(xy 402.932036 -55.012541) (xy 402.984165 -55.019778) (xy 403.034808 -55.034099) (xy 403.083006 -55.055233)
			(xy 403.12785 -55.082781) (xy 403.168489 -55.11622) (xy 403.186646 -55.135272) (xy 403.194152 -55.142692)
			(xy 403.213444 -55.151207) (xy 403.223984 -55.151782) (xy 403.29866 -55.151782) (xy 403.30921 -55.15125)
			(xy 403.328505 -55.142718) (xy 403.335998 -55.135272) (xy 403.354156 -55.116219) (xy 403.394786 -55.082763)
			(xy 403.439626 -55.055204) (xy 403.487826 -55.034065) (xy 403.538473 -55.019747) (xy 403.590606 -55.012521)
			(xy 403.616922 -55.012082) (xy 403.644171 -55.01259) (xy 403.698115 -55.020349) (xy 403.750406 -55.035705)
			(xy 403.799979 -55.058347) (xy 403.845825 -55.087813) (xy 403.887012 -55.123504) (xy 403.9227 -55.164692)
			(xy 403.952164 -55.21054) (xy 403.974802 -55.260115) (xy 403.990156 -55.312406) (xy 403.997912 -55.366351)
			(xy 403.997912 -55.420849) (xy 403.990156 -55.474794) (xy 403.974802 -55.527085) (xy 403.952164 -55.57666)
			(xy 403.9227 -55.622508) (xy 403.887012 -55.663696) (xy 403.845826 -55.699387) (xy 403.799979 -55.728853)
			(xy 403.750406 -55.751495) (xy 403.698115 -55.766851) (xy 403.644171 -55.77461) (xy 403.616922 -55.775098)
			(xy 403.590609 -55.774617) (xy 403.538481 -55.767385) (xy 403.487838 -55.753068) (xy 403.439639 -55.731939)
			(xy 403.394795 -55.704395) (xy 403.354155 -55.670959) (xy 403.335998 -55.651908) (xy 403.328478 -55.644505)
			(xy 403.309197 -55.635981) (xy 403.29866 -55.635398) (xy 403.223984 -55.635398) (xy 403.213432 -55.635905)
			(xy 403.194137 -55.644456) (xy 403.186646 -55.651908) (xy 403.168511 -55.670984) (xy 403.127877 -55.704439)
			(xy 403.083032 -55.731995) (xy 403.034827 -55.75313) (xy 402.984176 -55.767443) (xy 402.932039 -55.774662)
			(xy 402.905722 -55.775098) (xy 402.878467 -55.774657) (xy 402.824513 -55.766902) (xy 402.772211 -55.751547)
			(xy 402.722626 -55.728906) (xy 402.676769 -55.699437) (xy 402.635573 -55.663743) (xy 402.599876 -55.622548)
			(xy 402.570405 -55.576693) (xy 402.54776 -55.52711) (xy 402.532403 -55.474809) (xy 402.524645 -55.420855)
			(xy 400.749522 -55.420855) (xy 400.781239 -55.44725) (xy 400.818456 -55.488787) (xy 400.849229 -55.5353)
			(xy 400.872901 -55.585797) (xy 400.888969 -55.639204) (xy 400.897089 -55.69438) (xy 400.897598 -55.722266)
			(xy 400.897089 -55.750152) (xy 400.888969 -55.805328) (xy 400.872901 -55.858735) (xy 400.849229 -55.909232)
			(xy 400.818456 -55.955745) (xy 400.781239 -55.997282) (xy 400.738371 -56.032957) (xy 400.690765 -56.062011)
			(xy 400.639436 -56.083823) (xy 400.585479 -56.097929) (xy 400.530042 -56.104029) (xy 400.474308 -56.101992)
			(xy 400.419465 -56.091862) (xy 400.366681 -56.073855) (xy 400.317081 -56.048354) (xy 400.271723 -56.015903)
			(xy 400.231574 -55.977194) (xy 400.197488 -55.933051) (xy 400.170192 -55.884416) (xy 400.150269 -55.832325)
			(xy 400.138143 -55.777888) (xy 400.134072 -55.722266) (xy 386.882256 -55.722266) (xy 386.959152 -57.002934)
			(xy 395.863572 -57.002934) (xy 395.864098 -56.974844) (xy 395.872321 -56.919268) (xy 395.888607 -56.8655)
			(xy 395.912604 -56.814703) (xy 395.943794 -56.767976) (xy 395.981501 -56.72633) (xy 396.02491 -56.690666)
			(xy 396.048738 -56.675782) (xy 396.057628 -56.670448) (xy 396.06982 -56.65343) (xy 396.09014 -56.560212)
			(xy 396.085822 -56.539638) (xy 396.07998 -56.531002) (xy 396.063976 -56.506941) (xy 396.038635 -56.455008)
			(xy 396.021411 -56.399849) (xy 396.012696 -56.342725) (xy 396.012162 -56.313832) (xy 396.012685 -56.286581)
			(xy 396.020437 -56.232634) (xy 396.035787 -56.180339) (xy 396.058424 -56.130761) (xy 396.087886 -56.084909)
			(xy 396.123573 -56.043717) (xy 396.16476 -56.008023) (xy 396.210607 -55.978554) (xy 396.260181 -55.955909)
			(xy 396.312473 -55.94055) (xy 396.366419 -55.932789) (xy 396.39367 -55.932324) (xy 396.42104 -55.932802)
			(xy 396.475219 -55.940616) (xy 396.527722 -55.956102) (xy 396.577469 -55.978941) (xy 396.623436 -56.008664)
			(xy 396.644368 -56.026304) (xy 396.644622 -56.026558) (xy 396.651693 -56.032167) (xy 396.668622 -56.038399)
			(xy 396.677642 -56.03875) (xy 396.744698 -56.03875) (xy 396.753716 -56.038403) (xy 396.770633 -56.032149)
			(xy 396.777718 -56.026558) (xy 396.777718 -56.026304) (xy 396.777972 -56.026304) (xy 396.798905 -56.008663)
			(xy 396.844873 -55.978939) (xy 396.894619 -55.956093) (xy 396.947121 -55.940597) (xy 397.001299 -55.932768)
			(xy 397.056041 -55.932768) (xy 397.110219 -55.940597) (xy 397.162721 -55.956093) (xy 397.212467 -55.978939)
			(xy 397.258435 -56.008663) (xy 397.279368 -56.026304) (xy 397.279622 -56.026558) (xy 397.286693 -56.032167)
			(xy 397.303622 -56.038399) (xy 397.312642 -56.03875) (xy 397.379698 -56.03875) (xy 397.388716 -56.038403)
			(xy 397.405633 -56.032149) (xy 397.412718 -56.026558) (xy 397.412718 -56.026304) (xy 397.412972 -56.026304)
			(xy 397.433904 -56.008665) (xy 397.479877 -55.978953) (xy 397.529624 -55.956117) (xy 397.582125 -55.940626)
			(xy 397.636301 -55.932798) (xy 397.66367 -55.932324) (xy 397.690927 -55.932721) (xy 397.744885 -55.940475)
			(xy 397.797191 -55.95583) (xy 397.846779 -55.978472) (xy 397.89264 -56.007942) (xy 397.93384 -56.043639)
			(xy 397.96954 -56.084836) (xy 397.999013 -56.130694) (xy 398.02166 -56.180281) (xy 398.037019 -56.232585)
			(xy 398.044777 -56.286543) (xy 398.044777 -56.297068) (xy 398.386552 -56.297068) (xy 398.390623 -56.241446)
			(xy 398.402749 -56.187009) (xy 398.422672 -56.134918) (xy 398.449968 -56.086283) (xy 398.484054 -56.04214)
			(xy 398.524203 -56.003431) (xy 398.569561 -55.97098) (xy 398.619161 -55.945479) (xy 398.671945 -55.927472)
			(xy 398.726788 -55.917342) (xy 398.782522 -55.915305) (xy 398.837959 -55.921405) (xy 398.891916 -55.935511)
			(xy 398.943245 -55.957323) (xy 398.990851 -55.986377) (xy 399.033719 -56.022052) (xy 399.070936 -56.063589)
			(xy 399.101709 -56.110102) (xy 399.125381 -56.160599) (xy 399.141449 -56.214006) (xy 399.149569 -56.269182)
			(xy 399.150078 -56.297068) (xy 399.149569 -56.324954) (xy 399.141449 -56.38013) (xy 399.125381 -56.433537)
			(xy 399.101709 -56.484034) (xy 399.070936 -56.530547) (xy 399.033719 -56.572084) (xy 398.990851 -56.607759)
			(xy 398.943245 -56.636813) (xy 398.891916 -56.658625) (xy 398.837959 -56.672731) (xy 398.782522 -56.678831)
			(xy 398.726788 -56.676794) (xy 398.671945 -56.666664) (xy 398.619161 -56.648657) (xy 398.569561 -56.623156)
			(xy 398.524203 -56.590705) (xy 398.484054 -56.551996) (xy 398.449968 -56.507853) (xy 398.422672 -56.459218)
			(xy 398.402749 -56.407127) (xy 398.390623 -56.35269) (xy 398.386552 -56.297068) (xy 398.044777 -56.297068)
			(xy 398.044777 -56.341057) (xy 398.037019 -56.395015) (xy 398.02166 -56.447319) (xy 397.999013 -56.496906)
			(xy 397.96954 -56.542764) (xy 397.93384 -56.583961) (xy 397.89264 -56.619658) (xy 397.846779 -56.649128)
			(xy 397.797191 -56.67177) (xy 397.744885 -56.687125) (xy 397.690927 -56.694879) (xy 397.66367 -56.69534)
			(xy 397.636298 -56.694906) (xy 397.582117 -56.687083) (xy 397.529613 -56.671587) (xy 397.479867 -56.648738)
			(xy 397.433902 -56.619005) (xy 397.412972 -56.60136) (xy 397.412718 -56.601106) (xy 397.40563 -56.595521)
			(xy 397.388714 -56.589273) (xy 397.379698 -56.588914) (xy 397.312642 -56.588914) (xy 397.303627 -56.589288)
			(xy 397.28671 -56.595524) (xy 397.279622 -56.601106) (xy 397.279622 -56.60136) (xy 397.279368 -56.60136)
			(xy 397.258435 -56.619001) (xy 397.212467 -56.648725) (xy 397.162721 -56.671571) (xy 397.110219 -56.687067)
			(xy 397.056041 -56.694896) (xy 397.001299 -56.694896) (xy 396.947121 -56.687067) (xy 396.894619 -56.671571)
			(xy 396.844873 -56.648725) (xy 396.798905 -56.619001) (xy 396.777972 -56.60136) (xy 396.777718 -56.601106)
			(xy 396.77063 -56.595521) (xy 396.753714 -56.589273) (xy 396.744698 -56.588914) (xy 396.677642 -56.588914)
			(xy 396.668627 -56.589288) (xy 396.65171 -56.595524) (xy 396.644622 -56.601106) (xy 396.644114 -56.60136)
			(xy 396.631383 -56.612308) (xy 396.604289 -56.632147) (xy 396.590012 -56.640984) (xy 396.581122 -56.646318)
			(xy 396.56893 -56.663336) (xy 396.54861 -56.756554) (xy 396.552928 -56.777128) (xy 396.55877 -56.785764)
			(xy 396.574753 -56.809838) (xy 396.600101 -56.861766) (xy 396.617331 -56.916921) (xy 396.626051 -56.974042)
			(xy 396.626588 -57.002934) (xy 396.626102 -57.030185) (xy 396.618346 -57.084133) (xy 396.602991 -57.136428)
			(xy 396.580349 -57.186005) (xy 396.550883 -57.231855) (xy 396.515192 -57.273046) (xy 396.474001 -57.308737)
			(xy 396.428151 -57.338203) (xy 396.378574 -57.360845) (xy 396.326279 -57.3762) (xy 396.272331 -57.383956)
			(xy 396.217829 -57.383956) (xy 396.163881 -57.3762) (xy 396.111586 -57.360845) (xy 396.062009 -57.338203)
			(xy 396.016159 -57.308737) (xy 395.974968 -57.273046) (xy 395.939277 -57.231855) (xy 395.909811 -57.186005)
			(xy 395.887169 -57.136428) (xy 395.871814 -57.084133) (xy 395.864058 -57.030185) (xy 395.863572 -57.002934)
			(xy 386.959152 -57.002934) (xy 386.963666 -57.078118) (xy 386.988079 -57.48528) (xy 404.90597 -57.48528)
			(xy 404.910041 -57.429658) (xy 404.922167 -57.375221) (xy 404.94209 -57.32313) (xy 404.969386 -57.274495)
			(xy 405.003472 -57.230352) (xy 405.043621 -57.191643) (xy 405.088979 -57.159192) (xy 405.138579 -57.133691)
			(xy 405.191363 -57.115684) (xy 405.246206 -57.105554) (xy 405.30194 -57.103517) (xy 405.357377 -57.109617)
			(xy 405.411334 -57.123723) (xy 405.462663 -57.145535) (xy 405.510269 -57.174589) (xy 405.553137 -57.210264)
			(xy 405.590354 -57.251801) (xy 405.621127 -57.298314) (xy 405.644799 -57.348811) (xy 405.660867 -57.402218)
			(xy 405.668987 -57.457394) (xy 405.669496 -57.48528) (xy 405.668987 -57.513166) (xy 405.660867 -57.568342)
			(xy 405.644799 -57.621749) (xy 405.621127 -57.672246) (xy 405.590354 -57.718759) (xy 405.553137 -57.760296)
			(xy 405.510269 -57.795971) (xy 405.462663 -57.825025) (xy 405.411334 -57.846837) (xy 405.357377 -57.860943)
			(xy 405.30194 -57.867043) (xy 405.246206 -57.865006) (xy 405.191363 -57.854876) (xy 405.138579 -57.836869)
			(xy 405.088979 -57.811368) (xy 405.043621 -57.778917) (xy 405.003472 -57.740208) (xy 404.969386 -57.696065)
			(xy 404.94209 -57.64743) (xy 404.922167 -57.595339) (xy 404.910041 -57.540902) (xy 404.90597 -57.48528)
			(xy 386.988079 -57.48528) (xy 387.059674 -58.679334) (xy 396.295372 -58.679334) (xy 396.295804 -58.653019)
			(xy 396.303048 -58.600889) (xy 396.317374 -58.550246) (xy 396.338513 -58.502048) (xy 396.366065 -58.457205)
			(xy 396.399508 -58.416566) (xy 396.418562 -58.39841) (xy 396.425955 -58.390881) (xy 396.434486 -58.371607)
			(xy 396.435072 -58.361072) (xy 396.435072 -58.286396) (xy 396.434567 -58.275843) (xy 396.426016 -58.256548)
			(xy 396.418562 -58.249058) (xy 396.399486 -58.230923) (xy 396.366032 -58.190288) (xy 396.338477 -58.145443)
			(xy 396.317342 -58.097239) (xy 396.303029 -58.046588) (xy 396.295808 -57.994451) (xy 396.295372 -57.968134)
			(xy 396.295858 -57.940883) (xy 396.303614 -57.886935) (xy 396.318969 -57.83464) (xy 396.341611 -57.785063)
			(xy 396.371077 -57.739213) (xy 396.406768 -57.698022) (xy 396.447959 -57.662331) (xy 396.493809 -57.632865)
			(xy 396.543386 -57.610223) (xy 396.595681 -57.594868) (xy 396.649629 -57.587112) (xy 396.704131 -57.587112)
			(xy 396.758079 -57.594868) (xy 396.810374 -57.610223) (xy 396.859951 -57.632865) (xy 396.905801 -57.662331)
			(xy 396.946992 -57.698022) (xy 396.982683 -57.739213) (xy 397.012149 -57.785063) (xy 397.034791 -57.83464)
			(xy 397.050146 -57.886935) (xy 397.057902 -57.940883) (xy 397.058388 -57.968134) (xy 397.057947 -57.994449)
			(xy 397.050707 -58.046579) (xy 397.043439 -58.072274) (xy 400.293584 -58.072274) (xy 400.297655 -58.016652)
			(xy 400.309781 -57.962215) (xy 400.329704 -57.910124) (xy 400.357 -57.861489) (xy 400.391086 -57.817346)
			(xy 400.431235 -57.778637) (xy 400.476593 -57.746186) (xy 400.526193 -57.720685) (xy 400.578977 -57.702678)
			(xy 400.63382 -57.692548) (xy 400.689554 -57.690511) (xy 400.744991 -57.696611) (xy 400.798948 -57.710717)
			(xy 400.850277 -57.732529) (xy 400.897883 -57.761583) (xy 400.940751 -57.797258) (xy 400.977968 -57.838795)
			(xy 401.008741 -57.885308) (xy 401.032413 -57.935805) (xy 401.048481 -57.989212) (xy 401.056601 -58.044388)
			(xy 401.05711 -58.072274) (xy 401.05704 -58.076084) (xy 405.658064 -58.076084) (xy 405.662135 -58.020462)
			(xy 405.674261 -57.966025) (xy 405.694184 -57.913934) (xy 405.72148 -57.865299) (xy 405.755566 -57.821156)
			(xy 405.795715 -57.782447) (xy 405.841073 -57.749996) (xy 405.890673 -57.724495) (xy 405.943457 -57.706488)
			(xy 405.9983 -57.696358) (xy 406.054034 -57.694321) (xy 406.109471 -57.700421) (xy 406.163428 -57.714527)
			(xy 406.214757 -57.736339) (xy 406.262363 -57.765393) (xy 406.305231 -57.801068) (xy 406.342448 -57.842605)
			(xy 406.358784 -57.867296) (xy 407.943048 -57.867296) (xy 407.947119 -57.811674) (xy 407.959245 -57.757237)
			(xy 407.979168 -57.705146) (xy 408.006464 -57.656511) (xy 408.04055 -57.612368) (xy 408.080699 -57.573659)
			(xy 408.126057 -57.541208) (xy 408.175657 -57.515707) (xy 408.228441 -57.4977) (xy 408.283284 -57.48757)
			(xy 408.339018 -57.485533) (xy 408.394455 -57.491633) (xy 408.448412 -57.505739) (xy 408.499741 -57.527551)
			(xy 408.547347 -57.556605) (xy 408.590215 -57.59228) (xy 408.627432 -57.633817) (xy 408.658205 -57.68033)
			(xy 408.681877 -57.730827) (xy 408.697945 -57.784234) (xy 408.706065 -57.83941) (xy 408.706574 -57.867296)
			(xy 408.706065 -57.895182) (xy 408.697945 -57.950358) (xy 408.681877 -58.003765) (xy 408.658205 -58.054262)
			(xy 408.627432 -58.100775) (xy 408.590215 -58.142312) (xy 408.547347 -58.177987) (xy 408.499741 -58.207041)
			(xy 408.448412 -58.228853) (xy 408.394455 -58.242959) (xy 408.339018 -58.249059) (xy 408.283284 -58.247022)
			(xy 408.228441 -58.236892) (xy 408.175657 -58.218885) (xy 408.126057 -58.193384) (xy 408.080699 -58.160933)
			(xy 408.04055 -58.122224) (xy 408.006464 -58.078081) (xy 407.979168 -58.029446) (xy 407.959245 -57.977355)
			(xy 407.947119 -57.922918) (xy 407.943048 -57.867296) (xy 406.358784 -57.867296) (xy 406.373221 -57.889118)
			(xy 406.396893 -57.939615) (xy 406.412961 -57.993022) (xy 406.421081 -58.048198) (xy 406.42159 -58.076084)
			(xy 406.421081 -58.10397) (xy 406.412961 -58.159146) (xy 406.396893 -58.212553) (xy 406.373221 -58.26305)
			(xy 406.342448 -58.309563) (xy 406.305231 -58.3511) (xy 406.262363 -58.386775) (xy 406.214757 -58.415829)
			(xy 406.163428 -58.437641) (xy 406.109471 -58.451747) (xy 406.054034 -58.457847) (xy 405.9983 -58.45581)
			(xy 405.943457 -58.44568) (xy 405.890673 -58.427673) (xy 405.841073 -58.402172) (xy 405.795715 -58.369721)
			(xy 405.755566 -58.331012) (xy 405.72148 -58.286869) (xy 405.694184 -58.238234) (xy 405.674261 -58.186143)
			(xy 405.662135 -58.131706) (xy 405.658064 -58.076084) (xy 401.05704 -58.076084) (xy 401.056601 -58.10016)
			(xy 401.048481 -58.155336) (xy 401.032413 -58.208743) (xy 401.008741 -58.25924) (xy 400.977968 -58.305753)
			(xy 400.940751 -58.34729) (xy 400.897883 -58.382965) (xy 400.850277 -58.412019) (xy 400.798948 -58.433831)
			(xy 400.744991 -58.447937) (xy 400.689554 -58.454037) (xy 400.63382 -58.452) (xy 400.578977 -58.44187)
			(xy 400.526193 -58.423863) (xy 400.476593 -58.398362) (xy 400.431235 -58.365911) (xy 400.391086 -58.327202)
			(xy 400.357 -58.283059) (xy 400.329704 -58.234424) (xy 400.309781 -58.182333) (xy 400.297655 -58.127896)
			(xy 400.293584 -58.072274) (xy 397.043439 -58.072274) (xy 397.036383 -58.097222) (xy 397.015246 -58.145421)
			(xy 396.987695 -58.190264) (xy 396.954252 -58.230902) (xy 396.935198 -58.249058) (xy 396.927813 -58.256593)
			(xy 396.919279 -58.275863) (xy 396.918688 -58.286396) (xy 396.918688 -58.361072) (xy 396.919222 -58.371621)
			(xy 396.927754 -58.390916) (xy 396.935198 -58.39841) (xy 396.954251 -58.416568) (xy 396.987708 -58.457197)
			(xy 397.015268 -58.502037) (xy 397.036407 -58.550237) (xy 397.039513 -58.561224) (xy 406.862278 -58.561224)
			(xy 406.866349 -58.505602) (xy 406.878475 -58.451165) (xy 406.898398 -58.399074) (xy 406.925694 -58.350439)
			(xy 406.95978 -58.306296) (xy 406.999929 -58.267587) (xy 407.045287 -58.235136) (xy 407.094887 -58.209635)
			(xy 407.147671 -58.191628) (xy 407.202514 -58.181498) (xy 407.258248 -58.179461) (xy 407.313685 -58.185561)
			(xy 407.367642 -58.199667) (xy 407.418971 -58.221479) (xy 407.466577 -58.250533) (xy 407.509445 -58.286208)
			(xy 407.546662 -58.327745) (xy 407.577435 -58.374258) (xy 407.601107 -58.424755) (xy 407.608617 -58.449718)
			(xy 409.108908 -58.449718) (xy 409.112979 -58.394096) (xy 409.125105 -58.339659) (xy 409.145028 -58.287568)
			(xy 409.172324 -58.238933) (xy 409.20641 -58.19479) (xy 409.246559 -58.156081) (xy 409.291917 -58.12363)
			(xy 409.341517 -58.098129) (xy 409.394301 -58.080122) (xy 409.449144 -58.069992) (xy 409.504878 -58.067955)
			(xy 409.560315 -58.074055) (xy 409.614272 -58.088161) (xy 409.665601 -58.109973) (xy 409.713207 -58.139027)
			(xy 409.756075 -58.174702) (xy 409.793292 -58.216239) (xy 409.824065 -58.262752) (xy 409.847737 -58.313249)
			(xy 409.863805 -58.366656) (xy 409.871925 -58.421832) (xy 409.872434 -58.449718) (xy 409.871925 -58.477604)
			(xy 409.863805 -58.53278) (xy 409.847737 -58.586187) (xy 409.824065 -58.636684) (xy 409.793292 -58.683197)
			(xy 409.756075 -58.724734) (xy 409.713207 -58.760409) (xy 409.665601 -58.789463) (xy 409.614272 -58.811275)
			(xy 409.560315 -58.825381) (xy 409.504878 -58.831481) (xy 409.449144 -58.829444) (xy 409.394301 -58.819314)
			(xy 409.341517 -58.801307) (xy 409.291917 -58.775806) (xy 409.246559 -58.743355) (xy 409.20641 -58.704646)
			(xy 409.172324 -58.660503) (xy 409.145028 -58.611868) (xy 409.125105 -58.559777) (xy 409.112979 -58.50534)
			(xy 409.108908 -58.449718) (xy 407.608617 -58.449718) (xy 407.617175 -58.478162) (xy 407.625295 -58.533338)
			(xy 407.625804 -58.561224) (xy 407.625295 -58.58911) (xy 407.617175 -58.644286) (xy 407.601107 -58.697693)
			(xy 407.577435 -58.74819) (xy 407.546662 -58.794703) (xy 407.509445 -58.83624) (xy 407.466577 -58.871915)
			(xy 407.418971 -58.900969) (xy 407.367642 -58.922781) (xy 407.313685 -58.936887) (xy 407.258248 -58.942987)
			(xy 407.202514 -58.94095) (xy 407.147671 -58.93082) (xy 407.094887 -58.912813) (xy 407.045287 -58.887312)
			(xy 406.999929 -58.854861) (xy 406.95978 -58.816152) (xy 406.925694 -58.772009) (xy 406.898398 -58.723374)
			(xy 406.878475 -58.671283) (xy 406.866349 -58.616846) (xy 406.862278 -58.561224) (xy 397.039513 -58.561224)
			(xy 397.050724 -58.600884) (xy 397.057949 -58.653018) (xy 397.058388 -58.679334) (xy 397.057902 -58.706585)
			(xy 397.050146 -58.760533) (xy 397.034791 -58.812828) (xy 397.012149 -58.862405) (xy 396.982683 -58.908255)
			(xy 396.946992 -58.949446) (xy 396.905801 -58.985137) (xy 396.859951 -59.014603) (xy 396.810374 -59.037245)
			(xy 396.758079 -59.0526) (xy 396.704131 -59.060356) (xy 396.649629 -59.060356) (xy 396.595681 -59.0526)
			(xy 396.543386 -59.037245) (xy 396.493809 -59.014603) (xy 396.447959 -58.985137) (xy 396.406768 -58.949446)
			(xy 396.371077 -58.908255) (xy 396.341611 -58.862405) (xy 396.318969 -58.812828) (xy 396.303614 -58.760533)
			(xy 396.295858 -58.706585) (xy 396.295372 -58.679334) (xy 387.059674 -58.679334) (xy 387.089372 -59.174634)
			(xy 405.393142 -59.174634) (xy 405.397213 -59.119012) (xy 405.409339 -59.064575) (xy 405.429262 -59.012484)
			(xy 405.456558 -58.963849) (xy 405.490644 -58.919706) (xy 405.530793 -58.880997) (xy 405.576151 -58.848546)
			(xy 405.625751 -58.823045) (xy 405.678535 -58.805038) (xy 405.733378 -58.794908) (xy 405.789112 -58.792871)
			(xy 405.844549 -58.798971) (xy 405.898506 -58.813077) (xy 405.949835 -58.834889) (xy 405.997441 -58.863943)
			(xy 406.040309 -58.899618) (xy 406.077526 -58.941155) (xy 406.108299 -58.987668) (xy 406.131971 -59.038165)
			(xy 406.148039 -59.091572) (xy 406.156159 -59.146748) (xy 406.156668 -59.174634) (xy 406.156159 -59.20252)
			(xy 406.148039 -59.257696) (xy 406.131971 -59.311103) (xy 406.108299 -59.3616) (xy 406.077526 -59.408113)
			(xy 406.040309 -59.44965) (xy 405.997441 -59.485325) (xy 405.949835 -59.514379) (xy 405.898506 -59.536191)
			(xy 405.844549 -59.550297) (xy 405.789112 -59.556397) (xy 405.733378 -59.55436) (xy 405.678535 -59.54423)
			(xy 405.625751 -59.526223) (xy 405.576151 -59.500722) (xy 405.530793 -59.468271) (xy 405.490644 -59.429562)
			(xy 405.456558 -59.385419) (xy 405.429262 -59.336784) (xy 405.409339 -59.284693) (xy 405.397213 -59.230256)
			(xy 405.393142 -59.174634) (xy 387.089372 -59.174634) (xy 387.140014 -60.019254) (xy 396.435761 -60.019254)
			(xy 396.435761 -59.964746) (xy 396.443519 -59.910793) (xy 396.458877 -59.858493) (xy 396.481521 -59.808912)
			(xy 396.510992 -59.763058) (xy 396.546689 -59.721865) (xy 396.587885 -59.686172) (xy 396.633742 -59.656705)
			(xy 396.683325 -59.634065) (xy 396.735626 -59.618712) (xy 396.78958 -59.610959) (xy 396.816834 -59.610498)
			(xy 396.844205 -59.610945) (xy 396.898385 -59.618767) (xy 396.950888 -59.634261) (xy 397.000635 -59.657107)
			(xy 397.046601 -59.686835) (xy 397.067532 -59.704478) (xy 397.067786 -59.704732) (xy 397.07487 -59.710322)
			(xy 397.091789 -59.716566) (xy 397.100806 -59.716924) (xy 397.167862 -59.716924) (xy 397.176876 -59.716544)
			(xy 397.193793 -59.710312) (xy 397.200882 -59.704732) (xy 397.200882 -59.704478) (xy 397.201136 -59.704478)
			(xy 397.222069 -59.686837) (xy 397.268037 -59.657113) (xy 397.317783 -59.634267) (xy 397.370285 -59.618771)
			(xy 397.424463 -59.610942) (xy 397.479205 -59.610942) (xy 397.533383 -59.618771) (xy 397.585885 -59.634267)
			(xy 397.635631 -59.657113) (xy 397.681599 -59.686837) (xy 397.702532 -59.704478) (xy 397.702786 -59.704732)
			(xy 397.70987 -59.710322) (xy 397.726789 -59.716566) (xy 397.735806 -59.716924) (xy 397.802862 -59.716924)
			(xy 397.811876 -59.716544) (xy 397.828793 -59.710312) (xy 397.835882 -59.704732) (xy 397.835882 -59.704478)
			(xy 397.836136 -59.704478) (xy 397.857079 -59.686852) (xy 397.903049 -59.657139) (xy 397.952794 -59.634301)
			(xy 398.005292 -59.618807) (xy 398.059466 -59.610974) (xy 398.086834 -59.610498) (xy 398.114084 -59.610974)
			(xy 398.168029 -59.618735) (xy 398.22032 -59.634093) (xy 398.269894 -59.656736) (xy 398.315741 -59.686204)
			(xy 398.356928 -59.721896) (xy 398.392616 -59.763086) (xy 398.42208 -59.808936) (xy 398.444719 -59.858511)
			(xy 398.460073 -59.910804) (xy 398.467828 -59.96475) (xy 398.467828 -60.01925) (xy 398.460073 -60.073196)
			(xy 398.444719 -60.125489) (xy 398.42208 -60.175064) (xy 398.392616 -60.220914) (xy 398.356928 -60.262104)
			(xy 398.315741 -60.297796) (xy 398.269894 -60.327264) (xy 398.22032 -60.349907) (xy 398.168029 -60.365265)
			(xy 398.114084 -60.373026) (xy 398.086834 -60.373514) (xy 398.059465 -60.373025) (xy 398.005287 -60.365212)
			(xy 397.952784 -60.349728) (xy 397.903037 -60.326892) (xy 397.857069 -60.297173) (xy 397.836136 -60.279534)
			(xy 397.835882 -60.27928) (xy 397.828806 -60.273678) (xy 397.811881 -60.267441) (xy 397.802862 -60.267088)
			(xy 397.735806 -60.267088) (xy 397.72679 -60.267451) (xy 397.709873 -60.273695) (xy 397.702786 -60.27928)
			(xy 397.702532 -60.279534) (xy 397.681599 -60.297175) (xy 397.635631 -60.326899) (xy 397.585885 -60.349745)
			(xy 397.533383 -60.365241) (xy 397.479205 -60.37307) (xy 397.424463 -60.37307) (xy 397.370285 -60.365241)
			(xy 397.317783 -60.349745) (xy 397.268037 -60.326899) (xy 397.222069 -60.297175) (xy 397.201136 -60.279534)
			(xy 397.200882 -60.27928) (xy 397.193806 -60.273678) (xy 397.176881 -60.267441) (xy 397.167862 -60.267088)
			(xy 397.100806 -60.267088) (xy 397.09179 -60.267451) (xy 397.074873 -60.273695) (xy 397.067786 -60.27928)
			(xy 397.067786 -60.279534) (xy 397.067532 -60.279534) (xy 397.046603 -60.297177) (xy 397.000629 -60.326887)
			(xy 396.95088 -60.349722) (xy 396.898379 -60.365212) (xy 396.844203 -60.37304) (xy 396.816834 -60.373514)
			(xy 396.78958 -60.373041) (xy 396.735626 -60.365288) (xy 396.683325 -60.349935) (xy 396.633742 -60.327295)
			(xy 396.587885 -60.297828) (xy 396.546689 -60.262135) (xy 396.510992 -60.220942) (xy 396.481521 -60.175088)
			(xy 396.458877 -60.125507) (xy 396.443519 -60.073207) (xy 396.435761 -60.019254) (xy 387.140014 -60.019254)
			(xy 387.15061 -60.195968) (xy 387.15061 -60.19927) (xy 387.150864 -60.202064) (xy 387.150864 -60.20308)
			(xy 387.151118 -60.205112) (xy 387.151372 -60.209938) (xy 387.151372 -60.21197) (xy 387.15188 -60.233052)
			(xy 387.15188 -60.633356) (xy 408.096972 -60.633356) (xy 408.101043 -60.577734) (xy 408.113169 -60.523297)
			(xy 408.133092 -60.471206) (xy 408.160388 -60.422571) (xy 408.194474 -60.378428) (xy 408.234623 -60.339719)
			(xy 408.279981 -60.307268) (xy 408.329581 -60.281767) (xy 408.382365 -60.26376) (xy 408.437208 -60.25363)
			(xy 408.492942 -60.251593) (xy 408.548379 -60.257693) (xy 408.602336 -60.271799) (xy 408.653665 -60.293611)
			(xy 408.701271 -60.322665) (xy 408.744139 -60.35834) (xy 408.781356 -60.399877) (xy 408.812129 -60.44639)
			(xy 408.835801 -60.496887) (xy 408.851869 -60.550294) (xy 408.859989 -60.60547) (xy 408.860498 -60.633356)
			(xy 408.859989 -60.661242) (xy 408.851869 -60.716418) (xy 408.835801 -60.769825) (xy 408.812129 -60.820322)
			(xy 408.781356 -60.866835) (xy 408.744139 -60.908372) (xy 408.701271 -60.944047) (xy 408.653665 -60.973101)
			(xy 408.602336 -60.994913) (xy 408.548379 -61.009019) (xy 408.492942 -61.015119) (xy 408.437208 -61.013082)
			(xy 408.382365 -61.002952) (xy 408.329581 -60.984945) (xy 408.279981 -60.959444) (xy 408.234623 -60.926993)
			(xy 408.194474 -60.888284) (xy 408.160388 -60.844141) (xy 408.133092 -60.795506) (xy 408.113169 -60.743415)
			(xy 408.101043 -60.688978) (xy 408.096972 -60.633356) (xy 387.15188 -60.633356) (xy 387.15188 -61.487812)
			(xy 406.604468 -61.487812) (xy 406.608539 -61.43219) (xy 406.620665 -61.377753) (xy 406.640588 -61.325662)
			(xy 406.667884 -61.277027) (xy 406.70197 -61.232884) (xy 406.742119 -61.194175) (xy 406.787477 -61.161724)
			(xy 406.837077 -61.136223) (xy 406.889861 -61.118216) (xy 406.944704 -61.108086) (xy 407.000438 -61.106049)
			(xy 407.055875 -61.112149) (xy 407.109832 -61.126255) (xy 407.161161 -61.148067) (xy 407.208767 -61.177121)
			(xy 407.251635 -61.212796) (xy 407.288852 -61.254333) (xy 407.319625 -61.300846) (xy 407.343297 -61.351343)
			(xy 407.359365 -61.40475) (xy 407.367485 -61.459926) (xy 407.367994 -61.487812) (xy 407.367485 -61.515698)
			(xy 407.359365 -61.570874) (xy 407.343297 -61.624281) (xy 407.319625 -61.674778) (xy 407.288852 -61.721291)
			(xy 407.251635 -61.762828) (xy 407.208767 -61.798503) (xy 407.161161 -61.827557) (xy 407.109832 -61.849369)
			(xy 407.055875 -61.863475) (xy 407.000438 -61.869575) (xy 406.944704 -61.867538) (xy 406.889861 -61.857408)
			(xy 406.837077 -61.839401) (xy 406.787477 -61.8139) (xy 406.742119 -61.781449) (xy 406.70197 -61.74274)
			(xy 406.667884 -61.698597) (xy 406.640588 -61.649962) (xy 406.620665 -61.597871) (xy 406.608539 -61.543434)
			(xy 406.604468 -61.487812) (xy 387.15188 -61.487812) (xy 387.15188 -62.121034) (xy 404.542242 -62.121034)
			(xy 404.546313 -62.065412) (xy 404.558439 -62.010975) (xy 404.578362 -61.958884) (xy 404.605658 -61.910249)
			(xy 404.639744 -61.866106) (xy 404.679893 -61.827397) (xy 404.725251 -61.794946) (xy 404.774851 -61.769445)
			(xy 404.827635 -61.751438) (xy 404.882478 -61.741308) (xy 404.938212 -61.739271) (xy 404.993649 -61.745371)
			(xy 405.047606 -61.759477) (xy 405.098935 -61.781289) (xy 405.146541 -61.810343) (xy 405.189409 -61.846018)
			(xy 405.226626 -61.887555) (xy 405.257399 -61.934068) (xy 405.281071 -61.984565) (xy 405.297139 -62.037972)
			(xy 405.305259 -62.093148) (xy 405.305768 -62.121034) (xy 405.305259 -62.14892) (xy 405.297139 -62.204096)
			(xy 405.281071 -62.257503) (xy 405.257399 -62.308) (xy 405.226626 -62.354513) (xy 405.189409 -62.39605)
			(xy 405.146541 -62.431725) (xy 405.098935 -62.460779) (xy 405.047606 -62.482591) (xy 404.993649 -62.496697)
			(xy 404.938212 -62.502797) (xy 404.882478 -62.50076) (xy 404.827635 -62.49063) (xy 404.774851 -62.472623)
			(xy 404.725251 -62.447122) (xy 404.679893 -62.414671) (xy 404.639744 -62.375962) (xy 404.605658 -62.331819)
			(xy 404.578362 -62.283184) (xy 404.558439 -62.231093) (xy 404.546313 -62.176656) (xy 404.542242 -62.121034)
			(xy 387.15188 -62.121034) (xy 387.15188 -62.678774) (xy 407.966172 -62.678774) (xy 407.973925 -62.624826)
			(xy 407.989276 -62.572531) (xy 408.011913 -62.522952) (xy 408.041376 -62.4771) (xy 408.077064 -62.435907)
			(xy 408.118251 -62.400213) (xy 408.164098 -62.370743) (xy 408.213673 -62.348097) (xy 408.265966 -62.332738)
			(xy 408.319913 -62.324976) (xy 408.347164 -62.324488) (xy 408.370719 -62.324856) (xy 408.417463 -62.330721)
			(xy 408.440382 -62.336172) (xy 408.454152 -62.339145) (xy 408.482296 -62.338303) (xy 408.509142 -62.329809)
			(xy 408.532649 -62.314308) (xy 408.55103 -62.292978) (xy 408.562888 -62.267439) (xy 408.567324 -62.239634)
			(xy 408.563999 -62.211673) (xy 408.559 -62.198504) (xy 408.549686 -62.175116) (xy 408.536563 -62.126514)
			(xy 408.529941 -62.076609) (xy 408.529536 -62.051438) (xy 408.529937 -62.024184) (xy 408.537689 -61.97023)
			(xy 408.55304 -61.917929) (xy 408.575679 -61.868345) (xy 408.605143 -61.822487) (xy 408.640834 -61.781289)
			(xy 408.682024 -61.74559) (xy 408.727876 -61.716116) (xy 408.777456 -61.693468) (xy 408.829754 -61.678106)
			(xy 408.883706 -61.670343) (xy 408.938214 -61.670337) (xy 408.992168 -61.678089) (xy 409.044469 -61.69344)
			(xy 409.094053 -61.716078) (xy 409.139911 -61.745542) (xy 409.181109 -61.781232) (xy 409.216809 -61.822423)
			(xy 409.246283 -61.868274) (xy 409.268932 -61.917854) (xy 409.284294 -61.970152) (xy 409.292057 -62.024104)
			(xy 409.292063 -62.078612) (xy 409.284312 -62.132566) (xy 409.268961 -62.184867) (xy 409.246323 -62.234452)
			(xy 409.216859 -62.28031) (xy 409.181169 -62.321508) (xy 409.139979 -62.357208) (xy 409.094127 -62.386682)
			(xy 409.044548 -62.409331) (xy 408.99225 -62.424694) (xy 408.938298 -62.432457) (xy 408.911044 -62.432946)
			(xy 408.887489 -62.432575) (xy 408.840745 -62.426712) (xy 408.817826 -62.421262) (xy 408.804062 -62.418251)
			(xy 408.775909 -62.41909) (xy 408.749056 -62.427586) (xy 408.725543 -62.443092) (xy 408.707159 -62.46443)
			(xy 408.695301 -62.489977) (xy 408.69087 -62.517791) (xy 408.694204 -62.545759) (xy 408.699208 -62.55893)
			(xy 408.708532 -62.582314) (xy 408.721652 -62.630918) (xy 408.728269 -62.680824) (xy 408.728672 -62.705996)
			(xy 408.728227 -62.733247) (xy 408.720471 -62.787194) (xy 408.705117 -62.839489) (xy 408.682476 -62.889066)
			(xy 408.653011 -62.934917) (xy 408.617321 -62.976108) (xy 408.576132 -63.0118) (xy 408.530283 -63.041268)
			(xy 408.480707 -63.06391) (xy 408.428413 -63.079267) (xy 408.374466 -63.087025) (xy 408.319964 -63.087027)
			(xy 408.266016 -63.079273) (xy 408.213721 -63.06392) (xy 408.164143 -63.041282) (xy 408.118291 -63.011818)
			(xy 408.0771 -62.976129) (xy 408.041406 -62.934941) (xy 408.011938 -62.889092) (xy 407.989294 -62.839517)
			(xy 407.973935 -62.787223) (xy 407.966176 -62.733276) (xy 407.966172 -62.678774) (xy 387.15188 -62.678774)
			(xy 387.15188 -63.213554) (xy 396.420765 -63.213554) (xy 396.420765 -63.159046) (xy 396.428523 -63.105092)
			(xy 396.443882 -63.052792) (xy 396.466527 -63.00321) (xy 396.495999 -62.957355) (xy 396.531697 -62.916163)
			(xy 396.572894 -62.88047) (xy 396.618752 -62.851004) (xy 396.668337 -62.828365) (xy 396.720639 -62.813013)
			(xy 396.774594 -62.805262) (xy 396.801848 -62.804802) (xy 396.829217 -62.805298) (xy 396.883395 -62.813109)
			(xy 396.935898 -62.828591) (xy 396.985645 -62.851426) (xy 397.031613 -62.881144) (xy 397.052546 -62.898782)
			(xy 397.0528 -62.899036) (xy 397.059879 -62.904633) (xy 397.076802 -62.910872) (xy 397.08582 -62.911228)
			(xy 397.152876 -62.911228) (xy 397.161891 -62.910853) (xy 397.178808 -62.904617) (xy 397.185896 -62.899036)
			(xy 397.185896 -62.898782) (xy 397.18615 -62.898782) (xy 397.207083 -62.881141) (xy 397.253051 -62.851417)
			(xy 397.302797 -62.828571) (xy 397.355299 -62.813075) (xy 397.409477 -62.805246) (xy 397.464219 -62.805246)
			(xy 397.518397 -62.813075) (xy 397.570899 -62.828571) (xy 397.620645 -62.851417) (xy 397.666613 -62.881141)
			(xy 397.687546 -62.898782) (xy 397.6878 -62.899036) (xy 397.694879 -62.904633) (xy 397.711802 -62.910872)
			(xy 397.72082 -62.911228) (xy 397.787876 -62.911228) (xy 397.796891 -62.910853) (xy 397.813808 -62.904617)
			(xy 397.820896 -62.899036) (xy 397.820896 -62.898782) (xy 397.82115 -62.898782) (xy 397.842088 -62.88115)
			(xy 397.888059 -62.851438) (xy 397.937805 -62.828601) (xy 397.990305 -62.813108) (xy 398.044479 -62.805277)
			(xy 398.071848 -62.804802) (xy 398.099098 -62.805271) (xy 398.153042 -62.813033) (xy 398.205332 -62.828393)
			(xy 398.254905 -62.851038) (xy 398.30075 -62.880506) (xy 398.341936 -62.916198) (xy 398.377623 -62.957388)
			(xy 398.407086 -63.003238) (xy 398.429724 -63.052813) (xy 398.439536 -63.086234) (xy 401.687536 -63.086234)
			(xy 401.691607 -63.030612) (xy 401.703733 -62.976175) (xy 401.723656 -62.924084) (xy 401.750952 -62.875449)
			(xy 401.785038 -62.831306) (xy 401.825187 -62.792597) (xy 401.870545 -62.760146) (xy 401.920145 -62.734645)
			(xy 401.972929 -62.716638) (xy 402.027772 -62.706508) (xy 402.083506 -62.704471) (xy 402.138943 -62.710571)
			(xy 402.1929 -62.724677) (xy 402.244229 -62.746489) (xy 402.291835 -62.775543) (xy 402.334703 -62.811218)
			(xy 402.37192 -62.852755) (xy 402.402693 -62.899268) (xy 402.426365 -62.949765) (xy 402.442433 -63.003172)
			(xy 402.450553 -63.058348) (xy 402.451062 -63.086234) (xy 402.450553 -63.11412) (xy 402.442433 -63.169296)
			(xy 402.426365 -63.222703) (xy 402.402693 -63.2732) (xy 402.40254 -63.273432) (xy 403.876762 -63.273432)
			(xy 403.880833 -63.21781) (xy 403.892959 -63.163373) (xy 403.912882 -63.111282) (xy 403.940178 -63.062647)
			(xy 403.974264 -63.018504) (xy 404.014413 -62.979795) (xy 404.059771 -62.947344) (xy 404.109371 -62.921843)
			(xy 404.162155 -62.903836) (xy 404.216998 -62.893706) (xy 404.272732 -62.891669) (xy 404.328169 -62.897769)
			(xy 404.382126 -62.911875) (xy 404.433455 -62.933687) (xy 404.481061 -62.962741) (xy 404.523929 -62.998416)
			(xy 404.561146 -63.039953) (xy 404.591919 -63.086466) (xy 404.615591 -63.136963) (xy 404.631659 -63.19037)
			(xy 404.639779 -63.245546) (xy 404.640288 -63.273432) (xy 404.639779 -63.301318) (xy 404.631659 -63.356494)
			(xy 404.615591 -63.409901) (xy 404.591919 -63.460398) (xy 404.561146 -63.506911) (xy 404.523929 -63.548448)
			(xy 404.481061 -63.584123) (xy 404.433455 -63.613177) (xy 404.382126 -63.634989) (xy 404.328169 -63.649095)
			(xy 404.272732 -63.655195) (xy 404.216998 -63.653158) (xy 404.162155 -63.643028) (xy 404.109371 -63.625021)
			(xy 404.059771 -63.59952) (xy 404.014413 -63.567069) (xy 403.974264 -63.52836) (xy 403.940178 -63.484217)
			(xy 403.912882 -63.435582) (xy 403.892959 -63.383491) (xy 403.880833 -63.329054) (xy 403.876762 -63.273432)
			(xy 402.40254 -63.273432) (xy 402.37192 -63.319713) (xy 402.334703 -63.36125) (xy 402.291835 -63.396925)
			(xy 402.244229 -63.425979) (xy 402.1929 -63.447791) (xy 402.138943 -63.461897) (xy 402.083506 -63.467997)
			(xy 402.027772 -63.46596) (xy 401.972929 -63.45583) (xy 401.920145 -63.437823) (xy 401.870545 -63.412322)
			(xy 401.825187 -63.379871) (xy 401.785038 -63.341162) (xy 401.750952 -63.297019) (xy 401.723656 -63.248384)
			(xy 401.703733 -63.196293) (xy 401.691607 -63.141856) (xy 401.687536 -63.086234) (xy 398.439536 -63.086234)
			(xy 398.445077 -63.105105) (xy 398.452832 -63.15905) (xy 398.452832 -63.21355) (xy 398.445077 -63.267495)
			(xy 398.429724 -63.319787) (xy 398.407086 -63.369362) (xy 398.377623 -63.415212) (xy 398.341936 -63.456402)
			(xy 398.30075 -63.492094) (xy 398.254905 -63.521562) (xy 398.205332 -63.544207) (xy 398.153042 -63.559567)
			(xy 398.099098 -63.567329) (xy 398.071848 -63.567818) (xy 398.044478 -63.567344) (xy 397.990298 -63.559531)
			(xy 397.937795 -63.544045) (xy 397.888047 -63.521204) (xy 397.842081 -63.49148) (xy 397.82115 -63.473838)
			(xy 397.820896 -63.473584) (xy 397.813816 -63.467988) (xy 397.796894 -63.461747) (xy 397.787876 -63.461392)
			(xy 397.72082 -63.461392) (xy 397.711804 -63.46176) (xy 397.694887 -63.468) (xy 397.6878 -63.473584)
			(xy 397.687546 -63.473838) (xy 397.666613 -63.491479) (xy 397.620645 -63.521203) (xy 397.570899 -63.544049)
			(xy 397.518397 -63.559545) (xy 397.464219 -63.567374) (xy 397.409477 -63.567374) (xy 397.355299 -63.559545)
			(xy 397.302797 -63.544049) (xy 397.253051 -63.521203) (xy 397.207083 -63.491479) (xy 397.18615 -63.473838)
			(xy 397.185896 -63.473584) (xy 397.178816 -63.467988) (xy 397.161894 -63.461747) (xy 397.152876 -63.461392)
			(xy 397.08582 -63.461392) (xy 397.076804 -63.46176) (xy 397.059887 -63.468) (xy 397.0528 -63.473584)
			(xy 397.0528 -63.473838) (xy 397.052546 -63.473838) (xy 397.031613 -63.491475) (xy 396.98564 -63.521186)
			(xy 396.935892 -63.544022) (xy 396.883392 -63.559514) (xy 396.829217 -63.567343) (xy 396.801848 -63.567818)
			(xy 396.774594 -63.567338) (xy 396.720639 -63.559587) (xy 396.668337 -63.544235) (xy 396.618752 -63.521596)
			(xy 396.572894 -63.49213) (xy 396.531697 -63.456437) (xy 396.495999 -63.415245) (xy 396.466527 -63.36939)
			(xy 396.443882 -63.319808) (xy 396.428523 -63.267508) (xy 396.420765 -63.213554) (xy 387.15188 -63.213554)
			(xy 387.15188 -64.25819) (xy 387.151427 -64.290852) (xy 387.149003 -64.312292) (xy 407.20594 -64.312292)
			(xy 407.210011 -64.25667) (xy 407.222137 -64.202233) (xy 407.24206 -64.150142) (xy 407.269356 -64.101507)
			(xy 407.303442 -64.057364) (xy 407.343591 -64.018655) (xy 407.388949 -63.986204) (xy 407.438549 -63.960703)
			(xy 407.491333 -63.942696) (xy 407.546176 -63.932566) (xy 407.60191 -63.930529) (xy 407.657347 -63.936629)
			(xy 407.711304 -63.950735) (xy 407.762633 -63.972547) (xy 407.810239 -64.001601) (xy 407.853107 -64.037276)
			(xy 407.890324 -64.078813) (xy 407.921097 -64.125326) (xy 407.944769 -64.175823) (xy 407.960837 -64.22923)
			(xy 407.968957 -64.284406) (xy 407.969466 -64.312292) (xy 407.968957 -64.340178) (xy 407.960837 -64.395354)
			(xy 407.944769 -64.448761) (xy 407.921097 -64.499258) (xy 407.890324 -64.545771) (xy 407.853107 -64.587308)
			(xy 407.810239 -64.622983) (xy 407.762633 -64.652037) (xy 407.711304 -64.673849) (xy 407.657347 -64.687955)
			(xy 407.60191 -64.694055) (xy 407.546176 -64.692018) (xy 407.491333 -64.681888) (xy 407.438549 -64.663881)
			(xy 407.388949 -64.63838) (xy 407.343591 -64.605929) (xy 407.303442 -64.56722) (xy 407.269356 -64.523077)
			(xy 407.24206 -64.474442) (xy 407.222137 -64.422351) (xy 407.210011 -64.367914) (xy 407.20594 -64.312292)
			(xy 387.149003 -64.312292) (xy 387.144087 -64.355763) (xy 387.129522 -64.419443) (xy 387.107913 -64.481091)
			(xy 387.079534 -64.539929) (xy 387.044741 -64.595217) (xy 387.003973 -64.646259) (xy 386.981192 -64.66967)
			(xy 386.742432 -64.90843) (xy 386.739384 -64.913764) (xy 386.720225 -64.944592) (xy 386.67552 -65.001775)
			(xy 386.65023 -65.02781) (xy 386.577078 -65.100962) (xy 394.432534 -65.100962) (xy 394.436605 -65.04534)
			(xy 394.448731 -64.990903) (xy 394.468654 -64.938812) (xy 394.49595 -64.890177) (xy 394.530036 -64.846034)
			(xy 394.570185 -64.807325) (xy 394.615543 -64.774874) (xy 394.665143 -64.749373) (xy 394.717927 -64.731366)
			(xy 394.77277 -64.721236) (xy 394.828504 -64.719199) (xy 394.883941 -64.725299) (xy 394.937898 -64.739405)
			(xy 394.989227 -64.761217) (xy 395.036833 -64.790271) (xy 395.079701 -64.825946) (xy 395.116918 -64.867483)
			(xy 395.147691 -64.913996) (xy 395.171363 -64.964493) (xy 395.187431 -65.0179) (xy 395.195551 -65.073076)
			(xy 395.19606 -65.100962) (xy 395.195551 -65.128848) (xy 395.187431 -65.184024) (xy 395.171363 -65.237431)
			(xy 395.147691 -65.287928) (xy 395.116918 -65.334441) (xy 395.079701 -65.375978) (xy 395.036833 -65.411653)
			(xy 394.989227 -65.440707) (xy 394.937898 -65.462519) (xy 394.883941 -65.476625) (xy 394.828504 -65.482725)
			(xy 394.77277 -65.480688) (xy 394.717927 -65.470558) (xy 394.665143 -65.452551) (xy 394.615543 -65.42705)
			(xy 394.570185 -65.394599) (xy 394.530036 -65.35589) (xy 394.49595 -65.311747) (xy 394.468654 -65.263112)
			(xy 394.448731 -65.211021) (xy 394.436605 -65.156584) (xy 394.432534 -65.100962) (xy 386.577078 -65.100962)
			(xy 385.92252 -65.75552) (xy 388.646668 -65.75552) (xy 388.650739 -65.699898) (xy 388.662865 -65.645461)
			(xy 388.682788 -65.59337) (xy 388.710084 -65.544735) (xy 388.74417 -65.500592) (xy 388.784319 -65.461883)
			(xy 388.829677 -65.429432) (xy 388.879277 -65.403931) (xy 388.932061 -65.385924) (xy 388.986904 -65.375794)
			(xy 389.042638 -65.373757) (xy 389.098075 -65.379857) (xy 389.152032 -65.393963) (xy 389.203361 -65.415775)
			(xy 389.250967 -65.444829) (xy 389.293835 -65.480504) (xy 389.331052 -65.522041) (xy 389.361825 -65.568554)
			(xy 389.385497 -65.619051) (xy 389.401565 -65.672458) (xy 389.409685 -65.727634) (xy 389.410194 -65.75552)
			(xy 389.409685 -65.783406) (xy 389.401565 -65.838582) (xy 389.385497 -65.891989) (xy 389.361825 -65.942486)
			(xy 389.331052 -65.988999) (xy 389.293835 -66.030536) (xy 389.250967 -66.066211) (xy 389.203361 -66.095265)
			(xy 389.152032 -66.117077) (xy 389.098075 -66.131183) (xy 389.042638 -66.137283) (xy 388.986904 -66.135246)
			(xy 388.932061 -66.125116) (xy 388.879277 -66.107109) (xy 388.829677 -66.081608) (xy 388.784319 -66.049157)
			(xy 388.74417 -66.010448) (xy 388.710084 -65.966305) (xy 388.682788 -65.91767) (xy 388.662865 -65.865579)
			(xy 388.650739 -65.811142) (xy 388.646668 -65.75552) (xy 385.92252 -65.75552) (xy 384.549087 -67.128953)
			(xy 388.666675 -67.128953) (xy 388.666675 -67.074447) (xy 388.674433 -67.020496) (xy 388.68979 -66.968198)
			(xy 388.712434 -66.918618) (xy 388.741904 -66.872765) (xy 388.777599 -66.831574) (xy 388.818794 -66.795882)
			(xy 388.864649 -66.766417) (xy 388.914231 -66.743777) (xy 388.966531 -66.728425) (xy 389.020483 -66.720673)
			(xy 389.047736 -66.720212) (xy 389.075107 -66.720654) (xy 389.129287 -66.728477) (xy 389.181791 -66.743972)
			(xy 389.231537 -66.766819) (xy 389.277503 -66.796548) (xy 389.298434 -66.814192) (xy 389.298688 -66.814446)
			(xy 389.30577 -66.820039) (xy 389.32269 -66.826281) (xy 389.331708 -66.826638) (xy 389.398764 -66.826638)
			(xy 389.407778 -66.826255) (xy 389.424695 -66.820025) (xy 389.431784 -66.814446) (xy 389.431784 -66.814192)
			(xy 389.432038 -66.814192) (xy 389.452982 -66.796567) (xy 389.498951 -66.766854) (xy 389.548696 -66.744015)
			(xy 389.601194 -66.72852) (xy 389.655368 -66.720688) (xy 389.682736 -66.720212) (xy 389.709987 -66.72066)
			(xy 389.763934 -66.728421) (xy 389.816227 -66.74378) (xy 389.865802 -66.766425) (xy 389.91165 -66.795894)
			(xy 389.952838 -66.831587) (xy 389.988528 -66.872778) (xy 390.017992 -66.91863) (xy 390.040632 -66.968207)
			(xy 390.055986 -67.020502) (xy 390.063742 -67.074449) (xy 390.063742 -67.128951) (xy 390.055986 -67.182898)
			(xy 390.040632 -67.235193) (xy 390.017992 -67.28477) (xy 389.988528 -67.330622) (xy 389.952838 -67.371813)
			(xy 389.91165 -67.407506) (xy 389.865802 -67.436975) (xy 389.816227 -67.45962) (xy 389.763934 -67.474979)
			(xy 389.709987 -67.48274) (xy 389.682736 -67.483228) (xy 389.655366 -67.482758) (xy 389.601186 -67.474944)
			(xy 389.548682 -67.459457) (xy 389.498935 -67.436615) (xy 389.452969 -67.40689) (xy 389.432038 -67.389248)
			(xy 389.431784 -67.388994) (xy 389.424707 -67.383394) (xy 389.407783 -67.377156) (xy 389.398764 -67.376802)
			(xy 389.331708 -67.376802) (xy 389.322691 -67.377162) (xy 389.305774 -67.383408) (xy 389.298688 -67.388994)
			(xy 389.298688 -67.389248) (xy 389.298434 -67.389248) (xy 389.277493 -67.406877) (xy 389.231524 -67.436592)
			(xy 389.181778 -67.459431) (xy 389.129279 -67.474924) (xy 389.075105 -67.482754) (xy 389.047736 -67.483228)
			(xy 389.020483 -67.482727) (xy 388.966531 -67.474975) (xy 388.914231 -67.459623) (xy 388.864649 -67.436983)
			(xy 388.818794 -67.407518) (xy 388.777599 -67.371826) (xy 388.741904 -67.330635) (xy 388.712434 -67.284782)
			(xy 388.68979 -67.235202) (xy 388.674433 -67.182904) (xy 388.666675 -67.128953) (xy 384.549087 -67.128953)
			(xy 384.189986 -67.488054) (xy 393.079222 -67.488054) (xy 393.083293 -67.432432) (xy 393.095419 -67.377995)
			(xy 393.115342 -67.325904) (xy 393.142638 -67.277269) (xy 393.176724 -67.233126) (xy 393.216873 -67.194417)
			(xy 393.262231 -67.161966) (xy 393.311831 -67.136465) (xy 393.364615 -67.118458) (xy 393.419458 -67.108328)
			(xy 393.475192 -67.106291) (xy 393.530629 -67.112391) (xy 393.584586 -67.126497) (xy 393.635915 -67.148309)
			(xy 393.683521 -67.177363) (xy 393.726389 -67.213038) (xy 393.763606 -67.254575) (xy 393.794379 -67.301088)
			(xy 393.818051 -67.351585) (xy 393.834119 -67.404992) (xy 393.842239 -67.460168) (xy 393.842748 -67.488054)
			(xy 393.842239 -67.51594) (xy 393.839054 -67.537584) (xy 394.37132 -67.537584) (xy 394.375391 -67.481962)
			(xy 394.387517 -67.427525) (xy 394.40744 -67.375434) (xy 394.434736 -67.326799) (xy 394.468822 -67.282656)
			(xy 394.508971 -67.243947) (xy 394.554329 -67.211496) (xy 394.603929 -67.185995) (xy 394.656713 -67.167988)
			(xy 394.711556 -67.157858) (xy 394.76729 -67.155821) (xy 394.822727 -67.161921) (xy 394.876684 -67.176027)
			(xy 394.928013 -67.197839) (xy 394.975619 -67.226893) (xy 395.018487 -67.262568) (xy 395.055704 -67.304105)
			(xy 395.086477 -67.350618) (xy 395.110149 -67.401115) (xy 395.126217 -67.454522) (xy 395.134337 -67.509698)
			(xy 395.134846 -67.537584) (xy 395.134337 -67.56547) (xy 395.130292 -67.592956) (xy 395.645384 -67.592956)
			(xy 395.649455 -67.537334) (xy 395.661581 -67.482897) (xy 395.681504 -67.430806) (xy 395.7088 -67.382171)
			(xy 395.742886 -67.338028) (xy 395.783035 -67.299319) (xy 395.828393 -67.266868) (xy 395.877993 -67.241367)
			(xy 395.930777 -67.22336) (xy 395.98562 -67.21323) (xy 396.041354 -67.211193) (xy 396.096791 -67.217293)
			(xy 396.150748 -67.231399) (xy 396.202077 -67.253211) (xy 396.249683 -67.282265) (xy 396.292551 -67.31794)
			(xy 396.329768 -67.359477) (xy 396.360541 -67.40599) (xy 396.384213 -67.456487) (xy 396.400281 -67.509894)
			(xy 396.408398 -67.565051) (xy 398.746693 -67.565051) (xy 398.746693 -67.510549) (xy 398.75445 -67.456601)
			(xy 398.769806 -67.404306) (xy 398.792448 -67.354729) (xy 398.821916 -67.308879) (xy 398.857609 -67.26769)
			(xy 398.8988 -67.232) (xy 398.944652 -67.202536) (xy 398.994231 -67.179897) (xy 399.046526 -67.164545)
			(xy 399.100475 -67.156791) (xy 399.127726 -67.15633) (xy 399.155097 -67.156774) (xy 399.209277 -67.164596)
			(xy 399.261781 -67.18009) (xy 399.311528 -67.202937) (xy 399.357493 -67.232666) (xy 399.378424 -67.25031)
			(xy 399.378678 -67.250564) (xy 399.385761 -67.256155) (xy 399.402681 -67.262397) (xy 399.411698 -67.262756)
			(xy 399.478754 -67.262756) (xy 399.48777 -67.262387) (xy 399.504687 -67.256149) (xy 399.511774 -67.250564)
			(xy 399.511774 -67.25031) (xy 399.512028 -67.25031) (xy 399.532978 -67.232693) (xy 399.578945 -67.202977)
			(xy 399.628689 -67.180137) (xy 399.681185 -67.164641) (xy 399.735358 -67.156807) (xy 399.762726 -67.15633)
			(xy 399.789979 -67.156742) (xy 399.843929 -67.164502) (xy 399.896226 -67.179861) (xy 399.945805 -67.202506)
			(xy 399.991656 -67.231976) (xy 400.032848 -67.267671) (xy 400.06854 -67.308864) (xy 400.098007 -67.354718)
			(xy 400.120648 -67.404299) (xy 400.136004 -67.456596) (xy 400.14376 -67.510547) (xy 400.14376 -67.565053)
			(xy 400.136004 -67.619004) (xy 400.120648 -67.671301) (xy 400.098007 -67.720882) (xy 400.06854 -67.766736)
			(xy 400.032848 -67.807929) (xy 399.991656 -67.843624) (xy 399.945805 -67.873094) (xy 399.896226 -67.895739)
			(xy 399.843929 -67.911098) (xy 399.789979 -67.918858) (xy 399.762726 -67.919346) (xy 399.735356 -67.918878)
			(xy 399.681176 -67.911063) (xy 399.628673 -67.895575) (xy 399.578926 -67.872733) (xy 399.532959 -67.843008)
			(xy 399.512028 -67.825366) (xy 399.511774 -67.825112) (xy 399.504669 -67.819552) (xy 399.487767 -67.813289)
			(xy 399.478754 -67.81292) (xy 399.411698 -67.81292) (xy 399.40268 -67.813272) (xy 399.385763 -67.819522)
			(xy 399.378678 -67.825112) (xy 399.378678 -67.825366) (xy 399.378424 -67.825366) (xy 399.357489 -67.843002)
			(xy 399.311518 -67.872715) (xy 399.261771 -67.895553) (xy 399.209271 -67.911044) (xy 399.155095 -67.918872)
			(xy 399.127726 -67.919346) (xy 399.100475 -67.918809) (xy 399.046526 -67.911055) (xy 398.994231 -67.895703)
			(xy 398.944652 -67.873064) (xy 398.8988 -67.8436) (xy 398.857609 -67.80791) (xy 398.821916 -67.766721)
			(xy 398.792448 -67.720871) (xy 398.769806 -67.671294) (xy 398.75445 -67.618999) (xy 398.746693 -67.565051)
			(xy 396.408398 -67.565051) (xy 396.408401 -67.56507) (xy 396.40891 -67.592956) (xy 396.408401 -67.620842)
			(xy 396.400281 -67.676018) (xy 396.384213 -67.729425) (xy 396.360541 -67.779922) (xy 396.329768 -67.826435)
			(xy 396.292551 -67.867972) (xy 396.249683 -67.903647) (xy 396.202077 -67.932701) (xy 396.150748 -67.954513)
			(xy 396.096791 -67.968619) (xy 396.041354 -67.974719) (xy 395.98562 -67.972682) (xy 395.930777 -67.962552)
			(xy 395.877993 -67.944545) (xy 395.828393 -67.919044) (xy 395.783035 -67.886593) (xy 395.742886 -67.847884)
			(xy 395.7088 -67.803741) (xy 395.681504 -67.755106) (xy 395.661581 -67.703015) (xy 395.649455 -67.648578)
			(xy 395.645384 -67.592956) (xy 395.130292 -67.592956) (xy 395.126217 -67.620646) (xy 395.110149 -67.674053)
			(xy 395.086477 -67.72455) (xy 395.055704 -67.771063) (xy 395.018487 -67.8126) (xy 394.975619 -67.848275)
			(xy 394.928013 -67.877329) (xy 394.876684 -67.899141) (xy 394.822727 -67.913247) (xy 394.76729 -67.919347)
			(xy 394.711556 -67.91731) (xy 394.656713 -67.90718) (xy 394.603929 -67.889173) (xy 394.554329 -67.863672)
			(xy 394.508971 -67.831221) (xy 394.468822 -67.792512) (xy 394.434736 -67.748369) (xy 394.40744 -67.699734)
			(xy 394.387517 -67.647643) (xy 394.375391 -67.593206) (xy 394.37132 -67.537584) (xy 393.839054 -67.537584)
			(xy 393.834119 -67.571116) (xy 393.818051 -67.624523) (xy 393.794379 -67.67502) (xy 393.763606 -67.721533)
			(xy 393.726389 -67.76307) (xy 393.683521 -67.798745) (xy 393.635915 -67.827799) (xy 393.584586 -67.849611)
			(xy 393.530629 -67.863717) (xy 393.475192 -67.869817) (xy 393.419458 -67.86778) (xy 393.364615 -67.85765)
			(xy 393.311831 -67.839643) (xy 393.262231 -67.814142) (xy 393.216873 -67.781691) (xy 393.176724 -67.742982)
			(xy 393.142638 -67.698839) (xy 393.115342 -67.650204) (xy 393.095419 -67.598113) (xy 393.083293 -67.543676)
			(xy 393.079222 -67.488054) (xy 384.189986 -67.488054) (xy 383.091436 -68.586604) (xy 390.925304 -68.586604)
			(xy 390.925771 -68.559234) (xy 390.933589 -68.505055) (xy 390.949077 -68.452552) (xy 390.971919 -68.402805)
			(xy 391.001643 -68.356838) (xy 391.019284 -68.335906) (xy 391.019538 -68.335652) (xy 391.025113 -68.328558)
			(xy 391.031366 -68.311647) (xy 391.03173 -68.302632) (xy 391.03173 -68.235576) (xy 391.031378 -68.226559)
			(xy 391.025126 -68.209642) (xy 391.019538 -68.202556) (xy 391.019284 -68.202556) (xy 391.019284 -68.202302)
			(xy 391.00163 -68.181382) (xy 390.971921 -68.135406) (xy 390.949088 -68.085655) (xy 390.9336 -68.033152)
			(xy 390.925776 -67.978974) (xy 390.925304 -67.951604) (xy 390.925759 -67.924351) (xy 390.933516 -67.870399)
			(xy 390.948872 -67.8181) (xy 390.971515 -67.768519) (xy 391.000984 -67.722666) (xy 391.036678 -67.681472)
			(xy 391.077872 -67.645779) (xy 391.123726 -67.616311) (xy 391.173308 -67.593669) (xy 391.225607 -67.578314)
			(xy 391.279559 -67.570559) (xy 391.306812 -67.570096) (xy 391.333126 -67.570557) (xy 391.385255 -67.577793)
			(xy 391.435898 -67.592114) (xy 391.484097 -67.613247) (xy 391.52894 -67.640795) (xy 391.569579 -67.674234)
			(xy 391.587736 -67.693286) (xy 391.595244 -67.700703) (xy 391.614534 -67.709219) (xy 391.625074 -67.709796)
			(xy 391.69975 -67.709796) (xy 391.710298 -67.709255) (xy 391.729594 -67.700728) (xy 391.737088 -67.693286)
			(xy 391.755254 -67.674241) (xy 391.795882 -67.640783) (xy 391.84072 -67.613223) (xy 391.888919 -67.592083)
			(xy 391.939564 -67.577763) (xy 391.991696 -67.570536) (xy 392.018012 -67.570096) (xy 392.045382 -67.570556)
			(xy 392.099562 -67.578375) (xy 392.152065 -67.593866) (xy 392.201812 -67.616709) (xy 392.247778 -67.646434)
			(xy 392.26871 -67.664076) (xy 392.268964 -67.66433) (xy 392.276054 -67.669911) (xy 392.292968 -67.67616)
			(xy 392.301984 -67.676522) (xy 392.36904 -67.676522) (xy 392.378058 -67.676179) (xy 392.394975 -67.669921)
			(xy 392.40206 -67.66433) (xy 392.40206 -67.664076) (xy 392.402314 -67.664076) (xy 392.423265 -67.64646)
			(xy 392.469233 -67.616746) (xy 392.518976 -67.593906) (xy 392.571472 -67.578409) (xy 392.625644 -67.570574)
			(xy 392.653012 -67.570096) (xy 392.680264 -67.570567) (xy 392.734212 -67.578325) (xy 392.786507 -67.593682)
			(xy 392.836085 -67.616325) (xy 392.881936 -67.645792) (xy 392.923126 -67.681486) (xy 392.958817 -67.722677)
			(xy 392.988283 -67.768529) (xy 393.010924 -67.818108) (xy 393.026279 -67.870403) (xy 393.034035 -67.924352)
			(xy 393.03452 -67.951604) (xy 393.034076 -67.978975) (xy 393.026256 -68.033156) (xy 393.010763 -68.08566)
			(xy 392.987915 -68.135407) (xy 392.958185 -68.181372) (xy 392.94054 -68.202302) (xy 392.940286 -68.202556)
			(xy 392.93471 -68.20965) (xy 392.928457 -68.226561) (xy 392.928094 -68.235576) (xy 392.928094 -68.302632)
			(xy 392.928437 -68.31165) (xy 392.934695 -68.328567) (xy 392.940286 -68.335652) (xy 392.94054 -68.335652)
			(xy 392.94054 -68.335906) (xy 392.958202 -68.35682) (xy 392.987909 -68.402798) (xy 393.01074 -68.45255)
			(xy 393.026226 -68.505055) (xy 393.034049 -68.559234) (xy 393.03452 -68.586604) (xy 393.034026 -68.613855)
			(xy 393.026269 -68.667802) (xy 393.010914 -68.720095) (xy 392.994275 -68.75653) (xy 396.470378 -68.75653)
			(xy 396.470843 -68.729159) (xy 396.478658 -68.67498) (xy 396.494146 -68.622476) (xy 396.516989 -68.572729)
			(xy 396.546715 -68.526763) (xy 396.564358 -68.505832) (xy 396.564612 -68.505578) (xy 396.570215 -68.498503)
			(xy 396.576452 -68.481577) (xy 396.576804 -68.472558) (xy 396.576804 -68.405502) (xy 396.576445 -68.396485)
			(xy 396.570199 -68.379568) (xy 396.564612 -68.372482) (xy 396.564358 -68.372482) (xy 396.564358 -68.372228)
			(xy 396.546712 -68.351302) (xy 396.517002 -68.305327) (xy 396.494168 -68.255578) (xy 396.478679 -68.203076)
			(xy 396.470851 -68.148899) (xy 396.470378 -68.12153) (xy 396.470883 -68.094279) (xy 396.478636 -68.04033)
			(xy 396.493987 -67.988034) (xy 396.516625 -67.938455) (xy 396.546089 -67.892602) (xy 396.581778 -67.851409)
			(xy 396.622967 -67.815715) (xy 396.668816 -67.786246) (xy 396.718392 -67.763603) (xy 396.770687 -67.748245)
			(xy 396.824635 -67.740486) (xy 396.851886 -67.740022) (xy 396.879256 -67.740491) (xy 396.933435 -67.748307)
			(xy 396.985939 -67.763795) (xy 397.035686 -67.786637) (xy 397.081652 -67.816361) (xy 397.102584 -67.834002)
			(xy 397.102838 -67.834256) (xy 397.109933 -67.839829) (xy 397.126844 -67.846083) (xy 397.135858 -67.846448)
			(xy 397.202914 -67.846448) (xy 397.211933 -67.846109) (xy 397.22885 -67.83985) (xy 397.235934 -67.834256)
			(xy 397.235934 -67.834002) (xy 397.236188 -67.834002) (xy 397.257114 -67.816355) (xy 397.303088 -67.786645)
			(xy 397.352837 -67.76381) (xy 397.40534 -67.748321) (xy 397.459516 -67.740495) (xy 397.486886 -67.740022)
			(xy 397.5132 -67.740492) (xy 397.565329 -67.747725) (xy 397.615972 -67.762043) (xy 397.664171 -67.783175)
			(xy 397.709014 -67.810721) (xy 397.749654 -67.84416) (xy 397.76781 -67.863212) (xy 397.775324 -67.870622)
			(xy 397.79461 -67.879141) (xy 397.805148 -67.879722) (xy 397.879824 -67.879722) (xy 397.89037 -67.879159)
			(xy 397.909665 -67.870647) (xy 397.917162 -67.863212) (xy 397.935297 -67.844136) (xy 397.975931 -67.81068)
			(xy 398.020775 -67.783123) (xy 398.06898 -67.761988) (xy 398.119631 -67.747676) (xy 398.171769 -67.740457)
			(xy 398.198086 -67.740022) (xy 398.22534 -67.740468) (xy 398.279293 -67.748224) (xy 398.331593 -67.76358)
			(xy 398.381175 -67.786223) (xy 398.42703 -67.815692) (xy 398.468223 -67.851388) (xy 398.503917 -67.892583)
			(xy 398.533385 -67.938439) (xy 398.556026 -67.988022) (xy 398.571379 -68.040323) (xy 398.579133 -68.094276)
			(xy 398.579594 -68.12153) (xy 398.579147 -68.148901) (xy 398.571325 -68.203081) (xy 398.555831 -68.255584)
			(xy 398.532985 -68.305331) (xy 398.503257 -68.351297) (xy 398.485614 -68.372228) (xy 398.48536 -68.372482)
			(xy 398.47977 -68.379566) (xy 398.473526 -68.396485) (xy 398.473168 -68.405502) (xy 398.473168 -68.472558)
			(xy 398.473552 -68.481572) (xy 398.479782 -68.498489) (xy 398.48536 -68.505578) (xy 398.485614 -68.505578)
			(xy 398.485614 -68.505832) (xy 398.503237 -68.526777) (xy 398.532951 -68.572747) (xy 398.555789 -68.622491)
			(xy 398.571284 -68.674988) (xy 398.579117 -68.729162) (xy 398.579594 -68.75653) (xy 398.57915 -68.783783)
			(xy 398.571389 -68.837733) (xy 398.556029 -68.890029) (xy 398.533384 -68.939607) (xy 398.503913 -68.985458)
			(xy 398.468217 -69.026648) (xy 398.427023 -69.062339) (xy 398.381169 -69.091805) (xy 398.331588 -69.114445)
			(xy 398.27929 -69.129798) (xy 398.225339 -69.137553) (xy 398.198086 -69.138038) (xy 398.171771 -69.1376)
			(xy 398.11964 -69.130362) (xy 398.068996 -69.116038) (xy 398.020797 -69.0949) (xy 397.975954 -69.067348)
			(xy 397.935317 -69.033903) (xy 397.917162 -69.014848) (xy 397.90965 -69.007435) (xy 397.890363 -68.998916)
			(xy 397.879824 -68.998338) (xy 397.805148 -68.998338) (xy 397.794598 -68.998868) (xy 397.775302 -69.007402)
			(xy 397.76781 -69.014848) (xy 397.749652 -69.033901) (xy 397.709022 -69.067356) (xy 397.664182 -69.094915)
			(xy 397.615982 -69.116053) (xy 397.565335 -69.130371) (xy 397.513202 -69.137598) (xy 397.486886 -69.138038)
			(xy 397.459515 -69.137595) (xy 397.405334 -69.129774) (xy 397.35283 -69.11428) (xy 397.303084 -69.091433)
			(xy 397.257118 -69.061702) (xy 397.236188 -69.044058) (xy 397.235934 -69.043804) (xy 397.228842 -69.038226)
			(xy 397.211929 -69.031974) (xy 397.202914 -69.031612) (xy 397.135858 -69.031612) (xy 397.126844 -69.031994)
			(xy 397.109926 -69.038224) (xy 397.102838 -69.043804) (xy 397.102838 -69.044058) (xy 397.102584 -69.044058)
			(xy 397.081626 -69.061665) (xy 397.035661 -69.091383) (xy 396.98592 -69.114226) (xy 396.933425 -69.129724)
			(xy 396.879253 -69.13756) (xy 396.851886 -69.138038) (xy 396.824636 -69.137535) (xy 396.77069 -69.129778)
			(xy 396.718398 -69.114422) (xy 396.668822 -69.091782) (xy 396.622973 -69.062317) (xy 396.581784 -69.026627)
			(xy 396.546093 -68.985439) (xy 396.516626 -68.939592) (xy 396.493983 -68.890017) (xy 396.478626 -68.837725)
			(xy 396.470866 -68.78378) (xy 396.470378 -68.75653) (xy 392.994275 -68.75653) (xy 392.988273 -68.769672)
			(xy 392.958808 -68.815522) (xy 392.923117 -68.856712) (xy 392.881928 -68.892403) (xy 392.836079 -68.92187)
			(xy 392.786503 -68.944511) (xy 392.734209 -68.959868) (xy 392.680263 -68.967625) (xy 392.653012 -68.968112)
			(xy 392.625642 -68.967636) (xy 392.571464 -68.95982) (xy 392.518961 -68.944333) (xy 392.469214 -68.921494)
			(xy 392.423246 -68.891772) (xy 392.402314 -68.874132) (xy 392.40206 -68.873878) (xy 392.394962 -68.868308)
			(xy 392.378054 -68.862052) (xy 392.36904 -68.861686) (xy 392.301984 -68.861686) (xy 392.292967 -68.862039)
			(xy 392.27605 -68.86829) (xy 392.268964 -68.873878) (xy 392.268964 -68.874132) (xy 392.26871 -68.874132)
			(xy 392.247789 -68.891785) (xy 392.201813 -68.921494) (xy 392.152062 -68.944326) (xy 392.099559 -68.959814)
			(xy 392.045382 -68.967639) (xy 392.018012 -68.968112) (xy 391.991698 -68.967633) (xy 391.939571 -68.9604)
			(xy 391.888928 -68.946083) (xy 391.840729 -68.924952) (xy 391.795886 -68.897409) (xy 391.755245 -68.863972)
			(xy 391.737088 -68.844922) (xy 391.72957 -68.837516) (xy 391.710287 -68.828993) (xy 391.69975 -68.828412)
			(xy 391.625074 -68.828412) (xy 391.614527 -68.828964) (xy 391.595231 -68.837483) (xy 391.587736 -68.844922)
			(xy 391.569609 -68.864006) (xy 391.528973 -68.89746) (xy 391.484126 -68.925014) (xy 391.43592 -68.946148)
			(xy 391.385268 -68.960459) (xy 391.33313 -68.967677) (xy 391.306812 -68.968112) (xy 391.27956 -68.967634)
			(xy 391.225609 -68.959878) (xy 391.173312 -68.944524) (xy 391.123732 -68.921883) (xy 391.077879 -68.892417)
			(xy 391.036687 -68.856725) (xy 391.000993 -68.815533) (xy 390.971525 -68.769682) (xy 390.948882 -68.720103)
			(xy 390.933525 -68.667806) (xy 390.925768 -68.613856) (xy 390.925304 -68.586604) (xy 383.091436 -68.586604)
			(xy 380.122176 -71.555864) (xy 393.494512 -71.555864) (xy 393.498583 -71.500242) (xy 393.510709 -71.445805)
			(xy 393.530632 -71.393714) (xy 393.557928 -71.345079) (xy 393.592014 -71.300936) (xy 393.632163 -71.262227)
			(xy 393.677521 -71.229776) (xy 393.727121 -71.204275) (xy 393.779905 -71.186268) (xy 393.834748 -71.176138)
			(xy 393.890482 -71.174101) (xy 393.945919 -71.180201) (xy 393.999876 -71.194307) (xy 394.051205 -71.216119)
			(xy 394.098811 -71.245173) (xy 394.141679 -71.280848) (xy 394.178896 -71.322385) (xy 394.209669 -71.368898)
			(xy 394.233341 -71.419395) (xy 394.249409 -71.472802) (xy 394.257529 -71.527978) (xy 394.258038 -71.555864)
			(xy 394.257529 -71.58375) (xy 394.25169 -71.623428) (xy 395.003526 -71.623428) (xy 395.007597 -71.567806)
			(xy 395.019723 -71.513369) (xy 395.039646 -71.461278) (xy 395.066942 -71.412643) (xy 395.101028 -71.3685)
			(xy 395.141177 -71.329791) (xy 395.186535 -71.29734) (xy 395.236135 -71.271839) (xy 395.288919 -71.253832)
			(xy 395.343762 -71.243702) (xy 395.399496 -71.241665) (xy 395.454933 -71.247765) (xy 395.50889 -71.261871)
			(xy 395.560219 -71.283683) (xy 395.607825 -71.312737) (xy 395.650693 -71.348412) (xy 395.68791 -71.389949)
			(xy 395.718683 -71.436462) (xy 395.742355 -71.486959) (xy 395.758423 -71.540366) (xy 395.766543 -71.595542)
			(xy 395.767052 -71.623428) (xy 395.766543 -71.651314) (xy 395.758423 -71.70649) (xy 395.742355 -71.759897)
			(xy 395.718683 -71.810394) (xy 395.68791 -71.856907) (xy 395.650693 -71.898444) (xy 395.607825 -71.934119)
			(xy 395.560219 -71.963173) (xy 395.50889 -71.984985) (xy 395.454933 -71.999091) (xy 395.399496 -72.005191)
			(xy 395.343762 -72.003154) (xy 395.288919 -71.993024) (xy 395.236135 -71.975017) (xy 395.186535 -71.949516)
			(xy 395.141177 -71.917065) (xy 395.101028 -71.878356) (xy 395.066942 -71.834213) (xy 395.039646 -71.785578)
			(xy 395.019723 -71.733487) (xy 395.007597 -71.67905) (xy 395.003526 -71.623428) (xy 394.25169 -71.623428)
			(xy 394.249409 -71.638926) (xy 394.233341 -71.692333) (xy 394.209669 -71.74283) (xy 394.178896 -71.789343)
			(xy 394.141679 -71.83088) (xy 394.098811 -71.866555) (xy 394.051205 -71.895609) (xy 393.999876 -71.917421)
			(xy 393.945919 -71.931527) (xy 393.890482 -71.937627) (xy 393.834748 -71.93559) (xy 393.779905 -71.92546)
			(xy 393.727121 -71.907453) (xy 393.677521 -71.881952) (xy 393.632163 -71.849501) (xy 393.592014 -71.810792)
			(xy 393.557928 -71.766649) (xy 393.530632 -71.718014) (xy 393.510709 -71.665923) (xy 393.498583 -71.611486)
			(xy 393.494512 -71.555864) (xy 380.122176 -71.555864) (xy 377.635008 -74.043032) (xy 377.628166 -74.050432)
			(xy 377.620442 -74.06903) (xy 377.620022 -74.0791) (xy 377.620022 -75.152758) (xy 379.969266 -75.152758)
			(xy 379.973337 -75.097136) (xy 379.985463 -75.042699) (xy 380.005386 -74.990608) (xy 380.032682 -74.941973)
			(xy 380.066768 -74.89783) (xy 380.106917 -74.859121) (xy 380.152275 -74.82667) (xy 380.201875 -74.801169)
			(xy 380.254659 -74.783162) (xy 380.309502 -74.773032) (xy 380.365236 -74.770995) (xy 380.420673 -74.777095)
			(xy 380.47463 -74.791201) (xy 380.525959 -74.813013) (xy 380.573565 -74.842067) (xy 380.616433 -74.877742)
			(xy 380.65365 -74.919279) (xy 380.684423 -74.965792) (xy 380.708095 -75.016289) (xy 380.724088 -75.069446)
			(xy 381.604518 -75.069446) (xy 381.608589 -75.013824) (xy 381.620715 -74.959387) (xy 381.640638 -74.907296)
			(xy 381.667934 -74.858661) (xy 381.70202 -74.814518) (xy 381.742169 -74.775809) (xy 381.787527 -74.743358)
			(xy 381.837127 -74.717857) (xy 381.889911 -74.69985) (xy 381.944754 -74.68972) (xy 382.000488 -74.687683)
			(xy 382.055925 -74.693783) (xy 382.109882 -74.707889) (xy 382.161211 -74.729701) (xy 382.208817 -74.758755)
			(xy 382.251685 -74.79443) (xy 382.288902 -74.835967) (xy 382.319675 -74.88248) (xy 382.343347 -74.932977)
			(xy 382.359415 -74.986384) (xy 382.367535 -75.04156) (xy 382.368044 -75.069446) (xy 382.367535 -75.097332)
			(xy 382.359415 -75.152508) (xy 382.343347 -75.205915) (xy 382.319675 -75.256412) (xy 382.288902 -75.302925)
			(xy 382.251685 -75.344462) (xy 382.208817 -75.380137) (xy 382.161211 -75.409191) (xy 382.109882 -75.431003)
			(xy 382.055925 -75.445109) (xy 382.000488 -75.451209) (xy 381.944754 -75.449172) (xy 381.889911 -75.439042)
			(xy 381.837127 -75.421035) (xy 381.787527 -75.395534) (xy 381.742169 -75.363083) (xy 381.70202 -75.324374)
			(xy 381.667934 -75.280231) (xy 381.640638 -75.231596) (xy 381.620715 -75.179505) (xy 381.608589 -75.125068)
			(xy 381.604518 -75.069446) (xy 380.724088 -75.069446) (xy 380.724163 -75.069696) (xy 380.732283 -75.124872)
			(xy 380.732792 -75.152758) (xy 380.732283 -75.180644) (xy 380.724163 -75.23582) (xy 380.708095 -75.289227)
			(xy 380.684423 -75.339724) (xy 380.65365 -75.386237) (xy 380.616433 -75.427774) (xy 380.573565 -75.463449)
			(xy 380.525959 -75.492503) (xy 380.47463 -75.514315) (xy 380.420673 -75.528421) (xy 380.365236 -75.534521)
			(xy 380.309502 -75.532484) (xy 380.254659 -75.522354) (xy 380.201875 -75.504347) (xy 380.152275 -75.478846)
			(xy 380.106917 -75.446395) (xy 380.066768 -75.407686) (xy 380.032682 -75.363543) (xy 380.005386 -75.314908)
			(xy 379.985463 -75.262817) (xy 379.973337 -75.20838) (xy 379.969266 -75.152758) (xy 377.620022 -75.152758)
			(xy 377.620022 -75.556364) (xy 377.620276 -75.56119) (xy 377.620276 -75.561444) (xy 377.621237 -75.568169)
			(xy 377.626265 -75.580784) (xy 377.630182 -75.586336) (xy 377.634754 -75.59167) (xy 377.764294 -75.72121)
			(xy 377.771688 -75.728067) (xy 377.790287 -75.735818) (xy 377.800362 -75.736196) (xy 398.920462 -75.736196)
			(xy 398.930527 -75.735761) (xy 398.949115 -75.728031) (xy 398.95653 -75.72121) (xy 409.548584 -65.129156)
			(xy 409.552019 -65.125539) (xy 409.557524 -65.117223) (xy 409.559506 -65.112646) (xy 410.380434 -63.130938)
			(xy 410.380942 -63.129414) (xy 410.820362 -61.971936) (xy 411.416754 -60.400692) (xy 411.418297 -60.396344)
			(xy 411.419959 -60.38727) (xy 411.420056 -60.382658) (xy 411.420056 -55.370984) (xy 411.351476 -54.229254)
			(xy 411.275276 -52.958492) (xy 411.232604 -52.246784) (xy 411.153102 -50.921666) (xy 411.153102 -50.918364)
			(xy 411.152848 -50.916332) (xy 411.152848 -50.915316) (xy 411.152594 -50.91303) (xy 411.15234 -50.907696)
			(xy 411.15234 -50.906172) (xy 411.151832 -50.884836) (xy 411.151832 -50.884328) (xy 411.15249 -50.846417)
			(xy 411.162424 -50.771247) (xy 411.171644 -50.734468) (xy 411.418278 -49.8094) (xy 411.420056 -49.796446)
			(xy 411.420056 -42.59834) (xy 411.420523 -42.565186) (xy 411.427949 -42.499295) (xy 411.4427 -42.434649)
			(xy 411.464591 -42.372059) (xy 411.493348 -42.312311) (xy 411.52861 -42.256156) (xy 411.569933 -42.204299)
			(xy 411.59303 -42.18051) (xy 415.591498 -38.182042) (xy 415.598864 -38.168326) (xy 415.600134 -38.160706)
			(xy 415.607036 -38.125528) (xy 415.628241 -38.057046) (xy 415.657568 -37.991628) (xy 415.694585 -37.930235)
			(xy 415.738751 -37.873765) (xy 415.76371 -37.848032) (xy 416.11423 -37.497512) (xy 416.13993 -37.472549)
			(xy 416.196343 -37.42838) (xy 416.257685 -37.391358) (xy 416.323053 -37.362027) (xy 416.39149 -37.340817)
			(xy 416.42665 -37.333936) (xy 416.453574 -37.319966) (xy 416.459924 -37.313616) (xy 416.46619 -37.27675)
			(xy 416.486813 -37.204868) (xy 416.516331 -37.136159) (xy 416.554272 -37.071718) (xy 416.600032 -37.012572)
			(xy 416.62604 -36.985702) (xy 416.97656 -36.635182) (xy 417.005391 -36.607349) (xy 417.069239 -36.558921)
			(xy 417.103814 -36.538662) (xy 417.107878 -36.536122) (xy 417.134297 -36.518296) (xy 417.190302 -36.487871)
			(xy 417.219638 -36.475416) (xy 417.234121 -36.469585) (xy 417.263601 -36.459293) (xy 417.278566 -36.454842)
			(xy 417.294822 -36.45027) (xy 417.315396 -36.423092) (xy 417.315396 -35.964622) (xy 417.306252 -35.935666)
			(xy 417.28629 -35.905952) (xy 417.25292 -35.84262) (xy 417.227455 -35.775716) (xy 417.210269 -35.706224)
			(xy 417.201614 -35.635163) (xy 417.201096 -35.59937) (xy 417.201096 -35.103816) (xy 417.201656 -35.065007)
			(xy 417.211717 -34.988046) (xy 417.221162 -34.9504) (xy 417.22294 -34.94405) (xy 417.22294 -34.587942)
			(xy 417.223956 -34.553652) (xy 417.224094 -34.549482) (xy 417.223199 -34.541188) (xy 417.222178 -34.537142)
			(xy 417.212264 -34.498596) (xy 417.201684 -34.419712) (xy 417.201096 -34.379916) (xy 417.201096 -33.884616)
			(xy 417.201656 -33.845807) (xy 417.211717 -33.768846) (xy 417.221162 -33.7312) (xy 417.22294 -33.72485)
			(xy 417.22294 -33.450784) (xy 417.223136 -33.428278) (xy 417.226565 -33.383396) (xy 417.229798 -33.361122)
			(xy 417.230615 -33.355326) (xy 417.229838 -33.343649) (xy 417.228274 -33.338008) (xy 417.219658 -33.309297)
			(xy 417.207576 -33.25058) (xy 417.20149 -33.190943) (xy 417.201096 -33.16097) (xy 417.201096 -32.665416)
			(xy 417.201656 -32.626607) (xy 417.211717 -32.549646) (xy 417.221162 -32.512) (xy 417.22294 -32.50565)
			(xy 417.22294 -32.313372) (xy 417.22346 -32.278679) (xy 417.231743 -32.209788) (xy 417.23945 -32.175958)
			(xy 417.24091 -32.168597) (xy 417.24001 -32.153624) (xy 417.237672 -32.146494) (xy 417.226083 -32.113665)
			(xy 417.209806 -32.045972) (xy 417.201609 -31.976835) (xy 417.201096 -31.942024) (xy 417.201096 -31.446216)
			(xy 417.201656 -31.407407) (xy 417.211717 -31.330446) (xy 417.221162 -31.2928) (xy 417.22294 -31.28645)
			(xy 417.22294 -31.17596) (xy 417.223339 -31.145215) (xy 417.229816 -31.084068) (xy 417.242692 -31.023941)
			(xy 417.251896 -30.994604) (xy 417.254436 -30.978856) (xy 417.250118 -30.958536) (xy 417.238401 -30.930645)
			(xy 417.220065 -30.87299) (xy 417.207726 -30.813762) (xy 417.201511 -30.753582) (xy 417.201096 -30.723332)
			(xy 417.201096 -30.227016) (xy 417.201656 -30.188207) (xy 417.211717 -30.111246) (xy 417.221162 -30.0736)
			(xy 417.22294 -30.06725) (xy 417.22294 -30.038548) (xy 417.223566 -30.000296) (xy 417.233621 -29.924454)
			(xy 417.253512 -29.85058) (xy 417.267644 -29.815028) (xy 417.271464 -29.804613) (xy 417.27068 -29.782469)
			(xy 417.26612 -29.772356) (xy 417.250645 -29.741041) (xy 417.226338 -29.675554) (xy 417.209928 -29.607656)
			(xy 417.201642 -29.538296) (xy 417.201096 -29.50337) (xy 417.201096 -29.007308) (xy 417.201854 -28.96479)
			(xy 417.214098 -28.880641) (xy 417.22548 -28.839668) (xy 417.227258 -28.831286) (xy 417.231159 -28.801974)
			(xy 417.24415 -28.744283) (xy 417.262921 -28.688205) (xy 417.274756 -28.661106) (xy 417.28644 -28.636722)
			(xy 417.292028 -28.613354) (xy 417.284916 -28.587446) (xy 417.268929 -28.559888) (xy 417.242297 -28.502009)
			(xy 417.222043 -28.441602) (xy 417.208402 -28.379367) (xy 417.201533 -28.316026) (xy 417.201096 -28.28417)
			(xy 417.201096 -27.970734) (xy 417.200476 -27.95919) (xy 417.190299 -27.938456) (xy 417.17213 -27.924197)
			(xy 417.160964 -27.921204) (xy 417.160456 -27.921204) (xy 417.127658 -27.913866) (xy 417.063854 -27.892737)
			(xy 417.00286 -27.864502) (xy 416.945465 -27.829527) (xy 416.892412 -27.788263) (xy 416.844385 -27.741244)
			(xy 416.802005 -27.689077) (xy 416.76582 -27.632438) (xy 416.736299 -27.572057) (xy 416.713821 -27.508715)
			(xy 416.698679 -27.443231) (xy 416.691068 -27.376452) (xy 416.690556 -27.342846) (xy 416.690556 -27.342338)
			(xy 416.691006 -27.310077) (xy 416.698071 -27.245941) (xy 416.712078 -27.182956) (xy 416.732859 -27.121871)
			(xy 416.760169 -27.063412) (xy 416.793681 -27.008274) (xy 416.812984 -26.98242) (xy 416.81781 -26.976324)
			(xy 416.823652 -26.960068) (xy 416.823652 -26.864056) (xy 416.821874 -26.850848) (xy 416.812984 -26.839672)
			(xy 416.793657 -26.813834) (xy 416.760128 -26.758701) (xy 416.732811 -26.700241) (xy 416.712032 -26.639151)
			(xy 416.698038 -26.57616) (xy 416.690996 -26.512018) (xy 416.690556 -26.479754) (xy 416.690556 -26.479246)
			(xy 416.691092 -26.443534) (xy 416.699694 -26.372631) (xy 416.716778 -26.303282) (xy 416.742094 -26.236496)
			(xy 416.775275 -26.173248) (xy 416.815836 -26.11446) (xy 416.863186 -26.060988) (xy 416.916635 -26.013612)
			(xy 416.975403 -25.973023) (xy 417.038635 -25.939812) (xy 417.105408 -25.914463) (xy 417.17475 -25.897346)
			(xy 417.245649 -25.888709) (xy 417.28136 -25.888188) (xy 417.314522 -25.888667) (xy 417.380427 -25.896119)
			(xy 417.445084 -25.9109) (xy 417.50768 -25.932825) (xy 417.567429 -25.961618) (xy 417.623581 -25.996917)
			(xy 417.675428 -26.038279) (xy 417.69919 -26.061416) (xy 417.80206 -26.164286) (xy 417.809461 -26.171124)
			(xy 417.828059 -26.178839) (xy 417.838128 -26.179272) (xy 417.89604 -26.179272) (xy 417.929194 -26.179738)
			(xy 417.995086 -26.187162) (xy 418.059733 -26.201911) (xy 418.122324 -26.223802) (xy 418.182073 -26.252558)
			(xy 418.238229 -26.287819) (xy 418.290087 -26.329142) (xy 418.31387 -26.352246) (xy 418.322506 -26.360882)
			(xy 419.389558 -26.360882) (xy 419.393629 -26.30526) (xy 419.405755 -26.250823) (xy 419.425678 -26.198732)
			(xy 419.452974 -26.150097) (xy 419.48706 -26.105954) (xy 419.527209 -26.067245) (xy 419.572567 -26.034794)
			(xy 419.622167 -26.009293) (xy 419.674951 -25.991286) (xy 419.729794 -25.981156) (xy 419.785528 -25.979119)
			(xy 419.840965 -25.985219) (xy 419.894922 -25.999325) (xy 419.946251 -26.021137) (xy 419.993857 -26.050191)
			(xy 420.036725 -26.085866) (xy 420.073942 -26.127403) (xy 420.104715 -26.173916) (xy 420.128387 -26.224413)
			(xy 420.144455 -26.27782) (xy 420.150623 -26.319734) (xy 425.141896 -26.319734) (xy 425.145967 -26.264112)
			(xy 425.158093 -26.209675) (xy 425.178016 -26.157584) (xy 425.205312 -26.108949) (xy 425.239398 -26.064806)
			(xy 425.279547 -26.026097) (xy 425.324905 -25.993646) (xy 425.374505 -25.968145) (xy 425.427289 -25.950138)
			(xy 425.482132 -25.940008) (xy 425.537866 -25.937971) (xy 425.593303 -25.944071) (xy 425.64726 -25.958177)
			(xy 425.698589 -25.979989) (xy 425.746195 -26.009043) (xy 425.77586 -26.03373) (xy 431.567842 -26.03373)
			(xy 431.571913 -25.978108) (xy 431.584039 -25.923671) (xy 431.603962 -25.87158) (xy 431.631258 -25.822945)
			(xy 431.665344 -25.778802) (xy 431.705493 -25.740093) (xy 431.750851 -25.707642) (xy 431.800451 -25.682141)
			(xy 431.853235 -25.664134) (xy 431.908078 -25.654004) (xy 431.963812 -25.651967) (xy 432.019249 -25.658067)
			(xy 432.073206 -25.672173) (xy 432.124535 -25.693985) (xy 432.172141 -25.723039) (xy 432.215009 -25.758714)
			(xy 432.252226 -25.800251) (xy 432.282999 -25.846764) (xy 432.306671 -25.897261) (xy 432.322739 -25.950668)
			(xy 432.330859 -26.005844) (xy 432.331368 -26.03373) (xy 432.330859 -26.061616) (xy 432.322739 -26.116792)
			(xy 432.306671 -26.170199) (xy 432.282999 -26.220696) (xy 432.252765 -26.266394) (xy 434.820568 -26.266394)
			(xy 434.821054 -26.239143) (xy 434.82881 -26.185195) (xy 434.844165 -26.1329) (xy 434.866807 -26.083323)
			(xy 434.896273 -26.037473) (xy 434.931964 -25.996282) (xy 434.973155 -25.960591) (xy 435.019005 -25.931125)
			(xy 435.068582 -25.908483) (xy 435.120877 -25.893128) (xy 435.174825 -25.885372) (xy 435.229327 -25.885372)
			(xy 435.283275 -25.893128) (xy 435.33557 -25.908483) (xy 435.385147 -25.931125) (xy 435.430997 -25.960591)
			(xy 435.472188 -25.996282) (xy 435.507879 -26.037473) (xy 435.537345 -26.083323) (xy 435.559987 -26.1329)
			(xy 435.575342 -26.185195) (xy 435.583098 -26.239143) (xy 435.583584 -26.266394) (xy 435.583038 -26.295882)
			(xy 435.573943 -26.354153) (xy 435.555984 -26.410329) (xy 435.52959 -26.463069) (xy 435.49539 -26.511117)
			(xy 435.454199 -26.553326) (xy 435.43093 -26.571448) (xy 435.419784 -26.580314) (xy 435.402609 -26.603026)
			(xy 435.392368 -26.629594) (xy 435.389857 -26.657958) (xy 435.39527 -26.685912) (xy 435.408187 -26.711288)
			(xy 435.427605 -26.732114) (xy 435.439566 -26.73985) (xy 435.463295 -26.754767) (xy 435.506532 -26.790429)
			(xy 435.544085 -26.832034) (xy 435.575147 -26.878686) (xy 435.599048 -26.929381) (xy 435.615274 -26.983027)
			(xy 435.623475 -27.038471) (xy 435.62397 -27.066494) (xy 435.623484 -27.093745) (xy 435.615728 -27.147693)
			(xy 435.600373 -27.199988) (xy 435.577731 -27.249565) (xy 435.548265 -27.295415) (xy 435.512574 -27.336606)
			(xy 435.471383 -27.372297) (xy 435.425533 -27.401763) (xy 435.375956 -27.424405) (xy 435.323661 -27.43976)
			(xy 435.269713 -27.447516) (xy 435.215211 -27.447516) (xy 435.161263 -27.43976) (xy 435.108968 -27.424405)
			(xy 435.059391 -27.401763) (xy 435.013541 -27.372297) (xy 434.97235 -27.336606) (xy 434.936659 -27.295415)
			(xy 434.907193 -27.249565) (xy 434.884551 -27.199988) (xy 434.869196 -27.147693) (xy 434.86144 -27.093745)
			(xy 434.860954 -27.066494) (xy 434.861515 -27.037007) (xy 434.870611 -26.978738) (xy 434.888568 -26.922563)
			(xy 434.91496 -26.869823) (xy 434.949156 -26.821775) (xy 434.990342 -26.779564) (xy 435.013608 -26.76144)
			(xy 435.024673 -26.752476) (xy 435.041858 -26.729791) (xy 435.052113 -26.703243) (xy 435.054638 -26.674895)
			(xy 435.049239 -26.646953) (xy 435.036334 -26.621587) (xy 435.016927 -26.60077) (xy 435.004972 -26.593038)
			(xy 434.981224 -26.578151) (xy 434.93799 -26.542482) (xy 434.90044 -26.50087) (xy 434.869382 -26.454213)
			(xy 434.845484 -26.403514) (xy 434.829261 -26.349865) (xy 434.821062 -26.294419) (xy 434.820568 -26.266394)
			(xy 432.252765 -26.266394) (xy 432.252226 -26.267209) (xy 432.215009 -26.308746) (xy 432.172141 -26.344421)
			(xy 432.124535 -26.373475) (xy 432.073206 -26.395287) (xy 432.019249 -26.409393) (xy 431.963812 -26.415493)
			(xy 431.908078 -26.413456) (xy 431.853235 -26.403326) (xy 431.800451 -26.385319) (xy 431.750851 -26.359818)
			(xy 431.705493 -26.327367) (xy 431.665344 -26.288658) (xy 431.631258 -26.244515) (xy 431.603962 -26.19588)
			(xy 431.584039 -26.143789) (xy 431.571913 -26.089352) (xy 431.567842 -26.03373) (xy 425.77586 -26.03373)
			(xy 425.789063 -26.044718) (xy 425.82628 -26.086255) (xy 425.857053 -26.132768) (xy 425.880725 -26.183265)
			(xy 425.896793 -26.236672) (xy 425.904913 -26.291848) (xy 425.905422 -26.319734) (xy 425.904913 -26.34762)
			(xy 425.896793 -26.402796) (xy 425.880725 -26.456203) (xy 425.857053 -26.5067) (xy 425.82628 -26.553213)
			(xy 425.789063 -26.59475) (xy 425.746195 -26.630425) (xy 425.698589 -26.659479) (xy 425.64726 -26.681291)
			(xy 425.593303 -26.695397) (xy 425.537866 -26.701497) (xy 425.482132 -26.69946) (xy 425.427289 -26.68933)
			(xy 425.374505 -26.671323) (xy 425.324905 -26.645822) (xy 425.279547 -26.613371) (xy 425.239398 -26.574662)
			(xy 425.205312 -26.530519) (xy 425.178016 -26.481884) (xy 425.158093 -26.429793) (xy 425.145967 -26.375356)
			(xy 425.141896 -26.319734) (xy 420.150623 -26.319734) (xy 420.152575 -26.332996) (xy 420.153084 -26.360882)
			(xy 420.152575 -26.388768) (xy 420.144455 -26.443944) (xy 420.128387 -26.497351) (xy 420.104715 -26.547848)
			(xy 420.073942 -26.594361) (xy 420.036725 -26.635898) (xy 419.993857 -26.671573) (xy 419.946251 -26.700627)
			(xy 419.894922 -26.722439) (xy 419.840965 -26.736545) (xy 419.785528 -26.742645) (xy 419.729794 -26.740608)
			(xy 419.674951 -26.730478) (xy 419.622167 -26.712471) (xy 419.572567 -26.68697) (xy 419.527209 -26.654519)
			(xy 419.48706 -26.61581) (xy 419.452974 -26.571667) (xy 419.425678 -26.523032) (xy 419.405755 -26.470941)
			(xy 419.393629 -26.416504) (xy 419.389558 -26.360882) (xy 418.322506 -26.360882) (xy 418.60597 -26.644346)
			(xy 418.633449 -26.672768) (xy 418.681401 -26.735624) (xy 418.720563 -26.8043) (xy 418.736018 -26.840688)
			(xy 418.73678 -26.84272) (xy 418.749055 -26.870931) (xy 418.768268 -26.929381) (xy 418.777267 -26.971244)
			(xy 421.151048 -26.971244) (xy 421.155119 -26.915622) (xy 421.167245 -26.861185) (xy 421.187168 -26.809094)
			(xy 421.214464 -26.760459) (xy 421.24855 -26.716316) (xy 421.288699 -26.677607) (xy 421.334057 -26.645156)
			(xy 421.383657 -26.619655) (xy 421.436441 -26.601648) (xy 421.491284 -26.591518) (xy 421.547018 -26.589481)
			(xy 421.602455 -26.595581) (xy 421.656412 -26.609687) (xy 421.707741 -26.631499) (xy 421.755347 -26.660553)
			(xy 421.798215 -26.696228) (xy 421.835432 -26.737765) (xy 421.866205 -26.784278) (xy 421.889877 -26.834775)
			(xy 421.905945 -26.888182) (xy 421.914065 -26.943358) (xy 421.914574 -26.971244) (xy 421.914065 -26.99913)
			(xy 421.905945 -27.054306) (xy 421.889877 -27.107713) (xy 421.866205 -27.15821) (xy 421.835432 -27.204723)
			(xy 421.798215 -27.24626) (xy 421.755347 -27.281935) (xy 421.707741 -27.310989) (xy 421.656412 -27.332801)
			(xy 421.602455 -27.346907) (xy 421.547018 -27.353007) (xy 421.491284 -27.35097) (xy 421.436441 -27.34084)
			(xy 421.383657 -27.322833) (xy 421.334057 -27.297332) (xy 421.288699 -27.264881) (xy 421.24855 -27.226172)
			(xy 421.214464 -27.182029) (xy 421.187168 -27.133394) (xy 421.167245 -27.081303) (xy 421.155119 -27.026866)
			(xy 421.151048 -26.971244) (xy 418.777267 -26.971244) (xy 418.781199 -26.989534) (xy 418.787702 -27.050717)
			(xy 418.788088 -27.08148) (xy 418.788088 -29.114242) (xy 419.147244 -29.114242) (xy 419.147244 -28.250642)
			(xy 419.147734 -28.220658) (xy 419.155562 -28.161202) (xy 419.171083 -28.103277) (xy 419.194032 -28.047873)
			(xy 419.224016 -27.995939) (xy 419.260522 -27.948363) (xy 419.302927 -27.905958) (xy 419.350503 -27.869452)
			(xy 419.402437 -27.839468) (xy 419.457841 -27.816519) (xy 419.515766 -27.800998) (xy 419.575222 -27.79317)
			(xy 419.63519 -27.79317) (xy 419.694646 -27.800998) (xy 419.752571 -27.816519) (xy 419.807975 -27.839468)
			(xy 419.859909 -27.869452) (xy 419.907485 -27.905958) (xy 419.94989 -27.948363) (xy 419.986396 -27.995939)
			(xy 420.01638 -28.047873) (xy 420.039329 -28.103277) (xy 420.05485 -28.161202) (xy 420.062678 -28.220658)
			(xy 420.063168 -28.250642) (xy 420.063168 -28.469082) (xy 424.05249 -28.469082) (xy 424.056561 -28.41346)
			(xy 424.068687 -28.359023) (xy 424.08861 -28.306932) (xy 424.115906 -28.258297) (xy 424.149992 -28.214154)
			(xy 424.190141 -28.175445) (xy 424.235499 -28.142994) (xy 424.285099 -28.117493) (xy 424.337883 -28.099486)
			(xy 424.392726 -28.089356) (xy 424.44846 -28.087319) (xy 424.503897 -28.093419) (xy 424.557854 -28.107525)
			(xy 424.609183 -28.129337) (xy 424.625239 -28.139136) (xy 428.697896 -28.139136) (xy 428.701967 -28.083514)
			(xy 428.714093 -28.029077) (xy 428.734016 -27.976986) (xy 428.761312 -27.928351) (xy 428.795398 -27.884208)
			(xy 428.835547 -27.845499) (xy 428.880905 -27.813048) (xy 428.930505 -27.787547) (xy 428.983289 -27.76954)
			(xy 429.038132 -27.75941) (xy 429.093866 -27.757373) (xy 429.149303 -27.763473) (xy 429.20326 -27.777579)
			(xy 429.254589 -27.799391) (xy 429.302195 -27.828445) (xy 429.345063 -27.86412) (xy 429.38228 -27.905657)
			(xy 429.413053 -27.95217) (xy 429.436725 -28.002667) (xy 429.452793 -28.056074) (xy 429.460913 -28.11125)
			(xy 429.461422 -28.139136) (xy 429.967896 -28.139136) (xy 429.971967 -28.083514) (xy 429.984093 -28.029077)
			(xy 430.004016 -27.976986) (xy 430.031312 -27.928351) (xy 430.065398 -27.884208) (xy 430.105547 -27.845499)
			(xy 430.150905 -27.813048) (xy 430.200505 -27.787547) (xy 430.253289 -27.76954) (xy 430.308132 -27.75941)
			(xy 430.363866 -27.757373) (xy 430.419303 -27.763473) (xy 430.47326 -27.777579) (xy 430.524589 -27.799391)
			(xy 430.572195 -27.828445) (xy 430.615063 -27.86412) (xy 430.65228 -27.905657) (xy 430.683053 -27.95217)
			(xy 430.706725 -28.002667) (xy 430.722793 -28.056074) (xy 430.730913 -28.11125) (xy 430.731422 -28.139136)
			(xy 430.730913 -28.167022) (xy 430.722793 -28.222198) (xy 430.706725 -28.275605) (xy 430.683053 -28.326102)
			(xy 430.65228 -28.372615) (xy 430.615063 -28.414152) (xy 430.572195 -28.449827) (xy 430.524589 -28.478881)
			(xy 430.47326 -28.500693) (xy 430.419303 -28.514799) (xy 430.363866 -28.520899) (xy 430.308132 -28.518862)
			(xy 430.253289 -28.508732) (xy 430.200505 -28.490725) (xy 430.150905 -28.465224) (xy 430.105547 -28.432773)
			(xy 430.065398 -28.394064) (xy 430.031312 -28.349921) (xy 430.004016 -28.301286) (xy 429.984093 -28.249195)
			(xy 429.971967 -28.194758) (xy 429.967896 -28.139136) (xy 429.461422 -28.139136) (xy 429.460913 -28.167022)
			(xy 429.452793 -28.222198) (xy 429.436725 -28.275605) (xy 429.413053 -28.326102) (xy 429.38228 -28.372615)
			(xy 429.345063 -28.414152) (xy 429.302195 -28.449827) (xy 429.254589 -28.478881) (xy 429.20326 -28.500693)
			(xy 429.149303 -28.514799) (xy 429.093866 -28.520899) (xy 429.038132 -28.518862) (xy 428.983289 -28.508732)
			(xy 428.930505 -28.490725) (xy 428.880905 -28.465224) (xy 428.835547 -28.432773) (xy 428.795398 -28.394064)
			(xy 428.761312 -28.349921) (xy 428.734016 -28.301286) (xy 428.714093 -28.249195) (xy 428.701967 -28.194758)
			(xy 428.697896 -28.139136) (xy 424.625239 -28.139136) (xy 424.656789 -28.158391) (xy 424.699657 -28.194066)
			(xy 424.736874 -28.235603) (xy 424.767647 -28.282116) (xy 424.791319 -28.332613) (xy 424.807387 -28.38602)
			(xy 424.815507 -28.441196) (xy 424.816016 -28.469082) (xy 424.815507 -28.496968) (xy 424.807387 -28.552144)
			(xy 424.791319 -28.605551) (xy 424.767647 -28.656048) (xy 424.736874 -28.702561) (xy 424.699657 -28.744098)
			(xy 424.656789 -28.779773) (xy 424.609183 -28.808827) (xy 424.557854 -28.830639) (xy 424.503897 -28.844745)
			(xy 424.44846 -28.850845) (xy 424.392726 -28.848808) (xy 424.337883 -28.838678) (xy 424.285099 -28.820671)
			(xy 424.235499 -28.79517) (xy 424.190141 -28.762719) (xy 424.149992 -28.72401) (xy 424.115906 -28.679867)
			(xy 424.08861 -28.631232) (xy 424.068687 -28.579141) (xy 424.056561 -28.524704) (xy 424.05249 -28.469082)
			(xy 420.063168 -28.469082) (xy 420.063168 -29.114242) (xy 420.063035 -29.12237) (xy 434.906928 -29.12237)
			(xy 434.906928 -28.25877) (xy 434.907418 -28.228802) (xy 434.915241 -28.16938) (xy 434.930754 -28.111487)
			(xy 434.95369 -28.056114) (xy 434.983657 -28.004208) (xy 435.020144 -27.956658) (xy 435.062524 -27.914278)
			(xy 435.110074 -27.877791) (xy 435.16198 -27.847824) (xy 435.217353 -27.824888) (xy 435.275246 -27.809375)
			(xy 435.334668 -27.801552) (xy 435.394604 -27.801552) (xy 435.454026 -27.809375) (xy 435.511919 -27.824888)
			(xy 435.567292 -27.847824) (xy 435.619198 -27.877791) (xy 435.666748 -27.914278) (xy 435.709128 -27.956658)
			(xy 435.745615 -28.004208) (xy 435.775582 -28.056114) (xy 435.798518 -28.111487) (xy 435.814031 -28.16938)
			(xy 435.821854 -28.228802) (xy 435.822344 -28.25877) (xy 435.822344 -29.12237) (xy 435.821854 -29.152338)
			(xy 435.814031 -29.21176) (xy 435.798518 -29.269653) (xy 435.775582 -29.325026) (xy 435.745615 -29.376932)
			(xy 435.709128 -29.424482) (xy 435.666748 -29.466862) (xy 435.619198 -29.503349) (xy 435.567292 -29.533316)
			(xy 435.511919 -29.556252) (xy 435.454026 -29.571765) (xy 435.394604 -29.579588) (xy 435.334668 -29.579588)
			(xy 435.275246 -29.571765) (xy 435.217353 -29.556252) (xy 435.16198 -29.533316) (xy 435.110074 -29.503349)
			(xy 435.062524 -29.466862) (xy 435.020144 -29.424482) (xy 434.983657 -29.376932) (xy 434.95369 -29.325026)
			(xy 434.930754 -29.269653) (xy 434.915241 -29.21176) (xy 434.907418 -29.152338) (xy 434.906928 -29.12237)
			(xy 420.063035 -29.12237) (xy 420.062678 -29.144226) (xy 420.05485 -29.203682) (xy 420.039329 -29.261607)
			(xy 420.01638 -29.317011) (xy 419.986396 -29.368945) (xy 419.94989 -29.416521) (xy 419.907485 -29.458926)
			(xy 419.859909 -29.495432) (xy 419.807975 -29.525416) (xy 419.752571 -29.548365) (xy 419.694646 -29.563886)
			(xy 419.63519 -29.571714) (xy 419.575222 -29.571714) (xy 419.515766 -29.563886) (xy 419.457841 -29.548365)
			(xy 419.402437 -29.525416) (xy 419.350503 -29.495432) (xy 419.302927 -29.458926) (xy 419.260522 -29.416521)
			(xy 419.224016 -29.368945) (xy 419.194032 -29.317011) (xy 419.171083 -29.261607) (xy 419.155562 -29.203682)
			(xy 419.147734 -29.144226) (xy 419.147244 -29.114242) (xy 418.788088 -29.114242) (xy 418.788088 -30.92069)
			(xy 421.789352 -30.92069) (xy 421.789352 -30.05709) (xy 421.789842 -30.027106) (xy 421.79767 -29.96765)
			(xy 421.813191 -29.909725) (xy 421.83614 -29.854321) (xy 421.866124 -29.802387) (xy 421.90263 -29.754811)
			(xy 421.945035 -29.712406) (xy 421.992611 -29.6759) (xy 422.044545 -29.645916) (xy 422.099949 -29.622967)
			(xy 422.157874 -29.607446) (xy 422.21733 -29.599618) (xy 422.277298 -29.599618) (xy 422.336754 -29.607446)
			(xy 422.394679 -29.622967) (xy 422.450083 -29.645916) (xy 422.502017 -29.6759) (xy 422.549593 -29.712406)
			(xy 422.591998 -29.754811) (xy 422.628504 -29.802387) (xy 422.658488 -29.854321) (xy 422.681437 -29.909725)
			(xy 422.696958 -29.96765) (xy 422.704786 -30.027106) (xy 422.705276 -30.05709) (xy 422.705276 -30.376876)
			(xy 427.188884 -30.376876) (xy 427.189425 -30.34796) (xy 427.198145 -30.290788) (xy 427.215396 -30.235588)
			(xy 427.240784 -30.183626) (xy 427.273725 -30.136092) (xy 427.313465 -30.094076) (xy 427.33595 -30.075886)
			(xy 427.344762 -30.068284) (xy 427.354941 -30.047379) (xy 427.355508 -30.035754) (xy 427.355508 -29.955998)
			(xy 427.354953 -29.944368) (xy 427.344775 -29.923459) (xy 427.33595 -29.915866) (xy 427.31344 -29.897707)
			(xy 427.273709 -29.855679) (xy 427.240774 -29.808137) (xy 427.215391 -29.75617) (xy 427.19814 -29.700967)
			(xy 427.189416 -29.643794) (xy 427.188884 -29.614876) (xy 427.18937 -29.587625) (xy 427.197126 -29.533677)
			(xy 427.212481 -29.481382) (xy 427.235123 -29.431805) (xy 427.264589 -29.385955) (xy 427.30028 -29.344764)
			(xy 427.341471 -29.309073) (xy 427.387321 -29.279607) (xy 427.436898 -29.256965) (xy 427.489193 -29.24161)
			(xy 427.543141 -29.233854) (xy 427.597643 -29.233854) (xy 427.651591 -29.24161) (xy 427.703886 -29.256965)
			(xy 427.753463 -29.279607) (xy 427.799313 -29.309073) (xy 427.840504 -29.344764) (xy 427.876195 -29.385955)
			(xy 427.905661 -29.431805) (xy 427.928303 -29.481382) (xy 427.943658 -29.533677) (xy 427.951414 -29.587625)
			(xy 427.9519 -29.614876) (xy 427.951364 -29.643792) (xy 427.942639 -29.700963) (xy 427.925384 -29.756161)
			(xy 427.899996 -29.808123) (xy 427.867056 -29.855657) (xy 427.827318 -29.897675) (xy 427.804834 -29.915866)
			(xy 427.796041 -29.923486) (xy 427.785852 -29.944378) (xy 427.785276 -29.955998) (xy 427.785276 -30.035754)
			(xy 427.785772 -30.047392) (xy 427.795988 -30.068303) (xy 427.804834 -30.075886) (xy 427.827318 -30.094076)
			(xy 427.867051 -30.136097) (xy 427.899989 -30.183633) (xy 427.925377 -30.235594) (xy 427.942634 -30.290791)
			(xy 427.951364 -30.34796) (xy 427.9519 -30.376876) (xy 430.22901 -30.376876) (xy 430.229579 -30.347961)
			(xy 430.238297 -30.290792) (xy 430.255545 -30.235594) (xy 430.280927 -30.183632) (xy 430.313861 -30.136097)
			(xy 430.353594 -30.094078) (xy 430.376076 -30.075886) (xy 430.384892 -30.068288) (xy 430.395068 -30.04738)
			(xy 430.395634 -30.035754) (xy 430.395634 -29.955998) (xy 430.395105 -29.944364) (xy 430.384912 -29.923453)
			(xy 430.376076 -29.915866) (xy 430.353571 -29.8977) (xy 430.313838 -29.855675) (xy 430.280903 -29.808134)
			(xy 430.255518 -29.756168) (xy 430.238266 -29.700966) (xy 430.229542 -29.643793) (xy 430.22901 -29.614876)
			(xy 430.229496 -29.587625) (xy 430.237252 -29.533677) (xy 430.252607 -29.481382) (xy 430.275249 -29.431805)
			(xy 430.304715 -29.385955) (xy 430.340406 -29.344764) (xy 430.381597 -29.309073) (xy 430.427447 -29.279607)
			(xy 430.477024 -29.256965) (xy 430.529319 -29.24161) (xy 430.583267 -29.233854) (xy 430.637769 -29.233854)
			(xy 430.691717 -29.24161) (xy 430.744012 -29.256965) (xy 430.793589 -29.279607) (xy 430.839439 -29.309073)
			(xy 430.88063 -29.344764) (xy 430.916321 -29.385955) (xy 430.945787 -29.431805) (xy 430.968429 -29.481382)
			(xy 430.983784 -29.533677) (xy 430.99154 -29.587625) (xy 430.992026 -29.614876) (xy 430.991519 -29.643794)
			(xy 430.982791 -29.700967) (xy 430.965533 -29.756167) (xy 430.94014 -29.808129) (xy 430.907193 -29.855663)
			(xy 430.867448 -29.897678) (xy 430.84496 -29.915866) (xy 430.836172 -29.923491) (xy 430.825979 -29.944378)
			(xy 430.825402 -29.955998) (xy 430.825402 -30.035754) (xy 430.825924 -30.047388) (xy 430.836125 -30.068297)
			(xy 430.84496 -30.075886) (xy 430.867428 -30.094095) (xy 430.907166 -30.13611) (xy 430.940108 -30.183641)
			(xy 430.9655 -30.235599) (xy 430.982759 -30.290793) (xy 430.99149 -30.347961) (xy 430.992026 -30.376876)
			(xy 430.99154 -30.404127) (xy 430.983784 -30.458075) (xy 430.968429 -30.51037) (xy 430.945787 -30.559947)
			(xy 430.916321 -30.605797) (xy 430.88063 -30.646988) (xy 430.839439 -30.682679) (xy 430.793589 -30.712145)
			(xy 430.744012 -30.734787) (xy 430.691717 -30.750142) (xy 430.637769 -30.757898) (xy 430.583267 -30.757898)
			(xy 430.529319 -30.750142) (xy 430.477024 -30.734787) (xy 430.427447 -30.712145) (xy 430.381597 -30.682679)
			(xy 430.340406 -30.646988) (xy 430.304715 -30.605797) (xy 430.275249 -30.559947) (xy 430.252607 -30.51037)
			(xy 430.237252 -30.458075) (xy 430.229496 -30.404127) (xy 430.22901 -30.376876) (xy 427.9519 -30.376876)
			(xy 427.951414 -30.404127) (xy 427.943658 -30.458075) (xy 427.928303 -30.51037) (xy 427.905661 -30.559947)
			(xy 427.876195 -30.605797) (xy 427.840504 -30.646988) (xy 427.799313 -30.682679) (xy 427.753463 -30.712145)
			(xy 427.703886 -30.734787) (xy 427.651591 -30.750142) (xy 427.597643 -30.757898) (xy 427.543141 -30.757898)
			(xy 427.489193 -30.750142) (xy 427.436898 -30.734787) (xy 427.387321 -30.712145) (xy 427.341471 -30.682679)
			(xy 427.30028 -30.646988) (xy 427.264589 -30.605797) (xy 427.235123 -30.559947) (xy 427.212481 -30.51037)
			(xy 427.197126 -30.458075) (xy 427.18937 -30.404127) (xy 427.188884 -30.376876) (xy 422.705276 -30.376876)
			(xy 422.705276 -30.92069) (xy 422.705247 -30.922468) (xy 433.052728 -30.922468) (xy 433.052728 -30.058868)
			(xy 433.053218 -30.0289) (xy 433.061041 -29.969478) (xy 433.076554 -29.911585) (xy 433.09949 -29.856212)
			(xy 433.129457 -29.804306) (xy 433.165944 -29.756756) (xy 433.208324 -29.714376) (xy 433.255874 -29.677889)
			(xy 433.30778 -29.647922) (xy 433.363153 -29.624986) (xy 433.421046 -29.609473) (xy 433.480468 -29.60165)
			(xy 433.540404 -29.60165) (xy 433.599826 -29.609473) (xy 433.657719 -29.624986) (xy 433.713092 -29.647922)
			(xy 433.764998 -29.677889) (xy 433.812548 -29.714376) (xy 433.854928 -29.756756) (xy 433.891415 -29.804306)
			(xy 433.921382 -29.856212) (xy 433.944318 -29.911585) (xy 433.959831 -29.969478) (xy 433.967654 -30.0289)
			(xy 433.968144 -30.058868) (xy 433.968144 -30.922468) (xy 433.967654 -30.952436) (xy 433.959831 -31.011858)
			(xy 433.944318 -31.069751) (xy 433.921382 -31.125124) (xy 433.891415 -31.17703) (xy 433.854928 -31.22458)
			(xy 433.812548 -31.26696) (xy 433.764998 -31.303447) (xy 433.713092 -31.333414) (xy 433.657719 -31.35635)
			(xy 433.599826 -31.371863) (xy 433.540404 -31.379686) (xy 433.480468 -31.379686) (xy 433.421046 -31.371863)
			(xy 433.363153 -31.35635) (xy 433.30778 -31.333414) (xy 433.255874 -31.303447) (xy 433.208324 -31.26696)
			(xy 433.165944 -31.22458) (xy 433.129457 -31.17703) (xy 433.09949 -31.125124) (xy 433.076554 -31.069751)
			(xy 433.061041 -31.011858) (xy 433.053218 -30.952436) (xy 433.052728 -30.922468) (xy 422.705247 -30.922468)
			(xy 422.704786 -30.950674) (xy 422.696958 -31.01013) (xy 422.681437 -31.068055) (xy 422.658488 -31.123459)
			(xy 422.628504 -31.175393) (xy 422.591998 -31.222969) (xy 422.549593 -31.265374) (xy 422.502017 -31.30188)
			(xy 422.450083 -31.331864) (xy 422.394679 -31.354813) (xy 422.336754 -31.370334) (xy 422.277298 -31.378162)
			(xy 422.21733 -31.378162) (xy 422.157874 -31.370334) (xy 422.099949 -31.354813) (xy 422.044545 -31.331864)
			(xy 421.992611 -31.30188) (xy 421.945035 -31.265374) (xy 421.90263 -31.222969) (xy 421.866124 -31.175393)
			(xy 421.83614 -31.123459) (xy 421.813191 -31.068055) (xy 421.79767 -31.01013) (xy 421.789842 -30.950674)
			(xy 421.789352 -30.92069) (xy 418.788088 -30.92069) (xy 418.788088 -32.714184) (xy 419.147244 -32.714184)
			(xy 419.147244 -31.850584) (xy 419.147734 -31.8206) (xy 419.155562 -31.761144) (xy 419.171083 -31.703219)
			(xy 419.194032 -31.647815) (xy 419.224016 -31.595881) (xy 419.260522 -31.548305) (xy 419.302927 -31.5059)
			(xy 419.350503 -31.469394) (xy 419.402437 -31.43941) (xy 419.457841 -31.416461) (xy 419.515766 -31.40094)
			(xy 419.575222 -31.393112) (xy 419.63519 -31.393112) (xy 419.694646 -31.40094) (xy 419.752571 -31.416461)
			(xy 419.807975 -31.43941) (xy 419.859909 -31.469394) (xy 419.907485 -31.5059) (xy 419.94989 -31.548305)
			(xy 419.964912 -31.567882) (xy 427.29861 -31.567882) (xy 427.302681 -31.51226) (xy 427.314807 -31.457823)
			(xy 427.33473 -31.405732) (xy 427.362026 -31.357097) (xy 427.396112 -31.312954) (xy 427.436261 -31.274245)
			(xy 427.481619 -31.241794) (xy 427.531219 -31.216293) (xy 427.584003 -31.198286) (xy 427.638846 -31.188156)
			(xy 427.69458 -31.186119) (xy 427.750017 -31.192219) (xy 427.803974 -31.206325) (xy 427.855303 -31.228137)
			(xy 427.902909 -31.257191) (xy 427.945777 -31.292866) (xy 427.982994 -31.334403) (xy 428.013767 -31.380916)
			(xy 428.037439 -31.431413) (xy 428.053507 -31.48482) (xy 428.061627 -31.539996) (xy 428.062136 -31.567882)
			(xy 428.061627 -31.595768) (xy 428.053507 -31.650944) (xy 428.037439 -31.704351) (xy 428.030447 -31.719266)
			(xy 428.585374 -31.719266) (xy 428.589445 -31.663644) (xy 428.601571 -31.609207) (xy 428.621494 -31.557116)
			(xy 428.64879 -31.508481) (xy 428.682876 -31.464338) (xy 428.723025 -31.425629) (xy 428.768383 -31.393178)
			(xy 428.817983 -31.367677) (xy 428.870767 -31.34967) (xy 428.92561 -31.33954) (xy 428.981344 -31.337503)
			(xy 429.036781 -31.343603) (xy 429.090738 -31.357709) (xy 429.142067 -31.379521) (xy 429.189673 -31.408575)
			(xy 429.232541 -31.44425) (xy 429.269758 -31.485787) (xy 429.300531 -31.5323) (xy 429.324203 -31.582797)
			(xy 429.340271 -31.636204) (xy 429.344421 -31.664402) (xy 429.860962 -31.664402) (xy 429.865033 -31.60878)
			(xy 429.877159 -31.554343) (xy 429.897082 -31.502252) (xy 429.924378 -31.453617) (xy 429.958464 -31.409474)
			(xy 429.998613 -31.370765) (xy 430.043971 -31.338314) (xy 430.093571 -31.312813) (xy 430.146355 -31.294806)
			(xy 430.201198 -31.284676) (xy 430.256932 -31.282639) (xy 430.312369 -31.288739) (xy 430.366326 -31.302845)
			(xy 430.417655 -31.324657) (xy 430.465261 -31.353711) (xy 430.508129 -31.389386) (xy 430.545346 -31.430923)
			(xy 430.576119 -31.477436) (xy 430.599791 -31.527933) (xy 430.615859 -31.58134) (xy 430.623979 -31.636516)
			(xy 430.624488 -31.664402) (xy 430.623979 -31.692288) (xy 430.615859 -31.747464) (xy 430.606919 -31.777178)
			(xy 431.126136 -31.777178) (xy 431.130207 -31.721556) (xy 431.142333 -31.667119) (xy 431.162256 -31.615028)
			(xy 431.189552 -31.566393) (xy 431.223638 -31.52225) (xy 431.263787 -31.483541) (xy 431.309145 -31.45109)
			(xy 431.358745 -31.425589) (xy 431.411529 -31.407582) (xy 431.466372 -31.397452) (xy 431.522106 -31.395415)
			(xy 431.577543 -31.401515) (xy 431.6315 -31.415621) (xy 431.682829 -31.437433) (xy 431.730435 -31.466487)
			(xy 431.773303 -31.502162) (xy 431.81052 -31.543699) (xy 431.841293 -31.590212) (xy 431.864965 -31.640709)
			(xy 431.881033 -31.694116) (xy 431.889153 -31.749292) (xy 431.889662 -31.777178) (xy 431.889153 -31.805064)
			(xy 431.881033 -31.86024) (xy 431.864965 -31.913647) (xy 431.841293 -31.964144) (xy 431.81052 -32.010657)
			(xy 431.773303 -32.052194) (xy 431.730435 -32.087869) (xy 431.682829 -32.116923) (xy 431.6315 -32.138735)
			(xy 431.577543 -32.152841) (xy 431.522106 -32.158941) (xy 431.466372 -32.156904) (xy 431.411529 -32.146774)
			(xy 431.358745 -32.128767) (xy 431.309145 -32.103266) (xy 431.263787 -32.070815) (xy 431.223638 -32.032106)
			(xy 431.189552 -31.987963) (xy 431.162256 -31.939328) (xy 431.142333 -31.887237) (xy 431.130207 -31.8328)
			(xy 431.126136 -31.777178) (xy 430.606919 -31.777178) (xy 430.599791 -31.800871) (xy 430.576119 -31.851368)
			(xy 430.545346 -31.897881) (xy 430.508129 -31.939418) (xy 430.465261 -31.975093) (xy 430.417655 -32.004147)
			(xy 430.366326 -32.025959) (xy 430.312369 -32.040065) (xy 430.256932 -32.046165) (xy 430.201198 -32.044128)
			(xy 430.146355 -32.033998) (xy 430.093571 -32.015991) (xy 430.043971 -31.99049) (xy 429.998613 -31.958039)
			(xy 429.958464 -31.91933) (xy 429.924378 -31.875187) (xy 429.897082 -31.826552) (xy 429.877159 -31.774461)
			(xy 429.865033 -31.720024) (xy 429.860962 -31.664402) (xy 429.344421 -31.664402) (xy 429.348391 -31.69138)
			(xy 429.3489 -31.719266) (xy 429.348391 -31.747152) (xy 429.340271 -31.802328) (xy 429.324203 -31.855735)
			(xy 429.300531 -31.906232) (xy 429.269758 -31.952745) (xy 429.232541 -31.994282) (xy 429.189673 -32.029957)
			(xy 429.142067 -32.059011) (xy 429.090738 -32.080823) (xy 429.036781 -32.094929) (xy 428.981344 -32.101029)
			(xy 428.92561 -32.098992) (xy 428.870767 -32.088862) (xy 428.817983 -32.070855) (xy 428.768383 -32.045354)
			(xy 428.723025 -32.012903) (xy 428.682876 -31.974194) (xy 428.64879 -31.930051) (xy 428.621494 -31.881416)
			(xy 428.601571 -31.829325) (xy 428.589445 -31.774888) (xy 428.585374 -31.719266) (xy 428.030447 -31.719266)
			(xy 428.013767 -31.754848) (xy 427.982994 -31.801361) (xy 427.945777 -31.842898) (xy 427.902909 -31.878573)
			(xy 427.855303 -31.907627) (xy 427.803974 -31.929439) (xy 427.750017 -31.943545) (xy 427.69458 -31.949645)
			(xy 427.638846 -31.947608) (xy 427.584003 -31.937478) (xy 427.531219 -31.919471) (xy 427.481619 -31.89397)
			(xy 427.436261 -31.861519) (xy 427.396112 -31.82281) (xy 427.362026 -31.778667) (xy 427.33473 -31.730032)
			(xy 427.314807 -31.677941) (xy 427.302681 -31.623504) (xy 427.29861 -31.567882) (xy 419.964912 -31.567882)
			(xy 419.986396 -31.595881) (xy 420.01638 -31.647815) (xy 420.039329 -31.703219) (xy 420.05485 -31.761144)
			(xy 420.062678 -31.8206) (xy 420.063168 -31.850584) (xy 420.063168 -32.714184) (xy 420.063035 -32.722312)
			(xy 434.906928 -32.722312) (xy 434.906928 -31.858712) (xy 434.907418 -31.828744) (xy 434.915241 -31.769322)
			(xy 434.930754 -31.711429) (xy 434.95369 -31.656056) (xy 434.983657 -31.60415) (xy 435.020144 -31.5566)
			(xy 435.062524 -31.51422) (xy 435.110074 -31.477733) (xy 435.16198 -31.447766) (xy 435.217353 -31.42483)
			(xy 435.275246 -31.409317) (xy 435.334668 -31.401494) (xy 435.394604 -31.401494) (xy 435.454026 -31.409317)
			(xy 435.511919 -31.42483) (xy 435.567292 -31.447766) (xy 435.619198 -31.477733) (xy 435.666748 -31.51422)
			(xy 435.709128 -31.5566) (xy 435.745615 -31.60415) (xy 435.775582 -31.656056) (xy 435.798518 -31.711429)
			(xy 435.814031 -31.769322) (xy 435.821854 -31.828744) (xy 435.822344 -31.858712) (xy 435.822344 -32.722312)
			(xy 435.821854 -32.75228) (xy 435.814031 -32.811702) (xy 435.798518 -32.869595) (xy 435.775582 -32.924968)
			(xy 435.745615 -32.976874) (xy 435.709128 -33.024424) (xy 435.666748 -33.066804) (xy 435.619198 -33.103291)
			(xy 435.567292 -33.133258) (xy 435.511919 -33.156194) (xy 435.454026 -33.171707) (xy 435.394604 -33.17953)
			(xy 435.334668 -33.17953) (xy 435.275246 -33.171707) (xy 435.217353 -33.156194) (xy 435.16198 -33.133258)
			(xy 435.110074 -33.103291) (xy 435.062524 -33.066804) (xy 435.020144 -33.024424) (xy 434.983657 -32.976874)
			(xy 434.95369 -32.924968) (xy 434.930754 -32.869595) (xy 434.915241 -32.811702) (xy 434.907418 -32.75228)
			(xy 434.906928 -32.722312) (xy 420.063035 -32.722312) (xy 420.062678 -32.744168) (xy 420.05485 -32.803624)
			(xy 420.039329 -32.861549) (xy 420.01638 -32.916953) (xy 419.986396 -32.968887) (xy 419.94989 -33.016463)
			(xy 419.907485 -33.058868) (xy 419.859909 -33.095374) (xy 419.807975 -33.125358) (xy 419.752571 -33.148307)
			(xy 419.694646 -33.163828) (xy 419.63519 -33.171656) (xy 419.575222 -33.171656) (xy 419.515766 -33.163828)
			(xy 419.457841 -33.148307) (xy 419.402437 -33.125358) (xy 419.350503 -33.095374) (xy 419.302927 -33.058868)
			(xy 419.260522 -33.016463) (xy 419.224016 -32.968887) (xy 419.194032 -32.916953) (xy 419.171083 -32.861549)
			(xy 419.155562 -32.803624) (xy 419.147734 -32.744168) (xy 419.147244 -32.714184) (xy 418.788088 -32.714184)
			(xy 418.788088 -34.520886) (xy 421.789352 -34.520886) (xy 421.789352 -33.657286) (xy 421.789842 -33.627302)
			(xy 421.79767 -33.567846) (xy 421.813191 -33.509921) (xy 421.83614 -33.454517) (xy 421.866124 -33.402583)
			(xy 421.90263 -33.355007) (xy 421.945035 -33.312602) (xy 421.992611 -33.276096) (xy 422.044545 -33.246112)
			(xy 422.099949 -33.223163) (xy 422.157874 -33.207642) (xy 422.21733 -33.199814) (xy 422.277298 -33.199814)
			(xy 422.336754 -33.207642) (xy 422.394679 -33.223163) (xy 422.450083 -33.246112) (xy 422.502017 -33.276096)
			(xy 422.549593 -33.312602) (xy 422.591998 -33.355007) (xy 422.628504 -33.402583) (xy 422.658488 -33.454517)
			(xy 422.681437 -33.509921) (xy 422.696958 -33.567846) (xy 422.704786 -33.627302) (xy 422.705276 -33.657286)
			(xy 422.705276 -34.520886) (xy 422.705251 -34.52241) (xy 433.052728 -34.52241) (xy 433.052728 -33.65881)
			(xy 433.053218 -33.628842) (xy 433.061041 -33.56942) (xy 433.076554 -33.511527) (xy 433.09949 -33.456154)
			(xy 433.129457 -33.404248) (xy 433.165944 -33.356698) (xy 433.208324 -33.314318) (xy 433.255874 -33.277831)
			(xy 433.30778 -33.247864) (xy 433.363153 -33.224928) (xy 433.421046 -33.209415) (xy 433.480468 -33.201592)
			(xy 433.540404 -33.201592) (xy 433.599826 -33.209415) (xy 433.657719 -33.224928) (xy 433.713092 -33.247864)
			(xy 433.764998 -33.277831) (xy 433.812548 -33.314318) (xy 433.854928 -33.356698) (xy 433.891415 -33.404248)
			(xy 433.921382 -33.456154) (xy 433.944318 -33.511527) (xy 433.959831 -33.56942) (xy 433.967654 -33.628842)
			(xy 433.968144 -33.65881) (xy 433.968144 -34.52241) (xy 433.967654 -34.552378) (xy 433.959831 -34.6118)
			(xy 433.944318 -34.669693) (xy 433.921382 -34.725066) (xy 433.891415 -34.776972) (xy 433.854928 -34.824522)
			(xy 433.812548 -34.866902) (xy 433.764998 -34.903389) (xy 433.713092 -34.933356) (xy 433.657719 -34.956292)
			(xy 433.599826 -34.971805) (xy 433.540404 -34.979628) (xy 433.480468 -34.979628) (xy 433.421046 -34.971805)
			(xy 433.363153 -34.956292) (xy 433.30778 -34.933356) (xy 433.255874 -34.903389) (xy 433.208324 -34.866902)
			(xy 433.165944 -34.824522) (xy 433.129457 -34.776972) (xy 433.09949 -34.725066) (xy 433.076554 -34.669693)
			(xy 433.061041 -34.6118) (xy 433.053218 -34.552378) (xy 433.052728 -34.52241) (xy 422.705251 -34.52241)
			(xy 422.704786 -34.55087) (xy 422.696958 -34.610326) (xy 422.681437 -34.668251) (xy 422.658488 -34.723655)
			(xy 422.628504 -34.775589) (xy 422.591998 -34.823165) (xy 422.549593 -34.86557) (xy 422.502017 -34.902076)
			(xy 422.450083 -34.93206) (xy 422.394679 -34.955009) (xy 422.336754 -34.97053) (xy 422.277298 -34.978358)
			(xy 422.21733 -34.978358) (xy 422.157874 -34.97053) (xy 422.099949 -34.955009) (xy 422.044545 -34.93206)
			(xy 421.992611 -34.902076) (xy 421.945035 -34.86557) (xy 421.90263 -34.823165) (xy 421.866124 -34.775589)
			(xy 421.83614 -34.723655) (xy 421.813191 -34.668251) (xy 421.79767 -34.610326) (xy 421.789842 -34.55087)
			(xy 421.789352 -34.520886) (xy 418.788088 -34.520886) (xy 418.788088 -35.264852) (xy 430.202338 -35.264852)
			(xy 430.206409 -35.20923) (xy 430.218535 -35.154793) (xy 430.238458 -35.102702) (xy 430.265754 -35.054067)
			(xy 430.29984 -35.009924) (xy 430.339989 -34.971215) (xy 430.385347 -34.938764) (xy 430.434947 -34.913263)
			(xy 430.487731 -34.895256) (xy 430.542574 -34.885126) (xy 430.598308 -34.883089) (xy 430.653745 -34.889189)
			(xy 430.707702 -34.903295) (xy 430.759031 -34.925107) (xy 430.806637 -34.954161) (xy 430.849505 -34.989836)
			(xy 430.886722 -35.031373) (xy 430.917495 -35.077886) (xy 430.941167 -35.128383) (xy 430.957235 -35.18179)
			(xy 430.965355 -35.236966) (xy 430.965864 -35.264852) (xy 430.965355 -35.292738) (xy 430.957235 -35.347914)
			(xy 430.941167 -35.401321) (xy 430.917495 -35.451818) (xy 430.886722 -35.498331) (xy 430.849505 -35.539868)
			(xy 430.806637 -35.575543) (xy 430.759031 -35.604597) (xy 430.707702 -35.626409) (xy 430.653745 -35.640515)
			(xy 430.598308 -35.646615) (xy 430.542574 -35.644578) (xy 430.487731 -35.634448) (xy 430.434947 -35.616441)
			(xy 430.385347 -35.59094) (xy 430.339989 -35.558489) (xy 430.29984 -35.51978) (xy 430.265754 -35.475637)
			(xy 430.238458 -35.427002) (xy 430.218535 -35.374911) (xy 430.206409 -35.320474) (xy 430.202338 -35.264852)
			(xy 418.788088 -35.264852) (xy 418.788088 -35.876738) (xy 419.017194 -35.876738) (xy 419.021265 -35.821116)
			(xy 419.033391 -35.766679) (xy 419.053314 -35.714588) (xy 419.08061 -35.665953) (xy 419.114696 -35.62181)
			(xy 419.154845 -35.583101) (xy 419.200203 -35.55065) (xy 419.249803 -35.525149) (xy 419.302587 -35.507142)
			(xy 419.35743 -35.497012) (xy 419.413164 -35.494975) (xy 419.468601 -35.501075) (xy 419.522558 -35.515181)
			(xy 419.573887 -35.536993) (xy 419.621493 -35.566047) (xy 419.664361 -35.601722) (xy 419.701578 -35.643259)
			(xy 419.732351 -35.689772) (xy 419.756023 -35.740269) (xy 419.772091 -35.793676) (xy 419.780211 -35.848852)
			(xy 419.78072 -35.876738) (xy 423.088814 -35.876738) (xy 423.092885 -35.821116) (xy 423.105011 -35.766679)
			(xy 423.124934 -35.714588) (xy 423.15223 -35.665953) (xy 423.186316 -35.62181) (xy 423.226465 -35.583101)
			(xy 423.271823 -35.55065) (xy 423.321423 -35.525149) (xy 423.374207 -35.507142) (xy 423.42905 -35.497012)
			(xy 423.484784 -35.494975) (xy 423.540221 -35.501075) (xy 423.594178 -35.515181) (xy 423.645507 -35.536993)
			(xy 423.693113 -35.566047) (xy 423.735981 -35.601722) (xy 423.773198 -35.643259) (xy 423.803971 -35.689772)
			(xy 423.827643 -35.740269) (xy 423.843711 -35.793676) (xy 423.851831 -35.848852) (xy 423.85234 -35.876738)
			(xy 423.851831 -35.904624) (xy 423.843711 -35.9598) (xy 423.827643 -36.013207) (xy 423.803971 -36.063704)
			(xy 423.773198 -36.110217) (xy 423.735981 -36.151754) (xy 423.693113 -36.187429) (xy 423.645507 -36.216483)
			(xy 423.594178 -36.238295) (xy 423.540221 -36.252401) (xy 423.484784 -36.258501) (xy 423.42905 -36.256464)
			(xy 423.374207 -36.246334) (xy 423.321423 -36.228327) (xy 423.271823 -36.202826) (xy 423.226465 -36.170375)
			(xy 423.186316 -36.131666) (xy 423.15223 -36.087523) (xy 423.124934 -36.038888) (xy 423.105011 -35.986797)
			(xy 423.092885 -35.93236) (xy 423.088814 -35.876738) (xy 419.78072 -35.876738) (xy 419.780211 -35.904624)
			(xy 419.772091 -35.9598) (xy 419.756023 -36.013207) (xy 419.732351 -36.063704) (xy 419.701578 -36.110217)
			(xy 419.664361 -36.151754) (xy 419.621493 -36.187429) (xy 419.573887 -36.216483) (xy 419.522558 -36.238295)
			(xy 419.468601 -36.252401) (xy 419.413164 -36.258501) (xy 419.35743 -36.256464) (xy 419.302587 -36.246334)
			(xy 419.249803 -36.228327) (xy 419.200203 -36.202826) (xy 419.154845 -36.170375) (xy 419.114696 -36.131666)
			(xy 419.08061 -36.087523) (xy 419.053314 -36.038888) (xy 419.033391 -35.986797) (xy 419.021265 -35.93236)
			(xy 419.017194 -35.876738) (xy 418.788088 -35.876738) (xy 418.788088 -36.50996) (xy 420.913812 -36.50996)
			(xy 420.917883 -36.454338) (xy 420.930009 -36.399901) (xy 420.949932 -36.34781) (xy 420.977228 -36.299175)
			(xy 421.011314 -36.255032) (xy 421.051463 -36.216323) (xy 421.096821 -36.183872) (xy 421.146421 -36.158371)
			(xy 421.199205 -36.140364) (xy 421.254048 -36.130234) (xy 421.309782 -36.128197) (xy 421.365219 -36.134297)
			(xy 421.419176 -36.148403) (xy 421.470505 -36.170215) (xy 421.518111 -36.199269) (xy 421.560979 -36.234944)
			(xy 421.598196 -36.276481) (xy 421.628969 -36.322994) (xy 421.652641 -36.373491) (xy 421.668709 -36.426898)
			(xy 421.672634 -36.453572) (xy 424.228512 -36.453572) (xy 424.232583 -36.39795) (xy 424.244709 -36.343513)
			(xy 424.264632 -36.291422) (xy 424.291928 -36.242787) (xy 424.326014 -36.198644) (xy 424.366163 -36.159935)
			(xy 424.411521 -36.127484) (xy 424.461121 -36.101983) (xy 424.513905 -36.083976) (xy 424.568748 -36.073846)
			(xy 424.624482 -36.071809) (xy 424.679919 -36.077909) (xy 424.733876 -36.092015) (xy 424.785205 -36.113827)
			(xy 424.832811 -36.142881) (xy 424.875679 -36.178556) (xy 424.912896 -36.220093) (xy 424.943669 -36.266606)
			(xy 424.953205 -36.286948) (xy 431.500278 -36.286948) (xy 431.504349 -36.231326) (xy 431.516475 -36.176889)
			(xy 431.536398 -36.124798) (xy 431.563694 -36.076163) (xy 431.59778 -36.03202) (xy 431.637929 -35.993311)
			(xy 431.683287 -35.96086) (xy 431.732887 -35.935359) (xy 431.785671 -35.917352) (xy 431.840514 -35.907222)
			(xy 431.896248 -35.905185) (xy 431.951685 -35.911285) (xy 432.005642 -35.925391) (xy 432.056971 -35.947203)
			(xy 432.104577 -35.976257) (xy 432.147445 -36.011932) (xy 432.184662 -36.053469) (xy 432.215435 -36.099982)
			(xy 432.239107 -36.150479) (xy 432.255175 -36.203886) (xy 432.263295 -36.259062) (xy 432.263804 -36.286948)
			(xy 432.263295 -36.314834) (xy 432.255175 -36.37001) (xy 432.239107 -36.423417) (xy 432.215435 -36.473914)
			(xy 432.18789 -36.515548) (xy 433.314092 -36.515548) (xy 433.318163 -36.459926) (xy 433.330289 -36.405489)
			(xy 433.350212 -36.353398) (xy 433.377508 -36.304763) (xy 433.411594 -36.26062) (xy 433.451743 -36.221911)
			(xy 433.497101 -36.18946) (xy 433.546701 -36.163959) (xy 433.599485 -36.145952) (xy 433.654328 -36.135822)
			(xy 433.710062 -36.133785) (xy 433.765499 -36.139885) (xy 433.819456 -36.153991) (xy 433.870785 -36.175803)
			(xy 433.918391 -36.204857) (xy 433.961259 -36.240532) (xy 433.998476 -36.282069) (xy 434.029249 -36.328582)
			(xy 434.052921 -36.379079) (xy 434.068989 -36.432486) (xy 434.077109 -36.487662) (xy 434.077618 -36.515548)
			(xy 434.077109 -36.543434) (xy 434.068989 -36.59861) (xy 434.068532 -36.60013) (xy 438.298597 -36.60013)
			(xy 438.302601 -36.512245) (xy 438.314581 -36.425088) (xy 438.334436 -36.339381) (xy 438.362003 -36.255836)
			(xy 438.397053 -36.175143) (xy 438.439295 -36.097971) (xy 438.48838 -36.024961) (xy 438.543901 -35.956717)
			(xy 438.605398 -35.893804) (xy 438.67236 -35.836744) (xy 438.744234 -35.78601) (xy 438.820424 -35.742022)
			(xy 438.900298 -35.705144) (xy 438.983195 -35.675683) (xy 439.068427 -35.653881) (xy 439.155289 -35.639921)
			(xy 439.24306 -35.633917) (xy 439.331014 -35.63592) (xy 439.418421 -35.645912) (xy 439.504557 -35.663812)
			(xy 439.588709 -35.68947) (xy 439.670179 -35.722674) (xy 439.748292 -35.763148) (xy 439.8224 -35.810559)
			(xy 439.891891 -35.864512) (xy 439.956187 -35.92456) (xy 440.014756 -35.990207) (xy 440.067113 -36.060907)
			(xy 440.112825 -36.136076) (xy 440.151511 -36.21509) (xy 440.182852 -36.297295) (xy 440.206587 -36.382009)
			(xy 440.222521 -36.46853) (xy 440.230521 -36.556142) (xy 440.231022 -36.60013) (xy 440.230521 -36.644118)
			(xy 440.222521 -36.73173) (xy 440.206587 -36.818251) (xy 440.182852 -36.902965) (xy 440.151511 -36.98517)
			(xy 440.112825 -37.064184) (xy 440.067113 -37.139353) (xy 440.014756 -37.210053) (xy 439.956187 -37.2757)
			(xy 439.891891 -37.335748) (xy 439.8224 -37.389701) (xy 439.748292 -37.437112) (xy 439.670179 -37.477586)
			(xy 439.588709 -37.51079) (xy 439.504557 -37.536448) (xy 439.418421 -37.554348) (xy 439.331014 -37.56434)
			(xy 439.24306 -37.566343) (xy 439.155289 -37.560339) (xy 439.068427 -37.546379) (xy 438.983195 -37.524577)
			(xy 438.900298 -37.495116) (xy 438.820424 -37.458238) (xy 438.744234 -37.41425) (xy 438.67236 -37.363516)
			(xy 438.605398 -37.306456) (xy 438.543901 -37.243543) (xy 438.48838 -37.175299) (xy 438.439295 -37.102289)
			(xy 438.397053 -37.025117) (xy 438.362003 -36.944424) (xy 438.334436 -36.860879) (xy 438.314581 -36.775172)
			(xy 438.302601 -36.688015) (xy 438.298597 -36.60013) (xy 434.068532 -36.60013) (xy 434.052921 -36.652017)
			(xy 434.029249 -36.702514) (xy 433.998476 -36.749027) (xy 433.961259 -36.790564) (xy 433.918391 -36.826239)
			(xy 433.870785 -36.855293) (xy 433.819456 -36.877105) (xy 433.765499 -36.891211) (xy 433.710062 -36.897311)
			(xy 433.654328 -36.895274) (xy 433.599485 -36.885144) (xy 433.546701 -36.867137) (xy 433.497101 -36.841636)
			(xy 433.451743 -36.809185) (xy 433.411594 -36.770476) (xy 433.377508 -36.726333) (xy 433.350212 -36.677698)
			(xy 433.330289 -36.625607) (xy 433.318163 -36.57117) (xy 433.314092 -36.515548) (xy 432.18789 -36.515548)
			(xy 432.184662 -36.520427) (xy 432.147445 -36.561964) (xy 432.104577 -36.597639) (xy 432.056971 -36.626693)
			(xy 432.005642 -36.648505) (xy 431.951685 -36.662611) (xy 431.896248 -36.668711) (xy 431.840514 -36.666674)
			(xy 431.785671 -36.656544) (xy 431.732887 -36.638537) (xy 431.683287 -36.613036) (xy 431.637929 -36.580585)
			(xy 431.59778 -36.541876) (xy 431.563694 -36.497733) (xy 431.536398 -36.449098) (xy 431.516475 -36.397007)
			(xy 431.504349 -36.34257) (xy 431.500278 -36.286948) (xy 424.953205 -36.286948) (xy 424.967341 -36.317103)
			(xy 424.983409 -36.37051) (xy 424.991529 -36.425686) (xy 424.992038 -36.453572) (xy 424.991529 -36.481458)
			(xy 424.983409 -36.536634) (xy 424.967341 -36.590041) (xy 424.943669 -36.640538) (xy 424.912896 -36.687051)
			(xy 424.875679 -36.728588) (xy 424.832811 -36.764263) (xy 424.785205 -36.793317) (xy 424.733876 -36.815129)
			(xy 424.679919 -36.829235) (xy 424.624482 -36.835335) (xy 424.568748 -36.833298) (xy 424.513905 -36.823168)
			(xy 424.461121 -36.805161) (xy 424.411521 -36.77966) (xy 424.366163 -36.747209) (xy 424.326014 -36.7085)
			(xy 424.291928 -36.664357) (xy 424.264632 -36.615722) (xy 424.244709 -36.563631) (xy 424.232583 -36.509194)
			(xy 424.228512 -36.453572) (xy 421.672634 -36.453572) (xy 421.676829 -36.482074) (xy 421.677338 -36.50996)
			(xy 421.676829 -36.537846) (xy 421.668709 -36.593022) (xy 421.652641 -36.646429) (xy 421.628969 -36.696926)
			(xy 421.598196 -36.743439) (xy 421.560979 -36.784976) (xy 421.518111 -36.820651) (xy 421.470505 -36.849705)
			(xy 421.419176 -36.871517) (xy 421.365219 -36.885623) (xy 421.309782 -36.891723) (xy 421.254048 -36.889686)
			(xy 421.199205 -36.879556) (xy 421.146421 -36.861549) (xy 421.096821 -36.836048) (xy 421.051463 -36.803597)
			(xy 421.011314 -36.764888) (xy 420.977228 -36.720745) (xy 420.949932 -36.67211) (xy 420.930009 -36.620019)
			(xy 420.917883 -36.565582) (xy 420.913812 -36.50996) (xy 418.788088 -36.50996) (xy 418.788088 -36.815776)
			(xy 418.787603 -36.849252) (xy 418.779891 -36.915759) (xy 418.764601 -36.980941) (xy 418.741934 -37.04394)
			(xy 418.712191 -37.103923) (xy 418.694362 -37.13226) (xy 418.689856 -37.139914) (xy 418.685866 -37.157208)
			(xy 418.688018 -37.174824) (xy 418.696055 -37.190648) (xy 418.702236 -37.19703) (xy 418.720875 -37.215135)
			(xy 418.753575 -37.255518) (xy 418.780493 -37.299964) (xy 418.801132 -37.347651) (xy 418.815108 -37.397698)
			(xy 418.822164 -37.449179) (xy 418.822632 -37.47516) (xy 418.822172 -37.502415) (xy 418.81442 -37.556372)
			(xy 418.799067 -37.608676) (xy 418.776427 -37.658263) (xy 418.773796 -37.662358) (xy 420.248332 -37.662358)
			(xy 420.252403 -37.606736) (xy 420.264529 -37.552299) (xy 420.284452 -37.500208) (xy 420.311748 -37.451573)
			(xy 420.345834 -37.40743) (xy 420.385983 -37.368721) (xy 420.431341 -37.33627) (xy 420.480941 -37.310769)
			(xy 420.533725 -37.292762) (xy 420.588568 -37.282632) (xy 420.644302 -37.280595) (xy 420.699739 -37.286695)
			(xy 420.753696 -37.300801) (xy 420.805025 -37.322613) (xy 420.852631 -37.351667) (xy 420.895499 -37.387342)
			(xy 420.932716 -37.428879) (xy 420.963489 -37.475392) (xy 420.987161 -37.525889) (xy 421.003229 -37.579296)
			(xy 421.011349 -37.634472) (xy 421.011858 -37.662358) (xy 421.011349 -37.690244) (xy 421.003229 -37.74542)
			(xy 420.994595 -37.774118) (xy 431.764692 -37.774118) (xy 431.768763 -37.718496) (xy 431.780889 -37.664059)
			(xy 431.800812 -37.611968) (xy 431.828108 -37.563333) (xy 431.862194 -37.51919) (xy 431.902343 -37.480481)
			(xy 431.947701 -37.44803) (xy 431.997301 -37.422529) (xy 432.050085 -37.404522) (xy 432.104928 -37.394392)
			(xy 432.160662 -37.392355) (xy 432.216099 -37.398455) (xy 432.270056 -37.412561) (xy 432.321385 -37.434373)
			(xy 432.368991 -37.463427) (xy 432.411859 -37.499102) (xy 432.449076 -37.540639) (xy 432.479849 -37.587152)
			(xy 432.503521 -37.637649) (xy 432.519589 -37.691056) (xy 432.527709 -37.746232) (xy 432.528218 -37.774118)
			(xy 432.527709 -37.802004) (xy 432.519589 -37.85718) (xy 432.503521 -37.910587) (xy 432.479849 -37.961084)
			(xy 432.449076 -38.007597) (xy 432.411859 -38.049134) (xy 432.368991 -38.084809) (xy 432.321385 -38.113863)
			(xy 432.270056 -38.135675) (xy 432.216099 -38.149781) (xy 432.160662 -38.155881) (xy 432.104928 -38.153844)
			(xy 432.050085 -38.143714) (xy 431.997301 -38.125707) (xy 431.947701 -38.100206) (xy 431.902343 -38.067755)
			(xy 431.862194 -38.029046) (xy 431.828108 -37.984903) (xy 431.800812 -37.936268) (xy 431.780889 -37.884177)
			(xy 431.768763 -37.82974) (xy 431.764692 -37.774118) (xy 420.994595 -37.774118) (xy 420.987161 -37.798827)
			(xy 420.963489 -37.849324) (xy 420.932716 -37.895837) (xy 420.895499 -37.937374) (xy 420.852631 -37.973049)
			(xy 420.805025 -38.002103) (xy 420.753696 -38.023915) (xy 420.699739 -38.038021) (xy 420.644302 -38.044121)
			(xy 420.588568 -38.042084) (xy 420.533725 -38.031954) (xy 420.480941 -38.013947) (xy 420.431341 -37.988446)
			(xy 420.385983 -37.955995) (xy 420.345834 -37.917286) (xy 420.311748 -37.873143) (xy 420.284452 -37.824508)
			(xy 420.264529 -37.772417) (xy 420.252403 -37.71798) (xy 420.248332 -37.662358) (xy 418.773796 -37.662358)
			(xy 418.746961 -37.704123) (xy 418.711268 -37.745322) (xy 418.670074 -37.781022) (xy 418.624219 -37.810497)
			(xy 418.574636 -37.833145) (xy 418.522335 -37.848506) (xy 418.468379 -37.856267) (xy 418.441124 -37.856668)
			(xy 418.411181 -37.856084) (xy 418.352031 -37.846727) (xy 418.295071 -37.82824) (xy 418.2417 -37.801078)
			(xy 418.19323 -37.765907) (xy 418.17163 -37.745162) (xy 418.171376 -37.744908) (xy 418.12083 -37.744908)
			(xy 418.110766 -37.745344) (xy 418.09218 -37.753077) (xy 418.084762 -37.759894) (xy 417.114705 -38.729951)
			(xy 424.000897 -38.729951) (xy 424.000897 -38.675449) (xy 424.008654 -38.621501) (xy 424.02401 -38.569207)
			(xy 424.046652 -38.51963) (xy 424.07612 -38.47378) (xy 424.111813 -38.432592) (xy 424.153005 -38.396902)
			(xy 424.198856 -38.367438) (xy 424.248435 -38.3448) (xy 424.300731 -38.329448) (xy 424.354679 -38.321695)
			(xy 424.38193 -38.321234) (xy 424.410233 -38.321763) (xy 424.46622 -38.330106) (xy 424.520359 -38.346633)
			(xy 424.571461 -38.370981) (xy 424.618401 -38.402616) (xy 424.660149 -38.440843) (xy 424.695788 -38.48482)
			(xy 424.710606 -38.50894) (xy 424.71823 -38.520957) (xy 424.738843 -38.540558) (xy 424.764069 -38.5537)
			(xy 424.791945 -38.559362) (xy 424.8203 -38.557101) (xy 424.846927 -38.547095) (xy 424.869752 -38.530121)
			(xy 424.878754 -38.5191) (xy 424.896914 -38.496202) (xy 424.939083 -38.45574) (xy 424.986924 -38.422175)
			(xy 425.039321 -38.396291) (xy 425.09505 -38.378694) (xy 425.152809 -38.369794) (xy 425.18203 -38.36924)
			(xy 425.209283 -38.369632) (xy 425.263235 -38.377393) (xy 425.315532 -38.392753) (xy 425.365112 -38.415398)
			(xy 425.410964 -38.444869) (xy 425.452156 -38.480565) (xy 425.487849 -38.52176) (xy 425.517316 -38.567614)
			(xy 425.539958 -38.617196) (xy 425.555313 -38.669495) (xy 425.56307 -38.723447) (xy 425.56307 -38.777953)
			(xy 425.555313 -38.831905) (xy 425.539958 -38.884204) (xy 425.517316 -38.933786) (xy 425.487849 -38.97964)
			(xy 425.452156 -39.020835) (xy 425.410964 -39.056531) (xy 425.365112 -39.086002) (xy 425.315532 -39.108647)
			(xy 425.263235 -39.124007) (xy 425.209283 -39.131768) (xy 425.18203 -39.132256) (xy 425.153726 -39.131763)
			(xy 425.097736 -39.123415) (xy 425.043596 -39.106882) (xy 424.992495 -39.082527) (xy 424.945555 -39.050886)
			(xy 424.903808 -39.012655) (xy 424.86817 -38.968672) (xy 424.853354 -38.94455) (xy 424.845783 -38.932498)
			(xy 424.825158 -38.912896) (xy 424.79992 -38.899756) (xy 424.772035 -38.894099) (xy 424.743671 -38.896366)
			(xy 424.717038 -38.906381) (xy 424.694209 -38.923364) (xy 424.685206 -38.93439) (xy 424.667009 -38.957257)
			(xy 424.624848 -38.997722) (xy 424.577015 -39.031291) (xy 424.524625 -39.057179) (xy 424.468903 -39.074783)
			(xy 424.411149 -39.083692) (xy 424.38193 -39.08425) (xy 424.354679 -39.083705) (xy 424.300731 -39.075952)
			(xy 424.248435 -39.0606) (xy 424.198856 -39.037962) (xy 424.153005 -39.008498) (xy 424.111813 -38.972808)
			(xy 424.07612 -38.93162) (xy 424.046652 -38.88577) (xy 424.02401 -38.836193) (xy 424.008654 -38.783899)
			(xy 424.000897 -38.729951) (xy 417.114705 -38.729951) (xy 415.872676 -39.97198) (xy 426.195742 -39.97198)
			(xy 426.199813 -39.916358) (xy 426.211939 -39.861921) (xy 426.231862 -39.80983) (xy 426.259158 -39.761195)
			(xy 426.293244 -39.717052) (xy 426.333393 -39.678343) (xy 426.378751 -39.645892) (xy 426.428351 -39.620391)
			(xy 426.481135 -39.602384) (xy 426.535978 -39.592254) (xy 426.591712 -39.590217) (xy 426.647149 -39.596317)
			(xy 426.701106 -39.610423) (xy 426.752435 -39.632235) (xy 426.800041 -39.661289) (xy 426.842909 -39.696964)
			(xy 426.880126 -39.738501) (xy 426.910899 -39.785014) (xy 426.934571 -39.835511) (xy 426.950639 -39.888918)
			(xy 426.958759 -39.944094) (xy 426.959268 -39.97198) (xy 426.958759 -39.999866) (xy 426.950639 -40.055042)
			(xy 426.934571 -40.108449) (xy 426.910899 -40.158946) (xy 426.880126 -40.205459) (xy 426.842909 -40.246996)
			(xy 426.800041 -40.282671) (xy 426.752435 -40.311725) (xy 426.701106 -40.333537) (xy 426.647149 -40.347643)
			(xy 426.591712 -40.353743) (xy 426.535978 -40.351706) (xy 426.481135 -40.341576) (xy 426.428351 -40.323569)
			(xy 426.378751 -40.298068) (xy 426.333393 -40.265617) (xy 426.293244 -40.226908) (xy 426.259158 -40.182765)
			(xy 426.231862 -40.13413) (xy 426.211939 -40.082039) (xy 426.199813 -40.027602) (xy 426.195742 -39.97198)
			(xy 415.872676 -39.97198) (xy 414.575899 -41.268757) (xy 416.143827 -41.268757) (xy 416.143827 -41.214243)
			(xy 416.151586 -41.160284) (xy 416.166945 -41.107978) (xy 416.189593 -41.058391) (xy 416.219068 -41.012532)
			(xy 416.254769 -40.971335) (xy 416.295971 -40.935639) (xy 416.341833 -40.90617) (xy 416.391423 -40.883529)
			(xy 416.443731 -40.868176) (xy 416.497691 -40.860424) (xy 416.524948 -40.859964) (xy 416.553688 -40.860468)
			(xy 416.610515 -40.869097) (xy 416.665406 -40.886152) (xy 416.717117 -40.911248) (xy 416.764479 -40.943816)
			(xy 416.785806 -40.963088) (xy 416.792664 -40.969692) (xy 416.810698 -40.976804) (xy 416.899598 -40.976804)
			(xy 416.917632 -40.969692) (xy 416.92449 -40.963088) (xy 416.945805 -40.943803) (xy 416.993169 -40.911237)
			(xy 417.044884 -40.886146) (xy 417.099778 -40.869099) (xy 417.156608 -40.860482) (xy 417.185348 -40.859964)
			(xy 417.212595 -40.860509) (xy 417.266533 -40.868271) (xy 417.318819 -40.883629) (xy 417.368386 -40.906271)
			(xy 417.414227 -40.935737) (xy 417.455408 -40.971426) (xy 417.491092 -41.012611) (xy 417.520552 -41.058456)
			(xy 417.543188 -41.108026) (xy 417.558539 -41.160313) (xy 417.566294 -41.214253) (xy 417.566294 -41.268747)
			(xy 417.558539 -41.322687) (xy 417.543188 -41.374974) (xy 417.520552 -41.424544) (xy 417.491092 -41.470389)
			(xy 417.455408 -41.511574) (xy 417.414227 -41.547263) (xy 417.368386 -41.576729) (xy 417.318819 -41.599371)
			(xy 417.266533 -41.614729) (xy 417.212595 -41.622491) (xy 417.185348 -41.62298) (xy 417.156609 -41.622467)
			(xy 417.099782 -41.613838) (xy 417.044892 -41.596784) (xy 416.993181 -41.571691) (xy 416.945818 -41.539126)
			(xy 416.92449 -41.519856) (xy 416.917632 -41.513252) (xy 416.899598 -41.50614) (xy 416.810698 -41.50614)
			(xy 416.792664 -41.513252) (xy 416.785806 -41.519856) (xy 416.764499 -41.53915) (xy 416.717132 -41.571714)
			(xy 416.665415 -41.596802) (xy 416.61052 -41.613847) (xy 416.553688 -41.622463) (xy 416.524948 -41.62298)
			(xy 416.497691 -41.622576) (xy 416.443731 -41.614824) (xy 416.391423 -41.599471) (xy 416.341833 -41.57683)
			(xy 416.295971 -41.547361) (xy 416.254769 -41.511665) (xy 416.219068 -41.470468) (xy 416.189593 -41.424609)
			(xy 416.166945 -41.375022) (xy 416.151586 -41.322716) (xy 416.143827 -41.268757) (xy 414.575899 -41.268757)
			(xy 414.423098 -41.421558) (xy 412.89859 -42.94632) (xy 412.891737 -42.953715) (xy 412.883995 -42.972314)
			(xy 412.883604 -42.982388) (xy 412.883604 -43.305222) (xy 418.60724 -43.305222) (xy 418.607709 -43.277852)
			(xy 418.615525 -43.223672) (xy 418.631013 -43.171169) (xy 418.653854 -43.121422) (xy 418.683579 -43.075455)
			(xy 418.70122 -43.054524) (xy 418.701474 -43.05427) (xy 418.707046 -43.047174) (xy 418.7133 -43.030264)
			(xy 418.713666 -43.02125) (xy 418.713666 -42.954194) (xy 418.713319 -42.945176) (xy 418.707066 -42.928259)
			(xy 418.701474 -42.921174) (xy 418.70122 -42.921174) (xy 418.70122 -42.92092) (xy 418.68358 -42.899989)
			(xy 418.653868 -42.854016) (xy 418.631031 -42.804268) (xy 418.615541 -42.751767) (xy 418.607713 -42.697591)
			(xy 418.60724 -42.670222) (xy 418.607793 -42.641484) (xy 418.616411 -42.584659) (xy 418.633455 -42.529769)
			(xy 418.65854 -42.478057) (xy 418.691097 -42.430693) (xy 418.710364 -42.409364) (xy 418.716968 -42.402506)
			(xy 418.72408 -42.384472) (xy 418.72408 -42.295572) (xy 418.716968 -42.277538) (xy 418.710364 -42.27068)
			(xy 418.691113 -42.249335) (xy 418.658544 -42.201977) (xy 418.633448 -42.150268) (xy 418.616395 -42.09538)
			(xy 418.607769 -42.038554) (xy 418.607767 -41.981078) (xy 418.616388 -41.924251) (xy 418.633437 -41.869361)
			(xy 418.658528 -41.817651) (xy 418.691093 -41.77029) (xy 418.710364 -41.748964) (xy 418.716968 -41.742106)
			(xy 418.72408 -41.724072) (xy 418.72408 -41.635172) (xy 418.716968 -41.617138) (xy 418.710364 -41.61028)
			(xy 418.691108 -41.58894) (xy 418.658539 -41.541582) (xy 418.633443 -41.489874) (xy 418.616389 -41.434986)
			(xy 418.607763 -41.37816) (xy 418.60724 -41.349422) (xy 418.607726 -41.322171) (xy 418.615482 -41.268223)
			(xy 418.630837 -41.215928) (xy 418.653479 -41.166351) (xy 418.682945 -41.120501) (xy 418.718636 -41.07931)
			(xy 418.759827 -41.043619) (xy 418.805677 -41.014153) (xy 418.855254 -40.991511) (xy 418.907549 -40.976156)
			(xy 418.961497 -40.9684) (xy 419.015999 -40.9684) (xy 419.03912 -40.971724) (xy 426.893988 -40.971724)
			(xy 426.898059 -40.916102) (xy 426.910185 -40.861665) (xy 426.930108 -40.809574) (xy 426.957404 -40.760939)
			(xy 426.99149 -40.716796) (xy 427.031639 -40.678087) (xy 427.076997 -40.645636) (xy 427.126597 -40.620135)
			(xy 427.179381 -40.602128) (xy 427.234224 -40.591998) (xy 427.289958 -40.589961) (xy 427.345395 -40.596061)
			(xy 427.399352 -40.610167) (xy 427.450681 -40.631979) (xy 427.498287 -40.661033) (xy 427.541155 -40.696708)
			(xy 427.578372 -40.738245) (xy 427.609145 -40.784758) (xy 427.632817 -40.835255) (xy 427.648885 -40.888662)
			(xy 427.657005 -40.943838) (xy 427.657514 -40.971724) (xy 427.657005 -40.99961) (xy 427.648885 -41.054786)
			(xy 427.632817 -41.108193) (xy 427.609145 -41.15869) (xy 427.578372 -41.205203) (xy 427.541155 -41.24674)
			(xy 427.498287 -41.282415) (xy 427.450681 -41.311469) (xy 427.399352 -41.333281) (xy 427.345395 -41.347387)
			(xy 427.289958 -41.353487) (xy 427.234224 -41.35145) (xy 427.179381 -41.34132) (xy 427.126597 -41.323313)
			(xy 427.076997 -41.297812) (xy 427.031639 -41.265361) (xy 426.99149 -41.226652) (xy 426.957404 -41.182509)
			(xy 426.930108 -41.133874) (xy 426.910185 -41.081783) (xy 426.898059 -41.027346) (xy 426.893988 -40.971724)
			(xy 419.03912 -40.971724) (xy 419.069947 -40.976156) (xy 419.122242 -40.991511) (xy 419.171819 -41.014153)
			(xy 419.217669 -41.043619) (xy 419.25886 -41.07931) (xy 419.294551 -41.120501) (xy 419.324017 -41.166351)
			(xy 419.346659 -41.215928) (xy 419.362014 -41.268223) (xy 419.36977 -41.322171) (xy 419.370256 -41.349422)
			(xy 419.369731 -41.378161) (xy 419.361106 -41.434987) (xy 419.344056 -41.489877) (xy 419.318965 -41.541589)
			(xy 419.286402 -41.588952) (xy 419.267132 -41.61028) (xy 419.260528 -41.617138) (xy 419.253416 -41.635172)
			(xy 419.253416 -41.724072) (xy 419.260528 -41.742106) (xy 419.267132 -41.748964) (xy 419.286422 -41.770273)
			(xy 419.318982 -41.81764) (xy 419.344069 -41.869355) (xy 419.361114 -41.924248) (xy 419.369733 -41.981077)
			(xy 419.369731 -42.038555) (xy 419.361107 -42.095383) (xy 419.344057 -42.150275) (xy 419.318966 -42.201988)
			(xy 419.286402 -42.249352) (xy 419.267132 -42.27068) (xy 419.260528 -42.277538) (xy 419.253416 -42.295572)
			(xy 419.253416 -42.384472) (xy 419.260528 -42.402506) (xy 419.267132 -42.409364) (xy 419.286408 -42.430686)
			(xy 419.318975 -42.478049) (xy 419.344067 -42.529762) (xy 419.361116 -42.584654) (xy 419.369737 -42.641483)
			(xy 419.370256 -42.670222) (xy 419.369814 -42.697593) (xy 419.361992 -42.751774) (xy 419.346498 -42.804278)
			(xy 419.32594 -42.849038) (xy 421.191942 -42.849038) (xy 421.196013 -42.793416) (xy 421.208139 -42.738979)
			(xy 421.228062 -42.686888) (xy 421.255358 -42.638253) (xy 421.289444 -42.59411) (xy 421.329593 -42.555401)
			(xy 421.374951 -42.52295) (xy 421.424551 -42.497449) (xy 421.477335 -42.479442) (xy 421.532178 -42.469312)
			(xy 421.587912 -42.467275) (xy 421.643349 -42.473375) (xy 421.697306 -42.487481) (xy 421.748635 -42.509293)
			(xy 421.796241 -42.538347) (xy 421.839109 -42.574022) (xy 421.876326 -42.615559) (xy 421.907099 -42.662072)
			(xy 421.930771 -42.712569) (xy 421.946839 -42.765976) (xy 421.954959 -42.821152) (xy 421.95532 -42.84091)
			(xy 427.233078 -42.84091) (xy 427.237149 -42.785288) (xy 427.249275 -42.730851) (xy 427.269198 -42.67876)
			(xy 427.296494 -42.630125) (xy 427.33058 -42.585982) (xy 427.370729 -42.547273) (xy 427.416087 -42.514822)
			(xy 427.465687 -42.489321) (xy 427.518471 -42.471314) (xy 427.573314 -42.461184) (xy 427.629048 -42.459147)
			(xy 427.684485 -42.465247) (xy 427.738442 -42.479353) (xy 427.789771 -42.501165) (xy 427.837377 -42.530219)
			(xy 427.880245 -42.565894) (xy 427.917462 -42.607431) (xy 427.948235 -42.653944) (xy 427.971907 -42.704441)
			(xy 427.987975 -42.757848) (xy 427.996095 -42.813024) (xy 427.996604 -42.84091) (xy 427.996095 -42.868796)
			(xy 427.987975 -42.923972) (xy 427.971907 -42.977379) (xy 427.948235 -43.027876) (xy 427.917462 -43.074389)
			(xy 427.880245 -43.115926) (xy 427.837377 -43.151601) (xy 427.789771 -43.180655) (xy 427.738442 -43.202467)
			(xy 427.684485 -43.216573) (xy 427.629048 -43.222673) (xy 427.573314 -43.220636) (xy 427.518471 -43.210506)
			(xy 427.465687 -43.192499) (xy 427.416087 -43.166998) (xy 427.370729 -43.134547) (xy 427.33058 -43.095838)
			(xy 427.296494 -43.051695) (xy 427.269198 -43.00306) (xy 427.249275 -42.950969) (xy 427.237149 -42.896532)
			(xy 427.233078 -42.84091) (xy 421.95532 -42.84091) (xy 421.955468 -42.849038) (xy 421.954959 -42.876924)
			(xy 421.946839 -42.9321) (xy 421.930771 -42.985507) (xy 421.907099 -43.036004) (xy 421.876326 -43.082517)
			(xy 421.839109 -43.124054) (xy 421.796241 -43.159729) (xy 421.748635 -43.188783) (xy 421.697306 -43.210595)
			(xy 421.643349 -43.224701) (xy 421.587912 -43.230801) (xy 421.532178 -43.228764) (xy 421.477335 -43.218634)
			(xy 421.424551 -43.200627) (xy 421.374951 -43.175126) (xy 421.329593 -43.142675) (xy 421.289444 -43.103966)
			(xy 421.255358 -43.059823) (xy 421.228062 -43.011188) (xy 421.208139 -42.959097) (xy 421.196013 -42.90466)
			(xy 421.191942 -42.849038) (xy 419.32594 -42.849038) (xy 419.32365 -42.854024) (xy 419.29392 -42.899989)
			(xy 419.276276 -42.92092) (xy 419.276022 -42.921174) (xy 419.270431 -42.928257) (xy 419.264189 -42.945177)
			(xy 419.26383 -42.954194) (xy 419.26383 -43.02125) (xy 419.264204 -43.030265) (xy 419.270439 -43.047183)
			(xy 419.276022 -43.05427) (xy 419.276276 -43.05427) (xy 419.276276 -43.054524) (xy 419.293889 -43.075477)
			(xy 419.323606 -43.121444) (xy 419.346447 -43.171186) (xy 419.361944 -43.223682) (xy 419.369779 -43.277854)
			(xy 419.370256 -43.305222) (xy 419.36977 -43.332473) (xy 419.362014 -43.386421) (xy 419.346659 -43.438716)
			(xy 419.324017 -43.488293) (xy 419.294551 -43.534143) (xy 419.25886 -43.575334) (xy 419.217669 -43.611025)
			(xy 419.171819 -43.640491) (xy 419.122242 -43.663133) (xy 419.069947 -43.678488) (xy 419.015999 -43.686244)
			(xy 418.961497 -43.686244) (xy 418.907549 -43.678488) (xy 418.855254 -43.663133) (xy 418.805677 -43.640491)
			(xy 418.759827 -43.611025) (xy 418.718636 -43.575334) (xy 418.682945 -43.534143) (xy 418.653479 -43.488293)
			(xy 418.630837 -43.438716) (xy 418.615482 -43.386421) (xy 418.607726 -43.332473) (xy 418.60724 -43.305222)
			(xy 412.883604 -43.305222) (xy 412.883604 -43.73626) (xy 420.513 -43.73626) (xy 420.517071 -43.680638)
			(xy 420.529197 -43.626201) (xy 420.54912 -43.57411) (xy 420.576416 -43.525475) (xy 420.610502 -43.481332)
			(xy 420.650651 -43.442623) (xy 420.696009 -43.410172) (xy 420.745609 -43.384671) (xy 420.798393 -43.366664)
			(xy 420.853236 -43.356534) (xy 420.90897 -43.354497) (xy 420.964407 -43.360597) (xy 421.018364 -43.374703)
			(xy 421.069693 -43.396515) (xy 421.117299 -43.425569) (xy 421.160167 -43.461244) (xy 421.197384 -43.502781)
			(xy 421.228157 -43.549294) (xy 421.236383 -43.566842) (xy 423.63339 -43.566842) (xy 423.637461 -43.51122)
			(xy 423.649587 -43.456783) (xy 423.66951 -43.404692) (xy 423.696806 -43.356057) (xy 423.730892 -43.311914)
			(xy 423.771041 -43.273205) (xy 423.816399 -43.240754) (xy 423.865999 -43.215253) (xy 423.918783 -43.197246)
			(xy 423.973626 -43.187116) (xy 424.02936 -43.185079) (xy 424.084797 -43.191179) (xy 424.138754 -43.205285)
			(xy 424.190083 -43.227097) (xy 424.237689 -43.256151) (xy 424.280557 -43.291826) (xy 424.317774 -43.333363)
			(xy 424.348547 -43.379876) (xy 424.372219 -43.430373) (xy 424.388287 -43.48378) (xy 424.396407 -43.538956)
			(xy 424.396916 -43.566842) (xy 424.396407 -43.594728) (xy 424.388287 -43.649904) (xy 424.372219 -43.703311)
			(xy 424.348547 -43.753808) (xy 424.317774 -43.800321) (xy 424.280557 -43.841858) (xy 424.26247 -43.85691)
			(xy 425.019722 -43.85691) (xy 425.023793 -43.801288) (xy 425.035919 -43.746851) (xy 425.055842 -43.69476)
			(xy 425.083138 -43.646125) (xy 425.117224 -43.601982) (xy 425.157373 -43.563273) (xy 425.202731 -43.530822)
			(xy 425.252331 -43.505321) (xy 425.305115 -43.487314) (xy 425.359958 -43.477184) (xy 425.415692 -43.475147)
			(xy 425.471129 -43.481247) (xy 425.525086 -43.495353) (xy 425.576415 -43.517165) (xy 425.624021 -43.546219)
			(xy 425.666889 -43.581894) (xy 425.704106 -43.623431) (xy 425.734879 -43.669944) (xy 425.758551 -43.720441)
			(xy 425.774619 -43.773848) (xy 425.782739 -43.829024) (xy 425.783248 -43.85691) (xy 425.782739 -43.884796)
			(xy 425.774619 -43.939972) (xy 425.758551 -43.993379) (xy 425.734879 -44.043876) (xy 425.704106 -44.090389)
			(xy 425.666889 -44.131926) (xy 425.624021 -44.167601) (xy 425.576415 -44.196655) (xy 425.525086 -44.218467)
			(xy 425.471129 -44.232573) (xy 425.415692 -44.238673) (xy 425.359958 -44.236636) (xy 425.305115 -44.226506)
			(xy 425.252331 -44.208499) (xy 425.202731 -44.182998) (xy 425.157373 -44.150547) (xy 425.117224 -44.111838)
			(xy 425.083138 -44.067695) (xy 425.055842 -44.01906) (xy 425.035919 -43.966969) (xy 425.023793 -43.912532)
			(xy 425.019722 -43.85691) (xy 424.26247 -43.85691) (xy 424.237689 -43.877533) (xy 424.190083 -43.906587)
			(xy 424.138754 -43.928399) (xy 424.084797 -43.942505) (xy 424.02936 -43.948605) (xy 423.973626 -43.946568)
			(xy 423.918783 -43.936438) (xy 423.865999 -43.918431) (xy 423.816399 -43.89293) (xy 423.771041 -43.860479)
			(xy 423.730892 -43.82177) (xy 423.696806 -43.777627) (xy 423.66951 -43.728992) (xy 423.649587 -43.676901)
			(xy 423.637461 -43.622464) (xy 423.63339 -43.566842) (xy 421.236383 -43.566842) (xy 421.251829 -43.599791)
			(xy 421.267897 -43.653198) (xy 421.276017 -43.708374) (xy 421.276526 -43.73626) (xy 421.276017 -43.764146)
			(xy 421.267897 -43.819322) (xy 421.251829 -43.872729) (xy 421.228157 -43.923226) (xy 421.197384 -43.969739)
			(xy 421.160167 -44.011276) (xy 421.117299 -44.046951) (xy 421.069693 -44.076005) (xy 421.018364 -44.097817)
			(xy 420.964407 -44.111923) (xy 420.90897 -44.118023) (xy 420.853236 -44.115986) (xy 420.798393 -44.105856)
			(xy 420.745609 -44.087849) (xy 420.696009 -44.062348) (xy 420.650651 -44.029897) (xy 420.610502 -43.991188)
			(xy 420.576416 -43.947045) (xy 420.54912 -43.89841) (xy 420.529197 -43.846319) (xy 420.517071 -43.791882)
			(xy 420.513 -43.73626) (xy 412.883604 -43.73626) (xy 412.883604 -45.114464) (xy 420.365426 -45.114464)
			(xy 420.369497 -45.058842) (xy 420.381623 -45.004405) (xy 420.401546 -44.952314) (xy 420.428842 -44.903679)
			(xy 420.462928 -44.859536) (xy 420.503077 -44.820827) (xy 420.548435 -44.788376) (xy 420.598035 -44.762875)
			(xy 420.650819 -44.744868) (xy 420.705662 -44.734738) (xy 420.761396 -44.732701) (xy 420.816833 -44.738801)
			(xy 420.87079 -44.752907) (xy 420.922119 -44.774719) (xy 420.969725 -44.803773) (xy 421.012593 -44.839448)
			(xy 421.042575 -44.87291) (xy 427.233078 -44.87291) (xy 427.237149 -44.817288) (xy 427.249275 -44.762851)
			(xy 427.269198 -44.71076) (xy 427.296494 -44.662125) (xy 427.33058 -44.617982) (xy 427.370729 -44.579273)
			(xy 427.416087 -44.546822) (xy 427.465687 -44.521321) (xy 427.518471 -44.503314) (xy 427.573314 -44.493184)
			(xy 427.629048 -44.491147) (xy 427.684485 -44.497247) (xy 427.738442 -44.511353) (xy 427.789771 -44.533165)
			(xy 427.837377 -44.562219) (xy 427.880245 -44.597894) (xy 427.917462 -44.639431) (xy 427.948235 -44.685944)
			(xy 427.971907 -44.736441) (xy 427.987975 -44.789848) (xy 427.996095 -44.845024) (xy 427.996604 -44.87291)
			(xy 427.996095 -44.900796) (xy 427.987975 -44.955972) (xy 427.971907 -45.009379) (xy 427.948235 -45.059876)
			(xy 427.917462 -45.106389) (xy 427.880245 -45.147926) (xy 427.837377 -45.183601) (xy 427.789771 -45.212655)
			(xy 427.738442 -45.234467) (xy 427.684485 -45.248573) (xy 427.629048 -45.254673) (xy 427.573314 -45.252636)
			(xy 427.518471 -45.242506) (xy 427.465687 -45.224499) (xy 427.416087 -45.198998) (xy 427.370729 -45.166547)
			(xy 427.33058 -45.127838) (xy 427.296494 -45.083695) (xy 427.269198 -45.03506) (xy 427.249275 -44.982969)
			(xy 427.237149 -44.928532) (xy 427.233078 -44.87291) (xy 421.042575 -44.87291) (xy 421.04981 -44.880985)
			(xy 421.080583 -44.927498) (xy 421.104255 -44.977995) (xy 421.120323 -45.031402) (xy 421.128443 -45.086578)
			(xy 421.128952 -45.114464) (xy 421.128443 -45.14235) (xy 421.120323 -45.197526) (xy 421.104255 -45.250933)
			(xy 421.080583 -45.30143) (xy 421.04981 -45.347943) (xy 421.044168 -45.35424) (xy 425.00372 -45.35424)
			(xy 425.007791 -45.298618) (xy 425.019917 -45.244181) (xy 425.03984 -45.19209) (xy 425.067136 -45.143455)
			(xy 425.101222 -45.099312) (xy 425.141371 -45.060603) (xy 425.186729 -45.028152) (xy 425.236329 -45.002651)
			(xy 425.289113 -44.984644) (xy 425.343956 -44.974514) (xy 425.39969 -44.972477) (xy 425.455127 -44.978577)
			(xy 425.509084 -44.992683) (xy 425.560413 -45.014495) (xy 425.608019 -45.043549) (xy 425.650887 -45.079224)
			(xy 425.688104 -45.120761) (xy 425.718877 -45.167274) (xy 425.742549 -45.217771) (xy 425.758617 -45.271178)
			(xy 425.766737 -45.326354) (xy 425.767246 -45.35424) (xy 425.766737 -45.382126) (xy 425.758617 -45.437302)
			(xy 425.742549 -45.490709) (xy 425.718877 -45.541206) (xy 425.688104 -45.587719) (xy 425.650887 -45.629256)
			(xy 425.608019 -45.664931) (xy 425.560413 -45.693985) (xy 425.509084 -45.715797) (xy 425.455127 -45.729903)
			(xy 425.39969 -45.736003) (xy 425.343956 -45.733966) (xy 425.289113 -45.723836) (xy 425.236329 -45.705829)
			(xy 425.186729 -45.680328) (xy 425.141371 -45.647877) (xy 425.101222 -45.609168) (xy 425.067136 -45.565025)
			(xy 425.03984 -45.51639) (xy 425.019917 -45.464299) (xy 425.007791 -45.409862) (xy 425.00372 -45.35424)
			(xy 421.044168 -45.35424) (xy 421.012593 -45.38948) (xy 420.969725 -45.425155) (xy 420.922119 -45.454209)
			(xy 420.87079 -45.476021) (xy 420.816833 -45.490127) (xy 420.761396 -45.496227) (xy 420.705662 -45.49419)
			(xy 420.650819 -45.48406) (xy 420.598035 -45.466053) (xy 420.548435 -45.440552) (xy 420.503077 -45.408101)
			(xy 420.462928 -45.369392) (xy 420.428842 -45.325249) (xy 420.401546 -45.276614) (xy 420.381623 -45.224523)
			(xy 420.369497 -45.170086) (xy 420.365426 -45.114464) (xy 412.883604 -45.114464) (xy 412.883604 -46.082204)
			(xy 418.352478 -46.082204) (xy 418.352981 -46.054953) (xy 418.360737 -46.001007) (xy 418.376091 -45.948714)
			(xy 418.398731 -45.899137) (xy 418.428195 -45.853288) (xy 418.463885 -45.812098) (xy 418.505073 -45.776406)
			(xy 418.550921 -45.746939) (xy 418.600497 -45.724297) (xy 418.65279 -45.708941) (xy 418.706736 -45.701183)
			(xy 418.733986 -45.700696) (xy 418.760888 -45.701169) (xy 418.814158 -45.708739) (xy 418.865836 -45.723716)
			(xy 418.914897 -45.745805) (xy 418.96037 -45.774565) (xy 419.001352 -45.809429) (xy 419.03703 -45.849703)
			(xy 419.052248 -45.871892) (xy 419.05936 -45.882814) (xy 419.08222 -45.894752) (xy 419.194488 -45.89272)
			(xy 419.21684 -45.879766) (xy 419.223698 -45.86859) (xy 419.238634 -45.844998) (xy 419.274311 -45.802047)
			(xy 419.315867 -45.764753) (xy 419.362414 -45.733915) (xy 419.412959 -45.71019) (xy 419.466422 -45.694085)
			(xy 419.521662 -45.685944) (xy 419.54958 -45.685456) (xy 419.576573 -45.685929) (xy 419.630021 -45.693532)
			(xy 419.681864 -45.708589) (xy 419.731069 -45.730801) (xy 419.776653 -45.759723) (xy 419.797484 -45.776896)
			(xy 419.805612 -45.784008) (xy 419.826186 -45.790104) (xy 419.91153 -45.779182) (xy 419.922081 -45.777432)
			(xy 419.940361 -45.76636) (xy 419.946836 -45.757846) (xy 419.962173 -45.736603) (xy 419.997763 -45.698151)
			(xy 420.038283 -45.664933) (xy 420.082969 -45.637576) (xy 420.130979 -45.616595) (xy 420.181411 -45.602384)
			(xy 420.233312 -45.595212) (xy 420.25951 -45.594778) (xy 420.28676 -45.595293) (xy 420.340704 -45.60305)
			(xy 420.392996 -45.618406) (xy 420.44257 -45.641047) (xy 420.488417 -45.670512) (xy 420.529605 -45.706202)
			(xy 420.565294 -45.747391) (xy 420.594758 -45.793239) (xy 420.617398 -45.842813) (xy 420.632752 -45.895105)
			(xy 420.640508 -45.94905) (xy 420.640508 -46.00355) (xy 420.632752 -46.057495) (xy 420.617398 -46.109787)
			(xy 420.594758 -46.159361) (xy 420.565294 -46.205209) (xy 420.529605 -46.246398) (xy 420.488417 -46.282088)
			(xy 420.44257 -46.311553) (xy 420.392996 -46.334194) (xy 420.340704 -46.34955) (xy 420.28676 -46.357307)
			(xy 420.25951 -46.357794) (xy 420.232517 -46.357315) (xy 420.179071 -46.349712) (xy 420.127228 -46.334655)
			(xy 420.078023 -46.312445) (xy 420.032437 -46.283526) (xy 420.011606 -46.266354) (xy 420.003478 -46.259242)
			(xy 419.982904 -46.253146) (xy 419.89756 -46.264068) (xy 419.887025 -46.26588) (xy 419.868739 -46.276909)
			(xy 419.862254 -46.285404) (xy 419.844644 -46.309707) (xy 419.803047 -46.352965) (xy 419.77945 -46.37151)
			(xy 419.771576 -46.377352) (xy 419.761162 -46.394878) (xy 419.747954 -46.485302) (xy 419.75278 -46.504606)
			(xy 419.758622 -46.51248) (xy 419.758622 -46.512734) (xy 419.776119 -46.537483) (xy 419.803924 -46.591333)
			(xy 419.822862 -46.648904) (xy 419.830066 -46.693836) (xy 424.97629 -46.693836) (xy 424.976776 -46.666585)
			(xy 424.984532 -46.612637) (xy 424.999887 -46.560342) (xy 425.022529 -46.510765) (xy 425.051995 -46.464915)
			(xy 425.087686 -46.423724) (xy 425.128877 -46.388033) (xy 425.174727 -46.358567) (xy 425.224304 -46.335925)
			(xy 425.276599 -46.32057) (xy 425.330547 -46.312814) (xy 425.385049 -46.312814) (xy 425.438997 -46.32057)
			(xy 425.491292 -46.335925) (xy 425.540869 -46.358567) (xy 425.586719 -46.388033) (xy 425.62791 -46.423724)
			(xy 425.663601 -46.464915) (xy 425.693067 -46.510765) (xy 425.715709 -46.560342) (xy 425.731064 -46.612637)
			(xy 425.73882 -46.666585) (xy 425.739306 -46.693836) (xy 425.738832 -46.720264) (xy 425.731523 -46.772611)
			(xy 425.71705 -46.823446) (xy 425.695691 -46.871793) (xy 425.682156 -46.894496) (xy 425.681902 -46.89475)
			(xy 425.676565 -46.904768) (xy 425.674306 -46.927319) (xy 425.677584 -46.938184) (xy 425.703746 -47.01286)
			(xy 425.708133 -47.023374) (xy 425.724219 -47.039463) (xy 425.734734 -47.043848) (xy 425.734988 -47.043848)
			(xy 425.759506 -47.052894) (xy 425.805957 -47.076841) (xy 425.848708 -47.106901) (xy 425.886958 -47.142512)
			(xy 425.919993 -47.183008) (xy 425.947196 -47.227631) (xy 425.968056 -47.275549) (xy 425.982186 -47.325864)
			(xy 425.989319 -47.377635) (xy 425.98975 -47.403766) (xy 425.989264 -47.431017) (xy 425.987741 -47.441612)
			(xy 427.26178 -47.441612) (xy 427.265851 -47.38599) (xy 427.277977 -47.331553) (xy 427.2979 -47.279462)
			(xy 427.325196 -47.230827) (xy 427.359282 -47.186684) (xy 427.399431 -47.147975) (xy 427.444789 -47.115524)
			(xy 427.494389 -47.090023) (xy 427.547173 -47.072016) (xy 427.602016 -47.061886) (xy 427.65775 -47.059849)
			(xy 427.713187 -47.065949) (xy 427.767144 -47.080055) (xy 427.818473 -47.101867) (xy 427.866079 -47.130921)
			(xy 427.908947 -47.166596) (xy 427.946164 -47.208133) (xy 427.976937 -47.254646) (xy 428.000609 -47.305143)
			(xy 428.016677 -47.35855) (xy 428.024797 -47.413726) (xy 428.025306 -47.441612) (xy 428.024797 -47.469498)
			(xy 428.016677 -47.524674) (xy 428.000609 -47.578081) (xy 427.976937 -47.628578) (xy 427.946164 -47.675091)
			(xy 427.908947 -47.716628) (xy 427.866079 -47.752303) (xy 427.818473 -47.781357) (xy 427.767144 -47.803169)
			(xy 427.713187 -47.817275) (xy 427.65775 -47.823375) (xy 427.602016 -47.821338) (xy 427.547173 -47.811208)
			(xy 427.494389 -47.793201) (xy 427.444789 -47.7677) (xy 427.399431 -47.735249) (xy 427.359282 -47.69654)
			(xy 427.325196 -47.652397) (xy 427.2979 -47.603762) (xy 427.277977 -47.551671) (xy 427.265851 -47.497234)
			(xy 427.26178 -47.441612) (xy 425.987741 -47.441612) (xy 425.981508 -47.484965) (xy 425.966153 -47.53726)
			(xy 425.943511 -47.586837) (xy 425.914045 -47.632687) (xy 425.878354 -47.673878) (xy 425.837163 -47.709569)
			(xy 425.791313 -47.739035) (xy 425.741736 -47.761677) (xy 425.689441 -47.777032) (xy 425.635493 -47.784788)
			(xy 425.580991 -47.784788) (xy 425.527043 -47.777032) (xy 425.474748 -47.761677) (xy 425.425171 -47.739035)
			(xy 425.379321 -47.709569) (xy 425.33813 -47.673878) (xy 425.302439 -47.632687) (xy 425.272973 -47.586837)
			(xy 425.250331 -47.53726) (xy 425.234976 -47.484965) (xy 425.22722 -47.431017) (xy 425.226734 -47.403766)
			(xy 425.227203 -47.377338) (xy 425.234513 -47.324991) (xy 425.248987 -47.274156) (xy 425.270349 -47.225809)
			(xy 425.283884 -47.203106) (xy 425.284138 -47.202852) (xy 425.289473 -47.192833) (xy 425.291732 -47.170283)
			(xy 425.288456 -47.159418) (xy 425.262294 -47.084742) (xy 425.257934 -47.074214) (xy 425.241829 -47.058131)
			(xy 425.231306 -47.053754) (xy 425.231052 -47.053754) (xy 425.206544 -47.044684) (xy 425.160091 -47.020741)
			(xy 425.117339 -46.990685) (xy 425.079087 -46.955078) (xy 425.046051 -46.914585) (xy 425.018847 -46.869964)
			(xy 424.997985 -46.822049) (xy 424.983855 -46.771736) (xy 424.976721 -46.719966) (xy 424.97629 -46.693836)
			(xy 419.830066 -46.693836) (xy 419.832456 -46.708745) (xy 419.833044 -46.739048) (xy 419.832567 -46.766299)
			(xy 419.824805 -46.820245) (xy 419.809445 -46.872538) (xy 419.786801 -46.922113) (xy 419.757333 -46.967961)
			(xy 419.721641 -47.00915) (xy 419.680451 -47.044841) (xy 419.634602 -47.074307) (xy 419.585026 -47.09695)
			(xy 419.532733 -47.112307) (xy 419.478787 -47.120068) (xy 419.451536 -47.120556) (xy 419.425503 -47.120081)
			(xy 419.373922 -47.113) (xy 419.323781 -47.098976) (xy 419.276009 -47.078272) (xy 419.231493 -47.051269)
			(xy 419.210998 -47.035212) (xy 419.203248 -47.029459) (xy 419.184832 -47.023725) (xy 419.175184 -47.024036)
			(xy 419.095428 -47.030386) (xy 419.077648 -47.039022) (xy 419.071298 -47.046388) (xy 419.053141 -47.066057)
			(xy 419.012228 -47.100577) (xy 418.966894 -47.129043) (xy 418.918028 -47.150897) (xy 418.866588 -47.165709)
			(xy 418.813583 -47.17319) (xy 418.786818 -47.173642) (xy 418.759569 -47.173105) (xy 418.705625 -47.165352)
			(xy 418.653333 -47.150001) (xy 418.603758 -47.127364) (xy 418.557909 -47.097903) (xy 418.51672 -47.062217)
			(xy 418.481028 -47.021032) (xy 418.451561 -46.975187) (xy 418.428917 -46.925616) (xy 418.413559 -46.873326)
			(xy 418.405799 -46.819383) (xy 418.40531 -46.792134) (xy 418.405832 -46.76336) (xy 418.414483 -46.706465)
			(xy 418.43158 -46.651515) (xy 418.456734 -46.599755) (xy 418.489375 -46.552359) (xy 418.508688 -46.531022)
			(xy 418.516054 -46.523148) (xy 418.523166 -46.503336) (xy 418.5158 -46.40707) (xy 418.505894 -46.388274)
			(xy 418.497512 -46.38167) (xy 418.475326 -46.363447) (xy 418.436116 -46.321511) (xy 418.403631 -46.274175)
			(xy 418.378603 -46.222507) (xy 418.361597 -46.167672) (xy 418.352996 -46.110909) (xy 418.352478 -46.082204)
			(xy 412.883604 -46.082204) (xy 412.883604 -48.30699) (xy 424.85386 -48.30699) (xy 424.857931 -48.251368)
			(xy 424.870057 -48.196931) (xy 424.88998 -48.14484) (xy 424.917276 -48.096205) (xy 424.951362 -48.052062)
			(xy 424.991511 -48.013353) (xy 425.036869 -47.980902) (xy 425.086469 -47.955401) (xy 425.139253 -47.937394)
			(xy 425.194096 -47.927264) (xy 425.24983 -47.925227) (xy 425.305267 -47.931327) (xy 425.359224 -47.945433)
			(xy 425.410553 -47.967245) (xy 425.458159 -47.996299) (xy 425.501027 -48.031974) (xy 425.538244 -48.073511)
			(xy 425.569017 -48.120024) (xy 425.592689 -48.170521) (xy 425.608757 -48.223928) (xy 425.616877 -48.279104)
			(xy 425.617386 -48.30699) (xy 425.616877 -48.334876) (xy 425.608757 -48.390052) (xy 425.592689 -48.443459)
			(xy 425.569017 -48.493956) (xy 425.538244 -48.540469) (xy 425.501027 -48.582006) (xy 425.458159 -48.617681)
			(xy 425.410553 -48.646735) (xy 425.359224 -48.668547) (xy 425.305267 -48.682653) (xy 425.24983 -48.688753)
			(xy 425.194096 -48.686716) (xy 425.139253 -48.676586) (xy 425.086469 -48.658579) (xy 425.036869 -48.633078)
			(xy 424.991511 -48.600627) (xy 424.951362 -48.561918) (xy 424.917276 -48.517775) (xy 424.88998 -48.46914)
			(xy 424.870057 -48.417049) (xy 424.857931 -48.362612) (xy 424.85386 -48.30699) (xy 412.883604 -48.30699)
			(xy 412.883604 -48.753014) (xy 421.468294 -48.753014) (xy 421.472365 -48.697392) (xy 421.484491 -48.642955)
			(xy 421.504414 -48.590864) (xy 421.53171 -48.542229) (xy 421.565796 -48.498086) (xy 421.605945 -48.459377)
			(xy 421.651303 -48.426926) (xy 421.700903 -48.401425) (xy 421.753687 -48.383418) (xy 421.80853 -48.373288)
			(xy 421.864264 -48.371251) (xy 421.919701 -48.377351) (xy 421.973658 -48.391457) (xy 422.024987 -48.413269)
			(xy 422.072593 -48.442323) (xy 422.115461 -48.477998) (xy 422.152678 -48.519535) (xy 422.183451 -48.566048)
			(xy 422.207123 -48.616545) (xy 422.223191 -48.669952) (xy 422.231311 -48.725128) (xy 422.23182 -48.753014)
			(xy 422.231311 -48.7809) (xy 422.223191 -48.836076) (xy 422.220747 -48.8442) (xy 422.487342 -48.8442)
			(xy 422.491413 -48.788578) (xy 422.503539 -48.734141) (xy 422.523462 -48.68205) (xy 422.550758 -48.633415)
			(xy 422.584844 -48.589272) (xy 422.624993 -48.550563) (xy 422.670351 -48.518112) (xy 422.719951 -48.492611)
			(xy 422.772735 -48.474604) (xy 422.827578 -48.464474) (xy 422.883312 -48.462437) (xy 422.938749 -48.468537)
			(xy 422.992706 -48.482643) (xy 423.044035 -48.504455) (xy 423.091641 -48.533509) (xy 423.134509 -48.569184)
			(xy 423.171726 -48.610721) (xy 423.202499 -48.657234) (xy 423.226171 -48.707731) (xy 423.242239 -48.761138)
			(xy 423.250359 -48.816314) (xy 423.250868 -48.8442) (xy 423.250359 -48.872086) (xy 423.247361 -48.89246)
			(xy 423.51401 -48.89246) (xy 423.518081 -48.836838) (xy 423.530207 -48.782401) (xy 423.55013 -48.73031)
			(xy 423.577426 -48.681675) (xy 423.611512 -48.637532) (xy 423.651661 -48.598823) (xy 423.697019 -48.566372)
			(xy 423.746619 -48.540871) (xy 423.799403 -48.522864) (xy 423.854246 -48.512734) (xy 423.90998 -48.510697)
			(xy 423.965417 -48.516797) (xy 424.019374 -48.530903) (xy 424.070703 -48.552715) (xy 424.118309 -48.581769)
			(xy 424.161177 -48.617444) (xy 424.198394 -48.658981) (xy 424.229167 -48.705494) (xy 424.252839 -48.755991)
			(xy 424.268907 -48.809398) (xy 424.277027 -48.864574) (xy 424.277536 -48.89246) (xy 424.277027 -48.920346)
			(xy 424.274589 -48.93691) (xy 427.233078 -48.93691) (xy 427.237149 -48.881288) (xy 427.249275 -48.826851)
			(xy 427.269198 -48.77476) (xy 427.296494 -48.726125) (xy 427.33058 -48.681982) (xy 427.370729 -48.643273)
			(xy 427.416087 -48.610822) (xy 427.465687 -48.585321) (xy 427.518471 -48.567314) (xy 427.573314 -48.557184)
			(xy 427.629048 -48.555147) (xy 427.684485 -48.561247) (xy 427.738442 -48.575353) (xy 427.789771 -48.597165)
			(xy 427.837377 -48.626219) (xy 427.880245 -48.661894) (xy 427.917462 -48.703431) (xy 427.948235 -48.749944)
			(xy 427.971907 -48.800441) (xy 427.987975 -48.853848) (xy 427.996095 -48.909024) (xy 427.996604 -48.93691)
			(xy 427.996095 -48.964796) (xy 427.987975 -49.019972) (xy 427.971907 -49.073379) (xy 427.948235 -49.123876)
			(xy 427.917462 -49.170389) (xy 427.880245 -49.211926) (xy 427.837377 -49.247601) (xy 427.789771 -49.276655)
			(xy 427.738442 -49.298467) (xy 427.684485 -49.312573) (xy 427.629048 -49.318673) (xy 427.573314 -49.316636)
			(xy 427.518471 -49.306506) (xy 427.465687 -49.288499) (xy 427.416087 -49.262998) (xy 427.370729 -49.230547)
			(xy 427.33058 -49.191838) (xy 427.296494 -49.147695) (xy 427.269198 -49.09906) (xy 427.249275 -49.046969)
			(xy 427.237149 -48.992532) (xy 427.233078 -48.93691) (xy 424.274589 -48.93691) (xy 424.268907 -48.975522)
			(xy 424.252839 -49.028929) (xy 424.229167 -49.079426) (xy 424.198394 -49.125939) (xy 424.161177 -49.167476)
			(xy 424.118309 -49.203151) (xy 424.070703 -49.232205) (xy 424.019374 -49.254017) (xy 423.965417 -49.268123)
			(xy 423.90998 -49.274223) (xy 423.854246 -49.272186) (xy 423.799403 -49.262056) (xy 423.746619 -49.244049)
			(xy 423.697019 -49.218548) (xy 423.651661 -49.186097) (xy 423.611512 -49.147388) (xy 423.577426 -49.103245)
			(xy 423.55013 -49.05461) (xy 423.530207 -49.002519) (xy 423.518081 -48.948082) (xy 423.51401 -48.89246)
			(xy 423.247361 -48.89246) (xy 423.242239 -48.927262) (xy 423.226171 -48.980669) (xy 423.202499 -49.031166)
			(xy 423.171726 -49.077679) (xy 423.134509 -49.119216) (xy 423.091641 -49.154891) (xy 423.044035 -49.183945)
			(xy 422.992706 -49.205757) (xy 422.938749 -49.219863) (xy 422.883312 -49.225963) (xy 422.827578 -49.223926)
			(xy 422.772735 -49.213796) (xy 422.719951 -49.195789) (xy 422.670351 -49.170288) (xy 422.624993 -49.137837)
			(xy 422.584844 -49.099128) (xy 422.550758 -49.054985) (xy 422.523462 -49.00635) (xy 422.503539 -48.954259)
			(xy 422.491413 -48.899822) (xy 422.487342 -48.8442) (xy 422.220747 -48.8442) (xy 422.207123 -48.889483)
			(xy 422.183451 -48.93998) (xy 422.152678 -48.986493) (xy 422.115461 -49.02803) (xy 422.072593 -49.063705)
			(xy 422.024987 -49.092759) (xy 421.973658 -49.114571) (xy 421.919701 -49.128677) (xy 421.864264 -49.134777)
			(xy 421.80853 -49.13274) (xy 421.753687 -49.12261) (xy 421.700903 -49.104603) (xy 421.651303 -49.079102)
			(xy 421.605945 -49.046651) (xy 421.565796 -49.007942) (xy 421.53171 -48.963799) (xy 421.504414 -48.915164)
			(xy 421.484491 -48.863073) (xy 421.472365 -48.808636) (xy 421.468294 -48.753014) (xy 412.883604 -48.753014)
			(xy 412.883604 -49.601953) (xy 432.412859 -49.601953) (xy 432.412859 -49.547447) (xy 432.420616 -49.493497)
			(xy 432.435972 -49.441199) (xy 432.458615 -49.39162) (xy 432.488083 -49.345767) (xy 432.523776 -49.304575)
			(xy 432.564968 -49.268881) (xy 432.610821 -49.239414) (xy 432.660401 -49.216772) (xy 432.712699 -49.201416)
			(xy 432.766649 -49.193659) (xy 432.793902 -49.193196) (xy 432.821272 -49.193662) (xy 432.875451 -49.20148)
			(xy 432.927954 -49.216969) (xy 432.977701 -49.239811) (xy 433.023668 -49.269535) (xy 433.0446 -49.287176)
			(xy 433.044854 -49.28743) (xy 433.051947 -49.293007) (xy 433.068859 -49.299258) (xy 433.077874 -49.299622)
			(xy 433.14493 -49.299622) (xy 433.153948 -49.299275) (xy 433.170864 -49.29302) (xy 433.17795 -49.28743)
			(xy 433.17795 -49.287176) (xy 433.178204 -49.287176) (xy 433.199137 -49.269535) (xy 433.245105 -49.239811)
			(xy 433.294851 -49.216965) (xy 433.347353 -49.201469) (xy 433.401531 -49.19364) (xy 433.456273 -49.19364)
			(xy 433.510451 -49.201469) (xy 433.562953 -49.216965) (xy 433.612699 -49.239811) (xy 433.658667 -49.269535)
			(xy 433.6796 -49.287176) (xy 433.679854 -49.28743) (xy 433.686947 -49.293007) (xy 433.703859 -49.299258)
			(xy 433.712874 -49.299622) (xy 433.77993 -49.299622) (xy 433.788948 -49.299275) (xy 433.805864 -49.29302)
			(xy 433.81295 -49.28743) (xy 433.81295 -49.287176) (xy 433.813204 -49.287176) (xy 433.834137 -49.269535)
			(xy 433.880105 -49.239811) (xy 433.929851 -49.216965) (xy 433.982353 -49.201469) (xy 434.036531 -49.19364)
			(xy 434.091273 -49.19364) (xy 434.145451 -49.201469) (xy 434.197953 -49.216965) (xy 434.247699 -49.239811)
			(xy 434.293667 -49.269535) (xy 434.3146 -49.287176) (xy 434.314854 -49.28743) (xy 434.321947 -49.293007)
			(xy 434.338859 -49.299258) (xy 434.347874 -49.299622) (xy 434.41493 -49.299622) (xy 434.423948 -49.299275)
			(xy 434.440864 -49.29302) (xy 434.44795 -49.28743) (xy 434.44795 -49.287176) (xy 434.448204 -49.287176)
			(xy 434.469121 -49.269518) (xy 434.515098 -49.23981) (xy 434.56485 -49.216978) (xy 434.617353 -49.201491)
			(xy 434.671532 -49.193668) (xy 434.698902 -49.193196) (xy 434.726153 -49.193674) (xy 434.780102 -49.201431)
			(xy 434.832397 -49.216786) (xy 434.881974 -49.239428) (xy 434.927825 -49.268894) (xy 434.969015 -49.304586)
			(xy 435.004707 -49.345777) (xy 435.034173 -49.391628) (xy 435.056814 -49.441205) (xy 435.07217 -49.4935)
			(xy 435.079926 -49.547449) (xy 435.079926 -49.601951) (xy 435.07217 -49.6559) (xy 435.056814 -49.708195)
			(xy 435.034173 -49.757772) (xy 435.004707 -49.803623) (xy 434.969015 -49.844814) (xy 434.927825 -49.880506)
			(xy 434.881974 -49.909972) (xy 434.832397 -49.932614) (xy 434.780102 -49.947969) (xy 434.726153 -49.955726)
			(xy 434.698902 -49.956212) (xy 434.671532 -49.955742) (xy 434.617353 -49.947925) (xy 434.56485 -49.932436)
			(xy 434.515103 -49.909596) (xy 434.469136 -49.879872) (xy 434.448204 -49.862232) (xy 434.44795 -49.861978)
			(xy 434.440855 -49.856404) (xy 434.423945 -49.85015) (xy 434.41493 -49.849786) (xy 434.347874 -49.849786)
			(xy 434.338856 -49.850134) (xy 434.32194 -49.856388) (xy 434.314854 -49.861978) (xy 434.3146 -49.862232)
			(xy 434.293667 -49.879873) (xy 434.247699 -49.909597) (xy 434.197953 -49.932443) (xy 434.145451 -49.947939)
			(xy 434.091273 -49.955768) (xy 434.036531 -49.955768) (xy 433.982353 -49.947939) (xy 433.929851 -49.932443)
			(xy 433.880105 -49.909597) (xy 433.834137 -49.879873) (xy 433.813204 -49.862232) (xy 433.81295 -49.861978)
			(xy 433.805855 -49.856404) (xy 433.788945 -49.85015) (xy 433.77993 -49.849786) (xy 433.712874 -49.849786)
			(xy 433.703856 -49.850134) (xy 433.68694 -49.856388) (xy 433.679854 -49.861978) (xy 433.679854 -49.862232)
			(xy 433.6796 -49.862232) (xy 433.658667 -49.879873) (xy 433.612699 -49.909597) (xy 433.562953 -49.932443)
			(xy 433.510451 -49.947939) (xy 433.456273 -49.955768) (xy 433.401531 -49.955768) (xy 433.347353 -49.947939)
			(xy 433.294851 -49.932443) (xy 433.245105 -49.909597) (xy 433.199137 -49.879873) (xy 433.178204 -49.862232)
			(xy 433.17795 -49.861978) (xy 433.170855 -49.856404) (xy 433.153945 -49.85015) (xy 433.14493 -49.849786)
			(xy 433.077874 -49.849786) (xy 433.068856 -49.850134) (xy 433.05194 -49.856388) (xy 433.044854 -49.861978)
			(xy 433.044854 -49.862232) (xy 433.0446 -49.862232) (xy 433.023683 -49.87989) (xy 432.977705 -49.909598)
			(xy 432.927954 -49.932429) (xy 432.87545 -49.947916) (xy 432.821272 -49.95574) (xy 432.793902 -49.956212)
			(xy 432.766649 -49.955741) (xy 432.712699 -49.947984) (xy 432.660401 -49.932628) (xy 432.610821 -49.909986)
			(xy 432.564968 -49.880519) (xy 432.523776 -49.844825) (xy 432.488083 -49.803633) (xy 432.458615 -49.75778)
			(xy 432.435972 -49.708201) (xy 432.420616 -49.655903) (xy 432.412859 -49.601953) (xy 412.883604 -49.601953)
			(xy 412.883604 -50.502312) (xy 423.116754 -50.502312) (xy 423.120825 -50.44669) (xy 423.132951 -50.392253)
			(xy 423.152874 -50.340162) (xy 423.18017 -50.291527) (xy 423.214256 -50.247384) (xy 423.254405 -50.208675)
			(xy 423.299763 -50.176224) (xy 423.349363 -50.150723) (xy 423.402147 -50.132716) (xy 423.45699 -50.122586)
			(xy 423.512724 -50.120549) (xy 423.568161 -50.126649) (xy 423.622118 -50.140755) (xy 423.673447 -50.162567)
			(xy 423.721053 -50.191621) (xy 423.763921 -50.227296) (xy 423.801138 -50.268833) (xy 423.831911 -50.315346)
			(xy 423.855583 -50.365843) (xy 423.871651 -50.41925) (xy 423.879771 -50.474426) (xy 423.88028 -50.502312)
			(xy 423.879771 -50.530198) (xy 423.871651 -50.585374) (xy 423.855583 -50.638781) (xy 423.831911 -50.689278)
			(xy 423.801138 -50.735791) (xy 423.763921 -50.777328) (xy 423.721053 -50.813003) (xy 423.673447 -50.842057)
			(xy 423.622118 -50.863869) (xy 423.568161 -50.877975) (xy 423.512724 -50.884075) (xy 423.45699 -50.882038)
			(xy 423.402147 -50.871908) (xy 423.349363 -50.853901) (xy 423.299763 -50.8284) (xy 423.254405 -50.795949)
			(xy 423.214256 -50.75724) (xy 423.18017 -50.713097) (xy 423.152874 -50.664462) (xy 423.132951 -50.612371)
			(xy 423.120825 -50.557934) (xy 423.116754 -50.502312) (xy 412.883604 -50.502312) (xy 412.883604 -51.019456)
			(xy 425.04944 -51.019456) (xy 425.053511 -50.963834) (xy 425.065637 -50.909397) (xy 425.08556 -50.857306)
			(xy 425.112856 -50.808671) (xy 425.146942 -50.764528) (xy 425.187091 -50.725819) (xy 425.232449 -50.693368)
			(xy 425.282049 -50.667867) (xy 425.334833 -50.64986) (xy 425.389676 -50.63973) (xy 425.44541 -50.637693)
			(xy 425.500847 -50.643793) (xy 425.554804 -50.657899) (xy 425.606133 -50.679711) (xy 425.653739 -50.708765)
			(xy 425.696607 -50.74444) (xy 425.733824 -50.785977) (xy 425.764597 -50.83249) (xy 425.788269 -50.882987)
			(xy 425.804337 -50.936394) (xy 425.812457 -50.99157) (xy 425.812966 -51.019456) (xy 425.812457 -51.047342)
			(xy 425.804337 -51.102518) (xy 425.788269 -51.155925) (xy 425.764597 -51.206422) (xy 425.739741 -51.243992)
			(xy 433.432966 -51.243992) (xy 433.433411 -51.216621) (xy 433.441232 -51.16244) (xy 433.456725 -51.109936)
			(xy 433.479571 -51.06019) (xy 433.509302 -51.014224) (xy 433.526946 -50.993294) (xy 433.5272 -50.99304)
			(xy 433.532776 -50.985946) (xy 433.539029 -50.969035) (xy 433.539392 -50.96002) (xy 433.539392 -50.892964)
			(xy 433.539054 -50.883945) (xy 433.532793 -50.867028) (xy 433.5272 -50.859944) (xy 433.526946 -50.859944)
			(xy 433.526946 -50.85969) (xy 433.509296 -50.838767) (xy 433.479584 -50.792792) (xy 433.45675 -50.743043)
			(xy 433.441261 -50.69054) (xy 433.433437 -50.636362) (xy 433.432966 -50.608992) (xy 433.43347 -50.581742)
			(xy 433.441227 -50.527796) (xy 433.456582 -50.475503) (xy 433.479222 -50.425928) (xy 433.508687 -50.380079)
			(xy 433.544376 -50.338889) (xy 433.585564 -50.303198) (xy 433.631412 -50.273731) (xy 433.680986 -50.251088)
			(xy 433.733278 -50.235731) (xy 433.787224 -50.227972) (xy 433.814474 -50.227484) (xy 433.843392 -50.227989)
			(xy 433.900565 -50.236716) (xy 433.955766 -50.253975) (xy 434.007728 -50.279369) (xy 434.055261 -50.312316)
			(xy 434.097276 -50.352062) (xy 434.115464 -50.37455) (xy 434.123088 -50.383339) (xy 434.143976 -50.393531)
			(xy 434.155596 -50.394108) (xy 434.235352 -50.394108) (xy 434.246985 -50.393582) (xy 434.267894 -50.383383)
			(xy 434.275484 -50.37455) (xy 434.293671 -50.352064) (xy 434.335693 -50.312331) (xy 434.38323 -50.279394)
			(xy 434.435191 -50.254006) (xy 434.490389 -50.23675) (xy 434.547558 -50.22802) (xy 434.576474 -50.227484)
			(xy 434.603726 -50.227979) (xy 434.657675 -50.235733) (xy 434.709972 -50.251085) (xy 434.759551 -50.273724)
			(xy 434.805404 -50.303188) (xy 434.846597 -50.338879) (xy 434.882291 -50.380068) (xy 434.91176 -50.425919)
			(xy 434.934403 -50.475496) (xy 434.94976 -50.527792) (xy 434.957518 -50.58174) (xy 434.957982 -50.608992)
			(xy 434.957515 -50.635306) (xy 434.950281 -50.687435) (xy 434.935962 -50.738078) (xy 434.91483 -50.786277)
			(xy 434.887283 -50.83112) (xy 434.853844 -50.87176) (xy 434.834792 -50.889916) (xy 434.82738 -50.897429)
			(xy 434.818862 -50.916716) (xy 434.818282 -50.927254) (xy 434.818282 -51.00193) (xy 434.818841 -51.012476)
			(xy 434.827356 -51.031772) (xy 434.834792 -51.039268) (xy 434.853872 -51.057399) (xy 434.887327 -51.098034)
			(xy 434.914883 -51.142879) (xy 434.936017 -51.191085) (xy 434.950329 -51.241737) (xy 434.957547 -51.293874)
			(xy 434.957982 -51.320192) (xy 434.957537 -51.347446) (xy 434.949781 -51.401399) (xy 434.934424 -51.453699)
			(xy 434.911781 -51.50328) (xy 434.882311 -51.549135) (xy 434.846615 -51.590328) (xy 434.80542 -51.626022)
			(xy 434.759565 -51.655489) (xy 434.709982 -51.678131) (xy 434.657681 -51.693484) (xy 434.603728 -51.701238)
			(xy 434.576474 -51.7017) (xy 434.548808 -51.701208) (xy 434.494058 -51.693205) (xy 434.441036 -51.677385)
			(xy 434.390852 -51.654079) (xy 434.344557 -51.623774) (xy 434.303119 -51.587106) (xy 434.267407 -51.544842)
			(xy 434.25237 -51.521614) (xy 434.245757 -51.511918) (xy 434.225878 -51.499485) (xy 434.21427 -51.497738)
			(xy 434.13426 -51.489864) (xy 434.122621 -51.489211) (xy 434.100782 -51.497305) (xy 434.09235 -51.505358)
			(xy 434.092096 -51.505612) (xy 434.074002 -51.52418) (xy 434.033672 -51.556759) (xy 433.989301 -51.583573)
			(xy 433.941705 -51.604128) (xy 433.891763 -51.618045) (xy 433.840396 -51.625066) (xy 433.814474 -51.6255)
			(xy 433.787222 -51.625046) (xy 433.733272 -51.617286) (xy 433.680977 -51.601927) (xy 433.631399 -51.579283)
			(xy 433.585548 -51.549813) (xy 433.544358 -51.514118) (xy 433.508667 -51.472925) (xy 433.479201 -51.427071)
			(xy 433.456561 -51.377491) (xy 433.441207 -51.325194) (xy 433.433451 -51.271244) (xy 433.432966 -51.243992)
			(xy 425.739741 -51.243992) (xy 425.733824 -51.252935) (xy 425.696607 -51.294472) (xy 425.653739 -51.330147)
			(xy 425.606133 -51.359201) (xy 425.554804 -51.381013) (xy 425.500847 -51.395119) (xy 425.44541 -51.401219)
			(xy 425.389676 -51.399182) (xy 425.334833 -51.389052) (xy 425.282049 -51.371045) (xy 425.232449 -51.345544)
			(xy 425.187091 -51.313093) (xy 425.146942 -51.274384) (xy 425.112856 -51.230241) (xy 425.08556 -51.181606)
			(xy 425.065637 -51.129515) (xy 425.053511 -51.075078) (xy 425.04944 -51.019456) (xy 412.883604 -51.019456)
			(xy 412.883604 -52.035456) (xy 427.241206 -52.035456) (xy 427.245277 -51.979834) (xy 427.257403 -51.925397)
			(xy 427.277326 -51.873306) (xy 427.304622 -51.824671) (xy 427.338708 -51.780528) (xy 427.378857 -51.741819)
			(xy 427.424215 -51.709368) (xy 427.473815 -51.683867) (xy 427.526599 -51.66586) (xy 427.581442 -51.65573)
			(xy 427.637176 -51.653693) (xy 427.692613 -51.659793) (xy 427.74657 -51.673899) (xy 427.797899 -51.695711)
			(xy 427.845505 -51.724765) (xy 427.888373 -51.76044) (xy 427.92559 -51.801977) (xy 427.956363 -51.84849)
			(xy 427.980035 -51.898987) (xy 427.996103 -51.952394) (xy 428.004223 -52.00757) (xy 428.004732 -52.035456)
			(xy 428.004223 -52.063342) (xy 427.996103 -52.118518) (xy 427.980035 -52.171925) (xy 427.956363 -52.222422)
			(xy 427.92559 -52.268935) (xy 427.888373 -52.310472) (xy 427.845505 -52.346147) (xy 427.797899 -52.375201)
			(xy 427.74657 -52.397013) (xy 427.692613 -52.411119) (xy 427.637176 -52.417219) (xy 427.581442 -52.415182)
			(xy 427.526599 -52.405052) (xy 427.473815 -52.387045) (xy 427.424215 -52.361544) (xy 427.378857 -52.329093)
			(xy 427.338708 -52.290384) (xy 427.304622 -52.246241) (xy 427.277326 -52.197606) (xy 427.257403 -52.145515)
			(xy 427.245277 -52.091078) (xy 427.241206 -52.035456) (xy 412.883604 -52.035456) (xy 412.883604 -54.731412)
			(xy 413.82061 -54.731412) (xy 413.821081 -54.704042) (xy 413.828897 -54.649863) (xy 413.844385 -54.59736)
			(xy 413.867226 -54.547613) (xy 413.896949 -54.501646) (xy 413.91459 -54.480714) (xy 413.914844 -54.48046)
			(xy 413.920417 -54.473364) (xy 413.926671 -54.456454) (xy 413.927036 -54.44744) (xy 413.927036 -54.380384)
			(xy 413.926679 -54.371367) (xy 413.920431 -54.354451) (xy 413.914844 -54.347364) (xy 413.91459 -54.347364)
			(xy 413.91459 -54.34711) (xy 413.896963 -54.326167) (xy 413.86724 -54.2802) (xy 413.844396 -54.230455)
			(xy 413.828901 -54.177955) (xy 413.821072 -54.123779) (xy 413.821071 -54.069039) (xy 413.828897 -54.014863)
			(xy 413.84439 -53.962362) (xy 413.867231 -53.912616) (xy 413.896952 -53.866647) (xy 413.91459 -53.845714)
			(xy 413.914844 -53.84546) (xy 413.920417 -53.838364) (xy 413.926671 -53.821454) (xy 413.927036 -53.81244)
			(xy 413.927036 -53.745384) (xy 413.926679 -53.736367) (xy 413.920431 -53.719451) (xy 413.914844 -53.712364)
			(xy 413.91459 -53.712364) (xy 413.91459 -53.71211) (xy 413.896963 -53.691167) (xy 413.86724 -53.6452)
			(xy 413.844396 -53.595455) (xy 413.828901 -53.542955) (xy 413.821072 -53.488779) (xy 413.821071 -53.434039)
			(xy 413.828897 -53.379863) (xy 413.84439 -53.327362) (xy 413.867231 -53.277616) (xy 413.896952 -53.231647)
			(xy 413.91459 -53.210714) (xy 413.914844 -53.21046) (xy 413.920417 -53.203364) (xy 413.926671 -53.186454)
			(xy 413.927036 -53.17744) (xy 413.927036 -53.110384) (xy 413.926679 -53.101367) (xy 413.920431 -53.084451)
			(xy 413.914844 -53.077364) (xy 413.91459 -53.077364) (xy 413.91459 -53.07711) (xy 413.896941 -53.056186)
			(xy 413.867231 -53.010211) (xy 413.844397 -52.960461) (xy 413.828908 -52.907959) (xy 413.821083 -52.853782)
			(xy 413.82061 -52.826412) (xy 413.821096 -52.799161) (xy 413.828852 -52.745213) (xy 413.844207 -52.692918)
			(xy 413.866849 -52.643341) (xy 413.896315 -52.597491) (xy 413.932006 -52.5563) (xy 413.973197 -52.520609)
			(xy 414.019047 -52.491143) (xy 414.068624 -52.468501) (xy 414.120919 -52.453146) (xy 414.174867 -52.44539)
			(xy 414.229369 -52.44539) (xy 414.283317 -52.453146) (xy 414.335612 -52.468501) (xy 414.385189 -52.491143)
			(xy 414.431039 -52.520609) (xy 414.47223 -52.5563) (xy 414.507921 -52.597491) (xy 414.537387 -52.643341)
			(xy 414.560029 -52.692918) (xy 414.575384 -52.745213) (xy 414.58314 -52.799161) (xy 414.583626 -52.826412)
			(xy 414.583185 -52.853783) (xy 414.575364 -52.907964) (xy 414.55987 -52.960468) (xy 414.537022 -53.010215)
			(xy 414.507291 -53.05618) (xy 414.489646 -53.07711) (xy 414.489392 -53.077364) (xy 414.483813 -53.084456)
			(xy 414.477562 -53.101369) (xy 414.4772 -53.110384) (xy 414.4772 -53.17744) (xy 414.477538 -53.186459)
			(xy 414.483799 -53.203376) (xy 414.489392 -53.21046) (xy 414.489646 -53.21046) (xy 414.489646 -53.210714)
			(xy 414.5073 -53.231637) (xy 414.537026 -53.277606) (xy 414.559872 -53.327353) (xy 414.575369 -53.379857)
			(xy 414.583197 -53.434038) (xy 414.583196 -53.488781) (xy 414.575365 -53.542961) (xy 414.559866 -53.595464)
			(xy 414.537017 -53.64521) (xy 414.507289 -53.691178) (xy 414.489646 -53.71211) (xy 414.489392 -53.712364)
			(xy 414.483813 -53.719456) (xy 414.477562 -53.736369) (xy 414.4772 -53.745384) (xy 414.4772 -53.81244)
			(xy 414.477538 -53.821459) (xy 414.483799 -53.838376) (xy 414.489392 -53.84546) (xy 414.489646 -53.84546)
			(xy 414.489646 -53.845714) (xy 414.5073 -53.866637) (xy 414.537026 -53.912606) (xy 414.559872 -53.962353)
			(xy 414.575369 -54.014857) (xy 414.583197 -54.069038) (xy 414.583196 -54.123781) (xy 414.575365 -54.177961)
			(xy 414.559866 -54.230464) (xy 414.537017 -54.28021) (xy 414.507289 -54.326178) (xy 414.489646 -54.34711)
			(xy 414.489392 -54.347364) (xy 414.483813 -54.354456) (xy 414.477562 -54.371369) (xy 414.4772 -54.380384)
			(xy 414.4772 -54.44744) (xy 414.477538 -54.456459) (xy 414.483799 -54.473376) (xy 414.489392 -54.48046)
			(xy 414.489646 -54.48046) (xy 414.489646 -54.480714) (xy 414.50725 -54.501675) (xy 414.536969 -54.547639)
			(xy 414.559812 -54.597379) (xy 414.575312 -54.649874) (xy 414.583148 -54.704045) (xy 414.583626 -54.731412)
			(xy 414.58314 -54.758663) (xy 414.578476 -54.791102) (xy 416.476434 -54.791102) (xy 416.476893 -54.763731)
			(xy 416.484711 -54.709552) (xy 416.500202 -54.657048) (xy 416.523045 -54.607301) (xy 416.552772 -54.561335)
			(xy 416.570414 -54.540404) (xy 416.570668 -54.54015) (xy 416.576248 -54.533059) (xy 416.582497 -54.516145)
			(xy 416.58286 -54.50713) (xy 416.58286 -54.440074) (xy 416.582524 -54.431055) (xy 416.576263 -54.414137)
			(xy 416.570668 -54.407054) (xy 416.570414 -54.407054) (xy 416.570414 -54.4068) (xy 416.552776 -54.385865)
			(xy 416.523052 -54.339898) (xy 416.500207 -54.290152) (xy 416.484711 -54.23765) (xy 416.476883 -54.183472)
			(xy 416.476883 -54.128731) (xy 416.484711 -54.074553) (xy 416.500206 -54.022051) (xy 416.52305 -53.972305)
			(xy 416.552774 -53.926337) (xy 416.570414 -53.905404) (xy 416.570668 -53.90515) (xy 416.576248 -53.898059)
			(xy 416.582497 -53.881145) (xy 416.58286 -53.87213) (xy 416.58286 -53.805074) (xy 416.582524 -53.796055)
			(xy 416.576263 -53.779137) (xy 416.570668 -53.772054) (xy 416.570414 -53.772054) (xy 416.570414 -53.7718)
			(xy 416.552776 -53.750865) (xy 416.523052 -53.704898) (xy 416.500207 -53.655152) (xy 416.484711 -53.60265)
			(xy 416.476883 -53.548472) (xy 416.476883 -53.493731) (xy 416.484711 -53.439553) (xy 416.500206 -53.387051)
			(xy 416.52305 -53.337305) (xy 416.552774 -53.291337) (xy 416.570414 -53.270404) (xy 416.570668 -53.27015)
			(xy 416.576248 -53.263059) (xy 416.582497 -53.246145) (xy 416.58286 -53.23713) (xy 416.58286 -53.170074)
			(xy 416.582524 -53.161055) (xy 416.576263 -53.144137) (xy 416.570668 -53.137054) (xy 416.570414 -53.137054)
			(xy 416.570414 -53.1368) (xy 416.552764 -53.115877) (xy 416.523053 -53.069902) (xy 416.500219 -53.020152)
			(xy 416.484731 -52.967649) (xy 416.476906 -52.913472) (xy 416.476434 -52.886102) (xy 416.47692 -52.858851)
			(xy 416.484676 -52.804903) (xy 416.500031 -52.752608) (xy 416.522673 -52.703031) (xy 416.552139 -52.657181)
			(xy 416.58783 -52.61599) (xy 416.629021 -52.580299) (xy 416.674871 -52.550833) (xy 416.724448 -52.528191)
			(xy 416.776743 -52.512836) (xy 416.830691 -52.50508) (xy 416.885193 -52.50508) (xy 416.939141 -52.512836)
			(xy 416.991436 -52.528191) (xy 417.03054 -52.54605) (xy 421.979596 -52.54605) (xy 421.979596 -52.49155)
			(xy 421.987352 -52.437605) (xy 422.002707 -52.385313) (xy 422.025347 -52.335738) (xy 422.054811 -52.28989)
			(xy 422.090501 -52.248702) (xy 422.131689 -52.213012) (xy 422.177537 -52.183547) (xy 422.227111 -52.160907)
			(xy 422.279403 -52.145553) (xy 422.333348 -52.137796) (xy 422.360598 -52.13731) (xy 422.387968 -52.137775)
			(xy 422.442148 -52.145593) (xy 422.494651 -52.161082) (xy 422.544398 -52.183924) (xy 422.590364 -52.213649)
			(xy 422.611296 -52.23129) (xy 422.61155 -52.231544) (xy 422.618643 -52.237121) (xy 422.635555 -52.243372)
			(xy 422.64457 -52.243736) (xy 422.711626 -52.243736) (xy 422.720643 -52.243384) (xy 422.73756 -52.237132)
			(xy 422.744646 -52.231544) (xy 422.744646 -52.23129) (xy 422.7449 -52.23129) (xy 422.765833 -52.213649)
			(xy 422.811801 -52.183925) (xy 422.861547 -52.161079) (xy 422.914049 -52.145583) (xy 422.968227 -52.137754)
			(xy 423.022969 -52.137754) (xy 423.077147 -52.145583) (xy 423.129649 -52.161079) (xy 423.179395 -52.183925)
			(xy 423.225363 -52.213649) (xy 423.246296 -52.23129) (xy 423.24655 -52.231544) (xy 423.253643 -52.237121)
			(xy 423.270555 -52.243372) (xy 423.27957 -52.243736) (xy 423.346626 -52.243736) (xy 423.355643 -52.243384)
			(xy 423.37256 -52.237132) (xy 423.379646 -52.231544) (xy 423.379646 -52.23129) (xy 423.3799 -52.23129)
			(xy 423.40082 -52.213636) (xy 423.446796 -52.183927) (xy 423.496547 -52.161094) (xy 423.54905 -52.145606)
			(xy 423.603228 -52.137782) (xy 423.630598 -52.13731) (xy 423.657852 -52.137737) (xy 423.711806 -52.145494)
			(xy 423.764107 -52.16085) (xy 423.813689 -52.183494) (xy 423.859545 -52.212963) (xy 423.90074 -52.248659)
			(xy 423.936435 -52.289853) (xy 423.965905 -52.335709) (xy 423.988549 -52.385292) (xy 424.003906 -52.437592)
			(xy 424.011663 -52.491546) (xy 424.011663 -52.546054) (xy 424.005719 -52.587398) (xy 425.055282 -52.587398)
			(xy 425.059353 -52.531776) (xy 425.071479 -52.477339) (xy 425.091402 -52.425248) (xy 425.118698 -52.376613)
			(xy 425.152784 -52.33247) (xy 425.192933 -52.293761) (xy 425.238291 -52.26131) (xy 425.287891 -52.235809)
			(xy 425.340675 -52.217802) (xy 425.395518 -52.207672) (xy 425.451252 -52.205635) (xy 425.506689 -52.211735)
			(xy 425.560646 -52.225841) (xy 425.611975 -52.247653) (xy 425.659581 -52.276707) (xy 425.702449 -52.312382)
			(xy 425.739666 -52.353919) (xy 425.770439 -52.400432) (xy 425.794111 -52.450929) (xy 425.810179 -52.504336)
			(xy 425.817775 -52.555952) (xy 432.883779 -52.555952) (xy 432.883779 -52.501448) (xy 432.891536 -52.447499)
			(xy 432.906892 -52.395203) (xy 432.929535 -52.345625) (xy 432.959002 -52.299774) (xy 432.994696 -52.258583)
			(xy 433.035888 -52.222892) (xy 433.081741 -52.193426) (xy 433.13132 -52.170786) (xy 433.183617 -52.155432)
			(xy 433.237566 -52.147678) (xy 433.264818 -52.147216) (xy 433.292189 -52.147668) (xy 433.346369 -52.155488)
			(xy 433.398872 -52.170981) (xy 433.448619 -52.193826) (xy 433.494585 -52.223553) (xy 433.515516 -52.241196)
			(xy 433.51577 -52.24145) (xy 433.522857 -52.247036) (xy 433.539774 -52.253282) (xy 433.54879 -52.253642)
			(xy 433.615846 -52.253642) (xy 433.624862 -52.253272) (xy 433.64178 -52.247035) (xy 433.648866 -52.24145)
			(xy 433.648866 -52.241196) (xy 433.64912 -52.241196) (xy 433.670071 -52.22358) (xy 433.716039 -52.193865)
			(xy 433.765781 -52.171025) (xy 433.818278 -52.155528) (xy 433.87245 -52.147694) (xy 433.899818 -52.147216)
			(xy 433.92707 -52.147655) (xy 433.981019 -52.155414) (xy 434.033315 -52.170772) (xy 434.082893 -52.193415)
			(xy 434.128744 -52.222884) (xy 434.169935 -52.258578) (xy 434.205627 -52.29977) (xy 434.235093 -52.345623)
			(xy 434.257734 -52.395202) (xy 434.27309 -52.447498) (xy 434.280846 -52.501448) (xy 434.280846 -52.555952)
			(xy 434.27309 -52.609902) (xy 434.257734 -52.662198) (xy 434.235093 -52.711777) (xy 434.205627 -52.75763)
			(xy 434.169935 -52.798822) (xy 434.128744 -52.834516) (xy 434.082893 -52.863985) (xy 434.033315 -52.886628)
			(xy 433.981019 -52.901986) (xy 433.92707 -52.909745) (xy 433.899818 -52.910232) (xy 433.872447 -52.909772)
			(xy 433.818267 -52.901955) (xy 433.765764 -52.886466) (xy 433.716017 -52.863622) (xy 433.670051 -52.833895)
			(xy 433.64912 -52.816252) (xy 433.648866 -52.815998) (xy 433.641765 -52.810433) (xy 433.624859 -52.804173)
			(xy 433.615846 -52.803806) (xy 433.54879 -52.803806) (xy 433.539772 -52.804157) (xy 433.522856 -52.810409)
			(xy 433.51577 -52.815998) (xy 433.51577 -52.816252) (xy 433.515516 -52.816252) (xy 433.494583 -52.83389)
			(xy 433.448611 -52.863603) (xy 433.398864 -52.88644) (xy 433.346363 -52.901932) (xy 433.292187 -52.909759)
			(xy 433.264818 -52.910232) (xy 433.237566 -52.909722) (xy 433.183617 -52.901968) (xy 433.13132 -52.886614)
			(xy 433.081741 -52.863974) (xy 433.035888 -52.834508) (xy 432.994696 -52.798817) (xy 432.959002 -52.757626)
			(xy 432.929535 -52.711775) (xy 432.906892 -52.662197) (xy 432.891536 -52.609901) (xy 432.883779 -52.555952)
			(xy 425.817775 -52.555952) (xy 425.818299 -52.559512) (xy 425.818808 -52.587398) (xy 425.818299 -52.615284)
			(xy 425.810179 -52.67046) (xy 425.794111 -52.723867) (xy 425.770439 -52.774364) (xy 425.739666 -52.820877)
			(xy 425.702449 -52.862414) (xy 425.659581 -52.898089) (xy 425.611975 -52.927143) (xy 425.560646 -52.948955)
			(xy 425.506689 -52.963061) (xy 425.451252 -52.969161) (xy 425.395518 -52.967124) (xy 425.340675 -52.956994)
			(xy 425.287891 -52.938987) (xy 425.238291 -52.913486) (xy 425.192933 -52.881035) (xy 425.152784 -52.842326)
			(xy 425.118698 -52.798183) (xy 425.091402 -52.749548) (xy 425.071479 -52.697457) (xy 425.059353 -52.64302)
			(xy 425.055282 -52.587398) (xy 424.005719 -52.587398) (xy 424.003906 -52.600008) (xy 423.988549 -52.652308)
			(xy 423.965905 -52.701891) (xy 423.936435 -52.747747) (xy 423.90074 -52.788941) (xy 423.859545 -52.824637)
			(xy 423.813689 -52.854106) (xy 423.764107 -52.87675) (xy 423.711806 -52.892106) (xy 423.657852 -52.899863)
			(xy 423.630598 -52.900326) (xy 423.603227 -52.899879) (xy 423.549046 -52.892059) (xy 423.496542 -52.876567)
			(xy 423.446796 -52.85372) (xy 423.40083 -52.82399) (xy 423.3799 -52.806346) (xy 423.379646 -52.806092)
			(xy 423.372551 -52.800518) (xy 423.355641 -52.794264) (xy 423.346626 -52.7939) (xy 423.27957 -52.7939)
			(xy 423.270552 -52.794243) (xy 423.253635 -52.8005) (xy 423.24655 -52.806092) (xy 423.246296 -52.806346)
			(xy 423.225363 -52.823987) (xy 423.179395 -52.853711) (xy 423.129649 -52.876557) (xy 423.077147 -52.892053)
			(xy 423.022969 -52.899882) (xy 422.968227 -52.899882) (xy 422.914049 -52.892053) (xy 422.861547 -52.876557)
			(xy 422.811801 -52.853711) (xy 422.765833 -52.823987) (xy 422.7449 -52.806346) (xy 422.744646 -52.806092)
			(xy 422.737551 -52.800518) (xy 422.720641 -52.794264) (xy 422.711626 -52.7939) (xy 422.64457 -52.7939)
			(xy 422.635552 -52.794243) (xy 422.618635 -52.8005) (xy 422.61155 -52.806092) (xy 422.61155 -52.806346)
			(xy 422.611296 -52.806346) (xy 422.590369 -52.823992) (xy 422.544396 -52.853705) (xy 422.494647 -52.87654)
			(xy 422.442145 -52.892029) (xy 422.387968 -52.899854) (xy 422.360598 -52.900326) (xy 422.333348 -52.899804)
			(xy 422.279403 -52.892047) (xy 422.227111 -52.876693) (xy 422.177537 -52.854053) (xy 422.131689 -52.824588)
			(xy 422.090501 -52.788898) (xy 422.054811 -52.74771) (xy 422.025347 -52.701862) (xy 422.002707 -52.652287)
			(xy 421.987352 -52.599995) (xy 421.979596 -52.54605) (xy 417.03054 -52.54605) (xy 417.041013 -52.550833)
			(xy 417.086863 -52.580299) (xy 417.128054 -52.61599) (xy 417.163745 -52.657181) (xy 417.193211 -52.703031)
			(xy 417.215853 -52.752608) (xy 417.231208 -52.804903) (xy 417.238964 -52.858851) (xy 417.23945 -52.886102)
			(xy 417.238997 -52.913473) (xy 417.231178 -52.967653) (xy 417.215687 -53.020157) (xy 417.192842 -53.069903)
			(xy 417.163113 -53.115869) (xy 417.14547 -53.1368) (xy 417.145216 -53.137054) (xy 417.139644 -53.144151)
			(xy 417.133388 -53.16106) (xy 417.133024 -53.170074) (xy 417.133024 -53.23713) (xy 417.133361 -53.246149)
			(xy 417.139622 -53.263066) (xy 417.145216 -53.27015) (xy 417.14547 -53.27015) (xy 417.14547 -53.270404)
			(xy 417.163113 -53.291335) (xy 417.192838 -53.337303) (xy 417.215683 -53.38705) (xy 417.231179 -53.439552)
			(xy 417.239008 -53.493731) (xy 417.239008 -53.548472) (xy 417.231179 -53.602651) (xy 417.215682 -53.655153)
			(xy 417.192836 -53.7049) (xy 417.163111 -53.750867) (xy 417.14654 -53.77053) (xy 417.510722 -53.77053)
			(xy 417.511254 -53.741613) (xy 417.519979 -53.684443) (xy 417.537233 -53.629244) (xy 417.562623 -53.577282)
			(xy 417.595564 -53.529747) (xy 417.635303 -53.48773) (xy 417.657788 -53.46954) (xy 417.666565 -53.461904)
			(xy 417.676766 -53.441025) (xy 417.677346 -53.429408) (xy 417.677346 -53.349652) (xy 417.676839 -53.338016)
			(xy 417.666629 -53.317105) (xy 417.657788 -53.30952) (xy 417.635312 -53.291321) (xy 417.595577 -53.249302)
			(xy 417.562637 -53.201769) (xy 417.537248 -53.149809) (xy 417.51999 -53.094614) (xy 417.511258 -53.037445)
			(xy 417.510722 -53.00853) (xy 417.511183 -52.981277) (xy 417.518937 -52.927324) (xy 417.534291 -52.875024)
			(xy 417.556932 -52.825442) (xy 417.5864 -52.779587) (xy 417.622094 -52.738394) (xy 417.663287 -52.7027)
			(xy 417.709142 -52.673232) (xy 417.758724 -52.650591) (xy 417.811024 -52.635237) (xy 417.864977 -52.627483)
			(xy 417.89223 -52.627022) (xy 417.918545 -52.627462) (xy 417.970675 -52.634702) (xy 418.021318 -52.649026)
			(xy 418.069517 -52.670163) (xy 418.11436 -52.697714) (xy 418.154998 -52.731158) (xy 418.173154 -52.750212)
			(xy 418.180652 -52.757641) (xy 418.19995 -52.76615) (xy 418.210492 -52.766722) (xy 418.285168 -52.766722)
			(xy 418.295716 -52.766182) (xy 418.315011 -52.757654) (xy 418.322506 -52.750212) (xy 418.340668 -52.731163)
			(xy 418.381296 -52.697705) (xy 418.426135 -52.670144) (xy 418.474334 -52.649005) (xy 418.524981 -52.634686)
			(xy 418.577114 -52.627461) (xy 418.60343 -52.627022) (xy 418.630683 -52.62745) (xy 418.684635 -52.635211)
			(xy 418.736932 -52.650572) (xy 418.786512 -52.673219) (xy 418.832363 -52.702691) (xy 418.873554 -52.738388)
			(xy 418.909245 -52.779585) (xy 418.93871 -52.825441) (xy 418.961349 -52.875024) (xy 418.976701 -52.927324)
			(xy 418.984454 -52.981277) (xy 418.984938 -53.00853) (xy 418.984478 -53.036197) (xy 418.982247 -53.051456)
			(xy 427.241206 -53.051456) (xy 427.245277 -52.995834) (xy 427.257403 -52.941397) (xy 427.277326 -52.889306)
			(xy 427.304622 -52.840671) (xy 427.338708 -52.796528) (xy 427.378857 -52.757819) (xy 427.424215 -52.725368)
			(xy 427.473815 -52.699867) (xy 427.526599 -52.68186) (xy 427.581442 -52.67173) (xy 427.637176 -52.669693)
			(xy 427.692613 -52.675793) (xy 427.74657 -52.689899) (xy 427.797899 -52.711711) (xy 427.845505 -52.740765)
			(xy 427.888373 -52.77644) (xy 427.92559 -52.817977) (xy 427.956363 -52.86449) (xy 427.980035 -52.914987)
			(xy 427.996103 -52.968394) (xy 428.004223 -53.02357) (xy 428.004732 -53.051456) (xy 428.004223 -53.079342)
			(xy 427.996103 -53.134518) (xy 427.980035 -53.187925) (xy 427.956363 -53.238422) (xy 427.92559 -53.284935)
			(xy 427.888373 -53.326472) (xy 427.845505 -53.362147) (xy 427.797899 -53.391201) (xy 427.74657 -53.413013)
			(xy 427.692613 -53.427119) (xy 427.637176 -53.433219) (xy 427.581442 -53.431182) (xy 427.526599 -53.421052)
			(xy 427.473815 -53.403045) (xy 427.424215 -53.377544) (xy 427.378857 -53.345093) (xy 427.338708 -53.306384)
			(xy 427.304622 -53.262241) (xy 427.277326 -53.213606) (xy 427.257403 -53.161515) (xy 427.245277 -53.107078)
			(xy 427.241206 -53.051456) (xy 418.982247 -53.051456) (xy 418.976473 -53.09095) (xy 418.960649 -53.143974)
			(xy 418.937338 -53.194159) (xy 418.907028 -53.240455) (xy 418.870354 -53.28189) (xy 418.828083 -53.317599)
			(xy 418.804852 -53.332634) (xy 418.795162 -53.339255) (xy 418.782724 -53.359128) (xy 418.780976 -53.370734)
			(xy 418.773102 -53.450744) (xy 418.772465 -53.462382) (xy 418.78055 -53.484219) (xy 418.788596 -53.492654)
			(xy 418.78885 -53.492908) (xy 418.807408 -53.511012) (xy 418.83999 -53.551338) (xy 418.866808 -53.595707)
			(xy 418.887365 -53.643301) (xy 418.901283 -53.693242) (xy 418.908304 -53.744608) (xy 418.908738 -53.77053)
			(xy 418.90825 -53.797781) (xy 418.90049 -53.851727) (xy 418.885133 -53.90402) (xy 418.862491 -53.953595)
			(xy 418.833024 -53.999444) (xy 418.797333 -54.040633) (xy 418.756144 -54.076324) (xy 418.710295 -54.105791)
			(xy 418.66072 -54.128433) (xy 418.608427 -54.14379) (xy 418.554481 -54.15155) (xy 418.52723 -54.152038)
			(xy 418.49986 -54.151569) (xy 418.44568 -54.143755) (xy 418.393176 -54.128267) (xy 418.343429 -54.105425)
			(xy 418.297463 -54.0757) (xy 418.276532 -54.058058) (xy 418.276278 -54.057804) (xy 418.269202 -54.052203)
			(xy 418.252277 -54.045965) (xy 418.243258 -54.045612) (xy 418.176202 -54.045612) (xy 418.167185 -54.045967)
			(xy 418.150268 -54.052216) (xy 418.143182 -54.057804) (xy 418.143182 -54.058058) (xy 418.142928 -54.058058)
			(xy 418.121991 -54.075691) (xy 418.07602 -54.105405) (xy 418.026274 -54.128243) (xy 417.973774 -54.143735)
			(xy 417.919599 -54.151564) (xy 417.89223 -54.152038) (xy 417.864981 -54.151494) (xy 417.811037 -54.143742)
			(xy 417.758745 -54.128392) (xy 417.70917 -54.105757) (xy 417.663321 -54.076297) (xy 417.622131 -54.040611)
			(xy 417.586439 -53.999427) (xy 417.556972 -53.953583) (xy 417.534328 -53.904011) (xy 417.51897 -53.851722)
			(xy 417.51121 -53.797779) (xy 417.510722 -53.77053) (xy 417.14654 -53.77053) (xy 417.14547 -53.7718)
			(xy 417.145216 -53.772054) (xy 417.139644 -53.779151) (xy 417.133388 -53.79606) (xy 417.133024 -53.805074)
			(xy 417.133024 -53.87213) (xy 417.133361 -53.881149) (xy 417.139622 -53.898066) (xy 417.145216 -53.90515)
			(xy 417.14547 -53.90515) (xy 417.14547 -53.905404) (xy 417.163113 -53.926335) (xy 417.192838 -53.972303)
			(xy 417.215683 -54.02205) (xy 417.231179 -54.074552) (xy 417.239008 -54.128731) (xy 417.239008 -54.183472)
			(xy 417.231179 -54.237651) (xy 417.215682 -54.290153) (xy 417.20189 -54.320186) (xy 419.430454 -54.320186)
			(xy 419.430899 -54.292815) (xy 419.43872 -54.238634) (xy 419.454213 -54.18613) (xy 419.47706 -54.136384)
			(xy 419.50679 -54.090418) (xy 419.524434 -54.069488) (xy 419.524688 -54.069234) (xy 419.530265 -54.062141)
			(xy 419.536518 -54.045229) (xy 419.53688 -54.036214) (xy 419.53688 -53.969158) (xy 419.536499 -53.960143)
			(xy 419.530269 -53.943226) (xy 419.524688 -53.936138) (xy 419.524434 -53.936138) (xy 419.524434 -53.935884)
			(xy 419.506826 -53.914927) (xy 419.477108 -53.868961) (xy 419.454266 -53.81922) (xy 419.438768 -53.766725)
			(xy 419.430932 -53.712554) (xy 419.430454 -53.685186) (xy 419.43094 -53.657935) (xy 419.438696 -53.603987)
			(xy 419.454051 -53.551692) (xy 419.476693 -53.502115) (xy 419.506159 -53.456265) (xy 419.54185 -53.415074)
			(xy 419.583041 -53.379383) (xy 419.628891 -53.349917) (xy 419.678468 -53.327275) (xy 419.730763 -53.31192)
			(xy 419.784711 -53.304164) (xy 419.839213 -53.304164) (xy 419.893161 -53.31192) (xy 419.945456 -53.327275)
			(xy 419.995033 -53.349917) (xy 420.040883 -53.379383) (xy 420.082074 -53.415074) (xy 420.117765 -53.456265)
			(xy 420.143655 -53.496551) (xy 432.433464 -53.496551) (xy 432.433464 -53.442049) (xy 432.44122 -53.388101)
			(xy 432.456574 -53.335806) (xy 432.479215 -53.286229) (xy 432.50868 -53.240378) (xy 432.54437 -53.199187)
			(xy 432.585559 -53.163494) (xy 432.631408 -53.134026) (xy 432.680984 -53.111383) (xy 432.733278 -53.096025)
			(xy 432.787225 -53.088265) (xy 432.814476 -53.087778) (xy 432.841847 -53.088239) (xy 432.896027 -53.096055)
			(xy 432.948531 -53.111544) (xy 432.998277 -53.134388) (xy 433.044243 -53.164115) (xy 433.065174 -53.181758)
			(xy 433.065428 -53.182012) (xy 433.07253 -53.187576) (xy 433.089435 -53.193836) (xy 433.098448 -53.194204)
			(xy 433.165504 -53.194204) (xy 433.174521 -53.193848) (xy 433.191438 -53.1876) (xy 433.198524 -53.182012)
			(xy 433.198524 -53.181758) (xy 433.198778 -53.181758) (xy 433.219702 -53.164109) (xy 433.265678 -53.1344)
			(xy 433.315427 -53.111566) (xy 433.367929 -53.096077) (xy 433.422106 -53.088251) (xy 433.449476 -53.087778)
			(xy 433.476729 -53.088268) (xy 433.530681 -53.096022) (xy 433.582979 -53.111375) (xy 433.632561 -53.134015)
			(xy 433.678415 -53.163482) (xy 433.719609 -53.199174) (xy 433.755304 -53.240366) (xy 433.784773 -53.286218)
			(xy 433.807417 -53.335798) (xy 433.822773 -53.388096) (xy 433.830531 -53.442047) (xy 433.830531 -53.496553)
			(xy 433.822773 -53.550504) (xy 433.807417 -53.602802) (xy 433.784773 -53.652382) (xy 433.755304 -53.698234)
			(xy 433.719609 -53.739426) (xy 433.678415 -53.775118) (xy 433.632561 -53.804585) (xy 433.582979 -53.827225)
			(xy 433.530681 -53.842578) (xy 433.476729 -53.850332) (xy 433.449476 -53.850794) (xy 433.422105 -53.850343)
			(xy 433.367925 -53.842522) (xy 433.315422 -53.827029) (xy 433.265675 -53.804184) (xy 433.219709 -53.774457)
			(xy 433.198778 -53.756814) (xy 433.198524 -53.75656) (xy 433.191438 -53.750972) (xy 433.174521 -53.744727)
			(xy 433.165504 -53.744368) (xy 433.098448 -53.744368) (xy 433.089434 -53.744755) (xy 433.072517 -53.750982)
			(xy 433.065428 -53.75656) (xy 433.065428 -53.756814) (xy 433.065174 -53.756814) (xy 433.044227 -53.774434)
			(xy 432.998258 -53.804148) (xy 432.948514 -53.826988) (xy 432.896017 -53.842483) (xy 432.841844 -53.850317)
			(xy 432.814476 -53.850794) (xy 432.787225 -53.850335) (xy 432.733278 -53.842575) (xy 432.680984 -53.827217)
			(xy 432.631408 -53.804574) (xy 432.585559 -53.775106) (xy 432.54437 -53.739413) (xy 432.50868 -53.698222)
			(xy 432.479215 -53.652371) (xy 432.456574 -53.602794) (xy 432.44122 -53.550499) (xy 432.433464 -53.496551)
			(xy 420.143655 -53.496551) (xy 420.147231 -53.502115) (xy 420.169873 -53.551692) (xy 420.185228 -53.603987)
			(xy 420.192984 -53.657935) (xy 420.19347 -53.685186) (xy 420.193003 -53.712556) (xy 420.185187 -53.766736)
			(xy 420.169698 -53.819239) (xy 420.146856 -53.868986) (xy 420.117132 -53.914953) (xy 420.09949 -53.935884)
			(xy 420.099236 -53.936138) (xy 420.093662 -53.943233) (xy 420.087409 -53.960143) (xy 420.087044 -53.969158)
			(xy 420.087044 -54.036214) (xy 420.087385 -54.045233) (xy 420.093642 -54.06215) (xy 420.099236 -54.069234)
			(xy 420.09949 -54.069234) (xy 420.09949 -54.069488) (xy 420.117135 -54.090415) (xy 420.146847 -54.136389)
			(xy 420.169682 -54.186138) (xy 420.185171 -54.23864) (xy 420.192997 -54.292816) (xy 420.19347 -54.320186)
			(xy 420.192984 -54.347437) (xy 420.185228 -54.401385) (xy 420.169873 -54.45368) (xy 420.147231 -54.503257)
			(xy 420.117765 -54.549107) (xy 420.082074 -54.590298) (xy 420.040883 -54.625989) (xy 419.995033 -54.655455)
			(xy 419.945456 -54.678097) (xy 419.893161 -54.693452) (xy 419.839213 -54.701208) (xy 419.784711 -54.701208)
			(xy 419.730763 -54.693452) (xy 419.678468 -54.678097) (xy 419.628891 -54.655455) (xy 419.583041 -54.625989)
			(xy 419.54185 -54.590298) (xy 419.506159 -54.549107) (xy 419.476693 -54.503257) (xy 419.454051 -54.45368)
			(xy 419.438696 -54.401385) (xy 419.43094 -54.347437) (xy 419.430454 -54.320186) (xy 417.20189 -54.320186)
			(xy 417.192836 -54.3399) (xy 417.163111 -54.385867) (xy 417.14547 -54.4068) (xy 417.145216 -54.407054)
			(xy 417.139644 -54.414151) (xy 417.133388 -54.43106) (xy 417.133024 -54.440074) (xy 417.133024 -54.50713)
			(xy 417.133361 -54.516149) (xy 417.139622 -54.533066) (xy 417.145216 -54.54015) (xy 417.14547 -54.54015)
			(xy 417.14547 -54.540404) (xy 417.16312 -54.561328) (xy 417.192831 -54.607302) (xy 417.215665 -54.657052)
			(xy 417.231154 -54.709555) (xy 417.238978 -54.763732) (xy 417.239095 -54.770528) (xy 420.371016 -54.770528)
			(xy 420.371495 -54.743158) (xy 420.379309 -54.688979) (xy 420.394795 -54.636476) (xy 420.417634 -54.586729)
			(xy 420.447356 -54.540762) (xy 420.464996 -54.51983) (xy 420.46525 -54.519576) (xy 420.470859 -54.512505)
			(xy 420.477091 -54.495576) (xy 420.477442 -54.486556) (xy 420.477442 -54.4195) (xy 420.477097 -54.410482)
			(xy 420.470843 -54.393564) (xy 420.46525 -54.38648) (xy 420.464996 -54.38648) (xy 420.464996 -54.386226)
			(xy 420.447355 -54.365295) (xy 420.417644 -54.319322) (xy 420.394808 -54.269574) (xy 420.379317 -54.217073)
			(xy 420.37149 -54.162897) (xy 420.371016 -54.135528) (xy 420.371502 -54.108277) (xy 420.379258 -54.054329)
			(xy 420.394613 -54.002034) (xy 420.417255 -53.952457) (xy 420.446721 -53.906607) (xy 420.482412 -53.865416)
			(xy 420.523603 -53.829725) (xy 420.569453 -53.800259) (xy 420.61903 -53.777617) (xy 420.671325 -53.762262)
			(xy 420.725273 -53.754506) (xy 420.779775 -53.754506) (xy 420.833723 -53.762262) (xy 420.886018 -53.777617)
			(xy 420.935595 -53.800259) (xy 420.981445 -53.829725) (xy 421.022636 -53.865416) (xy 421.058327 -53.906607)
			(xy 421.087793 -53.952457) (xy 421.092868 -53.96357) (xy 425.072046 -53.96357) (xy 425.076117 -53.907948)
			(xy 425.088243 -53.853511) (xy 425.108166 -53.80142) (xy 425.135462 -53.752785) (xy 425.169548 -53.708642)
			(xy 425.209697 -53.669933) (xy 425.255055 -53.637482) (xy 425.304655 -53.611981) (xy 425.357439 -53.593974)
			(xy 425.412282 -53.583844) (xy 425.468016 -53.581807) (xy 425.523453 -53.587907) (xy 425.57741 -53.602013)
			(xy 425.628739 -53.623825) (xy 425.676345 -53.652879) (xy 425.719213 -53.688554) (xy 425.75643 -53.730091)
			(xy 425.787203 -53.776604) (xy 425.810875 -53.827101) (xy 425.826943 -53.880508) (xy 425.835063 -53.935684)
			(xy 425.835572 -53.96357) (xy 425.835063 -53.991456) (xy 425.826943 -54.046632) (xy 425.810875 -54.100039)
			(xy 425.787203 -54.150536) (xy 425.75643 -54.197049) (xy 425.719213 -54.238586) (xy 425.676345 -54.274261)
			(xy 425.628739 -54.303315) (xy 425.57741 -54.325127) (xy 425.523453 -54.339233) (xy 425.468016 -54.345333)
			(xy 425.412282 -54.343296) (xy 425.357439 -54.333166) (xy 425.304655 -54.315159) (xy 425.255055 -54.289658)
			(xy 425.209697 -54.257207) (xy 425.169548 -54.218498) (xy 425.135462 -54.174355) (xy 425.108166 -54.12572)
			(xy 425.088243 -54.073629) (xy 425.076117 -54.019192) (xy 425.072046 -53.96357) (xy 421.092868 -53.96357)
			(xy 421.110435 -54.002034) (xy 421.12579 -54.054329) (xy 421.133546 -54.108277) (xy 421.134032 -54.135528)
			(xy 421.133599 -54.1629) (xy 421.125776 -54.217081) (xy 421.11028 -54.269585) (xy 421.08743 -54.319331)
			(xy 421.057697 -54.365296) (xy 421.040052 -54.386226) (xy 421.039798 -54.38648) (xy 421.034213 -54.393568)
			(xy 421.027966 -54.410484) (xy 421.027606 -54.4195) (xy 421.027606 -54.486556) (xy 421.027983 -54.495571)
			(xy 421.034217 -54.512488) (xy 421.039798 -54.519576) (xy 421.040052 -54.519576) (xy 421.040052 -54.51983)
			(xy 421.057664 -54.540784) (xy 421.087382 -54.58675) (xy 421.110224 -54.636492) (xy 421.125721 -54.688988)
			(xy 421.133555 -54.74316) (xy 421.134032 -54.770528) (xy 421.133546 -54.797779) (xy 421.12579 -54.851727)
			(xy 421.110435 -54.904022) (xy 421.087793 -54.953599) (xy 421.065009 -54.989051) (xy 430.201068 -54.989051)
			(xy 430.201068 -54.934549) (xy 430.208824 -54.880603) (xy 430.224178 -54.828309) (xy 430.246817 -54.778733)
			(xy 430.276281 -54.732882) (xy 430.311971 -54.691692) (xy 430.353158 -54.655999) (xy 430.399006 -54.626532)
			(xy 430.448581 -54.603888) (xy 430.500874 -54.58853) (xy 430.554819 -54.58077) (xy 430.58207 -54.580282)
			(xy 430.610161 -54.580801) (xy 430.665737 -54.589023) (xy 430.719505 -54.60531) (xy 430.770303 -54.629309)
			(xy 430.81703 -54.6605) (xy 430.858675 -54.698209) (xy 430.894339 -54.741619) (xy 430.909222 -54.765448)
			(xy 430.914556 -54.774338) (xy 430.931574 -54.78653) (xy 431.024792 -54.80685) (xy 431.045366 -54.802532)
			(xy 431.054002 -54.79669) (xy 431.078063 -54.780686) (xy 431.129996 -54.755344) (xy 431.185154 -54.73812)
			(xy 431.242279 -54.729406) (xy 431.271172 -54.728872) (xy 431.298423 -54.729381) (xy 431.352371 -54.737134)
			(xy 431.404667 -54.752485) (xy 431.454246 -54.775123) (xy 431.500098 -54.804586) (xy 431.541291 -54.840275)
			(xy 431.576985 -54.881463) (xy 431.606454 -54.927312) (xy 431.629098 -54.976888) (xy 431.644456 -55.029182)
			(xy 431.652215 -55.083129) (xy 431.65268 -55.11038) (xy 431.652207 -55.13775) (xy 431.644392 -55.191929)
			(xy 431.628904 -55.244432) (xy 431.606064 -55.294179) (xy 431.576341 -55.340146) (xy 431.5587 -55.361078)
			(xy 431.558446 -55.361332) (xy 431.552875 -55.368429) (xy 431.54662 -55.385338) (xy 431.546254 -55.394352)
			(xy 431.546254 -55.461408) (xy 431.546596 -55.470427) (xy 431.552853 -55.487344) (xy 431.558446 -55.494428)
			(xy 431.5587 -55.494428) (xy 431.5587 -55.494682) (xy 431.57632 -55.515631) (xy 431.606044 -55.561597)
			(xy 431.628888 -55.61134) (xy 431.644385 -55.66384) (xy 431.652215 -55.718016) (xy 431.652217 -55.772754)
			(xy 431.644392 -55.826931) (xy 431.628899 -55.879431) (xy 431.606058 -55.929177) (xy 431.576338 -55.975145)
			(xy 431.5587 -55.996078) (xy 431.558446 -55.996332) (xy 431.552875 -56.003429) (xy 431.54662 -56.020338)
			(xy 431.546254 -56.029352) (xy 431.546254 -56.096408) (xy 431.546596 -56.105427) (xy 431.552853 -56.122344)
			(xy 431.558446 -56.129428) (xy 431.5587 -56.129428) (xy 431.5587 -56.129682) (xy 431.576344 -56.15061)
			(xy 431.606055 -56.196584) (xy 431.62889 -56.246332) (xy 431.64438 -56.298834) (xy 431.652207 -56.353011)
			(xy 431.65268 -56.38038) (xy 431.652194 -56.407631) (xy 431.644438 -56.461579) (xy 431.629083 -56.513874)
			(xy 431.606441 -56.563451) (xy 431.576975 -56.609301) (xy 431.541284 -56.650492) (xy 431.500093 -56.686183)
			(xy 431.454243 -56.715649) (xy 431.404666 -56.738291) (xy 431.352371 -56.753646) (xy 431.298423 -56.761402)
			(xy 431.243921 -56.761402) (xy 431.189973 -56.753646) (xy 431.137678 -56.738291) (xy 431.088101 -56.715649)
			(xy 431.042251 -56.686183) (xy 431.00106 -56.650492) (xy 430.965369 -56.609301) (xy 430.935903 -56.563451)
			(xy 430.913261 -56.513874) (xy 430.897906 -56.461579) (xy 430.89015 -56.407631) (xy 430.889664 -56.38038)
			(xy 430.890103 -56.353009) (xy 430.897925 -56.298828) (xy 430.913419 -56.246324) (xy 430.936268 -56.196577)
			(xy 430.965999 -56.150612) (xy 430.983644 -56.129682) (xy 430.983898 -56.129428) (xy 430.989479 -56.122337)
			(xy 430.995729 -56.105424) (xy 430.99609 -56.096408) (xy 430.99609 -56.029352) (xy 430.99571 -56.020337)
			(xy 430.989479 -56.00342) (xy 430.983898 -55.996332) (xy 430.983644 -55.996332) (xy 430.983644 -55.996078)
			(xy 430.965983 -55.975161) (xy 430.936258 -55.929191) (xy 430.913412 -55.879442) (xy 430.897917 -55.826938)
			(xy 430.89009 -55.772757) (xy 430.890092 -55.718013) (xy 430.897923 -55.663833) (xy 430.913423 -55.611329)
			(xy 430.936272 -55.561582) (xy 430.966001 -55.515614) (xy 430.983644 -55.494682) (xy 430.983898 -55.494428)
			(xy 430.989479 -55.487337) (xy 430.995729 -55.470424) (xy 430.99609 -55.461408) (xy 430.99609 -55.394352)
			(xy 430.99571 -55.385337) (xy 430.989479 -55.36842) (xy 430.983898 -55.361332) (xy 430.983644 -55.360824)
			(xy 430.972697 -55.348092) (xy 430.952858 -55.320999) (xy 430.94402 -55.306722) (xy 430.938686 -55.297832)
			(xy 430.921668 -55.28564) (xy 430.82845 -55.26532) (xy 430.807876 -55.269638) (xy 430.79924 -55.27548)
			(xy 430.775165 -55.291463) (xy 430.723238 -55.31681) (xy 430.668083 -55.334041) (xy 430.610962 -55.342761)
			(xy 430.58207 -55.343298) (xy 430.554819 -55.34283) (xy 430.500874 -55.33507) (xy 430.448581 -55.319712)
			(xy 430.399006 -55.297068) (xy 430.353158 -55.267601) (xy 430.311971 -55.231908) (xy 430.276281 -55.190718)
			(xy 430.246817 -55.144867) (xy 430.224178 -55.095291) (xy 430.208824 -55.042997) (xy 430.201068 -54.989051)
			(xy 421.065009 -54.989051) (xy 421.058327 -54.999449) (xy 421.022636 -55.04064) (xy 420.981445 -55.076331)
			(xy 420.935595 -55.105797) (xy 420.886018 -55.128439) (xy 420.833723 -55.143794) (xy 420.779775 -55.15155)
			(xy 420.725273 -55.15155) (xy 420.671325 -55.143794) (xy 420.61903 -55.128439) (xy 420.569453 -55.105797)
			(xy 420.523603 -55.076331) (xy 420.482412 -55.04064) (xy 420.446721 -54.999449) (xy 420.417255 -54.953599)
			(xy 420.394613 -54.904022) (xy 420.379258 -54.851727) (xy 420.371502 -54.797779) (xy 420.371016 -54.770528)
			(xy 417.239095 -54.770528) (xy 417.23945 -54.791102) (xy 417.238964 -54.818353) (xy 417.231208 -54.872301)
			(xy 417.215853 -54.924596) (xy 417.193211 -54.974173) (xy 417.163745 -55.020023) (xy 417.128054 -55.061214)
			(xy 417.086863 -55.096905) (xy 417.041013 -55.126371) (xy 416.991436 -55.149013) (xy 416.939141 -55.164368)
			(xy 416.885193 -55.172124) (xy 416.830691 -55.172124) (xy 416.776743 -55.164368) (xy 416.724448 -55.149013)
			(xy 416.674871 -55.126371) (xy 416.629021 -55.096905) (xy 416.58783 -55.061214) (xy 416.552139 -55.020023)
			(xy 416.522673 -54.974173) (xy 416.500031 -54.924596) (xy 416.484676 -54.872301) (xy 416.47692 -54.818353)
			(xy 416.476434 -54.791102) (xy 414.578476 -54.791102) (xy 414.575384 -54.812611) (xy 414.560029 -54.864906)
			(xy 414.537387 -54.914483) (xy 414.507921 -54.960333) (xy 414.47223 -55.001524) (xy 414.431039 -55.037215)
			(xy 414.385189 -55.066681) (xy 414.335612 -55.089323) (xy 414.283317 -55.104678) (xy 414.229369 -55.112434)
			(xy 414.174867 -55.112434) (xy 414.120919 -55.104678) (xy 414.068624 -55.089323) (xy 414.019047 -55.066681)
			(xy 413.973197 -55.037215) (xy 413.932006 -55.001524) (xy 413.896315 -54.960333) (xy 413.866849 -54.914483)
			(xy 413.844207 -54.864906) (xy 413.828852 -54.812611) (xy 413.821096 -54.758663) (xy 413.82061 -54.731412)
			(xy 412.883604 -54.731412) (xy 412.883604 -55.722266) (xy 426.13402 -55.722266) (xy 426.138091 -55.666644)
			(xy 426.150217 -55.612207) (xy 426.17014 -55.560116) (xy 426.197436 -55.511481) (xy 426.231522 -55.467338)
			(xy 426.271671 -55.428629) (xy 426.317029 -55.396178) (xy 426.366629 -55.370677) (xy 426.419413 -55.35267)
			(xy 426.474256 -55.34254) (xy 426.52999 -55.340503) (xy 426.585427 -55.346603) (xy 426.639384 -55.360709)
			(xy 426.690713 -55.382521) (xy 426.738319 -55.411575) (xy 426.749465 -55.420851) (xy 428.524668 -55.420851)
			(xy 428.524668 -55.366349) (xy 428.532424 -55.312403) (xy 428.547778 -55.260109) (xy 428.570417 -55.210533)
			(xy 428.599881 -55.164682) (xy 428.635571 -55.123492) (xy 428.676758 -55.087799) (xy 428.722606 -55.058332)
			(xy 428.772181 -55.035688) (xy 428.824474 -55.02033) (xy 428.878419 -55.01257) (xy 428.90567 -55.012082)
			(xy 428.931985 -55.012509) (xy 428.984115 -55.019753) (xy 429.034759 -55.03408) (xy 429.082957 -55.05522)
			(xy 429.1278 -55.082773) (xy 429.168438 -55.116218) (xy 429.186594 -55.135272) (xy 429.19412 -55.142669)
			(xy 429.213396 -55.151197) (xy 429.223932 -55.151782) (xy 429.298608 -55.151782) (xy 429.30916 -55.151276)
			(xy 429.328456 -55.142725) (xy 429.335946 -55.135272) (xy 429.354081 -55.116196) (xy 429.394716 -55.082742)
			(xy 429.43956 -55.055186) (xy 429.487765 -55.034051) (xy 429.538416 -55.019738) (xy 429.590553 -55.012518)
			(xy 429.61687 -55.012082) (xy 429.644124 -55.012563) (xy 429.698076 -55.020317) (xy 429.750376 -55.03567)
			(xy 429.799959 -55.05831) (xy 429.845815 -55.087776) (xy 429.88701 -55.123469) (xy 429.922706 -55.164661)
			(xy 429.952176 -55.210515) (xy 429.97482 -55.260095) (xy 429.990177 -55.312394) (xy 429.997935 -55.366347)
			(xy 429.997935 -55.420854) (xy 429.990177 -55.474806) (xy 429.97482 -55.527105) (xy 429.952176 -55.576685)
			(xy 429.922706 -55.622539) (xy 429.88701 -55.663731) (xy 429.845815 -55.699424) (xy 429.799959 -55.72889)
			(xy 429.750376 -55.75153) (xy 429.698076 -55.766883) (xy 429.644124 -55.774637) (xy 429.61687 -55.775098)
			(xy 429.590555 -55.774651) (xy 429.538426 -55.767412) (xy 429.487783 -55.753089) (xy 429.439584 -55.731953)
			(xy 429.394741 -55.704403) (xy 429.354102 -55.670961) (xy 429.335946 -55.651908) (xy 429.328445 -55.644482)
			(xy 429.309149 -55.635971) (xy 429.298608 -55.635398) (xy 429.223932 -55.635398) (xy 429.213383 -55.635932)
			(xy 429.194087 -55.644464) (xy 429.186594 -55.651908) (xy 429.168436 -55.670961) (xy 429.127807 -55.704418)
			(xy 429.082967 -55.731977) (xy 429.034767 -55.753116) (xy 428.98412 -55.767434) (xy 428.931986 -55.774659)
			(xy 428.90567 -55.775098) (xy 428.878419 -55.77463) (xy 428.824474 -55.76687) (xy 428.772181 -55.751512)
			(xy 428.722606 -55.728868) (xy 428.676758 -55.699401) (xy 428.635571 -55.663708) (xy 428.599881 -55.622518)
			(xy 428.570417 -55.576667) (xy 428.547778 -55.527091) (xy 428.532424 -55.474797) (xy 428.524668 -55.420851)
			(xy 426.749465 -55.420851) (xy 426.781187 -55.44725) (xy 426.818404 -55.488787) (xy 426.849177 -55.5353)
			(xy 426.872849 -55.585797) (xy 426.888917 -55.639204) (xy 426.897037 -55.69438) (xy 426.897546 -55.722266)
			(xy 426.897037 -55.750152) (xy 426.888917 -55.805328) (xy 426.872849 -55.858735) (xy 426.849177 -55.909232)
			(xy 426.818404 -55.955745) (xy 426.781187 -55.997282) (xy 426.738319 -56.032957) (xy 426.690713 -56.062011)
			(xy 426.639384 -56.083823) (xy 426.585427 -56.097929) (xy 426.52999 -56.104029) (xy 426.474256 -56.101992)
			(xy 426.419413 -56.091862) (xy 426.366629 -56.073855) (xy 426.317029 -56.048354) (xy 426.271671 -56.015903)
			(xy 426.231522 -55.977194) (xy 426.197436 -55.933051) (xy 426.17014 -55.884416) (xy 426.150217 -55.832325)
			(xy 426.138091 -55.777888) (xy 426.13402 -55.722266) (xy 412.883604 -55.722266) (xy 412.883604 -55.747412)
			(xy 412.958905 -57.002934) (xy 421.86352 -57.002934) (xy 421.864023 -56.974843) (xy 421.872247 -56.919265)
			(xy 421.888535 -56.865495) (xy 421.912536 -56.814697) (xy 421.94373 -56.76797) (xy 421.981442 -56.726325)
			(xy 422.024855 -56.690664) (xy 422.048686 -56.675782) (xy 422.057576 -56.670448) (xy 422.069768 -56.65343)
			(xy 422.090088 -56.560212) (xy 422.08577 -56.539638) (xy 422.079928 -56.531002) (xy 422.06393 -56.506937)
			(xy 422.038586 -56.455006) (xy 422.02136 -56.399849) (xy 422.012644 -56.342724) (xy 422.01211 -56.313832)
			(xy 422.012585 -56.286579) (xy 422.020338 -56.232628) (xy 422.035691 -56.180329) (xy 422.058331 -56.130748)
			(xy 422.087798 -56.084894) (xy 422.12349 -56.0437) (xy 422.164682 -56.008006) (xy 422.210535 -55.978538)
			(xy 422.260116 -55.955896) (xy 422.312414 -55.940541) (xy 422.366365 -55.932786) (xy 422.393618 -55.932324)
			(xy 422.420989 -55.932774) (xy 422.475169 -55.940595) (xy 422.527672 -55.956087) (xy 422.577419 -55.978933)
			(xy 422.623385 -56.008661) (xy 422.644316 -56.026304) (xy 422.64457 -56.026558) (xy 422.651656 -56.032145)
			(xy 422.668573 -56.03839) (xy 422.67759 -56.03875) (xy 422.744646 -56.03875) (xy 422.753662 -56.038378)
			(xy 422.770579 -56.032142) (xy 422.777666 -56.026558) (xy 422.777666 -56.026304) (xy 422.77792 -56.026304)
			(xy 422.798853 -56.008663) (xy 422.844821 -55.978939) (xy 422.894567 -55.956093) (xy 422.947069 -55.940597)
			(xy 423.001247 -55.932768) (xy 423.055989 -55.932768) (xy 423.110167 -55.940597) (xy 423.162669 -55.956093)
			(xy 423.212415 -55.978939) (xy 423.258383 -56.008663) (xy 423.279316 -56.026304) (xy 423.27957 -56.026558)
			(xy 423.286656 -56.032145) (xy 423.303573 -56.03839) (xy 423.31259 -56.03875) (xy 423.379646 -56.03875)
			(xy 423.388662 -56.038378) (xy 423.405579 -56.032142) (xy 423.412666 -56.026558) (xy 423.412666 -56.026304)
			(xy 423.41292 -56.026304) (xy 423.433872 -56.00869) (xy 423.479839 -55.978974) (xy 423.529582 -55.956133)
			(xy 423.582078 -55.940636) (xy 423.63625 -55.932802) (xy 423.663618 -55.932324) (xy 423.690871 -55.932747)
			(xy 423.744821 -55.940506) (xy 423.797118 -55.955864) (xy 423.846697 -55.978508) (xy 423.892549 -56.007978)
			(xy 423.933741 -56.043672) (xy 423.969433 -56.084865) (xy 423.9989 -56.130719) (xy 424.021542 -56.180299)
			(xy 424.036897 -56.232597) (xy 424.044654 -56.286547) (xy 424.044654 -56.297068) (xy 424.3865 -56.297068)
			(xy 424.390571 -56.241446) (xy 424.402697 -56.187009) (xy 424.42262 -56.134918) (xy 424.449916 -56.086283)
			(xy 424.484002 -56.04214) (xy 424.524151 -56.003431) (xy 424.569509 -55.97098) (xy 424.619109 -55.945479)
			(xy 424.671893 -55.927472) (xy 424.726736 -55.917342) (xy 424.78247 -55.915305) (xy 424.837907 -55.921405)
			(xy 424.891864 -55.935511) (xy 424.943193 -55.957323) (xy 424.990799 -55.986377) (xy 425.033667 -56.022052)
			(xy 425.070884 -56.063589) (xy 425.101657 -56.110102) (xy 425.125329 -56.160599) (xy 425.141397 -56.214006)
			(xy 425.149517 -56.269182) (xy 425.150026 -56.297068) (xy 425.149517 -56.324954) (xy 425.141397 -56.38013)
			(xy 425.125329 -56.433537) (xy 425.101657 -56.484034) (xy 425.070884 -56.530547) (xy 425.033667 -56.572084)
			(xy 424.990799 -56.607759) (xy 424.943193 -56.636813) (xy 424.891864 -56.658625) (xy 424.837907 -56.672731)
			(xy 424.78247 -56.678831) (xy 424.726736 -56.676794) (xy 424.671893 -56.666664) (xy 424.619109 -56.648657)
			(xy 424.569509 -56.623156) (xy 424.524151 -56.590705) (xy 424.484002 -56.551996) (xy 424.449916 -56.507853)
			(xy 424.42262 -56.459218) (xy 424.402697 -56.407127) (xy 424.390571 -56.35269) (xy 424.3865 -56.297068)
			(xy 424.044654 -56.297068) (xy 424.044654 -56.341053) (xy 424.036897 -56.395003) (xy 424.021542 -56.447301)
			(xy 423.9989 -56.496881) (xy 423.969433 -56.542735) (xy 423.933741 -56.583928) (xy 423.892549 -56.619622)
			(xy 423.846697 -56.649092) (xy 423.797118 -56.671736) (xy 423.744821 -56.687094) (xy 423.690871 -56.694853)
			(xy 423.663618 -56.69534) (xy 423.636247 -56.694878) (xy 423.582068 -56.687061) (xy 423.529564 -56.671572)
			(xy 423.479817 -56.648729) (xy 423.433851 -56.619003) (xy 423.41292 -56.60136) (xy 423.412666 -56.601106)
			(xy 423.405564 -56.595542) (xy 423.388659 -56.589281) (xy 423.379646 -56.588914) (xy 423.31259 -56.588914)
			(xy 423.303572 -56.589263) (xy 423.286655 -56.595516) (xy 423.27957 -56.601106) (xy 423.27957 -56.60136)
			(xy 423.279316 -56.60136) (xy 423.258383 -56.619001) (xy 423.212415 -56.648725) (xy 423.162669 -56.671571)
			(xy 423.110167 -56.687067) (xy 423.055989 -56.694896) (xy 423.001247 -56.694896) (xy 422.947069 -56.687067)
			(xy 422.894567 -56.671571) (xy 422.844821 -56.648725) (xy 422.798853 -56.619001) (xy 422.77792 -56.60136)
			(xy 422.777666 -56.601106) (xy 422.770564 -56.595542) (xy 422.753659 -56.589281) (xy 422.744646 -56.588914)
			(xy 422.67759 -56.588914) (xy 422.668572 -56.589263) (xy 422.651655 -56.595516) (xy 422.64457 -56.601106)
			(xy 422.644062 -56.60136) (xy 422.631328 -56.612304) (xy 422.604236 -56.632145) (xy 422.58996 -56.640984)
			(xy 422.58107 -56.646318) (xy 422.568878 -56.663336) (xy 422.548558 -56.756554) (xy 422.552876 -56.777128)
			(xy 422.558718 -56.785764) (xy 422.574707 -56.809835) (xy 422.600052 -56.861764) (xy 422.61728 -56.91692)
			(xy 422.625999 -56.974042) (xy 422.626536 -57.002934) (xy 422.62605 -57.030185) (xy 422.618294 -57.084133)
			(xy 422.602939 -57.136428) (xy 422.580297 -57.186005) (xy 422.550831 -57.231855) (xy 422.51514 -57.273046)
			(xy 422.473949 -57.308737) (xy 422.428099 -57.338203) (xy 422.378522 -57.360845) (xy 422.326227 -57.3762)
			(xy 422.272279 -57.383956) (xy 422.217777 -57.383956) (xy 422.163829 -57.3762) (xy 422.111534 -57.360845)
			(xy 422.061957 -57.338203) (xy 422.016107 -57.308737) (xy 421.974916 -57.273046) (xy 421.939225 -57.231855)
			(xy 421.909759 -57.186005) (xy 421.887117 -57.136428) (xy 421.871762 -57.084133) (xy 421.864006 -57.030185)
			(xy 421.86352 -57.002934) (xy 412.958905 -57.002934) (xy 412.987834 -57.48528) (xy 430.905918 -57.48528)
			(xy 430.909989 -57.429658) (xy 430.922115 -57.375221) (xy 430.942038 -57.32313) (xy 430.969334 -57.274495)
			(xy 431.00342 -57.230352) (xy 431.043569 -57.191643) (xy 431.088927 -57.159192) (xy 431.138527 -57.133691)
			(xy 431.191311 -57.115684) (xy 431.246154 -57.105554) (xy 431.301888 -57.103517) (xy 431.357325 -57.109617)
			(xy 431.411282 -57.123723) (xy 431.462611 -57.145535) (xy 431.510217 -57.174589) (xy 431.553085 -57.210264)
			(xy 431.590302 -57.251801) (xy 431.621075 -57.298314) (xy 431.644747 -57.348811) (xy 431.660815 -57.402218)
			(xy 431.668935 -57.457394) (xy 431.669444 -57.48528) (xy 431.668935 -57.513166) (xy 431.660815 -57.568342)
			(xy 431.644747 -57.621749) (xy 431.621075 -57.672246) (xy 431.590302 -57.718759) (xy 431.553085 -57.760296)
			(xy 431.510217 -57.795971) (xy 431.462611 -57.825025) (xy 431.411282 -57.846837) (xy 431.357325 -57.860943)
			(xy 431.301888 -57.867043) (xy 431.246154 -57.865006) (xy 431.191311 -57.854876) (xy 431.138527 -57.836869)
			(xy 431.088927 -57.811368) (xy 431.043569 -57.778917) (xy 431.00342 -57.740208) (xy 430.969334 -57.696065)
			(xy 430.942038 -57.64743) (xy 430.922115 -57.595339) (xy 430.909989 -57.540902) (xy 430.905918 -57.48528)
			(xy 412.987834 -57.48528) (xy 413.059449 -58.679334) (xy 422.29532 -58.679334) (xy 422.295737 -58.653018)
			(xy 422.302981 -58.600887) (xy 422.31731 -58.550243) (xy 422.338452 -58.502044) (xy 422.366007 -58.457202)
			(xy 422.399454 -58.416565) (xy 422.41851 -58.39841) (xy 422.425911 -58.390888) (xy 422.434435 -58.371608)
			(xy 422.43502 -58.361072) (xy 422.43502 -58.286396) (xy 422.434501 -58.275845) (xy 422.425958 -58.25655)
			(xy 422.41851 -58.249058) (xy 422.399443 -58.230914) (xy 422.365986 -58.190282) (xy 422.338429 -58.145439)
			(xy 422.317292 -58.097236) (xy 422.302978 -58.046587) (xy 422.295756 -57.994451) (xy 422.29532 -57.968134)
			(xy 422.295806 -57.940883) (xy 422.303562 -57.886935) (xy 422.318917 -57.83464) (xy 422.341559 -57.785063)
			(xy 422.371025 -57.739213) (xy 422.406716 -57.698022) (xy 422.447907 -57.662331) (xy 422.493757 -57.632865)
			(xy 422.543334 -57.610223) (xy 422.595629 -57.594868) (xy 422.649577 -57.587112) (xy 422.704079 -57.587112)
			(xy 422.758027 -57.594868) (xy 422.810322 -57.610223) (xy 422.859899 -57.632865) (xy 422.905749 -57.662331)
			(xy 422.94694 -57.698022) (xy 422.982631 -57.739213) (xy 423.012097 -57.785063) (xy 423.034739 -57.83464)
			(xy 423.050094 -57.886935) (xy 423.05785 -57.940883) (xy 423.058336 -57.968134) (xy 423.05788 -57.994448)
			(xy 423.050641 -58.046577) (xy 423.043374 -58.072274) (xy 426.293532 -58.072274) (xy 426.297603 -58.016652)
			(xy 426.309729 -57.962215) (xy 426.329652 -57.910124) (xy 426.356948 -57.861489) (xy 426.391034 -57.817346)
			(xy 426.431183 -57.778637) (xy 426.476541 -57.746186) (xy 426.526141 -57.720685) (xy 426.578925 -57.702678)
			(xy 426.633768 -57.692548) (xy 426.689502 -57.690511) (xy 426.744939 -57.696611) (xy 426.798896 -57.710717)
			(xy 426.850225 -57.732529) (xy 426.897831 -57.761583) (xy 426.940699 -57.797258) (xy 426.977916 -57.838795)
			(xy 427.008689 -57.885308) (xy 427.032361 -57.935805) (xy 427.048429 -57.989212) (xy 427.056549 -58.044388)
			(xy 427.057058 -58.072274) (xy 427.056988 -58.076084) (xy 431.658012 -58.076084) (xy 431.662083 -58.020462)
			(xy 431.674209 -57.966025) (xy 431.694132 -57.913934) (xy 431.721428 -57.865299) (xy 431.755514 -57.821156)
			(xy 431.795663 -57.782447) (xy 431.841021 -57.749996) (xy 431.890621 -57.724495) (xy 431.943405 -57.706488)
			(xy 431.998248 -57.696358) (xy 432.053982 -57.694321) (xy 432.109419 -57.700421) (xy 432.163376 -57.714527)
			(xy 432.214705 -57.736339) (xy 432.262311 -57.765393) (xy 432.305179 -57.801068) (xy 432.342396 -57.842605)
			(xy 432.373169 -57.889118) (xy 432.396841 -57.939615) (xy 432.412909 -57.993022) (xy 432.421029 -58.048198)
			(xy 432.421538 -58.076084) (xy 432.42107 -58.101738) (xy 433.942996 -58.101738) (xy 433.947067 -58.046116)
			(xy 433.959193 -57.991679) (xy 433.979116 -57.939588) (xy 434.006412 -57.890953) (xy 434.040498 -57.84681)
			(xy 434.080647 -57.808101) (xy 434.126005 -57.77565) (xy 434.175605 -57.750149) (xy 434.228389 -57.732142)
			(xy 434.283232 -57.722012) (xy 434.338966 -57.719975) (xy 434.394403 -57.726075) (xy 434.44836 -57.740181)
			(xy 434.499689 -57.761993) (xy 434.547295 -57.791047) (xy 434.590163 -57.826722) (xy 434.62738 -57.868259)
			(xy 434.658153 -57.914772) (xy 434.681825 -57.965269) (xy 434.697893 -58.018676) (xy 434.706013 -58.073852)
			(xy 434.706522 -58.101738) (xy 434.706013 -58.129624) (xy 434.697893 -58.1848) (xy 434.681825 -58.238207)
			(xy 434.658153 -58.288704) (xy 434.62738 -58.335217) (xy 434.590163 -58.376754) (xy 434.547295 -58.412429)
			(xy 434.499689 -58.441483) (xy 434.48031 -58.449718) (xy 435.108856 -58.449718) (xy 435.112927 -58.394096)
			(xy 435.125053 -58.339659) (xy 435.144976 -58.287568) (xy 435.172272 -58.238933) (xy 435.206358 -58.19479)
			(xy 435.246507 -58.156081) (xy 435.291865 -58.12363) (xy 435.341465 -58.098129) (xy 435.394249 -58.080122)
			(xy 435.449092 -58.069992) (xy 435.504826 -58.067955) (xy 435.560263 -58.074055) (xy 435.61422 -58.088161)
			(xy 435.665549 -58.109973) (xy 435.713155 -58.139027) (xy 435.756023 -58.174702) (xy 435.79324 -58.216239)
			(xy 435.824013 -58.262752) (xy 435.847685 -58.313249) (xy 435.863753 -58.366656) (xy 435.871873 -58.421832)
			(xy 435.872382 -58.449718) (xy 435.871873 -58.477604) (xy 435.863753 -58.53278) (xy 435.847685 -58.586187)
			(xy 435.824013 -58.636684) (xy 435.79324 -58.683197) (xy 435.756023 -58.724734) (xy 435.713155 -58.760409)
			(xy 435.665549 -58.789463) (xy 435.61422 -58.811275) (xy 435.560263 -58.825381) (xy 435.504826 -58.831481)
			(xy 435.449092 -58.829444) (xy 435.394249 -58.819314) (xy 435.341465 -58.801307) (xy 435.291865 -58.775806)
			(xy 435.246507 -58.743355) (xy 435.206358 -58.704646) (xy 435.172272 -58.660503) (xy 435.144976 -58.611868)
			(xy 435.125053 -58.559777) (xy 435.112927 -58.50534) (xy 435.108856 -58.449718) (xy 434.48031 -58.449718)
			(xy 434.44836 -58.463295) (xy 434.394403 -58.477401) (xy 434.338966 -58.483501) (xy 434.283232 -58.481464)
			(xy 434.228389 -58.471334) (xy 434.175605 -58.453327) (xy 434.126005 -58.427826) (xy 434.080647 -58.395375)
			(xy 434.040498 -58.356666) (xy 434.006412 -58.312523) (xy 433.979116 -58.263888) (xy 433.959193 -58.211797)
			(xy 433.947067 -58.15736) (xy 433.942996 -58.101738) (xy 432.42107 -58.101738) (xy 432.421029 -58.10397)
			(xy 432.412909 -58.159146) (xy 432.396841 -58.212553) (xy 432.373169 -58.26305) (xy 432.342396 -58.309563)
			(xy 432.305179 -58.3511) (xy 432.262311 -58.386775) (xy 432.214705 -58.415829) (xy 432.163376 -58.437641)
			(xy 432.109419 -58.451747) (xy 432.053982 -58.457847) (xy 431.998248 -58.45581) (xy 431.943405 -58.44568)
			(xy 431.890621 -58.427673) (xy 431.841021 -58.402172) (xy 431.795663 -58.369721) (xy 431.755514 -58.331012)
			(xy 431.721428 -58.286869) (xy 431.694132 -58.238234) (xy 431.674209 -58.186143) (xy 431.662083 -58.131706)
			(xy 431.658012 -58.076084) (xy 427.056988 -58.076084) (xy 427.056549 -58.10016) (xy 427.048429 -58.155336)
			(xy 427.032361 -58.208743) (xy 427.008689 -58.25924) (xy 426.977916 -58.305753) (xy 426.940699 -58.34729)
			(xy 426.897831 -58.382965) (xy 426.850225 -58.412019) (xy 426.798896 -58.433831) (xy 426.744939 -58.447937)
			(xy 426.689502 -58.454037) (xy 426.633768 -58.452) (xy 426.578925 -58.44187) (xy 426.526141 -58.423863)
			(xy 426.476541 -58.398362) (xy 426.431183 -58.365911) (xy 426.391034 -58.327202) (xy 426.356948 -58.283059)
			(xy 426.329652 -58.234424) (xy 426.309729 -58.182333) (xy 426.297603 -58.127896) (xy 426.293532 -58.072274)
			(xy 423.043374 -58.072274) (xy 423.036319 -58.097219) (xy 423.015184 -58.145418) (xy 422.987637 -58.190261)
			(xy 422.954198 -58.230901) (xy 422.935146 -58.249058) (xy 422.927768 -58.2566) (xy 422.919229 -58.275864)
			(xy 422.918636 -58.286396) (xy 422.918636 -58.361072) (xy 422.919156 -58.371623) (xy 422.927697 -58.390919)
			(xy 422.935146 -58.39841) (xy 422.954208 -58.416559) (xy 422.987663 -58.457191) (xy 423.01522 -58.502033)
			(xy 423.036357 -58.550235) (xy 423.039463 -58.561224) (xy 432.862226 -58.561224) (xy 432.866297 -58.505602)
			(xy 432.878423 -58.451165) (xy 432.898346 -58.399074) (xy 432.925642 -58.350439) (xy 432.959728 -58.306296)
			(xy 432.999877 -58.267587) (xy 433.045235 -58.235136) (xy 433.094835 -58.209635) (xy 433.147619 -58.191628)
			(xy 433.202462 -58.181498) (xy 433.258196 -58.179461) (xy 433.313633 -58.185561) (xy 433.36759 -58.199667)
			(xy 433.418919 -58.221479) (xy 433.466525 -58.250533) (xy 433.509393 -58.286208) (xy 433.54661 -58.327745)
			(xy 433.577383 -58.374258) (xy 433.601055 -58.424755) (xy 433.617123 -58.478162) (xy 433.625243 -58.533338)
			(xy 433.625752 -58.561224) (xy 433.625243 -58.58911) (xy 433.617123 -58.644286) (xy 433.601055 -58.697693)
			(xy 433.577383 -58.74819) (xy 433.54661 -58.794703) (xy 433.509393 -58.83624) (xy 433.466525 -58.871915)
			(xy 433.418919 -58.900969) (xy 433.36759 -58.922781) (xy 433.313633 -58.936887) (xy 433.258196 -58.942987)
			(xy 433.202462 -58.94095) (xy 433.147619 -58.93082) (xy 433.094835 -58.912813) (xy 433.045235 -58.887312)
			(xy 432.999877 -58.854861) (xy 432.959728 -58.816152) (xy 432.925642 -58.772009) (xy 432.898346 -58.723374)
			(xy 432.878423 -58.671283) (xy 432.866297 -58.616846) (xy 432.862226 -58.561224) (xy 423.039463 -58.561224)
			(xy 423.050673 -58.600883) (xy 423.057898 -58.653018) (xy 423.058336 -58.679334) (xy 423.05785 -58.706585)
			(xy 423.050094 -58.760533) (xy 423.034739 -58.812828) (xy 423.012097 -58.862405) (xy 422.982631 -58.908255)
			(xy 422.94694 -58.949446) (xy 422.905749 -58.985137) (xy 422.859899 -59.014603) (xy 422.810322 -59.037245)
			(xy 422.758027 -59.0526) (xy 422.704079 -59.060356) (xy 422.649577 -59.060356) (xy 422.595629 -59.0526)
			(xy 422.543334 -59.037245) (xy 422.493757 -59.014603) (xy 422.447907 -58.985137) (xy 422.406716 -58.949446)
			(xy 422.371025 -58.908255) (xy 422.341559 -58.862405) (xy 422.318917 -58.812828) (xy 422.303562 -58.760533)
			(xy 422.295806 -58.706585) (xy 422.29532 -58.679334) (xy 413.059449 -58.679334) (xy 413.089155 -59.174634)
			(xy 431.39309 -59.174634) (xy 431.397161 -59.119012) (xy 431.409287 -59.064575) (xy 431.42921 -59.012484)
			(xy 431.456506 -58.963849) (xy 431.490592 -58.919706) (xy 431.530741 -58.880997) (xy 431.576099 -58.848546)
			(xy 431.625699 -58.823045) (xy 431.678483 -58.805038) (xy 431.733326 -58.794908) (xy 431.78906 -58.792871)
			(xy 431.844497 -58.798971) (xy 431.898454 -58.813077) (xy 431.949783 -58.834889) (xy 431.997389 -58.863943)
			(xy 432.040257 -58.899618) (xy 432.077474 -58.941155) (xy 432.108247 -58.987668) (xy 432.131919 -59.038165)
			(xy 432.147987 -59.091572) (xy 432.156107 -59.146748) (xy 432.156616 -59.174634) (xy 432.156107 -59.20252)
			(xy 432.147987 -59.257696) (xy 432.131919 -59.311103) (xy 432.108247 -59.3616) (xy 432.077474 -59.408113)
			(xy 432.040257 -59.44965) (xy 431.997389 -59.485325) (xy 431.949783 -59.514379) (xy 431.898454 -59.536191)
			(xy 431.844497 -59.550297) (xy 431.78906 -59.556397) (xy 431.733326 -59.55436) (xy 431.678483 -59.54423)
			(xy 431.625699 -59.526223) (xy 431.576099 -59.500722) (xy 431.530741 -59.468271) (xy 431.490592 -59.429562)
			(xy 431.456506 -59.385419) (xy 431.42921 -59.336784) (xy 431.409287 -59.284693) (xy 431.397161 -59.230256)
			(xy 431.39309 -59.174634) (xy 413.089155 -59.174634) (xy 413.126936 -59.804554) (xy 413.127952 -59.838844)
			(xy 413.127952 -59.839352) (xy 413.127419 -59.874545) (xy 413.118934 -59.944419) (xy 413.102095 -60.012762)
			(xy 413.099744 -60.01925) (xy 422.435784 -60.01925) (xy 422.435784 -59.96475) (xy 422.44354 -59.910805)
			(xy 422.458894 -59.858512) (xy 422.481533 -59.808937) (xy 422.510997 -59.763088) (xy 422.546686 -59.721899)
			(xy 422.587874 -59.686208) (xy 422.633721 -59.656742) (xy 422.683295 -59.6341) (xy 422.735587 -59.618743)
			(xy 422.789532 -59.610985) (xy 422.816782 -59.610498) (xy 422.844152 -59.610975) (xy 422.89833 -59.61879)
			(xy 422.950833 -59.634277) (xy 423.00058 -59.657116) (xy 423.046548 -59.686838) (xy 423.06748 -59.704478)
			(xy 423.067734 -59.704732) (xy 423.074833 -59.710301) (xy 423.09174 -59.716557) (xy 423.100754 -59.716924)
			(xy 423.16781 -59.716924) (xy 423.176827 -59.716566) (xy 423.193743 -59.710319) (xy 423.20083 -59.704732)
			(xy 423.20083 -59.704478) (xy 423.201084 -59.704478) (xy 423.222017 -59.686837) (xy 423.267985 -59.657113)
			(xy 423.317731 -59.634267) (xy 423.370233 -59.618771) (xy 423.424411 -59.610942) (xy 423.479153 -59.610942)
			(xy 423.533331 -59.618771) (xy 423.585833 -59.634267) (xy 423.635579 -59.657113) (xy 423.681547 -59.686837)
			(xy 423.70248 -59.704478) (xy 423.702734 -59.704732) (xy 423.709833 -59.710301) (xy 423.72674 -59.716557)
			(xy 423.735754 -59.716924) (xy 423.80281 -59.716924) (xy 423.811827 -59.716566) (xy 423.828743 -59.710319)
			(xy 423.83583 -59.704732) (xy 423.83583 -59.704478) (xy 423.836084 -59.704478) (xy 423.857008 -59.68683)
			(xy 423.902984 -59.65712) (xy 423.952733 -59.634286) (xy 424.005235 -59.618797) (xy 424.059412 -59.610971)
			(xy 424.086782 -59.610498) (xy 424.114036 -59.610948) (xy 424.16799 -59.618703) (xy 424.220291 -59.634058)
			(xy 424.269874 -59.6567) (xy 424.31573 -59.686168) (xy 424.356925 -59.721862) (xy 424.392622 -59.763056)
			(xy 424.422092 -59.80891) (xy 424.444736 -59.858492) (xy 424.460093 -59.910793) (xy 424.467851 -59.964746)
			(xy 424.467851 -60.019254) (xy 424.460093 -60.073207) (xy 424.444736 -60.125508) (xy 424.422092 -60.17509)
			(xy 424.392622 -60.220944) (xy 424.356925 -60.262138) (xy 424.31573 -60.297832) (xy 424.269874 -60.3273)
			(xy 424.220291 -60.349942) (xy 424.16799 -60.365297) (xy 424.114036 -60.373052) (xy 424.086782 -60.373514)
			(xy 424.059412 -60.373055) (xy 424.005232 -60.365235) (xy 423.952729 -60.349744) (xy 423.902983 -60.326901)
			(xy 423.857016 -60.297175) (xy 423.836084 -60.279534) (xy 423.83583 -60.27928) (xy 423.828741 -60.273698)
			(xy 423.811826 -60.267449) (xy 423.80281 -60.267088) (xy 423.735754 -60.267088) (xy 423.72674 -60.267473)
			(xy 423.709823 -60.273701) (xy 423.702734 -60.27928) (xy 423.70248 -60.279534) (xy 423.681547 -60.297175)
			(xy 423.635579 -60.326899) (xy 423.585833 -60.349745) (xy 423.533331 -60.365241) (xy 423.479153 -60.37307)
			(xy 423.424411 -60.37307) (xy 423.370233 -60.365241) (xy 423.317731 -60.349745) (xy 423.267985 -60.326899)
			(xy 423.222017 -60.297175) (xy 423.201084 -60.279534) (xy 423.20083 -60.27928) (xy 423.193741 -60.273698)
			(xy 423.176826 -60.267449) (xy 423.16781 -60.267088) (xy 423.100754 -60.267088) (xy 423.09174 -60.267473)
			(xy 423.074823 -60.273701) (xy 423.067734 -60.27928) (xy 423.067734 -60.279534) (xy 423.06748 -60.279534)
			(xy 423.046533 -60.297154) (xy 423.000564 -60.326868) (xy 422.95082 -60.349707) (xy 422.898323 -60.365202)
			(xy 422.84415 -60.373037) (xy 422.816782 -60.373514) (xy 422.789532 -60.373015) (xy 422.735587 -60.365257)
			(xy 422.683295 -60.3499) (xy 422.633721 -60.327258) (xy 422.587874 -60.297792) (xy 422.546686 -60.262101)
			(xy 422.510997 -60.220912) (xy 422.481533 -60.175063) (xy 422.458894 -60.125488) (xy 422.44354 -60.073195)
			(xy 422.435784 -60.01925) (xy 413.099744 -60.01925) (xy 413.090106 -60.045854) (xy 412.886906 -60.581286)
			(xy 412.885359 -60.585633) (xy 412.883691 -60.594707) (xy 412.883604 -60.59932) (xy 412.883604 -60.633356)
			(xy 434.09692 -60.633356) (xy 434.100991 -60.577734) (xy 434.113117 -60.523297) (xy 434.13304 -60.471206)
			(xy 434.160336 -60.422571) (xy 434.194422 -60.378428) (xy 434.234571 -60.339719) (xy 434.279929 -60.307268)
			(xy 434.329529 -60.281767) (xy 434.382313 -60.26376) (xy 434.437156 -60.25363) (xy 434.49289 -60.251593)
			(xy 434.548327 -60.257693) (xy 434.602284 -60.271799) (xy 434.653613 -60.293611) (xy 434.701219 -60.322665)
			(xy 434.744087 -60.35834) (xy 434.781304 -60.399877) (xy 434.812077 -60.44639) (xy 434.835749 -60.496887)
			(xy 434.851817 -60.550294) (xy 434.859937 -60.60547) (xy 434.860446 -60.633356) (xy 434.859937 -60.661242)
			(xy 434.851817 -60.716418) (xy 434.835749 -60.769825) (xy 434.812077 -60.820322) (xy 434.781304 -60.866835)
			(xy 434.744087 -60.908372) (xy 434.701219 -60.944047) (xy 434.653613 -60.973101) (xy 434.602284 -60.994913)
			(xy 434.548327 -61.009019) (xy 434.49289 -61.015119) (xy 434.437156 -61.013082) (xy 434.382313 -61.002952)
			(xy 434.329529 -60.984945) (xy 434.279929 -60.959444) (xy 434.234571 -60.926993) (xy 434.194422 -60.888284)
			(xy 434.160336 -60.844141) (xy 434.13304 -60.795506) (xy 434.113117 -60.743415) (xy 434.100991 -60.688978)
			(xy 434.09692 -60.633356) (xy 412.883604 -60.633356) (xy 412.883604 -60.7949) (xy 412.882972 -60.833576)
			(xy 412.872877 -60.910267) (xy 412.85286 -60.984985) (xy 412.838646 -61.02096) (xy 412.645284 -61.487812)
			(xy 432.604416 -61.487812) (xy 432.608487 -61.43219) (xy 432.620613 -61.377753) (xy 432.640536 -61.325662)
			(xy 432.667832 -61.277027) (xy 432.701918 -61.232884) (xy 432.742067 -61.194175) (xy 432.787425 -61.161724)
			(xy 432.837025 -61.136223) (xy 432.889809 -61.118216) (xy 432.944652 -61.108086) (xy 433.000386 -61.106049)
			(xy 433.055823 -61.112149) (xy 433.10978 -61.126255) (xy 433.161109 -61.148067) (xy 433.208715 -61.177121)
			(xy 433.251583 -61.212796) (xy 433.2888 -61.254333) (xy 433.319573 -61.300846) (xy 433.343245 -61.351343)
			(xy 433.359313 -61.40475) (xy 433.367433 -61.459926) (xy 433.367942 -61.487812) (xy 433.367433 -61.515698)
			(xy 433.359313 -61.570874) (xy 433.343245 -61.624281) (xy 433.319573 -61.674778) (xy 433.2888 -61.721291)
			(xy 433.251583 -61.762828) (xy 433.208715 -61.798503) (xy 433.161109 -61.827557) (xy 433.10978 -61.849369)
			(xy 433.055823 -61.863475) (xy 433.000386 -61.869575) (xy 432.944652 -61.867538) (xy 432.889809 -61.857408)
			(xy 432.837025 -61.839401) (xy 432.787425 -61.8139) (xy 432.742067 -61.781449) (xy 432.701918 -61.74274)
			(xy 432.667832 -61.698597) (xy 432.640536 -61.649962) (xy 432.620613 -61.597871) (xy 432.608487 -61.543434)
			(xy 432.604416 -61.487812) (xy 412.645284 -61.487812) (xy 412.383015 -62.121034) (xy 430.54219 -62.121034)
			(xy 430.546261 -62.065412) (xy 430.558387 -62.010975) (xy 430.57831 -61.958884) (xy 430.605606 -61.910249)
			(xy 430.639692 -61.866106) (xy 430.679841 -61.827397) (xy 430.725199 -61.794946) (xy 430.774799 -61.769445)
			(xy 430.827583 -61.751438) (xy 430.882426 -61.741308) (xy 430.93816 -61.739271) (xy 430.993597 -61.745371)
			(xy 431.047554 -61.759477) (xy 431.098883 -61.781289) (xy 431.146489 -61.810343) (xy 431.189357 -61.846018)
			(xy 431.226574 -61.887555) (xy 431.257347 -61.934068) (xy 431.281019 -61.984565) (xy 431.297087 -62.037972)
			(xy 431.305207 -62.093148) (xy 431.305716 -62.121034) (xy 431.305207 -62.14892) (xy 431.297087 -62.204096)
			(xy 431.281019 -62.257503) (xy 431.257347 -62.308) (xy 431.226574 -62.354513) (xy 431.189357 -62.39605)
			(xy 431.146489 -62.431725) (xy 431.098883 -62.460779) (xy 431.047554 -62.482591) (xy 430.993597 -62.496697)
			(xy 430.93816 -62.502797) (xy 430.882426 -62.50076) (xy 430.827583 -62.49063) (xy 430.774799 -62.472623)
			(xy 430.725199 -62.447122) (xy 430.679841 -62.414671) (xy 430.639692 -62.375962) (xy 430.605606 -62.331819)
			(xy 430.57831 -62.283184) (xy 430.558387 -62.231093) (xy 430.546261 -62.176656) (xy 430.54219 -62.121034)
			(xy 412.383015 -62.121034) (xy 411.930515 -63.21355) (xy 422.420788 -63.21355) (xy 422.420788 -63.15905)
			(xy 422.428544 -63.105104) (xy 422.443899 -63.052811) (xy 422.466539 -63.003235) (xy 422.496004 -62.957386)
			(xy 422.531694 -62.916197) (xy 422.572883 -62.880507) (xy 422.618732 -62.851041) (xy 422.668307 -62.8284)
			(xy 422.7206 -62.813045) (xy 422.774546 -62.805289) (xy 422.801796 -62.804802) (xy 422.829166 -62.80527)
			(xy 422.883345 -62.813087) (xy 422.935848 -62.828576) (xy 422.985595 -62.851417) (xy 423.031562 -62.881141)
			(xy 423.052494 -62.898782) (xy 423.052748 -62.899036) (xy 423.059842 -62.904611) (xy 423.076753 -62.910864)
			(xy 423.085768 -62.911228) (xy 423.152824 -62.911228) (xy 423.161841 -62.910877) (xy 423.178758 -62.904625)
			(xy 423.185844 -62.899036) (xy 423.185844 -62.898782) (xy 423.186098 -62.898782) (xy 423.207031 -62.881141)
			(xy 423.252999 -62.851417) (xy 423.302745 -62.828571) (xy 423.355247 -62.813075) (xy 423.409425 -62.805246)
			(xy 423.464167 -62.805246) (xy 423.518345 -62.813075) (xy 423.570847 -62.828571) (xy 423.620593 -62.851417)
			(xy 423.666561 -62.881141) (xy 423.687494 -62.898782) (xy 423.687748 -62.899036) (xy 423.694842 -62.904611)
			(xy 423.711753 -62.910864) (xy 423.720768 -62.911228) (xy 423.787824 -62.911228) (xy 423.796841 -62.910877)
			(xy 423.813758 -62.904625) (xy 423.820844 -62.899036) (xy 423.820844 -62.898782) (xy 423.821098 -62.898782)
			(xy 423.842018 -62.881128) (xy 423.887994 -62.851419) (xy 423.937745 -62.828586) (xy 423.990248 -62.813098)
			(xy 424.044426 -62.805274) (xy 424.071796 -62.804802) (xy 424.09905 -62.805245) (xy 424.153003 -62.813001)
			(xy 424.205302 -62.828357) (xy 424.254884 -62.851) (xy 424.300739 -62.880469) (xy 424.341934 -62.916164)
			(xy 424.377629 -62.957358) (xy 424.407098 -63.003212) (xy 424.429741 -63.052794) (xy 424.43956 -63.086234)
			(xy 427.687484 -63.086234) (xy 427.691555 -63.030612) (xy 427.703681 -62.976175) (xy 427.723604 -62.924084)
			(xy 427.7509 -62.875449) (xy 427.784986 -62.831306) (xy 427.825135 -62.792597) (xy 427.870493 -62.760146)
			(xy 427.920093 -62.734645) (xy 427.972877 -62.716638) (xy 428.02772 -62.706508) (xy 428.083454 -62.704471)
			(xy 428.138891 -62.710571) (xy 428.192848 -62.724677) (xy 428.213015 -62.733247) (xy 433.966051 -62.733247)
			(xy 433.966052 -62.67874) (xy 433.97381 -62.624788) (xy 433.989167 -62.57249) (xy 434.011811 -62.522909)
			(xy 434.041281 -62.477056) (xy 434.076976 -62.435863) (xy 434.118171 -62.40017) (xy 434.164025 -62.370702)
			(xy 434.213607 -62.348061) (xy 434.265906 -62.332706) (xy 434.319859 -62.324951) (xy 434.347112 -62.324488)
			(xy 434.370667 -62.324866) (xy 434.417411 -62.330724) (xy 434.44033 -62.336172) (xy 434.454089 -62.339193)
			(xy 434.482238 -62.338341) (xy 434.509085 -62.329838) (xy 434.532591 -62.314329) (xy 434.550972 -62.292993)
			(xy 434.562831 -62.267451) (xy 434.567268 -62.239641) (xy 434.563945 -62.211676) (xy 434.558948 -62.198504)
			(xy 434.549637 -62.175115) (xy 434.536512 -62.126514) (xy 434.529889 -62.076609) (xy 434.529484 -62.051438)
			(xy 434.529914 -62.024182) (xy 434.537667 -61.970223) (xy 434.55302 -61.917917) (xy 434.575661 -61.868329)
			(xy 434.605129 -61.822468) (xy 434.640824 -61.781267) (xy 434.682019 -61.745565) (xy 434.727876 -61.71609)
			(xy 434.77746 -61.693441) (xy 434.829764 -61.67808) (xy 434.883721 -61.670319) (xy 434.938234 -61.670315)
			(xy 434.992192 -61.67807) (xy 435.044497 -61.693426) (xy 435.094085 -61.716069) (xy 435.139945 -61.745538)
			(xy 435.181144 -61.781235) (xy 435.216844 -61.822431) (xy 435.246317 -61.868289) (xy 435.268964 -61.917875)
			(xy 435.284323 -61.970179) (xy 435.292082 -62.024136) (xy 435.292084 -62.078649) (xy 435.284326 -62.132607)
			(xy 435.268969 -62.184911) (xy 435.246324 -62.234498) (xy 435.216853 -62.280357) (xy 435.181155 -62.321555)
			(xy 435.139957 -62.357253) (xy 435.094097 -62.386724) (xy 435.044511 -62.409369) (xy 434.992206 -62.424727)
			(xy 434.938248 -62.432484) (xy 434.910992 -62.432946) (xy 434.887437 -62.432566) (xy 434.840693 -62.426709)
			(xy 434.817774 -62.421262) (xy 434.804021 -62.418198) (xy 434.775864 -62.419049) (xy 434.749009 -62.427554)
			(xy 434.725496 -62.443068) (xy 434.707112 -62.464412) (xy 434.695254 -62.489965) (xy 434.690822 -62.517784)
			(xy 434.694153 -62.545756) (xy 434.699156 -62.55893) (xy 434.708478 -62.582315) (xy 434.721599 -62.630918)
			(xy 434.728217 -62.680825) (xy 434.72862 -62.705996) (xy 434.728149 -62.733249) (xy 434.720392 -62.787201)
			(xy 434.705036 -62.8395) (xy 434.682394 -62.889082) (xy 434.652925 -62.934936) (xy 434.617231 -62.976129)
			(xy 434.576038 -63.011824) (xy 434.530184 -63.041293) (xy 434.480603 -63.063935) (xy 434.428304 -63.079292)
			(xy 434.374352 -63.087049) (xy 434.319845 -63.087049) (xy 434.265893 -63.079291) (xy 434.213595 -63.063935)
			(xy 434.164014 -63.041291) (xy 434.11816 -63.011822) (xy 434.076967 -62.976128) (xy 434.041273 -62.934934)
			(xy 434.011805 -62.889079) (xy 433.989163 -62.839498) (xy 433.973807 -62.787199) (xy 433.966051 -62.733247)
			(xy 428.213015 -62.733247) (xy 428.244177 -62.746489) (xy 428.291783 -62.775543) (xy 428.334651 -62.811218)
			(xy 428.371868 -62.852755) (xy 428.402641 -62.899268) (xy 428.426313 -62.949765) (xy 428.442381 -63.003172)
			(xy 428.450501 -63.058348) (xy 428.45101 -63.086234) (xy 428.450501 -63.11412) (xy 428.442381 -63.169296)
			(xy 428.426313 -63.222703) (xy 428.402641 -63.2732) (xy 428.402488 -63.273432) (xy 429.87671 -63.273432)
			(xy 429.880781 -63.21781) (xy 429.892907 -63.163373) (xy 429.91283 -63.111282) (xy 429.940126 -63.062647)
			(xy 429.974212 -63.018504) (xy 430.014361 -62.979795) (xy 430.059719 -62.947344) (xy 430.109319 -62.921843)
			(xy 430.162103 -62.903836) (xy 430.216946 -62.893706) (xy 430.27268 -62.891669) (xy 430.328117 -62.897769)
			(xy 430.382074 -62.911875) (xy 430.433403 -62.933687) (xy 430.481009 -62.962741) (xy 430.523877 -62.998416)
			(xy 430.561094 -63.039953) (xy 430.591867 -63.086466) (xy 430.615539 -63.136963) (xy 430.631607 -63.19037)
			(xy 430.639727 -63.245546) (xy 430.640236 -63.273432) (xy 430.639727 -63.301318) (xy 430.631607 -63.356494)
			(xy 430.615539 -63.409901) (xy 430.591867 -63.460398) (xy 430.561094 -63.506911) (xy 430.523877 -63.548448)
			(xy 430.481009 -63.584123) (xy 430.433403 -63.613177) (xy 430.382074 -63.634989) (xy 430.328117 -63.649095)
			(xy 430.27268 -63.655195) (xy 430.216946 -63.653158) (xy 430.162103 -63.643028) (xy 430.109319 -63.625021)
			(xy 430.059719 -63.59952) (xy 430.014361 -63.567069) (xy 429.974212 -63.52836) (xy 429.940126 -63.484217)
			(xy 429.91283 -63.435582) (xy 429.892907 -63.383491) (xy 429.880781 -63.329054) (xy 429.87671 -63.273432)
			(xy 428.402488 -63.273432) (xy 428.371868 -63.319713) (xy 428.334651 -63.36125) (xy 428.291783 -63.396925)
			(xy 428.244177 -63.425979) (xy 428.192848 -63.447791) (xy 428.138891 -63.461897) (xy 428.083454 -63.467997)
			(xy 428.02772 -63.46596) (xy 427.972877 -63.45583) (xy 427.920093 -63.437823) (xy 427.870493 -63.412322)
			(xy 427.825135 -63.379871) (xy 427.784986 -63.341162) (xy 427.7509 -63.297019) (xy 427.723604 -63.248384)
			(xy 427.703681 -63.196293) (xy 427.691555 -63.141856) (xy 427.687484 -63.086234) (xy 424.43956 -63.086234)
			(xy 424.445098 -63.105093) (xy 424.452855 -63.159046) (xy 424.452855 -63.213554) (xy 424.445098 -63.267507)
			(xy 424.429741 -63.319806) (xy 424.407098 -63.369388) (xy 424.377629 -63.415242) (xy 424.341934 -63.456436)
			(xy 424.300739 -63.492131) (xy 424.254884 -63.5216) (xy 424.205302 -63.544243) (xy 424.153003 -63.559599)
			(xy 424.09905 -63.567355) (xy 424.071796 -63.567818) (xy 424.044425 -63.567374) (xy 423.990244 -63.559554)
			(xy 423.93774 -63.544061) (xy 423.887993 -63.521214) (xy 423.842028 -63.491483) (xy 423.821098 -63.473838)
			(xy 423.820844 -63.473584) (xy 423.81375 -63.468008) (xy 423.796839 -63.461755) (xy 423.787824 -63.461392)
			(xy 423.720768 -63.461392) (xy 423.71175 -63.461736) (xy 423.694833 -63.467993) (xy 423.687748 -63.473584)
			(xy 423.687494 -63.473838) (xy 423.666561 -63.491479) (xy 423.620593 -63.521203) (xy 423.570847 -63.544049)
			(xy 423.518345 -63.559545) (xy 423.464167 -63.567374) (xy 423.409425 -63.567374) (xy 423.355247 -63.559545)
			(xy 423.302745 -63.544049) (xy 423.252999 -63.521203) (xy 423.207031 -63.491479) (xy 423.186098 -63.473838)
			(xy 423.185844 -63.473584) (xy 423.17875 -63.468008) (xy 423.161839 -63.461755) (xy 423.152824 -63.461392)
			(xy 423.085768 -63.461392) (xy 423.07675 -63.461736) (xy 423.059833 -63.467993) (xy 423.052748 -63.473584)
			(xy 423.052748 -63.473838) (xy 423.052494 -63.473838) (xy 423.03158 -63.4915) (xy 422.985602 -63.521207)
			(xy 422.93585 -63.544038) (xy 422.883345 -63.559524) (xy 422.829166 -63.567347) (xy 422.801796 -63.567818)
			(xy 422.774546 -63.567311) (xy 422.7206 -63.559555) (xy 422.668307 -63.5442) (xy 422.618732 -63.521559)
			(xy 422.572883 -63.492093) (xy 422.531694 -63.456403) (xy 422.496004 -63.415214) (xy 422.466539 -63.369365)
			(xy 422.443899 -63.319789) (xy 422.428544 -63.267496) (xy 422.420788 -63.21355) (xy 411.930515 -63.21355)
			(xy 411.42031 -64.445388) (xy 411.419802 -64.446912) (xy 411.171507 -65.100962) (xy 420.432482 -65.100962)
			(xy 420.436553 -65.04534) (xy 420.448679 -64.990903) (xy 420.468602 -64.938812) (xy 420.495898 -64.890177)
			(xy 420.529984 -64.846034) (xy 420.570133 -64.807325) (xy 420.615491 -64.774874) (xy 420.665091 -64.749373)
			(xy 420.717875 -64.731366) (xy 420.772718 -64.721236) (xy 420.828452 -64.719199) (xy 420.883889 -64.725299)
			(xy 420.937846 -64.739405) (xy 420.989175 -64.761217) (xy 421.036781 -64.790271) (xy 421.079649 -64.825946)
			(xy 421.116866 -64.867483) (xy 421.147639 -64.913996) (xy 421.171311 -64.964493) (xy 421.187379 -65.0179)
			(xy 421.195499 -65.073076) (xy 421.196008 -65.100962) (xy 421.195586 -65.124076) (xy 432.407312 -65.124076)
			(xy 432.411383 -65.068454) (xy 432.423509 -65.014017) (xy 432.443432 -64.961926) (xy 432.470728 -64.913291)
			(xy 432.504814 -64.869148) (xy 432.544963 -64.830439) (xy 432.590321 -64.797988) (xy 432.639921 -64.772487)
			(xy 432.692705 -64.75448) (xy 432.747548 -64.74435) (xy 432.803282 -64.742313) (xy 432.858719 -64.748413)
			(xy 432.912676 -64.762519) (xy 432.964005 -64.784331) (xy 433.011611 -64.813385) (xy 433.054479 -64.84906)
			(xy 433.091696 -64.890597) (xy 433.122469 -64.93711) (xy 433.146141 -64.987607) (xy 433.162209 -65.041014)
			(xy 433.170329 -65.09619) (xy 433.170838 -65.124076) (xy 433.170329 -65.151962) (xy 433.162209 -65.207138)
			(xy 433.146141 -65.260545) (xy 433.122469 -65.311042) (xy 433.091696 -65.357555) (xy 433.054479 -65.399092)
			(xy 433.011611 -65.434767) (xy 432.964005 -65.463821) (xy 432.912676 -65.485633) (xy 432.858719 -65.499739)
			(xy 432.803282 -65.505839) (xy 432.747548 -65.503802) (xy 432.692705 -65.493672) (xy 432.639921 -65.475665)
			(xy 432.590321 -65.450164) (xy 432.544963 -65.417713) (xy 432.504814 -65.379004) (xy 432.470728 -65.334861)
			(xy 432.443432 -65.286226) (xy 432.423509 -65.234135) (xy 432.411383 -65.179698) (xy 432.407312 -65.124076)
			(xy 421.195586 -65.124076) (xy 421.195499 -65.128848) (xy 421.187379 -65.184024) (xy 421.171311 -65.237431)
			(xy 421.147639 -65.287928) (xy 421.116866 -65.334441) (xy 421.079649 -65.375978) (xy 421.036781 -65.411653)
			(xy 420.989175 -65.440707) (xy 420.937846 -65.462519) (xy 420.883889 -65.476625) (xy 420.828452 -65.482725)
			(xy 420.772718 -65.480688) (xy 420.717875 -65.470558) (xy 420.665091 -65.452551) (xy 420.615491 -65.42705)
			(xy 420.570133 -65.394599) (xy 420.529984 -65.35589) (xy 420.495898 -65.311747) (xy 420.468602 -65.263112)
			(xy 420.448679 -65.211021) (xy 420.436553 -65.156584) (xy 420.432482 -65.100962) (xy 411.171507 -65.100962)
			(xy 410.92302 -65.75552) (xy 414.646616 -65.75552) (xy 414.650687 -65.699898) (xy 414.662813 -65.645461)
			(xy 414.682736 -65.59337) (xy 414.710032 -65.544735) (xy 414.744118 -65.500592) (xy 414.784267 -65.461883)
			(xy 414.829625 -65.429432) (xy 414.879225 -65.403931) (xy 414.932009 -65.385924) (xy 414.986852 -65.375794)
			(xy 415.042586 -65.373757) (xy 415.098023 -65.379857) (xy 415.15198 -65.393963) (xy 415.203309 -65.415775)
			(xy 415.250915 -65.444829) (xy 415.293783 -65.480504) (xy 415.331 -65.522041) (xy 415.361773 -65.568554)
			(xy 415.385445 -65.619051) (xy 415.401513 -65.672458) (xy 415.409633 -65.727634) (xy 415.410142 -65.75552)
			(xy 415.409633 -65.783406) (xy 415.401513 -65.838582) (xy 415.385445 -65.891989) (xy 415.361773 -65.942486)
			(xy 415.331 -65.988999) (xy 415.293783 -66.030536) (xy 415.250915 -66.066211) (xy 415.203309 -66.095265)
			(xy 415.15198 -66.117077) (xy 415.098023 -66.131183) (xy 415.042586 -66.137283) (xy 414.986852 -66.135246)
			(xy 414.932009 -66.125116) (xy 414.879225 -66.107109) (xy 414.829625 -66.081608) (xy 414.784267 -66.049157)
			(xy 414.744118 -66.010448) (xy 414.710032 -65.966305) (xy 414.682736 -65.91767) (xy 414.662813 -65.865579)
			(xy 414.650687 -65.811142) (xy 414.646616 -65.75552) (xy 410.92302 -65.75552) (xy 410.914342 -65.77838)
			(xy 410.903058 -65.806989) (xy 410.875292 -65.861867) (xy 410.841888 -65.913508) (xy 410.80322 -65.961335)
			(xy 410.781754 -65.983358) (xy 409.636192 -67.128949) (xy 414.666698 -67.128949) (xy 414.666698 -67.074451)
			(xy 414.674454 -67.020508) (xy 414.689807 -66.968217) (xy 414.712446 -66.918643) (xy 414.741909 -66.872796)
			(xy 414.777597 -66.831609) (xy 414.818783 -66.795919) (xy 414.864629 -66.766454) (xy 414.914202 -66.743813)
			(xy 414.966492 -66.728457) (xy 415.020435 -66.720699) (xy 415.047684 -66.720212) (xy 415.075054 -66.720685)
			(xy 415.129233 -66.7285) (xy 415.181736 -66.743988) (xy 415.231483 -66.766828) (xy 415.27745 -66.796551)
			(xy 415.298382 -66.814192) (xy 415.298636 -66.814446) (xy 415.305733 -66.820017) (xy 415.322642 -66.826272)
			(xy 415.331656 -66.826638) (xy 415.398712 -66.826638) (xy 415.407728 -66.826279) (xy 415.424645 -66.820032)
			(xy 415.431732 -66.814446) (xy 415.431732 -66.814192) (xy 415.431986 -66.814192) (xy 415.452911 -66.796545)
			(xy 415.498886 -66.766834) (xy 415.548635 -66.744) (xy 415.601138 -66.728511) (xy 415.655314 -66.720685)
			(xy 415.682684 -66.720212) (xy 415.709939 -66.720634) (xy 415.763895 -66.728389) (xy 415.816197 -66.743745)
			(xy 415.865782 -66.766388) (xy 415.91164 -66.795857) (xy 415.952836 -66.831552) (xy 415.988534 -66.872748)
			(xy 416.018005 -66.918604) (xy 416.04065 -66.968188) (xy 416.056007 -67.02049) (xy 416.063765 -67.074445)
			(xy 416.063765 -67.128955) (xy 416.056007 -67.18291) (xy 416.04065 -67.235212) (xy 416.018005 -67.284796)
			(xy 415.988534 -67.330652) (xy 415.952836 -67.371848) (xy 415.91164 -67.407543) (xy 415.865782 -67.437012)
			(xy 415.816197 -67.459655) (xy 415.763895 -67.475011) (xy 415.709939 -67.482766) (xy 415.682684 -67.483228)
			(xy 415.655313 -67.482789) (xy 415.601132 -67.474967) (xy 415.548628 -67.459473) (xy 415.498881 -67.436625)
			(xy 415.452916 -67.406893) (xy 415.431986 -67.389248) (xy 415.431732 -67.388994) (xy 415.424641 -67.383414)
			(xy 415.407728 -67.377164) (xy 415.398712 -67.376802) (xy 415.331656 -67.376802) (xy 415.322642 -67.377186)
			(xy 415.305725 -67.383415) (xy 415.298636 -67.388994) (xy 415.298636 -67.389248) (xy 415.298382 -67.389248)
			(xy 415.277423 -67.406854) (xy 415.231459 -67.436573) (xy 415.181718 -67.459416) (xy 415.129223 -67.474914)
			(xy 415.075051 -67.48275) (xy 415.047684 -67.483228) (xy 415.020435 -67.482701) (xy 414.966492 -67.474943)
			(xy 414.914202 -67.459587) (xy 414.864629 -67.436946) (xy 414.818783 -67.407481) (xy 414.777597 -67.371791)
			(xy 414.741909 -67.330604) (xy 414.712446 -67.284757) (xy 414.689807 -67.235183) (xy 414.674454 -67.182892)
			(xy 414.666698 -67.128949) (xy 409.636192 -67.128949) (xy 409.277096 -67.488054) (xy 419.07917 -67.488054)
			(xy 419.083241 -67.432432) (xy 419.095367 -67.377995) (xy 419.11529 -67.325904) (xy 419.142586 -67.277269)
			(xy 419.176672 -67.233126) (xy 419.216821 -67.194417) (xy 419.262179 -67.161966) (xy 419.311779 -67.136465)
			(xy 419.364563 -67.118458) (xy 419.419406 -67.108328) (xy 419.47514 -67.106291) (xy 419.530577 -67.112391)
			(xy 419.584534 -67.126497) (xy 419.635863 -67.148309) (xy 419.683469 -67.177363) (xy 419.726337 -67.213038)
			(xy 419.763554 -67.254575) (xy 419.794327 -67.301088) (xy 419.817999 -67.351585) (xy 419.834067 -67.404992)
			(xy 419.842187 -67.460168) (xy 419.842696 -67.488054) (xy 419.842187 -67.51594) (xy 419.839002 -67.537584)
			(xy 420.371268 -67.537584) (xy 420.375339 -67.481962) (xy 420.387465 -67.427525) (xy 420.407388 -67.375434)
			(xy 420.434684 -67.326799) (xy 420.46877 -67.282656) (xy 420.508919 -67.243947) (xy 420.554277 -67.211496)
			(xy 420.603877 -67.185995) (xy 420.656661 -67.167988) (xy 420.711504 -67.157858) (xy 420.767238 -67.155821)
			(xy 420.822675 -67.161921) (xy 420.876632 -67.176027) (xy 420.927961 -67.197839) (xy 420.975567 -67.226893)
			(xy 421.018435 -67.262568) (xy 421.055652 -67.304105) (xy 421.086425 -67.350618) (xy 421.110097 -67.401115)
			(xy 421.126165 -67.454522) (xy 421.134285 -67.509698) (xy 421.134794 -67.537584) (xy 421.134285 -67.56547)
			(xy 421.13024 -67.592956) (xy 421.645332 -67.592956) (xy 421.649403 -67.537334) (xy 421.661529 -67.482897)
			(xy 421.681452 -67.430806) (xy 421.708748 -67.382171) (xy 421.742834 -67.338028) (xy 421.782983 -67.299319)
			(xy 421.828341 -67.266868) (xy 421.877941 -67.241367) (xy 421.930725 -67.22336) (xy 421.985568 -67.21323)
			(xy 422.041302 -67.211193) (xy 422.096739 -67.217293) (xy 422.150696 -67.231399) (xy 422.202025 -67.253211)
			(xy 422.249631 -67.282265) (xy 422.292499 -67.31794) (xy 422.329716 -67.359477) (xy 422.360489 -67.40599)
			(xy 422.384161 -67.456487) (xy 422.400229 -67.509894) (xy 422.408346 -67.565047) (xy 424.746716 -67.565047)
			(xy 424.746716 -67.510553) (xy 424.754471 -67.456613) (xy 424.769823 -67.404325) (xy 424.79246 -67.354755)
			(xy 424.821921 -67.30891) (xy 424.857606 -67.267725) (xy 424.898789 -67.232037) (xy 424.944632 -67.202573)
			(xy 424.994201 -67.179933) (xy 425.046487 -67.164577) (xy 425.100427 -67.156818) (xy 425.127674 -67.15633)
			(xy 425.155044 -67.156804) (xy 425.209223 -67.164619) (xy 425.261726 -67.180106) (xy 425.311473 -67.202946)
			(xy 425.35744 -67.232669) (xy 425.378372 -67.25031) (xy 425.378626 -67.250564) (xy 425.385724 -67.256133)
			(xy 425.402632 -67.262389) (xy 425.411646 -67.262756) (xy 425.478702 -67.262756) (xy 425.48772 -67.262409)
			(xy 425.504637 -67.256155) (xy 425.511722 -67.250564) (xy 425.511722 -67.25031) (xy 425.511976 -67.25031)
			(xy 425.532908 -67.23267) (xy 425.57888 -67.202958) (xy 425.628628 -67.180122) (xy 425.681129 -67.164631)
			(xy 425.735305 -67.156804) (xy 425.762674 -67.15633) (xy 425.789931 -67.156715) (xy 425.84389 -67.16447)
			(xy 425.896196 -67.179825) (xy 425.945785 -67.202469) (xy 425.991646 -67.231939) (xy 426.032846 -67.267636)
			(xy 426.068546 -67.308834) (xy 426.098019 -67.354693) (xy 426.120666 -67.404279) (xy 426.136025 -67.456585)
			(xy 426.143783 -67.510543) (xy 426.143783 -67.565057) (xy 426.136025 -67.619015) (xy 426.120666 -67.671321)
			(xy 426.098019 -67.720907) (xy 426.068546 -67.766766) (xy 426.032846 -67.807964) (xy 425.991646 -67.843661)
			(xy 425.945785 -67.873131) (xy 425.896196 -67.895775) (xy 425.84389 -67.91113) (xy 425.789931 -67.918885)
			(xy 425.762674 -67.919346) (xy 425.735303 -67.918908) (xy 425.681122 -67.911086) (xy 425.628618 -67.895591)
			(xy 425.578871 -67.872742) (xy 425.532906 -67.843011) (xy 425.511976 -67.825366) (xy 425.511722 -67.825112)
			(xy 425.504632 -67.81953) (xy 425.487718 -67.81328) (xy 425.478702 -67.81292) (xy 425.411646 -67.81292)
			(xy 425.402631 -67.813295) (xy 425.385714 -67.81953) (xy 425.378626 -67.825112) (xy 425.378626 -67.825366)
			(xy 425.378372 -67.825366) (xy 425.357419 -67.84298) (xy 425.311453 -67.872696) (xy 425.26171 -67.895538)
			(xy 425.209214 -67.911035) (xy 425.155042 -67.918869) (xy 425.127674 -67.919346) (xy 425.100427 -67.918782)
			(xy 425.046487 -67.911023) (xy 424.994201 -67.895667) (xy 424.944632 -67.873027) (xy 424.898789 -67.843563)
			(xy 424.857606 -67.807875) (xy 424.821921 -67.76669) (xy 424.79246 -67.720845) (xy 424.769823 -67.671275)
			(xy 424.754471 -67.618987) (xy 424.746716 -67.565047) (xy 422.408346 -67.565047) (xy 422.408349 -67.56507)
			(xy 422.408858 -67.592956) (xy 422.408349 -67.620842) (xy 422.400229 -67.676018) (xy 422.384161 -67.729425)
			(xy 422.360489 -67.779922) (xy 422.329716 -67.826435) (xy 422.292499 -67.867972) (xy 422.249631 -67.903647)
			(xy 422.202025 -67.932701) (xy 422.150696 -67.954513) (xy 422.096739 -67.968619) (xy 422.041302 -67.974719)
			(xy 421.985568 -67.972682) (xy 421.930725 -67.962552) (xy 421.877941 -67.944545) (xy 421.828341 -67.919044)
			(xy 421.782983 -67.886593) (xy 421.742834 -67.847884) (xy 421.708748 -67.803741) (xy 421.681452 -67.755106)
			(xy 421.661529 -67.703015) (xy 421.649403 -67.648578) (xy 421.645332 -67.592956) (xy 421.13024 -67.592956)
			(xy 421.126165 -67.620646) (xy 421.110097 -67.674053) (xy 421.086425 -67.72455) (xy 421.055652 -67.771063)
			(xy 421.018435 -67.8126) (xy 420.975567 -67.848275) (xy 420.927961 -67.877329) (xy 420.876632 -67.899141)
			(xy 420.822675 -67.913247) (xy 420.767238 -67.919347) (xy 420.711504 -67.91731) (xy 420.656661 -67.90718)
			(xy 420.603877 -67.889173) (xy 420.554277 -67.863672) (xy 420.508919 -67.831221) (xy 420.46877 -67.792512)
			(xy 420.434684 -67.748369) (xy 420.407388 -67.699734) (xy 420.387465 -67.647643) (xy 420.375339 -67.593206)
			(xy 420.371268 -67.537584) (xy 419.839002 -67.537584) (xy 419.834067 -67.571116) (xy 419.817999 -67.624523)
			(xy 419.794327 -67.67502) (xy 419.763554 -67.721533) (xy 419.726337 -67.76307) (xy 419.683469 -67.798745)
			(xy 419.635863 -67.827799) (xy 419.584534 -67.849611) (xy 419.530577 -67.863717) (xy 419.47514 -67.869817)
			(xy 419.419406 -67.86778) (xy 419.364563 -67.85765) (xy 419.311779 -67.839643) (xy 419.262179 -67.814142)
			(xy 419.216821 -67.781691) (xy 419.176672 -67.742982) (xy 419.142586 -67.698839) (xy 419.11529 -67.650204)
			(xy 419.095367 -67.598113) (xy 419.083241 -67.543676) (xy 419.07917 -67.488054) (xy 409.277096 -67.488054)
			(xy 408.178573 -68.586604) (xy 416.925252 -68.586604) (xy 416.925708 -68.559233) (xy 416.933526 -68.505053)
			(xy 416.949017 -68.45255) (xy 416.971861 -68.402803) (xy 417.001589 -68.356837) (xy 417.019232 -68.335906)
			(xy 417.019486 -68.335652) (xy 417.025055 -68.328554) (xy 417.031313 -68.311646) (xy 417.031678 -68.302632)
			(xy 417.031678 -68.235576) (xy 417.031337 -68.226557) (xy 417.025079 -68.20964) (xy 417.019486 -68.202556)
			(xy 417.019232 -68.202556) (xy 417.019232 -68.202302) (xy 417.001585 -68.181376) (xy 416.971874 -68.135402)
			(xy 416.949039 -68.085653) (xy 416.933549 -68.033151) (xy 416.925724 -67.978974) (xy 416.925252 -67.951604)
			(xy 416.925781 -67.924355) (xy 416.933536 -67.870411) (xy 416.948889 -67.818119) (xy 416.971527 -67.768545)
			(xy 417.000989 -67.722696) (xy 417.036676 -67.681507) (xy 417.077861 -67.645815) (xy 417.123706 -67.616348)
			(xy 417.173278 -67.593704) (xy 417.225568 -67.578346) (xy 417.279511 -67.570585) (xy 417.30676 -67.570096)
			(xy 417.333075 -67.570525) (xy 417.385205 -67.577768) (xy 417.435849 -67.592094) (xy 417.484048 -67.613234)
			(xy 417.52889 -67.640787) (xy 417.569528 -67.674232) (xy 417.587684 -67.693286) (xy 417.595212 -67.70068)
			(xy 417.614487 -67.709209) (xy 417.625022 -67.709796) (xy 417.699698 -67.709796) (xy 417.710249 -67.70928)
			(xy 417.729544 -67.700736) (xy 417.737036 -67.693286) (xy 417.755178 -67.674217) (xy 417.795811 -67.640762)
			(xy 417.840654 -67.613205) (xy 417.888858 -67.592069) (xy 417.939507 -67.577754) (xy 417.991643 -67.570533)
			(xy 418.01796 -67.570096) (xy 418.045329 -67.570586) (xy 418.099507 -67.578399) (xy 418.15201 -67.593882)
			(xy 418.201757 -67.616718) (xy 418.247725 -67.646437) (xy 418.268658 -67.664076) (xy 418.268912 -67.66433)
			(xy 418.275988 -67.669931) (xy 418.292913 -67.676168) (xy 418.301932 -67.676522) (xy 418.368988 -67.676522)
			(xy 418.378004 -67.676154) (xy 418.39492 -67.669914) (xy 418.402008 -67.66433) (xy 418.402008 -67.664076)
			(xy 418.402262 -67.664076) (xy 418.423194 -67.646438) (xy 418.469168 -67.616726) (xy 418.518915 -67.593891)
			(xy 418.571415 -67.578399) (xy 418.625591 -67.570571) (xy 418.65296 -67.570096) (xy 418.680212 -67.570593)
			(xy 418.734162 -67.578344) (xy 418.786459 -67.593695) (xy 418.83604 -67.616333) (xy 418.881893 -67.645798)
			(xy 418.923086 -67.681488) (xy 418.958781 -67.722678) (xy 418.988249 -67.768529) (xy 419.010892 -67.818107)
			(xy 419.026248 -67.870403) (xy 419.034005 -67.924352) (xy 419.034468 -67.951604) (xy 419.034012 -67.978975)
			(xy 419.026193 -68.033155) (xy 419.010702 -68.085658) (xy 418.987858 -68.135405) (xy 418.958131 -68.181371)
			(xy 418.940488 -68.202302) (xy 418.940234 -68.202556) (xy 418.934652 -68.209645) (xy 418.928404 -68.22656)
			(xy 418.928042 -68.235576) (xy 418.928042 -68.302632) (xy 418.928375 -68.311652) (xy 418.934638 -68.328569)
			(xy 418.940234 -68.335652) (xy 418.940488 -68.335652) (xy 418.940488 -68.335906) (xy 418.958141 -68.356827)
			(xy 418.987852 -68.402802) (xy 419.010685 -68.452553) (xy 419.026173 -68.505056) (xy 419.033996 -68.559234)
			(xy 419.034468 -68.586604) (xy 419.034048 -68.613859) (xy 419.02629 -68.667813) (xy 419.010931 -68.720114)
			(xy 418.994299 -68.75653) (xy 422.470326 -68.75653) (xy 422.470803 -68.72916) (xy 422.478617 -68.674981)
			(xy 422.494104 -68.622478) (xy 422.516943 -68.572731) (xy 422.546666 -68.526764) (xy 422.564306 -68.505832)
			(xy 422.56456 -68.505578) (xy 422.570169 -68.498507) (xy 422.576401 -68.481578) (xy 422.576752 -68.472558)
			(xy 422.576752 -68.405502) (xy 422.576404 -68.396484) (xy 422.570151 -68.379567) (xy 422.56456 -68.372482)
			(xy 422.564306 -68.372482) (xy 422.564306 -68.372228) (xy 422.546668 -68.351295) (xy 422.516955 -68.305323)
			(xy 422.494119 -68.255575) (xy 422.478628 -68.203075) (xy 422.4708 -68.148899) (xy 422.470326 -68.12153)
			(xy 422.470783 -68.094276) (xy 422.478537 -68.040323) (xy 422.493891 -67.988023) (xy 422.516533 -67.938441)
			(xy 422.546001 -67.892586) (xy 422.581695 -67.851392) (xy 422.622889 -67.815698) (xy 422.668745 -67.786231)
			(xy 422.718327 -67.76359) (xy 422.770627 -67.748236) (xy 422.82458 -67.740483) (xy 422.851834 -67.740022)
			(xy 422.879205 -67.740463) (xy 422.933386 -67.748286) (xy 422.985889 -67.763781) (xy 423.035636 -67.786628)
			(xy 423.081601 -67.816358) (xy 423.102532 -67.834002) (xy 423.102786 -67.834256) (xy 423.109868 -67.83985)
			(xy 423.126788 -67.846091) (xy 423.135806 -67.846448) (xy 423.202862 -67.846448) (xy 423.211878 -67.846084)
			(xy 423.228796 -67.839843) (xy 423.235882 -67.834256) (xy 423.235882 -67.834002) (xy 423.236136 -67.834002)
			(xy 423.257082 -67.81638) (xy 423.303051 -67.786665) (xy 423.352795 -67.763826) (xy 423.405292 -67.748331)
			(xy 423.459466 -67.740498) (xy 423.486834 -67.740022) (xy 423.513149 -67.74046) (xy 423.565279 -67.7477)
			(xy 423.615923 -67.762024) (xy 423.664122 -67.783162) (xy 423.708964 -67.810714) (xy 423.749603 -67.844158)
			(xy 423.767758 -67.863212) (xy 423.775292 -67.870599) (xy 423.794563 -67.879131) (xy 423.805096 -67.879722)
			(xy 423.879772 -67.879722) (xy 423.890321 -67.879185) (xy 423.909615 -67.870654) (xy 423.91711 -67.863212)
			(xy 423.93527 -67.844161) (xy 423.975899 -67.810703) (xy 424.020738 -67.783143) (xy 424.068938 -67.762004)
			(xy 424.119585 -67.747686) (xy 424.171718 -67.740461) (xy 424.198034 -67.740022) (xy 424.225287 -67.740446)
			(xy 424.279239 -67.748208) (xy 424.331537 -67.763569) (xy 424.381116 -67.786216) (xy 424.426968 -67.815689)
			(xy 424.468158 -67.851387) (xy 424.503849 -67.892584) (xy 424.533314 -67.93844) (xy 424.555953 -67.988023)
			(xy 424.571305 -68.040324) (xy 424.579058 -68.094276) (xy 424.579542 -68.12153) (xy 424.579108 -68.148902)
			(xy 424.571284 -68.203083) (xy 424.555789 -68.255587) (xy 424.532939 -68.305333) (xy 424.503207 -68.351298)
			(xy 424.485562 -68.372228) (xy 424.485308 -68.372482) (xy 424.479724 -68.37957) (xy 424.473475 -68.396486)
			(xy 424.473116 -68.405502) (xy 424.473116 -68.472558) (xy 424.47349 -68.481573) (xy 424.479725 -68.49849)
			(xy 424.485308 -68.505578) (xy 424.485562 -68.505578) (xy 424.485562 -68.505832) (xy 424.503177 -68.526784)
			(xy 424.532894 -68.572751) (xy 424.555735 -68.622493) (xy 424.571231 -68.67499) (xy 424.579065 -68.729162)
			(xy 424.579542 -68.75653) (xy 424.57905 -68.78378) (xy 424.57129 -68.837726) (xy 424.555933 -68.890019)
			(xy 424.533291 -68.939594) (xy 424.503825 -68.985442) (xy 424.468134 -69.026631) (xy 424.426946 -69.062322)
			(xy 424.381097 -69.091789) (xy 424.331522 -69.114432) (xy 424.27923 -69.12979) (xy 424.225284 -69.13755)
			(xy 424.198034 -69.138038) (xy 424.171718 -69.137634) (xy 424.119586 -69.130389) (xy 424.068941 -69.116059)
			(xy 424.020742 -69.094915) (xy 423.9759 -69.067356) (xy 423.935264 -69.033906) (xy 423.91711 -69.014848)
			(xy 423.90958 -69.007456) (xy 423.890307 -68.998925) (xy 423.879772 -68.998338) (xy 423.805096 -68.998338)
			(xy 423.794543 -68.99884) (xy 423.775247 -69.007393) (xy 423.767758 -69.014848) (xy 423.749625 -69.033926)
			(xy 423.70899 -69.067379) (xy 423.664144 -69.094934) (xy 423.615939 -69.116068) (xy 423.565288 -69.130381)
			(xy 423.513151 -69.137602) (xy 423.486834 -69.138038) (xy 423.459464 -69.137567) (xy 423.405284 -69.129753)
			(xy 423.352781 -69.114266) (xy 423.303034 -69.091425) (xy 423.257067 -69.0617) (xy 423.236136 -69.044058)
			(xy 423.235882 -69.043804) (xy 423.228804 -69.038204) (xy 423.211881 -69.031965) (xy 423.202862 -69.031612)
			(xy 423.135806 -69.031612) (xy 423.126789 -69.031969) (xy 423.109872 -69.038216) (xy 423.102786 -69.043804)
			(xy 423.102786 -69.044058) (xy 423.102532 -69.044058) (xy 423.081593 -69.061689) (xy 423.035623 -69.091404)
			(xy 422.985877 -69.114242) (xy 422.933378 -69.129734) (xy 422.879203 -69.137564) (xy 422.851834 -69.138038)
			(xy 422.824583 -69.137513) (xy 422.770636 -69.129762) (xy 422.718341 -69.114411) (xy 422.668763 -69.091775)
			(xy 422.622911 -69.062313) (xy 422.581719 -69.026626) (xy 422.546025 -68.98544) (xy 422.516556 -68.939593)
			(xy 422.493911 -68.890019) (xy 422.478552 -68.837726) (xy 422.470791 -68.783781) (xy 422.470326 -68.75653)
			(xy 418.994299 -68.75653) (xy 418.988285 -68.769697) (xy 418.958813 -68.815552) (xy 418.923115 -68.856746)
			(xy 418.881917 -68.89244) (xy 418.836059 -68.921906) (xy 418.786473 -68.944547) (xy 418.73417 -68.959899)
			(xy 418.680215 -68.967651) (xy 418.65296 -68.968112) (xy 418.625591 -68.967608) (xy 418.571414 -68.959799)
			(xy 418.518911 -68.944318) (xy 418.469164 -68.921485) (xy 418.423195 -68.891769) (xy 418.402262 -68.874132)
			(xy 418.402008 -68.873878) (xy 418.394925 -68.868286) (xy 418.378005 -68.862043) (xy 418.368988 -68.861686)
			(xy 418.301932 -68.861686) (xy 418.292917 -68.862061) (xy 418.276 -68.868296) (xy 418.268912 -68.873878)
			(xy 418.268912 -68.874132) (xy 418.268658 -68.874132) (xy 418.247719 -68.891762) (xy 418.201748 -68.921474)
			(xy 418.152002 -68.944312) (xy 418.099503 -68.959805) (xy 418.045329 -68.967636) (xy 418.01796 -68.968112)
			(xy 417.991645 -68.967667) (xy 417.939516 -68.960427) (xy 417.888873 -68.946104) (xy 417.840674 -68.924967)
			(xy 417.795831 -68.897417) (xy 417.755192 -68.863975) (xy 417.737036 -68.844922) (xy 417.7295 -68.837537)
			(xy 417.710231 -68.829003) (xy 417.699698 -68.828412) (xy 417.625022 -68.828412) (xy 417.614472 -68.828936)
			(xy 417.595176 -68.837474) (xy 417.587684 -68.844922) (xy 417.569534 -68.863983) (xy 417.528902 -68.897438)
			(xy 417.484061 -68.924996) (xy 417.435859 -68.946134) (xy 417.385211 -68.96045) (xy 417.333076 -68.967674)
			(xy 417.30676 -68.968112) (xy 417.279508 -68.967659) (xy 417.225559 -68.959898) (xy 417.173264 -68.944538)
			(xy 417.123687 -68.921892) (xy 417.077837 -68.892422) (xy 417.036647 -68.856727) (xy 417.000956 -68.815534)
			(xy 416.971491 -68.769681) (xy 416.94885 -68.720102) (xy 416.933495 -68.667806) (xy 416.925738 -68.613856)
			(xy 416.925252 -68.586604) (xy 408.178573 -68.586604) (xy 405.209387 -71.555864) (xy 419.49446 -71.555864)
			(xy 419.498531 -71.500242) (xy 419.510657 -71.445805) (xy 419.53058 -71.393714) (xy 419.557876 -71.345079)
			(xy 419.591962 -71.300936) (xy 419.632111 -71.262227) (xy 419.677469 -71.229776) (xy 419.727069 -71.204275)
			(xy 419.779853 -71.186268) (xy 419.834696 -71.176138) (xy 419.89043 -71.174101) (xy 419.945867 -71.180201)
			(xy 419.999824 -71.194307) (xy 420.051153 -71.216119) (xy 420.098759 -71.245173) (xy 420.141627 -71.280848)
			(xy 420.178844 -71.322385) (xy 420.209617 -71.368898) (xy 420.233289 -71.419395) (xy 420.249357 -71.472802)
			(xy 420.257477 -71.527978) (xy 420.257986 -71.555864) (xy 420.257477 -71.58375) (xy 420.251638 -71.623428)
			(xy 421.003474 -71.623428) (xy 421.007545 -71.567806) (xy 421.019671 -71.513369) (xy 421.039594 -71.461278)
			(xy 421.06689 -71.412643) (xy 421.100976 -71.3685) (xy 421.141125 -71.329791) (xy 421.186483 -71.29734)
			(xy 421.236083 -71.271839) (xy 421.288867 -71.253832) (xy 421.34371 -71.243702) (xy 421.399444 -71.241665)
			(xy 421.454881 -71.247765) (xy 421.508838 -71.261871) (xy 421.560167 -71.283683) (xy 421.607773 -71.312737)
			(xy 421.650641 -71.348412) (xy 421.687858 -71.389949) (xy 421.718631 -71.436462) (xy 421.742303 -71.486959)
			(xy 421.758371 -71.540366) (xy 421.766491 -71.595542) (xy 421.767 -71.623428) (xy 421.766491 -71.651314)
			(xy 421.758371 -71.70649) (xy 421.742303 -71.759897) (xy 421.718631 -71.810394) (xy 421.687858 -71.856907)
			(xy 421.650641 -71.898444) (xy 421.607773 -71.934119) (xy 421.560167 -71.963173) (xy 421.508838 -71.984985)
			(xy 421.454881 -71.999091) (xy 421.399444 -72.005191) (xy 421.34371 -72.003154) (xy 421.288867 -71.993024)
			(xy 421.236083 -71.975017) (xy 421.186483 -71.949516) (xy 421.141125 -71.917065) (xy 421.100976 -71.878356)
			(xy 421.06689 -71.834213) (xy 421.039594 -71.785578) (xy 421.019671 -71.733487) (xy 421.007545 -71.67905)
			(xy 421.003474 -71.623428) (xy 420.251638 -71.623428) (xy 420.249357 -71.638926) (xy 420.233289 -71.692333)
			(xy 420.209617 -71.74283) (xy 420.178844 -71.789343) (xy 420.141627 -71.83088) (xy 420.098759 -71.866555)
			(xy 420.051153 -71.895609) (xy 419.999824 -71.917421) (xy 419.945867 -71.931527) (xy 419.89043 -71.937627)
			(xy 419.834696 -71.93559) (xy 419.779853 -71.92546) (xy 419.727069 -71.907453) (xy 419.677469 -71.881952)
			(xy 419.632111 -71.849501) (xy 419.591962 -71.810792) (xy 419.557876 -71.766649) (xy 419.53058 -71.718014)
			(xy 419.510657 -71.665923) (xy 419.498531 -71.611486) (xy 419.49446 -71.555864) (xy 405.209387 -71.555864)
			(xy 403.766449 -72.998838) (xy 405.177496 -72.998838) (xy 405.181567 -72.943216) (xy 405.193693 -72.888779)
			(xy 405.213616 -72.836688) (xy 405.240912 -72.788053) (xy 405.274998 -72.74391) (xy 405.315147 -72.705201)
			(xy 405.360505 -72.67275) (xy 405.410105 -72.647249) (xy 405.462889 -72.629242) (xy 405.517732 -72.619112)
			(xy 405.573466 -72.617075) (xy 405.628903 -72.623175) (xy 405.68286 -72.637281) (xy 405.734189 -72.659093)
			(xy 405.781795 -72.688147) (xy 405.824663 -72.723822) (xy 405.86188 -72.765359) (xy 405.892653 -72.811872)
			(xy 405.916325 -72.862369) (xy 405.932393 -72.915776) (xy 405.940513 -72.970952) (xy 405.941022 -72.998838)
			(xy 405.940513 -73.026724) (xy 405.932393 -73.0819) (xy 405.916325 -73.135307) (xy 405.892653 -73.185804)
			(xy 405.86188 -73.232317) (xy 405.824663 -73.273854) (xy 405.781795 -73.309529) (xy 405.734189 -73.338583)
			(xy 405.68286 -73.360395) (xy 405.628903 -73.374501) (xy 405.573466 -73.380601) (xy 405.517732 -73.378564)
			(xy 405.462889 -73.368434) (xy 405.410105 -73.350427) (xy 405.360505 -73.324926) (xy 405.315147 -73.292475)
			(xy 405.274998 -73.253766) (xy 405.240912 -73.209623) (xy 405.213616 -73.160988) (xy 405.193693 -73.108897)
			(xy 405.181567 -73.05446) (xy 405.177496 -72.998838) (xy 403.766449 -72.998838) (xy 402.222168 -74.543158)
			(xy 405.05202 -74.543158) (xy 405.056091 -74.487536) (xy 405.068217 -74.433099) (xy 405.08814 -74.381008)
			(xy 405.115436 -74.332373) (xy 405.149522 -74.28823) (xy 405.189671 -74.249521) (xy 405.235029 -74.21707)
			(xy 405.284629 -74.191569) (xy 405.337413 -74.173562) (xy 405.392256 -74.163432) (xy 405.44799 -74.161395)
			(xy 405.503427 -74.167495) (xy 405.557384 -74.181601) (xy 405.608713 -74.203413) (xy 405.656319 -74.232467)
			(xy 405.699187 -74.268142) (xy 405.736404 -74.309679) (xy 405.767177 -74.356192) (xy 405.790849 -74.406689)
			(xy 405.806917 -74.460096) (xy 405.815037 -74.515272) (xy 405.815546 -74.543158) (xy 405.815037 -74.571044)
			(xy 405.806917 -74.62622) (xy 405.790849 -74.679627) (xy 405.767177 -74.730124) (xy 405.736404 -74.776637)
			(xy 405.699187 -74.818174) (xy 405.656319 -74.853849) (xy 405.608713 -74.882903) (xy 405.557384 -74.904715)
			(xy 405.503427 -74.918821) (xy 405.44799 -74.924921) (xy 405.392256 -74.922884) (xy 405.337413 -74.912754)
			(xy 405.284629 -74.894747) (xy 405.235029 -74.869246) (xy 405.189671 -74.836795) (xy 405.149522 -74.798086)
			(xy 405.115436 -74.753943) (xy 405.08814 -74.705308) (xy 405.068217 -74.653217) (xy 405.056091 -74.59878)
			(xy 405.05202 -74.543158) (xy 402.222168 -74.543158) (xy 400.634454 -76.130912) (xy 400.629628 -76.1365)
			(xy 400.624959 -76.14324) (xy 400.619774 -76.158786) (xy 400.619468 -76.16698) (xy 400.619468 -77.510132)
			(xy 400.619722 -77.514958) (xy 400.619722 -77.515212) (xy 400.62068 -77.521939) (xy 400.625706 -77.534556)
			(xy 400.629628 -77.540104) (xy 400.6342 -77.545438) (xy 401.496784 -78.408022) (xy 401.503125 -78.413918)
			(xy 401.518704 -78.421449) (xy 401.527264 -78.422754) (xy 401.530058 -78.423008) (xy 409.323032 -78.423008)
			(xy 409.333929 -78.423497) (xy 409.353801 -78.432442) (xy 409.361386 -78.44028) (xy 409.36291 -78.442058)
			(xy 409.36672 -78.445868) (xy 409.385516 -78.453996) (xy 423.253662 -78.453996) (xy 423.263727 -78.453561)
			(xy 423.282315 -78.445831) (xy 423.28973 -78.43901) (xy 434.433726 -67.295014) (xy 434.441092 -67.281298)
			(xy 434.442362 -67.273678) (xy 434.449268 -67.238523) (xy 434.470476 -67.170088) (xy 434.499802 -67.104719)
			(xy 434.536815 -67.043374) (xy 434.580972 -66.986953) (xy 434.605938 -66.961258) (xy 434.956458 -66.610738)
			(xy 434.982158 -66.585775) (xy 435.038572 -66.541607) (xy 435.099913 -66.504587) (xy 435.165282 -66.475257)
			(xy 435.233719 -66.454049) (xy 435.268878 -66.447162) (xy 435.276498 -66.445892) (xy 435.290214 -66.438526)
			(xy 435.81701 -65.91173) (xy 435.820442 -65.908112) (xy 435.82594 -65.899792) (xy 435.827932 -65.89522)
			(xy 436.0926 -65.256664) (xy 436.09387 -65.24117) (xy 436.092092 -65.23355) (xy 436.085861 -65.202622)
			(xy 436.079245 -65.139876) (xy 436.078884 -65.108328) (xy 436.079484 -65.06966) (xy 436.0895 -64.992977)
			(xy 436.109418 -64.918251) (xy 436.123588 -64.882268) (xy 436.313072 -64.42456) (xy 436.327289 -64.391649)
			(xy 436.362561 -64.329231) (xy 436.405124 -64.271538) (xy 436.454352 -64.219416) (xy 436.509522 -64.173631)
			(xy 436.539386 -64.153796) (xy 436.558944 -64.130174) (xy 436.562246 -64.1223) (xy 436.554312 -64.087727)
			(xy 436.545779 -64.017306) (xy 436.545228 -63.981838) (xy 436.545857 -63.943161) (xy 436.555947 -63.866468)
			(xy 436.575958 -63.791748) (xy 436.590186 -63.755778) (xy 436.77967 -63.29807) (xy 436.793653 -63.265636)
			(xy 436.828256 -63.204062) (xy 436.869958 -63.147055) (xy 436.918161 -63.09543) (xy 436.972179 -63.049923)
			(xy 437.001412 -63.0301) (xy 437.001666 -63.0301) (xy 437.007928 -63.025577) (xy 437.017612 -63.013552)
			(xy 437.020716 -63.006478) (xy 437.031892 -62.978538) (xy 437.0705 -62.880748) (xy 437.072169 -62.876296)
			(xy 437.073962 -62.86696) (xy 437.074056 -62.862206) (xy 437.074056 -62.760606) (xy 437.073766 -62.752937)
			(xy 437.069122 -62.738319) (xy 437.064912 -62.731904) (xy 437.064912 -62.73165) (xy 437.04495 -62.701908)
			(xy 437.011583 -62.638521) (xy 436.986123 -62.571566) (xy 436.968943 -62.502025) (xy 436.960296 -62.430916)
			(xy 436.959756 -62.3951) (xy 436.959756 -61.899546) (xy 436.960298 -61.863756) (xy 436.96898 -61.792703)
			(xy 436.986174 -61.723218) (xy 437.011628 -61.656316) (xy 437.044971 -61.592975) (xy 437.064912 -61.56325)
			(xy 437.074056 -61.534294) (xy 437.074056 -61.52515) (xy 437.052421 -61.494661) (xy 437.016183 -61.429267)
			(xy 436.988482 -61.359826) (xy 436.969761 -61.287445) (xy 436.960319 -61.213281) (xy 436.959756 -61.1759)
			(xy 436.959756 -60.680346) (xy 436.960298 -60.644556) (xy 436.96898 -60.573503) (xy 436.986174 -60.504018)
			(xy 437.011628 -60.437116) (xy 437.044971 -60.373775) (xy 437.064912 -60.34405) (xy 437.074056 -60.315094)
			(xy 437.074056 -43.20794) (xy 437.074523 -43.174786) (xy 437.081949 -43.108895) (xy 437.0967 -43.044249)
			(xy 437.118591 -42.981659) (xy 437.147348 -42.921911) (xy 437.18261 -42.865756) (xy 437.223933 -42.813899)
			(xy 437.24703 -42.79011) (xy 437.250586 -42.786554) (xy 437.276748 -42.758614) (xy 438.92216 -41.113202)
			(xy 438.929526 -41.099486) (xy 438.930796 -41.091866) (xy 438.937786 -41.056909) (xy 438.959059 -40.988868)
			(xy 438.98837 -40.923883) (xy 439.025294 -40.8629) (xy 439.069293 -40.806808) (xy 439.094118 -40.781224)
			(xy 439.444638 -40.430704) (xy 439.470193 -40.405882) (xy 439.526244 -40.361906) (xy 439.587177 -40.324991)
			(xy 439.652108 -40.295674) (xy 439.720094 -40.274379) (xy 439.755026 -40.267382) (xy 439.781696 -40.253412)
			(xy 439.790586 -40.244522) (xy 439.796935 -40.207896) (xy 439.817645 -40.136505) (xy 439.84715 -40.068276)
			(xy 439.884983 -40.004289) (xy 439.930545 -39.945554) (xy 439.956448 -39.918894) (xy 440.306968 -39.568374)
			(xy 440.332524 -39.543555) (xy 440.388577 -39.499583) (xy 440.449511 -39.462673) (xy 440.514443 -39.433361)
			(xy 440.582429 -39.41207) (xy 440.617356 -39.405052) (xy 440.644026 -39.391082) (xy 440.652916 -39.382192)
			(xy 440.659267 -39.345568) (xy 440.679981 -39.274179) (xy 440.70949 -39.205953) (xy 440.747326 -39.14197)
			(xy 440.792892 -39.08324) (xy 440.818778 -39.056564) (xy 441.169298 -38.706044) (xy 441.194854 -38.681223)
			(xy 441.250905 -38.637247) (xy 441.311838 -38.600332) (xy 441.376769 -38.571013) (xy 441.444754 -38.549716)
			(xy 441.479686 -38.542722) (xy 441.506356 -38.528752) (xy 441.515246 -38.519862) (xy 441.521598 -38.483238)
			(xy 441.542313 -38.411849) (xy 441.571822 -38.343624) (xy 441.609657 -38.27964) (xy 441.655221 -38.220908)
			(xy 441.681108 -38.194234) (xy 441.729622 -38.14572) (xy 441.732162 -38.141402) (xy 441.74639 -38.120017)
			(xy 441.77806 -38.079572) (xy 441.795408 -38.06063) (xy 441.814966 -38.040818) (xy 441.815474 -38.04031)
			(xy 442.122052 -37.733986) (xy 442.148193 -37.708596) (xy 442.205709 -37.663845) (xy 442.268358 -37.626618)
			(xy 442.335161 -37.597497) (xy 442.369956 -37.586666) (xy 442.403484 -37.554662) (xy 442.414135 -37.525439)
			(xy 442.440743 -37.469214) (xy 442.473119 -37.416102) (xy 442.510904 -37.366691) (xy 442.532008 -37.343842)
			(xy 442.537596 -37.33673) (xy 442.554511 -37.311468) (xy 442.592813 -37.26425) (xy 442.61405 -37.242496)
			(xy 442.926978 -36.929568) (xy 442.953682 -36.903623) (xy 443.012538 -36.858021) (xy 443.044326 -36.838636)
			(xy 443.074542 -36.821507) (xy 443.138212 -36.793745) (xy 443.171326 -36.783264) (xy 443.190846 -36.777604)
			(xy 443.230507 -36.768706) (xy 443.250574 -36.765484) (xy 443.250828 -36.765484) (xy 443.2554 -36.764722)
			(xy 443.255908 -36.764722) (xy 443.259718 -36.76396) (xy 443.266176 -36.762375) (xy 443.278011 -36.75632)
			(xy 443.283086 -36.752022) (xy 443.284356 -36.750752) (xy 443.286388 -36.74872) (xy 443.288166 -36.74745)
			(xy 443.305184 -36.730432) (xy 443.310915 -36.724151) (xy 443.318312 -36.708854) (xy 443.319662 -36.70046)
			(xy 443.320678 -36.692332) (xy 443.316868 -36.675314) (xy 443.312042 -36.667694) (xy 443.295148 -36.639952)
			(xy 443.26694 -36.581442) (xy 443.245421 -36.520154) (xy 443.230859 -36.456852) (xy 443.223434 -36.392322)
			(xy 443.222888 -36.359846) (xy 443.222888 -35.915854) (xy 443.223372 -35.882378) (xy 443.231084 -35.815873)
			(xy 443.246378 -35.750691) (xy 443.269051 -35.687696) (xy 443.298804 -35.627719) (xy 443.316614 -35.59937)
			(xy 443.320424 -35.593528) (xy 443.324488 -35.579558) (xy 443.324488 -35.367976) (xy 443.320424 -35.354006)
			(xy 443.316614 -35.348164) (xy 443.298691 -35.319748) (xy 443.268771 -35.259593) (xy 443.245971 -35.196395)
			(xy 443.230594 -35.130993) (xy 443.222845 -35.064256) (xy 443.22238 -35.030664) (xy 443.22238 -34.588704)
			(xy 443.222902 -34.555165) (xy 443.2307 -34.488541) (xy 443.246091 -34.423251) (xy 443.26887 -34.360158)
			(xy 443.298738 -34.300095) (xy 443.316614 -34.271712) (xy 443.316614 -34.271458) (xy 443.31763 -34.270188)
			(xy 443.321948 -34.26333) (xy 443.324488 -34.251646) (xy 443.324488 -34.240216) (xy 443.322964 -34.228278)
			(xy 443.319916 -34.215324) (xy 443.315344 -34.208212) (xy 443.297778 -34.179996) (xy 443.268448 -34.12035)
			(xy 443.246094 -34.057754) (xy 443.231007 -33.993022) (xy 443.223382 -33.926993) (xy 443.222888 -33.89376)
			(xy 443.222888 -33.450784) (xy 443.223384 -33.417666) (xy 443.230964 -33.351865) (xy 443.245966 -33.28735)
			(xy 443.268196 -33.224955) (xy 443.297368 -33.165489) (xy 443.314836 -33.137348) (xy 443.3189 -33.130998)
			(xy 443.322202 -33.119314) (xy 443.323726 -33.111948) (xy 443.324488 -33.104582) (xy 443.324488 -33.096708)
			(xy 443.318646 -33.076642) (xy 443.314836 -33.070292) (xy 443.314582 -33.069784) (xy 443.314582 -33.06953)
			(xy 443.313566 -33.06826) (xy 443.313312 -33.068006) (xy 443.296102 -33.039997) (xy 443.267395 -32.980854)
			(xy 443.245527 -32.918856) (xy 443.230777 -32.854791) (xy 443.223332 -32.789472) (xy 443.222888 -32.756602)
			(xy 443.222888 -32.313118) (xy 443.223517 -32.274817) (xy 443.233589 -32.198878) (xy 443.242954 -32.161734)
			(xy 443.24476 -32.154385) (xy 443.244374 -32.139262) (xy 443.242192 -32.132016) (xy 443.232203 -32.101305)
			(xy 443.218191 -32.038259) (xy 443.211129 -31.974062) (xy 443.210696 -31.94177) (xy 443.210696 -31.446216)
			(xy 443.210989 -31.417198) (xy 443.216585 -31.359434) (xy 443.221872 -31.3309) (xy 443.222888 -31.326074)
			(xy 443.222888 -31.175198) (xy 443.223342 -31.142526) (xy 443.230688 -31.077597) (xy 443.245266 -31.0139)
			(xy 443.255654 -30.98292) (xy 443.258702 -30.965902) (xy 443.254892 -30.946852) (xy 443.240924 -30.911216)
			(xy 443.221261 -30.837243) (xy 443.211329 -30.761349) (xy 443.210696 -30.723078) (xy 443.210696 -30.227016)
			(xy 443.210989 -30.197998) (xy 443.216585 -30.140234) (xy 443.221872 -30.1117) (xy 443.222888 -30.106874)
			(xy 443.222888 -30.038294) (xy 443.223293 -30.008361) (xy 443.229487 -29.948817) (xy 443.241766 -29.890224)
			(xy 443.260002 -29.833204) (xy 443.271656 -29.80563) (xy 443.275974 -29.78531) (xy 443.27064 -29.762958)
			(xy 443.256338 -29.732619) (xy 443.233908 -29.669405) (xy 443.218785 -29.604057) (xy 443.211164 -29.537416)
			(xy 443.210696 -29.503878) (xy 443.210696 -29.007308) (xy 443.211095 -28.978152) (xy 443.216945 -28.920132)
			(xy 443.22238 -28.891484) (xy 443.223142 -28.883102) (xy 443.224657 -28.849921) (xy 443.234283 -28.784199)
			(xy 443.251323 -28.719998) (xy 443.275557 -28.658153) (xy 443.290706 -28.628594) (xy 443.294449 -28.620845)
			(xy 443.297069 -28.603846) (xy 443.293953 -28.586931) (xy 443.289944 -28.579318) (xy 443.271138 -28.545505)
			(xy 443.241507 -28.474034) (xy 443.221456 -28.399306) (xy 443.21133 -28.322601) (xy 443.210696 -28.283916)
			(xy 443.210696 -27.933142) (xy 443.208664 -27.930602) (xy 443.20714 -27.929078) (xy 443.1719 -27.924089)
			(xy 443.102871 -27.906746) (xy 443.036426 -27.881234) (xy 442.973528 -27.847924) (xy 442.915087 -27.807297)
			(xy 442.861952 -27.759943) (xy 442.814891 -27.706547) (xy 442.774587 -27.647884) (xy 442.741624 -27.584803)
			(xy 442.71648 -27.518218) (xy 442.699517 -27.449094) (xy 442.690984 -27.378433) (xy 442.690504 -27.342846)
			(xy 442.690504 -27.342338) (xy 442.690954 -27.310077) (xy 442.69802 -27.245942) (xy 442.712027 -27.182957)
			(xy 442.73281 -27.121873) (xy 442.760121 -27.063415) (xy 442.793636 -27.008279) (xy 442.812932 -26.98242)
			(xy 442.818012 -26.975816) (xy 442.8236 -26.960068) (xy 442.8236 -26.862024) (xy 442.817758 -26.845768)
			(xy 442.812932 -26.839672) (xy 442.793603 -26.813835) (xy 442.760072 -26.758703) (xy 442.732753 -26.700243)
			(xy 442.711972 -26.639153) (xy 442.697977 -26.576161) (xy 442.690934 -26.512018) (xy 442.690504 -26.479754)
			(xy 442.690504 -26.479246) (xy 442.69104 -26.443533) (xy 442.699642 -26.372628) (xy 442.716725 -26.303276)
			(xy 442.742041 -26.236487) (xy 442.775221 -26.173237) (xy 442.815781 -26.114445) (xy 442.863131 -26.06097)
			(xy 442.916579 -26.01359) (xy 442.975347 -25.972996) (xy 443.038579 -25.93978) (xy 443.105353 -25.914426)
			(xy 443.174695 -25.897303) (xy 443.245596 -25.888661) (xy 443.281308 -25.888188) (xy 443.314469 -25.888669)
			(xy 443.380372 -25.896126) (xy 443.445025 -25.910912) (xy 443.507618 -25.932841) (xy 443.567364 -25.961637)
			(xy 443.623511 -25.996938) (xy 443.675355 -26.038302) (xy 443.699138 -26.061416) (xy 443.802008 -26.164286)
			(xy 443.809406 -26.171133) (xy 443.828004 -26.178866) (xy 443.838076 -26.179272) (xy 443.90564 -26.179272)
			(xy 443.938794 -26.179738) (xy 444.004686 -26.187162) (xy 444.069333 -26.201911) (xy 444.131924 -26.223802)
			(xy 444.191673 -26.252558) (xy 444.247829 -26.287819) (xy 444.299687 -26.329142) (xy 444.32347 -26.352246)
			(xy 444.332106 -26.360882) (xy 445.389506 -26.360882) (xy 445.393577 -26.30526) (xy 445.405703 -26.250823)
			(xy 445.425626 -26.198732) (xy 445.452922 -26.150097) (xy 445.487008 -26.105954) (xy 445.527157 -26.067245)
			(xy 445.572515 -26.034794) (xy 445.622115 -26.009293) (xy 445.674899 -25.991286) (xy 445.729742 -25.981156)
			(xy 445.785476 -25.979119) (xy 445.840913 -25.985219) (xy 445.89487 -25.999325) (xy 445.946199 -26.021137)
			(xy 445.993805 -26.050191) (xy 446.036673 -26.085866) (xy 446.07389 -26.127403) (xy 446.104663 -26.173916)
			(xy 446.128335 -26.224413) (xy 446.144403 -26.27782) (xy 446.150571 -26.319734) (xy 451.141844 -26.319734)
			(xy 451.145915 -26.264112) (xy 451.158041 -26.209675) (xy 451.177964 -26.157584) (xy 451.20526 -26.108949)
			(xy 451.239346 -26.064806) (xy 451.279495 -26.026097) (xy 451.324853 -25.993646) (xy 451.374453 -25.968145)
			(xy 451.427237 -25.950138) (xy 451.48208 -25.940008) (xy 451.537814 -25.937971) (xy 451.593251 -25.944071)
			(xy 451.647208 -25.958177) (xy 451.698537 -25.979989) (xy 451.746143 -26.009043) (xy 451.789011 -26.044718)
			(xy 451.826228 -26.086255) (xy 451.857001 -26.132768) (xy 451.880673 -26.183265) (xy 451.896741 -26.236672)
			(xy 451.904861 -26.291848) (xy 451.90537 -26.319734) (xy 451.904861 -26.34762) (xy 451.896741 -26.402796)
			(xy 451.880673 -26.456203) (xy 451.857001 -26.5067) (xy 451.826228 -26.553213) (xy 451.789011 -26.59475)
			(xy 451.746143 -26.630425) (xy 451.698537 -26.659479) (xy 451.647208 -26.681291) (xy 451.593251 -26.695397)
			(xy 451.537814 -26.701497) (xy 451.48208 -26.69946) (xy 451.427237 -26.68933) (xy 451.374453 -26.671323)
			(xy 451.324853 -26.645822) (xy 451.279495 -26.613371) (xy 451.239346 -26.574662) (xy 451.20526 -26.530519)
			(xy 451.177964 -26.481884) (xy 451.158041 -26.429793) (xy 451.145915 -26.375356) (xy 451.141844 -26.319734)
			(xy 446.150571 -26.319734) (xy 446.152523 -26.332996) (xy 446.153032 -26.360882) (xy 446.152523 -26.388768)
			(xy 446.144403 -26.443944) (xy 446.128335 -26.497351) (xy 446.104663 -26.547848) (xy 446.07389 -26.594361)
			(xy 446.036673 -26.635898) (xy 445.993805 -26.671573) (xy 445.946199 -26.700627) (xy 445.89487 -26.722439)
			(xy 445.840913 -26.736545) (xy 445.785476 -26.742645) (xy 445.729742 -26.740608) (xy 445.674899 -26.730478)
			(xy 445.622115 -26.712471) (xy 445.572515 -26.68697) (xy 445.527157 -26.654519) (xy 445.487008 -26.61581)
			(xy 445.452922 -26.571667) (xy 445.425626 -26.523032) (xy 445.405703 -26.470941) (xy 445.393577 -26.416504)
			(xy 445.389506 -26.360882) (xy 444.332106 -26.360882) (xy 444.61557 -26.644346) (xy 444.63868 -26.668125)
			(xy 444.680011 -26.719978) (xy 444.715278 -26.776133) (xy 444.744037 -26.835882) (xy 444.765926 -26.898476)
			(xy 444.780671 -26.963126) (xy 444.781584 -26.971244) (xy 447.150996 -26.971244) (xy 447.155067 -26.915622)
			(xy 447.167193 -26.861185) (xy 447.187116 -26.809094) (xy 447.214412 -26.760459) (xy 447.248498 -26.716316)
			(xy 447.288647 -26.677607) (xy 447.334005 -26.645156) (xy 447.383605 -26.619655) (xy 447.436389 -26.601648)
			(xy 447.491232 -26.591518) (xy 447.546966 -26.589481) (xy 447.602403 -26.595581) (xy 447.65636 -26.609687)
			(xy 447.707689 -26.631499) (xy 447.755295 -26.660553) (xy 447.798163 -26.696228) (xy 447.83538 -26.737765)
			(xy 447.866153 -26.784278) (xy 447.889825 -26.834775) (xy 447.905893 -26.888182) (xy 447.914013 -26.943358)
			(xy 447.914522 -26.971244) (xy 447.914013 -26.99913) (xy 447.905893 -27.054306) (xy 447.889825 -27.107713)
			(xy 447.866153 -27.15821) (xy 447.83538 -27.204723) (xy 447.798163 -27.24626) (xy 447.755295 -27.281935)
			(xy 447.707689 -27.310989) (xy 447.65636 -27.332801) (xy 447.602403 -27.346907) (xy 447.546966 -27.353007)
			(xy 447.491232 -27.35097) (xy 447.436389 -27.34084) (xy 447.383605 -27.322833) (xy 447.334005 -27.297332)
			(xy 447.288647 -27.264881) (xy 447.248498 -27.226172) (xy 447.214412 -27.182029) (xy 447.187116 -27.133394)
			(xy 447.167193 -27.081303) (xy 447.155067 -27.026866) (xy 447.150996 -26.971244) (xy 444.781584 -26.971244)
			(xy 444.788086 -27.029021) (xy 444.788544 -27.062176) (xy 444.788544 -29.114242) (xy 445.147192 -29.114242)
			(xy 445.147192 -28.250642) (xy 445.147682 -28.220658) (xy 445.15551 -28.161202) (xy 445.171031 -28.103277)
			(xy 445.19398 -28.047873) (xy 445.223964 -27.995939) (xy 445.26047 -27.948363) (xy 445.302875 -27.905958)
			(xy 445.350451 -27.869452) (xy 445.402385 -27.839468) (xy 445.457789 -27.816519) (xy 445.515714 -27.800998)
			(xy 445.57517 -27.79317) (xy 445.635138 -27.79317) (xy 445.694594 -27.800998) (xy 445.752519 -27.816519)
			(xy 445.807923 -27.839468) (xy 445.859857 -27.869452) (xy 445.907433 -27.905958) (xy 445.949838 -27.948363)
			(xy 445.986344 -27.995939) (xy 446.016328 -28.047873) (xy 446.039277 -28.103277) (xy 446.054798 -28.161202)
			(xy 446.062626 -28.220658) (xy 446.063116 -28.250642) (xy 446.063116 -28.469082) (xy 450.052438 -28.469082)
			(xy 450.056509 -28.41346) (xy 450.068635 -28.359023) (xy 450.088558 -28.306932) (xy 450.115854 -28.258297)
			(xy 450.14994 -28.214154) (xy 450.190089 -28.175445) (xy 450.235447 -28.142994) (xy 450.285047 -28.117493)
			(xy 450.337831 -28.099486) (xy 450.392674 -28.089356) (xy 450.448408 -28.087319) (xy 450.503845 -28.093419)
			(xy 450.557802 -28.107525) (xy 450.609131 -28.129337) (xy 450.656737 -28.158391) (xy 450.699605 -28.194066)
			(xy 450.736822 -28.235603) (xy 450.767595 -28.282116) (xy 450.791267 -28.332613) (xy 450.807335 -28.38602)
			(xy 450.815455 -28.441196) (xy 450.815964 -28.469082) (xy 450.815455 -28.496968) (xy 450.807335 -28.552144)
			(xy 450.791267 -28.605551) (xy 450.767595 -28.656048) (xy 450.736822 -28.702561) (xy 450.699605 -28.744098)
			(xy 450.656737 -28.779773) (xy 450.609131 -28.808827) (xy 450.557802 -28.830639) (xy 450.503845 -28.844745)
			(xy 450.448408 -28.850845) (xy 450.392674 -28.848808) (xy 450.337831 -28.838678) (xy 450.285047 -28.820671)
			(xy 450.235447 -28.79517) (xy 450.190089 -28.762719) (xy 450.14994 -28.72401) (xy 450.115854 -28.679867)
			(xy 450.088558 -28.631232) (xy 450.068635 -28.579141) (xy 450.056509 -28.524704) (xy 450.052438 -28.469082)
			(xy 446.063116 -28.469082) (xy 446.063116 -29.114242) (xy 446.062626 -29.144226) (xy 446.054798 -29.203682)
			(xy 446.039277 -29.261607) (xy 446.016328 -29.317011) (xy 445.986344 -29.368945) (xy 445.949838 -29.416521)
			(xy 445.907433 -29.458926) (xy 445.859857 -29.495432) (xy 445.807923 -29.525416) (xy 445.752519 -29.548365)
			(xy 445.694594 -29.563886) (xy 445.635138 -29.571714) (xy 445.57517 -29.571714) (xy 445.515714 -29.563886)
			(xy 445.457789 -29.548365) (xy 445.402385 -29.525416) (xy 445.350451 -29.495432) (xy 445.302875 -29.458926)
			(xy 445.26047 -29.416521) (xy 445.223964 -29.368945) (xy 445.19398 -29.317011) (xy 445.171031 -29.261607)
			(xy 445.15551 -29.203682) (xy 445.147682 -29.144226) (xy 445.147192 -29.114242) (xy 444.788544 -29.114242)
			(xy 444.788544 -30.92069) (xy 447.7893 -30.92069) (xy 447.7893 -30.05709) (xy 447.78979 -30.027106)
			(xy 447.797618 -29.96765) (xy 447.813139 -29.909725) (xy 447.836088 -29.854321) (xy 447.866072 -29.802387)
			(xy 447.902578 -29.754811) (xy 447.944983 -29.712406) (xy 447.992559 -29.6759) (xy 448.044493 -29.645916)
			(xy 448.099897 -29.622967) (xy 448.157822 -29.607446) (xy 448.217278 -29.599618) (xy 448.277246 -29.599618)
			(xy 448.336702 -29.607446) (xy 448.394627 -29.622967) (xy 448.450031 -29.645916) (xy 448.501965 -29.6759)
			(xy 448.549541 -29.712406) (xy 448.591946 -29.754811) (xy 448.628452 -29.802387) (xy 448.658436 -29.854321)
			(xy 448.681385 -29.909725) (xy 448.696906 -29.96765) (xy 448.704734 -30.027106) (xy 448.705224 -30.05709)
			(xy 448.705224 -30.92069) (xy 448.704734 -30.950674) (xy 448.696906 -31.01013) (xy 448.681385 -31.068055)
			(xy 448.658436 -31.123459) (xy 448.628452 -31.175393) (xy 448.591946 -31.222969) (xy 448.549541 -31.265374)
			(xy 448.501965 -31.30188) (xy 448.450031 -31.331864) (xy 448.394627 -31.354813) (xy 448.336702 -31.370334)
			(xy 448.277246 -31.378162) (xy 448.217278 -31.378162) (xy 448.157822 -31.370334) (xy 448.099897 -31.354813)
			(xy 448.044493 -31.331864) (xy 447.992559 -31.30188) (xy 447.944983 -31.265374) (xy 447.902578 -31.222969)
			(xy 447.866072 -31.175393) (xy 447.836088 -31.123459) (xy 447.813139 -31.068055) (xy 447.797618 -31.01013)
			(xy 447.78979 -30.950674) (xy 447.7893 -30.92069) (xy 444.788544 -30.92069) (xy 444.788544 -32.714184)
			(xy 445.147192 -32.714184) (xy 445.147192 -31.850584) (xy 445.147682 -31.8206) (xy 445.15551 -31.761144)
			(xy 445.171031 -31.703219) (xy 445.19398 -31.647815) (xy 445.223964 -31.595881) (xy 445.26047 -31.548305)
			(xy 445.302875 -31.5059) (xy 445.350451 -31.469394) (xy 445.402385 -31.43941) (xy 445.457789 -31.416461)
			(xy 445.515714 -31.40094) (xy 445.57517 -31.393112) (xy 445.635138 -31.393112) (xy 445.694594 -31.40094)
			(xy 445.752519 -31.416461) (xy 445.807923 -31.43941) (xy 445.859857 -31.469394) (xy 445.907433 -31.5059)
			(xy 445.949838 -31.548305) (xy 445.986344 -31.595881) (xy 446.016328 -31.647815) (xy 446.039277 -31.703219)
			(xy 446.054798 -31.761144) (xy 446.062626 -31.8206) (xy 446.063116 -31.850584) (xy 446.063116 -32.714184)
			(xy 446.062626 -32.744168) (xy 446.054798 -32.803624) (xy 446.039277 -32.861549) (xy 446.016328 -32.916953)
			(xy 445.986344 -32.968887) (xy 445.949838 -33.016463) (xy 445.907433 -33.058868) (xy 445.859857 -33.095374)
			(xy 445.807923 -33.125358) (xy 445.752519 -33.148307) (xy 445.694594 -33.163828) (xy 445.635138 -33.171656)
			(xy 445.57517 -33.171656) (xy 445.515714 -33.163828) (xy 445.457789 -33.148307) (xy 445.402385 -33.125358)
			(xy 445.350451 -33.095374) (xy 445.302875 -33.058868) (xy 445.26047 -33.016463) (xy 445.223964 -32.968887)
			(xy 445.19398 -32.916953) (xy 445.171031 -32.861549) (xy 445.15551 -32.803624) (xy 445.147682 -32.744168)
			(xy 445.147192 -32.714184) (xy 444.788544 -32.714184) (xy 444.788544 -34.520886) (xy 447.7893 -34.520886)
			(xy 447.7893 -33.657286) (xy 447.78979 -33.627302) (xy 447.797618 -33.567846) (xy 447.813139 -33.509921)
			(xy 447.836088 -33.454517) (xy 447.866072 -33.402583) (xy 447.902578 -33.355007) (xy 447.944983 -33.312602)
			(xy 447.992559 -33.276096) (xy 448.044493 -33.246112) (xy 448.099897 -33.223163) (xy 448.157822 -33.207642)
			(xy 448.217278 -33.199814) (xy 448.277246 -33.199814) (xy 448.336702 -33.207642) (xy 448.394627 -33.223163)
			(xy 448.450031 -33.246112) (xy 448.501965 -33.276096) (xy 448.549541 -33.312602) (xy 448.591946 -33.355007)
			(xy 448.628452 -33.402583) (xy 448.658436 -33.454517) (xy 448.681385 -33.509921) (xy 448.696906 -33.567846)
			(xy 448.704734 -33.627302) (xy 448.705224 -33.657286) (xy 448.705224 -34.520886) (xy 448.704734 -34.55087)
			(xy 448.696906 -34.610326) (xy 448.681385 -34.668251) (xy 448.658436 -34.723655) (xy 448.628452 -34.775589)
			(xy 448.591946 -34.823165) (xy 448.549541 -34.86557) (xy 448.501965 -34.902076) (xy 448.450031 -34.93206)
			(xy 448.394627 -34.955009) (xy 448.336702 -34.97053) (xy 448.277246 -34.978358) (xy 448.217278 -34.978358)
			(xy 448.157822 -34.97053) (xy 448.099897 -34.955009) (xy 448.044493 -34.93206) (xy 447.992559 -34.902076)
			(xy 447.944983 -34.86557) (xy 447.902578 -34.823165) (xy 447.866072 -34.775589) (xy 447.836088 -34.723655)
			(xy 447.813139 -34.668251) (xy 447.797618 -34.610326) (xy 447.78979 -34.55087) (xy 447.7893 -34.520886)
			(xy 444.788544 -34.520886) (xy 444.788544 -37.07384) (xy 444.788078 -37.106994) (xy 444.780655 -37.172886)
			(xy 444.765905 -37.237534) (xy 444.744015 -37.300125) (xy 444.71526 -37.359875) (xy 444.679999 -37.416031)
			(xy 444.638677 -37.46789) (xy 444.61557 -37.49167) (xy 440.838487 -41.268753) (xy 442.14385 -41.268753)
			(xy 442.14385 -41.214247) (xy 442.151607 -41.160296) (xy 442.166963 -41.107997) (xy 442.189605 -41.058417)
			(xy 442.219073 -41.012563) (xy 442.254767 -40.97137) (xy 442.29596 -40.935676) (xy 442.341813 -40.906207)
			(xy 442.391394 -40.883564) (xy 442.443692 -40.868208) (xy 442.497643 -40.86045) (xy 442.524896 -40.859964)
			(xy 442.553634 -40.8605) (xy 442.610461 -40.869121) (xy 442.665351 -40.886169) (xy 442.717063 -40.911257)
			(xy 442.764426 -40.943819) (xy 442.785754 -40.963088) (xy 442.792612 -40.969692) (xy 442.810646 -40.976804)
			(xy 442.899546 -40.976804) (xy 442.91758 -40.969692) (xy 442.924438 -40.963088) (xy 442.945774 -40.943827)
			(xy 442.993133 -40.911258) (xy 443.044842 -40.886163) (xy 443.099731 -40.86911) (xy 443.156557 -40.860485)
			(xy 443.185296 -40.859964) (xy 443.212547 -40.860483) (xy 443.266494 -40.868239) (xy 443.318789 -40.883593)
			(xy 443.368366 -40.906234) (xy 443.414216 -40.9357) (xy 443.455406 -40.971391) (xy 443.491098 -41.012581)
			(xy 443.520564 -41.058431) (xy 443.543205 -41.108007) (xy 443.55856 -41.160302) (xy 443.566317 -41.214249)
			(xy 443.566317 -41.268751) (xy 443.55856 -41.322698) (xy 443.543205 -41.374993) (xy 443.520564 -41.424569)
			(xy 443.491098 -41.470419) (xy 443.455406 -41.511609) (xy 443.414216 -41.5473) (xy 443.368366 -41.576766)
			(xy 443.318789 -41.599407) (xy 443.266494 -41.614761) (xy 443.212547 -41.622517) (xy 443.185296 -41.62298)
			(xy 443.156558 -41.622437) (xy 443.099732 -41.613816) (xy 443.044843 -41.596769) (xy 442.993131 -41.571683)
			(xy 442.945767 -41.539123) (xy 442.924438 -41.519856) (xy 442.91758 -41.513252) (xy 442.899546 -41.50614)
			(xy 442.810646 -41.50614) (xy 442.792612 -41.513252) (xy 442.785754 -41.519856) (xy 442.764428 -41.539128)
			(xy 442.717066 -41.571694) (xy 442.665354 -41.596786) (xy 442.610463 -41.613837) (xy 442.553635 -41.622459)
			(xy 442.524896 -41.62298) (xy 442.497643 -41.62255) (xy 442.443692 -41.614792) (xy 442.391394 -41.599436)
			(xy 442.341813 -41.576793) (xy 442.29596 -41.547324) (xy 442.254767 -41.51163) (xy 442.219073 -41.470437)
			(xy 442.189605 -41.424583) (xy 442.166963 -41.375003) (xy 442.151607 -41.322704) (xy 442.14385 -41.268753)
			(xy 440.838487 -41.268753) (xy 438.802018 -43.305222) (xy 444.607188 -43.305222) (xy 444.60767 -43.277852)
			(xy 444.615484 -43.223674) (xy 444.63097 -43.171171) (xy 444.653808 -43.121424) (xy 444.683529 -43.075456)
			(xy 444.701168 -43.054524) (xy 444.701422 -43.05427) (xy 444.706988 -43.047169) (xy 444.713246 -43.030263)
			(xy 444.713614 -43.02125) (xy 444.713614 -42.954194) (xy 444.713257 -42.945177) (xy 444.707009 -42.92826)
			(xy 444.701422 -42.921174) (xy 444.701168 -42.921174) (xy 444.701168 -42.92092) (xy 444.68352 -42.899995)
			(xy 444.65381 -42.85402) (xy 444.630977 -42.804271) (xy 444.615488 -42.751768) (xy 444.607661 -42.697592)
			(xy 444.607188 -42.670222) (xy 444.607728 -42.641484) (xy 444.616347 -42.584657) (xy 444.633394 -42.529767)
			(xy 444.658482 -42.478055) (xy 444.691043 -42.430691) (xy 444.710312 -42.409364) (xy 444.716916 -42.402506)
			(xy 444.724028 -42.384472) (xy 444.724028 -42.295572) (xy 444.716916 -42.277538) (xy 444.710312 -42.27068)
			(xy 444.691064 -42.249334) (xy 444.658499 -42.201975) (xy 444.633407 -42.150266) (xy 444.616356 -42.095378)
			(xy 444.607731 -42.038554) (xy 444.607729 -41.981078) (xy 444.616348 -41.924253) (xy 444.633395 -41.869364)
			(xy 444.658482 -41.817653) (xy 444.691043 -41.770291) (xy 444.710312 -41.748964) (xy 444.716916 -41.742106)
			(xy 444.724028 -41.724072) (xy 444.724028 -41.635172) (xy 444.716916 -41.617138) (xy 444.710312 -41.61028)
			(xy 444.691047 -41.588948) (xy 444.658481 -41.541587) (xy 444.633388 -41.489876) (xy 444.616336 -41.434987)
			(xy 444.607711 -41.378161) (xy 444.607188 -41.349422) (xy 444.607674 -41.322171) (xy 444.61543 -41.268223)
			(xy 444.630785 -41.215928) (xy 444.653427 -41.166351) (xy 444.682893 -41.120501) (xy 444.718584 -41.07931)
			(xy 444.759775 -41.043619) (xy 444.805625 -41.014153) (xy 444.855202 -40.991511) (xy 444.907497 -40.976156)
			(xy 444.961445 -40.9684) (xy 445.015947 -40.9684) (xy 445.069895 -40.976156) (xy 445.12219 -40.991511)
			(xy 445.171767 -41.014153) (xy 445.217617 -41.043619) (xy 445.258808 -41.07931) (xy 445.294499 -41.120501)
			(xy 445.323965 -41.166351) (xy 445.346607 -41.215928) (xy 445.361962 -41.268223) (xy 445.369718 -41.322171)
			(xy 445.370204 -41.349422) (xy 445.369693 -41.378161) (xy 445.361067 -41.434989) (xy 445.344014 -41.48988)
			(xy 445.31892 -41.541592) (xy 445.286352 -41.588954) (xy 445.26708 -41.61028) (xy 445.260476 -41.617138)
			(xy 445.253364 -41.635172) (xy 445.253364 -41.724072) (xy 445.260476 -41.742106) (xy 445.26708 -41.748964)
			(xy 445.286372 -41.770272) (xy 445.318937 -41.817638) (xy 445.344027 -41.869353) (xy 445.361075 -41.924246)
			(xy 445.369695 -41.981076) (xy 445.369693 -42.038556) (xy 445.361068 -42.095385) (xy 445.344015 -42.150277)
			(xy 445.31892 -42.20199) (xy 445.286352 -42.249353) (xy 445.26708 -42.27068) (xy 445.260476 -42.277538)
			(xy 445.253364 -42.295572) (xy 445.253364 -42.384472) (xy 445.260476 -42.402506) (xy 445.26708 -42.409364)
			(xy 445.286364 -42.430679) (xy 445.318928 -42.478045) (xy 445.344017 -42.52976) (xy 445.361065 -42.584653)
			(xy 445.369685 -42.641482) (xy 445.370204 -42.670222) (xy 445.36975 -42.697593) (xy 445.361929 -42.751772)
			(xy 445.346437 -42.804275) (xy 445.325882 -42.849038) (xy 447.19189 -42.849038) (xy 447.195961 -42.793416)
			(xy 447.208087 -42.738979) (xy 447.22801 -42.686888) (xy 447.255306 -42.638253) (xy 447.289392 -42.59411)
			(xy 447.329541 -42.555401) (xy 447.374899 -42.52295) (xy 447.424499 -42.497449) (xy 447.477283 -42.479442)
			(xy 447.532126 -42.469312) (xy 447.58786 -42.467275) (xy 447.643297 -42.473375) (xy 447.697254 -42.487481)
			(xy 447.748583 -42.509293) (xy 447.796189 -42.538347) (xy 447.839057 -42.574022) (xy 447.876274 -42.615559)
			(xy 447.907047 -42.662072) (xy 447.930719 -42.712569) (xy 447.946787 -42.765976) (xy 447.954907 -42.821152)
			(xy 447.955268 -42.84091) (xy 453.233026 -42.84091) (xy 453.237097 -42.785288) (xy 453.249223 -42.730851)
			(xy 453.269146 -42.67876) (xy 453.296442 -42.630125) (xy 453.330528 -42.585982) (xy 453.370677 -42.547273)
			(xy 453.416035 -42.514822) (xy 453.465635 -42.489321) (xy 453.518419 -42.471314) (xy 453.573262 -42.461184)
			(xy 453.628996 -42.459147) (xy 453.684433 -42.465247) (xy 453.73839 -42.479353) (xy 453.789719 -42.501165)
			(xy 453.837325 -42.530219) (xy 453.880193 -42.565894) (xy 453.91741 -42.607431) (xy 453.948183 -42.653944)
			(xy 453.971855 -42.704441) (xy 453.987923 -42.757848) (xy 453.996043 -42.813024) (xy 453.996552 -42.84091)
			(xy 453.996043 -42.868796) (xy 453.987923 -42.923972) (xy 453.971855 -42.977379) (xy 453.948183 -43.027876)
			(xy 453.91741 -43.074389) (xy 453.880193 -43.115926) (xy 453.837325 -43.151601) (xy 453.789719 -43.180655)
			(xy 453.73839 -43.202467) (xy 453.684433 -43.216573) (xy 453.628996 -43.222673) (xy 453.573262 -43.220636)
			(xy 453.518419 -43.210506) (xy 453.465635 -43.192499) (xy 453.416035 -43.166998) (xy 453.370677 -43.134547)
			(xy 453.330528 -43.095838) (xy 453.296442 -43.051695) (xy 453.269146 -43.00306) (xy 453.249223 -42.950969)
			(xy 453.237097 -42.896532) (xy 453.233026 -42.84091) (xy 447.955268 -42.84091) (xy 447.955416 -42.849038)
			(xy 447.954907 -42.876924) (xy 447.946787 -42.9321) (xy 447.930719 -42.985507) (xy 447.907047 -43.036004)
			(xy 447.876274 -43.082517) (xy 447.839057 -43.124054) (xy 447.796189 -43.159729) (xy 447.748583 -43.188783)
			(xy 447.697254 -43.210595) (xy 447.643297 -43.224701) (xy 447.58786 -43.230801) (xy 447.532126 -43.228764)
			(xy 447.477283 -43.218634) (xy 447.424499 -43.200627) (xy 447.374899 -43.175126) (xy 447.329541 -43.142675)
			(xy 447.289392 -43.103966) (xy 447.255306 -43.059823) (xy 447.22801 -43.011188) (xy 447.208087 -42.959097)
			(xy 447.195961 -42.90466) (xy 447.19189 -42.849038) (xy 445.325882 -42.849038) (xy 445.323593 -42.854022)
			(xy 445.293866 -42.899989) (xy 445.276224 -42.92092) (xy 445.27597 -42.921174) (xy 445.270385 -42.928261)
			(xy 445.264138 -42.945178) (xy 445.263778 -42.954194) (xy 445.263778 -43.02125) (xy 445.264164 -43.030264)
			(xy 445.270392 -43.047181) (xy 445.27597 -43.05427) (xy 445.276224 -43.05427) (xy 445.276224 -43.054524)
			(xy 445.293845 -43.075471) (xy 445.323558 -43.12144) (xy 445.346398 -43.171184) (xy 445.361893 -43.223681)
			(xy 445.369727 -43.277854) (xy 445.370204 -43.305222) (xy 445.369718 -43.332473) (xy 445.361962 -43.386421)
			(xy 445.346607 -43.438716) (xy 445.323965 -43.488293) (xy 445.294499 -43.534143) (xy 445.258808 -43.575334)
			(xy 445.217617 -43.611025) (xy 445.171767 -43.640491) (xy 445.12219 -43.663133) (xy 445.069895 -43.678488)
			(xy 445.015947 -43.686244) (xy 444.961445 -43.686244) (xy 444.907497 -43.678488) (xy 444.855202 -43.663133)
			(xy 444.805625 -43.640491) (xy 444.759775 -43.611025) (xy 444.718584 -43.575334) (xy 444.682893 -43.534143)
			(xy 444.653427 -43.488293) (xy 444.630785 -43.438716) (xy 444.61543 -43.386421) (xy 444.607674 -43.332473)
			(xy 444.607188 -43.305222) (xy 438.802018 -43.305222) (xy 438.559702 -43.547538) (xy 438.552861 -43.554939)
			(xy 438.54514 -43.573537) (xy 438.544716 -43.583606) (xy 438.544716 -43.73626) (xy 446.512948 -43.73626)
			(xy 446.517019 -43.680638) (xy 446.529145 -43.626201) (xy 446.549068 -43.57411) (xy 446.576364 -43.525475)
			(xy 446.61045 -43.481332) (xy 446.650599 -43.442623) (xy 446.695957 -43.410172) (xy 446.745557 -43.384671)
			(xy 446.798341 -43.366664) (xy 446.853184 -43.356534) (xy 446.908918 -43.354497) (xy 446.964355 -43.360597)
			(xy 447.018312 -43.374703) (xy 447.069641 -43.396515) (xy 447.117247 -43.425569) (xy 447.160115 -43.461244)
			(xy 447.197332 -43.502781) (xy 447.228105 -43.549294) (xy 447.236331 -43.566842) (xy 449.633338 -43.566842)
			(xy 449.637409 -43.51122) (xy 449.649535 -43.456783) (xy 449.669458 -43.404692) (xy 449.696754 -43.356057)
			(xy 449.73084 -43.311914) (xy 449.770989 -43.273205) (xy 449.816347 -43.240754) (xy 449.865947 -43.215253)
			(xy 449.918731 -43.197246) (xy 449.973574 -43.187116) (xy 450.029308 -43.185079) (xy 450.084745 -43.191179)
			(xy 450.138702 -43.205285) (xy 450.190031 -43.227097) (xy 450.237637 -43.256151) (xy 450.280505 -43.291826)
			(xy 450.317722 -43.333363) (xy 450.348495 -43.379876) (xy 450.372167 -43.430373) (xy 450.388235 -43.48378)
			(xy 450.396355 -43.538956) (xy 450.396864 -43.566842) (xy 450.396355 -43.594728) (xy 450.388235 -43.649904)
			(xy 450.372167 -43.703311) (xy 450.348495 -43.753808) (xy 450.317722 -43.800321) (xy 450.280505 -43.841858)
			(xy 450.262418 -43.85691) (xy 451.01967 -43.85691) (xy 451.023741 -43.801288) (xy 451.035867 -43.746851)
			(xy 451.05579 -43.69476) (xy 451.083086 -43.646125) (xy 451.117172 -43.601982) (xy 451.157321 -43.563273)
			(xy 451.202679 -43.530822) (xy 451.252279 -43.505321) (xy 451.305063 -43.487314) (xy 451.359906 -43.477184)
			(xy 451.41564 -43.475147) (xy 451.471077 -43.481247) (xy 451.525034 -43.495353) (xy 451.576363 -43.517165)
			(xy 451.623969 -43.546219) (xy 451.666837 -43.581894) (xy 451.704054 -43.623431) (xy 451.734827 -43.669944)
			(xy 451.758499 -43.720441) (xy 451.774567 -43.773848) (xy 451.782687 -43.829024) (xy 451.783196 -43.85691)
			(xy 451.782687 -43.884796) (xy 451.774567 -43.939972) (xy 451.758499 -43.993379) (xy 451.734827 -44.043876)
			(xy 451.704054 -44.090389) (xy 451.666837 -44.131926) (xy 451.623969 -44.167601) (xy 451.576363 -44.196655)
			(xy 451.525034 -44.218467) (xy 451.471077 -44.232573) (xy 451.41564 -44.238673) (xy 451.359906 -44.236636)
			(xy 451.305063 -44.226506) (xy 451.252279 -44.208499) (xy 451.202679 -44.182998) (xy 451.157321 -44.150547)
			(xy 451.117172 -44.111838) (xy 451.083086 -44.067695) (xy 451.05579 -44.01906) (xy 451.035867 -43.966969)
			(xy 451.023741 -43.912532) (xy 451.01967 -43.85691) (xy 450.262418 -43.85691) (xy 450.237637 -43.877533)
			(xy 450.190031 -43.906587) (xy 450.138702 -43.928399) (xy 450.084745 -43.942505) (xy 450.029308 -43.948605)
			(xy 449.973574 -43.946568) (xy 449.918731 -43.936438) (xy 449.865947 -43.918431) (xy 449.816347 -43.89293)
			(xy 449.770989 -43.860479) (xy 449.73084 -43.82177) (xy 449.696754 -43.777627) (xy 449.669458 -43.728992)
			(xy 449.649535 -43.676901) (xy 449.637409 -43.622464) (xy 449.633338 -43.566842) (xy 447.236331 -43.566842)
			(xy 447.251777 -43.599791) (xy 447.267845 -43.653198) (xy 447.275965 -43.708374) (xy 447.276474 -43.73626)
			(xy 447.275965 -43.764146) (xy 447.267845 -43.819322) (xy 447.251777 -43.872729) (xy 447.228105 -43.923226)
			(xy 447.197332 -43.969739) (xy 447.160115 -44.011276) (xy 447.117247 -44.046951) (xy 447.069641 -44.076005)
			(xy 447.018312 -44.097817) (xy 446.964355 -44.111923) (xy 446.908918 -44.118023) (xy 446.853184 -44.115986)
			(xy 446.798341 -44.105856) (xy 446.745557 -44.087849) (xy 446.695957 -44.062348) (xy 446.650599 -44.029897)
			(xy 446.61045 -43.991188) (xy 446.576364 -43.947045) (xy 446.549068 -43.89841) (xy 446.529145 -43.846319)
			(xy 446.517019 -43.791882) (xy 446.512948 -43.73626) (xy 438.544716 -43.73626) (xy 438.544716 -45.114464)
			(xy 446.365374 -45.114464) (xy 446.369445 -45.058842) (xy 446.381571 -45.004405) (xy 446.401494 -44.952314)
			(xy 446.42879 -44.903679) (xy 446.462876 -44.859536) (xy 446.503025 -44.820827) (xy 446.548383 -44.788376)
			(xy 446.597983 -44.762875) (xy 446.650767 -44.744868) (xy 446.70561 -44.734738) (xy 446.761344 -44.732701)
			(xy 446.816781 -44.738801) (xy 446.870738 -44.752907) (xy 446.922067 -44.774719) (xy 446.969673 -44.803773)
			(xy 447.012541 -44.839448) (xy 447.042523 -44.87291) (xy 453.233026 -44.87291) (xy 453.237097 -44.817288)
			(xy 453.249223 -44.762851) (xy 453.269146 -44.71076) (xy 453.296442 -44.662125) (xy 453.330528 -44.617982)
			(xy 453.370677 -44.579273) (xy 453.416035 -44.546822) (xy 453.465635 -44.521321) (xy 453.518419 -44.503314)
			(xy 453.573262 -44.493184) (xy 453.628996 -44.491147) (xy 453.684433 -44.497247) (xy 453.73839 -44.511353)
			(xy 453.789719 -44.533165) (xy 453.837325 -44.562219) (xy 453.880193 -44.597894) (xy 453.91741 -44.639431)
			(xy 453.948183 -44.685944) (xy 453.971855 -44.736441) (xy 453.987923 -44.789848) (xy 453.996043 -44.845024)
			(xy 453.996552 -44.87291) (xy 453.996043 -44.900796) (xy 453.987923 -44.955972) (xy 453.971855 -45.009379)
			(xy 453.948183 -45.059876) (xy 453.91741 -45.106389) (xy 453.880193 -45.147926) (xy 453.837325 -45.183601)
			(xy 453.789719 -45.212655) (xy 453.73839 -45.234467) (xy 453.684433 -45.248573) (xy 453.628996 -45.254673)
			(xy 453.573262 -45.252636) (xy 453.518419 -45.242506) (xy 453.465635 -45.224499) (xy 453.416035 -45.198998)
			(xy 453.370677 -45.166547) (xy 453.330528 -45.127838) (xy 453.296442 -45.083695) (xy 453.269146 -45.03506)
			(xy 453.249223 -44.982969) (xy 453.237097 -44.928532) (xy 453.233026 -44.87291) (xy 447.042523 -44.87291)
			(xy 447.049758 -44.880985) (xy 447.080531 -44.927498) (xy 447.104203 -44.977995) (xy 447.120271 -45.031402)
			(xy 447.128391 -45.086578) (xy 447.1289 -45.114464) (xy 447.128391 -45.14235) (xy 447.120271 -45.197526)
			(xy 447.104203 -45.250933) (xy 447.080531 -45.30143) (xy 447.049758 -45.347943) (xy 447.044116 -45.35424)
			(xy 451.003668 -45.35424) (xy 451.007739 -45.298618) (xy 451.019865 -45.244181) (xy 451.039788 -45.19209)
			(xy 451.067084 -45.143455) (xy 451.10117 -45.099312) (xy 451.141319 -45.060603) (xy 451.186677 -45.028152)
			(xy 451.236277 -45.002651) (xy 451.289061 -44.984644) (xy 451.343904 -44.974514) (xy 451.399638 -44.972477)
			(xy 451.455075 -44.978577) (xy 451.509032 -44.992683) (xy 451.560361 -45.014495) (xy 451.607967 -45.043549)
			(xy 451.650835 -45.079224) (xy 451.688052 -45.120761) (xy 451.718825 -45.167274) (xy 451.742497 -45.217771)
			(xy 451.758565 -45.271178) (xy 451.766685 -45.326354) (xy 451.767194 -45.35424) (xy 451.766685 -45.382126)
			(xy 451.758565 -45.437302) (xy 451.742497 -45.490709) (xy 451.718825 -45.541206) (xy 451.688052 -45.587719)
			(xy 451.650835 -45.629256) (xy 451.607967 -45.664931) (xy 451.560361 -45.693985) (xy 451.509032 -45.715797)
			(xy 451.455075 -45.729903) (xy 451.399638 -45.736003) (xy 451.343904 -45.733966) (xy 451.289061 -45.723836)
			(xy 451.236277 -45.705829) (xy 451.186677 -45.680328) (xy 451.141319 -45.647877) (xy 451.10117 -45.609168)
			(xy 451.067084 -45.565025) (xy 451.039788 -45.51639) (xy 451.019865 -45.464299) (xy 451.007739 -45.409862)
			(xy 451.003668 -45.35424) (xy 447.044116 -45.35424) (xy 447.012541 -45.38948) (xy 446.969673 -45.425155)
			(xy 446.922067 -45.454209) (xy 446.870738 -45.476021) (xy 446.816781 -45.490127) (xy 446.761344 -45.496227)
			(xy 446.70561 -45.49419) (xy 446.650767 -45.48406) (xy 446.597983 -45.466053) (xy 446.548383 -45.440552)
			(xy 446.503025 -45.408101) (xy 446.462876 -45.369392) (xy 446.42879 -45.325249) (xy 446.401494 -45.276614)
			(xy 446.381571 -45.224523) (xy 446.369445 -45.170086) (xy 446.365374 -45.114464) (xy 438.544716 -45.114464)
			(xy 438.544716 -46.082204) (xy 444.352426 -46.082204) (xy 444.352859 -46.05495) (xy 444.360616 -46.000996)
			(xy 444.375974 -45.948695) (xy 444.398618 -45.899113) (xy 444.428089 -45.853258) (xy 444.463786 -45.812065)
			(xy 444.504982 -45.776371) (xy 444.550839 -45.746904) (xy 444.600424 -45.724263) (xy 444.652725 -45.70891)
			(xy 444.70668 -45.701157) (xy 444.733934 -45.700696) (xy 444.760837 -45.701132) (xy 444.814109 -45.708709)
			(xy 444.865787 -45.723693) (xy 444.914849 -45.745787) (xy 444.960321 -45.774553) (xy 445.001302 -45.809422)
			(xy 445.036979 -45.849701) (xy 445.052196 -45.871892) (xy 445.059308 -45.882814) (xy 445.082168 -45.894752)
			(xy 445.194436 -45.89272) (xy 445.216788 -45.879766) (xy 445.223646 -45.86859) (xy 445.23855 -45.844977)
			(xy 445.274232 -45.802025) (xy 445.315793 -45.764733) (xy 445.362346 -45.733897) (xy 445.412896 -45.710175)
			(xy 445.466364 -45.694075) (xy 445.521608 -45.68594) (xy 445.549528 -45.685456) (xy 445.576522 -45.685901)
			(xy 445.629971 -45.693511) (xy 445.681814 -45.708575) (xy 445.731019 -45.730792) (xy 445.776602 -45.75972)
			(xy 445.797432 -45.776896) (xy 445.80556 -45.784008) (xy 445.826134 -45.790104) (xy 445.911478 -45.779182)
			(xy 445.922022 -45.777407) (xy 445.940305 -45.766353) (xy 445.946784 -45.757846) (xy 445.962154 -45.736628)
			(xy 445.997738 -45.698175) (xy 446.038252 -45.664955) (xy 446.082933 -45.637595) (xy 446.130938 -45.616609)
			(xy 446.181364 -45.602394) (xy 446.233262 -45.595215) (xy 446.259458 -45.594778) (xy 446.286712 -45.595266)
			(xy 446.340665 -45.603018) (xy 446.392966 -45.61837) (xy 446.44255 -45.641009) (xy 446.488407 -45.670475)
			(xy 446.529603 -45.706168) (xy 446.5653 -45.74736) (xy 446.59477 -45.793213) (xy 446.617415 -45.842794)
			(xy 446.632773 -45.895094) (xy 446.640531 -45.949046) (xy 446.640531 -46.003554) (xy 446.632773 -46.057506)
			(xy 446.617415 -46.109806) (xy 446.59477 -46.159387) (xy 446.5653 -46.20524) (xy 446.529603 -46.246432)
			(xy 446.488407 -46.282125) (xy 446.44255 -46.311591) (xy 446.392966 -46.33423) (xy 446.340665 -46.349582)
			(xy 446.286712 -46.357334) (xy 446.259458 -46.357794) (xy 446.232464 -46.357345) (xy 446.179016 -46.349735)
			(xy 446.127173 -46.334671) (xy 446.077969 -46.312454) (xy 446.032385 -46.283528) (xy 446.011554 -46.266354)
			(xy 446.003426 -46.259242) (xy 445.982852 -46.253146) (xy 445.897508 -46.264068) (xy 445.886967 -46.265854)
			(xy 445.868684 -46.276901) (xy 445.862202 -46.285404) (xy 445.844586 -46.309702) (xy 445.802992 -46.352963)
			(xy 445.779398 -46.37151) (xy 445.771524 -46.377352) (xy 445.76111 -46.394878) (xy 445.747902 -46.485302)
			(xy 445.752728 -46.504606) (xy 445.75857 -46.51248) (xy 445.75857 -46.512734) (xy 445.776072 -46.537479)
			(xy 445.803875 -46.591331) (xy 445.822812 -46.648903) (xy 445.830015 -46.693836) (xy 450.976238 -46.693836)
			(xy 450.976724 -46.666585) (xy 450.98448 -46.612637) (xy 450.999835 -46.560342) (xy 451.022477 -46.510765)
			(xy 451.051943 -46.464915) (xy 451.087634 -46.423724) (xy 451.128825 -46.388033) (xy 451.174675 -46.358567)
			(xy 451.224252 -46.335925) (xy 451.276547 -46.32057) (xy 451.330495 -46.312814) (xy 451.384997 -46.312814)
			(xy 451.438945 -46.32057) (xy 451.49124 -46.335925) (xy 451.540817 -46.358567) (xy 451.586667 -46.388033)
			(xy 451.627858 -46.423724) (xy 451.663549 -46.464915) (xy 451.693015 -46.510765) (xy 451.715657 -46.560342)
			(xy 451.731012 -46.612637) (xy 451.738768 -46.666585) (xy 451.739254 -46.693836) (xy 451.738788 -46.720264)
			(xy 451.731477 -46.772612) (xy 451.717002 -46.823447) (xy 451.69564 -46.871793) (xy 451.682104 -46.894496)
			(xy 451.68185 -46.89475) (xy 451.676513 -46.904768) (xy 451.674256 -46.927318) (xy 451.677532 -46.938184)
			(xy 451.703694 -47.01286) (xy 451.708059 -47.023385) (xy 451.724161 -47.03947) (xy 451.734682 -47.043848)
			(xy 451.734936 -47.043848) (xy 451.759443 -47.052923) (xy 451.805895 -47.076865) (xy 451.848648 -47.106919)
			(xy 451.8869 -47.142526) (xy 451.919937 -47.183018) (xy 451.947141 -47.227638) (xy 451.968003 -47.275553)
			(xy 451.982133 -47.325866) (xy 451.989267 -47.377636) (xy 451.989698 -47.403766) (xy 451.989212 -47.431017)
			(xy 451.987689 -47.441612) (xy 453.261728 -47.441612) (xy 453.265799 -47.38599) (xy 453.277925 -47.331553)
			(xy 453.297848 -47.279462) (xy 453.325144 -47.230827) (xy 453.35923 -47.186684) (xy 453.399379 -47.147975)
			(xy 453.444737 -47.115524) (xy 453.494337 -47.090023) (xy 453.547121 -47.072016) (xy 453.601964 -47.061886)
			(xy 453.657698 -47.059849) (xy 453.713135 -47.065949) (xy 453.767092 -47.080055) (xy 453.818421 -47.101867)
			(xy 453.866027 -47.130921) (xy 453.908895 -47.166596) (xy 453.946112 -47.208133) (xy 453.976885 -47.254646)
			(xy 454.000557 -47.305143) (xy 454.016625 -47.35855) (xy 454.024745 -47.413726) (xy 454.025254 -47.441612)
			(xy 454.024745 -47.469498) (xy 454.016625 -47.524674) (xy 454.000557 -47.578081) (xy 453.976885 -47.628578)
			(xy 453.946112 -47.675091) (xy 453.908895 -47.716628) (xy 453.866027 -47.752303) (xy 453.818421 -47.781357)
			(xy 453.767092 -47.803169) (xy 453.713135 -47.817275) (xy 453.657698 -47.823375) (xy 453.601964 -47.821338)
			(xy 453.547121 -47.811208) (xy 453.494337 -47.793201) (xy 453.444737 -47.7677) (xy 453.399379 -47.735249)
			(xy 453.35923 -47.69654) (xy 453.325144 -47.652397) (xy 453.297848 -47.603762) (xy 453.277925 -47.551671)
			(xy 453.265799 -47.497234) (xy 453.261728 -47.441612) (xy 451.987689 -47.441612) (xy 451.981456 -47.484965)
			(xy 451.966101 -47.53726) (xy 451.943459 -47.586837) (xy 451.913993 -47.632687) (xy 451.878302 -47.673878)
			(xy 451.837111 -47.709569) (xy 451.791261 -47.739035) (xy 451.741684 -47.761677) (xy 451.689389 -47.777032)
			(xy 451.635441 -47.784788) (xy 451.580939 -47.784788) (xy 451.526991 -47.777032) (xy 451.474696 -47.761677)
			(xy 451.425119 -47.739035) (xy 451.379269 -47.709569) (xy 451.338078 -47.673878) (xy 451.302387 -47.632687)
			(xy 451.272921 -47.586837) (xy 451.250279 -47.53726) (xy 451.234924 -47.484965) (xy 451.227168 -47.431017)
			(xy 451.226682 -47.403766) (xy 451.227158 -47.377339) (xy 451.234467 -47.324991) (xy 451.248939 -47.274157)
			(xy 451.270298 -47.225809) (xy 451.283832 -47.203106) (xy 451.284086 -47.202852) (xy 451.289421 -47.192834)
			(xy 451.291678 -47.170284) (xy 451.288404 -47.159418) (xy 451.262242 -47.084742) (xy 451.25786 -47.074226)
			(xy 451.24177 -47.058137) (xy 451.231254 -47.053754) (xy 451.231 -47.053754) (xy 451.206502 -47.044657)
			(xy 451.160048 -47.02072) (xy 451.117295 -46.990669) (xy 451.079041 -46.955066) (xy 451.046003 -46.914576)
			(xy 451.018798 -46.869958) (xy 450.997935 -46.822045) (xy 450.983804 -46.771734) (xy 450.976669 -46.719965)
			(xy 450.976238 -46.693836) (xy 445.830015 -46.693836) (xy 445.832405 -46.708745) (xy 445.832992 -46.739048)
			(xy 445.832567 -46.766301) (xy 445.824803 -46.820252) (xy 445.809441 -46.872549) (xy 445.786793 -46.922127)
			(xy 445.757321 -46.967978) (xy 445.721623 -47.009168) (xy 445.680427 -47.044859) (xy 445.634571 -47.074324)
			(xy 445.584989 -47.096964) (xy 445.532689 -47.112317) (xy 445.478737 -47.120071) (xy 445.451484 -47.120556)
			(xy 445.42545 -47.120111) (xy 445.373868 -47.113022) (xy 445.323726 -47.098992) (xy 445.275955 -47.078281)
			(xy 445.23144 -47.051272) (xy 445.210946 -47.035212) (xy 445.203182 -47.029481) (xy 445.184777 -47.023734)
			(xy 445.175132 -47.024036) (xy 445.095376 -47.030386) (xy 445.077596 -47.039022) (xy 445.071246 -47.046388)
			(xy 445.053065 -47.066034) (xy 445.012157 -47.100556) (xy 444.966828 -47.129025) (xy 444.917967 -47.150882)
			(xy 444.866531 -47.1657) (xy 444.81353 -47.173187) (xy 444.786766 -47.173642) (xy 444.759515 -47.173154)
			(xy 444.70557 -47.165394) (xy 444.653277 -47.150036) (xy 444.603702 -47.127393) (xy 444.557853 -47.097927)
			(xy 444.516664 -47.062236) (xy 444.480973 -47.021047) (xy 444.451507 -46.975198) (xy 444.428864 -46.925623)
			(xy 444.413506 -46.87333) (xy 444.405746 -46.819385) (xy 444.405258 -46.792134) (xy 444.405794 -46.763361)
			(xy 444.414444 -46.706467) (xy 444.431538 -46.651517) (xy 444.456689 -46.599757) (xy 444.489326 -46.55236)
			(xy 444.508636 -46.531022) (xy 444.516002 -46.523148) (xy 444.523114 -46.503336) (xy 444.515748 -46.40707)
			(xy 444.505842 -46.388274) (xy 444.49746 -46.38167) (xy 444.475284 -46.363435) (xy 444.436071 -46.321503)
			(xy 444.403583 -46.27417) (xy 444.378553 -46.222504) (xy 444.361546 -46.167671) (xy 444.352944 -46.110909)
			(xy 444.352426 -46.082204) (xy 438.544716 -46.082204) (xy 438.544716 -48.30699) (xy 450.853808 -48.30699)
			(xy 450.857879 -48.251368) (xy 450.870005 -48.196931) (xy 450.889928 -48.14484) (xy 450.917224 -48.096205)
			(xy 450.95131 -48.052062) (xy 450.991459 -48.013353) (xy 451.036817 -47.980902) (xy 451.086417 -47.955401)
			(xy 451.139201 -47.937394) (xy 451.194044 -47.927264) (xy 451.249778 -47.925227) (xy 451.305215 -47.931327)
			(xy 451.359172 -47.945433) (xy 451.410501 -47.967245) (xy 451.458107 -47.996299) (xy 451.500975 -48.031974)
			(xy 451.538192 -48.073511) (xy 451.568965 -48.120024) (xy 451.592637 -48.170521) (xy 451.608705 -48.223928)
			(xy 451.616825 -48.279104) (xy 451.617334 -48.30699) (xy 451.616825 -48.334876) (xy 451.608705 -48.390052)
			(xy 451.592637 -48.443459) (xy 451.568965 -48.493956) (xy 451.538192 -48.540469) (xy 451.500975 -48.582006)
			(xy 451.458107 -48.617681) (xy 451.410501 -48.646735) (xy 451.359172 -48.668547) (xy 451.305215 -48.682653)
			(xy 451.249778 -48.688753) (xy 451.194044 -48.686716) (xy 451.139201 -48.676586) (xy 451.086417 -48.658579)
			(xy 451.036817 -48.633078) (xy 450.991459 -48.600627) (xy 450.95131 -48.561918) (xy 450.917224 -48.517775)
			(xy 450.889928 -48.46914) (xy 450.870005 -48.417049) (xy 450.857879 -48.362612) (xy 450.853808 -48.30699)
			(xy 438.544716 -48.30699) (xy 438.544716 -48.753014) (xy 447.468242 -48.753014) (xy 447.472313 -48.697392)
			(xy 447.484439 -48.642955) (xy 447.504362 -48.590864) (xy 447.531658 -48.542229) (xy 447.565744 -48.498086)
			(xy 447.605893 -48.459377) (xy 447.651251 -48.426926) (xy 447.700851 -48.401425) (xy 447.753635 -48.383418)
			(xy 447.808478 -48.373288) (xy 447.864212 -48.371251) (xy 447.919649 -48.377351) (xy 447.973606 -48.391457)
			(xy 448.024935 -48.413269) (xy 448.072541 -48.442323) (xy 448.115409 -48.477998) (xy 448.152626 -48.519535)
			(xy 448.183399 -48.566048) (xy 448.207071 -48.616545) (xy 448.223139 -48.669952) (xy 448.231259 -48.725128)
			(xy 448.231768 -48.753014) (xy 448.231259 -48.7809) (xy 448.223139 -48.836076) (xy 448.220695 -48.8442)
			(xy 448.48729 -48.8442) (xy 448.491361 -48.788578) (xy 448.503487 -48.734141) (xy 448.52341 -48.68205)
			(xy 448.550706 -48.633415) (xy 448.584792 -48.589272) (xy 448.624941 -48.550563) (xy 448.670299 -48.518112)
			(xy 448.719899 -48.492611) (xy 448.772683 -48.474604) (xy 448.827526 -48.464474) (xy 448.88326 -48.462437)
			(xy 448.938697 -48.468537) (xy 448.992654 -48.482643) (xy 449.043983 -48.504455) (xy 449.091589 -48.533509)
			(xy 449.134457 -48.569184) (xy 449.171674 -48.610721) (xy 449.202447 -48.657234) (xy 449.226119 -48.707731)
			(xy 449.242187 -48.761138) (xy 449.250307 -48.816314) (xy 449.250816 -48.8442) (xy 449.250307 -48.872086)
			(xy 449.247309 -48.89246) (xy 449.513958 -48.89246) (xy 449.518029 -48.836838) (xy 449.530155 -48.782401)
			(xy 449.550078 -48.73031) (xy 449.577374 -48.681675) (xy 449.61146 -48.637532) (xy 449.651609 -48.598823)
			(xy 449.696967 -48.566372) (xy 449.746567 -48.540871) (xy 449.799351 -48.522864) (xy 449.854194 -48.512734)
			(xy 449.909928 -48.510697) (xy 449.965365 -48.516797) (xy 450.019322 -48.530903) (xy 450.070651 -48.552715)
			(xy 450.118257 -48.581769) (xy 450.161125 -48.617444) (xy 450.198342 -48.658981) (xy 450.229115 -48.705494)
			(xy 450.252787 -48.755991) (xy 450.268855 -48.809398) (xy 450.276975 -48.864574) (xy 450.277484 -48.89246)
			(xy 450.276975 -48.920346) (xy 450.274537 -48.93691) (xy 453.205848 -48.93691) (xy 453.209919 -48.881288)
			(xy 453.222045 -48.826851) (xy 453.241968 -48.77476) (xy 453.269264 -48.726125) (xy 453.30335 -48.681982)
			(xy 453.343499 -48.643273) (xy 453.388857 -48.610822) (xy 453.438457 -48.585321) (xy 453.491241 -48.567314)
			(xy 453.546084 -48.557184) (xy 453.601818 -48.555147) (xy 453.657255 -48.561247) (xy 453.711212 -48.575353)
			(xy 453.762541 -48.597165) (xy 453.810147 -48.626219) (xy 453.853015 -48.661894) (xy 453.890232 -48.703431)
			(xy 453.921005 -48.749944) (xy 453.944677 -48.800441) (xy 453.960745 -48.853848) (xy 453.968865 -48.909024)
			(xy 453.969374 -48.93691) (xy 453.968865 -48.964796) (xy 453.960745 -49.019972) (xy 453.944677 -49.073379)
			(xy 453.921005 -49.123876) (xy 453.890232 -49.170389) (xy 453.853015 -49.211926) (xy 453.810147 -49.247601)
			(xy 453.762541 -49.276655) (xy 453.711212 -49.298467) (xy 453.657255 -49.312573) (xy 453.601818 -49.318673)
			(xy 453.546084 -49.316636) (xy 453.491241 -49.306506) (xy 453.438457 -49.288499) (xy 453.388857 -49.262998)
			(xy 453.343499 -49.230547) (xy 453.30335 -49.191838) (xy 453.269264 -49.147695) (xy 453.241968 -49.09906)
			(xy 453.222045 -49.046969) (xy 453.209919 -48.992532) (xy 453.205848 -48.93691) (xy 450.274537 -48.93691)
			(xy 450.268855 -48.975522) (xy 450.252787 -49.028929) (xy 450.229115 -49.079426) (xy 450.198342 -49.125939)
			(xy 450.161125 -49.167476) (xy 450.118257 -49.203151) (xy 450.070651 -49.232205) (xy 450.019322 -49.254017)
			(xy 449.965365 -49.268123) (xy 449.909928 -49.274223) (xy 449.854194 -49.272186) (xy 449.799351 -49.262056)
			(xy 449.746567 -49.244049) (xy 449.696967 -49.218548) (xy 449.651609 -49.186097) (xy 449.61146 -49.147388)
			(xy 449.577374 -49.103245) (xy 449.550078 -49.05461) (xy 449.530155 -49.002519) (xy 449.518029 -48.948082)
			(xy 449.513958 -48.89246) (xy 449.247309 -48.89246) (xy 449.242187 -48.927262) (xy 449.226119 -48.980669)
			(xy 449.202447 -49.031166) (xy 449.171674 -49.077679) (xy 449.134457 -49.119216) (xy 449.091589 -49.154891)
			(xy 449.043983 -49.183945) (xy 448.992654 -49.205757) (xy 448.938697 -49.219863) (xy 448.88326 -49.225963)
			(xy 448.827526 -49.223926) (xy 448.772683 -49.213796) (xy 448.719899 -49.195789) (xy 448.670299 -49.170288)
			(xy 448.624941 -49.137837) (xy 448.584792 -49.099128) (xy 448.550706 -49.054985) (xy 448.52341 -49.00635)
			(xy 448.503487 -48.954259) (xy 448.491361 -48.899822) (xy 448.48729 -48.8442) (xy 448.220695 -48.8442)
			(xy 448.207071 -48.889483) (xy 448.183399 -48.93998) (xy 448.152626 -48.986493) (xy 448.115409 -49.02803)
			(xy 448.072541 -49.063705) (xy 448.024935 -49.092759) (xy 447.973606 -49.114571) (xy 447.919649 -49.128677)
			(xy 447.864212 -49.134777) (xy 447.808478 -49.13274) (xy 447.753635 -49.12261) (xy 447.700851 -49.104603)
			(xy 447.651251 -49.079102) (xy 447.605893 -49.046651) (xy 447.565744 -49.007942) (xy 447.531658 -48.963799)
			(xy 447.504362 -48.915164) (xy 447.484439 -48.863073) (xy 447.472313 -48.808636) (xy 447.468242 -48.753014)
			(xy 438.544716 -48.753014) (xy 438.544716 -49.95291) (xy 453.233026 -49.95291) (xy 453.237097 -49.897288)
			(xy 453.249223 -49.842851) (xy 453.269146 -49.79076) (xy 453.296442 -49.742125) (xy 453.330528 -49.697982)
			(xy 453.370677 -49.659273) (xy 453.416035 -49.626822) (xy 453.465635 -49.601321) (xy 453.518419 -49.583314)
			(xy 453.573262 -49.573184) (xy 453.628996 -49.571147) (xy 453.684433 -49.577247) (xy 453.73839 -49.591353)
			(xy 453.789719 -49.613165) (xy 453.837325 -49.642219) (xy 453.880193 -49.677894) (xy 453.91741 -49.719431)
			(xy 453.948183 -49.765944) (xy 453.971855 -49.816441) (xy 453.987923 -49.869848) (xy 453.996043 -49.925024)
			(xy 453.996552 -49.95291) (xy 453.996043 -49.980796) (xy 453.987923 -50.035972) (xy 453.971855 -50.089379)
			(xy 453.948183 -50.139876) (xy 453.91741 -50.186389) (xy 453.880193 -50.227926) (xy 453.837325 -50.263601)
			(xy 453.789719 -50.292655) (xy 453.73839 -50.314467) (xy 453.684433 -50.328573) (xy 453.628996 -50.334673)
			(xy 453.573262 -50.332636) (xy 453.518419 -50.322506) (xy 453.465635 -50.304499) (xy 453.416035 -50.278998)
			(xy 453.370677 -50.246547) (xy 453.330528 -50.207838) (xy 453.296442 -50.163695) (xy 453.269146 -50.11506)
			(xy 453.249223 -50.062969) (xy 453.237097 -50.008532) (xy 453.233026 -49.95291) (xy 438.544716 -49.95291)
			(xy 438.544716 -50.107342) (xy 438.599519 -51.019456) (xy 451.049388 -51.019456) (xy 451.053459 -50.963834)
			(xy 451.065585 -50.909397) (xy 451.085508 -50.857306) (xy 451.112804 -50.808671) (xy 451.14689 -50.764528)
			(xy 451.187039 -50.725819) (xy 451.232397 -50.693368) (xy 451.281997 -50.667867) (xy 451.334781 -50.64986)
			(xy 451.389624 -50.63973) (xy 451.445358 -50.637693) (xy 451.500795 -50.643793) (xy 451.554752 -50.657899)
			(xy 451.606081 -50.679711) (xy 451.653687 -50.708765) (xy 451.696555 -50.74444) (xy 451.733772 -50.785977)
			(xy 451.764545 -50.83249) (xy 451.788217 -50.882987) (xy 451.804285 -50.936394) (xy 451.812405 -50.99157)
			(xy 451.812914 -51.019456) (xy 451.812405 -51.047342) (xy 451.804285 -51.102518) (xy 451.788217 -51.155925)
			(xy 451.764545 -51.206422) (xy 451.733772 -51.252935) (xy 451.696555 -51.294472) (xy 451.653687 -51.330147)
			(xy 451.606081 -51.359201) (xy 451.554752 -51.381013) (xy 451.500795 -51.395119) (xy 451.445358 -51.401219)
			(xy 451.389624 -51.399182) (xy 451.334781 -51.389052) (xy 451.281997 -51.371045) (xy 451.232397 -51.345544)
			(xy 451.187039 -51.313093) (xy 451.14689 -51.274384) (xy 451.112804 -51.230241) (xy 451.085508 -51.181606)
			(xy 451.065585 -51.129515) (xy 451.053459 -51.075078) (xy 451.049388 -51.019456) (xy 438.599519 -51.019456)
			(xy 438.660564 -52.035456) (xy 453.241154 -52.035456) (xy 453.245225 -51.979834) (xy 453.257351 -51.925397)
			(xy 453.277274 -51.873306) (xy 453.30457 -51.824671) (xy 453.338656 -51.780528) (xy 453.378805 -51.741819)
			(xy 453.424163 -51.709368) (xy 453.473763 -51.683867) (xy 453.526547 -51.66586) (xy 453.58139 -51.65573)
			(xy 453.637124 -51.653693) (xy 453.692561 -51.659793) (xy 453.746518 -51.673899) (xy 453.797847 -51.695711)
			(xy 453.845453 -51.724765) (xy 453.888321 -51.76044) (xy 453.925538 -51.801977) (xy 453.956311 -51.84849)
			(xy 453.979983 -51.898987) (xy 453.996051 -51.952394) (xy 454.004171 -52.00757) (xy 454.00468 -52.035456)
			(xy 454.004171 -52.063342) (xy 453.996051 -52.118518) (xy 453.979983 -52.171925) (xy 453.956311 -52.222422)
			(xy 453.925538 -52.268935) (xy 453.888321 -52.310472) (xy 453.845453 -52.346147) (xy 453.797847 -52.375201)
			(xy 453.746518 -52.397013) (xy 453.692561 -52.411119) (xy 453.637124 -52.417219) (xy 453.58139 -52.415182)
			(xy 453.526547 -52.405052) (xy 453.473763 -52.387045) (xy 453.424163 -52.361544) (xy 453.378805 -52.329093)
			(xy 453.338656 -52.290384) (xy 453.30457 -52.246241) (xy 453.277274 -52.197606) (xy 453.257351 -52.145515)
			(xy 453.245225 -52.091078) (xy 453.241154 -52.035456) (xy 438.660564 -52.035456) (xy 438.822546 -54.731412)
			(xy 439.820558 -54.731412) (xy 439.821017 -54.704041) (xy 439.828834 -54.649861) (xy 439.844324 -54.597358)
			(xy 439.867168 -54.547611) (xy 439.896895 -54.501645) (xy 439.914538 -54.480714) (xy 439.914792 -54.48046)
			(xy 439.920359 -54.47336) (xy 439.926618 -54.456454) (xy 439.926984 -54.44744) (xy 439.926984 -54.380384)
			(xy 439.926638 -54.371366) (xy 439.920383 -54.354449) (xy 439.914792 -54.347364) (xy 439.914538 -54.347364)
			(xy 439.914538 -54.34711) (xy 439.896909 -54.326168) (xy 439.867182 -54.280202) (xy 439.844336 -54.230457)
			(xy 439.828838 -54.177957) (xy 439.821008 -54.123779) (xy 439.821007 -54.069039) (xy 439.828834 -54.014861)
			(xy 439.844329 -53.96236) (xy 439.867174 -53.912614) (xy 439.896898 -53.866647) (xy 439.914538 -53.845714)
			(xy 439.914792 -53.84546) (xy 439.920359 -53.83836) (xy 439.926618 -53.821454) (xy 439.926984 -53.81244)
			(xy 439.926984 -53.745384) (xy 439.926638 -53.736366) (xy 439.920383 -53.719449) (xy 439.914792 -53.712364)
			(xy 439.914538 -53.712364) (xy 439.914538 -53.71211) (xy 439.896909 -53.691168) (xy 439.867182 -53.645202)
			(xy 439.844336 -53.595457) (xy 439.828838 -53.542957) (xy 439.821008 -53.488779) (xy 439.821007 -53.434039)
			(xy 439.828834 -53.379861) (xy 439.844329 -53.32736) (xy 439.867174 -53.277614) (xy 439.896898 -53.231647)
			(xy 439.914538 -53.210714) (xy 439.914792 -53.21046) (xy 439.920359 -53.20336) (xy 439.926618 -53.186454)
			(xy 439.926984 -53.17744) (xy 439.926984 -53.110384) (xy 439.926638 -53.101366) (xy 439.920383 -53.084449)
			(xy 439.914792 -53.077364) (xy 439.914538 -53.077364) (xy 439.914538 -53.07711) (xy 439.896896 -53.05618)
			(xy 439.867183 -53.010207) (xy 439.844347 -52.960459) (xy 439.828857 -52.907958) (xy 439.821031 -52.853781)
			(xy 439.820558 -52.826412) (xy 439.821044 -52.799161) (xy 439.8288 -52.745213) (xy 439.844155 -52.692918)
			(xy 439.866797 -52.643341) (xy 439.896263 -52.597491) (xy 439.931954 -52.5563) (xy 439.973145 -52.520609)
			(xy 440.018995 -52.491143) (xy 440.068572 -52.468501) (xy 440.120867 -52.453146) (xy 440.174815 -52.44539)
			(xy 440.229317 -52.44539) (xy 440.283265 -52.453146) (xy 440.33556 -52.468501) (xy 440.385137 -52.491143)
			(xy 440.430987 -52.520609) (xy 440.472178 -52.5563) (xy 440.507869 -52.597491) (xy 440.537335 -52.643341)
			(xy 440.559977 -52.692918) (xy 440.575332 -52.745213) (xy 440.583088 -52.799161) (xy 440.583574 -52.826412)
			(xy 440.583121 -52.853783) (xy 440.575301 -52.907963) (xy 440.559809 -52.960466) (xy 440.536965 -53.010213)
			(xy 440.507237 -53.056179) (xy 440.489594 -53.07711) (xy 440.48934 -53.077364) (xy 440.483755 -53.084452)
			(xy 440.477509 -53.101368) (xy 440.477148 -53.110384) (xy 440.477148 -53.17744) (xy 440.477475 -53.18646)
			(xy 440.483742 -53.203377) (xy 440.48934 -53.21046) (xy 440.489594 -53.21046) (xy 440.489594 -53.210714)
			(xy 440.507246 -53.231638) (xy 440.536968 -53.277608) (xy 440.559812 -53.327355) (xy 440.575306 -53.379859)
			(xy 440.583133 -53.434038) (xy 440.583132 -53.48878) (xy 440.575302 -53.542959) (xy 440.559805 -53.595462)
			(xy 440.53696 -53.645208) (xy 440.507235 -53.691177) (xy 440.489594 -53.71211) (xy 440.48934 -53.712364)
			(xy 440.483755 -53.719452) (xy 440.477509 -53.736368) (xy 440.477148 -53.745384) (xy 440.477148 -53.81244)
			(xy 440.477475 -53.82146) (xy 440.483742 -53.838377) (xy 440.48934 -53.84546) (xy 440.489594 -53.84546)
			(xy 440.489594 -53.845714) (xy 440.507246 -53.866638) (xy 440.536968 -53.912608) (xy 440.559812 -53.962355)
			(xy 440.575306 -54.014859) (xy 440.583133 -54.069038) (xy 440.583132 -54.12378) (xy 440.575302 -54.177959)
			(xy 440.559805 -54.230462) (xy 440.53696 -54.280208) (xy 440.507235 -54.326177) (xy 440.489594 -54.34711)
			(xy 440.48934 -54.347364) (xy 440.483755 -54.354452) (xy 440.477509 -54.371368) (xy 440.477148 -54.380384)
			(xy 440.477148 -54.44744) (xy 440.477475 -54.45646) (xy 440.483742 -54.473377) (xy 440.48934 -54.48046)
			(xy 440.489594 -54.48046) (xy 440.489594 -54.480714) (xy 440.507205 -54.501668) (xy 440.536922 -54.547635)
			(xy 440.559763 -54.597377) (xy 440.57526 -54.649873) (xy 440.583096 -54.704044) (xy 440.583574 -54.731412)
			(xy 440.583088 -54.758663) (xy 440.578424 -54.791102) (xy 442.476382 -54.791102) (xy 442.476829 -54.763731)
			(xy 442.484649 -54.70955) (xy 442.500141 -54.657046) (xy 442.522987 -54.607299) (xy 442.552718 -54.561334)
			(xy 442.570362 -54.540404) (xy 442.570616 -54.54015) (xy 442.57619 -54.533055) (xy 442.582444 -54.516145)
			(xy 442.582808 -54.50713) (xy 442.582808 -54.440074) (xy 442.582461 -54.431056) (xy 442.576206 -54.414139)
			(xy 442.570616 -54.407054) (xy 442.570362 -54.407054) (xy 442.570362 -54.4068) (xy 442.552722 -54.385866)
			(xy 442.522994 -54.3399) (xy 442.500147 -54.290154) (xy 442.484649 -54.237651) (xy 442.476819 -54.183472)
			(xy 442.476819 -54.128731) (xy 442.484648 -54.074551) (xy 442.500146 -54.022049) (xy 442.522993 -53.972303)
			(xy 442.55272 -53.926336) (xy 442.570362 -53.905404) (xy 442.570616 -53.90515) (xy 442.57619 -53.898055)
			(xy 442.582444 -53.881145) (xy 442.582808 -53.87213) (xy 442.582808 -53.805074) (xy 442.582461 -53.796056)
			(xy 442.576206 -53.779139) (xy 442.570616 -53.772054) (xy 442.570362 -53.772054) (xy 442.570362 -53.7718)
			(xy 442.552722 -53.750866) (xy 442.522994 -53.7049) (xy 442.500147 -53.655154) (xy 442.484649 -53.602651)
			(xy 442.476819 -53.548472) (xy 442.476819 -53.493731) (xy 442.484648 -53.439551) (xy 442.500146 -53.387049)
			(xy 442.522993 -53.337303) (xy 442.55272 -53.291336) (xy 442.570362 -53.270404) (xy 442.570616 -53.27015)
			(xy 442.57619 -53.263055) (xy 442.582444 -53.246145) (xy 442.582808 -53.23713) (xy 442.582808 -53.170074)
			(xy 442.582461 -53.161056) (xy 442.576206 -53.144139) (xy 442.570616 -53.137054) (xy 442.570362 -53.137054)
			(xy 442.570362 -53.1368) (xy 442.552703 -53.115884) (xy 442.522995 -53.069906) (xy 442.500164 -53.020155)
			(xy 442.484677 -52.967651) (xy 442.476853 -52.913472) (xy 442.476382 -52.886102) (xy 442.476868 -52.858851)
			(xy 442.484624 -52.804903) (xy 442.499979 -52.752608) (xy 442.522621 -52.703031) (xy 442.552087 -52.657181)
			(xy 442.587778 -52.61599) (xy 442.628969 -52.580299) (xy 442.674819 -52.550833) (xy 442.724396 -52.528191)
			(xy 442.776691 -52.512836) (xy 442.830639 -52.50508) (xy 442.885141 -52.50508) (xy 442.939089 -52.512836)
			(xy 442.991384 -52.528191) (xy 443.030497 -52.546054) (xy 447.979473 -52.546054) (xy 447.979473 -52.491546)
			(xy 447.987231 -52.437594) (xy 448.002589 -52.385295) (xy 448.025234 -52.335714) (xy 448.054705 -52.289861)
			(xy 448.090401 -52.248669) (xy 448.131598 -52.212977) (xy 448.177454 -52.183512) (xy 448.227038 -52.160873)
			(xy 448.279339 -52.145521) (xy 448.333292 -52.13777) (xy 448.360546 -52.13731) (xy 448.387915 -52.137805)
			(xy 448.442093 -52.145616) (xy 448.494596 -52.161098) (xy 448.544343 -52.183933) (xy 448.590311 -52.213652)
			(xy 448.611244 -52.23129) (xy 448.611498 -52.231544) (xy 448.618577 -52.237141) (xy 448.6355 -52.24338)
			(xy 448.644518 -52.243736) (xy 448.711574 -52.243736) (xy 448.720589 -52.243359) (xy 448.737505 -52.237124)
			(xy 448.744594 -52.231544) (xy 448.744594 -52.23129) (xy 448.744848 -52.23129) (xy 448.765781 -52.213649)
			(xy 448.811749 -52.183925) (xy 448.861495 -52.161079) (xy 448.913997 -52.145583) (xy 448.968175 -52.137754)
			(xy 449.022917 -52.137754) (xy 449.077095 -52.145583) (xy 449.129597 -52.161079) (xy 449.179343 -52.183925)
			(xy 449.225311 -52.213649) (xy 449.246244 -52.23129) (xy 449.246498 -52.231544) (xy 449.253577 -52.237141)
			(xy 449.2705 -52.24338) (xy 449.279518 -52.243736) (xy 449.346574 -52.243736) (xy 449.355589 -52.243359)
			(xy 449.372505 -52.237124) (xy 449.379594 -52.231544) (xy 449.379594 -52.23129) (xy 449.379848 -52.23129)
			(xy 449.400788 -52.21366) (xy 449.446758 -52.183947) (xy 449.496504 -52.16111) (xy 449.549003 -52.145616)
			(xy 449.603177 -52.137786) (xy 449.630546 -52.13731) (xy 449.657796 -52.137763) (xy 449.711742 -52.145525)
			(xy 449.764033 -52.160885) (xy 449.813607 -52.18353) (xy 449.859454 -52.212999) (xy 449.900641 -52.248692)
			(xy 449.936329 -52.289883) (xy 449.965792 -52.335733) (xy 449.988431 -52.38531) (xy 450.003785 -52.437603)
			(xy 450.01154 -52.49155) (xy 450.01154 -52.54605) (xy 450.005596 -52.587398) (xy 451.05523 -52.587398)
			(xy 451.059301 -52.531776) (xy 451.071427 -52.477339) (xy 451.09135 -52.425248) (xy 451.118646 -52.376613)
			(xy 451.152732 -52.33247) (xy 451.192881 -52.293761) (xy 451.238239 -52.26131) (xy 451.287839 -52.235809)
			(xy 451.340623 -52.217802) (xy 451.395466 -52.207672) (xy 451.4512 -52.205635) (xy 451.506637 -52.211735)
			(xy 451.560594 -52.225841) (xy 451.611923 -52.247653) (xy 451.659529 -52.276707) (xy 451.702397 -52.312382)
			(xy 451.739614 -52.353919) (xy 451.770387 -52.400432) (xy 451.794059 -52.450929) (xy 451.810127 -52.504336)
			(xy 451.818247 -52.559512) (xy 451.818756 -52.587398) (xy 451.818247 -52.615284) (xy 451.810127 -52.67046)
			(xy 451.794059 -52.723867) (xy 451.770387 -52.774364) (xy 451.739614 -52.820877) (xy 451.702397 -52.862414)
			(xy 451.659529 -52.898089) (xy 451.611923 -52.927143) (xy 451.560594 -52.948955) (xy 451.506637 -52.963061)
			(xy 451.4512 -52.969161) (xy 451.395466 -52.967124) (xy 451.340623 -52.956994) (xy 451.287839 -52.938987)
			(xy 451.238239 -52.913486) (xy 451.192881 -52.881035) (xy 451.152732 -52.842326) (xy 451.118646 -52.798183)
			(xy 451.09135 -52.749548) (xy 451.071427 -52.697457) (xy 451.059301 -52.64302) (xy 451.05523 -52.587398)
			(xy 450.005596 -52.587398) (xy 450.003785 -52.599997) (xy 449.988431 -52.65229) (xy 449.965792 -52.701867)
			(xy 449.936329 -52.747717) (xy 449.900641 -52.788908) (xy 449.859454 -52.824601) (xy 449.813607 -52.85407)
			(xy 449.764033 -52.876715) (xy 449.711742 -52.892075) (xy 449.657796 -52.899837) (xy 449.630546 -52.900326)
			(xy 449.603176 -52.899851) (xy 449.548996 -52.892038) (xy 449.496493 -52.876552) (xy 449.446746 -52.853712)
			(xy 449.400779 -52.823988) (xy 449.379848 -52.806346) (xy 449.379594 -52.806092) (xy 449.372514 -52.800496)
			(xy 449.355592 -52.794255) (xy 449.346574 -52.7939) (xy 449.279518 -52.7939) (xy 449.270502 -52.794266)
			(xy 449.253585 -52.800507) (xy 449.246498 -52.806092) (xy 449.246244 -52.806346) (xy 449.225311 -52.823987)
			(xy 449.179343 -52.853711) (xy 449.129597 -52.876557) (xy 449.077095 -52.892053) (xy 449.022917 -52.899882)
			(xy 448.968175 -52.899882) (xy 448.913997 -52.892053) (xy 448.861495 -52.876557) (xy 448.811749 -52.853711)
			(xy 448.765781 -52.823987) (xy 448.744848 -52.806346) (xy 448.744594 -52.806092) (xy 448.737514 -52.800496)
			(xy 448.720592 -52.794255) (xy 448.711574 -52.7939) (xy 448.644518 -52.7939) (xy 448.635502 -52.794266)
			(xy 448.618585 -52.800507) (xy 448.611498 -52.806092) (xy 448.611498 -52.806346) (xy 448.611244 -52.806346)
			(xy 448.590299 -52.82397) (xy 448.544331 -52.853686) (xy 448.494587 -52.876525) (xy 448.442088 -52.89202)
			(xy 448.387914 -52.899851) (xy 448.360546 -52.900326) (xy 448.333292 -52.89983) (xy 448.279339 -52.892079)
			(xy 448.227038 -52.876727) (xy 448.177454 -52.854088) (xy 448.131598 -52.824623) (xy 448.090401 -52.788931)
			(xy 448.054705 -52.747739) (xy 448.025234 -52.701886) (xy 448.002589 -52.652305) (xy 447.987231 -52.600006)
			(xy 447.979473 -52.546054) (xy 443.030497 -52.546054) (xy 443.040961 -52.550833) (xy 443.086811 -52.580299)
			(xy 443.128002 -52.61599) (xy 443.163693 -52.657181) (xy 443.193159 -52.703031) (xy 443.215801 -52.752608)
			(xy 443.231156 -52.804903) (xy 443.238912 -52.858851) (xy 443.239398 -52.886102) (xy 443.238934 -52.913472)
			(xy 443.231115 -52.967651) (xy 443.215626 -53.020155) (xy 443.192784 -53.069901) (xy 443.163059 -53.115868)
			(xy 443.145418 -53.1368) (xy 443.145164 -53.137054) (xy 443.139587 -53.144147) (xy 443.133335 -53.161059)
			(xy 443.132972 -53.170074) (xy 443.132972 -53.23713) (xy 443.133321 -53.246148) (xy 443.139575 -53.263064)
			(xy 443.145164 -53.27015) (xy 443.145418 -53.27015) (xy 443.145418 -53.270404) (xy 443.163059 -53.291336)
			(xy 443.19278 -53.337305) (xy 443.215623 -53.387052) (xy 443.231117 -53.439553) (xy 443.238944 -53.493731)
			(xy 443.238944 -53.548472) (xy 443.231116 -53.602649) (xy 443.215621 -53.655151) (xy 443.192779 -53.704898)
			(xy 443.163057 -53.750866) (xy 443.146488 -53.77053) (xy 443.51067 -53.77053) (xy 443.511183 -53.741613)
			(xy 443.51991 -53.68444) (xy 443.537167 -53.62924) (xy 443.562559 -53.577278) (xy 443.595505 -53.529744)
			(xy 443.635249 -53.487729) (xy 443.657736 -53.46954) (xy 443.666521 -53.461912) (xy 443.676715 -53.441027)
			(xy 443.677294 -53.429408) (xy 443.677294 -53.349652) (xy 443.67677 -53.338018) (xy 443.666571 -53.317109)
			(xy 443.657736 -53.30952) (xy 443.63527 -53.291309) (xy 443.595532 -53.249294) (xy 443.56259 -53.201764)
			(xy 443.537198 -53.149806) (xy 443.519938 -53.094612) (xy 443.511206 -53.037445) (xy 443.51067 -53.00853)
			(xy 443.511183 -52.981279) (xy 443.518935 -52.927331) (xy 443.534287 -52.875035) (xy 443.556924 -52.825457)
			(xy 443.586387 -52.779605) (xy 443.622075 -52.738412) (xy 443.663263 -52.702718) (xy 443.709111 -52.673249)
			(xy 443.758687 -52.650605) (xy 443.81098 -52.635247) (xy 443.864927 -52.627487) (xy 443.892178 -52.627022)
			(xy 443.918492 -52.627497) (xy 443.97062 -52.634729) (xy 444.021263 -52.649046) (xy 444.069462 -52.670177)
			(xy 444.114306 -52.697723) (xy 444.154946 -52.731161) (xy 444.173102 -52.750212) (xy 444.180619 -52.757618)
			(xy 444.199903 -52.76614) (xy 444.21044 -52.766722) (xy 444.285116 -52.766722) (xy 444.295667 -52.766208)
			(xy 444.314962 -52.757662) (xy 444.322454 -52.750212) (xy 444.340593 -52.73114) (xy 444.381226 -52.697683)
			(xy 444.426069 -52.670126) (xy 444.474274 -52.648991) (xy 444.524924 -52.634677) (xy 444.577061 -52.627458)
			(xy 444.603378 -52.627022) (xy 444.630632 -52.627476) (xy 444.684585 -52.635231) (xy 444.736884 -52.650585)
			(xy 444.786466 -52.673228) (xy 444.832321 -52.702696) (xy 444.873515 -52.738391) (xy 444.909209 -52.779585)
			(xy 444.938676 -52.825441) (xy 444.961317 -52.875023) (xy 444.976671 -52.927323) (xy 444.984425 -52.981276)
			(xy 444.984886 -53.00853) (xy 444.984404 -53.036196) (xy 444.982173 -53.051456) (xy 453.241154 -53.051456)
			(xy 453.245225 -52.995834) (xy 453.257351 -52.941397) (xy 453.277274 -52.889306) (xy 453.30457 -52.840671)
			(xy 453.338656 -52.796528) (xy 453.378805 -52.757819) (xy 453.424163 -52.725368) (xy 453.473763 -52.699867)
			(xy 453.526547 -52.68186) (xy 453.58139 -52.67173) (xy 453.637124 -52.669693) (xy 453.692561 -52.675793)
			(xy 453.746518 -52.689899) (xy 453.797847 -52.711711) (xy 453.845453 -52.740765) (xy 453.888321 -52.77644)
			(xy 453.925538 -52.817977) (xy 453.956311 -52.86449) (xy 453.979983 -52.914987) (xy 453.996051 -52.968394)
			(xy 454.004171 -53.02357) (xy 454.00468 -53.051456) (xy 454.004171 -53.079342) (xy 453.996051 -53.134518)
			(xy 453.979983 -53.187925) (xy 453.956311 -53.238422) (xy 453.925538 -53.284935) (xy 453.888321 -53.326472)
			(xy 453.845453 -53.362147) (xy 453.797847 -53.391201) (xy 453.746518 -53.413013) (xy 453.692561 -53.427119)
			(xy 453.637124 -53.433219) (xy 453.58139 -53.431182) (xy 453.526547 -53.421052) (xy 453.473763 -53.403045)
			(xy 453.424163 -53.377544) (xy 453.378805 -53.345093) (xy 453.338656 -53.306384) (xy 453.30457 -53.262241)
			(xy 453.277274 -53.213606) (xy 453.257351 -53.161515) (xy 453.245225 -53.107078) (xy 453.241154 -53.051456)
			(xy 444.982173 -53.051456) (xy 444.9764 -53.090947) (xy 444.960578 -53.14397) (xy 444.937271 -53.194154)
			(xy 444.906965 -53.240449) (xy 444.870295 -53.281887) (xy 444.828029 -53.317598) (xy 444.8048 -53.332634)
			(xy 444.795119 -53.339266) (xy 444.782674 -53.35913) (xy 444.780924 -53.370734) (xy 444.77305 -53.450744)
			(xy 444.772399 -53.462383) (xy 444.780492 -53.484221) (xy 444.788544 -53.492654) (xy 444.788798 -53.492908)
			(xy 444.807365 -53.511003) (xy 444.839945 -53.551332) (xy 444.86676 -53.595703) (xy 444.887315 -53.643299)
			(xy 444.901231 -53.693241) (xy 444.908252 -53.744608) (xy 444.908686 -53.77053) (xy 444.90825 -53.797783)
			(xy 444.900489 -53.851734) (xy 444.885129 -53.904031) (xy 444.862483 -53.953609) (xy 444.833011 -53.999461)
			(xy 444.797314 -54.040651) (xy 444.756119 -54.076342) (xy 444.710264 -54.105808) (xy 444.660682 -54.128447)
			(xy 444.608383 -54.1438) (xy 444.554431 -54.151554) (xy 444.527178 -54.152038) (xy 444.499807 -54.1516)
			(xy 444.445626 -54.143778) (xy 444.393122 -54.128283) (xy 444.343375 -54.105435) (xy 444.29741 -54.075703)
			(xy 444.27648 -54.058058) (xy 444.276226 -54.057804) (xy 444.269136 -54.052223) (xy 444.252222 -54.045973)
			(xy 444.243206 -54.045612) (xy 444.17615 -54.045612) (xy 444.167135 -54.045991) (xy 444.150218 -54.052223)
			(xy 444.14313 -54.057804) (xy 444.14313 -54.058058) (xy 444.142876 -54.058058) (xy 444.121921 -54.075668)
			(xy 444.075955 -54.105386) (xy 444.026213 -54.128228) (xy 443.973718 -54.143726) (xy 443.919546 -54.151561)
			(xy 443.892178 -54.152038) (xy 443.864928 -54.151543) (xy 443.810982 -54.143784) (xy 443.758689 -54.128428)
			(xy 443.709114 -54.105786) (xy 443.663265 -54.07632) (xy 443.622076 -54.04063) (xy 443.586384 -53.999442)
			(xy 443.556918 -53.953593) (xy 443.534275 -53.904018) (xy 443.518918 -53.851726) (xy 443.511158 -53.79778)
			(xy 443.51067 -53.77053) (xy 443.146488 -53.77053) (xy 443.145418 -53.7718) (xy 443.145164 -53.772054)
			(xy 443.139587 -53.779147) (xy 443.133335 -53.796059) (xy 443.132972 -53.805074) (xy 443.132972 -53.87213)
			(xy 443.133321 -53.881148) (xy 443.139575 -53.898064) (xy 443.145164 -53.90515) (xy 443.145418 -53.90515)
			(xy 443.145418 -53.905404) (xy 443.163059 -53.926336) (xy 443.19278 -53.972305) (xy 443.215623 -54.022052)
			(xy 443.231117 -54.074553) (xy 443.238944 -54.128731) (xy 443.238944 -54.183472) (xy 443.231116 -54.237649)
			(xy 443.215621 -54.290151) (xy 443.20183 -54.320186) (xy 445.430402 -54.320186) (xy 445.430859 -54.292815)
			(xy 445.438679 -54.238636) (xy 445.45417 -54.186133) (xy 445.477014 -54.136386) (xy 445.50674 -54.09042)
			(xy 445.524382 -54.069488) (xy 445.524636 -54.069234) (xy 445.530218 -54.062145) (xy 445.536467 -54.04523)
			(xy 445.536828 -54.036214) (xy 445.536828 -53.969158) (xy 445.536437 -53.960145) (xy 445.530212 -53.943228)
			(xy 445.524636 -53.936138) (xy 445.524382 -53.936138) (xy 445.524382 -53.935884) (xy 445.506766 -53.914933)
			(xy 445.477051 -53.868965) (xy 445.454211 -53.819223) (xy 445.438715 -53.766726) (xy 445.43088 -53.712554)
			(xy 445.430402 -53.685186) (xy 445.430888 -53.657935) (xy 445.438644 -53.603987) (xy 445.453999 -53.551692)
			(xy 445.476641 -53.502115) (xy 445.506107 -53.456265) (xy 445.541798 -53.415074) (xy 445.582989 -53.379383)
			(xy 445.628839 -53.349917) (xy 445.678416 -53.327275) (xy 445.730711 -53.31192) (xy 445.784659 -53.304164)
			(xy 445.839161 -53.304164) (xy 445.893109 -53.31192) (xy 445.945404 -53.327275) (xy 445.994981 -53.349917)
			(xy 446.040831 -53.379383) (xy 446.082022 -53.415074) (xy 446.117713 -53.456265) (xy 446.147179 -53.502115)
			(xy 446.169821 -53.551692) (xy 446.185176 -53.603987) (xy 446.192932 -53.657935) (xy 446.193418 -53.685186)
			(xy 446.192964 -53.712557) (xy 446.185146 -53.766737) (xy 446.169655 -53.819241) (xy 446.14681 -53.868988)
			(xy 446.117082 -53.914954) (xy 446.099438 -53.935884) (xy 446.099184 -53.936138) (xy 446.093615 -53.943237)
			(xy 446.087358 -53.960144) (xy 446.086992 -53.969158) (xy 446.086992 -54.036214) (xy 446.087344 -54.045231)
			(xy 446.093595 -54.062148) (xy 446.099184 -54.069234) (xy 446.099438 -54.069234) (xy 446.099438 -54.069488)
			(xy 446.117091 -54.090409) (xy 446.1468 -54.136385) (xy 446.169632 -54.186136) (xy 446.18512 -54.238639)
			(xy 446.192946 -54.292816) (xy 446.193418 -54.320186) (xy 446.192932 -54.347437) (xy 446.185176 -54.401385)
			(xy 446.169821 -54.45368) (xy 446.147179 -54.503257) (xy 446.117713 -54.549107) (xy 446.082022 -54.590298)
			(xy 446.040831 -54.625989) (xy 445.994981 -54.655455) (xy 445.945404 -54.678097) (xy 445.893109 -54.693452)
			(xy 445.839161 -54.701208) (xy 445.784659 -54.701208) (xy 445.730711 -54.693452) (xy 445.678416 -54.678097)
			(xy 445.628839 -54.655455) (xy 445.582989 -54.625989) (xy 445.541798 -54.590298) (xy 445.506107 -54.549107)
			(xy 445.476641 -54.503257) (xy 445.453999 -54.45368) (xy 445.438644 -54.401385) (xy 445.430888 -54.347437)
			(xy 445.430402 -54.320186) (xy 443.20183 -54.320186) (xy 443.192779 -54.339898) (xy 443.163057 -54.385866)
			(xy 443.145418 -54.4068) (xy 443.145164 -54.407054) (xy 443.139587 -54.414147) (xy 443.133335 -54.431059)
			(xy 443.132972 -54.440074) (xy 443.132972 -54.50713) (xy 443.133321 -54.516148) (xy 443.139575 -54.533064)
			(xy 443.145164 -54.54015) (xy 443.145418 -54.54015) (xy 443.145418 -54.540404) (xy 443.163075 -54.561321)
			(xy 443.192784 -54.607299) (xy 443.215616 -54.65705) (xy 443.231103 -54.709554) (xy 443.238926 -54.763732)
			(xy 443.239043 -54.770528) (xy 446.370964 -54.770528) (xy 446.371431 -54.743158) (xy 446.379246 -54.688978)
			(xy 446.394734 -54.636474) (xy 446.417576 -54.586727) (xy 446.447302 -54.540761) (xy 446.464944 -54.51983)
			(xy 446.465198 -54.519576) (xy 446.470801 -54.5125) (xy 446.477038 -54.495575) (xy 446.47739 -54.486556)
			(xy 446.47739 -54.4195) (xy 446.477035 -54.410483) (xy 446.470786 -54.393566) (xy 446.465198 -54.38648)
			(xy 446.464944 -54.38648) (xy 446.464944 -54.386226) (xy 446.44731 -54.365289) (xy 446.417596 -54.319318)
			(xy 446.394759 -54.269572) (xy 446.379266 -54.217072) (xy 446.371438 -54.162897) (xy 446.370964 -54.135528)
			(xy 446.37145 -54.108277) (xy 446.379206 -54.054329) (xy 446.394561 -54.002034) (xy 446.417203 -53.952457)
			(xy 446.446669 -53.906607) (xy 446.48236 -53.865416) (xy 446.523551 -53.829725) (xy 446.569401 -53.800259)
			(xy 446.618978 -53.777617) (xy 446.671273 -53.762262) (xy 446.725221 -53.754506) (xy 446.779723 -53.754506)
			(xy 446.833671 -53.762262) (xy 446.885966 -53.777617) (xy 446.935543 -53.800259) (xy 446.981393 -53.829725)
			(xy 447.022584 -53.865416) (xy 447.058275 -53.906607) (xy 447.087741 -53.952457) (xy 447.092816 -53.96357)
			(xy 451.071994 -53.96357) (xy 451.076065 -53.907948) (xy 451.088191 -53.853511) (xy 451.108114 -53.80142)
			(xy 451.13541 -53.752785) (xy 451.169496 -53.708642) (xy 451.209645 -53.669933) (xy 451.255003 -53.637482)
			(xy 451.304603 -53.611981) (xy 451.357387 -53.593974) (xy 451.41223 -53.583844) (xy 451.467964 -53.581807)
			(xy 451.523401 -53.587907) (xy 451.577358 -53.602013) (xy 451.628687 -53.623825) (xy 451.676293 -53.652879)
			(xy 451.719161 -53.688554) (xy 451.756378 -53.730091) (xy 451.787151 -53.776604) (xy 451.810823 -53.827101)
			(xy 451.826891 -53.880508) (xy 451.835011 -53.935684) (xy 451.83552 -53.96357) (xy 451.835011 -53.991456)
			(xy 451.826891 -54.046632) (xy 451.810823 -54.100039) (xy 451.787151 -54.150536) (xy 451.756378 -54.197049)
			(xy 451.719161 -54.238586) (xy 451.676293 -54.274261) (xy 451.628687 -54.303315) (xy 451.577358 -54.325127)
			(xy 451.523401 -54.339233) (xy 451.467964 -54.345333) (xy 451.41223 -54.343296) (xy 451.357387 -54.333166)
			(xy 451.304603 -54.315159) (xy 451.255003 -54.289658) (xy 451.209645 -54.257207) (xy 451.169496 -54.218498)
			(xy 451.13541 -54.174355) (xy 451.108114 -54.12572) (xy 451.088191 -54.073629) (xy 451.076065 -54.019192)
			(xy 451.071994 -53.96357) (xy 447.092816 -53.96357) (xy 447.110383 -54.002034) (xy 447.125738 -54.054329)
			(xy 447.133494 -54.108277) (xy 447.13398 -54.135528) (xy 447.133535 -54.162899) (xy 447.125713 -54.217079)
			(xy 447.110219 -54.269583) (xy 447.087373 -54.319329) (xy 447.057643 -54.365295) (xy 447.04 -54.386226)
			(xy 447.039746 -54.38648) (xy 447.034155 -54.393563) (xy 447.027912 -54.410483) (xy 447.027554 -54.4195)
			(xy 447.027554 -54.486556) (xy 447.02792 -54.495572) (xy 447.03416 -54.51249) (xy 447.039746 -54.519576)
			(xy 447.04 -54.519576) (xy 447.04 -54.51983) (xy 447.05762 -54.540778) (xy 447.087334 -54.586746)
			(xy 447.110174 -54.63649) (xy 447.12567 -54.688987) (xy 447.133503 -54.74316) (xy 447.13398 -54.770528)
			(xy 447.133494 -54.797779) (xy 447.125738 -54.851727) (xy 447.110383 -54.904022) (xy 447.087741 -54.953599)
			(xy 447.058275 -54.999449) (xy 447.022584 -55.04064) (xy 446.981393 -55.076331) (xy 446.935543 -55.105797)
			(xy 446.885966 -55.128439) (xy 446.833671 -55.143794) (xy 446.779723 -55.15155) (xy 446.725221 -55.15155)
			(xy 446.671273 -55.143794) (xy 446.618978 -55.128439) (xy 446.569401 -55.105797) (xy 446.523551 -55.076331)
			(xy 446.48236 -55.04064) (xy 446.446669 -54.999449) (xy 446.417203 -54.953599) (xy 446.394561 -54.904022)
			(xy 446.379206 -54.851727) (xy 446.37145 -54.797779) (xy 446.370964 -54.770528) (xy 443.239043 -54.770528)
			(xy 443.239398 -54.791102) (xy 443.238912 -54.818353) (xy 443.231156 -54.872301) (xy 443.215801 -54.924596)
			(xy 443.193159 -54.974173) (xy 443.163693 -55.020023) (xy 443.128002 -55.061214) (xy 443.086811 -55.096905)
			(xy 443.040961 -55.126371) (xy 442.991384 -55.149013) (xy 442.939089 -55.164368) (xy 442.885141 -55.172124)
			(xy 442.830639 -55.172124) (xy 442.776691 -55.164368) (xy 442.724396 -55.149013) (xy 442.674819 -55.126371)
			(xy 442.628969 -55.096905) (xy 442.587778 -55.061214) (xy 442.552087 -55.020023) (xy 442.522621 -54.974173)
			(xy 442.499979 -54.924596) (xy 442.484624 -54.872301) (xy 442.476868 -54.818353) (xy 442.476382 -54.791102)
			(xy 440.578424 -54.791102) (xy 440.575332 -54.812611) (xy 440.559977 -54.864906) (xy 440.537335 -54.914483)
			(xy 440.507869 -54.960333) (xy 440.472178 -55.001524) (xy 440.430987 -55.037215) (xy 440.385137 -55.066681)
			(xy 440.33556 -55.089323) (xy 440.283265 -55.104678) (xy 440.229317 -55.112434) (xy 440.174815 -55.112434)
			(xy 440.120867 -55.104678) (xy 440.068572 -55.089323) (xy 440.018995 -55.066681) (xy 439.973145 -55.037215)
			(xy 439.931954 -55.001524) (xy 439.896263 -54.960333) (xy 439.866797 -54.914483) (xy 439.844155 -54.864906)
			(xy 439.8288 -54.812611) (xy 439.821044 -54.758663) (xy 439.820558 -54.731412) (xy 438.822546 -54.731412)
			(xy 438.88208 -55.722266) (xy 452.133968 -55.722266) (xy 452.138039 -55.666644) (xy 452.150165 -55.612207)
			(xy 452.170088 -55.560116) (xy 452.197384 -55.511481) (xy 452.23147 -55.467338) (xy 452.271619 -55.428629)
			(xy 452.316977 -55.396178) (xy 452.366577 -55.370677) (xy 452.419361 -55.35267) (xy 452.474204 -55.34254)
			(xy 452.529938 -55.340503) (xy 452.585375 -55.346603) (xy 452.639332 -55.360709) (xy 452.690661 -55.382521)
			(xy 452.738267 -55.411575) (xy 452.781135 -55.44725) (xy 452.818352 -55.488787) (xy 452.849125 -55.5353)
			(xy 452.872797 -55.585797) (xy 452.888865 -55.639204) (xy 452.896985 -55.69438) (xy 452.897494 -55.722266)
			(xy 452.896985 -55.750152) (xy 452.888865 -55.805328) (xy 452.872797 -55.858735) (xy 452.849125 -55.909232)
			(xy 452.818352 -55.955745) (xy 452.781135 -55.997282) (xy 452.738267 -56.032957) (xy 452.690661 -56.062011)
			(xy 452.639332 -56.083823) (xy 452.585375 -56.097929) (xy 452.529938 -56.104029) (xy 452.474204 -56.101992)
			(xy 452.419361 -56.091862) (xy 452.366577 -56.073855) (xy 452.316977 -56.048354) (xy 452.271619 -56.015903)
			(xy 452.23147 -55.977194) (xy 452.197384 -55.933051) (xy 452.170088 -55.884416) (xy 452.150165 -55.832325)
			(xy 452.138039 -55.777888) (xy 452.133968 -55.722266) (xy 438.88208 -55.722266) (xy 438.959027 -57.002934)
			(xy 447.863468 -57.002934) (xy 447.863996 -56.974844) (xy 447.872218 -56.919268) (xy 447.888504 -56.865501)
			(xy 447.912501 -56.814703) (xy 447.943691 -56.767976) (xy 447.981398 -56.72633) (xy 448.024806 -56.690666)
			(xy 448.048634 -56.675782) (xy 448.057524 -56.670448) (xy 448.069716 -56.65343) (xy 448.090036 -56.560212)
			(xy 448.085718 -56.539638) (xy 448.079876 -56.531002) (xy 448.063872 -56.506941) (xy 448.038531 -56.455008)
			(xy 448.021306 -56.399849) (xy 448.012592 -56.342725) (xy 448.012058 -56.313832) (xy 448.012608 -56.286583)
			(xy 448.020359 -56.232639) (xy 448.035709 -56.180348) (xy 448.058343 -56.130773) (xy 448.087803 -56.084924)
			(xy 448.123488 -56.043735) (xy 448.164672 -56.008043) (xy 448.210515 -55.978575) (xy 448.260086 -55.955932)
			(xy 448.312375 -55.940573) (xy 448.366317 -55.932813) (xy 448.393566 -55.932324) (xy 448.420936 -55.932804)
			(xy 448.475115 -55.940618) (xy 448.527618 -55.956103) (xy 448.577365 -55.978942) (xy 448.623332 -56.008664)
			(xy 448.644264 -56.026304) (xy 448.644518 -56.026558) (xy 448.65159 -56.032165) (xy 448.668518 -56.038398)
			(xy 448.677538 -56.03875) (xy 448.744594 -56.03875) (xy 448.753612 -56.038401) (xy 448.770529 -56.032149)
			(xy 448.777614 -56.026558) (xy 448.777614 -56.026304) (xy 448.777868 -56.026304) (xy 448.798801 -56.008663)
			(xy 448.844769 -55.978939) (xy 448.894515 -55.956093) (xy 448.947017 -55.940597) (xy 449.001195 -55.932768)
			(xy 449.055937 -55.932768) (xy 449.110115 -55.940597) (xy 449.162617 -55.956093) (xy 449.212363 -55.978939)
			(xy 449.258331 -56.008663) (xy 449.279264 -56.026304) (xy 449.279518 -56.026558) (xy 449.28659 -56.032165)
			(xy 449.303518 -56.038398) (xy 449.312538 -56.03875) (xy 449.379594 -56.03875) (xy 449.388612 -56.038401)
			(xy 449.405529 -56.032149) (xy 449.412614 -56.026558) (xy 449.412614 -56.026304) (xy 449.412868 -56.026304)
			(xy 449.433802 -56.008667) (xy 449.479774 -55.978955) (xy 449.529521 -55.956118) (xy 449.582021 -55.940627)
			(xy 449.636197 -55.932798) (xy 449.663566 -55.932324) (xy 449.690823 -55.932721) (xy 449.744782 -55.940474)
			(xy 449.797088 -55.955829) (xy 449.846677 -55.978471) (xy 449.892538 -56.007941) (xy 449.933738 -56.043637)
			(xy 449.969439 -56.084835) (xy 449.998913 -56.130693) (xy 450.021559 -56.18028) (xy 450.036918 -56.232585)
			(xy 450.044677 -56.286543) (xy 450.044677 -56.297068) (xy 450.386448 -56.297068) (xy 450.390519 -56.241446)
			(xy 450.402645 -56.187009) (xy 450.422568 -56.134918) (xy 450.449864 -56.086283) (xy 450.48395 -56.04214)
			(xy 450.524099 -56.003431) (xy 450.569457 -55.97098) (xy 450.619057 -55.945479) (xy 450.671841 -55.927472)
			(xy 450.726684 -55.917342) (xy 450.782418 -55.915305) (xy 450.837855 -55.921405) (xy 450.891812 -55.935511)
			(xy 450.943141 -55.957323) (xy 450.990747 -55.986377) (xy 451.033615 -56.022052) (xy 451.070832 -56.063589)
			(xy 451.101605 -56.110102) (xy 451.125277 -56.160599) (xy 451.141345 -56.214006) (xy 451.149465 -56.269182)
			(xy 451.149974 -56.297068) (xy 451.149465 -56.324954) (xy 451.141345 -56.38013) (xy 451.125277 -56.433537)
			(xy 451.101605 -56.484034) (xy 451.070832 -56.530547) (xy 451.033615 -56.572084) (xy 450.990747 -56.607759)
			(xy 450.943141 -56.636813) (xy 450.891812 -56.658625) (xy 450.837855 -56.672731) (xy 450.782418 -56.678831)
			(xy 450.726684 -56.676794) (xy 450.671841 -56.666664) (xy 450.619057 -56.648657) (xy 450.569457 -56.623156)
			(xy 450.524099 -56.590705) (xy 450.48395 -56.551996) (xy 450.449864 -56.507853) (xy 450.422568 -56.459218)
			(xy 450.402645 -56.407127) (xy 450.390519 -56.35269) (xy 450.386448 -56.297068) (xy 450.044677 -56.297068)
			(xy 450.044677 -56.341057) (xy 450.036918 -56.395015) (xy 450.021559 -56.44732) (xy 449.998913 -56.496907)
			(xy 449.969439 -56.542765) (xy 449.933738 -56.583963) (xy 449.892538 -56.619659) (xy 449.846677 -56.649129)
			(xy 449.797088 -56.671771) (xy 449.744782 -56.687126) (xy 449.690823 -56.694879) (xy 449.663566 -56.69534)
			(xy 449.636194 -56.694908) (xy 449.582013 -56.687085) (xy 449.529509 -56.671588) (xy 449.479763 -56.648738)
			(xy 449.433798 -56.619005) (xy 449.412868 -56.60136) (xy 449.412614 -56.601106) (xy 449.405527 -56.59552)
			(xy 449.388611 -56.589273) (xy 449.379594 -56.588914) (xy 449.312538 -56.588914) (xy 449.303523 -56.589286)
			(xy 449.286605 -56.595523) (xy 449.279518 -56.601106) (xy 449.279518 -56.60136) (xy 449.279264 -56.60136)
			(xy 449.258331 -56.619001) (xy 449.212363 -56.648725) (xy 449.162617 -56.671571) (xy 449.110115 -56.687067)
			(xy 449.055937 -56.694896) (xy 449.001195 -56.694896) (xy 448.947017 -56.687067) (xy 448.894515 -56.671571)
			(xy 448.844769 -56.648725) (xy 448.798801 -56.619001) (xy 448.777868 -56.60136) (xy 448.777614 -56.601106)
			(xy 448.770527 -56.59552) (xy 448.753611 -56.589273) (xy 448.744594 -56.588914) (xy 448.677538 -56.588914)
			(xy 448.668523 -56.589286) (xy 448.651605 -56.595523) (xy 448.644518 -56.601106) (xy 448.64401 -56.60136)
			(xy 448.631279 -56.612308) (xy 448.604185 -56.632147) (xy 448.589908 -56.640984) (xy 448.581018 -56.646318)
			(xy 448.568826 -56.663336) (xy 448.548506 -56.756554) (xy 448.552824 -56.777128) (xy 448.558666 -56.785764)
			(xy 448.574649 -56.809839) (xy 448.599997 -56.861766) (xy 448.617227 -56.916921) (xy 448.625947 -56.974042)
			(xy 448.626484 -57.002934) (xy 448.625998 -57.030185) (xy 448.618242 -57.084133) (xy 448.602887 -57.136428)
			(xy 448.580245 -57.186005) (xy 448.550779 -57.231855) (xy 448.515088 -57.273046) (xy 448.473897 -57.308737)
			(xy 448.428047 -57.338203) (xy 448.37847 -57.360845) (xy 448.326175 -57.3762) (xy 448.272227 -57.383956)
			(xy 448.217725 -57.383956) (xy 448.163777 -57.3762) (xy 448.111482 -57.360845) (xy 448.061905 -57.338203)
			(xy 448.016055 -57.308737) (xy 447.974864 -57.273046) (xy 447.939173 -57.231855) (xy 447.909707 -57.186005)
			(xy 447.887065 -57.136428) (xy 447.87171 -57.084133) (xy 447.863954 -57.030185) (xy 447.863468 -57.002934)
			(xy 438.959027 -57.002934) (xy 439.059751 -58.679334) (xy 448.295268 -58.679334) (xy 448.295702 -58.653019)
			(xy 448.302945 -58.600889) (xy 448.317271 -58.550246) (xy 448.33841 -58.502048) (xy 448.365962 -58.457205)
			(xy 448.399405 -58.416566) (xy 448.418458 -58.39841) (xy 448.425851 -58.390881) (xy 448.434382 -58.371607)
			(xy 448.434968 -58.361072) (xy 448.434968 -58.286396) (xy 448.434464 -58.275843) (xy 448.425912 -58.256548)
			(xy 448.418458 -58.249058) (xy 448.399381 -58.230924) (xy 448.365927 -58.190289) (xy 448.338372 -58.145444)
			(xy 448.317238 -58.097239) (xy 448.302925 -58.046588) (xy 448.295704 -57.994451) (xy 448.295268 -57.968134)
			(xy 448.295754 -57.940883) (xy 448.30351 -57.886935) (xy 448.318865 -57.83464) (xy 448.341507 -57.785063)
			(xy 448.370973 -57.739213) (xy 448.406664 -57.698022) (xy 448.447855 -57.662331) (xy 448.493705 -57.632865)
			(xy 448.543282 -57.610223) (xy 448.595577 -57.594868) (xy 448.649525 -57.587112) (xy 448.704027 -57.587112)
			(xy 448.757975 -57.594868) (xy 448.81027 -57.610223) (xy 448.859847 -57.632865) (xy 448.905697 -57.662331)
			(xy 448.946888 -57.698022) (xy 448.982579 -57.739213) (xy 449.012045 -57.785063) (xy 449.034687 -57.83464)
			(xy 449.050042 -57.886935) (xy 449.057798 -57.940883) (xy 449.058284 -57.968134) (xy 449.057844 -57.994449)
			(xy 449.050605 -58.046579) (xy 449.043337 -58.072274) (xy 452.29348 -58.072274) (xy 452.297551 -58.016652)
			(xy 452.309677 -57.962215) (xy 452.3296 -57.910124) (xy 452.356896 -57.861489) (xy 452.390982 -57.817346)
			(xy 452.431131 -57.778637) (xy 452.476489 -57.746186) (xy 452.526089 -57.720685) (xy 452.578873 -57.702678)
			(xy 452.633716 -57.692548) (xy 452.68945 -57.690511) (xy 452.744887 -57.696611) (xy 452.798844 -57.710717)
			(xy 452.850173 -57.732529) (xy 452.897779 -57.761583) (xy 452.940647 -57.797258) (xy 452.977864 -57.838795)
			(xy 453.008637 -57.885308) (xy 453.032309 -57.935805) (xy 453.048377 -57.989212) (xy 453.056497 -58.044388)
			(xy 453.057006 -58.072274) (xy 453.056497 -58.10016) (xy 453.048377 -58.155336) (xy 453.032309 -58.208743)
			(xy 453.008637 -58.25924) (xy 452.977864 -58.305753) (xy 452.940647 -58.34729) (xy 452.897779 -58.382965)
			(xy 452.850173 -58.412019) (xy 452.798844 -58.433831) (xy 452.744887 -58.447937) (xy 452.68945 -58.454037)
			(xy 452.633716 -58.452) (xy 452.578873 -58.44187) (xy 452.526089 -58.423863) (xy 452.476489 -58.398362)
			(xy 452.431131 -58.365911) (xy 452.390982 -58.327202) (xy 452.356896 -58.283059) (xy 452.3296 -58.234424)
			(xy 452.309677 -58.182333) (xy 452.297551 -58.127896) (xy 452.29348 -58.072274) (xy 449.043337 -58.072274)
			(xy 449.03628 -58.097222) (xy 449.015143 -58.145421) (xy 448.987592 -58.190264) (xy 448.954148 -58.230902)
			(xy 448.935094 -58.249058) (xy 448.927708 -58.256593) (xy 448.919175 -58.275863) (xy 448.918584 -58.286396)
			(xy 448.918584 -58.361072) (xy 448.91912 -58.371621) (xy 448.927651 -58.390916) (xy 448.935094 -58.39841)
			(xy 448.954146 -58.416569) (xy 448.987604 -58.457198) (xy 449.015164 -58.502037) (xy 449.036303 -58.550237)
			(xy 449.05062 -58.600884) (xy 449.057845 -58.653018) (xy 449.058284 -58.679334) (xy 449.057798 -58.706585)
			(xy 449.050042 -58.760533) (xy 449.034687 -58.812828) (xy 449.012045 -58.862405) (xy 448.982579 -58.908255)
			(xy 448.946888 -58.949446) (xy 448.905697 -58.985137) (xy 448.859847 -59.014603) (xy 448.81027 -59.037245)
			(xy 448.757975 -59.0526) (xy 448.704027 -59.060356) (xy 448.649525 -59.060356) (xy 448.595577 -59.0526)
			(xy 448.543282 -59.037245) (xy 448.493705 -59.014603) (xy 448.447855 -58.985137) (xy 448.406664 -58.949446)
			(xy 448.370973 -58.908255) (xy 448.341507 -58.862405) (xy 448.318865 -58.812828) (xy 448.30351 -58.760533)
			(xy 448.295754 -58.706585) (xy 448.295268 -58.679334) (xy 439.059751 -58.679334) (xy 439.140258 -60.019254)
			(xy 448.435661 -60.019254) (xy 448.435661 -59.964746) (xy 448.443419 -59.910794) (xy 448.458776 -59.858494)
			(xy 448.481421 -59.808913) (xy 448.510891 -59.763059) (xy 448.546587 -59.721866) (xy 448.587783 -59.686173)
			(xy 448.633639 -59.656706) (xy 448.683222 -59.634066) (xy 448.735523 -59.618713) (xy 448.789476 -59.610959)
			(xy 448.81673 -59.610498) (xy 448.844101 -59.610947) (xy 448.898281 -59.618769) (xy 448.950784 -59.634262)
			(xy 449.00053 -59.657108) (xy 449.046497 -59.686835) (xy 449.067428 -59.704478) (xy 449.067682 -59.704732)
			(xy 449.074767 -59.710321) (xy 449.091685 -59.716565) (xy 449.100702 -59.716924) (xy 449.167758 -59.716924)
			(xy 449.176772 -59.716542) (xy 449.193689 -59.710311) (xy 449.200778 -59.704732) (xy 449.200778 -59.704478)
			(xy 449.201032 -59.704478) (xy 449.221965 -59.686837) (xy 449.267933 -59.657113) (xy 449.317679 -59.634267)
			(xy 449.370181 -59.618771) (xy 449.424359 -59.610942) (xy 449.479101 -59.610942) (xy 449.533279 -59.618771)
			(xy 449.585781 -59.634267) (xy 449.635527 -59.657113) (xy 449.681495 -59.686837) (xy 449.702428 -59.704478)
			(xy 449.702682 -59.704732) (xy 449.709767 -59.710321) (xy 449.726685 -59.716565) (xy 449.735702 -59.716924)
			(xy 449.802758 -59.716924) (xy 449.811772 -59.716542) (xy 449.828689 -59.710311) (xy 449.835778 -59.704732)
			(xy 449.835778 -59.704478) (xy 449.836032 -59.704478) (xy 449.856976 -59.686854) (xy 449.902946 -59.657141)
			(xy 449.95269 -59.634302) (xy 450.005188 -59.618807) (xy 450.059362 -59.610975) (xy 450.08673 -59.610498)
			(xy 450.11398 -59.610974) (xy 450.167926 -59.618734) (xy 450.220218 -59.634092) (xy 450.269792 -59.656735)
			(xy 450.315639 -59.686203) (xy 450.356826 -59.721895) (xy 450.392515 -59.763085) (xy 450.421979 -59.808935)
			(xy 450.444619 -59.858511) (xy 450.459972 -59.910804) (xy 450.467728 -59.96475) (xy 450.467728 -60.01925)
			(xy 450.459972 -60.073196) (xy 450.444619 -60.125489) (xy 450.421979 -60.175065) (xy 450.392515 -60.220915)
			(xy 450.356826 -60.262105) (xy 450.315639 -60.297797) (xy 450.269792 -60.327265) (xy 450.220218 -60.349908)
			(xy 450.167926 -60.365266) (xy 450.11398 -60.373026) (xy 450.08673 -60.373514) (xy 450.059361 -60.373027)
			(xy 450.005183 -60.365214) (xy 449.95268 -60.349729) (xy 449.902933 -60.326892) (xy 449.856965 -60.297173)
			(xy 449.836032 -60.279534) (xy 449.835778 -60.27928) (xy 449.828704 -60.273676) (xy 449.811777 -60.26744)
			(xy 449.802758 -60.267088) (xy 449.735702 -60.267088) (xy 449.726686 -60.267449) (xy 449.709769 -60.273694)
			(xy 449.702682 -60.27928) (xy 449.702428 -60.279534) (xy 449.681495 -60.297175) (xy 449.635527 -60.326899)
			(xy 449.585781 -60.349745) (xy 449.533279 -60.365241) (xy 449.479101 -60.37307) (xy 449.424359 -60.37307)
			(xy 449.370181 -60.365241) (xy 449.317679 -60.349745) (xy 449.267933 -60.326899) (xy 449.221965 -60.297175)
			(xy 449.201032 -60.279534) (xy 449.200778 -60.27928) (xy 449.193704 -60.273676) (xy 449.176777 -60.26744)
			(xy 449.167758 -60.267088) (xy 449.100702 -60.267088) (xy 449.091686 -60.267449) (xy 449.074769 -60.273694)
			(xy 449.067682 -60.27928) (xy 449.067682 -60.279534) (xy 449.067428 -60.279534) (xy 449.046501 -60.297179)
			(xy 449.000526 -60.326889) (xy 448.950777 -60.349723) (xy 448.898276 -60.365213) (xy 448.844099 -60.37304)
			(xy 448.81673 -60.373514) (xy 448.789476 -60.373041) (xy 448.735523 -60.365287) (xy 448.683222 -60.349934)
			(xy 448.633639 -60.327294) (xy 448.587783 -60.297827) (xy 448.546587 -60.262134) (xy 448.510891 -60.220941)
			(xy 448.481421 -60.175087) (xy 448.458776 -60.125506) (xy 448.443419 -60.073206) (xy 448.435661 -60.019254)
			(xy 439.140258 -60.019254) (xy 439.141108 -60.033408) (xy 439.141108 -60.036964) (xy 439.142378 -60.06846)
			(xy 439.142378 -60.079636) (xy 439.181494 -61.327284) (xy 439.181748 -61.345318) (xy 439.181748 -61.34608)
			(xy 439.181748 -61.35243) (xy 439.181748 -61.361066) (xy 439.180986 -61.3791) (xy 439.179462 -61.398912)
			(xy 439.178192 -61.411358) (xy 439.172604 -61.449458) (xy 439.167136 -61.477712) (xy 439.15136 -61.533058)
			(xy 439.141108 -61.559948) (xy 438.537858 -63.08344) (xy 438.535997 -63.118347) (xy 438.525076 -63.187394)
			(xy 438.517689 -63.213554) (xy 448.420665 -63.213554) (xy 448.420665 -63.159046) (xy 448.428423 -63.105092)
			(xy 448.443781 -63.052793) (xy 448.466426 -63.003211) (xy 448.495898 -62.957357) (xy 448.531595 -62.916164)
			(xy 448.572792 -62.880471) (xy 448.618649 -62.851005) (xy 448.668234 -62.828366) (xy 448.720536 -62.813014)
			(xy 448.77449 -62.805262) (xy 448.801744 -62.804802) (xy 448.829113 -62.8053) (xy 448.883291 -62.81311)
			(xy 448.935794 -62.828592) (xy 448.985541 -62.851426) (xy 449.031509 -62.881144) (xy 449.052442 -62.898782)
			(xy 449.052696 -62.899036) (xy 449.059777 -62.904631) (xy 449.076698 -62.910872) (xy 449.085716 -62.911228)
			(xy 449.152772 -62.911228) (xy 449.161787 -62.910851) (xy 449.178704 -62.904617) (xy 449.185792 -62.899036)
			(xy 449.185792 -62.898782) (xy 449.186046 -62.898782) (xy 449.206979 -62.881141) (xy 449.252947 -62.851417)
			(xy 449.302693 -62.828571) (xy 449.355195 -62.813075) (xy 449.409373 -62.805246) (xy 449.464115 -62.805246)
			(xy 449.518293 -62.813075) (xy 449.570795 -62.828571) (xy 449.620541 -62.851417) (xy 449.666509 -62.881141)
			(xy 449.687442 -62.898782) (xy 449.687696 -62.899036) (xy 449.694777 -62.904631) (xy 449.711698 -62.910872)
			(xy 449.720716 -62.911228) (xy 449.787772 -62.911228) (xy 449.796787 -62.910851) (xy 449.813704 -62.904617)
			(xy 449.820792 -62.899036) (xy 449.820792 -62.898782) (xy 449.821046 -62.898782) (xy 449.841985 -62.881152)
			(xy 449.887956 -62.851439) (xy 449.937702 -62.828602) (xy 449.990201 -62.813109) (xy 450.044375 -62.805278)
			(xy 450.071744 -62.804802) (xy 450.098994 -62.805271) (xy 450.152938 -62.813033) (xy 450.205229 -62.828392)
			(xy 450.254802 -62.851036) (xy 450.300648 -62.880504) (xy 450.341834 -62.916197) (xy 450.377522 -62.957387)
			(xy 450.406985 -63.003237) (xy 450.429623 -63.052812) (xy 450.444977 -63.105105) (xy 450.452732 -63.15905)
			(xy 450.452732 -63.21355) (xy 450.444977 -63.267495) (xy 450.429623 -63.319788) (xy 450.406985 -63.369363)
			(xy 450.377522 -63.415213) (xy 450.341834 -63.456403) (xy 450.300648 -63.492096) (xy 450.254802 -63.521564)
			(xy 450.205229 -63.544208) (xy 450.152938 -63.559567) (xy 450.098994 -63.567329) (xy 450.071744 -63.567818)
			(xy 450.044374 -63.567346) (xy 449.990194 -63.559533) (xy 449.93769 -63.544046) (xy 449.887943 -63.521205)
			(xy 449.841977 -63.49148) (xy 449.821046 -63.473838) (xy 449.820792 -63.473584) (xy 449.813713 -63.467986)
			(xy 449.79679 -63.461747) (xy 449.787772 -63.461392) (xy 449.720716 -63.461392) (xy 449.7117 -63.461758)
			(xy 449.694783 -63.468) (xy 449.687696 -63.473584) (xy 449.687442 -63.473838) (xy 449.666509 -63.491479)
			(xy 449.620541 -63.521203) (xy 449.570795 -63.544049) (xy 449.518293 -63.559545) (xy 449.464115 -63.567374)
			(xy 449.409373 -63.567374) (xy 449.355195 -63.559545) (xy 449.302693 -63.544049) (xy 449.252947 -63.521203)
			(xy 449.206979 -63.491479) (xy 449.186046 -63.473838) (xy 449.185792 -63.473584) (xy 449.178713 -63.467986)
			(xy 449.16179 -63.461747) (xy 449.152772 -63.461392) (xy 449.085716 -63.461392) (xy 449.0767 -63.461758)
			(xy 449.059783 -63.468) (xy 449.052696 -63.473584) (xy 449.052696 -63.473838) (xy 449.052442 -63.473838)
			(xy 449.03151 -63.491477) (xy 448.985537 -63.521188) (xy 448.935789 -63.544023) (xy 448.883289 -63.559515)
			(xy 448.829113 -63.567344) (xy 448.801744 -63.567818) (xy 448.77449 -63.567338) (xy 448.720536 -63.559586)
			(xy 448.668234 -63.544234) (xy 448.618649 -63.521595) (xy 448.572792 -63.492129) (xy 448.531595 -63.456436)
			(xy 448.495898 -63.415243) (xy 448.466426 -63.369389) (xy 448.443781 -63.319807) (xy 448.428423 -63.267508)
			(xy 448.420665 -63.213554) (xy 438.517689 -63.213554) (xy 438.506079 -63.254669) (xy 438.493154 -63.287148)
			(xy 437.741865 -65.100962) (xy 446.43243 -65.100962) (xy 446.436501 -65.04534) (xy 446.448627 -64.990903)
			(xy 446.46855 -64.938812) (xy 446.495846 -64.890177) (xy 446.529932 -64.846034) (xy 446.570081 -64.807325)
			(xy 446.615439 -64.774874) (xy 446.665039 -64.749373) (xy 446.717823 -64.731366) (xy 446.772666 -64.721236)
			(xy 446.8284 -64.719199) (xy 446.883837 -64.725299) (xy 446.937794 -64.739405) (xy 446.989123 -64.761217)
			(xy 447.036729 -64.790271) (xy 447.079597 -64.825946) (xy 447.116814 -64.867483) (xy 447.147587 -64.913996)
			(xy 447.171259 -64.964493) (xy 447.187327 -65.0179) (xy 447.195447 -65.073076) (xy 447.195956 -65.100962)
			(xy 447.195447 -65.128848) (xy 447.187327 -65.184024) (xy 447.171259 -65.237431) (xy 447.147587 -65.287928)
			(xy 447.116814 -65.334441) (xy 447.079597 -65.375978) (xy 447.036729 -65.411653) (xy 446.989123 -65.440707)
			(xy 446.937794 -65.462519) (xy 446.883837 -65.476625) (xy 446.8284 -65.482725) (xy 446.772666 -65.480688)
			(xy 446.717823 -65.470558) (xy 446.665039 -65.452551) (xy 446.615439 -65.42705) (xy 446.570081 -65.394599)
			(xy 446.529932 -65.35589) (xy 446.495846 -65.311747) (xy 446.46855 -65.263112) (xy 446.448627 -65.211021)
			(xy 446.436501 -65.156584) (xy 446.43243 -65.100962) (xy 437.741865 -65.100962) (xy 437.66359 -65.289938)
			(xy 437.479349 -65.75552) (xy 440.646564 -65.75552) (xy 440.650635 -65.699898) (xy 440.662761 -65.645461)
			(xy 440.682684 -65.59337) (xy 440.70998 -65.544735) (xy 440.744066 -65.500592) (xy 440.784215 -65.461883)
			(xy 440.829573 -65.429432) (xy 440.879173 -65.403931) (xy 440.931957 -65.385924) (xy 440.9868 -65.375794)
			(xy 441.042534 -65.373757) (xy 441.097971 -65.379857) (xy 441.151928 -65.393963) (xy 441.203257 -65.415775)
			(xy 441.250863 -65.444829) (xy 441.293731 -65.480504) (xy 441.330948 -65.522041) (xy 441.361721 -65.568554)
			(xy 441.385393 -65.619051) (xy 441.401461 -65.672458) (xy 441.409581 -65.727634) (xy 441.41009 -65.75552)
			(xy 441.409581 -65.783406) (xy 441.401461 -65.838582) (xy 441.385393 -65.891989) (xy 441.361721 -65.942486)
			(xy 441.330948 -65.988999) (xy 441.293731 -66.030536) (xy 441.250863 -66.066211) (xy 441.203257 -66.095265)
			(xy 441.151928 -66.117077) (xy 441.097971 -66.131183) (xy 441.042534 -66.137283) (xy 440.9868 -66.135246)
			(xy 440.931957 -66.125116) (xy 440.879173 -66.107109) (xy 440.829573 -66.081608) (xy 440.784215 -66.049157)
			(xy 440.744066 -66.010448) (xy 440.70998 -65.966305) (xy 440.682684 -65.91767) (xy 440.662761 -65.865579)
			(xy 440.650635 -65.811142) (xy 440.646564 -65.75552) (xy 437.479349 -65.75552) (xy 437.174894 -66.524886)
			(xy 437.162711 -66.554388) (xy 437.132798 -66.610777) (xy 437.115204 -66.637408) (xy 437.109616 -66.645536)
			(xy 437.088026 -66.674238) (xy 437.086756 -66.676016) (xy 437.070563 -66.705611) (xy 437.032401 -66.761245)
			(xy 436.988137 -66.812158) (xy 436.963566 -66.835274) (xy 436.669887 -67.128953) (xy 440.666575 -67.128953)
			(xy 440.666575 -67.074447) (xy 440.674333 -67.020496) (xy 440.68969 -66.968199) (xy 440.712333 -66.918619)
			(xy 440.741803 -66.872767) (xy 440.777498 -66.831575) (xy 440.818692 -66.795883) (xy 440.864547 -66.766418)
			(xy 440.914129 -66.743778) (xy 440.966428 -66.728426) (xy 441.020379 -66.720673) (xy 441.047632 -66.720212)
			(xy 441.075003 -66.720656) (xy 441.129183 -66.728479) (xy 441.181687 -66.743973) (xy 441.231433 -66.76682)
			(xy 441.277399 -66.796549) (xy 441.29833 -66.814192) (xy 441.298584 -66.814446) (xy 441.305667 -66.820038)
			(xy 441.322587 -66.82628) (xy 441.331604 -66.826638) (xy 441.39866 -66.826638) (xy 441.407674 -66.826254)
			(xy 441.424591 -66.820024) (xy 441.43168 -66.814446) (xy 441.43168 -66.814192) (xy 441.431934 -66.814192)
			(xy 441.452879 -66.796569) (xy 441.498848 -66.766855) (xy 441.548593 -66.744016) (xy 441.60109 -66.728521)
			(xy 441.655264 -66.720689) (xy 441.682632 -66.720212) (xy 441.709883 -66.72066) (xy 441.76383 -66.728421)
			(xy 441.816124 -66.743779) (xy 441.8657 -66.766423) (xy 441.911549 -66.795892) (xy 441.952737 -66.831586)
			(xy 441.988427 -66.872777) (xy 442.017892 -66.918628) (xy 442.040532 -66.968206) (xy 442.055886 -67.020501)
			(xy 442.063642 -67.074449) (xy 442.063642 -67.128951) (xy 442.055886 -67.182899) (xy 442.040532 -67.235194)
			(xy 442.017892 -67.284772) (xy 441.988427 -67.330623) (xy 441.952737 -67.371814) (xy 441.911549 -67.407508)
			(xy 441.8657 -67.436977) (xy 441.816124 -67.459621) (xy 441.76383 -67.474979) (xy 441.709883 -67.48274)
			(xy 441.682632 -67.483228) (xy 441.655262 -67.482761) (xy 441.601082 -67.474946) (xy 441.548578 -67.459458)
			(xy 441.498831 -67.436616) (xy 441.452865 -67.40689) (xy 441.431934 -67.389248) (xy 441.43168 -67.388994)
			(xy 441.424604 -67.383392) (xy 441.407679 -67.377155) (xy 441.39866 -67.376802) (xy 441.331604 -67.376802)
			(xy 441.322587 -67.37716) (xy 441.30567 -67.383407) (xy 441.298584 -67.388994) (xy 441.298584 -67.389248)
			(xy 441.29833 -67.389248) (xy 441.277391 -67.406878) (xy 441.231421 -67.436593) (xy 441.181675 -67.459432)
			(xy 441.129176 -67.474925) (xy 441.075001 -67.482754) (xy 441.047632 -67.483228) (xy 441.020379 -67.482727)
			(xy 440.966428 -67.474974) (xy 440.914129 -67.459622) (xy 440.864547 -67.436982) (xy 440.818692 -67.407516)
			(xy 440.777498 -67.371825) (xy 440.741803 -67.330633) (xy 440.712333 -67.284781) (xy 440.68969 -67.235201)
			(xy 440.674333 -67.182904) (xy 440.666575 -67.128953) (xy 436.669887 -67.128953) (xy 436.310786 -67.488054)
			(xy 445.079118 -67.488054) (xy 445.083189 -67.432432) (xy 445.095315 -67.377995) (xy 445.115238 -67.325904)
			(xy 445.142534 -67.277269) (xy 445.17662 -67.233126) (xy 445.216769 -67.194417) (xy 445.262127 -67.161966)
			(xy 445.311727 -67.136465) (xy 445.364511 -67.118458) (xy 445.419354 -67.108328) (xy 445.475088 -67.106291)
			(xy 445.530525 -67.112391) (xy 445.584482 -67.126497) (xy 445.635811 -67.148309) (xy 445.683417 -67.177363)
			(xy 445.726285 -67.213038) (xy 445.763502 -67.254575) (xy 445.794275 -67.301088) (xy 445.817947 -67.351585)
			(xy 445.834015 -67.404992) (xy 445.842135 -67.460168) (xy 445.842644 -67.488054) (xy 445.842135 -67.51594)
			(xy 445.83895 -67.537584) (xy 446.371216 -67.537584) (xy 446.375287 -67.481962) (xy 446.387413 -67.427525)
			(xy 446.407336 -67.375434) (xy 446.434632 -67.326799) (xy 446.468718 -67.282656) (xy 446.508867 -67.243947)
			(xy 446.554225 -67.211496) (xy 446.603825 -67.185995) (xy 446.656609 -67.167988) (xy 446.711452 -67.157858)
			(xy 446.767186 -67.155821) (xy 446.822623 -67.161921) (xy 446.87658 -67.176027) (xy 446.927909 -67.197839)
			(xy 446.975515 -67.226893) (xy 447.018383 -67.262568) (xy 447.0556 -67.304105) (xy 447.086373 -67.350618)
			(xy 447.110045 -67.401115) (xy 447.126113 -67.454522) (xy 447.134233 -67.509698) (xy 447.134742 -67.537584)
			(xy 447.134233 -67.56547) (xy 447.130188 -67.592956) (xy 447.64528 -67.592956) (xy 447.649351 -67.537334)
			(xy 447.661477 -67.482897) (xy 447.6814 -67.430806) (xy 447.708696 -67.382171) (xy 447.742782 -67.338028)
			(xy 447.782931 -67.299319) (xy 447.828289 -67.266868) (xy 447.877889 -67.241367) (xy 447.930673 -67.22336)
			(xy 447.985516 -67.21323) (xy 448.04125 -67.211193) (xy 448.096687 -67.217293) (xy 448.150644 -67.231399)
			(xy 448.201973 -67.253211) (xy 448.249579 -67.282265) (xy 448.292447 -67.31794) (xy 448.329664 -67.359477)
			(xy 448.360437 -67.40599) (xy 448.384109 -67.456487) (xy 448.400177 -67.509894) (xy 448.408294 -67.565051)
			(xy 450.746593 -67.565051) (xy 450.746593 -67.510549) (xy 450.75435 -67.456601) (xy 450.769706 -67.404307)
			(xy 450.792348 -67.35473) (xy 450.821815 -67.308881) (xy 450.857507 -67.267692) (xy 450.898698 -67.232001)
			(xy 450.94455 -67.202537) (xy 450.994128 -67.179898) (xy 451.046423 -67.164545) (xy 451.100371 -67.156792)
			(xy 451.127622 -67.15633) (xy 451.154993 -67.156776) (xy 451.209173 -67.164597) (xy 451.261677 -67.180091)
			(xy 451.311423 -67.202937) (xy 451.357389 -67.232666) (xy 451.37832 -67.25031) (xy 451.378574 -67.250564)
			(xy 451.385658 -67.256153) (xy 451.402577 -67.262397) (xy 451.411594 -67.262756) (xy 451.47865 -67.262756)
			(xy 451.487666 -67.262385) (xy 451.504583 -67.256148) (xy 451.51167 -67.250564) (xy 451.51167 -67.25031)
			(xy 451.511924 -67.25031) (xy 451.532875 -67.232695) (xy 451.578843 -67.202979) (xy 451.628585 -67.180138)
			(xy 451.681082 -67.164642) (xy 451.735254 -67.156807) (xy 451.762622 -67.15633) (xy 451.789875 -67.156741)
			(xy 451.843826 -67.164501) (xy 451.896123 -67.17986) (xy 451.945702 -67.202504) (xy 451.991555 -67.231974)
			(xy 452.032746 -67.267669) (xy 452.068439 -67.308863) (xy 452.097906 -67.354717) (xy 452.120548 -67.404298)
			(xy 452.135903 -67.456596) (xy 452.14366 -67.510547) (xy 452.14366 -67.565053) (xy 452.135903 -67.619004)
			(xy 452.120548 -67.671302) (xy 452.097906 -67.720883) (xy 452.068439 -67.766737) (xy 452.032746 -67.807931)
			(xy 451.991555 -67.843626) (xy 451.945702 -67.873096) (xy 451.896123 -67.89574) (xy 451.843826 -67.911099)
			(xy 451.789875 -67.918859) (xy 451.762622 -67.919346) (xy 451.735252 -67.91888) (xy 451.681072 -67.911064)
			(xy 451.628568 -67.895576) (xy 451.578821 -67.872734) (xy 451.532855 -67.843008) (xy 451.511924 -67.825366)
			(xy 451.51167 -67.825112) (xy 451.504567 -67.81955) (xy 451.487663 -67.813288) (xy 451.47865 -67.81292)
			(xy 451.411594 -67.81292) (xy 451.402576 -67.81327) (xy 451.385659 -67.819522) (xy 451.378574 -67.825112)
			(xy 451.378574 -67.825366) (xy 451.37832 -67.825366) (xy 451.357387 -67.843004) (xy 451.311415 -67.872717)
			(xy 451.261668 -67.895554) (xy 451.209167 -67.911045) (xy 451.154991 -67.918873) (xy 451.127622 -67.919346)
			(xy 451.100371 -67.918808) (xy 451.046423 -67.911055) (xy 450.994128 -67.895702) (xy 450.94455 -67.873063)
			(xy 450.898698 -67.843599) (xy 450.857507 -67.807908) (xy 450.821815 -67.766719) (xy 450.792348 -67.72087)
			(xy 450.769706 -67.671293) (xy 450.75435 -67.618999) (xy 450.746593 -67.565051) (xy 448.408294 -67.565051)
			(xy 448.408297 -67.56507) (xy 448.408806 -67.592956) (xy 448.408297 -67.620842) (xy 448.400177 -67.676018)
			(xy 448.384109 -67.729425) (xy 448.360437 -67.779922) (xy 448.329664 -67.826435) (xy 448.292447 -67.867972)
			(xy 448.249579 -67.903647) (xy 448.201973 -67.932701) (xy 448.150644 -67.954513) (xy 448.096687 -67.968619)
			(xy 448.04125 -67.974719) (xy 447.985516 -67.972682) (xy 447.930673 -67.962552) (xy 447.877889 -67.944545)
			(xy 447.828289 -67.919044) (xy 447.782931 -67.886593) (xy 447.742782 -67.847884) (xy 447.708696 -67.803741)
			(xy 447.6814 -67.755106) (xy 447.661477 -67.703015) (xy 447.649351 -67.648578) (xy 447.64528 -67.592956)
			(xy 447.130188 -67.592956) (xy 447.126113 -67.620646) (xy 447.110045 -67.674053) (xy 447.086373 -67.72455)
			(xy 447.0556 -67.771063) (xy 447.018383 -67.8126) (xy 446.975515 -67.848275) (xy 446.927909 -67.877329)
			(xy 446.87658 -67.899141) (xy 446.822623 -67.913247) (xy 446.767186 -67.919347) (xy 446.711452 -67.91731)
			(xy 446.656609 -67.90718) (xy 446.603825 -67.889173) (xy 446.554225 -67.863672) (xy 446.508867 -67.831221)
			(xy 446.468718 -67.792512) (xy 446.434632 -67.748369) (xy 446.407336 -67.699734) (xy 446.387413 -67.647643)
			(xy 446.375287 -67.593206) (xy 446.371216 -67.537584) (xy 445.83895 -67.537584) (xy 445.834015 -67.571116)
			(xy 445.817947 -67.624523) (xy 445.794275 -67.67502) (xy 445.763502 -67.721533) (xy 445.726285 -67.76307)
			(xy 445.683417 -67.798745) (xy 445.635811 -67.827799) (xy 445.584482 -67.849611) (xy 445.530525 -67.863717)
			(xy 445.475088 -67.869817) (xy 445.419354 -67.86778) (xy 445.364511 -67.85765) (xy 445.311727 -67.839643)
			(xy 445.262127 -67.814142) (xy 445.216769 -67.781691) (xy 445.17662 -67.742982) (xy 445.142534 -67.698839)
			(xy 445.115238 -67.650204) (xy 445.095315 -67.598113) (xy 445.083189 -67.543676) (xy 445.079118 -67.488054)
			(xy 436.310786 -67.488054) (xy 435.212236 -68.586604) (xy 442.9252 -68.586604) (xy 442.925668 -68.559234)
			(xy 442.933486 -68.505055) (xy 442.948974 -68.452552) (xy 442.971815 -68.402805) (xy 443.001539 -68.356838)
			(xy 443.01918 -68.335906) (xy 443.019434 -68.335652) (xy 443.025009 -68.328557) (xy 443.031261 -68.311647)
			(xy 443.031626 -68.302632) (xy 443.031626 -68.235576) (xy 443.031275 -68.226559) (xy 443.025023 -68.209642)
			(xy 443.019434 -68.202556) (xy 443.01918 -68.202556) (xy 443.01918 -68.202302) (xy 443.001525 -68.181383)
			(xy 442.971816 -68.135406) (xy 442.948984 -68.085655) (xy 442.933496 -68.033152) (xy 442.925672 -67.978974)
			(xy 442.9252 -67.951604) (xy 442.925659 -67.924351) (xy 442.933416 -67.870399) (xy 442.948772 -67.818101)
			(xy 442.971414 -67.76852) (xy 443.000883 -67.722667) (xy 443.036577 -67.681474) (xy 443.07777 -67.64578)
			(xy 443.123624 -67.616312) (xy 443.173205 -67.59367) (xy 443.225503 -67.578315) (xy 443.279455 -67.570559)
			(xy 443.306708 -67.570096) (xy 443.333022 -67.570559) (xy 443.385151 -67.577795) (xy 443.435793 -67.592115)
			(xy 443.483992 -67.613248) (xy 443.528836 -67.640795) (xy 443.569475 -67.674234) (xy 443.587632 -67.693286)
			(xy 443.595142 -67.700702) (xy 443.614431 -67.709218) (xy 443.62497 -67.709796) (xy 443.699646 -67.709796)
			(xy 443.710194 -67.709253) (xy 443.72949 -67.700728) (xy 443.736984 -67.693286) (xy 443.755152 -67.674243)
			(xy 443.795779 -67.640785) (xy 443.840617 -67.613225) (xy 443.888815 -67.592084) (xy 443.93946 -67.577764)
			(xy 443.991593 -67.570536) (xy 444.017908 -67.570096) (xy 444.045278 -67.570558) (xy 444.099458 -67.578377)
			(xy 444.151961 -67.593867) (xy 444.201707 -67.61671) (xy 444.247674 -67.646435) (xy 444.268606 -67.664076)
			(xy 444.26886 -67.66433) (xy 444.275951 -67.669909) (xy 444.292865 -67.676159) (xy 444.30188 -67.676522)
			(xy 444.368936 -67.676522) (xy 444.377954 -67.676178) (xy 444.394871 -67.669921) (xy 444.401956 -67.66433)
			(xy 444.401956 -67.664076) (xy 444.40221 -67.664076) (xy 444.423124 -67.646415) (xy 444.469102 -67.616707)
			(xy 444.518854 -67.593876) (xy 444.571359 -67.57839) (xy 444.625538 -67.570567) (xy 444.652908 -67.570096)
			(xy 444.68016 -67.57057) (xy 444.734108 -67.578328) (xy 444.786403 -67.593684) (xy 444.835981 -67.616327)
			(xy 444.881831 -67.645794) (xy 444.923022 -67.681487) (xy 444.958713 -67.722678) (xy 444.988179 -67.76853)
			(xy 445.01082 -67.818108) (xy 445.026174 -67.870404) (xy 445.03393 -67.924352) (xy 445.034416 -67.951604)
			(xy 445.033973 -67.978975) (xy 445.026153 -68.033156) (xy 445.010659 -68.08566) (xy 444.987812 -68.135407)
			(xy 444.958081 -68.181372) (xy 444.940436 -68.202302) (xy 444.940182 -68.202556) (xy 444.934606 -68.20965)
			(xy 444.928353 -68.226561) (xy 444.92799 -68.235576) (xy 444.92799 -68.302632) (xy 444.928334 -68.31165)
			(xy 444.934591 -68.328567) (xy 444.940182 -68.335652) (xy 444.940436 -68.335652) (xy 444.940436 -68.335906)
			(xy 444.958097 -68.35682) (xy 444.987804 -68.402799) (xy 445.010635 -68.452551) (xy 445.026121 -68.505055)
			(xy 445.033945 -68.559234) (xy 445.034416 -68.586604) (xy 445.033926 -68.613855) (xy 445.026169 -68.667802)
			(xy 445.010814 -68.720096) (xy 444.994175 -68.75653) (xy 448.470274 -68.75653) (xy 448.47074 -68.72916)
			(xy 448.478555 -68.67498) (xy 448.494043 -68.622476) (xy 448.516885 -68.572729) (xy 448.546612 -68.526763)
			(xy 448.564254 -68.505832) (xy 448.564508 -68.505578) (xy 448.570111 -68.498503) (xy 448.576347 -68.481577)
			(xy 448.5767 -68.472558) (xy 448.5767 -68.405502) (xy 448.576342 -68.396485) (xy 448.570095 -68.379568)
			(xy 448.564508 -68.372482) (xy 448.564254 -68.372482) (xy 448.564254 -68.372228) (xy 448.546623 -68.351289)
			(xy 448.516908 -68.305319) (xy 448.49407 -68.255573) (xy 448.478577 -68.203074) (xy 448.470748 -68.148899)
			(xy 448.470274 -68.12153) (xy 448.470783 -68.094279) (xy 448.478536 -68.04033) (xy 448.493887 -67.988034)
			(xy 448.516525 -67.938456) (xy 448.545988 -67.892603) (xy 448.581677 -67.851411) (xy 448.622865 -67.815717)
			(xy 448.668713 -67.786248) (xy 448.718289 -67.763604) (xy 448.770583 -67.748246) (xy 448.824531 -67.740487)
			(xy 448.851782 -67.740022) (xy 448.879152 -67.740493) (xy 448.933331 -67.748309) (xy 448.985834 -67.763797)
			(xy 449.035581 -67.786637) (xy 449.081548 -67.816361) (xy 449.10248 -67.834002) (xy 449.102734 -67.834256)
			(xy 449.10983 -67.839828) (xy 449.12674 -67.846082) (xy 449.135754 -67.846448) (xy 449.20281 -67.846448)
			(xy 449.211829 -67.846107) (xy 449.228746 -67.839849) (xy 449.23583 -67.834256) (xy 449.23583 -67.834002)
			(xy 449.236084 -67.834002) (xy 449.257012 -67.816357) (xy 449.302986 -67.786646) (xy 449.352734 -67.763811)
			(xy 449.405236 -67.748322) (xy 449.459413 -67.740495) (xy 449.486782 -67.740022) (xy 449.513096 -67.740494)
			(xy 449.565224 -67.747727) (xy 449.615867 -67.762045) (xy 449.664067 -67.783176) (xy 449.70891 -67.810722)
			(xy 449.74955 -67.84416) (xy 449.767706 -67.863212) (xy 449.775222 -67.87062) (xy 449.794506 -67.879141)
			(xy 449.805044 -67.879722) (xy 449.87972 -67.879722) (xy 449.890265 -67.879157) (xy 449.909561 -67.870646)
			(xy 449.917058 -67.863212) (xy 449.935195 -67.844138) (xy 449.975828 -67.810682) (xy 450.020672 -67.783125)
			(xy 450.068877 -67.76199) (xy 450.119528 -67.747677) (xy 450.171665 -67.740457) (xy 450.197982 -67.740022)
			(xy 450.225236 -67.740472) (xy 450.279189 -67.748227) (xy 450.331489 -67.763583) (xy 450.381071 -67.786225)
			(xy 450.426925 -67.815694) (xy 450.468119 -67.851389) (xy 450.503813 -67.892584) (xy 450.53328 -67.93844)
			(xy 450.555921 -67.988023) (xy 450.571275 -68.040323) (xy 450.579029 -68.094276) (xy 450.57949 -68.12153)
			(xy 450.579044 -68.148901) (xy 450.571222 -68.203081) (xy 450.555728 -68.255584) (xy 450.532882 -68.305331)
			(xy 450.503153 -68.351297) (xy 450.48551 -68.372228) (xy 450.485256 -68.372482) (xy 450.479666 -68.379566)
			(xy 450.473422 -68.396485) (xy 450.473064 -68.405502) (xy 450.473064 -68.472558) (xy 450.473449 -68.481572)
			(xy 450.479678 -68.498489) (xy 450.485256 -68.505578) (xy 450.48551 -68.505578) (xy 450.48551 -68.505832)
			(xy 450.503132 -68.526778) (xy 450.532846 -68.572747) (xy 450.555685 -68.622491) (xy 450.57118 -68.674989)
			(xy 450.579013 -68.729162) (xy 450.57949 -68.75653) (xy 450.57905 -68.783783) (xy 450.571289 -68.837733)
			(xy 450.555929 -68.89003) (xy 450.533283 -68.939608) (xy 450.503812 -68.985459) (xy 450.468116 -69.02665)
			(xy 450.426921 -69.062341) (xy 450.381066 -69.091806) (xy 450.331485 -69.114446) (xy 450.279186 -69.129799)
			(xy 450.225235 -69.137553) (xy 450.197982 -69.138038) (xy 450.171667 -69.137602) (xy 450.119536 -69.130364)
			(xy 450.068892 -69.11604) (xy 450.020693 -69.094902) (xy 449.97585 -69.067349) (xy 449.935213 -69.033903)
			(xy 449.917058 -69.014848) (xy 449.909547 -69.007433) (xy 449.890259 -68.998915) (xy 449.87972 -68.998338)
			(xy 449.805044 -68.998338) (xy 449.794494 -68.998866) (xy 449.775198 -69.007401) (xy 449.767706 -69.014848)
			(xy 449.74955 -69.033903) (xy 449.708919 -69.067358) (xy 449.664079 -69.094916) (xy 449.615878 -69.116054)
			(xy 449.565231 -69.130372) (xy 449.513098 -69.137598) (xy 449.486782 -69.138038) (xy 449.459411 -69.137598)
			(xy 449.40523 -69.129776) (xy 449.352726 -69.114282) (xy 449.302979 -69.091434) (xy 449.257014 -69.061703)
			(xy 449.236084 -69.044058) (xy 449.23583 -69.043804) (xy 449.228739 -69.038224) (xy 449.211826 -69.031973)
			(xy 449.20281 -69.031612) (xy 449.135754 -69.031612) (xy 449.126739 -69.031992) (xy 449.109822 -69.038224)
			(xy 449.102734 -69.043804) (xy 449.102734 -69.044058) (xy 449.10248 -69.044058) (xy 449.081523 -69.061667)
			(xy 449.035558 -69.091384) (xy 448.985817 -69.114227) (xy 448.933321 -69.129725) (xy 448.87915 -69.13756)
			(xy 448.851782 -69.138038) (xy 448.824532 -69.137539) (xy 448.770586 -69.129781) (xy 448.718293 -69.114425)
			(xy 448.668718 -69.091784) (xy 448.622869 -69.062319) (xy 448.58168 -69.026629) (xy 448.545989 -68.98544)
			(xy 448.516522 -68.939593) (xy 448.493879 -68.890018) (xy 448.478522 -68.837726) (xy 448.470762 -68.78378)
			(xy 448.470274 -68.75653) (xy 444.994175 -68.75653) (xy 444.988173 -68.769673) (xy 444.958707 -68.815523)
			(xy 444.923016 -68.856713) (xy 444.881826 -68.892404) (xy 444.835977 -68.921871) (xy 444.7864 -68.944512)
			(xy 444.734106 -68.959868) (xy 444.680159 -68.967626) (xy 444.652908 -68.968112) (xy 444.625538 -68.967638)
			(xy 444.571359 -68.959822) (xy 444.518857 -68.944334) (xy 444.46911 -68.921494) (xy 444.423142 -68.891772)
			(xy 444.40221 -68.874132) (xy 444.401956 -68.873878) (xy 444.394859 -68.868306) (xy 444.37795 -68.862051)
			(xy 444.368936 -68.861686) (xy 444.30188 -68.861686) (xy 444.292863 -68.862037) (xy 444.275946 -68.868289)
			(xy 444.26886 -68.873878) (xy 444.26886 -68.874132) (xy 444.268606 -68.874132) (xy 444.247687 -68.891787)
			(xy 444.20171 -68.921495) (xy 444.151959 -68.944328) (xy 444.099456 -68.959815) (xy 444.045278 -68.96764)
			(xy 444.017908 -68.968112) (xy 443.991594 -68.967635) (xy 443.939466 -68.960402) (xy 443.888824 -68.946084)
			(xy 443.840625 -68.924954) (xy 443.795781 -68.897409) (xy 443.755141 -68.863973) (xy 443.736984 -68.844922)
			(xy 443.729467 -68.837515) (xy 443.710184 -68.828993) (xy 443.699646 -68.828412) (xy 443.62497 -68.828412)
			(xy 443.614423 -68.828962) (xy 443.595127 -68.837482) (xy 443.587632 -68.844922) (xy 443.569507 -68.864008)
			(xy 443.52887 -68.897461) (xy 443.484023 -68.925016) (xy 443.435817 -68.946149) (xy 443.385164 -68.96046)
			(xy 443.333026 -68.967677) (xy 443.306708 -68.968112) (xy 443.279456 -68.967637) (xy 443.225505 -68.959881)
			(xy 443.173208 -68.944527) (xy 443.123628 -68.921885) (xy 443.077775 -68.892419) (xy 443.036582 -68.856726)
			(xy 443.000889 -68.815535) (xy 442.97142 -68.769683) (xy 442.948778 -68.720103) (xy 442.933421 -68.667807)
			(xy 442.925664 -68.613856) (xy 442.9252 -68.586604) (xy 435.212236 -68.586604) (xy 432.242976 -71.555864)
			(xy 445.494408 -71.555864) (xy 445.498479 -71.500242) (xy 445.510605 -71.445805) (xy 445.530528 -71.393714)
			(xy 445.557824 -71.345079) (xy 445.59191 -71.300936) (xy 445.632059 -71.262227) (xy 445.677417 -71.229776)
			(xy 445.727017 -71.204275) (xy 445.779801 -71.186268) (xy 445.834644 -71.176138) (xy 445.890378 -71.174101)
			(xy 445.945815 -71.180201) (xy 445.999772 -71.194307) (xy 446.051101 -71.216119) (xy 446.098707 -71.245173)
			(xy 446.141575 -71.280848) (xy 446.178792 -71.322385) (xy 446.209565 -71.368898) (xy 446.233237 -71.419395)
			(xy 446.249305 -71.472802) (xy 446.257425 -71.527978) (xy 446.257934 -71.555864) (xy 446.257425 -71.58375)
			(xy 446.251586 -71.623428) (xy 447.003422 -71.623428) (xy 447.007493 -71.567806) (xy 447.019619 -71.513369)
			(xy 447.039542 -71.461278) (xy 447.066838 -71.412643) (xy 447.100924 -71.3685) (xy 447.141073 -71.329791)
			(xy 447.186431 -71.29734) (xy 447.236031 -71.271839) (xy 447.288815 -71.253832) (xy 447.343658 -71.243702)
			(xy 447.399392 -71.241665) (xy 447.454829 -71.247765) (xy 447.508786 -71.261871) (xy 447.560115 -71.283683)
			(xy 447.607721 -71.312737) (xy 447.650589 -71.348412) (xy 447.687806 -71.389949) (xy 447.718579 -71.436462)
			(xy 447.742251 -71.486959) (xy 447.758319 -71.540366) (xy 447.766439 -71.595542) (xy 447.766948 -71.623428)
			(xy 447.766439 -71.651314) (xy 447.758319 -71.70649) (xy 447.742251 -71.759897) (xy 447.718579 -71.810394)
			(xy 447.687806 -71.856907) (xy 447.650589 -71.898444) (xy 447.607721 -71.934119) (xy 447.560115 -71.963173)
			(xy 447.508786 -71.984985) (xy 447.454829 -71.999091) (xy 447.399392 -72.005191) (xy 447.343658 -72.003154)
			(xy 447.288815 -71.993024) (xy 447.236031 -71.975017) (xy 447.186431 -71.949516) (xy 447.141073 -71.917065)
			(xy 447.100924 -71.878356) (xy 447.066838 -71.834213) (xy 447.039542 -71.785578) (xy 447.019619 -71.733487)
			(xy 447.007493 -71.67905) (xy 447.003422 -71.623428) (xy 446.251586 -71.623428) (xy 446.249305 -71.638926)
			(xy 446.233237 -71.692333) (xy 446.209565 -71.74283) (xy 446.178792 -71.789343) (xy 446.141575 -71.83088)
			(xy 446.098707 -71.866555) (xy 446.051101 -71.895609) (xy 445.999772 -71.917421) (xy 445.945815 -71.931527)
			(xy 445.890378 -71.937627) (xy 445.834644 -71.93559) (xy 445.779801 -71.92546) (xy 445.727017 -71.907453)
			(xy 445.677417 -71.881952) (xy 445.632059 -71.849501) (xy 445.59191 -71.810792) (xy 445.557824 -71.766649)
			(xy 445.530528 -71.718014) (xy 445.510605 -71.665923) (xy 445.498479 -71.611486) (xy 445.494408 -71.555864)
			(xy 432.242976 -71.555864) (xy 430.81956 -72.97928) (xy 432.334668 -72.97928) (xy 432.338739 -72.923658)
			(xy 432.350865 -72.869221) (xy 432.370788 -72.81713) (xy 432.398084 -72.768495) (xy 432.43217 -72.724352)
			(xy 432.472319 -72.685643) (xy 432.517677 -72.653192) (xy 432.567277 -72.627691) (xy 432.620061 -72.609684)
			(xy 432.674904 -72.599554) (xy 432.730638 -72.597517) (xy 432.786075 -72.603617) (xy 432.840032 -72.617723)
			(xy 432.891361 -72.639535) (xy 432.938967 -72.668589) (xy 432.981835 -72.704264) (xy 433.019052 -72.745801)
			(xy 433.049825 -72.792314) (xy 433.073497 -72.842811) (xy 433.089565 -72.896218) (xy 433.097685 -72.951394)
			(xy 433.098194 -72.97928) (xy 433.097685 -73.007166) (xy 433.089565 -73.062342) (xy 433.073497 -73.115749)
			(xy 433.049825 -73.166246) (xy 433.019052 -73.212759) (xy 432.981835 -73.254296) (xy 432.938967 -73.289971)
			(xy 432.891361 -73.319025) (xy 432.840032 -73.340837) (xy 432.786075 -73.354943) (xy 432.730638 -73.361043)
			(xy 432.674904 -73.359006) (xy 432.620061 -73.348876) (xy 432.567277 -73.330869) (xy 432.517677 -73.305368)
			(xy 432.472319 -73.272917) (xy 432.43217 -73.234208) (xy 432.398084 -73.190065) (xy 432.370788 -73.14143)
			(xy 432.350865 -73.089339) (xy 432.338739 -73.034902) (xy 432.334668 -72.97928) (xy 430.81956 -72.97928)
			(xy 430.153064 -73.645776) (xy 430.146223 -73.653176) (xy 430.138506 -73.671775) (xy 430.138078 -73.681844)
			(xy 430.138078 -74.503788) (xy 430.138332 -74.508614) (xy 430.138332 -74.508868) (xy 430.139284 -74.515597)
			(xy 430.144303 -74.52822) (xy 430.148238 -74.53376) (xy 430.15281 -74.539094) (xy 430.267364 -74.653648)
			(xy 430.272698 -74.65822) (xy 431.568352 -74.65822) (xy 431.572166 -74.655159) (xy 431.578681 -74.647868)
			(xy 431.581306 -74.643742) (xy 431.58537 -74.63536) (xy 431.618898 -74.54646) (xy 431.621393 -74.539097)
			(xy 431.622294 -74.523584) (xy 431.620676 -74.51598) (xy 431.618898 -74.508868) (xy 431.611024 -74.495914)
			(xy 431.604928 -74.49058) (xy 431.604166 -74.489818) (xy 431.60315 -74.489056) (xy 431.583383 -74.470867)
			(xy 431.548642 -74.429898) (xy 431.519988 -74.384464) (xy 431.497986 -74.335461) (xy 431.483072 -74.283857)
			(xy 431.475539 -74.230672) (xy 431.475134 -74.203814) (xy 431.47562 -74.176563) (xy 431.483376 -74.122615)
			(xy 431.498731 -74.07032) (xy 431.521373 -74.020743) (xy 431.550839 -73.974893) (xy 431.58653 -73.933702)
			(xy 431.627721 -73.898011) (xy 431.673571 -73.868545) (xy 431.723148 -73.845903) (xy 431.775443 -73.830548)
			(xy 431.829391 -73.822792) (xy 431.883893 -73.822792) (xy 431.937841 -73.830548) (xy 431.990136 -73.845903)
			(xy 432.039713 -73.868545) (xy 432.085563 -73.898011) (xy 432.126754 -73.933702) (xy 432.162445 -73.974893)
			(xy 432.191911 -74.020743) (xy 432.214553 -74.07032) (xy 432.229908 -74.122615) (xy 432.237664 -74.176563)
			(xy 432.23815 -74.203814) (xy 432.237692 -74.23067) (xy 432.230163 -74.283851) (xy 432.215256 -74.335452)
			(xy 432.193266 -74.384455) (xy 432.164625 -74.429893) (xy 432.129899 -74.470869) (xy 432.110134 -74.489056)
			(xy 432.109118 -74.489818) (xy 432.10607 -74.492866) (xy 432.099529 -74.500078) (xy 432.091966 -74.518002)
			(xy 432.091628 -74.537452) (xy 432.09464 -74.546714) (xy 432.116992 -74.605896) (xy 432.116992 -74.606404)
			(xy 432.127914 -74.63536) (xy 432.132994 -74.645266) (xy 432.135472 -74.648937) (xy 432.141477 -74.655448)
			(xy 432.144932 -74.65822) (xy 452.31304 -74.65822) (xy 452.323107 -74.65779) (xy 452.341703 -74.650068)
			(xy 452.349108 -74.643234) (xy 457.925678 -69.06641) (xy 457.932528 -69.059013) (xy 457.94027 -69.040415)
			(xy 457.940664 -69.030342) (xy 457.940664 -35.827208) (xy 457.940242 -35.817138) (xy 457.932525 -35.798535)
			(xy 457.925678 -35.79114) (xy 452.498206 -30.363668) (xy 452.475309 -30.340103) (xy 452.434357 -30.288719)
			(xy 452.399411 -30.233076) (xy 452.370908 -30.173873) (xy 452.349208 -30.111853) (xy 452.334583 -30.047794)
			(xy 452.327215 -29.982501) (xy 452.326756 -29.949648) (xy 452.326756 -25.877012) (xy 452.327216 -25.844158)
			(xy 452.33457 -25.778863) (xy 452.349189 -25.714801) (xy 452.370888 -25.652779) (xy 452.399393 -25.593576)
			(xy 452.434348 -25.537937) (xy 452.475311 -25.48656) (xy 452.498206 -25.462992) (xy 453.573896 -24.387302)
			(xy 453.57415 -24.375364) (xy 453.572118 -24.353012) (xy 453.572118 -24.352504) (xy 453.568308 -24.313642)
			(xy 453.567611 -24.307798) (xy 453.563891 -24.296637) (xy 453.560942 -24.291544) (xy 453.555354 -24.2824)
			(xy 453.545702 -24.27605) (xy 453.522693 -24.260351) (xy 453.480918 -24.223507) (xy 453.444749 -24.181147)
			(xy 453.414907 -24.134115) (xy 453.391986 -24.083349) (xy 453.376443 -24.029861) (xy 453.368589 -23.974716)
			(xy 453.368156 -23.946866) (xy 453.368608 -23.920074) (xy 453.375872 -23.866985) (xy 453.390262 -23.81537)
			(xy 453.411511 -23.76618) (xy 453.439229 -23.720322) (xy 453.472903 -23.678642) (xy 453.511914 -23.641909)
			(xy 453.555542 -23.610799) (xy 453.602983 -23.585887) (xy 453.627998 -23.57628) (xy 453.637904 -23.572724)
			(xy 453.643327 -23.570564) (xy 453.653077 -23.564149) (xy 453.657208 -23.560024) (xy 453.661272 -23.55596)
			(xy 453.661272 -22.202394) (xy 453.652382 -22.19325) (xy 453.64654 -22.188424) (xy 453.629268 -22.18182)
			(xy 453.62876 -22.18182) (xy 453.61733 -22.177248) (xy 453.616822 -22.177248) (xy 453.590095 -22.165637)
			(xy 453.540226 -22.135498) (xy 453.495522 -22.098123) (xy 453.457026 -22.054381) (xy 453.425632 -22.005292)
			(xy 453.402073 -21.951998) (xy 453.386897 -21.895739) (xy 453.380457 -21.837827) (xy 453.38111 -21.808694)
			(xy 453.382791 -21.780474) (xy 453.393437 -21.724955) (xy 453.412154 -21.671613) (xy 453.438534 -21.621614)
			(xy 453.471999 -21.576053) (xy 453.511817 -21.535926) (xy 453.557119 -21.50211) (xy 453.606912 -21.475345)
			(xy 453.633332 -21.465286) (xy 453.640952 -21.46173) (xy 453.65289 -21.455126) (xy 453.661272 -21.44649)
			(xy 453.661272 -18.846038) (xy 453.661752 -18.813161) (xy 453.669148 -18.747825) (xy 453.683805 -18.683726)
			(xy 453.705542 -18.621668) (xy 453.734083 -18.562432) (xy 453.769072 -18.50676) (xy 453.810069 -18.455352)
			(xy 453.832976 -18.431764) (xy 454.414382 -17.850358) (xy 454.437947 -17.827462) (xy 454.489331 -17.78651)
			(xy 454.544974 -17.751565) (xy 454.604177 -17.723066) (xy 454.666198 -17.701369) (xy 454.730257 -17.686747)
			(xy 454.795549 -17.679385) (xy 454.828402 -17.678908) (xy 454.828656 -17.678908) (xy 454.864056 -17.679419)
			(xy 454.93434 -17.687948) (xy 455.003083 -17.704888) (xy 455.069282 -17.72999) (xy 455.131973 -17.76289)
			(xy 455.190241 -17.803108) (xy 455.243236 -17.850055) (xy 455.290185 -17.903049) (xy 455.330403 -17.961316)
			(xy 455.363305 -18.024007) (xy 455.388409 -18.090206) (xy 455.40535 -18.158949) (xy 455.413881 -18.229232)
			(xy 455.41438 -18.264632) (xy 455.41438 -18.264886) (xy 455.413921 -18.29774) (xy 455.406565 -18.363034)
			(xy 455.391946 -18.427095) (xy 455.370245 -18.489116) (xy 455.341737 -18.548317) (xy 455.30678 -18.603954)
			(xy 455.265814 -18.655328) (xy 455.24293 -18.678906) (xy 454.99401 -18.927826) (xy 454.991978 -18.937732)
			(xy 455.016362 -19.02206) (xy 455.02195 -19.034506) (xy 455.02576 -19.040602) (xy 455.033126 -19.047206)
			(xy 455.03846 -19.052286) (xy 455.050652 -19.058636) (xy 455.05751 -19.059906) (xy 455.090505 -19.067367)
			(xy 455.15464 -19.088886) (xy 455.215865 -19.117657) (xy 455.273364 -19.153298) (xy 455.326369 -19.195331)
			(xy 455.350626 -19.21891) (xy 455.836274 -19.704558) (xy 455.856743 -19.725529) (xy 455.89383 -19.770906)
			(xy 455.926182 -19.819772) (xy 455.94016 -19.845528) (xy 455.941684 -19.848068) (xy 455.957386 -19.875003)
			(xy 455.98355 -19.931597) (xy 456.003445 -19.990687) (xy 456.016837 -20.051581) (xy 456.023571 -20.113565)
			(xy 456.02398 -20.14474) (xy 456.02398 -24.24684) (xy 456.023557 -24.278014) (xy 456.016819 -24.339996)
			(xy 456.003425 -24.400888) (xy 455.983533 -24.459977) (xy 455.957376 -24.516572) (xy 455.941684 -24.543512)
			(xy 455.94016 -24.546052) (xy 455.926161 -24.571795) (xy 455.893788 -24.620643) (xy 455.856718 -24.666029)
			(xy 455.836274 -24.687022) (xy 453.97293 -26.550112) (xy 453.966082 -26.55751) (xy 453.958347 -26.576108)
			(xy 453.957944 -26.58618) (xy 453.957944 -29.495242) (xy 453.958376 -29.505308) (xy 453.966106 -29.523897)
			(xy 453.97293 -29.53131) (xy 455.187415 -30.745738) (xy 457.614517 -30.745738) (xy 457.614517 -30.616598)
			(xy 457.622467 -30.487703) (xy 457.638337 -30.359543) (xy 457.662066 -30.232602) (xy 457.693565 -30.107363)
			(xy 457.732714 -29.9843) (xy 457.779365 -29.863881) (xy 457.83334 -29.746562) (xy 457.894435 -29.632788)
			(xy 457.962418 -29.522991) (xy 458.037032 -29.417588) (xy 458.117993 -29.316978) (xy 458.204993 -29.221543)
			(xy 458.297704 -29.131644) (xy 458.395774 -29.047623) (xy 458.498829 -28.969799) (xy 458.60648 -28.898467)
			(xy 458.718319 -28.833897) (xy 458.83392 -28.776335) (xy 458.952845 -28.725998) (xy 459.074644 -28.683078)
			(xy 459.198854 -28.647737) (xy 459.325003 -28.62011) (xy 459.452615 -28.600301) (xy 459.581204 -28.588385)
			(xy 459.710282 -28.584409) (xy 459.83936 -28.588385) (xy 459.967949 -28.600301) (xy 460.095561 -28.62011)
			(xy 460.22171 -28.647737) (xy 460.34592 -28.683078) (xy 460.467719 -28.725998) (xy 460.586644 -28.776335)
			(xy 460.702245 -28.833897) (xy 460.814084 -28.898467) (xy 460.921735 -28.969799) (xy 461.02479 -29.047623)
			(xy 461.12286 -29.131644) (xy 461.215571 -29.221543) (xy 461.302571 -29.316978) (xy 461.383532 -29.417588)
			(xy 461.458146 -29.522991) (xy 461.526129 -29.632788) (xy 461.587224 -29.746562) (xy 461.641199 -29.863881)
			(xy 461.68785 -29.9843) (xy 461.726999 -30.107363) (xy 461.758498 -30.232602) (xy 461.782227 -30.359543)
			(xy 461.798097 -30.487703) (xy 461.806047 -30.616598) (xy 461.806544 -30.681168) (xy 461.806047 -30.745738)
			(xy 461.798097 -30.874633) (xy 461.782227 -31.002793) (xy 461.758498 -31.129734) (xy 461.726999 -31.254973)
			(xy 461.68785 -31.378036) (xy 461.641199 -31.498455) (xy 461.587224 -31.615774) (xy 461.526129 -31.729548)
			(xy 461.458146 -31.839345) (xy 461.383532 -31.944748) (xy 461.302571 -32.045358) (xy 461.215571 -32.140793)
			(xy 461.12286 -32.230692) (xy 461.02479 -32.314713) (xy 460.921735 -32.392537) (xy 460.814084 -32.463869)
			(xy 460.702245 -32.528439) (xy 460.586644 -32.586001) (xy 460.467719 -32.636338) (xy 460.34592 -32.679258)
			(xy 460.22171 -32.714599) (xy 460.095561 -32.742226) (xy 459.967949 -32.762035) (xy 459.83936 -32.773951)
			(xy 459.710282 -32.777928) (xy 459.581204 -32.773951) (xy 459.452615 -32.762035) (xy 459.325003 -32.742226)
			(xy 459.198854 -32.714599) (xy 459.074644 -32.679258) (xy 458.952845 -32.636338) (xy 458.83392 -32.586001)
			(xy 458.718319 -32.528439) (xy 458.60648 -32.463869) (xy 458.498829 -32.392537) (xy 458.395774 -32.314713)
			(xy 458.297704 -32.230692) (xy 458.204993 -32.140793) (xy 458.117993 -32.045358) (xy 458.037032 -31.944748)
			(xy 457.962418 -31.839345) (xy 457.894435 -31.729548) (xy 457.83334 -31.615774) (xy 457.779365 -31.498455)
			(xy 457.732714 -31.378036) (xy 457.693565 -31.254973) (xy 457.662066 -31.129734) (xy 457.638337 -31.002793)
			(xy 457.622467 -30.874633) (xy 457.614517 -30.745738) (xy 455.187415 -30.745738) (xy 459.40091 -34.959036)
			(xy 459.423338 -34.982075) (xy 459.463554 -35.032246) (xy 459.498026 -35.086524) (xy 459.526338 -35.144255)
			(xy 459.548149 -35.204743) (xy 459.556104 -35.235896) (xy 459.55712 -35.238944) (xy 459.565516 -35.267173)
			(xy 459.577269 -35.324885) (xy 459.583169 -35.383485) (xy 459.583536 -35.412934) (xy 459.583536 -69.44487)
			(xy 459.583168 -69.47472) (xy 459.577096 -69.534111) (xy 459.565002 -69.592573) (xy 459.556358 -69.621146)
			(xy 459.555342 -69.624194) (xy 459.547318 -69.655087) (xy 459.525446 -69.715055) (xy 459.497186 -69.77229)
			(xy 459.462874 -69.826115) (xy 459.422916 -69.875893) (xy 459.400656 -69.898768) (xy 454.514458 -74.784966)
			(xy 458.026514 -74.784966) (xy 458.030585 -74.729344) (xy 458.042711 -74.674907) (xy 458.062634 -74.622816)
			(xy 458.08993 -74.574181) (xy 458.124016 -74.530038) (xy 458.164165 -74.491329) (xy 458.209523 -74.458878)
			(xy 458.259123 -74.433377) (xy 458.311907 -74.41537) (xy 458.36675 -74.40524) (xy 458.422484 -74.403203)
			(xy 458.477921 -74.409303) (xy 458.531878 -74.423409) (xy 458.583207 -74.445221) (xy 458.630813 -74.474275)
			(xy 458.673681 -74.50995) (xy 458.710898 -74.551487) (xy 458.741671 -74.598) (xy 458.765343 -74.648497)
			(xy 458.781411 -74.701904) (xy 458.789531 -74.75708) (xy 458.79004 -74.784966) (xy 458.789531 -74.812852)
			(xy 458.781411 -74.868028) (xy 458.765343 -74.921435) (xy 458.741671 -74.971932) (xy 458.710898 -75.018445)
			(xy 458.673681 -75.059982) (xy 458.630813 -75.095657) (xy 458.583207 -75.124711) (xy 458.531878 -75.146523)
			(xy 458.477921 -75.160629) (xy 458.422484 -75.166729) (xy 458.36675 -75.164692) (xy 458.311907 -75.154562)
			(xy 458.259123 -75.136555) (xy 458.209523 -75.111054) (xy 458.164165 -75.078603) (xy 458.124016 -75.039894)
			(xy 458.08993 -74.995751) (xy 458.062634 -74.947116) (xy 458.042711 -74.895025) (xy 458.030585 -74.840588)
			(xy 458.026514 -74.784966) (xy 454.514458 -74.784966) (xy 453.181466 -76.117958) (xy 453.157902 -76.140856)
			(xy 453.106519 -76.18181) (xy 453.050876 -76.216759) (xy 452.991673 -76.245263) (xy 452.929652 -76.266964)
			(xy 452.865593 -76.28159) (xy 452.8003 -76.288958) (xy 452.767446 -76.289408) (xy 429.855376 -76.289408)
			(xy 429.845308 -76.289836) (xy 429.826711 -76.297557) (xy 429.819308 -76.304394) (xy 429.6819 -76.441808)
			(xy 458.137766 -76.441808) (xy 458.141837 -76.386186) (xy 458.153963 -76.331749) (xy 458.173886 -76.279658)
			(xy 458.201182 -76.231023) (xy 458.235268 -76.18688) (xy 458.275417 -76.148171) (xy 458.320775 -76.11572)
			(xy 458.370375 -76.090219) (xy 458.423159 -76.072212) (xy 458.478002 -76.062082) (xy 458.533736 -76.060045)
			(xy 458.589173 -76.066145) (xy 458.64313 -76.080251) (xy 458.694459 -76.102063) (xy 458.742065 -76.131117)
			(xy 458.784933 -76.166792) (xy 458.82215 -76.208329) (xy 458.852923 -76.254842) (xy 458.876595 -76.305339)
			(xy 458.892663 -76.358746) (xy 458.900783 -76.413922) (xy 458.901292 -76.441808) (xy 458.900783 -76.469694)
			(xy 458.892663 -76.52487) (xy 458.876595 -76.578277) (xy 458.852923 -76.628774) (xy 458.82215 -76.675287)
			(xy 458.784933 -76.716824) (xy 458.742065 -76.752499) (xy 458.694459 -76.781553) (xy 458.64313 -76.803365)
			(xy 458.589173 -76.817471) (xy 458.533736 -76.823571) (xy 458.478002 -76.821534) (xy 458.423159 -76.811404)
			(xy 458.370375 -76.793397) (xy 458.320775 -76.767896) (xy 458.275417 -76.735445) (xy 458.235268 -76.696736)
			(xy 458.201182 -76.652593) (xy 458.173886 -76.603958) (xy 458.153963 -76.551867) (xy 458.141837 -76.49743)
			(xy 458.137766 -76.441808) (xy 429.6819 -76.441808) (xy 428.917395 -77.206348) (xy 430.98415 -77.206348)
			(xy 430.988221 -77.150726) (xy 431.000347 -77.096289) (xy 431.02027 -77.044198) (xy 431.047566 -76.995563)
			(xy 431.081652 -76.95142) (xy 431.121801 -76.912711) (xy 431.167159 -76.88026) (xy 431.216759 -76.854759)
			(xy 431.269543 -76.836752) (xy 431.324386 -76.826622) (xy 431.38012 -76.824585) (xy 431.435557 -76.830685)
			(xy 431.489514 -76.844791) (xy 431.540843 -76.866603) (xy 431.588449 -76.895657) (xy 431.631317 -76.931332)
			(xy 431.668534 -76.972869) (xy 431.683189 -76.99502) (xy 453.687178 -76.99502) (xy 453.691249 -76.939398)
			(xy 453.703375 -76.884961) (xy 453.723298 -76.83287) (xy 453.750594 -76.784235) (xy 453.78468 -76.740092)
			(xy 453.824829 -76.701383) (xy 453.870187 -76.668932) (xy 453.919787 -76.643431) (xy 453.972571 -76.625424)
			(xy 454.027414 -76.615294) (xy 454.083148 -76.613257) (xy 454.138585 -76.619357) (xy 454.192542 -76.633463)
			(xy 454.243871 -76.655275) (xy 454.291477 -76.684329) (xy 454.334345 -76.720004) (xy 454.371562 -76.761541)
			(xy 454.402335 -76.808054) (xy 454.426007 -76.858551) (xy 454.442075 -76.911958) (xy 454.450195 -76.967134)
			(xy 454.450704 -76.99502) (xy 454.450195 -77.022906) (xy 454.446337 -77.049122) (xy 455.173078 -77.049122)
			(xy 455.177149 -76.9935) (xy 455.189275 -76.939063) (xy 455.209198 -76.886972) (xy 455.236494 -76.838337)
			(xy 455.27058 -76.794194) (xy 455.310729 -76.755485) (xy 455.356087 -76.723034) (xy 455.405687 -76.697533)
			(xy 455.458471 -76.679526) (xy 455.513314 -76.669396) (xy 455.569048 -76.667359) (xy 455.624485 -76.673459)
			(xy 455.678442 -76.687565) (xy 455.729771 -76.709377) (xy 455.777377 -76.738431) (xy 455.820245 -76.774106)
			(xy 455.857462 -76.815643) (xy 455.888235 -76.862156) (xy 455.911907 -76.912653) (xy 455.927975 -76.96606)
			(xy 455.936095 -77.021236) (xy 455.936604 -77.049122) (xy 455.936095 -77.077008) (xy 455.927975 -77.132184)
			(xy 455.911907 -77.185591) (xy 455.888235 -77.236088) (xy 455.857462 -77.282601) (xy 455.820245 -77.324138)
			(xy 455.777377 -77.359813) (xy 455.729771 -77.388867) (xy 455.678442 -77.410679) (xy 455.624485 -77.424785)
			(xy 455.569048 -77.430885) (xy 455.513314 -77.428848) (xy 455.458471 -77.418718) (xy 455.405687 -77.400711)
			(xy 455.356087 -77.37521) (xy 455.310729 -77.342759) (xy 455.27058 -77.30405) (xy 455.236494 -77.259907)
			(xy 455.209198 -77.211272) (xy 455.189275 -77.159181) (xy 455.177149 -77.104744) (xy 455.173078 -77.049122)
			(xy 454.446337 -77.049122) (xy 454.442075 -77.078082) (xy 454.426007 -77.131489) (xy 454.402335 -77.181986)
			(xy 454.371562 -77.228499) (xy 454.334345 -77.270036) (xy 454.291477 -77.305711) (xy 454.243871 -77.334765)
			(xy 454.192542 -77.356577) (xy 454.138585 -77.370683) (xy 454.083148 -77.376783) (xy 454.027414 -77.374746)
			(xy 453.972571 -77.364616) (xy 453.919787 -77.346609) (xy 453.870187 -77.321108) (xy 453.824829 -77.288657)
			(xy 453.78468 -77.249948) (xy 453.750594 -77.205805) (xy 453.723298 -77.15717) (xy 453.703375 -77.105079)
			(xy 453.691249 -77.050642) (xy 453.687178 -76.99502) (xy 431.683189 -76.99502) (xy 431.699307 -77.019382)
			(xy 431.722979 -77.069879) (xy 431.739047 -77.123286) (xy 431.747167 -77.178462) (xy 431.747676 -77.206348)
			(xy 431.747167 -77.234234) (xy 431.739047 -77.28941) (xy 431.722979 -77.342817) (xy 431.699307 -77.393314)
			(xy 431.668534 -77.439827) (xy 431.631317 -77.481364) (xy 431.588449 -77.517039) (xy 431.540843 -77.546093)
			(xy 431.489514 -77.567905) (xy 431.435557 -77.582011) (xy 431.38012 -77.588111) (xy 431.324386 -77.586074)
			(xy 431.269543 -77.575944) (xy 431.216759 -77.557937) (xy 431.167159 -77.532436) (xy 431.121801 -77.499985)
			(xy 431.081652 -77.461276) (xy 431.047566 -77.417133) (xy 431.02027 -77.368498) (xy 431.000347 -77.316407)
			(xy 430.988221 -77.26197) (xy 430.98415 -77.206348) (xy 428.917395 -77.206348) (xy 426.941873 -79.18196)
			(xy 427.891702 -79.18196) (xy 427.892188 -79.154709) (xy 427.899944 -79.100761) (xy 427.915299 -79.048466)
			(xy 427.937941 -78.998889) (xy 427.967407 -78.953039) (xy 428.003098 -78.911848) (xy 428.044289 -78.876157)
			(xy 428.090139 -78.846691) (xy 428.139716 -78.824049) (xy 428.192011 -78.808694) (xy 428.245959 -78.800938)
			(xy 428.300461 -78.800938) (xy 428.354409 -78.808694) (xy 428.406704 -78.824049) (xy 428.456281 -78.846691)
			(xy 428.502131 -78.876157) (xy 428.543322 -78.911848) (xy 428.579013 -78.953039) (xy 428.608479 -78.998889)
			(xy 428.631121 -79.048466) (xy 428.646476 -79.100761) (xy 428.654232 -79.154709) (xy 428.654718 -79.18196)
			(xy 428.654155 -79.210843) (xy 428.645439 -79.267948) (xy 428.628216 -79.323087) (xy 428.602877 -79.375)
			(xy 428.570004 -79.422501) (xy 428.530347 -79.464504) (xy 428.507906 -79.482696) (xy 428.496983 -79.491859)
			(xy 428.48023 -79.514911) (xy 428.470491 -79.541691) (xy 428.468522 -79.57012) (xy 428.474477 -79.597987)
			(xy 428.487892 -79.623128) (xy 428.507725 -79.64359) (xy 428.519844 -79.651098) (xy 428.544444 -79.665765)
			(xy 428.589317 -79.701352) (xy 428.628365 -79.743248) (xy 428.660711 -79.790512) (xy 428.685626 -79.842081)
			(xy 428.702551 -79.896794) (xy 428.711105 -79.953424) (xy 428.711614 -79.98206) (xy 428.711128 -80.009311)
			(xy 428.703372 -80.063259) (xy 428.688017 -80.115554) (xy 428.665375 -80.165131) (xy 428.635909 -80.210981)
			(xy 428.600218 -80.252172) (xy 428.559027 -80.287863) (xy 428.513177 -80.317329) (xy 428.4636 -80.339971)
			(xy 428.411305 -80.355326) (xy 428.357357 -80.363082) (xy 428.302855 -80.363082) (xy 428.248907 -80.355326)
			(xy 428.196612 -80.339971) (xy 428.147035 -80.317329) (xy 428.101185 -80.287863) (xy 428.059994 -80.252172)
			(xy 428.024303 -80.210981) (xy 427.994837 -80.165131) (xy 427.972195 -80.115554) (xy 427.95684 -80.063259)
			(xy 427.949084 -80.009311) (xy 427.948598 -79.98206) (xy 427.949097 -79.953174) (xy 427.957826 -79.896066)
			(xy 427.975062 -79.840926) (xy 428.000412 -79.789013) (xy 428.033296 -79.741514) (xy 428.072964 -79.699514)
			(xy 428.09541 -79.681324) (xy 428.106309 -79.672136) (xy 428.123059 -79.649089) (xy 428.132798 -79.622315)
			(xy 428.134769 -79.593893) (xy 428.12882 -79.566031) (xy 428.115412 -79.540892) (xy 428.095587 -79.520431)
			(xy 428.083472 -79.512922) (xy 428.058862 -79.498273) (xy 428.013992 -79.462679) (xy 427.974948 -79.420778)
			(xy 427.942605 -79.373512) (xy 427.917692 -79.321941) (xy 427.900768 -79.267227) (xy 427.892212 -79.210596)
			(xy 427.891702 -79.18196) (xy 426.941873 -79.18196) (xy 424.224196 -81.89976) (xy 424.197526 -81.925554)
			(xy 424.1388 -81.9709) (xy 424.107102 -81.990184) (xy 424.101514 -81.993486) (xy 423.79138 -82.303874)
			(xy 423.772771 -82.322103) (xy 423.732834 -82.355553) (xy 423.711624 -82.370676) (xy 423.707814 -82.373216)
			(xy 423.666666 -82.414364) (xy 425.781722 -82.414364) (xy 425.785793 -82.358742) (xy 425.797919 -82.304305)
			(xy 425.817842 -82.252214) (xy 425.845138 -82.203579) (xy 425.879224 -82.159436) (xy 425.919373 -82.120727)
			(xy 425.964731 -82.088276) (xy 426.014331 -82.062775) (xy 426.067115 -82.044768) (xy 426.121958 -82.034638)
			(xy 426.177692 -82.032601) (xy 426.233129 -82.038701) (xy 426.287086 -82.052807) (xy 426.338415 -82.074619)
			(xy 426.386021 -82.103673) (xy 426.428889 -82.139348) (xy 426.466106 -82.180885) (xy 426.496879 -82.227398)
			(xy 426.520551 -82.277895) (xy 426.536619 -82.331302) (xy 426.544739 -82.386478) (xy 426.545248 -82.414364)
			(xy 426.545007 -82.427572) (xy 427.232824 -82.427572) (xy 427.236895 -82.37195) (xy 427.249021 -82.317513)
			(xy 427.268944 -82.265422) (xy 427.29624 -82.216787) (xy 427.330326 -82.172644) (xy 427.370475 -82.133935)
			(xy 427.415833 -82.101484) (xy 427.465433 -82.075983) (xy 427.518217 -82.057976) (xy 427.57306 -82.047846)
			(xy 427.628794 -82.045809) (xy 427.684231 -82.051909) (xy 427.738188 -82.066015) (xy 427.789517 -82.087827)
			(xy 427.837123 -82.116881) (xy 427.879991 -82.152556) (xy 427.917208 -82.194093) (xy 427.947981 -82.240606)
			(xy 427.971653 -82.291103) (xy 427.987721 -82.34451) (xy 427.995841 -82.399686) (xy 427.99635 -82.427572)
			(xy 427.995841 -82.455458) (xy 427.987721 -82.510634) (xy 427.971653 -82.564041) (xy 427.947981 -82.614538)
			(xy 427.917208 -82.661051) (xy 427.879991 -82.702588) (xy 427.837123 -82.738263) (xy 427.789517 -82.767317)
			(xy 427.738188 -82.789129) (xy 427.684231 -82.803235) (xy 427.628794 -82.809335) (xy 427.57306 -82.807298)
			(xy 427.518217 -82.797168) (xy 427.465433 -82.779161) (xy 427.415833 -82.75366) (xy 427.370475 -82.721209)
			(xy 427.330326 -82.6825) (xy 427.29624 -82.638357) (xy 427.268944 -82.589722) (xy 427.249021 -82.537631)
			(xy 427.236895 -82.483194) (xy 427.232824 -82.427572) (xy 426.545007 -82.427572) (xy 426.544739 -82.44225)
			(xy 426.536619 -82.497426) (xy 426.520551 -82.550833) (xy 426.496879 -82.60133) (xy 426.466106 -82.647843)
			(xy 426.428889 -82.68938) (xy 426.386021 -82.725055) (xy 426.338415 -82.754109) (xy 426.287086 -82.775921)
			(xy 426.233129 -82.790027) (xy 426.177692 -82.796127) (xy 426.121958 -82.79409) (xy 426.067115 -82.78396)
			(xy 426.014331 -82.765953) (xy 425.964731 -82.740452) (xy 425.919373 -82.708001) (xy 425.879224 -82.669292)
			(xy 425.845138 -82.625149) (xy 425.817842 -82.576514) (xy 425.797919 -82.524423) (xy 425.785793 -82.469986)
			(xy 425.781722 -82.414364) (xy 423.666666 -82.414364) (xy 423.509186 -82.571844) (xy 423.48603 -82.594386)
			(xy 423.435505 -82.634682) (xy 423.380786 -82.669068) (xy 423.322561 -82.697111) (xy 423.261562 -82.718459)
			(xy 423.198557 -82.732842) (xy 423.134337 -82.740081) (xy 423.102024 -82.7405) (xy 414.849056 -82.7405)
			(xy 414.843046 -82.740667) (xy 414.831363 -82.743489) (xy 414.825942 -82.746088) (xy 414.822465 -82.747924)
			(xy 414.81608 -82.752511) (xy 414.813242 -82.755232) (xy 414.719008 -82.849466) (xy 435.673752 -82.849466)
			(xy 435.677823 -82.793844) (xy 435.689949 -82.739407) (xy 435.709872 -82.687316) (xy 435.737168 -82.638681)
			(xy 435.771254 -82.594538) (xy 435.811403 -82.555829) (xy 435.856761 -82.523378) (xy 435.906361 -82.497877)
			(xy 435.959145 -82.47987) (xy 436.013988 -82.46974) (xy 436.069722 -82.467703) (xy 436.125159 -82.473803)
			(xy 436.179116 -82.487909) (xy 436.230445 -82.509721) (xy 436.278051 -82.538775) (xy 436.320919 -82.57445)
			(xy 436.358136 -82.615987) (xy 436.388909 -82.6625) (xy 436.412581 -82.712997) (xy 436.428649 -82.766404)
			(xy 436.436769 -82.82158) (xy 436.437278 -82.849466) (xy 436.436769 -82.877352) (xy 436.428649 -82.932528)
			(xy 436.412581 -82.985935) (xy 436.388909 -83.036432) (xy 436.358136 -83.082945) (xy 436.320919 -83.124482)
			(xy 436.278051 -83.160157) (xy 436.230445 -83.189211) (xy 436.179116 -83.211023) (xy 436.125159 -83.225129)
			(xy 436.069722 -83.231229) (xy 436.013988 -83.229192) (xy 435.959145 -83.219062) (xy 435.906361 -83.201055)
			(xy 435.856761 -83.175554) (xy 435.811403 -83.143103) (xy 435.771254 -83.104394) (xy 435.737168 -83.060251)
			(xy 435.709872 -83.011616) (xy 435.689949 -82.959525) (xy 435.677823 -82.905088) (xy 435.673752 -82.849466)
			(xy 414.719008 -82.849466) (xy 414.428178 -83.140296) (xy 414.425474 -83.143149) (xy 414.420886 -83.149529)
			(xy 414.419034 -83.152996) (xy 414.416455 -83.158424) (xy 414.413641 -83.170103) (xy 414.413446 -83.17611)
			(xy 414.413446 -83.282536) (xy 414.416748 -83.294982) (xy 414.419796 -83.30057) (xy 414.437094 -83.333121)
			(xy 414.464278 -83.40164) (xy 414.482642 -83.47303) (xy 414.490132 -83.532218) (xy 424.611544 -83.532218)
			(xy 424.615615 -83.476596) (xy 424.627741 -83.422159) (xy 424.647664 -83.370068) (xy 424.67496 -83.321433)
			(xy 424.709046 -83.27729) (xy 424.749195 -83.238581) (xy 424.794553 -83.20613) (xy 424.844153 -83.180629)
			(xy 424.896937 -83.162622) (xy 424.95178 -83.152492) (xy 425.007514 -83.150455) (xy 425.062951 -83.156555)
			(xy 425.116908 -83.170661) (xy 425.168237 -83.192473) (xy 425.215843 -83.221527) (xy 425.258711 -83.257202)
			(xy 425.295928 -83.298739) (xy 425.326701 -83.345252) (xy 425.350373 -83.395749) (xy 425.366441 -83.449156)
			(xy 425.374561 -83.504332) (xy 425.37507 -83.532218) (xy 425.374561 -83.560104) (xy 425.366441 -83.61528)
			(xy 425.350373 -83.668687) (xy 425.326701 -83.719184) (xy 425.295928 -83.765697) (xy 425.258711 -83.807234)
			(xy 425.215843 -83.842909) (xy 425.168237 -83.871963) (xy 425.116908 -83.893775) (xy 425.062951 -83.907881)
			(xy 425.007514 -83.913981) (xy 424.95178 -83.911944) (xy 424.896937 -83.901814) (xy 424.844153 -83.883807)
			(xy 424.794553 -83.858306) (xy 424.749195 -83.825855) (xy 424.709046 -83.787146) (xy 424.67496 -83.743003)
			(xy 424.647664 -83.694368) (xy 424.627741 -83.642277) (xy 424.615615 -83.58784) (xy 424.611544 -83.532218)
			(xy 414.490132 -83.532218) (xy 414.491896 -83.546161) (xy 414.49244 -83.583018) (xy 414.491969 -83.616673)
			(xy 414.484253 -83.683539) (xy 414.468924 -83.749079) (xy 414.446185 -83.812432) (xy 414.416335 -83.87276)
			(xy 414.39846 -83.90128) (xy 414.390332 -83.928712) (xy 414.397698 -83.955128) (xy 414.413838 -83.982602)
			(xy 414.440722 -84.040375) (xy 414.46117 -84.100728) (xy 414.474939 -84.162944) (xy 414.481868 -84.226289)
			(xy 414.48228 -84.25815) (xy 414.48228 -84.258658) (xy 414.481791 -84.292915) (xy 414.473797 -84.36096)
			(xy 414.457925 -84.42761) (xy 414.440104 -84.476336) (xy 427.965614 -84.476336) (xy 427.969685 -84.420714)
			(xy 427.981811 -84.366277) (xy 428.001734 -84.314186) (xy 428.02903 -84.265551) (xy 428.063116 -84.221408)
			(xy 428.103265 -84.182699) (xy 428.148623 -84.150248) (xy 428.198223 -84.124747) (xy 428.251007 -84.10674)
			(xy 428.30585 -84.09661) (xy 428.361584 -84.094573) (xy 428.417021 -84.100673) (xy 428.470978 -84.114779)
			(xy 428.522307 -84.136591) (xy 428.569913 -84.165645) (xy 428.612781 -84.20132) (xy 428.649998 -84.242857)
			(xy 428.659108 -84.256626) (xy 435.377842 -84.256626) (xy 435.381913 -84.201004) (xy 435.394039 -84.146567)
			(xy 435.413962 -84.094476) (xy 435.441258 -84.045841) (xy 435.475344 -84.001698) (xy 435.515493 -83.962989)
			(xy 435.560851 -83.930538) (xy 435.610451 -83.905037) (xy 435.663235 -83.88703) (xy 435.718078 -83.8769)
			(xy 435.773812 -83.874863) (xy 435.829249 -83.880963) (xy 435.883206 -83.895069) (xy 435.934535 -83.916881)
			(xy 435.982141 -83.945935) (xy 436.025009 -83.98161) (xy 436.062226 -84.023147) (xy 436.092999 -84.06966)
			(xy 436.116671 -84.120157) (xy 436.132739 -84.173564) (xy 436.140859 -84.22874) (xy 436.141368 -84.256626)
			(xy 436.140859 -84.284512) (xy 436.132739 -84.339688) (xy 436.116671 -84.393095) (xy 436.092999 -84.443592)
			(xy 436.062226 -84.490105) (xy 436.025009 -84.531642) (xy 435.982141 -84.567317) (xy 435.934535 -84.596371)
			(xy 435.883206 -84.618183) (xy 435.829249 -84.632289) (xy 435.773812 -84.638389) (xy 435.718078 -84.636352)
			(xy 435.663235 -84.626222) (xy 435.610451 -84.608215) (xy 435.560851 -84.582714) (xy 435.515493 -84.550263)
			(xy 435.475344 -84.511554) (xy 435.441258 -84.467411) (xy 435.413962 -84.418776) (xy 435.394039 -84.366685)
			(xy 435.381913 -84.312248) (xy 435.377842 -84.256626) (xy 428.659108 -84.256626) (xy 428.680771 -84.28937)
			(xy 428.704443 -84.339867) (xy 428.720511 -84.393274) (xy 428.728631 -84.44845) (xy 428.72914 -84.476336)
			(xy 428.728631 -84.504222) (xy 428.720511 -84.559398) (xy 428.704443 -84.612805) (xy 428.680771 -84.663302)
			(xy 428.649998 -84.709815) (xy 428.612781 -84.751352) (xy 428.569913 -84.787027) (xy 428.522307 -84.816081)
			(xy 428.470978 -84.837893) (xy 428.417021 -84.851999) (xy 428.361584 -84.858099) (xy 428.30585 -84.856062)
			(xy 428.251007 -84.845932) (xy 428.198223 -84.827925) (xy 428.148623 -84.802424) (xy 428.103265 -84.769973)
			(xy 428.063116 -84.731264) (xy 428.02903 -84.687121) (xy 428.001734 -84.638486) (xy 427.981811 -84.586395)
			(xy 427.969685 -84.531958) (xy 427.965614 -84.476336) (xy 414.440104 -84.476336) (xy 414.434391 -84.491955)
			(xy 414.403516 -84.553117) (xy 414.365722 -84.610263) (xy 414.321523 -84.662614) (xy 414.29686 -84.686394)
			(xy 414.282382 -84.70011) (xy 414.27996 -84.706882) (xy 414.278546 -84.721188) (xy 414.279588 -84.728304)
			(xy 414.280858 -84.734654) (xy 414.28543 -84.744814) (xy 414.298124 -84.775312) (xy 414.316059 -84.83889)
			(xy 414.325176 -84.904318) (xy 414.325816 -84.937346) (xy 414.325816 -84.947506) (xy 414.324733 -84.978343)
			(xy 414.315692 -85.039382) (xy 414.298949 -85.098772) (xy 414.274775 -85.155544) (xy 414.243564 -85.208774)
			(xy 414.227387 -85.2297) (xy 416.185602 -85.2297) (xy 416.189673 -85.174078) (xy 416.201799 -85.119641)
			(xy 416.221722 -85.06755) (xy 416.249018 -85.018915) (xy 416.283104 -84.974772) (xy 416.323253 -84.936063)
			(xy 416.368611 -84.903612) (xy 416.418211 -84.878111) (xy 416.470995 -84.860104) (xy 416.525838 -84.849974)
			(xy 416.581572 -84.847937) (xy 416.637009 -84.854037) (xy 416.690966 -84.868143) (xy 416.742295 -84.889955)
			(xy 416.789901 -84.919009) (xy 416.832769 -84.954684) (xy 416.869986 -84.996221) (xy 416.900759 -85.042734)
			(xy 416.924431 -85.093231) (xy 416.940499 -85.146638) (xy 416.948619 -85.201814) (xy 416.949128 -85.2297)
			(xy 416.948619 -85.257586) (xy 416.940499 -85.312762) (xy 416.924431 -85.366169) (xy 416.900759 -85.416666)
			(xy 416.869986 -85.463179) (xy 416.832769 -85.504716) (xy 416.789901 -85.540391) (xy 416.742295 -85.569445)
			(xy 416.690966 -85.591257) (xy 416.637009 -85.605363) (xy 416.581572 -85.611463) (xy 416.525838 -85.609426)
			(xy 416.470995 -85.599296) (xy 416.418211 -85.581289) (xy 416.368611 -85.555788) (xy 416.323253 -85.523337)
			(xy 416.283104 -85.484628) (xy 416.249018 -85.440485) (xy 416.221722 -85.39185) (xy 416.201799 -85.339759)
			(xy 416.189673 -85.285322) (xy 416.185602 -85.2297) (xy 414.227387 -85.2297) (xy 414.205825 -85.257593)
			(xy 414.184338 -85.279738) (xy 413.216039 -86.247986) (xy 423.538648 -86.247986) (xy 423.542719 -86.192364)
			(xy 423.554845 -86.137927) (xy 423.574768 -86.085836) (xy 423.602064 -86.037201) (xy 423.63615 -85.993058)
			(xy 423.676299 -85.954349) (xy 423.721657 -85.921898) (xy 423.771257 -85.896397) (xy 423.824041 -85.87839)
			(xy 423.878884 -85.86826) (xy 423.934618 -85.866223) (xy 423.990055 -85.872323) (xy 424.044012 -85.886429)
			(xy 424.095341 -85.908241) (xy 424.142947 -85.937295) (xy 424.185815 -85.97297) (xy 424.223032 -86.014507)
			(xy 424.253805 -86.06102) (xy 424.277477 -86.111517) (xy 424.293545 -86.164924) (xy 424.301665 -86.2201)
			(xy 424.302174 -86.247986) (xy 424.301665 -86.275872) (xy 424.293545 -86.331048) (xy 424.277477 -86.384455)
			(xy 424.253805 -86.434952) (xy 424.223032 -86.481465) (xy 424.185815 -86.523002) (xy 424.142947 -86.558677)
			(xy 424.095341 -86.587731) (xy 424.052053 -86.606126) (xy 435.464202 -86.606126) (xy 435.468273 -86.550504)
			(xy 435.480399 -86.496067) (xy 435.500322 -86.443976) (xy 435.527618 -86.395341) (xy 435.561704 -86.351198)
			(xy 435.601853 -86.312489) (xy 435.647211 -86.280038) (xy 435.696811 -86.254537) (xy 435.749595 -86.23653)
			(xy 435.804438 -86.2264) (xy 435.860172 -86.224363) (xy 435.915609 -86.230463) (xy 435.969566 -86.244569)
			(xy 436.020895 -86.266381) (xy 436.068501 -86.295435) (xy 436.111369 -86.33111) (xy 436.148586 -86.372647)
			(xy 436.179359 -86.41916) (xy 436.203031 -86.469657) (xy 436.219099 -86.523064) (xy 436.227219 -86.57824)
			(xy 436.227728 -86.606126) (xy 436.227219 -86.634012) (xy 436.219099 -86.689188) (xy 436.203031 -86.742595)
			(xy 436.179359 -86.793092) (xy 436.148586 -86.839605) (xy 436.111369 -86.881142) (xy 436.068501 -86.916817)
			(xy 436.020895 -86.945871) (xy 435.969566 -86.967683) (xy 435.915609 -86.981789) (xy 435.860172 -86.987889)
			(xy 435.804438 -86.985852) (xy 435.749595 -86.975722) (xy 435.696811 -86.957715) (xy 435.647211 -86.932214)
			(xy 435.601853 -86.899763) (xy 435.561704 -86.861054) (xy 435.527618 -86.816911) (xy 435.500322 -86.768276)
			(xy 435.480399 -86.716185) (xy 435.468273 -86.661748) (xy 435.464202 -86.606126) (xy 424.052053 -86.606126)
			(xy 424.044012 -86.609543) (xy 423.990055 -86.623649) (xy 423.934618 -86.629749) (xy 423.878884 -86.627712)
			(xy 423.824041 -86.617582) (xy 423.771257 -86.599575) (xy 423.721657 -86.574074) (xy 423.676299 -86.541623)
			(xy 423.63615 -86.502914) (xy 423.602064 -86.458771) (xy 423.574768 -86.410136) (xy 423.554845 -86.358045)
			(xy 423.542719 -86.303608) (xy 423.538648 -86.247986) (xy 413.216039 -86.247986) (xy 412.32369 -87.140288)
			(xy 415.304476 -87.140288) (xy 415.308547 -87.084666) (xy 415.320673 -87.030229) (xy 415.340596 -86.978138)
			(xy 415.367892 -86.929503) (xy 415.401978 -86.88536) (xy 415.442127 -86.846651) (xy 415.487485 -86.8142)
			(xy 415.537085 -86.788699) (xy 415.589869 -86.770692) (xy 415.644712 -86.760562) (xy 415.700446 -86.758525)
			(xy 415.755883 -86.764625) (xy 415.80984 -86.778731) (xy 415.861169 -86.800543) (xy 415.908775 -86.829597)
			(xy 415.951643 -86.865272) (xy 415.98886 -86.906809) (xy 416.019633 -86.953322) (xy 416.043305 -87.003819)
			(xy 416.059373 -87.057226) (xy 416.067493 -87.112402) (xy 416.068002 -87.140288) (xy 416.067493 -87.168174)
			(xy 416.059373 -87.22335) (xy 416.043305 -87.276757) (xy 416.019633 -87.327254) (xy 415.98886 -87.373767)
			(xy 415.980487 -87.383112) (xy 434.523386 -87.383112) (xy 434.527457 -87.32749) (xy 434.539583 -87.273053)
			(xy 434.559506 -87.220962) (xy 434.586802 -87.172327) (xy 434.620888 -87.128184) (xy 434.661037 -87.089475)
			(xy 434.706395 -87.057024) (xy 434.755995 -87.031523) (xy 434.808779 -87.013516) (xy 434.863622 -87.003386)
			(xy 434.919356 -87.001349) (xy 434.974793 -87.007449) (xy 435.02875 -87.021555) (xy 435.080079 -87.043367)
			(xy 435.127685 -87.072421) (xy 435.170553 -87.108096) (xy 435.20777 -87.149633) (xy 435.238543 -87.196146)
			(xy 435.262215 -87.246643) (xy 435.278283 -87.30005) (xy 435.286403 -87.355226) (xy 435.286912 -87.383112)
			(xy 435.286403 -87.410998) (xy 435.278283 -87.466174) (xy 435.262215 -87.519581) (xy 435.238543 -87.570078)
			(xy 435.20777 -87.616591) (xy 435.170553 -87.658128) (xy 435.127685 -87.693803) (xy 435.080079 -87.722857)
			(xy 435.02875 -87.744669) (xy 434.974793 -87.758775) (xy 434.919356 -87.764875) (xy 434.863622 -87.762838)
			(xy 434.808779 -87.752708) (xy 434.755995 -87.734701) (xy 434.706395 -87.7092) (xy 434.661037 -87.676749)
			(xy 434.620888 -87.63804) (xy 434.586802 -87.593897) (xy 434.559506 -87.545262) (xy 434.539583 -87.493171)
			(xy 434.527457 -87.438734) (xy 434.523386 -87.383112) (xy 415.980487 -87.383112) (xy 415.951643 -87.415304)
			(xy 415.908775 -87.450979) (xy 415.861169 -87.480033) (xy 415.80984 -87.501845) (xy 415.755883 -87.515951)
			(xy 415.700446 -87.522051) (xy 415.644712 -87.520014) (xy 415.589869 -87.509884) (xy 415.537085 -87.491877)
			(xy 415.487485 -87.466376) (xy 415.442127 -87.433925) (xy 415.401978 -87.395216) (xy 415.367892 -87.351073)
			(xy 415.340596 -87.302438) (xy 415.320673 -87.250347) (xy 415.308547 -87.19591) (xy 415.304476 -87.140288)
			(xy 412.32369 -87.140288) (xy 411.216191 -88.247728) (xy 413.813496 -88.247728) (xy 413.817567 -88.192106)
			(xy 413.829693 -88.137669) (xy 413.849616 -88.085578) (xy 413.876912 -88.036943) (xy 413.910998 -87.9928)
			(xy 413.951147 -87.954091) (xy 413.996505 -87.92164) (xy 414.046105 -87.896139) (xy 414.098889 -87.878132)
			(xy 414.153732 -87.868002) (xy 414.209466 -87.865965) (xy 414.264903 -87.872065) (xy 414.31886 -87.886171)
			(xy 414.370189 -87.907983) (xy 414.417795 -87.937037) (xy 414.460663 -87.972712) (xy 414.49788 -88.014249)
			(xy 414.528653 -88.060762) (xy 414.552325 -88.111259) (xy 414.568393 -88.164666) (xy 414.576513 -88.219842)
			(xy 414.577022 -88.247728) (xy 414.576513 -88.275614) (xy 414.568393 -88.33079) (xy 414.554792 -88.375998)
			(xy 428.223678 -88.375998) (xy 428.227749 -88.320376) (xy 428.239875 -88.265939) (xy 428.259798 -88.213848)
			(xy 428.287094 -88.165213) (xy 428.32118 -88.12107) (xy 428.361329 -88.082361) (xy 428.406687 -88.04991)
			(xy 428.456287 -88.024409) (xy 428.509071 -88.006402) (xy 428.563914 -87.996272) (xy 428.619648 -87.994235)
			(xy 428.675085 -88.000335) (xy 428.729042 -88.014441) (xy 428.780371 -88.036253) (xy 428.827977 -88.065307)
			(xy 428.870845 -88.100982) (xy 428.908062 -88.142519) (xy 428.938835 -88.189032) (xy 428.962507 -88.239529)
			(xy 428.978575 -88.292936) (xy 428.986695 -88.348112) (xy 428.987204 -88.375998) (xy 428.986842 -88.39581)
			(xy 429.557686 -88.39581) (xy 429.561757 -88.340188) (xy 429.573883 -88.285751) (xy 429.593806 -88.23366)
			(xy 429.621102 -88.185025) (xy 429.655188 -88.140882) (xy 429.695337 -88.102173) (xy 429.740695 -88.069722)
			(xy 429.790295 -88.044221) (xy 429.843079 -88.026214) (xy 429.897922 -88.016084) (xy 429.953656 -88.014047)
			(xy 430.009093 -88.020147) (xy 430.06305 -88.034253) (xy 430.114379 -88.056065) (xy 430.161985 -88.085119)
			(xy 430.204853 -88.120794) (xy 430.24207 -88.162331) (xy 430.272843 -88.208844) (xy 430.296515 -88.259341)
			(xy 430.312583 -88.312748) (xy 430.320703 -88.367924) (xy 430.321212 -88.39581) (xy 430.320703 -88.423696)
			(xy 430.312583 -88.478872) (xy 430.296515 -88.532279) (xy 430.272843 -88.582776) (xy 430.24207 -88.629289)
			(xy 430.204853 -88.670826) (xy 430.161985 -88.706501) (xy 430.114379 -88.735555) (xy 430.06305 -88.757367)
			(xy 430.009093 -88.771473) (xy 429.953656 -88.777573) (xy 429.897922 -88.775536) (xy 429.843079 -88.765406)
			(xy 429.790295 -88.747399) (xy 429.740695 -88.721898) (xy 429.695337 -88.689447) (xy 429.655188 -88.650738)
			(xy 429.621102 -88.606595) (xy 429.593806 -88.55796) (xy 429.573883 -88.505869) (xy 429.561757 -88.451432)
			(xy 429.557686 -88.39581) (xy 428.986842 -88.39581) (xy 428.986695 -88.403884) (xy 428.978575 -88.45906)
			(xy 428.962507 -88.512467) (xy 428.938835 -88.562964) (xy 428.908062 -88.609477) (xy 428.870845 -88.651014)
			(xy 428.827977 -88.686689) (xy 428.780371 -88.715743) (xy 428.729042 -88.737555) (xy 428.675085 -88.751661)
			(xy 428.619648 -88.757761) (xy 428.563914 -88.755724) (xy 428.509071 -88.745594) (xy 428.456287 -88.727587)
			(xy 428.406687 -88.702086) (xy 428.361329 -88.669635) (xy 428.32118 -88.630926) (xy 428.287094 -88.586783)
			(xy 428.259798 -88.538148) (xy 428.239875 -88.486057) (xy 428.227749 -88.43162) (xy 428.223678 -88.375998)
			(xy 414.554792 -88.375998) (xy 414.552325 -88.384197) (xy 414.528653 -88.434694) (xy 414.49788 -88.481207)
			(xy 414.460663 -88.522744) (xy 414.417795 -88.558419) (xy 414.370189 -88.587473) (xy 414.31886 -88.609285)
			(xy 414.264903 -88.623391) (xy 414.209466 -88.629491) (xy 414.153732 -88.627454) (xy 414.098889 -88.617324)
			(xy 414.046105 -88.599317) (xy 413.996505 -88.573816) (xy 413.951147 -88.541365) (xy 413.910998 -88.502656)
			(xy 413.876912 -88.458513) (xy 413.849616 -88.409878) (xy 413.829693 -88.357787) (xy 413.817567 -88.30335)
			(xy 413.813496 -88.247728) (xy 411.216191 -88.247728) (xy 410.301488 -89.162382) (xy 412.65932 -89.162382)
			(xy 412.663391 -89.10676) (xy 412.675517 -89.052323) (xy 412.69544 -89.000232) (xy 412.722736 -88.951597)
			(xy 412.756822 -88.907454) (xy 412.796971 -88.868745) (xy 412.842329 -88.836294) (xy 412.891929 -88.810793)
			(xy 412.944713 -88.792786) (xy 412.999556 -88.782656) (xy 413.05529 -88.780619) (xy 413.110727 -88.786719)
			(xy 413.164684 -88.800825) (xy 413.216013 -88.822637) (xy 413.263619 -88.851691) (xy 413.306487 -88.887366)
			(xy 413.343704 -88.928903) (xy 413.374477 -88.975416) (xy 413.398149 -89.025913) (xy 413.414217 -89.07932)
			(xy 413.422337 -89.134496) (xy 413.422846 -89.162382) (xy 413.422337 -89.190268) (xy 413.414217 -89.245444)
			(xy 413.398149 -89.298851) (xy 413.374477 -89.349348) (xy 413.343704 -89.395861) (xy 413.3128 -89.430352)
			(xy 419.929816 -89.430352) (xy 419.933887 -89.37473) (xy 419.946013 -89.320293) (xy 419.965936 -89.268202)
			(xy 419.993232 -89.219567) (xy 420.027318 -89.175424) (xy 420.067467 -89.136715) (xy 420.112825 -89.104264)
			(xy 420.162425 -89.078763) (xy 420.215209 -89.060756) (xy 420.270052 -89.050626) (xy 420.325786 -89.048589)
			(xy 420.381223 -89.054689) (xy 420.43518 -89.068795) (xy 420.486509 -89.090607) (xy 420.534115 -89.119661)
			(xy 420.576983 -89.155336) (xy 420.6142 -89.196873) (xy 420.644973 -89.243386) (xy 420.668645 -89.293883)
			(xy 420.684713 -89.34729) (xy 420.692833 -89.402466) (xy 420.693342 -89.430352) (xy 420.692833 -89.458238)
			(xy 420.684713 -89.513414) (xy 420.668645 -89.566821) (xy 420.644973 -89.617318) (xy 420.6142 -89.663831)
			(xy 420.576983 -89.705368) (xy 420.534115 -89.741043) (xy 420.501164 -89.761153) (xy 422.18606 -89.761153)
			(xy 422.18606 -89.706647) (xy 422.193817 -89.652697) (xy 422.209173 -89.6004) (xy 422.231815 -89.55082)
			(xy 422.261282 -89.504968) (xy 422.296976 -89.463776) (xy 422.338168 -89.428082) (xy 422.38402 -89.398615)
			(xy 422.4336 -89.375973) (xy 422.485897 -89.360617) (xy 422.539847 -89.35286) (xy 422.5671 -89.352374)
			(xy 422.594118 -89.352881) (xy 422.64761 -89.360518) (xy 422.699491 -89.375624) (xy 422.748722 -89.397899)
			(xy 422.794318 -89.426895) (xy 422.835368 -89.462034) (xy 422.87105 -89.502612) (xy 422.900651 -89.547818)
			(xy 422.91254 -89.572084) (xy 422.919278 -89.585231) (xy 422.938949 -89.607253) (xy 422.964097 -89.622728)
			(xy 422.992621 -89.630364) (xy 423.022138 -89.629523) (xy 423.050181 -89.620275) (xy 423.074407 -89.603392)
			(xy 423.08399 -89.59215) (xy 423.102187 -89.570117) (xy 423.144068 -89.531242) (xy 423.191278 -89.499046)
			(xy 423.24276 -89.474249) (xy 423.297364 -89.457405) (xy 423.353869 -89.448891) (xy 423.38244 -89.448386)
			(xy 423.409689 -89.448886) (xy 423.463632 -89.456648) (xy 423.515921 -89.472006) (xy 423.565492 -89.494649)
			(xy 423.611337 -89.524116) (xy 423.652522 -89.559807) (xy 423.688208 -89.600995) (xy 423.71767 -89.646843)
			(xy 423.740308 -89.696417) (xy 423.755661 -89.748708) (xy 423.762695 -89.797636) (xy 423.880024 -89.797636)
			(xy 423.884095 -89.742014) (xy 423.896221 -89.687577) (xy 423.916144 -89.635486) (xy 423.94344 -89.586851)
			(xy 423.977526 -89.542708) (xy 424.017675 -89.503999) (xy 424.063033 -89.471548) (xy 424.112633 -89.446047)
			(xy 424.165417 -89.42804) (xy 424.22026 -89.41791) (xy 424.275994 -89.415873) (xy 424.331431 -89.421973)
			(xy 424.385388 -89.436079) (xy 424.436717 -89.457891) (xy 424.484323 -89.486945) (xy 424.527191 -89.52262)
			(xy 424.564408 -89.564157) (xy 424.595181 -89.61067) (xy 424.618853 -89.661167) (xy 424.634921 -89.714574)
			(xy 424.643041 -89.76975) (xy 424.64355 -89.797636) (xy 424.643041 -89.825522) (xy 424.634921 -89.880698)
			(xy 424.633394 -89.885774) (xy 424.743624 -89.885774) (xy 424.747695 -89.830152) (xy 424.759821 -89.775715)
			(xy 424.779744 -89.723624) (xy 424.80704 -89.674989) (xy 424.841126 -89.630846) (xy 424.881275 -89.592137)
			(xy 424.926633 -89.559686) (xy 424.976233 -89.534185) (xy 425.029017 -89.516178) (xy 425.08386 -89.506048)
			(xy 425.139594 -89.504011) (xy 425.195031 -89.510111) (xy 425.248988 -89.524217) (xy 425.300317 -89.546029)
			(xy 425.347923 -89.575083) (xy 425.390791 -89.610758) (xy 425.428008 -89.652295) (xy 425.458781 -89.698808)
			(xy 425.482453 -89.749305) (xy 425.492103 -89.78138) (xy 428.520604 -89.78138) (xy 428.524675 -89.725758)
			(xy 428.536801 -89.671321) (xy 428.556724 -89.61923) (xy 428.58402 -89.570595) (xy 428.618106 -89.526452)
			(xy 428.658255 -89.487743) (xy 428.703613 -89.455292) (xy 428.753213 -89.429791) (xy 428.805997 -89.411784)
			(xy 428.86084 -89.401654) (xy 428.916574 -89.399617) (xy 428.972011 -89.405717) (xy 429.025968 -89.419823)
			(xy 429.077297 -89.441635) (xy 429.124903 -89.470689) (xy 429.167771 -89.506364) (xy 429.204988 -89.547901)
			(xy 429.235761 -89.594414) (xy 429.259433 -89.644911) (xy 429.275501 -89.698318) (xy 429.283621 -89.753494)
			(xy 429.28413 -89.78138) (xy 429.283621 -89.809266) (xy 429.275501 -89.864442) (xy 429.259433 -89.917849)
			(xy 429.235761 -89.968346) (xy 429.204988 -90.014859) (xy 429.167771 -90.056396) (xy 429.124903 -90.092071)
			(xy 429.077297 -90.121125) (xy 429.025968 -90.142937) (xy 428.972011 -90.157043) (xy 428.916574 -90.163143)
			(xy 428.86084 -90.161106) (xy 428.805997 -90.150976) (xy 428.753213 -90.132969) (xy 428.703613 -90.107468)
			(xy 428.658255 -90.075017) (xy 428.618106 -90.036308) (xy 428.58402 -89.992165) (xy 428.556724 -89.94353)
			(xy 428.536801 -89.891439) (xy 428.524675 -89.837002) (xy 428.520604 -89.78138) (xy 425.492103 -89.78138)
			(xy 425.498521 -89.802712) (xy 425.506641 -89.857888) (xy 425.50715 -89.885774) (xy 425.506641 -89.91366)
			(xy 425.498521 -89.968836) (xy 425.482453 -90.022243) (xy 425.458781 -90.07274) (xy 425.428008 -90.119253)
			(xy 425.390791 -90.16079) (xy 425.347923 -90.196465) (xy 425.300317 -90.225519) (xy 425.248988 -90.247331)
			(xy 425.195031 -90.261437) (xy 425.139594 -90.267537) (xy 425.08386 -90.2655) (xy 425.029017 -90.25537)
			(xy 424.976233 -90.237363) (xy 424.926633 -90.211862) (xy 424.881275 -90.179411) (xy 424.841126 -90.140702)
			(xy 424.80704 -90.096559) (xy 424.779744 -90.047924) (xy 424.759821 -89.995833) (xy 424.747695 -89.941396)
			(xy 424.743624 -89.885774) (xy 424.633394 -89.885774) (xy 424.618853 -89.934105) (xy 424.595181 -89.984602)
			(xy 424.564408 -90.031115) (xy 424.527191 -90.072652) (xy 424.484323 -90.108327) (xy 424.436717 -90.137381)
			(xy 424.385388 -90.159193) (xy 424.331431 -90.173299) (xy 424.275994 -90.179399) (xy 424.22026 -90.177362)
			(xy 424.165417 -90.167232) (xy 424.112633 -90.149225) (xy 424.063033 -90.123724) (xy 424.017675 -90.091273)
			(xy 423.977526 -90.052564) (xy 423.94344 -90.008421) (xy 423.916144 -89.959786) (xy 423.896221 -89.907695)
			(xy 423.884095 -89.853258) (xy 423.880024 -89.797636) (xy 423.762695 -89.797636) (xy 423.763416 -89.802651)
			(xy 423.763416 -89.857149) (xy 423.755661 -89.911092) (xy 423.740308 -89.963383) (xy 423.71767 -90.012957)
			(xy 423.688208 -90.058805) (xy 423.652522 -90.099993) (xy 423.611337 -90.135684) (xy 423.565492 -90.165151)
			(xy 423.515921 -90.187794) (xy 423.463632 -90.203152) (xy 423.409689 -90.210914) (xy 423.38244 -90.211402)
			(xy 423.35542 -90.210959) (xy 423.301924 -90.203313) (xy 423.250041 -90.188198) (xy 423.200809 -90.165914)
			(xy 423.155213 -90.136909) (xy 423.114165 -90.101762) (xy 423.078485 -90.061175) (xy 423.048887 -90.015961)
			(xy 423.037 -89.991692) (xy 423.030208 -89.978577) (xy 423.010545 -89.956563) (xy 422.985408 -89.941092)
			(xy 422.956896 -89.933454) (xy 422.927391 -89.934289) (xy 422.899357 -89.943525) (xy 422.875134 -89.960392)
			(xy 422.86555 -89.971626) (xy 422.847325 -89.993634) (xy 422.80545 -90.032512) (xy 422.758247 -90.064712)
			(xy 422.70677 -90.089513) (xy 422.652171 -90.106362) (xy 422.59567 -90.114882) (xy 422.5671 -90.11539)
			(xy 422.539847 -90.11494) (xy 422.485897 -90.107183) (xy 422.4336 -90.091827) (xy 422.38402 -90.069185)
			(xy 422.338168 -90.039718) (xy 422.296976 -90.004024) (xy 422.261282 -89.962832) (xy 422.231815 -89.91698)
			(xy 422.209173 -89.8674) (xy 422.193817 -89.815103) (xy 422.18606 -89.761153) (xy 420.501164 -89.761153)
			(xy 420.486509 -89.770097) (xy 420.43518 -89.791909) (xy 420.381223 -89.806015) (xy 420.325786 -89.812115)
			(xy 420.270052 -89.810078) (xy 420.215209 -89.799948) (xy 420.162425 -89.781941) (xy 420.112825 -89.75644)
			(xy 420.067467 -89.723989) (xy 420.027318 -89.68528) (xy 419.993232 -89.641137) (xy 419.965936 -89.592502)
			(xy 419.946013 -89.540411) (xy 419.933887 -89.485974) (xy 419.929816 -89.430352) (xy 413.3128 -89.430352)
			(xy 413.306487 -89.437398) (xy 413.263619 -89.473073) (xy 413.216013 -89.502127) (xy 413.164684 -89.523939)
			(xy 413.110727 -89.538045) (xy 413.05529 -89.544145) (xy 412.999556 -89.542108) (xy 412.944713 -89.531978)
			(xy 412.891929 -89.513971) (xy 412.842329 -89.48847) (xy 412.796971 -89.456019) (xy 412.756822 -89.41731)
			(xy 412.722736 -89.373167) (xy 412.69544 -89.324532) (xy 412.675517 -89.272441) (xy 412.663391 -89.218004)
			(xy 412.65932 -89.162382) (xy 410.301488 -89.162382) (xy 409.388564 -90.075258) (xy 409.385855 -90.078107)
			(xy 409.381255 -90.084482) (xy 409.37942 -90.087958) (xy 409.376838 -90.093385) (xy 409.374016 -90.105065)
			(xy 409.373832 -90.111072) (xy 409.373832 -90.682064) (xy 429.17821 -90.682064) (xy 429.182281 -90.626442)
			(xy 429.194407 -90.572005) (xy 429.21433 -90.519914) (xy 429.241626 -90.471279) (xy 429.275712 -90.427136)
			(xy 429.315861 -90.388427) (xy 429.361219 -90.355976) (xy 429.410819 -90.330475) (xy 429.463603 -90.312468)
			(xy 429.518446 -90.302338) (xy 429.57418 -90.300301) (xy 429.629617 -90.306401) (xy 429.683574 -90.320507)
			(xy 429.734903 -90.342319) (xy 429.782509 -90.371373) (xy 429.825377 -90.407048) (xy 429.862594 -90.448585)
			(xy 429.893367 -90.495098) (xy 429.917039 -90.545595) (xy 429.933107 -90.599002) (xy 429.941227 -90.654178)
			(xy 429.941736 -90.682064) (xy 429.941227 -90.70995) (xy 429.933107 -90.765126) (xy 429.917039 -90.818533)
			(xy 429.893367 -90.86903) (xy 429.862594 -90.915543) (xy 429.825377 -90.95708) (xy 429.782509 -90.992755)
			(xy 429.734903 -91.021809) (xy 429.683574 -91.043621) (xy 429.629617 -91.057727) (xy 429.57418 -91.063827)
			(xy 429.518446 -91.06179) (xy 429.463603 -91.05166) (xy 429.410819 -91.033653) (xy 429.361219 -91.008152)
			(xy 429.315861 -90.975701) (xy 429.275712 -90.936992) (xy 429.241626 -90.892849) (xy 429.21433 -90.844214)
			(xy 429.194407 -90.792123) (xy 429.182281 -90.737686) (xy 429.17821 -90.682064) (xy 409.373832 -90.682064)
			(xy 409.373832 -93.039184) (xy 409.374449 -93.051031) (xy 409.385045 -93.072222) (xy 409.394152 -93.079824)
			(xy 416.442398 -93.079824) (xy 416.46842 -93.080355) (xy 416.51982 -93.088528) (xy 416.569314 -93.104626)
			(xy 416.615686 -93.128256) (xy 416.6578 -93.158836) (xy 416.676586 -93.176852) (xy 418.238686 -94.738952)
			(xy 418.256799 -94.757732) (xy 418.287484 -94.799929) (xy 418.311183 -94.84641) (xy 418.327313 -94.896029)
			(xy 418.335475 -94.947561) (xy 418.335968 -94.973648) (xy 418.335968 -95.214948) (xy 419.939229 -95.214948)
			(xy 419.943184 -95.123111) (xy 419.955019 -95.031954) (xy 419.974646 -94.942151) (xy 420.00192 -94.854369)
			(xy 420.03664 -94.769255) (xy 420.078548 -94.687442) (xy 420.127334 -94.609534) (xy 420.182637 -94.536109)
			(xy 420.244047 -94.467709) (xy 420.311109 -94.404842) (xy 420.383328 -94.347972) (xy 420.460168 -94.297521)
			(xy 420.541061 -94.253862) (xy 420.625407 -94.217319) (xy 420.712583 -94.188162) (xy 420.801942 -94.166608)
			(xy 420.892823 -94.152814) (xy 420.984554 -94.146884) (xy 421.076455 -94.148862) (xy 421.167846 -94.158733)
			(xy 421.25805 -94.176423) (xy 421.346399 -94.201803) (xy 421.432239 -94.234683) (xy 421.462231 -94.24924)
			(xy 443.73622 -94.24924) (xy 443.740291 -94.193618) (xy 443.752417 -94.139181) (xy 443.77234 -94.08709)
			(xy 443.799636 -94.038455) (xy 443.833722 -93.994312) (xy 443.873871 -93.955603) (xy 443.919229 -93.923152)
			(xy 443.968829 -93.897651) (xy 444.021613 -93.879644) (xy 444.076456 -93.869514) (xy 444.13219 -93.867477)
			(xy 444.187627 -93.873577) (xy 444.241584 -93.887683) (xy 444.292913 -93.909495) (xy 444.340519 -93.938549)
			(xy 444.383387 -93.974224) (xy 444.420604 -94.015761) (xy 444.451377 -94.062274) (xy 444.475049 -94.112771)
			(xy 444.491117 -94.166178) (xy 444.499237 -94.221354) (xy 444.499746 -94.24924) (xy 444.499237 -94.277126)
			(xy 444.491117 -94.332302) (xy 444.475049 -94.385709) (xy 444.451377 -94.436206) (xy 444.420604 -94.482719)
			(xy 444.383387 -94.524256) (xy 444.340519 -94.559931) (xy 444.292913 -94.588985) (xy 444.241584 -94.610797)
			(xy 444.187627 -94.624903) (xy 444.13219 -94.631003) (xy 444.076456 -94.628966) (xy 444.021613 -94.618836)
			(xy 443.968829 -94.600829) (xy 443.919229 -94.575328) (xy 443.873871 -94.542877) (xy 443.833722 -94.504168)
			(xy 443.799636 -94.460025) (xy 443.77234 -94.41139) (xy 443.752417 -94.359299) (xy 443.740291 -94.304862)
			(xy 443.73622 -94.24924) (xy 421.462231 -94.24924) (xy 421.514935 -94.274821) (xy 421.593875 -94.32192)
			(xy 421.668473 -94.37563) (xy 421.738179 -94.435554) (xy 421.802474 -94.501248) (xy 421.860885 -94.572226)
			(xy 421.912977 -94.647963) (xy 421.958366 -94.727898) (xy 421.996716 -94.811438) (xy 422.027741 -94.897966)
			(xy 422.051214 -94.986841) (xy 422.06696 -95.077405) (xy 422.074862 -95.168987) (xy 422.075356 -95.214948)
			(xy 422.074862 -95.260909) (xy 422.06696 -95.352491) (xy 422.051214 -95.443055) (xy 422.027741 -95.53193)
			(xy 421.996716 -95.618458) (xy 421.958366 -95.701998) (xy 421.912977 -95.781933) (xy 421.860885 -95.85767)
			(xy 421.802474 -95.928648) (xy 421.742773 -95.989648) (xy 423.864022 -95.989648) (xy 423.868093 -95.934026)
			(xy 423.880219 -95.879589) (xy 423.900142 -95.827498) (xy 423.927438 -95.778863) (xy 423.961524 -95.73472)
			(xy 424.001673 -95.696011) (xy 424.047031 -95.66356) (xy 424.096631 -95.638059) (xy 424.149415 -95.620052)
			(xy 424.204258 -95.609922) (xy 424.259992 -95.607885) (xy 424.315429 -95.613985) (xy 424.369386 -95.628091)
			(xy 424.420715 -95.649903) (xy 424.468321 -95.678957) (xy 424.511189 -95.714632) (xy 424.548406 -95.756169)
			(xy 424.579179 -95.802682) (xy 424.602851 -95.853179) (xy 424.618919 -95.906586) (xy 424.627039 -95.961762)
			(xy 424.627548 -95.989648) (xy 426.469554 -95.989648) (xy 426.473625 -95.934026) (xy 426.485751 -95.879589)
			(xy 426.505674 -95.827498) (xy 426.53297 -95.778863) (xy 426.567056 -95.73472) (xy 426.607205 -95.696011)
			(xy 426.652563 -95.66356) (xy 426.702163 -95.638059) (xy 426.754947 -95.620052) (xy 426.80979 -95.609922)
			(xy 426.865524 -95.607885) (xy 426.920961 -95.613985) (xy 426.974918 -95.628091) (xy 427.026247 -95.649903)
			(xy 427.073853 -95.678957) (xy 427.116721 -95.714632) (xy 427.153938 -95.756169) (xy 427.184221 -95.801942)
			(xy 436.941466 -95.801942) (xy 436.945537 -95.74632) (xy 436.957663 -95.691883) (xy 436.977586 -95.639792)
			(xy 437.004882 -95.591157) (xy 437.038968 -95.547014) (xy 437.079117 -95.508305) (xy 437.124475 -95.475854)
			(xy 437.174075 -95.450353) (xy 437.226859 -95.432346) (xy 437.281702 -95.422216) (xy 437.337436 -95.420179)
			(xy 437.392873 -95.426279) (xy 437.44683 -95.440385) (xy 437.498159 -95.462197) (xy 437.545765 -95.491251)
			(xy 437.588633 -95.526926) (xy 437.62585 -95.568463) (xy 437.656623 -95.614976) (xy 437.680295 -95.665473)
			(xy 437.696363 -95.71888) (xy 437.704483 -95.774056) (xy 437.704992 -95.801942) (xy 438.974736 -95.801942)
			(xy 438.978807 -95.74632) (xy 438.990933 -95.691883) (xy 439.010856 -95.639792) (xy 439.038152 -95.591157)
			(xy 439.072238 -95.547014) (xy 439.112387 -95.508305) (xy 439.157745 -95.475854) (xy 439.207345 -95.450353)
			(xy 439.260129 -95.432346) (xy 439.314972 -95.422216) (xy 439.370706 -95.420179) (xy 439.426143 -95.426279)
			(xy 439.4801 -95.440385) (xy 439.531429 -95.462197) (xy 439.579035 -95.491251) (xy 439.621903 -95.526926)
			(xy 439.65912 -95.568463) (xy 439.689893 -95.614976) (xy 439.713565 -95.665473) (xy 439.729633 -95.71888)
			(xy 439.737753 -95.774056) (xy 439.738262 -95.801942) (xy 441.015626 -95.801942) (xy 441.019697 -95.74632)
			(xy 441.031823 -95.691883) (xy 441.051746 -95.639792) (xy 441.079042 -95.591157) (xy 441.113128 -95.547014)
			(xy 441.153277 -95.508305) (xy 441.198635 -95.475854) (xy 441.248235 -95.450353) (xy 441.301019 -95.432346)
			(xy 441.355862 -95.422216) (xy 441.411596 -95.420179) (xy 441.467033 -95.426279) (xy 441.52099 -95.440385)
			(xy 441.572319 -95.462197) (xy 441.619925 -95.491251) (xy 441.662793 -95.526926) (xy 441.70001 -95.568463)
			(xy 441.730783 -95.614976) (xy 441.754455 -95.665473) (xy 441.770523 -95.71888) (xy 441.778643 -95.774056)
			(xy 441.779152 -95.801942) (xy 442.021466 -95.801942) (xy 442.025537 -95.74632) (xy 442.037663 -95.691883)
			(xy 442.057586 -95.639792) (xy 442.084882 -95.591157) (xy 442.118968 -95.547014) (xy 442.159117 -95.508305)
			(xy 442.204475 -95.475854) (xy 442.254075 -95.450353) (xy 442.306859 -95.432346) (xy 442.361702 -95.422216)
			(xy 442.417436 -95.420179) (xy 442.472873 -95.426279) (xy 442.52683 -95.440385) (xy 442.578159 -95.462197)
			(xy 442.625765 -95.491251) (xy 442.668633 -95.526926) (xy 442.70585 -95.568463) (xy 442.736623 -95.614976)
			(xy 442.760295 -95.665473) (xy 442.776363 -95.71888) (xy 442.784483 -95.774056) (xy 442.784992 -95.801942)
			(xy 442.784483 -95.829828) (xy 442.777338 -95.878378) (xy 447.420115 -95.878378) (xy 447.427868 -95.824421)
			(xy 447.443221 -95.772116) (xy 447.465861 -95.722529) (xy 447.495329 -95.676668) (xy 447.531023 -95.635468)
			(xy 447.572217 -95.599767) (xy 447.618072 -95.570292) (xy 447.667656 -95.547643) (xy 447.719958 -95.532281)
			(xy 447.773914 -95.524519) (xy 447.828426 -95.524515) (xy 447.882383 -95.532268) (xy 447.934688 -95.547622)
			(xy 447.984275 -95.570263) (xy 448.030135 -95.599731) (xy 448.071335 -95.635425) (xy 448.107035 -95.67662)
			(xy 448.13651 -95.722476) (xy 448.159158 -95.77206) (xy 448.17452 -95.824362) (xy 448.182281 -95.878318)
			(xy 448.182746 -95.905574) (xy 448.182746 -95.906082) (xy 448.182663 -95.916454) (xy 448.181521 -95.937166)
			(xy 448.18046 -95.947484) (xy 448.179401 -95.96203) (xy 448.184605 -95.990714) (xy 448.197692 -96.016765)
			(xy 448.217597 -96.038064) (xy 448.242703 -96.052882) (xy 448.27097 -96.060014) (xy 448.3001 -96.05888)
			(xy 448.314064 -96.054672) (xy 448.343673 -96.045318) (xy 448.404939 -96.035236) (xy 448.435984 -96.034606)
			(xy 448.436238 -96.034606) (xy 448.463486 -96.035119) (xy 448.517426 -96.04288) (xy 448.569712 -96.058237)
			(xy 448.619281 -96.08088) (xy 448.665123 -96.110346) (xy 448.706305 -96.146036) (xy 448.741989 -96.187224)
			(xy 448.771448 -96.233071) (xy 448.794083 -96.282643) (xy 448.809433 -96.334932) (xy 448.817185 -96.388873)
			(xy 448.817182 -96.443368) (xy 448.809424 -96.497309) (xy 448.794069 -96.549596) (xy 448.771428 -96.599166)
			(xy 448.741964 -96.645009) (xy 448.706276 -96.686193) (xy 448.66509 -96.721879) (xy 448.619245 -96.75134)
			(xy 448.569673 -96.773977) (xy 448.517385 -96.789329) (xy 448.463444 -96.797084) (xy 448.408949 -96.797084)
			(xy 448.355008 -96.789328) (xy 448.30272 -96.773975) (xy 448.253149 -96.751337) (xy 448.207305 -96.721875)
			(xy 448.166119 -96.686188) (xy 448.130432 -96.645004) (xy 448.100968 -96.59916) (xy 448.078329 -96.54959)
			(xy 448.062974 -96.497302) (xy 448.055217 -96.443362) (xy 448.05473 -96.416114) (xy 448.05473 -96.415606)
			(xy 448.054812 -96.405234) (xy 448.055955 -96.384522) (xy 448.057016 -96.374204) (xy 448.058118 -96.359659)
			(xy 448.052909 -96.330969) (xy 448.039816 -96.304914) (xy 448.019904 -96.283612) (xy 447.99479 -96.268795)
			(xy 447.966515 -96.261666) (xy 447.937378 -96.262804) (xy 447.923412 -96.267016) (xy 447.893805 -96.276375)
			(xy 447.832537 -96.286454) (xy 447.801492 -96.287082) (xy 447.801238 -96.287082) (xy 447.773982 -96.286686)
			(xy 447.720025 -96.278933) (xy 447.66772 -96.263581) (xy 447.618132 -96.240941) (xy 447.572271 -96.211474)
			(xy 447.531071 -96.17578) (xy 447.495369 -96.134586) (xy 447.465894 -96.088731) (xy 447.443244 -96.039148)
			(xy 447.427882 -95.986846) (xy 447.420119 -95.93289) (xy 447.420115 -95.878378) (xy 442.777338 -95.878378)
			(xy 442.776363 -95.885004) (xy 442.760295 -95.938411) (xy 442.736623 -95.988908) (xy 442.70585 -96.035421)
			(xy 442.668633 -96.076958) (xy 442.625765 -96.112633) (xy 442.578159 -96.141687) (xy 442.52683 -96.163499)
			(xy 442.472873 -96.177605) (xy 442.417436 -96.183705) (xy 442.361702 -96.181668) (xy 442.306859 -96.171538)
			(xy 442.254075 -96.153531) (xy 442.204475 -96.12803) (xy 442.159117 -96.095579) (xy 442.118968 -96.05687)
			(xy 442.084882 -96.012727) (xy 442.057586 -95.964092) (xy 442.037663 -95.912001) (xy 442.025537 -95.857564)
			(xy 442.021466 -95.801942) (xy 441.779152 -95.801942) (xy 441.778643 -95.829828) (xy 441.770523 -95.885004)
			(xy 441.754455 -95.938411) (xy 441.730783 -95.988908) (xy 441.70001 -96.035421) (xy 441.662793 -96.076958)
			(xy 441.619925 -96.112633) (xy 441.572319 -96.141687) (xy 441.52099 -96.163499) (xy 441.467033 -96.177605)
			(xy 441.411596 -96.183705) (xy 441.355862 -96.181668) (xy 441.301019 -96.171538) (xy 441.248235 -96.153531)
			(xy 441.198635 -96.12803) (xy 441.153277 -96.095579) (xy 441.113128 -96.05687) (xy 441.079042 -96.012727)
			(xy 441.051746 -95.964092) (xy 441.031823 -95.912001) (xy 441.019697 -95.857564) (xy 441.015626 -95.801942)
			(xy 439.738262 -95.801942) (xy 439.737753 -95.829828) (xy 439.729633 -95.885004) (xy 439.713565 -95.938411)
			(xy 439.689893 -95.988908) (xy 439.65912 -96.035421) (xy 439.621903 -96.076958) (xy 439.579035 -96.112633)
			(xy 439.531429 -96.141687) (xy 439.4801 -96.163499) (xy 439.426143 -96.177605) (xy 439.370706 -96.183705)
			(xy 439.314972 -96.181668) (xy 439.260129 -96.171538) (xy 439.207345 -96.153531) (xy 439.157745 -96.12803)
			(xy 439.112387 -96.095579) (xy 439.072238 -96.05687) (xy 439.038152 -96.012727) (xy 439.010856 -95.964092)
			(xy 438.990933 -95.912001) (xy 438.978807 -95.857564) (xy 438.974736 -95.801942) (xy 437.704992 -95.801942)
			(xy 437.704483 -95.829828) (xy 437.696363 -95.885004) (xy 437.680295 -95.938411) (xy 437.656623 -95.988908)
			(xy 437.62585 -96.035421) (xy 437.588633 -96.076958) (xy 437.545765 -96.112633) (xy 437.498159 -96.141687)
			(xy 437.44683 -96.163499) (xy 437.392873 -96.177605) (xy 437.337436 -96.183705) (xy 437.281702 -96.181668)
			(xy 437.226859 -96.171538) (xy 437.174075 -96.153531) (xy 437.124475 -96.12803) (xy 437.079117 -96.095579)
			(xy 437.038968 -96.05687) (xy 437.004882 -96.012727) (xy 436.977586 -95.964092) (xy 436.957663 -95.912001)
			(xy 436.945537 -95.857564) (xy 436.941466 -95.801942) (xy 427.184221 -95.801942) (xy 427.184711 -95.802682)
			(xy 427.208383 -95.853179) (xy 427.224451 -95.906586) (xy 427.232571 -95.961762) (xy 427.23308 -95.989648)
			(xy 427.232571 -96.017534) (xy 427.224451 -96.07271) (xy 427.208383 -96.126117) (xy 427.184711 -96.176614)
			(xy 427.153938 -96.223127) (xy 427.116721 -96.264664) (xy 427.073853 -96.300339) (xy 427.026247 -96.329393)
			(xy 426.974918 -96.351205) (xy 426.920961 -96.365311) (xy 426.865524 -96.371411) (xy 426.80979 -96.369374)
			(xy 426.754947 -96.359244) (xy 426.702163 -96.341237) (xy 426.652563 -96.315736) (xy 426.607205 -96.283285)
			(xy 426.567056 -96.244576) (xy 426.53297 -96.200433) (xy 426.505674 -96.151798) (xy 426.485751 -96.099707)
			(xy 426.473625 -96.04527) (xy 426.469554 -95.989648) (xy 424.627548 -95.989648) (xy 424.627039 -96.017534)
			(xy 424.618919 -96.07271) (xy 424.602851 -96.126117) (xy 424.579179 -96.176614) (xy 424.548406 -96.223127)
			(xy 424.511189 -96.264664) (xy 424.468321 -96.300339) (xy 424.420715 -96.329393) (xy 424.369386 -96.351205)
			(xy 424.315429 -96.365311) (xy 424.259992 -96.371411) (xy 424.204258 -96.369374) (xy 424.149415 -96.359244)
			(xy 424.096631 -96.341237) (xy 424.047031 -96.315736) (xy 424.001673 -96.283285) (xy 423.961524 -96.244576)
			(xy 423.927438 -96.200433) (xy 423.900142 -96.151798) (xy 423.880219 -96.099707) (xy 423.868093 -96.04527)
			(xy 423.864022 -95.989648) (xy 421.742773 -95.989648) (xy 421.738179 -95.994342) (xy 421.668473 -96.054266)
			(xy 421.593875 -96.107976) (xy 421.514935 -96.155075) (xy 421.432239 -96.195213) (xy 421.346399 -96.228093)
			(xy 421.25805 -96.253473) (xy 421.167846 -96.271163) (xy 421.076455 -96.281034) (xy 420.984554 -96.283012)
			(xy 420.892823 -96.277082) (xy 420.801942 -96.263288) (xy 420.712583 -96.241734) (xy 420.625407 -96.212577)
			(xy 420.541061 -96.176034) (xy 420.460168 -96.132375) (xy 420.383328 -96.081924) (xy 420.311109 -96.025054)
			(xy 420.244047 -95.962187) (xy 420.182637 -95.893787) (xy 420.127334 -95.820362) (xy 420.078548 -95.742454)
			(xy 420.03664 -95.660641) (xy 420.00192 -95.575527) (xy 419.974646 -95.487745) (xy 419.955019 -95.397942)
			(xy 419.943184 -95.306785) (xy 419.939229 -95.214948) (xy 418.335968 -95.214948) (xy 418.335968 -96.374966)
			(xy 442.727078 -96.374966) (xy 442.731149 -96.319344) (xy 442.743275 -96.264907) (xy 442.763198 -96.212816)
			(xy 442.790494 -96.164181) (xy 442.82458 -96.120038) (xy 442.864729 -96.081329) (xy 442.910087 -96.048878)
			(xy 442.959687 -96.023377) (xy 443.012471 -96.00537) (xy 443.067314 -95.99524) (xy 443.123048 -95.993203)
			(xy 443.178485 -95.999303) (xy 443.232442 -96.013409) (xy 443.283771 -96.035221) (xy 443.331377 -96.064275)
			(xy 443.374245 -96.09995) (xy 443.411462 -96.141487) (xy 443.442235 -96.188) (xy 443.465907 -96.238497)
			(xy 443.480906 -96.288352) (xy 444.152272 -96.288352) (xy 444.156343 -96.23273) (xy 444.168469 -96.178293)
			(xy 444.188392 -96.126202) (xy 444.215688 -96.077567) (xy 444.249774 -96.033424) (xy 444.289923 -95.994715)
			(xy 444.335281 -95.962264) (xy 444.384881 -95.936763) (xy 444.437665 -95.918756) (xy 444.492508 -95.908626)
			(xy 444.548242 -95.906589) (xy 444.603679 -95.912689) (xy 444.657636 -95.926795) (xy 444.708965 -95.948607)
			(xy 444.756571 -95.977661) (xy 444.799439 -96.013336) (xy 444.836656 -96.054873) (xy 444.867429 -96.101386)
			(xy 444.891101 -96.151883) (xy 444.907169 -96.20529) (xy 444.915289 -96.260466) (xy 444.91552 -96.273112)
			(xy 445.497964 -96.273112) (xy 445.502035 -96.21749) (xy 445.514161 -96.163053) (xy 445.534084 -96.110962)
			(xy 445.56138 -96.062327) (xy 445.595466 -96.018184) (xy 445.635615 -95.979475) (xy 445.680973 -95.947024)
			(xy 445.730573 -95.921523) (xy 445.783357 -95.903516) (xy 445.8382 -95.893386) (xy 445.893934 -95.891349)
			(xy 445.949371 -95.897449) (xy 446.003328 -95.911555) (xy 446.054657 -95.933367) (xy 446.102263 -95.962421)
			(xy 446.145131 -95.998096) (xy 446.182348 -96.039633) (xy 446.213121 -96.086146) (xy 446.236793 -96.136643)
			(xy 446.252861 -96.19005) (xy 446.260981 -96.245226) (xy 446.26149 -96.273112) (xy 446.260981 -96.300998)
			(xy 446.252861 -96.356174) (xy 446.236793 -96.409581) (xy 446.213121 -96.460078) (xy 446.182348 -96.506591)
			(xy 446.145131 -96.548128) (xy 446.102263 -96.583803) (xy 446.054657 -96.612857) (xy 446.003328 -96.634669)
			(xy 445.949371 -96.648775) (xy 445.893934 -96.654875) (xy 445.8382 -96.652838) (xy 445.783357 -96.642708)
			(xy 445.730573 -96.624701) (xy 445.680973 -96.5992) (xy 445.635615 -96.566749) (xy 445.595466 -96.52804)
			(xy 445.56138 -96.483897) (xy 445.534084 -96.435262) (xy 445.514161 -96.383171) (xy 445.502035 -96.328734)
			(xy 445.497964 -96.273112) (xy 444.91552 -96.273112) (xy 444.915798 -96.288352) (xy 444.915289 -96.316238)
			(xy 444.907169 -96.371414) (xy 444.891101 -96.424821) (xy 444.867429 -96.475318) (xy 444.836656 -96.521831)
			(xy 444.799439 -96.563368) (xy 444.756571 -96.599043) (xy 444.708965 -96.628097) (xy 444.657636 -96.649909)
			(xy 444.603679 -96.664015) (xy 444.548242 -96.670115) (xy 444.492508 -96.668078) (xy 444.437665 -96.657948)
			(xy 444.384881 -96.639941) (xy 444.335281 -96.61444) (xy 444.289923 -96.581989) (xy 444.249774 -96.54328)
			(xy 444.215688 -96.499137) (xy 444.188392 -96.450502) (xy 444.168469 -96.398411) (xy 444.156343 -96.343974)
			(xy 444.152272 -96.288352) (xy 443.480906 -96.288352) (xy 443.481975 -96.291904) (xy 443.490095 -96.34708)
			(xy 443.490604 -96.374966) (xy 443.490095 -96.402852) (xy 443.481975 -96.458028) (xy 443.465907 -96.511435)
			(xy 443.442235 -96.561932) (xy 443.411462 -96.608445) (xy 443.374245 -96.649982) (xy 443.331377 -96.685657)
			(xy 443.283771 -96.714711) (xy 443.232442 -96.736523) (xy 443.178485 -96.750629) (xy 443.123048 -96.756729)
			(xy 443.067314 -96.754692) (xy 443.012471 -96.744562) (xy 442.959687 -96.726555) (xy 442.910087 -96.701054)
			(xy 442.864729 -96.668603) (xy 442.82458 -96.629894) (xy 442.790494 -96.585751) (xy 442.763198 -96.537116)
			(xy 442.743275 -96.485025) (xy 442.731149 -96.430588) (xy 442.727078 -96.374966) (xy 418.335968 -96.374966)
			(xy 418.335968 -96.711516) (xy 418.339524 -96.718628) (xy 418.353975 -96.746743) (xy 418.374473 -96.806537)
			(xy 418.384863 -96.868887) (xy 418.385498 -96.900492) (xy 418.385498 -96.901) (xy 418.385035 -96.928253)
			(xy 418.377278 -96.982203) (xy 418.361921 -97.0345) (xy 418.359438 -97.039938) (xy 423.025568 -97.039938)
			(xy 423.029639 -96.984316) (xy 423.041765 -96.929879) (xy 423.061688 -96.877788) (xy 423.088984 -96.829153)
			(xy 423.12307 -96.78501) (xy 423.163219 -96.746301) (xy 423.208577 -96.71385) (xy 423.258177 -96.688349)
			(xy 423.310961 -96.670342) (xy 423.365804 -96.660212) (xy 423.421538 -96.658175) (xy 423.476975 -96.664275)
			(xy 423.530932 -96.678381) (xy 423.582261 -96.700193) (xy 423.629867 -96.729247) (xy 423.672735 -96.764922)
			(xy 423.709952 -96.806459) (xy 423.740725 -96.852972) (xy 423.764397 -96.903469) (xy 423.780465 -96.956876)
			(xy 423.787643 -97.005648) (xy 426.469554 -97.005648) (xy 426.473625 -96.950026) (xy 426.485751 -96.895589)
			(xy 426.505674 -96.843498) (xy 426.53297 -96.794863) (xy 426.567056 -96.75072) (xy 426.607205 -96.712011)
			(xy 426.652563 -96.67956) (xy 426.702163 -96.654059) (xy 426.754947 -96.636052) (xy 426.80979 -96.625922)
			(xy 426.865524 -96.623885) (xy 426.920961 -96.629985) (xy 426.974918 -96.644091) (xy 427.026247 -96.665903)
			(xy 427.073853 -96.694957) (xy 427.116721 -96.730632) (xy 427.153938 -96.772169) (xy 427.184711 -96.818682)
			(xy 427.208383 -96.869179) (xy 427.224451 -96.922586) (xy 427.232571 -96.977762) (xy 427.23308 -97.005648)
			(xy 427.232571 -97.033534) (xy 427.224451 -97.08871) (xy 427.208383 -97.142117) (xy 427.184711 -97.192614)
			(xy 427.153938 -97.239127) (xy 427.116721 -97.280664) (xy 427.073853 -97.316339) (xy 427.026247 -97.345393)
			(xy 426.974918 -97.367205) (xy 426.920961 -97.381311) (xy 426.865524 -97.387411) (xy 426.80979 -97.385374)
			(xy 426.754947 -97.375244) (xy 426.702163 -97.357237) (xy 426.652563 -97.331736) (xy 426.607205 -97.299285)
			(xy 426.567056 -97.260576) (xy 426.53297 -97.216433) (xy 426.505674 -97.167798) (xy 426.485751 -97.115707)
			(xy 426.473625 -97.06127) (xy 426.469554 -97.005648) (xy 423.787643 -97.005648) (xy 423.788585 -97.012052)
			(xy 423.789094 -97.039938) (xy 423.788585 -97.067824) (xy 423.780465 -97.123) (xy 423.764397 -97.176407)
			(xy 423.740725 -97.226904) (xy 423.709952 -97.273417) (xy 423.672735 -97.314954) (xy 423.629867 -97.350629)
			(xy 423.582261 -97.379683) (xy 423.530932 -97.401495) (xy 423.476975 -97.415601) (xy 423.421538 -97.421701)
			(xy 423.365804 -97.419664) (xy 423.310961 -97.409534) (xy 423.258177 -97.391527) (xy 423.208577 -97.366026)
			(xy 423.163219 -97.333575) (xy 423.12307 -97.294866) (xy 423.088984 -97.250723) (xy 423.061688 -97.202088)
			(xy 423.041765 -97.149997) (xy 423.029639 -97.09556) (xy 423.025568 -97.039938) (xy 418.359438 -97.039938)
			(xy 418.339279 -97.08408) (xy 418.309811 -97.129932) (xy 418.274117 -97.171124) (xy 418.232924 -97.206817)
			(xy 418.187071 -97.236284) (xy 418.137491 -97.258925) (xy 418.085193 -97.27428) (xy 418.031243 -97.282035)
			(xy 418.00399 -97.282508) (xy 418.003228 -97.282508) (xy 417.98734 -97.282335) (xy 417.955675 -97.279664)
			(xy 417.939982 -97.277174) (xy 417.938458 -97.27692) (xy 417.936172 -97.276666) (xy 417.926205 -97.275884)
			(xy 417.906967 -97.281264) (xy 417.898834 -97.28708) (xy 417.885626 -97.297748) (xy 417.885118 -97.298256)
			(xy 417.862004 -97.317306) (xy 417.861242 -97.318068) (xy 417.85794 -97.320862) (xy 417.840414 -97.333562)
			(xy 417.835588 -97.336864) (xy 417.830508 -97.340674) (xy 417.829492 -97.342706) (xy 417.829492 -97.64014)
			(xy 422.218102 -97.64014) (xy 422.222173 -97.584518) (xy 422.234299 -97.530081) (xy 422.254222 -97.47799)
			(xy 422.281518 -97.429355) (xy 422.315604 -97.385212) (xy 422.355753 -97.346503) (xy 422.401111 -97.314052)
			(xy 422.450711 -97.288551) (xy 422.503495 -97.270544) (xy 422.558338 -97.260414) (xy 422.614072 -97.258377)
			(xy 422.669509 -97.264477) (xy 422.723466 -97.278583) (xy 422.774795 -97.300395) (xy 422.822401 -97.329449)
			(xy 422.865269 -97.365124) (xy 422.902486 -97.406661) (xy 422.933259 -97.453174) (xy 422.956931 -97.503671)
			(xy 422.972999 -97.557078) (xy 422.981119 -97.612254) (xy 422.981628 -97.64014) (xy 422.981119 -97.668026)
			(xy 422.972999 -97.723202) (xy 422.956931 -97.776609) (xy 422.933259 -97.827106) (xy 422.902486 -97.873619)
			(xy 422.865269 -97.915156) (xy 422.822401 -97.950831) (xy 422.774795 -97.979885) (xy 422.723466 -98.001697)
			(xy 422.669509 -98.015803) (xy 422.614072 -98.021903) (xy 422.558338 -98.019866) (xy 422.503495 -98.009736)
			(xy 422.450711 -97.991729) (xy 422.401111 -97.966228) (xy 422.355753 -97.933777) (xy 422.315604 -97.895068)
			(xy 422.281518 -97.850925) (xy 422.254222 -97.80229) (xy 422.234299 -97.750199) (xy 422.222173 -97.695762)
			(xy 422.218102 -97.64014) (xy 417.829492 -97.64014) (xy 417.829492 -97.722182) (xy 417.82993 -97.732246)
			(xy 417.837664 -97.750829) (xy 417.844478 -97.75825) (xy 418.257327 -98.171) (xy 423.864022 -98.171)
			(xy 423.868093 -98.115378) (xy 423.880219 -98.060941) (xy 423.900142 -98.00885) (xy 423.927438 -97.960215)
			(xy 423.961524 -97.916072) (xy 424.001673 -97.877363) (xy 424.047031 -97.844912) (xy 424.096631 -97.819411)
			(xy 424.149415 -97.801404) (xy 424.204258 -97.791274) (xy 424.259992 -97.789237) (xy 424.315429 -97.795337)
			(xy 424.369386 -97.809443) (xy 424.420715 -97.831255) (xy 424.468321 -97.860309) (xy 424.511189 -97.895984)
			(xy 424.548406 -97.937521) (xy 424.559028 -97.953576) (xy 436.643016 -97.953576) (xy 436.647087 -97.897954)
			(xy 436.659213 -97.843517) (xy 436.679136 -97.791426) (xy 436.706432 -97.742791) (xy 436.740518 -97.698648)
			(xy 436.780667 -97.659939) (xy 436.826025 -97.627488) (xy 436.875625 -97.601987) (xy 436.928409 -97.58398)
			(xy 436.983252 -97.57385) (xy 437.038986 -97.571813) (xy 437.094423 -97.577913) (xy 437.14838 -97.592019)
			(xy 437.199709 -97.613831) (xy 437.247315 -97.642885) (xy 437.290183 -97.67856) (xy 437.3274 -97.720097)
			(xy 437.358173 -97.76661) (xy 437.381845 -97.817107) (xy 437.383089 -97.821242) (xy 437.957466 -97.821242)
			(xy 437.961537 -97.76562) (xy 437.973663 -97.711183) (xy 437.993586 -97.659092) (xy 438.020882 -97.610457)
			(xy 438.054968 -97.566314) (xy 438.095117 -97.527605) (xy 438.140475 -97.495154) (xy 438.190075 -97.469653)
			(xy 438.242859 -97.451646) (xy 438.297702 -97.441516) (xy 438.353436 -97.439479) (xy 438.408873 -97.445579)
			(xy 438.46283 -97.459685) (xy 438.514159 -97.481497) (xy 438.561765 -97.510551) (xy 438.604633 -97.546226)
			(xy 438.64185 -97.587763) (xy 438.672623 -97.634276) (xy 438.696295 -97.684773) (xy 438.712363 -97.73818)
			(xy 438.720483 -97.793356) (xy 438.720992 -97.821242) (xy 438.720495 -97.848447) (xy 439.22852 -97.848447)
			(xy 439.22852 -97.793953) (xy 439.236275 -97.740012) (xy 439.251628 -97.687725) (xy 439.274265 -97.638154)
			(xy 439.303727 -97.592309) (xy 439.339413 -97.551124) (xy 439.380597 -97.515437) (xy 439.42644 -97.485973)
			(xy 439.47601 -97.463334) (xy 439.528297 -97.447979) (xy 439.582237 -97.440221) (xy 439.609484 -97.439734)
			(xy 439.638401 -97.440251) (xy 439.695573 -97.448978) (xy 439.750772 -97.466236) (xy 439.802734 -97.491628)
			(xy 439.850268 -97.524572) (xy 439.892284 -97.564314) (xy 439.910474 -97.5868) (xy 439.918102 -97.595585)
			(xy 439.938987 -97.605781) (xy 439.950606 -97.606358) (xy 440.030362 -97.606358) (xy 440.041999 -97.605855)
			(xy 440.062909 -97.595642) (xy 440.070494 -97.5868) (xy 440.088688 -97.564319) (xy 440.130707 -97.524584)
			(xy 440.178242 -97.491645) (xy 440.230202 -97.466256) (xy 440.285399 -97.448999) (xy 440.342568 -97.440269)
			(xy 440.371484 -97.439734) (xy 440.398741 -97.440112) (xy 440.452699 -97.447868) (xy 440.505005 -97.463224)
			(xy 440.554593 -97.485868) (xy 440.600453 -97.515339) (xy 440.641652 -97.551037) (xy 440.677351 -97.592234)
			(xy 440.706824 -97.638093) (xy 440.72947 -97.68768) (xy 440.744829 -97.739985) (xy 440.752587 -97.793943)
			(xy 440.752587 -97.821242) (xy 441.005466 -97.821242) (xy 441.009537 -97.76562) (xy 441.021663 -97.711183)
			(xy 441.041586 -97.659092) (xy 441.068882 -97.610457) (xy 441.102968 -97.566314) (xy 441.143117 -97.527605)
			(xy 441.188475 -97.495154) (xy 441.238075 -97.469653) (xy 441.290859 -97.451646) (xy 441.345702 -97.441516)
			(xy 441.401436 -97.439479) (xy 441.456873 -97.445579) (xy 441.51083 -97.459685) (xy 441.562159 -97.481497)
			(xy 441.609765 -97.510551) (xy 441.629968 -97.527364) (xy 442.639702 -97.527364) (xy 442.643773 -97.471742)
			(xy 442.655899 -97.417305) (xy 442.675822 -97.365214) (xy 442.703118 -97.316579) (xy 442.737204 -97.272436)
			(xy 442.777353 -97.233727) (xy 442.822711 -97.201276) (xy 442.872311 -97.175775) (xy 442.925095 -97.157768)
			(xy 442.979938 -97.147638) (xy 443.035672 -97.145601) (xy 443.091109 -97.151701) (xy 443.145066 -97.165807)
			(xy 443.196395 -97.187619) (xy 443.244001 -97.216673) (xy 443.286869 -97.252348) (xy 443.324086 -97.293885)
			(xy 443.354859 -97.340398) (xy 443.378531 -97.390895) (xy 443.394599 -97.444302) (xy 443.402719 -97.499478)
			(xy 443.403228 -97.527364) (xy 443.402719 -97.55525) (xy 443.394599 -97.610426) (xy 443.378531 -97.663833)
			(xy 443.354859 -97.71433) (xy 443.324086 -97.760843) (xy 443.286869 -97.80238) (xy 443.244001 -97.838055)
			(xy 443.196395 -97.867109) (xy 443.145066 -97.888921) (xy 443.091109 -97.903027) (xy 443.035672 -97.909127)
			(xy 442.979938 -97.90709) (xy 442.925095 -97.89696) (xy 442.872311 -97.878953) (xy 442.822711 -97.853452)
			(xy 442.777353 -97.821001) (xy 442.737204 -97.782292) (xy 442.703118 -97.738149) (xy 442.675822 -97.689514)
			(xy 442.655899 -97.637423) (xy 442.643773 -97.582986) (xy 442.639702 -97.527364) (xy 441.629968 -97.527364)
			(xy 441.652633 -97.546226) (xy 441.68985 -97.587763) (xy 441.720623 -97.634276) (xy 441.744295 -97.684773)
			(xy 441.760363 -97.73818) (xy 441.768483 -97.793356) (xy 441.768992 -97.821242) (xy 441.768483 -97.849128)
			(xy 441.760363 -97.904304) (xy 441.744295 -97.957711) (xy 441.720623 -98.008208) (xy 441.68985 -98.054721)
			(xy 441.652633 -98.096258) (xy 441.609765 -98.131933) (xy 441.562159 -98.160987) (xy 441.51083 -98.182799)
			(xy 441.456873 -98.196905) (xy 441.401436 -98.203005) (xy 441.345702 -98.200968) (xy 441.290859 -98.190838)
			(xy 441.238075 -98.172831) (xy 441.188475 -98.14733) (xy 441.143117 -98.114879) (xy 441.102968 -98.07617)
			(xy 441.068882 -98.032027) (xy 441.041586 -97.983392) (xy 441.021663 -97.931301) (xy 441.009537 -97.876864)
			(xy 441.005466 -97.821242) (xy 440.752587 -97.821242) (xy 440.752587 -97.848457) (xy 440.744829 -97.902415)
			(xy 440.72947 -97.95472) (xy 440.706824 -98.004307) (xy 440.677351 -98.050166) (xy 440.641652 -98.091363)
			(xy 440.600453 -98.127061) (xy 440.554593 -98.156532) (xy 440.505005 -98.179176) (xy 440.452699 -98.194532)
			(xy 440.398741 -98.202288) (xy 440.371484 -98.20275) (xy 440.342568 -98.20219) (xy 440.285398 -98.193472)
			(xy 440.2302 -98.176224) (xy 440.178237 -98.15084) (xy 440.130702 -98.117903) (xy 440.088685 -98.078167)
			(xy 440.070494 -98.055684) (xy 440.062883 -98.046881) (xy 440.041985 -98.036696) (xy 440.030362 -98.036126)
			(xy 439.950606 -98.036126) (xy 439.938975 -98.036674) (xy 439.918065 -98.046856) (xy 439.910474 -98.055684)
			(xy 439.892294 -98.078177) (xy 439.850272 -98.117912) (xy 439.802735 -98.15085) (xy 439.750772 -98.176237)
			(xy 439.695572 -98.193491) (xy 439.638401 -98.202217) (xy 439.609484 -98.20275) (xy 439.582237 -98.202179)
			(xy 439.528297 -98.194421) (xy 439.47601 -98.179066) (xy 439.42644 -98.156427) (xy 439.380597 -98.126963)
			(xy 439.339413 -98.091276) (xy 439.303727 -98.050091) (xy 439.274265 -98.004246) (xy 439.251628 -97.954675)
			(xy 439.236275 -97.902388) (xy 439.22852 -97.848447) (xy 438.720495 -97.848447) (xy 438.720483 -97.849128)
			(xy 438.712363 -97.904304) (xy 438.696295 -97.957711) (xy 438.672623 -98.008208) (xy 438.64185 -98.054721)
			(xy 438.604633 -98.096258) (xy 438.561765 -98.131933) (xy 438.514159 -98.160987) (xy 438.46283 -98.182799)
			(xy 438.408873 -98.196905) (xy 438.353436 -98.203005) (xy 438.297702 -98.200968) (xy 438.242859 -98.190838)
			(xy 438.190075 -98.172831) (xy 438.140475 -98.14733) (xy 438.095117 -98.114879) (xy 438.054968 -98.07617)
			(xy 438.020882 -98.032027) (xy 437.993586 -97.983392) (xy 437.973663 -97.931301) (xy 437.961537 -97.876864)
			(xy 437.957466 -97.821242) (xy 437.383089 -97.821242) (xy 437.397913 -97.870514) (xy 437.406033 -97.92569)
			(xy 437.406542 -97.953576) (xy 437.406033 -97.981462) (xy 437.397913 -98.036638) (xy 437.381845 -98.090045)
			(xy 437.358173 -98.140542) (xy 437.3274 -98.187055) (xy 437.290183 -98.228592) (xy 437.247315 -98.264267)
			(xy 437.199709 -98.293321) (xy 437.14838 -98.315133) (xy 437.094423 -98.329239) (xy 437.038986 -98.335339)
			(xy 436.983252 -98.333302) (xy 436.928409 -98.323172) (xy 436.875625 -98.305165) (xy 436.826025 -98.279664)
			(xy 436.780667 -98.247213) (xy 436.740518 -98.208504) (xy 436.706432 -98.164361) (xy 436.679136 -98.115726)
			(xy 436.659213 -98.063635) (xy 436.647087 -98.009198) (xy 436.643016 -97.953576) (xy 424.559028 -97.953576)
			(xy 424.579179 -97.984034) (xy 424.602851 -98.034531) (xy 424.618919 -98.087938) (xy 424.627039 -98.143114)
			(xy 424.627548 -98.171) (xy 424.627039 -98.198886) (xy 424.618919 -98.254062) (xy 424.602851 -98.307469)
			(xy 424.579179 -98.357966) (xy 424.548406 -98.404479) (xy 424.511189 -98.446016) (xy 424.468321 -98.481691)
			(xy 424.420715 -98.510745) (xy 424.369386 -98.532557) (xy 424.328048 -98.543364) (xy 435.285894 -98.543364)
			(xy 435.289965 -98.487742) (xy 435.302091 -98.433305) (xy 435.322014 -98.381214) (xy 435.34931 -98.332579)
			(xy 435.383396 -98.288436) (xy 435.423545 -98.249727) (xy 435.468903 -98.217276) (xy 435.518503 -98.191775)
			(xy 435.571287 -98.173768) (xy 435.62613 -98.163638) (xy 435.681864 -98.161601) (xy 435.737301 -98.167701)
			(xy 435.791258 -98.181807) (xy 435.842587 -98.203619) (xy 435.890193 -98.232673) (xy 435.933061 -98.268348)
			(xy 435.970278 -98.309885) (xy 436.001051 -98.356398) (xy 436.024723 -98.406895) (xy 436.040791 -98.460302)
			(xy 436.048911 -98.515478) (xy 436.04942 -98.543364) (xy 436.048911 -98.57125) (xy 436.040791 -98.626426)
			(xy 436.024723 -98.679833) (xy 436.001051 -98.73033) (xy 435.98174 -98.759518) (xy 447.471292 -98.759518)
			(xy 447.471771 -98.732148) (xy 447.479586 -98.67797) (xy 447.495072 -98.625467) (xy 447.517911 -98.57572)
			(xy 447.547632 -98.529752) (xy 447.565272 -98.50882) (xy 447.565526 -98.508566) (xy 447.571094 -98.501467)
			(xy 447.577351 -98.48456) (xy 447.577718 -98.475546) (xy 447.577718 -98.40849) (xy 447.577362 -98.399473)
			(xy 447.571113 -98.382556) (xy 447.565526 -98.37547) (xy 447.565272 -98.37547) (xy 447.565272 -98.375216)
			(xy 447.547647 -98.35427) (xy 447.517918 -98.308306) (xy 447.495069 -98.258562) (xy 447.479569 -98.206061)
			(xy 447.471738 -98.151884) (xy 447.471736 -98.097143) (xy 447.479564 -98.042965) (xy 447.495059 -97.990464)
			(xy 447.517905 -97.940718) (xy 447.547631 -97.894752) (xy 447.565272 -97.87382) (xy 447.565526 -97.873566)
			(xy 447.571094 -97.866467) (xy 447.577351 -97.84956) (xy 447.577718 -97.840546) (xy 447.577718 -97.77349)
			(xy 447.577362 -97.764473) (xy 447.571113 -97.747556) (xy 447.565526 -97.74047) (xy 447.565272 -97.74047)
			(xy 447.565272 -97.740216) (xy 447.547623 -97.719292) (xy 447.517913 -97.673317) (xy 447.49508 -97.623567)
			(xy 447.479591 -97.571065) (xy 447.471765 -97.516888) (xy 447.471292 -97.489518) (xy 447.471778 -97.462267)
			(xy 447.479534 -97.408319) (xy 447.494889 -97.356024) (xy 447.517531 -97.306447) (xy 447.546997 -97.260597)
			(xy 447.582688 -97.219406) (xy 447.623879 -97.183715) (xy 447.669729 -97.154249) (xy 447.719306 -97.131607)
			(xy 447.771601 -97.116252) (xy 447.825549 -97.108496) (xy 447.880051 -97.108496) (xy 447.933999 -97.116252)
			(xy 447.986294 -97.131607) (xy 448.035871 -97.154249) (xy 448.081721 -97.183715) (xy 448.122912 -97.219406)
			(xy 448.158603 -97.260597) (xy 448.188069 -97.306447) (xy 448.210711 -97.356024) (xy 448.226066 -97.408319)
			(xy 448.233822 -97.462267) (xy 448.234308 -97.489518) (xy 448.233851 -97.516889) (xy 448.22603 -97.571068)
			(xy 448.210539 -97.623571) (xy 448.187696 -97.673318) (xy 448.15797 -97.719284) (xy 448.140328 -97.740216)
			(xy 448.140074 -97.74047) (xy 448.134491 -97.747559) (xy 448.128243 -97.764474) (xy 448.127882 -97.77349)
			(xy 448.127882 -97.840546) (xy 448.128269 -97.84956) (xy 448.134496 -97.866477) (xy 448.140074 -97.873566)
			(xy 448.140328 -97.873566) (xy 448.140328 -97.87382) (xy 448.157988 -97.894738) (xy 448.187716 -97.940707)
			(xy 448.210563 -97.990455) (xy 448.22606 -98.04296) (xy 448.233887 -98.097142) (xy 448.233886 -98.151886)
			(xy 448.226054 -98.206066) (xy 448.210553 -98.25857) (xy 448.187703 -98.308317) (xy 448.157972 -98.354284)
			(xy 448.140328 -98.375216) (xy 448.140074 -98.37547) (xy 448.134491 -98.382559) (xy 448.128243 -98.399474)
			(xy 448.127882 -98.40849) (xy 448.127882 -98.475546) (xy 448.128269 -98.48456) (xy 448.134496 -98.501477)
			(xy 448.136129 -98.503552) (xy 449.126063 -98.503552) (xy 449.126063 -98.449048) (xy 449.13382 -98.395098)
			(xy 449.149176 -98.342801) (xy 449.171818 -98.293222) (xy 449.201286 -98.247369) (xy 449.236979 -98.206177)
			(xy 449.278171 -98.170485) (xy 449.324023 -98.141017) (xy 449.373603 -98.118375) (xy 449.4259 -98.10302)
			(xy 449.47985 -98.095263) (xy 449.507102 -98.0948) (xy 449.533416 -98.095266) (xy 449.585545 -98.102501)
			(xy 449.636187 -98.116821) (xy 449.684386 -98.137953) (xy 449.72923 -98.1655) (xy 449.769869 -98.198938)
			(xy 449.788026 -98.21799) (xy 449.795537 -98.225404) (xy 449.814825 -98.233921) (xy 449.825364 -98.2345)
			(xy 449.90004 -98.2345) (xy 449.910588 -98.233952) (xy 449.929883 -98.22543) (xy 449.937378 -98.21799)
			(xy 449.955549 -98.19895) (xy 449.996176 -98.165492) (xy 450.041013 -98.137931) (xy 450.089211 -98.11679)
			(xy 450.139855 -98.102469) (xy 450.191987 -98.095241) (xy 450.218302 -98.0948) (xy 450.245554 -98.09527)
			(xy 450.299502 -98.103027) (xy 450.351798 -98.118382) (xy 450.401376 -98.141024) (xy 450.447227 -98.170491)
			(xy 450.488418 -98.206183) (xy 450.52411 -98.247374) (xy 450.553577 -98.293226) (xy 450.573272 -98.336354)
			(xy 451.149466 -98.336354) (xy 451.149948 -98.308984) (xy 451.157759 -98.254805) (xy 451.173244 -98.202302)
			(xy 451.196082 -98.152554) (xy 451.225805 -98.106587) (xy 451.243446 -98.085656) (xy 451.2437 -98.085402)
			(xy 451.249292 -98.078319) (xy 451.255535 -98.0614) (xy 451.255892 -98.052382) (xy 451.255892 -97.985326)
			(xy 451.255524 -97.97631) (xy 451.249284 -97.959393) (xy 451.2437 -97.952306) (xy 451.243446 -97.952306)
			(xy 451.243446 -97.952052) (xy 451.225759 -97.931156) (xy 451.196035 -97.885182) (xy 451.173191 -97.83543)
			(xy 451.157698 -97.782922) (xy 451.149873 -97.728738) (xy 451.149878 -97.673992) (xy 451.157713 -97.61981)
			(xy 451.173216 -97.567305) (xy 451.196068 -97.517557) (xy 451.225801 -97.471588) (xy 451.243446 -97.450656)
			(xy 451.2437 -97.450402) (xy 451.249292 -97.443319) (xy 451.255535 -97.4264) (xy 451.255892 -97.417382)
			(xy 451.255892 -97.350326) (xy 451.255524 -97.34131) (xy 451.249284 -97.324393) (xy 451.2437 -97.317306)
			(xy 451.243446 -97.317306) (xy 451.243446 -97.317052) (xy 451.225825 -97.296105) (xy 451.196109 -97.250137)
			(xy 451.173269 -97.200394) (xy 451.157774 -97.147896) (xy 451.149942 -97.093722) (xy 451.149466 -97.066354)
			(xy 451.149952 -97.039103) (xy 451.157708 -96.985155) (xy 451.173063 -96.93286) (xy 451.195705 -96.883283)
			(xy 451.225171 -96.837433) (xy 451.260862 -96.796242) (xy 451.302053 -96.760551) (xy 451.347903 -96.731085)
			(xy 451.39748 -96.708443) (xy 451.449775 -96.693088) (xy 451.503723 -96.685332) (xy 451.558225 -96.685332)
			(xy 451.612173 -96.693088) (xy 451.664468 -96.708443) (xy 451.714045 -96.731085) (xy 451.759895 -96.760551)
			(xy 451.801086 -96.796242) (xy 451.836777 -96.837433) (xy 451.866243 -96.883283) (xy 451.888885 -96.93286)
			(xy 451.90424 -96.985155) (xy 451.911996 -97.039103) (xy 451.912482 -97.066354) (xy 451.911993 -97.093723)
			(xy 451.904182 -97.147902) (xy 451.888698 -97.200405) (xy 451.865861 -97.250152) (xy 451.836141 -97.29612)
			(xy 451.818502 -97.317052) (xy 451.818248 -97.317306) (xy 451.812647 -97.324382) (xy 451.80641 -97.341307)
			(xy 451.806056 -97.350326) (xy 451.806056 -97.417382) (xy 451.80641 -97.426399) (xy 451.812658 -97.443317)
			(xy 451.818248 -97.450402) (xy 451.818502 -97.450402) (xy 451.818502 -97.450656) (xy 451.836096 -97.471626)
			(xy 451.865821 -97.517588) (xy 451.888667 -97.567328) (xy 451.904166 -97.619824) (xy 451.911998 -97.673997)
			(xy 451.912003 -97.728733) (xy 451.904181 -97.782908) (xy 451.888692 -97.835407) (xy 451.865854 -97.885151)
			(xy 451.836138 -97.931119) (xy 451.818502 -97.952052) (xy 451.818248 -97.952306) (xy 451.812647 -97.959382)
			(xy 451.80641 -97.976307) (xy 451.806056 -97.985326) (xy 451.806056 -98.052382) (xy 451.80641 -98.061399)
			(xy 451.812658 -98.078317) (xy 451.818248 -98.085402) (xy 451.818502 -98.085402) (xy 451.818502 -98.085656)
			(xy 451.836134 -98.106594) (xy 451.865847 -98.152565) (xy 451.888684 -98.202311) (xy 451.904177 -98.25481)
			(xy 451.912007 -98.308985) (xy 451.912482 -98.336354) (xy 451.911996 -98.363605) (xy 451.90424 -98.417553)
			(xy 451.888885 -98.469848) (xy 451.866243 -98.519425) (xy 451.836777 -98.565275) (xy 451.801086 -98.606466)
			(xy 451.759895 -98.642157) (xy 451.714045 -98.671623) (xy 451.664468 -98.694265) (xy 451.612173 -98.70962)
			(xy 451.558225 -98.717376) (xy 451.503723 -98.717376) (xy 451.449775 -98.70962) (xy 451.39748 -98.694265)
			(xy 451.347903 -98.671623) (xy 451.302053 -98.642157) (xy 451.260862 -98.606466) (xy 451.225171 -98.565275)
			(xy 451.195705 -98.519425) (xy 451.173063 -98.469848) (xy 451.157708 -98.417553) (xy 451.149952 -98.363605)
			(xy 451.149466 -98.336354) (xy 450.573272 -98.336354) (xy 450.576218 -98.342804) (xy 450.591574 -98.3951)
			(xy 450.59933 -98.449048) (xy 450.59933 -98.503552) (xy 450.591574 -98.5575) (xy 450.576218 -98.609796)
			(xy 450.553577 -98.659374) (xy 450.52411 -98.705226) (xy 450.488418 -98.746417) (xy 450.447227 -98.782109)
			(xy 450.401376 -98.811576) (xy 450.351798 -98.834218) (xy 450.299502 -98.849573) (xy 450.245554 -98.85733)
			(xy 450.218302 -98.857816) (xy 450.191988 -98.857342) (xy 450.13986 -98.850108) (xy 450.089218 -98.83579)
			(xy 450.041019 -98.814658) (xy 449.996175 -98.787114) (xy 449.955535 -98.753677) (xy 449.937378 -98.734626)
			(xy 449.929863 -98.727216) (xy 449.910578 -98.718696) (xy 449.90004 -98.718116) (xy 449.825364 -98.718116)
			(xy 449.814816 -98.718662) (xy 449.79552 -98.727185) (xy 449.788026 -98.734626) (xy 449.769856 -98.753667)
			(xy 449.729229 -98.787124) (xy 449.684391 -98.814685) (xy 449.636194 -98.835826) (xy 449.585549 -98.850146)
			(xy 449.533417 -98.857375) (xy 449.507102 -98.857816) (xy 449.47985 -98.857337) (xy 449.4259 -98.84958)
			(xy 449.373603 -98.834225) (xy 449.324023 -98.811583) (xy 449.278171 -98.782115) (xy 449.236979 -98.746423)
			(xy 449.201286 -98.705231) (xy 449.171818 -98.659378) (xy 449.149176 -98.609799) (xy 449.13382 -98.557502)
			(xy 449.126063 -98.503552) (xy 448.136129 -98.503552) (xy 448.140074 -98.508566) (xy 448.140328 -98.509074)
			(xy 448.151273 -98.521808) (xy 448.171114 -98.548899) (xy 448.179952 -98.563176) (xy 448.185286 -98.572066)
			(xy 448.202304 -98.584258) (xy 448.295522 -98.604578) (xy 448.316096 -98.60026) (xy 448.324732 -98.594418)
			(xy 448.348787 -98.578404) (xy 448.400722 -98.553064) (xy 448.455882 -98.535842) (xy 448.513009 -98.527132)
			(xy 448.541902 -98.5266) (xy 448.569154 -98.52707) (xy 448.623102 -98.534827) (xy 448.675398 -98.550182)
			(xy 448.724976 -98.572824) (xy 448.770827 -98.602291) (xy 448.812018 -98.637983) (xy 448.84771 -98.679174)
			(xy 448.877177 -98.725026) (xy 448.899818 -98.774604) (xy 448.915174 -98.8269) (xy 448.92293 -98.880848)
			(xy 448.92293 -98.935352) (xy 448.915174 -98.9893) (xy 448.899818 -99.041596) (xy 448.877177 -99.091174)
			(xy 448.84771 -99.137026) (xy 448.812018 -99.178217) (xy 448.770827 -99.213909) (xy 448.724976 -99.243376)
			(xy 448.675398 -99.266018) (xy 448.623102 -99.281373) (xy 448.569154 -99.28913) (xy 448.541902 -99.289616)
			(xy 448.51381 -99.28912) (xy 448.458233 -99.280893) (xy 448.404464 -99.264602) (xy 448.353667 -99.2406)
			(xy 448.30694 -99.209405) (xy 448.265295 -99.171693) (xy 448.229633 -99.12828) (xy 448.21475 -99.10445)
			(xy 448.209416 -99.09556) (xy 448.192398 -99.083368) (xy 448.09918 -99.063048) (xy 448.078606 -99.067366)
			(xy 448.06997 -99.073208) (xy 448.045916 -99.089224) (xy 447.993981 -99.114563) (xy 447.93882 -99.131784)
			(xy 447.881693 -99.140494) (xy 447.8528 -99.141026) (xy 447.82555 -99.140522) (xy 447.771603 -99.132766)
			(xy 447.71931 -99.117412) (xy 447.669734 -99.094772) (xy 447.623885 -99.065308) (xy 447.582695 -99.029618)
			(xy 447.547003 -98.98843) (xy 447.517536 -98.942582) (xy 447.494894 -98.893007) (xy 447.479538 -98.840714)
			(xy 447.471779 -98.786768) (xy 447.471292 -98.759518) (xy 435.98174 -98.759518) (xy 435.970278 -98.776843)
			(xy 435.933061 -98.81838) (xy 435.890193 -98.854055) (xy 435.842587 -98.883109) (xy 435.791258 -98.904921)
			(xy 435.737301 -98.919027) (xy 435.681864 -98.925127) (xy 435.62613 -98.92309) (xy 435.571287 -98.91296)
			(xy 435.518503 -98.894953) (xy 435.468903 -98.869452) (xy 435.423545 -98.837001) (xy 435.383396 -98.798292)
			(xy 435.34931 -98.754149) (xy 435.322014 -98.705514) (xy 435.302091 -98.653423) (xy 435.289965 -98.598986)
			(xy 435.285894 -98.543364) (xy 424.328048 -98.543364) (xy 424.315429 -98.546663) (xy 424.259992 -98.552763)
			(xy 424.204258 -98.550726) (xy 424.149415 -98.540596) (xy 424.096631 -98.522589) (xy 424.047031 -98.497088)
			(xy 424.001673 -98.464637) (xy 423.961524 -98.425928) (xy 423.927438 -98.381785) (xy 423.900142 -98.33315)
			(xy 423.880219 -98.281059) (xy 423.868093 -98.226622) (xy 423.864022 -98.171) (xy 418.257327 -98.171)
			(xy 418.905436 -98.818954) (xy 418.91204 -98.820986) (xy 418.93801 -98.829172) (xy 418.9875 -98.851878)
			(xy 419.033264 -98.881384) (xy 419.074373 -98.91709) (xy 419.109993 -98.958273) (xy 419.139403 -99.004097)
			(xy 419.162007 -99.053635) (xy 419.177345 -99.10588) (xy 419.185107 -99.159775) (xy 419.185598 -99.187)
			(xy 419.185135 -99.214253) (xy 419.177378 -99.268203) (xy 419.162021 -99.3205) (xy 419.139379 -99.37008)
			(xy 419.109911 -99.415932) (xy 419.089069 -99.439984) (xy 423.610022 -99.439984) (xy 423.614093 -99.384362)
			(xy 423.626219 -99.329925) (xy 423.646142 -99.277834) (xy 423.673438 -99.229199) (xy 423.707524 -99.185056)
			(xy 423.747673 -99.146347) (xy 423.793031 -99.113896) (xy 423.842631 -99.088395) (xy 423.895415 -99.070388)
			(xy 423.950258 -99.060258) (xy 424.005992 -99.058221) (xy 424.061429 -99.064321) (xy 424.115386 -99.078427)
			(xy 424.166715 -99.100239) (xy 424.214321 -99.129293) (xy 424.257189 -99.164968) (xy 424.294406 -99.206505)
			(xy 424.325179 -99.253018) (xy 424.348851 -99.303515) (xy 424.364919 -99.356922) (xy 424.373039 -99.412098)
			(xy 424.373548 -99.439984) (xy 424.373376 -99.449382) (xy 436.206136 -99.449382) (xy 436.210207 -99.39376)
			(xy 436.222333 -99.339323) (xy 436.242256 -99.287232) (xy 436.269552 -99.238597) (xy 436.303638 -99.194454)
			(xy 436.343787 -99.155745) (xy 436.389145 -99.123294) (xy 436.438745 -99.097793) (xy 436.491529 -99.079786)
			(xy 436.546372 -99.069656) (xy 436.602106 -99.067619) (xy 436.657543 -99.073719) (xy 436.7115 -99.087825)
			(xy 436.762829 -99.109637) (xy 436.810435 -99.138691) (xy 436.853303 -99.174366) (xy 436.89052 -99.215903)
			(xy 436.921293 -99.262416) (xy 436.944965 -99.312913) (xy 436.961033 -99.36632) (xy 436.969153 -99.421496)
			(xy 436.969662 -99.449382) (xy 436.969495 -99.458526) (xy 441.938662 -99.458526) (xy 441.942733 -99.402904)
			(xy 441.954859 -99.348467) (xy 441.974782 -99.296376) (xy 442.002078 -99.247741) (xy 442.036164 -99.203598)
			(xy 442.076313 -99.164889) (xy 442.121671 -99.132438) (xy 442.171271 -99.106937) (xy 442.224055 -99.08893)
			(xy 442.278898 -99.0788) (xy 442.334632 -99.076763) (xy 442.390069 -99.082863) (xy 442.444026 -99.096969)
			(xy 442.495355 -99.118781) (xy 442.542961 -99.147835) (xy 442.585829 -99.18351) (xy 442.623046 -99.225047)
			(xy 442.653819 -99.27156) (xy 442.677491 -99.322057) (xy 442.693559 -99.375464) (xy 442.701679 -99.43064)
			(xy 442.702188 -99.458526) (xy 442.701679 -99.486412) (xy 442.693559 -99.541588) (xy 442.677491 -99.594995)
			(xy 442.653819 -99.645492) (xy 442.623046 -99.692005) (xy 442.585829 -99.733542) (xy 442.542961 -99.769217)
			(xy 442.495355 -99.798271) (xy 442.444026 -99.820083) (xy 442.390069 -99.834189) (xy 442.334632 -99.840289)
			(xy 442.278898 -99.838252) (xy 442.224055 -99.828122) (xy 442.171271 -99.810115) (xy 442.121671 -99.784614)
			(xy 442.076313 -99.752163) (xy 442.036164 -99.713454) (xy 442.002078 -99.669311) (xy 441.974782 -99.620676)
			(xy 441.954859 -99.568585) (xy 441.942733 -99.514148) (xy 441.938662 -99.458526) (xy 436.969495 -99.458526)
			(xy 436.969153 -99.477268) (xy 436.961033 -99.532444) (xy 436.944965 -99.585851) (xy 436.921293 -99.636348)
			(xy 436.89052 -99.682861) (xy 436.853303 -99.724398) (xy 436.810435 -99.760073) (xy 436.762829 -99.789127)
			(xy 436.7115 -99.810939) (xy 436.657543 -99.825045) (xy 436.602106 -99.831145) (xy 436.546372 -99.829108)
			(xy 436.491529 -99.818978) (xy 436.438745 -99.800971) (xy 436.389145 -99.77547) (xy 436.343787 -99.743019)
			(xy 436.303638 -99.70431) (xy 436.269552 -99.660167) (xy 436.242256 -99.611532) (xy 436.222333 -99.559441)
			(xy 436.210207 -99.505004) (xy 436.206136 -99.449382) (xy 424.373376 -99.449382) (xy 424.373039 -99.46787)
			(xy 424.364919 -99.523046) (xy 424.348851 -99.576453) (xy 424.325179 -99.62695) (xy 424.294406 -99.673463)
			(xy 424.257189 -99.715) (xy 424.214321 -99.750675) (xy 424.166715 -99.779729) (xy 424.115386 -99.801541)
			(xy 424.061429 -99.815647) (xy 424.005992 -99.821747) (xy 423.950258 -99.81971) (xy 423.895415 -99.80958)
			(xy 423.842631 -99.791573) (xy 423.793031 -99.766072) (xy 423.747673 -99.733621) (xy 423.707524 -99.694912)
			(xy 423.673438 -99.650769) (xy 423.646142 -99.602134) (xy 423.626219 -99.550043) (xy 423.614093 -99.495606)
			(xy 423.610022 -99.439984) (xy 419.089069 -99.439984) (xy 419.074217 -99.457124) (xy 419.033024 -99.492817)
			(xy 418.987171 -99.522284) (xy 418.937591 -99.544925) (xy 418.885293 -99.56028) (xy 418.831343 -99.568035)
			(xy 418.80409 -99.568508) (xy 418.776861 -99.56803) (xy 418.722953 -99.560299) (xy 418.670694 -99.54498)
			(xy 418.621143 -99.522386) (xy 418.575309 -99.492975) (xy 418.534123 -99.457346) (xy 418.498422 -99.416222)
			(xy 418.468932 -99.370439) (xy 418.446252 -99.320928) (xy 418.438076 -99.29495) (xy 418.436044 -99.288346)
			(xy 417.263072 -98.115374) (xy 417.24504 -98.096603) (xy 417.214462 -98.054487) (xy 417.190837 -98.00811)
			(xy 417.174748 -97.958613) (xy 417.166589 -97.907209) (xy 417.166044 -97.881186) (xy 417.166044 -97.173796)
			(xy 417.16562 -97.163749) (xy 417.157916 -97.14519) (xy 417.143686 -97.131001) (xy 417.134548 -97.126806)
			(xy 417.120324 -97.12071) (xy 417.090352 -97.126806) (xy 416.712908 -97.50425) (xy 416.689343 -97.527146)
			(xy 416.637959 -97.568095) (xy 416.582315 -97.603039) (xy 416.523112 -97.631537) (xy 416.461091 -97.653233)
			(xy 416.397033 -97.667853) (xy 416.331741 -97.675214) (xy 416.298888 -97.6757) (xy 415.508694 -97.6757)
			(xy 415.475841 -97.675239) (xy 415.410547 -97.667882) (xy 415.346487 -97.653261) (xy 415.284467 -97.63156)
			(xy 415.225267 -97.603051) (xy 415.169631 -97.568094) (xy 415.118258 -97.527128) (xy 415.094674 -97.50425)
			(xy 414.406588 -96.81591) (xy 414.399189 -96.809065) (xy 414.380591 -96.801333) (xy 414.37052 -96.800924)
			(xy 406.208484 -96.800924) (xy 406.170243 -96.800289) (xy 406.094417 -96.790299) (xy 406.020538 -96.770519)
			(xy 405.984964 -96.756474) (xy 405.922226 -96.730566) (xy 405.912836 -96.727223) (xy 405.892923 -96.727231)
			(xy 405.874511 -96.734814) (xy 405.867108 -96.741488) (xy 403.803866 -98.80473) (xy 403.796469 -98.811579)
			(xy 403.77787 -98.819312) (xy 403.767798 -98.819716) (xy 402.796502 -98.819716) (xy 402.788628 -98.820224)
			(xy 402.779472 -98.82212) (xy 402.763316 -98.8315) (xy 402.757132 -98.838512) (xy 402.751036 -98.84664)
			(xy 402.71573 -98.933508) (xy 402.712555 -98.942351) (xy 402.712157 -98.961119) (xy 402.714968 -98.970084)
			(xy 402.715984 -98.972624) (xy 402.720556 -98.983546) (xy 402.722377 -98.987643) (xy 402.727234 -98.995178)
			(xy 402.730208 -98.998532) (xy 402.732494 -99.001072) (xy 402.733002 -99.001834) (xy 402.733256 -99.001834)
			(xy 402.75369 -99.024677) (xy 402.788899 -99.074846) (xy 402.817094 -99.129267) (xy 402.837771 -99.186964)
			(xy 402.850561 -99.246906) (xy 402.853398 -99.277424) (xy 402.854668 -99.30511) (xy 402.854668 -100.039932)
			(xy 422.176954 -100.039932) (xy 422.181025 -99.98431) (xy 422.193151 -99.929873) (xy 422.213074 -99.877782)
			(xy 422.24037 -99.829147) (xy 422.274456 -99.785004) (xy 422.314605 -99.746295) (xy 422.359963 -99.713844)
			(xy 422.409563 -99.688343) (xy 422.462347 -99.670336) (xy 422.51719 -99.660206) (xy 422.572924 -99.658169)
			(xy 422.628361 -99.664269) (xy 422.682318 -99.678375) (xy 422.733647 -99.700187) (xy 422.781253 -99.729241)
			(xy 422.824121 -99.764916) (xy 422.861338 -99.806453) (xy 422.892111 -99.852966) (xy 422.915783 -99.903463)
			(xy 422.931851 -99.95687) (xy 422.939971 -100.012046) (xy 422.94048 -100.039932) (xy 422.939971 -100.067818)
			(xy 422.931851 -100.122994) (xy 422.915783 -100.176401) (xy 422.892111 -100.226898) (xy 422.861338 -100.273411)
			(xy 422.824121 -100.314948) (xy 422.781253 -100.350623) (xy 422.733647 -100.379677) (xy 422.682318 -100.401489)
			(xy 422.628361 -100.415595) (xy 422.572924 -100.421695) (xy 422.51719 -100.419658) (xy 422.462347 -100.409528)
			(xy 422.409563 -100.391521) (xy 422.359963 -100.36602) (xy 422.314605 -100.333569) (xy 422.274456 -100.29486)
			(xy 422.24037 -100.250717) (xy 422.213074 -100.202082) (xy 422.193151 -100.149991) (xy 422.181025 -100.095554)
			(xy 422.176954 -100.039932) (xy 402.854668 -100.039932) (xy 402.854668 -100.17633) (xy 402.854178 -100.206298)
			(xy 402.846355 -100.26572) (xy 402.830842 -100.323613) (xy 402.807906 -100.378986) (xy 402.777939 -100.430892)
			(xy 402.741452 -100.478442) (xy 402.699072 -100.520822) (xy 402.651522 -100.557309) (xy 402.599616 -100.587276)
			(xy 402.544243 -100.610212) (xy 402.48635 -100.625725) (xy 402.426928 -100.633548) (xy 402.366992 -100.633548)
			(xy 402.30757 -100.625725) (xy 402.249677 -100.610212) (xy 402.194304 -100.587276) (xy 402.142398 -100.557309)
			(xy 402.094848 -100.520822) (xy 402.052468 -100.478442) (xy 402.015981 -100.430892) (xy 401.986014 -100.378986)
			(xy 401.963078 -100.323613) (xy 401.947565 -100.26572) (xy 401.939742 -100.206298) (xy 401.939252 -100.17633)
			(xy 401.939252 -99.304348) (xy 401.940162 -99.276489) (xy 401.947915 -99.22129) (xy 401.962315 -99.167441)
			(xy 401.983147 -99.11574) (xy 402.010103 -99.06695) (xy 402.042785 -99.021796) (xy 402.061426 -99.001072)
			(xy 402.063712 -98.998532) (xy 402.066789 -98.995076) (xy 402.071774 -98.987282) (xy 402.073618 -98.983038)
			(xy 402.077428 -98.97364) (xy 402.079206 -98.969068) (xy 402.079968 -98.966528) (xy 402.082081 -98.958279)
			(xy 402.081297 -98.941278) (xy 402.078444 -98.933254) (xy 402.077682 -98.931476) (xy 402.047456 -98.858324)
			(xy 402.046948 -98.857054) (xy 402.046186 -98.855784) (xy 402.041868 -98.847402) (xy 402.041868 -98.847148)
			(xy 402.037504 -98.839508) (xy 402.024624 -98.827538) (xy 402.008457 -98.820628) (xy 401.999704 -98.819716)
			(xy 392.171428 -98.819716) (xy 392.162792 -98.820478) (xy 392.154156 -98.822764) (xy 392.145774 -98.826066)
			(xy 392.142472 -98.827082) (xy 392.129264 -98.82886) (xy 389.77951 -98.82886) (xy 389.773501 -98.829032)
			(xy 389.761823 -98.831862) (xy 389.756396 -98.834448) (xy 389.752922 -98.836288) (xy 389.746545 -98.840884)
			(xy 389.743696 -98.843592) (xy 389.417052 -99.170236) (xy 389.414347 -99.173088) (xy 389.409757 -99.179467)
			(xy 389.407908 -99.182936) (xy 389.405324 -99.188363) (xy 389.402498 -99.200042) (xy 389.40232 -99.20605)
			(xy 389.40232 -101.976428) (xy 400.085052 -101.976428) (xy 400.085052 -101.112828) (xy 400.085542 -101.08286)
			(xy 400.093365 -101.023438) (xy 400.108878 -100.965545) (xy 400.131814 -100.910172) (xy 400.161781 -100.858266)
			(xy 400.198268 -100.810716) (xy 400.240648 -100.768336) (xy 400.288198 -100.731849) (xy 400.340104 -100.701882)
			(xy 400.395477 -100.678946) (xy 400.45337 -100.663433) (xy 400.512792 -100.65561) (xy 400.572728 -100.65561)
			(xy 400.63215 -100.663433) (xy 400.690043 -100.678946) (xy 400.745416 -100.701882) (xy 400.797322 -100.731849)
			(xy 400.842313 -100.766372) (xy 405.89784 -100.766372) (xy 405.901911 -100.71075) (xy 405.914037 -100.656313)
			(xy 405.93396 -100.604222) (xy 405.961256 -100.555587) (xy 405.995342 -100.511444) (xy 406.035491 -100.472735)
			(xy 406.080849 -100.440284) (xy 406.130449 -100.414783) (xy 406.183233 -100.396776) (xy 406.238076 -100.386646)
			(xy 406.29381 -100.384609) (xy 406.349247 -100.390709) (xy 406.403204 -100.404815) (xy 406.454533 -100.426627)
			(xy 406.502139 -100.455681) (xy 406.545007 -100.491356) (xy 406.582224 -100.532893) (xy 406.612997 -100.579406)
			(xy 406.636669 -100.629903) (xy 406.652737 -100.68331) (xy 406.660857 -100.738486) (xy 406.661366 -100.766372)
			(xy 406.660857 -100.794258) (xy 406.652737 -100.849434) (xy 406.636669 -100.902841) (xy 406.612997 -100.953338)
			(xy 406.582224 -100.999851) (xy 406.545007 -101.041388) (xy 406.502139 -101.077063) (xy 406.454533 -101.106117)
			(xy 406.403204 -101.127929) (xy 406.349247 -101.142035) (xy 406.29381 -101.148135) (xy 406.238076 -101.146098)
			(xy 406.183233 -101.135968) (xy 406.130449 -101.117961) (xy 406.080849 -101.09246) (xy 406.035491 -101.060009)
			(xy 405.995342 -101.0213) (xy 405.961256 -100.977157) (xy 405.93396 -100.928522) (xy 405.914037 -100.876431)
			(xy 405.901911 -100.821994) (xy 405.89784 -100.766372) (xy 400.842313 -100.766372) (xy 400.844872 -100.768336)
			(xy 400.887252 -100.810716) (xy 400.923739 -100.858266) (xy 400.953706 -100.910172) (xy 400.976642 -100.965545)
			(xy 400.992155 -101.023438) (xy 400.999978 -101.08286) (xy 401.000468 -101.112828) (xy 401.000468 -101.240082)
			(xy 422.594022 -101.240082) (xy 422.598093 -101.18446) (xy 422.610219 -101.130023) (xy 422.630142 -101.077932)
			(xy 422.657438 -101.029297) (xy 422.691524 -100.985154) (xy 422.731673 -100.946445) (xy 422.777031 -100.913994)
			(xy 422.826631 -100.888493) (xy 422.879415 -100.870486) (xy 422.934258 -100.860356) (xy 422.989992 -100.858319)
			(xy 423.045429 -100.864419) (xy 423.099386 -100.878525) (xy 423.150715 -100.900337) (xy 423.198321 -100.929391)
			(xy 423.241189 -100.965066) (xy 423.278406 -101.006603) (xy 423.309179 -101.053116) (xy 423.316929 -101.069648)
			(xy 423.886374 -101.069648) (xy 423.890445 -101.014026) (xy 423.902571 -100.959589) (xy 423.922494 -100.907498)
			(xy 423.94979 -100.858863) (xy 423.983876 -100.81472) (xy 424.024025 -100.776011) (xy 424.069383 -100.74356)
			(xy 424.118983 -100.718059) (xy 424.171767 -100.700052) (xy 424.22661 -100.689922) (xy 424.282344 -100.687885)
			(xy 424.337781 -100.693985) (xy 424.391738 -100.708091) (xy 424.443067 -100.729903) (xy 424.490673 -100.758957)
			(xy 424.533541 -100.794632) (xy 424.570758 -100.836169) (xy 424.601531 -100.882682) (xy 424.625203 -100.933179)
			(xy 424.641271 -100.986586) (xy 424.649391 -101.041762) (xy 424.6499 -101.069648) (xy 426.469554 -101.069648)
			(xy 426.473625 -101.014026) (xy 426.485751 -100.959589) (xy 426.505674 -100.907498) (xy 426.53297 -100.858863)
			(xy 426.567056 -100.81472) (xy 426.607205 -100.776011) (xy 426.652563 -100.74356) (xy 426.702163 -100.718059)
			(xy 426.754947 -100.700052) (xy 426.80979 -100.689922) (xy 426.865524 -100.687885) (xy 426.920961 -100.693985)
			(xy 426.974918 -100.708091) (xy 427.026247 -100.729903) (xy 427.073853 -100.758957) (xy 427.116721 -100.794632)
			(xy 427.153938 -100.836169) (xy 427.184711 -100.882682) (xy 427.208383 -100.933179) (xy 427.224451 -100.986586)
			(xy 427.232571 -101.041762) (xy 427.23308 -101.069648) (xy 427.232571 -101.097534) (xy 427.224451 -101.15271)
			(xy 427.213277 -101.18985) (xy 445.29349 -101.18985) (xy 445.29349 -101.13535) (xy 445.301246 -101.081404)
			(xy 445.316601 -101.029111) (xy 445.339241 -100.979536) (xy 445.368706 -100.933687) (xy 445.404396 -100.892499)
			(xy 445.445584 -100.856808) (xy 445.491433 -100.827343) (xy 445.541008 -100.804702) (xy 445.5933 -100.789347)
			(xy 445.647246 -100.781591) (xy 445.674496 -100.781104) (xy 445.701866 -100.781571) (xy 445.756045 -100.789389)
			(xy 445.808548 -100.804877) (xy 445.858295 -100.827719) (xy 445.904262 -100.857443) (xy 445.925194 -100.875084)
			(xy 445.925448 -100.875338) (xy 445.932542 -100.880913) (xy 445.949453 -100.887166) (xy 445.958468 -100.88753)
			(xy 446.025524 -100.88753) (xy 446.034541 -100.887178) (xy 446.051458 -100.880926) (xy 446.058544 -100.875338)
			(xy 446.058544 -100.875084) (xy 446.058798 -100.875084) (xy 446.079718 -100.85743) (xy 446.125694 -100.827721)
			(xy 446.175445 -100.804888) (xy 446.227948 -100.7894) (xy 446.282126 -100.781576) (xy 446.309496 -100.781104)
			(xy 446.33675 -100.781543) (xy 446.390703 -100.789299) (xy 446.443003 -100.804656) (xy 446.492585 -100.827299)
			(xy 446.53844 -100.856767) (xy 446.579635 -100.892462) (xy 446.61533 -100.933656) (xy 446.6448 -100.979511)
			(xy 446.667443 -101.029093) (xy 446.6828 -101.081393) (xy 446.690557 -101.135346) (xy 446.690557 -101.189854)
			(xy 446.6828 -101.243807) (xy 446.667443 -101.296107) (xy 446.6448 -101.345689) (xy 446.61533 -101.391544)
			(xy 446.579635 -101.432738) (xy 446.53844 -101.468433) (xy 446.492585 -101.497901) (xy 446.443003 -101.520544)
			(xy 446.390703 -101.535901) (xy 446.33675 -101.543657) (xy 446.309496 -101.54412) (xy 446.282125 -101.543676)
			(xy 446.227944 -101.535856) (xy 446.17544 -101.520363) (xy 446.125693 -101.497515) (xy 446.079728 -101.467785)
			(xy 446.058798 -101.45014) (xy 446.058544 -101.449886) (xy 446.05145 -101.44431) (xy 446.034539 -101.438057)
			(xy 446.025524 -101.437694) (xy 445.958468 -101.437694) (xy 445.94945 -101.438037) (xy 445.932533 -101.444295)
			(xy 445.925448 -101.449886) (xy 445.925448 -101.45014) (xy 445.925194 -101.45014) (xy 445.90428 -101.467802)
			(xy 445.858302 -101.497509) (xy 445.80855 -101.52034) (xy 445.756045 -101.535826) (xy 445.701866 -101.543649)
			(xy 445.674496 -101.54412) (xy 445.647246 -101.543609) (xy 445.5933 -101.535853) (xy 445.541008 -101.520498)
			(xy 445.491433 -101.497857) (xy 445.445584 -101.468392) (xy 445.404396 -101.432701) (xy 445.368706 -101.391513)
			(xy 445.339241 -101.345664) (xy 445.316601 -101.296089) (xy 445.301246 -101.243796) (xy 445.29349 -101.18985)
			(xy 427.213277 -101.18985) (xy 427.208383 -101.206117) (xy 427.184711 -101.256614) (xy 427.153938 -101.303127)
			(xy 427.116721 -101.344664) (xy 427.073853 -101.380339) (xy 427.026247 -101.409393) (xy 426.974918 -101.431205)
			(xy 426.920961 -101.445311) (xy 426.865524 -101.451411) (xy 426.80979 -101.449374) (xy 426.754947 -101.439244)
			(xy 426.702163 -101.421237) (xy 426.652563 -101.395736) (xy 426.607205 -101.363285) (xy 426.567056 -101.324576)
			(xy 426.53297 -101.280433) (xy 426.505674 -101.231798) (xy 426.485751 -101.179707) (xy 426.473625 -101.12527)
			(xy 426.469554 -101.069648) (xy 424.6499 -101.069648) (xy 424.649391 -101.097534) (xy 424.641271 -101.15271)
			(xy 424.625203 -101.206117) (xy 424.601531 -101.256614) (xy 424.570758 -101.303127) (xy 424.533541 -101.344664)
			(xy 424.490673 -101.380339) (xy 424.443067 -101.409393) (xy 424.391738 -101.431205) (xy 424.337781 -101.445311)
			(xy 424.282344 -101.451411) (xy 424.22661 -101.449374) (xy 424.171767 -101.439244) (xy 424.118983 -101.421237)
			(xy 424.069383 -101.395736) (xy 424.024025 -101.363285) (xy 423.983876 -101.324576) (xy 423.94979 -101.280433)
			(xy 423.922494 -101.231798) (xy 423.902571 -101.179707) (xy 423.890445 -101.12527) (xy 423.886374 -101.069648)
			(xy 423.316929 -101.069648) (xy 423.332851 -101.103613) (xy 423.348919 -101.15702) (xy 423.357039 -101.212196)
			(xy 423.357548 -101.240082) (xy 423.357039 -101.267968) (xy 423.348919 -101.323144) (xy 423.332851 -101.376551)
			(xy 423.309179 -101.427048) (xy 423.278406 -101.473561) (xy 423.241189 -101.515098) (xy 423.198321 -101.550773)
			(xy 423.151788 -101.579172) (xy 436.070754 -101.579172) (xy 436.074825 -101.52355) (xy 436.086951 -101.469113)
			(xy 436.106874 -101.417022) (xy 436.13417 -101.368387) (xy 436.168256 -101.324244) (xy 436.208405 -101.285535)
			(xy 436.253763 -101.253084) (xy 436.303363 -101.227583) (xy 436.356147 -101.209576) (xy 436.41099 -101.199446)
			(xy 436.466724 -101.197409) (xy 436.522161 -101.203509) (xy 436.576118 -101.217615) (xy 436.627447 -101.239427)
			(xy 436.675053 -101.268481) (xy 436.717921 -101.304156) (xy 436.755138 -101.345693) (xy 436.785911 -101.392206)
			(xy 436.809583 -101.442703) (xy 436.825651 -101.49611) (xy 436.833771 -101.551286) (xy 436.83428 -101.579172)
			(xy 436.833771 -101.607058) (xy 436.825651 -101.662234) (xy 436.809583 -101.715641) (xy 436.785911 -101.766138)
			(xy 436.755138 -101.812651) (xy 436.717921 -101.854188) (xy 436.698003 -101.870764) (xy 441.53912 -101.870764)
			(xy 441.543191 -101.815142) (xy 441.555317 -101.760705) (xy 441.57524 -101.708614) (xy 441.602536 -101.659979)
			(xy 441.636622 -101.615836) (xy 441.676771 -101.577127) (xy 441.722129 -101.544676) (xy 441.771729 -101.519175)
			(xy 441.824513 -101.501168) (xy 441.879356 -101.491038) (xy 441.93509 -101.489001) (xy 441.990527 -101.495101)
			(xy 442.044484 -101.509207) (xy 442.095813 -101.531019) (xy 442.143419 -101.560073) (xy 442.186287 -101.595748)
			(xy 442.223504 -101.637285) (xy 442.254277 -101.683798) (xy 442.277949 -101.734295) (xy 442.294017 -101.787702)
			(xy 442.302137 -101.842878) (xy 442.302646 -101.870764) (xy 442.302137 -101.89865) (xy 442.294017 -101.953826)
			(xy 442.277949 -102.007233) (xy 442.254277 -102.05773) (xy 442.223504 -102.104243) (xy 442.200022 -102.130451)
			(xy 444.843152 -102.130451) (xy 444.843152 -102.075949) (xy 444.850908 -102.022002) (xy 444.866261 -101.969707)
			(xy 444.888901 -101.920129) (xy 444.918365 -101.874278) (xy 444.954054 -101.833086) (xy 444.995241 -101.797392)
			(xy 445.041089 -101.767923) (xy 445.090664 -101.745277) (xy 445.142957 -101.729917) (xy 445.196903 -101.722155)
			(xy 445.224154 -101.721666) (xy 445.251524 -101.722143) (xy 445.305703 -101.729956) (xy 445.358207 -101.745441)
			(xy 445.407954 -101.768281) (xy 445.453921 -101.798005) (xy 445.474852 -101.815646) (xy 445.475106 -101.8159)
			(xy 445.482187 -101.821495) (xy 445.499108 -101.827737) (xy 445.508126 -101.828092) (xy 445.575182 -101.828092)
			(xy 445.584198 -101.827728) (xy 445.601115 -101.821486) (xy 445.608202 -101.8159) (xy 445.608202 -101.815646)
			(xy 445.608456 -101.815646) (xy 445.6294 -101.798021) (xy 445.675369 -101.768306) (xy 445.725113 -101.745466)
			(xy 445.777611 -101.729972) (xy 445.831786 -101.722141) (xy 445.859154 -101.721666) (xy 445.886407 -101.722178)
			(xy 445.940359 -101.729929) (xy 445.992659 -101.74528) (xy 446.042242 -101.767919) (xy 446.088097 -101.797383)
			(xy 446.129293 -101.833075) (xy 446.164989 -101.874266) (xy 446.194459 -101.920118) (xy 446.217104 -101.969698)
			(xy 446.232461 -102.021996) (xy 446.240219 -102.075947) (xy 446.240219 -102.130453) (xy 446.232461 -102.184404)
			(xy 446.217104 -102.236702) (xy 446.194459 -102.286282) (xy 446.164989 -102.332134) (xy 446.129293 -102.373325)
			(xy 446.088097 -102.409017) (xy 446.042242 -102.438481) (xy 445.992659 -102.46112) (xy 445.940359 -102.476471)
			(xy 445.886407 -102.484222) (xy 445.859154 -102.484682) (xy 445.831785 -102.484189) (xy 445.777607 -102.476378)
			(xy 445.725104 -102.460896) (xy 445.675356 -102.43806) (xy 445.629388 -102.408341) (xy 445.608456 -102.390702)
			(xy 445.608202 -102.390448) (xy 445.601124 -102.38485) (xy 445.5842 -102.378611) (xy 445.575182 -102.378256)
			(xy 445.508126 -102.378256) (xy 445.499109 -102.378613) (xy 445.482191 -102.384859) (xy 445.475106 -102.390448)
			(xy 445.475106 -102.390702) (xy 445.474852 -102.390702) (xy 445.453911 -102.40833) (xy 445.407941 -102.438044)
			(xy 445.358196 -102.460882) (xy 445.305697 -102.476375) (xy 445.251523 -102.484206) (xy 445.224154 -102.484682)
			(xy 445.196903 -102.484245) (xy 445.142957 -102.476483) (xy 445.090664 -102.461123) (xy 445.041089 -102.438477)
			(xy 444.995241 -102.409008) (xy 444.954054 -102.373314) (xy 444.918365 -102.332122) (xy 444.888901 -102.286271)
			(xy 444.866261 -102.236693) (xy 444.850908 -102.184398) (xy 444.843152 -102.130451) (xy 442.200022 -102.130451)
			(xy 442.186287 -102.14578) (xy 442.143419 -102.181455) (xy 442.095813 -102.210509) (xy 442.044484 -102.232321)
			(xy 441.990527 -102.246427) (xy 441.93509 -102.252527) (xy 441.879356 -102.25049) (xy 441.824513 -102.24036)
			(xy 441.771729 -102.222353) (xy 441.722129 -102.196852) (xy 441.676771 -102.164401) (xy 441.636622 -102.125692)
			(xy 441.602536 -102.081549) (xy 441.57524 -102.032914) (xy 441.555317 -101.980823) (xy 441.543191 -101.926386)
			(xy 441.53912 -101.870764) (xy 436.698003 -101.870764) (xy 436.675053 -101.889863) (xy 436.627447 -101.918917)
			(xy 436.576118 -101.940729) (xy 436.522161 -101.954835) (xy 436.466724 -101.960935) (xy 436.41099 -101.958898)
			(xy 436.356147 -101.948768) (xy 436.303363 -101.930761) (xy 436.253763 -101.90526) (xy 436.208405 -101.872809)
			(xy 436.168256 -101.8341) (xy 436.13417 -101.789957) (xy 436.106874 -101.741322) (xy 436.086951 -101.689231)
			(xy 436.074825 -101.634794) (xy 436.070754 -101.579172) (xy 423.151788 -101.579172) (xy 423.150715 -101.579827)
			(xy 423.099386 -101.601639) (xy 423.045429 -101.615745) (xy 422.989992 -101.621845) (xy 422.934258 -101.619808)
			(xy 422.879415 -101.609678) (xy 422.826631 -101.591671) (xy 422.777031 -101.56617) (xy 422.731673 -101.533719)
			(xy 422.691524 -101.49501) (xy 422.657438 -101.450867) (xy 422.630142 -101.402232) (xy 422.610219 -101.350141)
			(xy 422.598093 -101.295704) (xy 422.594022 -101.240082) (xy 401.000468 -101.240082) (xy 401.000468 -101.976428)
			(xy 400.999978 -102.006396) (xy 400.992155 -102.065818) (xy 400.976642 -102.123711) (xy 400.953706 -102.179084)
			(xy 400.923739 -102.23099) (xy 400.887252 -102.27854) (xy 400.844872 -102.32092) (xy 400.797322 -102.357407)
			(xy 400.745416 -102.387374) (xy 400.690043 -102.41031) (xy 400.63215 -102.425823) (xy 400.572728 -102.433646)
			(xy 400.512792 -102.433646) (xy 400.45337 -102.425823) (xy 400.395477 -102.41031) (xy 400.340104 -102.387374)
			(xy 400.288198 -102.357407) (xy 400.240648 -102.32092) (xy 400.198268 -102.27854) (xy 400.161781 -102.23099)
			(xy 400.131814 -102.179084) (xy 400.108878 -102.123711) (xy 400.093365 -102.065818) (xy 400.085542 -102.006396)
			(xy 400.085052 -101.976428) (xy 389.40232 -101.976428) (xy 389.40232 -103.776272) (xy 401.939252 -103.776272)
			(xy 401.939252 -102.912672) (xy 401.939742 -102.882704) (xy 401.947565 -102.823282) (xy 401.963078 -102.765389)
			(xy 401.986014 -102.710016) (xy 402.015981 -102.65811) (xy 402.052468 -102.61056) (xy 402.094848 -102.56818)
			(xy 402.142398 -102.531693) (xy 402.194304 -102.501726) (xy 402.249677 -102.47879) (xy 402.30757 -102.463277)
			(xy 402.366992 -102.455454) (xy 402.426928 -102.455454) (xy 402.48635 -102.463277) (xy 402.544243 -102.47879)
			(xy 402.568892 -102.489) (xy 423.102022 -102.489) (xy 423.106093 -102.433378) (xy 423.118219 -102.378941)
			(xy 423.138142 -102.32685) (xy 423.165438 -102.278215) (xy 423.199524 -102.234072) (xy 423.239673 -102.195363)
			(xy 423.285031 -102.162912) (xy 423.334631 -102.137411) (xy 423.387415 -102.119404) (xy 423.442258 -102.109274)
			(xy 423.497992 -102.107237) (xy 423.553429 -102.113337) (xy 423.607386 -102.127443) (xy 423.658715 -102.149255)
			(xy 423.706321 -102.178309) (xy 423.749189 -102.213984) (xy 423.786406 -102.255521) (xy 423.817179 -102.302034)
			(xy 423.840851 -102.352531) (xy 423.856919 -102.405938) (xy 423.865039 -102.461114) (xy 423.865548 -102.489)
			(xy 423.865039 -102.516886) (xy 423.856919 -102.572062) (xy 423.840851 -102.625469) (xy 423.817179 -102.675966)
			(xy 423.786406 -102.722479) (xy 423.749189 -102.764016) (xy 423.706321 -102.799691) (xy 423.658715 -102.828745)
			(xy 423.607386 -102.850557) (xy 423.553429 -102.864663) (xy 423.497992 -102.870763) (xy 423.442258 -102.868726)
			(xy 423.387415 -102.858596) (xy 423.334631 -102.840589) (xy 423.285031 -102.815088) (xy 423.239673 -102.782637)
			(xy 423.199524 -102.743928) (xy 423.165438 -102.699785) (xy 423.138142 -102.65115) (xy 423.118219 -102.599059)
			(xy 423.106093 -102.544622) (xy 423.102022 -102.489) (xy 402.568892 -102.489) (xy 402.599616 -102.501726)
			(xy 402.651522 -102.531693) (xy 402.699072 -102.56818) (xy 402.741452 -102.61056) (xy 402.777939 -102.65811)
			(xy 402.807906 -102.710016) (xy 402.830842 -102.765389) (xy 402.846355 -102.823282) (xy 402.854178 -102.882704)
			(xy 402.854668 -102.912672) (xy 402.854668 -103.13924) (xy 437.807098 -103.13924) (xy 437.811169 -103.083618)
			(xy 437.823295 -103.029181) (xy 437.843218 -102.97709) (xy 437.870514 -102.928455) (xy 437.9046 -102.884312)
			(xy 437.944749 -102.845603) (xy 437.990107 -102.813152) (xy 438.039707 -102.787651) (xy 438.092491 -102.769644)
			(xy 438.147334 -102.759514) (xy 438.203068 -102.757477) (xy 438.258505 -102.763577) (xy 438.312462 -102.777683)
			(xy 438.363791 -102.799495) (xy 438.411397 -102.828549) (xy 438.454265 -102.864224) (xy 438.491482 -102.905761)
			(xy 438.522255 -102.952274) (xy 438.545927 -103.002771) (xy 438.561995 -103.056178) (xy 438.570115 -103.111354)
			(xy 438.570624 -103.13924) (xy 438.570115 -103.167126) (xy 438.561995 -103.222302) (xy 438.545927 -103.275709)
			(xy 438.522255 -103.326206) (xy 438.491482 -103.372719) (xy 438.454265 -103.414256) (xy 438.411397 -103.449931)
			(xy 438.363791 -103.478985) (xy 438.312462 -103.500797) (xy 438.258505 -103.514903) (xy 438.203068 -103.521003)
			(xy 438.147334 -103.518966) (xy 438.092491 -103.508836) (xy 438.039707 -103.490829) (xy 437.990107 -103.465328)
			(xy 437.944749 -103.432877) (xy 437.9046 -103.394168) (xy 437.870514 -103.350025) (xy 437.843218 -103.30139)
			(xy 437.823295 -103.249299) (xy 437.811169 -103.194862) (xy 437.807098 -103.13924) (xy 402.854668 -103.13924)
			(xy 402.854668 -103.776272) (xy 402.854178 -103.80624) (xy 402.846355 -103.865662) (xy 402.840905 -103.886)
			(xy 423.610022 -103.886) (xy 423.614093 -103.830378) (xy 423.626219 -103.775941) (xy 423.646142 -103.72385)
			(xy 423.673438 -103.675215) (xy 423.707524 -103.631072) (xy 423.747673 -103.592363) (xy 423.793031 -103.559912)
			(xy 423.842631 -103.534411) (xy 423.895415 -103.516404) (xy 423.950258 -103.506274) (xy 424.005992 -103.504237)
			(xy 424.061429 -103.510337) (xy 424.115386 -103.524443) (xy 424.166715 -103.546255) (xy 424.214321 -103.575309)
			(xy 424.257189 -103.610984) (xy 424.294406 -103.652521) (xy 424.325179 -103.699034) (xy 424.348851 -103.749531)
			(xy 424.364919 -103.802938) (xy 424.373039 -103.858114) (xy 424.373548 -103.886) (xy 424.373039 -103.913886)
			(xy 424.364919 -103.969062) (xy 424.348851 -104.022469) (xy 424.325179 -104.072966) (xy 424.294406 -104.119479)
			(xy 424.257189 -104.161016) (xy 424.214321 -104.196691) (xy 424.166715 -104.225745) (xy 424.115386 -104.247557)
			(xy 424.061429 -104.261663) (xy 424.005992 -104.267763) (xy 423.950258 -104.265726) (xy 423.895415 -104.255596)
			(xy 423.842631 -104.237589) (xy 423.793031 -104.212088) (xy 423.747673 -104.179637) (xy 423.707524 -104.140928)
			(xy 423.673438 -104.096785) (xy 423.646142 -104.04815) (xy 423.626219 -103.996059) (xy 423.614093 -103.941622)
			(xy 423.610022 -103.886) (xy 402.840905 -103.886) (xy 402.830842 -103.923555) (xy 402.807906 -103.978928)
			(xy 402.777939 -104.030834) (xy 402.741452 -104.078384) (xy 402.699072 -104.120764) (xy 402.651522 -104.157251)
			(xy 402.599616 -104.187218) (xy 402.544243 -104.210154) (xy 402.48635 -104.225667) (xy 402.426928 -104.23349)
			(xy 402.366992 -104.23349) (xy 402.30757 -104.225667) (xy 402.249677 -104.210154) (xy 402.194304 -104.187218)
			(xy 402.142398 -104.157251) (xy 402.094848 -104.120764) (xy 402.052468 -104.078384) (xy 402.015981 -104.030834)
			(xy 401.986014 -103.978928) (xy 401.963078 -103.923555) (xy 401.947565 -103.865662) (xy 401.939742 -103.80624)
			(xy 401.939252 -103.776272) (xy 389.40232 -103.776272) (xy 389.40232 -105.57637) (xy 400.085052 -105.57637)
			(xy 400.085052 -104.71277) (xy 400.085542 -104.682802) (xy 400.093365 -104.62338) (xy 400.108878 -104.565487)
			(xy 400.131814 -104.510114) (xy 400.161781 -104.458208) (xy 400.198268 -104.410658) (xy 400.240648 -104.368278)
			(xy 400.288198 -104.331791) (xy 400.340104 -104.301824) (xy 400.395477 -104.278888) (xy 400.45337 -104.263375)
			(xy 400.512792 -104.255552) (xy 400.572728 -104.255552) (xy 400.63215 -104.263375) (xy 400.690043 -104.278888)
			(xy 400.745416 -104.301824) (xy 400.797322 -104.331791) (xy 400.844872 -104.368278) (xy 400.887252 -104.410658)
			(xy 400.923739 -104.458208) (xy 400.953706 -104.510114) (xy 400.976642 -104.565487) (xy 400.992155 -104.62338)
			(xy 400.998941 -104.674924) (xy 436.859424 -104.674924) (xy 436.863495 -104.619302) (xy 436.875621 -104.564865)
			(xy 436.895544 -104.512774) (xy 436.92284 -104.464139) (xy 436.956926 -104.419996) (xy 436.997075 -104.381287)
			(xy 437.042433 -104.348836) (xy 437.092033 -104.323335) (xy 437.144817 -104.305328) (xy 437.19966 -104.295198)
			(xy 437.255394 -104.293161) (xy 437.310831 -104.299261) (xy 437.364788 -104.313367) (xy 437.416117 -104.335179)
			(xy 437.463723 -104.364233) (xy 437.506591 -104.399908) (xy 437.543808 -104.441445) (xy 437.574581 -104.487958)
			(xy 437.598253 -104.538455) (xy 437.614321 -104.591862) (xy 437.622441 -104.647038) (xy 437.62295 -104.674924)
			(xy 437.622441 -104.70281) (xy 437.614321 -104.757986) (xy 437.598253 -104.811393) (xy 437.574581 -104.86189)
			(xy 437.543808 -104.908403) (xy 437.506591 -104.94994) (xy 437.463723 -104.985615) (xy 437.416117 -105.014669)
			(xy 437.364788 -105.036481) (xy 437.310831 -105.050587) (xy 437.255394 -105.056687) (xy 437.19966 -105.05465)
			(xy 437.144817 -105.04452) (xy 437.092033 -105.026513) (xy 437.042433 -105.001012) (xy 436.997075 -104.968561)
			(xy 436.956926 -104.929852) (xy 436.92284 -104.885709) (xy 436.895544 -104.837074) (xy 436.875621 -104.784983)
			(xy 436.863495 -104.730546) (xy 436.859424 -104.674924) (xy 400.998941 -104.674924) (xy 400.999978 -104.682802)
			(xy 401.000468 -104.71277) (xy 401.000468 -105.57637) (xy 400.999978 -105.606338) (xy 400.992155 -105.66576)
			(xy 400.976642 -105.723653) (xy 400.953706 -105.779026) (xy 400.923739 -105.830932) (xy 400.887252 -105.878482)
			(xy 400.844872 -105.920862) (xy 400.797322 -105.957349) (xy 400.745416 -105.987316) (xy 400.690043 -106.010252)
			(xy 400.63215 -106.025765) (xy 400.572728 -106.033588) (xy 400.512792 -106.033588) (xy 400.45337 -106.025765)
			(xy 400.395477 -106.010252) (xy 400.340104 -105.987316) (xy 400.288198 -105.957349) (xy 400.240648 -105.920862)
			(xy 400.198268 -105.878482) (xy 400.161781 -105.830932) (xy 400.131814 -105.779026) (xy 400.108878 -105.723653)
			(xy 400.093365 -105.66576) (xy 400.085542 -105.606338) (xy 400.085052 -105.57637) (xy 389.40232 -105.57637)
			(xy 389.40232 -107.376214) (xy 401.939252 -107.376214) (xy 401.939252 -106.512614) (xy 401.939742 -106.482646)
			(xy 401.947565 -106.423224) (xy 401.963078 -106.365331) (xy 401.986014 -106.309958) (xy 402.015981 -106.258052)
			(xy 402.052468 -106.210502) (xy 402.094848 -106.168122) (xy 402.142398 -106.131635) (xy 402.194304 -106.101668)
			(xy 402.249677 -106.078732) (xy 402.30757 -106.063219) (xy 402.366992 -106.055396) (xy 402.426928 -106.055396)
			(xy 402.48635 -106.063219) (xy 402.544243 -106.078732) (xy 402.599616 -106.101668) (xy 402.651522 -106.131635)
			(xy 402.699072 -106.168122) (xy 402.741452 -106.210502) (xy 402.777939 -106.258052) (xy 402.807906 -106.309958)
			(xy 402.830842 -106.365331) (xy 402.846355 -106.423224) (xy 402.854178 -106.482646) (xy 402.854668 -106.512614)
			(xy 402.854668 -107.210352) (xy 413.291526 -107.210352) (xy 413.295597 -107.15473) (xy 413.307723 -107.100293)
			(xy 413.327646 -107.048202) (xy 413.354942 -106.999567) (xy 413.389028 -106.955424) (xy 413.429177 -106.916715)
			(xy 413.474535 -106.884264) (xy 413.524135 -106.858763) (xy 413.576919 -106.840756) (xy 413.631762 -106.830626)
			(xy 413.687496 -106.828589) (xy 413.742933 -106.834689) (xy 413.79689 -106.848795) (xy 413.848219 -106.870607)
			(xy 413.895825 -106.899661) (xy 413.938693 -106.935336) (xy 413.97591 -106.976873) (xy 414.006683 -107.023386)
			(xy 414.023006 -107.058206) (xy 437.873902 -107.058206) (xy 437.874429 -107.029467) (xy 437.883051 -106.97264)
			(xy 437.9001 -106.917749) (xy 437.925191 -106.866037) (xy 437.957755 -106.818675) (xy 437.977026 -106.797348)
			(xy 437.98363 -106.79049) (xy 437.990742 -106.772456) (xy 437.990742 -106.683556) (xy 437.98363 -106.665522)
			(xy 437.977026 -106.658664) (xy 437.957761 -106.637332) (xy 437.925195 -106.589971) (xy 437.900103 -106.53826)
			(xy 437.883053 -106.48337) (xy 437.87443 -106.426543) (xy 437.874429 -106.369066) (xy 437.883051 -106.312239)
			(xy 437.9001 -106.257349) (xy 437.925191 -106.205637) (xy 437.957756 -106.158275) (xy 437.977026 -106.136948)
			(xy 437.98363 -106.13009) (xy 437.990742 -106.112056) (xy 437.990742 -106.023156) (xy 437.98363 -106.005122)
			(xy 437.977026 -105.998264) (xy 437.957756 -105.976936) (xy 437.92519 -105.929574) (xy 437.900098 -105.877863)
			(xy 437.883047 -105.822972) (xy 437.874423 -105.766145) (xy 437.873902 -105.737406) (xy 437.874388 -105.710155)
			(xy 437.882144 -105.656207) (xy 437.897499 -105.603912) (xy 437.920141 -105.554335) (xy 437.949607 -105.508485)
			(xy 437.985298 -105.467294) (xy 438.026489 -105.431603) (xy 438.072339 -105.402137) (xy 438.121916 -105.379495)
			(xy 438.174211 -105.36414) (xy 438.228159 -105.356384) (xy 438.282661 -105.356384) (xy 438.336609 -105.36414)
			(xy 438.388904 -105.379495) (xy 438.438481 -105.402137) (xy 438.484331 -105.431603) (xy 438.525522 -105.467294)
			(xy 438.561213 -105.508485) (xy 438.590679 -105.554335) (xy 438.613321 -105.603912) (xy 438.628676 -105.656207)
			(xy 438.636432 -105.710155) (xy 438.636918 -105.737406) (xy 438.636393 -105.766145) (xy 438.62777 -105.822972)
			(xy 438.61072 -105.877862) (xy 438.585629 -105.929574) (xy 438.553064 -105.976937) (xy 438.533794 -105.998264)
			(xy 438.52719 -106.005122) (xy 438.520078 -106.023156) (xy 438.520078 -106.112056) (xy 438.52719 -106.13009)
			(xy 438.533794 -106.136948) (xy 438.55307 -106.15827) (xy 438.585633 -106.205634) (xy 438.610724 -106.257346)
			(xy 438.627772 -106.312238) (xy 438.636394 -106.369065) (xy 438.636393 -106.426543) (xy 438.62777 -106.483371)
			(xy 438.61072 -106.538262) (xy 438.585629 -106.589974) (xy 438.553064 -106.637337) (xy 438.533794 -106.658664)
			(xy 438.52719 -106.665522) (xy 438.520078 -106.683556) (xy 438.520078 -106.772456) (xy 438.52719 -106.79049)
			(xy 438.533794 -106.797348) (xy 438.553056 -106.818683) (xy 438.585626 -106.866042) (xy 438.610721 -106.917751)
			(xy 438.627773 -106.972641) (xy 438.636397 -107.029467) (xy 438.636918 -107.058206) (xy 438.636432 -107.085457)
			(xy 438.628676 -107.139405) (xy 438.613321 -107.1917) (xy 438.590679 -107.241277) (xy 438.561213 -107.287127)
			(xy 438.525522 -107.328318) (xy 438.484331 -107.364009) (xy 438.438481 -107.393475) (xy 438.388904 -107.416117)
			(xy 438.336609 -107.431472) (xy 438.282661 -107.439228) (xy 438.228159 -107.439228) (xy 438.174211 -107.431472)
			(xy 438.121916 -107.416117) (xy 438.072339 -107.393475) (xy 438.026489 -107.364009) (xy 437.985298 -107.328318)
			(xy 437.949607 -107.287127) (xy 437.920141 -107.241277) (xy 437.897499 -107.1917) (xy 437.882144 -107.139405)
			(xy 437.874388 -107.085457) (xy 437.873902 -107.058206) (xy 414.023006 -107.058206) (xy 414.030355 -107.073883)
			(xy 414.046423 -107.12729) (xy 414.054543 -107.182466) (xy 414.055052 -107.210352) (xy 414.054543 -107.238238)
			(xy 414.046423 -107.293414) (xy 414.030355 -107.346821) (xy 414.006683 -107.397318) (xy 413.97591 -107.443831)
			(xy 413.938693 -107.485368) (xy 413.895825 -107.521043) (xy 413.848219 -107.550097) (xy 413.79689 -107.571909)
			(xy 413.742933 -107.586015) (xy 413.687496 -107.592115) (xy 413.631762 -107.590078) (xy 413.576919 -107.579948)
			(xy 413.524135 -107.561941) (xy 413.474535 -107.53644) (xy 413.429177 -107.503989) (xy 413.389028 -107.46528)
			(xy 413.354942 -107.421137) (xy 413.327646 -107.372502) (xy 413.307723 -107.320411) (xy 413.295597 -107.265974)
			(xy 413.291526 -107.210352) (xy 402.854668 -107.210352) (xy 402.854668 -107.376214) (xy 402.854178 -107.406182)
			(xy 402.846355 -107.465604) (xy 402.830842 -107.523497) (xy 402.807906 -107.57887) (xy 402.777939 -107.630776)
			(xy 402.741452 -107.678326) (xy 402.699072 -107.720706) (xy 402.651522 -107.757193) (xy 402.599616 -107.78716)
			(xy 402.544243 -107.810096) (xy 402.48635 -107.825609) (xy 402.426928 -107.833432) (xy 402.366992 -107.833432)
			(xy 402.30757 -107.825609) (xy 402.249677 -107.810096) (xy 402.194304 -107.78716) (xy 402.142398 -107.757193)
			(xy 402.094848 -107.720706) (xy 402.052468 -107.678326) (xy 402.015981 -107.630776) (xy 401.986014 -107.57887)
			(xy 401.963078 -107.523497) (xy 401.947565 -107.465604) (xy 401.939742 -107.406182) (xy 401.939252 -107.376214)
			(xy 389.40232 -107.376214) (xy 389.40232 -109.176312) (xy 400.085052 -109.176312) (xy 400.085052 -108.312712)
			(xy 400.085542 -108.282744) (xy 400.093365 -108.223322) (xy 400.108878 -108.165429) (xy 400.131814 -108.110056)
			(xy 400.161781 -108.05815) (xy 400.198268 -108.0106) (xy 400.240648 -107.96822) (xy 400.288198 -107.931733)
			(xy 400.340104 -107.901766) (xy 400.395477 -107.87883) (xy 400.45337 -107.863317) (xy 400.512792 -107.855494)
			(xy 400.572728 -107.855494) (xy 400.63215 -107.863317) (xy 400.690043 -107.87883) (xy 400.745416 -107.901766)
			(xy 400.797322 -107.931733) (xy 400.844872 -107.96822) (xy 400.887252 -108.0106) (xy 400.923739 -108.05815)
			(xy 400.953706 -108.110056) (xy 400.976642 -108.165429) (xy 400.992155 -108.223322) (xy 400.999978 -108.282744)
			(xy 401.000468 -108.312712) (xy 401.000468 -108.379006) (xy 438.762902 -108.379006) (xy 438.763429 -108.350267)
			(xy 438.772051 -108.29344) (xy 438.7891 -108.238549) (xy 438.814191 -108.186837) (xy 438.846755 -108.139475)
			(xy 438.866026 -108.118148) (xy 438.87263 -108.11129) (xy 438.879742 -108.093256) (xy 438.879742 -108.004356)
			(xy 438.87263 -107.986322) (xy 438.866026 -107.979464) (xy 438.846761 -107.958132) (xy 438.814195 -107.910771)
			(xy 438.789103 -107.85906) (xy 438.772053 -107.80417) (xy 438.76343 -107.747343) (xy 438.763429 -107.689866)
			(xy 438.772051 -107.633039) (xy 438.7891 -107.578149) (xy 438.814191 -107.526437) (xy 438.846756 -107.479075)
			(xy 438.866026 -107.457748) (xy 438.87263 -107.45089) (xy 438.879742 -107.432856) (xy 438.879742 -107.343956)
			(xy 438.87263 -107.325922) (xy 438.866026 -107.319064) (xy 438.846761 -107.297732) (xy 438.814195 -107.250371)
			(xy 438.789103 -107.19866) (xy 438.772053 -107.14377) (xy 438.76343 -107.086943) (xy 438.763429 -107.029466)
			(xy 438.772051 -106.972639) (xy 438.7891 -106.917749) (xy 438.814191 -106.866037) (xy 438.846756 -106.818675)
			(xy 438.866026 -106.797348) (xy 438.87263 -106.79049) (xy 438.879742 -106.772456) (xy 438.879742 -106.683556)
			(xy 438.87263 -106.665522) (xy 438.866026 -106.658664) (xy 438.846761 -106.637332) (xy 438.814195 -106.589971)
			(xy 438.789103 -106.53826) (xy 438.772053 -106.48337) (xy 438.76343 -106.426543) (xy 438.763429 -106.369066)
			(xy 438.772051 -106.312239) (xy 438.7891 -106.257349) (xy 438.814191 -106.205637) (xy 438.846756 -106.158275)
			(xy 438.866026 -106.136948) (xy 438.87263 -106.13009) (xy 438.879742 -106.112056) (xy 438.879742 -106.023156)
			(xy 438.87263 -106.005122) (xy 438.866026 -105.998264) (xy 438.846761 -105.976932) (xy 438.814195 -105.929571)
			(xy 438.789103 -105.87786) (xy 438.772053 -105.82297) (xy 438.76343 -105.766143) (xy 438.763429 -105.708666)
			(xy 438.772051 -105.651839) (xy 438.7891 -105.596949) (xy 438.814191 -105.545237) (xy 438.846756 -105.497875)
			(xy 438.866026 -105.476548) (xy 438.87263 -105.46969) (xy 438.879742 -105.451656) (xy 438.879742 -105.362756)
			(xy 438.87263 -105.344722) (xy 438.866026 -105.337864) (xy 438.846761 -105.316532) (xy 438.814195 -105.269171)
			(xy 438.789103 -105.21746) (xy 438.772053 -105.16257) (xy 438.76343 -105.105743) (xy 438.763429 -105.048266)
			(xy 438.772051 -104.991439) (xy 438.7891 -104.936549) (xy 438.814191 -104.884837) (xy 438.846756 -104.837475)
			(xy 438.866026 -104.816148) (xy 438.87263 -104.80929) (xy 438.879742 -104.791256) (xy 438.879742 -104.702356)
			(xy 438.87263 -104.684322) (xy 438.866026 -104.677464) (xy 438.846761 -104.656132) (xy 438.814195 -104.608771)
			(xy 438.789103 -104.55706) (xy 438.772053 -104.50217) (xy 438.76343 -104.445343) (xy 438.763429 -104.387866)
			(xy 438.772051 -104.331039) (xy 438.7891 -104.276149) (xy 438.814191 -104.224437) (xy 438.846756 -104.177075)
			(xy 438.866026 -104.155748) (xy 438.87263 -104.14889) (xy 438.879742 -104.130856) (xy 438.879742 -104.041956)
			(xy 438.87263 -104.023922) (xy 438.866026 -104.017064) (xy 438.846761 -103.995732) (xy 438.814195 -103.948371)
			(xy 438.789103 -103.89666) (xy 438.772053 -103.84177) (xy 438.76343 -103.784943) (xy 438.763429 -103.727466)
			(xy 438.772051 -103.670639) (xy 438.7891 -103.615749) (xy 438.814191 -103.564037) (xy 438.846756 -103.516675)
			(xy 438.866026 -103.495348) (xy 438.87263 -103.48849) (xy 438.879742 -103.470456) (xy 438.879742 -103.381556)
			(xy 438.87263 -103.363522) (xy 438.866026 -103.356664) (xy 438.846756 -103.335336) (xy 438.81419 -103.287974)
			(xy 438.789098 -103.236263) (xy 438.772047 -103.181372) (xy 438.763423 -103.124545) (xy 438.762902 -103.095806)
			(xy 438.763344 -103.068599) (xy 438.771069 -103.014735) (xy 438.786375 -102.962517) (xy 438.808953 -102.913008)
			(xy 438.838342 -102.867212) (xy 438.873946 -102.826063) (xy 438.915041 -102.790395) (xy 438.937654 -102.775258)
			(xy 438.946036 -102.769924) (xy 438.957212 -102.753668) (xy 438.9755 -102.674674) (xy 438.977308 -102.665045)
			(xy 438.974311 -102.645703) (xy 438.969658 -102.637082) (xy 438.969404 -102.637082) (xy 438.969404 -102.636574)
			(xy 438.956199 -102.614063) (xy 438.935343 -102.566221) (xy 438.921193 -102.515987) (xy 438.914009 -102.464294)
			(xy 438.913524 -102.4382) (xy 438.91401 -102.410949) (xy 438.921766 -102.357001) (xy 438.937121 -102.304706)
			(xy 438.959763 -102.255129) (xy 438.989229 -102.209279) (xy 439.02492 -102.168088) (xy 439.066111 -102.132397)
			(xy 439.111961 -102.102931) (xy 439.161538 -102.080289) (xy 439.213833 -102.064934) (xy 439.267781 -102.057178)
			(xy 439.322283 -102.057178) (xy 439.376231 -102.064934) (xy 439.428526 -102.080289) (xy 439.478103 -102.102931)
			(xy 439.523953 -102.132397) (xy 439.565144 -102.168088) (xy 439.600835 -102.209279) (xy 439.630301 -102.255129)
			(xy 439.652943 -102.304706) (xy 439.668298 -102.357001) (xy 439.676054 -102.410949) (xy 439.67654 -102.4382)
			(xy 439.676083 -102.465407) (xy 439.668359 -102.519269) (xy 439.653054 -102.571485) (xy 439.630478 -102.620994)
			(xy 439.601091 -102.666789) (xy 439.56549 -102.70794) (xy 439.524399 -102.743609) (xy 439.501788 -102.758748)
			(xy 439.493406 -102.764082) (xy 439.48223 -102.780338) (xy 439.463942 -102.859332) (xy 439.462138 -102.868962)
			(xy 439.465134 -102.888302) (xy 439.469784 -102.896924) (xy 439.470038 -102.896924) (xy 439.470038 -102.897432)
			(xy 439.48325 -102.919939) (xy 439.504103 -102.967783) (xy 439.518251 -103.018018) (xy 439.525433 -103.069712)
			(xy 439.525918 -103.095806) (xy 439.525393 -103.124545) (xy 439.51677 -103.181372) (xy 439.49972 -103.236262)
			(xy 439.474629 -103.287974) (xy 439.442064 -103.335337) (xy 439.422794 -103.356664) (xy 439.41619 -103.363522)
			(xy 439.409078 -103.381556) (xy 439.409078 -103.470456) (xy 439.41619 -103.48849) (xy 439.422794 -103.495348)
			(xy 439.44207 -103.51667) (xy 439.474633 -103.564034) (xy 439.499724 -103.615746) (xy 439.516772 -103.670638)
			(xy 439.525394 -103.727465) (xy 439.525393 -103.784943) (xy 439.51677 -103.841771) (xy 439.49972 -103.896662)
			(xy 439.474629 -103.948374) (xy 439.442064 -103.995737) (xy 439.422794 -104.017064) (xy 439.417168 -104.022906)
			(xy 444.16599 -104.022906) (xy 444.166465 -103.996592) (xy 444.173698 -103.944464) (xy 444.188016 -103.893822)
			(xy 444.209147 -103.845623) (xy 444.236692 -103.800779) (xy 444.270129 -103.760139) (xy 444.28918 -103.741982)
			(xy 444.296589 -103.734466) (xy 444.30511 -103.715182) (xy 444.30569 -103.704644) (xy 444.30569 -103.629968)
			(xy 444.30514 -103.619421) (xy 444.29662 -103.600125) (xy 444.28918 -103.59263) (xy 444.270142 -103.574457)
			(xy 444.236684 -103.53383) (xy 444.209123 -103.488994) (xy 444.187982 -103.440796) (xy 444.173661 -103.390152)
			(xy 444.166431 -103.338021) (xy 444.16599 -103.311706) (xy 444.166461 -103.284453) (xy 444.174217 -103.230503)
			(xy 444.189572 -103.178205) (xy 444.212214 -103.128625) (xy 444.241681 -103.082772) (xy 444.277374 -103.04158)
			(xy 444.318566 -103.005886) (xy 444.364418 -102.976418) (xy 444.413998 -102.953775) (xy 444.466295 -102.938419)
			(xy 444.520245 -102.930661) (xy 444.547498 -102.930198) (xy 444.575163 -102.930713) (xy 444.629912 -102.938712)
			(xy 444.682933 -102.954528) (xy 444.733117 -102.977831) (xy 444.779413 -103.008132) (xy 444.820851 -103.044796)
			(xy 444.856564 -103.087057) (xy 444.871602 -103.110284) (xy 444.878229 -103.119969) (xy 444.898098 -103.132408)
			(xy 444.909702 -103.13416) (xy 444.989712 -103.142034) (xy 445.001351 -103.14267) (xy 445.023189 -103.134588)
			(xy 445.031622 -103.12654) (xy 445.031876 -103.126286) (xy 445.049936 -103.107683) (xy 445.090272 -103.075107)
			(xy 445.134651 -103.048297) (xy 445.182254 -103.027749) (xy 445.232202 -103.01384) (xy 445.283574 -103.006827)
			(xy 445.309498 -103.006398) (xy 445.336751 -103.006857) (xy 445.390702 -103.014614) (xy 445.443001 -103.02997)
			(xy 445.492581 -103.052613) (xy 445.538435 -103.082081) (xy 445.579628 -103.117775) (xy 445.615321 -103.158969)
			(xy 445.644789 -103.204822) (xy 445.667431 -103.254403) (xy 445.682787 -103.306701) (xy 445.690543 -103.360653)
			(xy 445.691006 -103.387906) (xy 445.690542 -103.415276) (xy 445.682723 -103.469455) (xy 445.667234 -103.521958)
			(xy 445.644392 -103.571705) (xy 445.614667 -103.617672) (xy 445.597026 -103.638604) (xy 445.596772 -103.638858)
			(xy 445.591194 -103.64595) (xy 445.584943 -103.662863) (xy 445.58458 -103.671878) (xy 445.58458 -103.685653)
			(xy 456.792771 -103.685653) (xy 456.792771 -103.631147) (xy 456.800529 -103.577195) (xy 456.815886 -103.524896)
			(xy 456.838531 -103.475315) (xy 456.868001 -103.429462) (xy 456.903697 -103.38827) (xy 456.944893 -103.352578)
			(xy 456.990749 -103.323112) (xy 457.040332 -103.300473) (xy 457.092632 -103.285121) (xy 457.146585 -103.277369)
			(xy 457.173838 -103.276908) (xy 457.200153 -103.277348) (xy 457.252283 -103.284588) (xy 457.302926 -103.298912)
			(xy 457.351125 -103.32005) (xy 457.395968 -103.347601) (xy 457.436606 -103.381044) (xy 457.454762 -103.400098)
			(xy 457.462296 -103.407484) (xy 457.481567 -103.416017) (xy 457.4921 -103.416608) (xy 457.566776 -103.416608)
			(xy 457.577325 -103.416077) (xy 457.596621 -103.407543) (xy 457.604114 -103.400098) (xy 457.623934 -103.37931)
			(xy 457.668706 -103.343335) (xy 457.718364 -103.314475) (xy 457.771786 -103.293382) (xy 457.827765 -103.280533)
			(xy 457.885038 -103.276218) (xy 457.942311 -103.280533) (xy 457.99829 -103.293382) (xy 458.051712 -103.314475)
			(xy 458.10137 -103.343335) (xy 458.146142 -103.37931) (xy 458.165962 -103.400098) (xy 458.173496 -103.407484)
			(xy 458.192767 -103.416017) (xy 458.2033 -103.416608) (xy 458.277976 -103.416608) (xy 458.288525 -103.416077)
			(xy 458.307821 -103.407543) (xy 458.315314 -103.400098) (xy 458.333469 -103.381042) (xy 458.374099 -103.347585)
			(xy 458.418939 -103.320026) (xy 458.46714 -103.298888) (xy 458.517788 -103.284571) (xy 458.569922 -103.277346)
			(xy 458.596238 -103.276908) (xy 458.623489 -103.277364) (xy 458.677434 -103.285126) (xy 458.729727 -103.300485)
			(xy 458.779301 -103.323129) (xy 458.825149 -103.352598) (xy 458.866336 -103.388291) (xy 458.902025 -103.429482)
			(xy 458.931489 -103.475332) (xy 458.954129 -103.524909) (xy 458.969482 -103.577203) (xy 458.977238 -103.631149)
			(xy 458.977238 -103.685651) (xy 458.969482 -103.739597) (xy 458.954129 -103.791891) (xy 458.931489 -103.841468)
			(xy 458.902025 -103.887319) (xy 458.866336 -103.928509) (xy 458.825149 -103.964202) (xy 458.779301 -103.993671)
			(xy 458.729727 -104.016315) (xy 458.677434 -104.031674) (xy 458.623489 -104.039436) (xy 458.596238 -104.039924)
			(xy 458.569923 -104.03949) (xy 458.517793 -104.032247) (xy 458.46715 -104.017921) (xy 458.418952 -103.996782)
			(xy 458.374109 -103.969231) (xy 458.33347 -103.935788) (xy 458.315314 -103.916734) (xy 458.307785 -103.909341)
			(xy 458.288511 -103.900811) (xy 458.277976 -103.900224) (xy 458.2033 -103.900224) (xy 458.192748 -103.900733)
			(xy 458.173452 -103.909281) (xy 458.165962 -103.916734) (xy 458.146142 -103.937522) (xy 458.10137 -103.973497)
			(xy 458.051712 -104.002357) (xy 457.99829 -104.02345) (xy 457.942311 -104.036299) (xy 457.885038 -104.040614)
			(xy 457.827765 -104.036299) (xy 457.771786 -104.02345) (xy 457.718364 -104.002357) (xy 457.668706 -103.973497)
			(xy 457.623934 -103.937522) (xy 457.604114 -103.916734) (xy 457.596585 -103.909341) (xy 457.577311 -103.900811)
			(xy 457.566776 -103.900224) (xy 457.4921 -103.900224) (xy 457.481548 -103.900733) (xy 457.462252 -103.909281)
			(xy 457.454762 -103.916734) (xy 457.436625 -103.935807) (xy 457.39599 -103.969262) (xy 457.351146 -103.996817)
			(xy 457.302942 -104.017953) (xy 457.252291 -104.032266) (xy 457.200155 -104.039487) (xy 457.173838 -104.039924)
			(xy 457.146585 -104.039431) (xy 457.092632 -104.031679) (xy 457.040332 -104.016327) (xy 456.990749 -103.993688)
			(xy 456.944893 -103.964222) (xy 456.903697 -103.92853) (xy 456.868001 -103.887338) (xy 456.838531 -103.841485)
			(xy 456.815886 -103.791904) (xy 456.800529 -103.739605) (xy 456.792771 -103.685653) (xy 445.58458 -103.685653)
			(xy 445.58458 -103.738934) (xy 445.584925 -103.747952) (xy 445.591181 -103.764869) (xy 445.596772 -103.771954)
			(xy 445.597026 -103.771954) (xy 445.597026 -103.772208) (xy 445.614686 -103.793123) (xy 445.644394 -103.839101)
			(xy 445.667226 -103.888853) (xy 445.682712 -103.941357) (xy 445.690535 -103.995536) (xy 445.691006 -104.022906)
			(xy 445.690528 -104.050157) (xy 445.68277 -104.104106) (xy 445.667414 -104.156401) (xy 445.644772 -104.205978)
			(xy 445.615305 -104.251828) (xy 445.579613 -104.293019) (xy 445.538422 -104.32871) (xy 445.492571 -104.358176)
			(xy 445.442993 -104.380817) (xy 445.390698 -104.396172) (xy 445.336749 -104.403928) (xy 445.309498 -104.404414)
			(xy 445.280579 -104.40393) (xy 445.223405 -104.395198) (xy 445.168204 -104.377936) (xy 445.116242 -104.352538)
			(xy 445.068709 -104.319587) (xy 445.026696 -104.279838) (xy 445.008508 -104.257348) (xy 445.000897 -104.248546)
			(xy 444.979999 -104.238361) (xy 444.968376 -104.23779) (xy 444.88862 -104.23779) (xy 444.876992 -104.238359)
			(xy 444.856082 -104.248527) (xy 444.848488 -104.257348) (xy 444.830316 -104.279847) (xy 444.788291 -104.319579)
			(xy 444.740751 -104.352515) (xy 444.688787 -104.3779) (xy 444.633587 -104.395154) (xy 444.576415 -104.40388)
			(xy 444.547498 -104.404414) (xy 444.520247 -104.403924) (xy 444.4663 -104.396167) (xy 444.414005 -104.380812)
			(xy 444.364429 -104.358171) (xy 444.318578 -104.328706) (xy 444.277388 -104.293014) (xy 444.241697 -104.251825)
			(xy 444.21223 -104.205975) (xy 444.189589 -104.156398) (xy 444.174233 -104.104104) (xy 444.166476 -104.050157)
			(xy 444.16599 -104.022906) (xy 439.417168 -104.022906) (xy 439.41619 -104.023922) (xy 439.409078 -104.041956)
			(xy 439.409078 -104.130856) (xy 439.41619 -104.14889) (xy 439.422794 -104.155748) (xy 439.44207 -104.17707)
			(xy 439.474633 -104.224434) (xy 439.499724 -104.276146) (xy 439.516772 -104.331038) (xy 439.525394 -104.387865)
			(xy 439.525393 -104.445343) (xy 439.51677 -104.502171) (xy 439.49972 -104.557062) (xy 439.474629 -104.608774)
			(xy 439.442064 -104.656137) (xy 439.422794 -104.677464) (xy 439.41619 -104.684322) (xy 439.409078 -104.702356)
			(xy 439.409078 -104.791256) (xy 439.41619 -104.80929) (xy 439.422794 -104.816148) (xy 439.44207 -104.83747)
			(xy 439.474633 -104.884834) (xy 439.499724 -104.936546) (xy 439.516772 -104.991438) (xy 439.525394 -105.048265)
			(xy 439.525393 -105.08445) (xy 444.044072 -105.08445) (xy 444.044072 -105.02995) (xy 444.051828 -104.976004)
			(xy 444.067181 -104.923711) (xy 444.089821 -104.874135) (xy 444.119285 -104.828285) (xy 444.154974 -104.787095)
			(xy 444.196161 -104.751403) (xy 444.242008 -104.721935) (xy 444.291582 -104.699292) (xy 444.343874 -104.683934)
			(xy 444.39782 -104.676174) (xy 444.42507 -104.675686) (xy 444.452439 -104.676173) (xy 444.506617 -104.683986)
			(xy 444.55912 -104.699471) (xy 444.608867 -104.722308) (xy 444.654835 -104.752027) (xy 444.675768 -104.769666)
			(xy 444.676022 -104.76992) (xy 444.683096 -104.775524) (xy 444.700023 -104.78176) (xy 444.709042 -104.782112)
			(xy 444.776098 -104.782112) (xy 444.785114 -104.781751) (xy 444.802031 -104.775506) (xy 444.809118 -104.76992)
			(xy 444.809118 -104.769666) (xy 444.809372 -104.769666) (xy 444.830305 -104.752025) (xy 444.876273 -104.722301)
			(xy 444.926019 -104.699455) (xy 444.978521 -104.683959) (xy 445.032699 -104.67613) (xy 445.087441 -104.67613)
			(xy 445.141619 -104.683959) (xy 445.194121 -104.699455) (xy 445.243867 -104.722301) (xy 445.289835 -104.752025)
			(xy 445.310768 -104.769666) (xy 445.311022 -104.76992) (xy 445.318096 -104.775524) (xy 445.335023 -104.78176)
			(xy 445.344042 -104.782112) (xy 445.411098 -104.782112) (xy 445.420114 -104.781751) (xy 445.437031 -104.775506)
			(xy 445.444118 -104.76992) (xy 445.444118 -104.769666) (xy 445.444372 -104.769666) (xy 445.465305 -104.752025)
			(xy 445.511273 -104.722301) (xy 445.561019 -104.699455) (xy 445.613521 -104.683959) (xy 445.667699 -104.67613)
			(xy 445.722441 -104.67613) (xy 445.776619 -104.683959) (xy 445.829121 -104.699455) (xy 445.878867 -104.722301)
			(xy 445.924835 -104.752025) (xy 445.945768 -104.769666) (xy 445.946022 -104.76992) (xy 445.953096 -104.775524)
			(xy 445.970023 -104.78176) (xy 445.979042 -104.782112) (xy 446.046098 -104.782112) (xy 446.055114 -104.781751)
			(xy 446.072031 -104.775506) (xy 446.079118 -104.76992) (xy 446.079118 -104.769666) (xy 446.079372 -104.769666)
			(xy 446.100299 -104.752021) (xy 446.146274 -104.722311) (xy 446.196023 -104.699477) (xy 446.248524 -104.683987)
			(xy 446.302701 -104.67616) (xy 446.33007 -104.675686) (xy 446.357324 -104.676159) (xy 446.411277 -104.683913)
			(xy 446.463578 -104.699266) (xy 446.513161 -104.721906) (xy 446.559017 -104.751373) (xy 446.600213 -104.787066)
			(xy 446.635909 -104.828259) (xy 446.665379 -104.874113) (xy 446.688024 -104.923694) (xy 446.703381 -104.975994)
			(xy 446.711139 -105.029946) (xy 446.711139 -105.084454) (xy 446.703381 -105.138406) (xy 446.688024 -105.190706)
			(xy 446.665379 -105.240287) (xy 446.635909 -105.286141) (xy 446.600213 -105.327334) (xy 446.559017 -105.363027)
			(xy 446.513161 -105.392494) (xy 446.463578 -105.415134) (xy 446.411277 -105.430487) (xy 446.357324 -105.438241)
			(xy 446.33007 -105.438702) (xy 446.302699 -105.438253) (xy 446.248519 -105.430431) (xy 446.196016 -105.414938)
			(xy 446.14627 -105.392092) (xy 446.100303 -105.362365) (xy 446.079372 -105.344722) (xy 446.079118 -105.344468)
			(xy 446.072033 -105.338879) (xy 446.055115 -105.332635) (xy 446.046098 -105.332276) (xy 445.979042 -105.332276)
			(xy 445.970028 -105.332658) (xy 445.953111 -105.338889) (xy 445.946022 -105.344468) (xy 445.945768 -105.344722)
			(xy 445.924835 -105.362363) (xy 445.878867 -105.392087) (xy 445.829121 -105.414933) (xy 445.776619 -105.430429)
			(xy 445.722441 -105.438258) (xy 445.667699 -105.438258) (xy 445.613521 -105.430429) (xy 445.561019 -105.414933)
			(xy 445.511273 -105.392087) (xy 445.465305 -105.362363) (xy 445.444372 -105.344722) (xy 445.444118 -105.344468)
			(xy 445.437033 -105.338879) (xy 445.420115 -105.332635) (xy 445.411098 -105.332276) (xy 445.344042 -105.332276)
			(xy 445.335028 -105.332658) (xy 445.318111 -105.338889) (xy 445.311022 -105.344468) (xy 445.311022 -105.344722)
			(xy 445.310768 -105.344722) (xy 445.289835 -105.362363) (xy 445.243867 -105.392087) (xy 445.194121 -105.414933)
			(xy 445.141619 -105.430429) (xy 445.087441 -105.438258) (xy 445.032699 -105.438258) (xy 444.978521 -105.430429)
			(xy 444.926019 -105.414933) (xy 444.876273 -105.392087) (xy 444.830305 -105.362363) (xy 444.809372 -105.344722)
			(xy 444.809118 -105.344468) (xy 444.802033 -105.338879) (xy 444.785115 -105.332635) (xy 444.776098 -105.332276)
			(xy 444.709042 -105.332276) (xy 444.700028 -105.332658) (xy 444.683111 -105.338889) (xy 444.676022 -105.344468)
			(xy 444.676022 -105.344722) (xy 444.675768 -105.344722) (xy 444.654824 -105.362346) (xy 444.608854 -105.392059)
			(xy 444.55911 -105.414898) (xy 444.506612 -105.430393) (xy 444.452438 -105.438225) (xy 444.42507 -105.438702)
			(xy 444.39782 -105.438226) (xy 444.343874 -105.430466) (xy 444.291582 -105.415108) (xy 444.242008 -105.392465)
			(xy 444.196161 -105.362997) (xy 444.154974 -105.327305) (xy 444.119285 -105.286115) (xy 444.089821 -105.240265)
			(xy 444.067181 -105.190689) (xy 444.051828 -105.138396) (xy 444.044072 -105.08445) (xy 439.525393 -105.08445)
			(xy 439.525393 -105.105743) (xy 439.51677 -105.162571) (xy 439.49972 -105.217462) (xy 439.474629 -105.269174)
			(xy 439.442064 -105.316537) (xy 439.422794 -105.337864) (xy 439.41619 -105.344722) (xy 439.409078 -105.362756)
			(xy 439.409078 -105.451656) (xy 439.41619 -105.46969) (xy 439.422794 -105.476548) (xy 439.44207 -105.49787)
			(xy 439.474633 -105.545234) (xy 439.499724 -105.596946) (xy 439.516772 -105.651838) (xy 439.525394 -105.708665)
			(xy 439.525393 -105.766143) (xy 439.51677 -105.822971) (xy 439.49972 -105.877862) (xy 439.474629 -105.929574)
			(xy 439.442064 -105.976937) (xy 439.422794 -105.998264) (xy 439.41619 -106.005122) (xy 439.409078 -106.023156)
			(xy 439.409078 -106.112056) (xy 439.41619 -106.13009) (xy 439.422794 -106.136948) (xy 439.44207 -106.15827)
			(xy 439.474633 -106.205634) (xy 439.499724 -106.257346) (xy 439.516772 -106.312238) (xy 439.525394 -106.369065)
			(xy 439.525393 -106.426543) (xy 439.51677 -106.483371) (xy 439.49972 -106.538262) (xy 439.474629 -106.589974)
			(xy 439.442064 -106.637337) (xy 439.422794 -106.658664) (xy 439.41619 -106.665522) (xy 439.409078 -106.683556)
			(xy 439.409078 -106.772456) (xy 439.41619 -106.79049) (xy 439.422794 -106.797348) (xy 439.427403 -106.802446)
			(xy 456.721028 -106.802446) (xy 456.721028 -106.747954) (xy 456.728782 -106.694018) (xy 456.744133 -106.641733)
			(xy 456.766768 -106.592166) (xy 456.796226 -106.546323) (xy 456.831909 -106.50514) (xy 456.873088 -106.469453)
			(xy 456.918927 -106.439989) (xy 456.968492 -106.417349) (xy 457.020775 -106.401992) (xy 457.07471 -106.394231)
			(xy 457.101956 -106.393742) (xy 457.128272 -106.394159) (xy 457.180403 -106.401402) (xy 457.231047 -106.41573)
			(xy 457.279246 -106.436872) (xy 457.324089 -106.464428) (xy 457.364725 -106.497876) (xy 457.38288 -106.516932)
			(xy 457.390416 -106.524317) (xy 457.409685 -106.532853) (xy 457.420218 -106.533442) (xy 457.494894 -106.533442)
			(xy 457.505443 -106.532911) (xy 457.524738 -106.524376) (xy 457.532232 -106.516932) (xy 457.552052 -106.496144)
			(xy 457.596824 -106.460169) (xy 457.646482 -106.431309) (xy 457.699904 -106.410216) (xy 457.755883 -106.397367)
			(xy 457.813156 -106.393052) (xy 457.870429 -106.397367) (xy 457.926408 -106.410216) (xy 457.97983 -106.431309)
			(xy 458.029488 -106.460169) (xy 458.07426 -106.496144) (xy 458.09408 -106.516932) (xy 458.101616 -106.524317)
			(xy 458.120885 -106.532853) (xy 458.131418 -106.533442) (xy 458.206094 -106.533442) (xy 458.216643 -106.532911)
			(xy 458.235938 -106.524376) (xy 458.243432 -106.516932) (xy 458.261585 -106.497874) (xy 458.302215 -106.464416)
			(xy 458.347055 -106.436856) (xy 458.395257 -106.415718) (xy 458.445905 -106.401402) (xy 458.49804 -106.394179)
			(xy 458.524356 -106.393742) (xy 458.551614 -106.394102) (xy 458.605577 -106.401855) (xy 458.657887 -106.417209)
			(xy 458.70748 -106.439852) (xy 458.753344 -106.469323) (xy 458.794548 -106.505021) (xy 458.830251 -106.54622)
			(xy 458.859727 -106.592082) (xy 458.882375 -106.641671) (xy 458.897736 -106.69398) (xy 458.905495 -106.747942)
			(xy 458.905495 -106.802458) (xy 458.897736 -106.85642) (xy 458.882375 -106.908729) (xy 458.859727 -106.958318)
			(xy 458.830251 -107.00418) (xy 458.794548 -107.045379) (xy 458.753344 -107.081077) (xy 458.70748 -107.110548)
			(xy 458.657887 -107.133191) (xy 458.605577 -107.148545) (xy 458.551615 -107.156298) (xy 458.524356 -107.156758)
			(xy 458.49804 -107.156333) (xy 458.44591 -107.149092) (xy 458.395265 -107.134765) (xy 458.347066 -107.113625)
			(xy 458.302224 -107.08607) (xy 458.261587 -107.052624) (xy 458.243432 -107.033568) (xy 458.235891 -107.026188)
			(xy 458.216626 -107.017649) (xy 458.206094 -107.017058) (xy 458.131418 -107.017058) (xy 458.12087 -107.017596)
			(xy 458.101575 -107.026126) (xy 458.09408 -107.033568) (xy 458.07426 -107.054356) (xy 458.029488 -107.090331)
			(xy 457.97983 -107.119191) (xy 457.926408 -107.140284) (xy 457.870429 -107.153133) (xy 457.813156 -107.157448)
			(xy 457.755883 -107.153133) (xy 457.699904 -107.140284) (xy 457.646482 -107.119191) (xy 457.596824 -107.090331)
			(xy 457.552052 -107.054356) (xy 457.532232 -107.033568) (xy 457.524691 -107.026188) (xy 457.505426 -107.017649)
			(xy 457.494894 -107.017058) (xy 457.420218 -107.017058) (xy 457.40967 -107.017596) (xy 457.390375 -107.026126)
			(xy 457.38288 -107.033568) (xy 457.364721 -107.05262) (xy 457.324093 -107.086079) (xy 457.279253 -107.113639)
			(xy 457.231053 -107.134778) (xy 457.180406 -107.149096) (xy 457.128272 -107.15632) (xy 457.101956 -107.156758)
			(xy 457.07471 -107.156169) (xy 457.020775 -107.148408) (xy 456.968492 -107.133051) (xy 456.918927 -107.110411)
			(xy 456.873088 -107.080947) (xy 456.831909 -107.04526) (xy 456.796226 -107.004077) (xy 456.766768 -106.958234)
			(xy 456.744133 -106.908667) (xy 456.728782 -106.856382) (xy 456.721028 -106.802446) (xy 439.427403 -106.802446)
			(xy 439.44207 -106.81867) (xy 439.474633 -106.866034) (xy 439.499724 -106.917746) (xy 439.516772 -106.972638)
			(xy 439.525394 -107.029465) (xy 439.525393 -107.086943) (xy 439.51677 -107.143771) (xy 439.49972 -107.198662)
			(xy 439.474629 -107.250374) (xy 439.442064 -107.297737) (xy 439.422794 -107.319064) (xy 439.41619 -107.325922)
			(xy 439.409078 -107.343956) (xy 439.409078 -107.432856) (xy 439.41619 -107.45089) (xy 439.422794 -107.457748)
			(xy 439.44207 -107.47907) (xy 439.474633 -107.526434) (xy 439.499724 -107.578146) (xy 439.516772 -107.633038)
			(xy 439.525394 -107.689865) (xy 439.525393 -107.740249) (xy 443.984396 -107.740249) (xy 443.984396 -107.685751)
			(xy 443.992152 -107.631808) (xy 444.007505 -107.579517) (xy 444.030144 -107.529944) (xy 444.059607 -107.484096)
			(xy 444.095294 -107.442909) (xy 444.13648 -107.407219) (xy 444.182326 -107.377753) (xy 444.231898 -107.355112)
			(xy 444.284188 -107.339756) (xy 444.338131 -107.331998) (xy 444.36538 -107.33151) (xy 444.39275 -107.331985)
			(xy 444.446929 -107.339801) (xy 444.499432 -107.355287) (xy 444.549179 -107.378127) (xy 444.595146 -107.40785)
			(xy 444.616078 -107.42549) (xy 444.616332 -107.425744) (xy 444.62343 -107.431314) (xy 444.640338 -107.437569)
			(xy 444.649352 -107.437936) (xy 444.716408 -107.437936) (xy 444.725424 -107.437575) (xy 444.742341 -107.43133)
			(xy 444.749428 -107.425744) (xy 444.749428 -107.42549) (xy 444.749682 -107.42549) (xy 444.770615 -107.407849)
			(xy 444.816583 -107.378125) (xy 444.866329 -107.355279) (xy 444.918831 -107.339783) (xy 444.973009 -107.331954)
			(xy 445.027751 -107.331954) (xy 445.081929 -107.339783) (xy 445.134431 -107.355279) (xy 445.184177 -107.378125)
			(xy 445.230145 -107.407849) (xy 445.251078 -107.42549) (xy 445.251332 -107.425744) (xy 445.25843 -107.431314)
			(xy 445.275338 -107.437569) (xy 445.284352 -107.437936) (xy 445.351408 -107.437936) (xy 445.360424 -107.437575)
			(xy 445.377341 -107.43133) (xy 445.384428 -107.425744) (xy 445.384428 -107.42549) (xy 445.384682 -107.42549)
			(xy 445.405615 -107.407849) (xy 445.451583 -107.378125) (xy 445.501329 -107.355279) (xy 445.553831 -107.339783)
			(xy 445.608009 -107.331954) (xy 445.662751 -107.331954) (xy 445.716929 -107.339783) (xy 445.769431 -107.355279)
			(xy 445.819177 -107.378125) (xy 445.865145 -107.407849) (xy 445.886078 -107.42549) (xy 445.886332 -107.425744)
			(xy 445.89343 -107.431314) (xy 445.910338 -107.437569) (xy 445.919352 -107.437936) (xy 445.986408 -107.437936)
			(xy 445.995424 -107.437575) (xy 446.012341 -107.43133) (xy 446.019428 -107.425744) (xy 446.019428 -107.42549)
			(xy 446.019682 -107.42549) (xy 446.040609 -107.407844) (xy 446.086583 -107.378134) (xy 446.136332 -107.355299)
			(xy 446.188834 -107.33981) (xy 446.24301 -107.331983) (xy 446.27038 -107.33151) (xy 446.297635 -107.331936)
			(xy 446.351591 -107.339691) (xy 446.403894 -107.355046) (xy 446.453479 -107.377688) (xy 446.499336 -107.407157)
			(xy 446.540534 -107.442852) (xy 446.576231 -107.484047) (xy 446.605702 -107.529904) (xy 446.628347 -107.579488)
			(xy 446.643705 -107.63179) (xy 446.651463 -107.685745) (xy 446.651463 -107.740255) (xy 446.643705 -107.79421)
			(xy 446.628347 -107.846512) (xy 446.605702 -107.896096) (xy 446.576231 -107.941953) (xy 446.540534 -107.983148)
			(xy 446.499336 -108.018843) (xy 446.453479 -108.048312) (xy 446.403894 -108.070954) (xy 446.351591 -108.086309)
			(xy 446.297635 -108.094064) (xy 446.27038 -108.094526) (xy 446.243008 -108.09409) (xy 446.188827 -108.086267)
			(xy 446.136323 -108.070772) (xy 446.086577 -108.047924) (xy 446.040612 -108.018191) (xy 446.019682 -108.000546)
			(xy 446.019428 -108.000292) (xy 446.012338 -107.99471) (xy 445.995424 -107.988461) (xy 445.986408 -107.9881)
			(xy 445.919352 -107.9881) (xy 445.910338 -107.988482) (xy 445.893421 -107.994712) (xy 445.886332 -108.000292)
			(xy 445.886078 -108.000546) (xy 445.865145 -108.018187) (xy 445.819177 -108.047911) (xy 445.769431 -108.070757)
			(xy 445.716929 -108.086253) (xy 445.662751 -108.094082) (xy 445.608009 -108.094082) (xy 445.553831 -108.086253)
			(xy 445.501329 -108.070757) (xy 445.451583 -108.047911) (xy 445.405615 -108.018187) (xy 445.384682 -108.000546)
			(xy 445.384428 -108.000292) (xy 445.377338 -107.99471) (xy 445.360424 -107.988461) (xy 445.351408 -107.9881)
			(xy 445.284352 -107.9881) (xy 445.275338 -107.988482) (xy 445.258421 -107.994712) (xy 445.251332 -108.000292)
			(xy 445.251332 -108.000546) (xy 445.251078 -108.000546) (xy 445.230145 -108.018187) (xy 445.184177 -108.047911)
			(xy 445.134431 -108.070757) (xy 445.081929 -108.086253) (xy 445.027751 -108.094082) (xy 444.973009 -108.094082)
			(xy 444.918831 -108.086253) (xy 444.866329 -108.070757) (xy 444.816583 -108.047911) (xy 444.770615 -108.018187)
			(xy 444.749682 -108.000546) (xy 444.749428 -108.000292) (xy 444.742338 -107.99471) (xy 444.725424 -107.988461)
			(xy 444.716408 -107.9881) (xy 444.649352 -107.9881) (xy 444.640338 -107.988482) (xy 444.623421 -107.994712)
			(xy 444.616332 -108.000292) (xy 444.616332 -108.000546) (xy 444.616078 -108.000546) (xy 444.59512 -108.018154)
			(xy 444.549155 -108.047872) (xy 444.499415 -108.070715) (xy 444.446919 -108.086213) (xy 444.392748 -108.094048)
			(xy 444.36538 -108.094526) (xy 444.338131 -108.094002) (xy 444.284188 -108.086244) (xy 444.231898 -108.070888)
			(xy 444.182326 -108.048247) (xy 444.13648 -108.018781) (xy 444.095294 -107.983091) (xy 444.059607 -107.941904)
			(xy 444.030144 -107.896056) (xy 444.007505 -107.846483) (xy 443.992152 -107.794192) (xy 443.984396 -107.740249)
			(xy 439.525393 -107.740249) (xy 439.525393 -107.747343) (xy 439.51677 -107.804171) (xy 439.49972 -107.859062)
			(xy 439.474629 -107.910774) (xy 439.442064 -107.958137) (xy 439.422794 -107.979464) (xy 439.41619 -107.986322)
			(xy 439.409078 -108.004356) (xy 439.409078 -108.093256) (xy 439.41619 -108.11129) (xy 439.422794 -108.118148)
			(xy 439.442056 -108.139483) (xy 439.474626 -108.186842) (xy 439.499721 -108.238551) (xy 439.516773 -108.293441)
			(xy 439.525397 -108.350267) (xy 439.525918 -108.379006) (xy 439.525432 -108.406257) (xy 439.517676 -108.460205)
			(xy 439.502321 -108.5125) (xy 439.479679 -108.562077) (xy 439.474905 -108.569506) (xy 455.161142 -108.569506)
			(xy 455.161601 -108.542135) (xy 455.169419 -108.487956) (xy 455.184909 -108.435452) (xy 455.207753 -108.385705)
			(xy 455.23748 -108.339739) (xy 455.255122 -108.318808) (xy 455.255376 -108.318554) (xy 455.260955 -108.311463)
			(xy 455.267204 -108.294549) (xy 455.267568 -108.285534) (xy 455.267568 -108.218478) (xy 455.267229 -108.209459)
			(xy 455.26097 -108.192542) (xy 455.255376 -108.185458) (xy 455.255122 -108.185458) (xy 455.255122 -108.185204)
			(xy 455.237475 -108.164278) (xy 455.207763 -108.118304) (xy 455.184929 -108.068555) (xy 455.16944 -108.016053)
			(xy 455.161614 -107.961876) (xy 455.161142 -107.934506) (xy 455.161628 -107.907255) (xy 455.169384 -107.853307)
			(xy 455.184739 -107.801012) (xy 455.207381 -107.751435) (xy 455.236847 -107.705585) (xy 455.272538 -107.664394)
			(xy 455.313729 -107.628703) (xy 455.359579 -107.599237) (xy 455.409156 -107.576595) (xy 455.461451 -107.56124)
			(xy 455.515399 -107.553484) (xy 455.569901 -107.553484) (xy 455.623849 -107.56124) (xy 455.676144 -107.576595)
			(xy 455.725721 -107.599237) (xy 455.771571 -107.628703) (xy 455.812762 -107.664394) (xy 455.848453 -107.705585)
			(xy 455.877919 -107.751435) (xy 455.900561 -107.801012) (xy 455.915916 -107.853307) (xy 455.923672 -107.907255)
			(xy 455.924158 -107.934506) (xy 455.923706 -107.961877) (xy 455.915886 -108.016057) (xy 455.900394 -108.068561)
			(xy 455.877549 -108.118307) (xy 455.847821 -108.164273) (xy 455.830178 -108.185204) (xy 455.829924 -108.185458)
			(xy 455.82434 -108.192546) (xy 455.818094 -108.209462) (xy 455.817732 -108.218478) (xy 455.817732 -108.285534)
			(xy 455.818066 -108.294553) (xy 455.824329 -108.311471) (xy 455.829924 -108.318554) (xy 455.830178 -108.318554)
			(xy 455.830178 -108.318808) (xy 455.847831 -108.339729) (xy 455.877541 -108.385705) (xy 455.900375 -108.435455)
			(xy 455.915863 -108.487958) (xy 455.923687 -108.542136) (xy 455.924158 -108.569506) (xy 455.923672 -108.596757)
			(xy 455.915916 -108.650705) (xy 455.900561 -108.703) (xy 455.877919 -108.752577) (xy 455.848453 -108.798427)
			(xy 455.812762 -108.839618) (xy 455.771571 -108.875309) (xy 455.725721 -108.904775) (xy 455.676144 -108.927417)
			(xy 455.623849 -108.942772) (xy 455.569901 -108.950528) (xy 455.515399 -108.950528) (xy 455.461451 -108.942772)
			(xy 455.409156 -108.927417) (xy 455.359579 -108.904775) (xy 455.313729 -108.875309) (xy 455.272538 -108.839618)
			(xy 455.236847 -108.798427) (xy 455.207381 -108.752577) (xy 455.184739 -108.703) (xy 455.169384 -108.650705)
			(xy 455.161628 -108.596757) (xy 455.161142 -108.569506) (xy 439.474905 -108.569506) (xy 439.450213 -108.607927)
			(xy 439.414522 -108.649118) (xy 439.373331 -108.684809) (xy 439.327481 -108.714275) (xy 439.277904 -108.736917)
			(xy 439.225609 -108.752272) (xy 439.171661 -108.760028) (xy 439.117159 -108.760028) (xy 439.063211 -108.752272)
			(xy 439.010916 -108.736917) (xy 438.961339 -108.714275) (xy 438.915489 -108.684809) (xy 438.874298 -108.649118)
			(xy 438.838607 -108.607927) (xy 438.809141 -108.562077) (xy 438.786499 -108.5125) (xy 438.771144 -108.460205)
			(xy 438.763388 -108.406257) (xy 438.762902 -108.379006) (xy 401.000468 -108.379006) (xy 401.000468 -109.176312)
			(xy 400.999978 -109.20628) (xy 400.992155 -109.265702) (xy 400.976642 -109.323595) (xy 400.953706 -109.378968)
			(xy 400.923739 -109.430874) (xy 400.887252 -109.478424) (xy 400.844872 -109.520804) (xy 400.797322 -109.557291)
			(xy 400.745416 -109.587258) (xy 400.690043 -109.610194) (xy 400.63215 -109.625707) (xy 400.572728 -109.63353)
			(xy 400.512792 -109.63353) (xy 400.45337 -109.625707) (xy 400.395477 -109.610194) (xy 400.340104 -109.587258)
			(xy 400.288198 -109.557291) (xy 400.240648 -109.520804) (xy 400.198268 -109.478424) (xy 400.161781 -109.430874)
			(xy 400.131814 -109.378968) (xy 400.108878 -109.323595) (xy 400.093365 -109.265702) (xy 400.085542 -109.20628)
			(xy 400.085052 -109.176312) (xy 389.40232 -109.176312) (xy 389.40232 -110.97641) (xy 401.939252 -110.97641)
			(xy 401.939252 -110.11281) (xy 401.939742 -110.082842) (xy 401.947565 -110.02342) (xy 401.963078 -109.965527)
			(xy 401.986014 -109.910154) (xy 402.015981 -109.858248) (xy 402.052468 -109.810698) (xy 402.094848 -109.768318)
			(xy 402.142398 -109.731831) (xy 402.194304 -109.701864) (xy 402.249677 -109.678928) (xy 402.30757 -109.663415)
			(xy 402.366992 -109.655592) (xy 402.426928 -109.655592) (xy 402.48635 -109.663415) (xy 402.544243 -109.678928)
			(xy 402.599616 -109.701864) (xy 402.651522 -109.731831) (xy 402.699072 -109.768318) (xy 402.741452 -109.810698)
			(xy 402.777939 -109.858248) (xy 402.807906 -109.910154) (xy 402.830842 -109.965527) (xy 402.846355 -110.02342)
			(xy 402.854178 -110.082842) (xy 402.854668 -110.11281) (xy 402.854668 -110.530132) (xy 418.729158 -110.530132)
			(xy 418.733229 -110.47451) (xy 418.745355 -110.420073) (xy 418.765278 -110.367982) (xy 418.792574 -110.319347)
			(xy 418.82666 -110.275204) (xy 418.866809 -110.236495) (xy 418.912167 -110.204044) (xy 418.961767 -110.178543)
			(xy 419.014551 -110.160536) (xy 419.069394 -110.150406) (xy 419.125128 -110.148369) (xy 419.180565 -110.154469)
			(xy 419.234522 -110.168575) (xy 419.285851 -110.190387) (xy 419.333457 -110.219441) (xy 419.376325 -110.255116)
			(xy 419.413542 -110.296653) (xy 419.444315 -110.343166) (xy 419.467987 -110.393663) (xy 419.484055 -110.44707)
			(xy 419.492175 -110.502246) (xy 419.492684 -110.530132) (xy 419.492175 -110.558018) (xy 419.484055 -110.613194)
			(xy 419.467987 -110.666601) (xy 419.444315 -110.717098) (xy 419.413542 -110.763611) (xy 419.376325 -110.805148)
			(xy 419.333457 -110.840823) (xy 419.285851 -110.869877) (xy 419.234522 -110.891689) (xy 419.180565 -110.905795)
			(xy 419.125128 -110.911895) (xy 419.069394 -110.909858) (xy 419.014551 -110.899728) (xy 418.961767 -110.881721)
			(xy 418.912167 -110.85622) (xy 418.866809 -110.823769) (xy 418.82666 -110.78506) (xy 418.792574 -110.740917)
			(xy 418.765278 -110.692282) (xy 418.745355 -110.640191) (xy 418.733229 -110.585754) (xy 418.729158 -110.530132)
			(xy 402.854668 -110.530132) (xy 402.854668 -110.97641) (xy 402.854178 -111.006378) (xy 402.846355 -111.0658)
			(xy 402.830842 -111.123693) (xy 402.807906 -111.179066) (xy 402.777939 -111.230972) (xy 402.741452 -111.278522)
			(xy 402.699072 -111.320902) (xy 402.681948 -111.334042) (xy 412.56407 -111.334042) (xy 412.568141 -111.27842)
			(xy 412.580267 -111.223983) (xy 412.60019 -111.171892) (xy 412.627486 -111.123257) (xy 412.661572 -111.079114)
			(xy 412.701721 -111.040405) (xy 412.747079 -111.007954) (xy 412.796679 -110.982453) (xy 412.849463 -110.964446)
			(xy 412.904306 -110.954316) (xy 412.96004 -110.952279) (xy 413.015477 -110.958379) (xy 413.069434 -110.972485)
			(xy 413.120763 -110.994297) (xy 413.168369 -111.023351) (xy 413.211237 -111.059026) (xy 413.248454 -111.100563)
			(xy 413.279227 -111.147076) (xy 413.302899 -111.197573) (xy 413.318967 -111.25098) (xy 413.327087 -111.306156)
			(xy 413.327596 -111.334042) (xy 413.327087 -111.361928) (xy 413.318967 -111.417104) (xy 413.302899 -111.470511)
			(xy 413.279227 -111.521008) (xy 413.248454 -111.567521) (xy 413.211237 -111.609058) (xy 413.168369 -111.644733)
			(xy 413.120763 -111.673787) (xy 413.069434 -111.695599) (xy 413.015477 -111.709705) (xy 412.96004 -111.715805)
			(xy 412.904306 -111.713768) (xy 412.849463 -111.703638) (xy 412.796679 -111.685631) (xy 412.747079 -111.66013)
			(xy 412.701721 -111.627679) (xy 412.661572 -111.58897) (xy 412.627486 -111.544827) (xy 412.60019 -111.496192)
			(xy 412.580267 -111.444101) (xy 412.568141 -111.389664) (xy 412.56407 -111.334042) (xy 402.681948 -111.334042)
			(xy 402.651522 -111.357389) (xy 402.599616 -111.387356) (xy 402.544243 -111.410292) (xy 402.48635 -111.425805)
			(xy 402.426928 -111.433628) (xy 402.366992 -111.433628) (xy 402.30757 -111.425805) (xy 402.249677 -111.410292)
			(xy 402.194304 -111.387356) (xy 402.142398 -111.357389) (xy 402.094848 -111.320902) (xy 402.052468 -111.278522)
			(xy 402.015981 -111.230972) (xy 401.986014 -111.179066) (xy 401.963078 -111.123693) (xy 401.947565 -111.0658)
			(xy 401.939742 -111.006378) (xy 401.939252 -110.97641) (xy 389.40232 -110.97641) (xy 389.40232 -112.776508)
			(xy 400.085052 -112.776508) (xy 400.085052 -111.912908) (xy 400.085542 -111.88294) (xy 400.093365 -111.823518)
			(xy 400.108878 -111.765625) (xy 400.131814 -111.710252) (xy 400.161781 -111.658346) (xy 400.198268 -111.610796)
			(xy 400.240648 -111.568416) (xy 400.288198 -111.531929) (xy 400.340104 -111.501962) (xy 400.395477 -111.479026)
			(xy 400.45337 -111.463513) (xy 400.512792 -111.45569) (xy 400.572728 -111.45569) (xy 400.63215 -111.463513)
			(xy 400.690043 -111.479026) (xy 400.745416 -111.501962) (xy 400.797322 -111.531929) (xy 400.844872 -111.568416)
			(xy 400.887252 -111.610796) (xy 400.923739 -111.658346) (xy 400.953706 -111.710252) (xy 400.976642 -111.765625)
			(xy 400.992155 -111.823518) (xy 400.999978 -111.88294) (xy 400.999999 -111.884206) (xy 418.664388 -111.884206)
			(xy 418.668459 -111.828584) (xy 418.680585 -111.774147) (xy 418.700508 -111.722056) (xy 418.727804 -111.673421)
			(xy 418.76189 -111.629278) (xy 418.802039 -111.590569) (xy 418.847397 -111.558118) (xy 418.896997 -111.532617)
			(xy 418.949781 -111.51461) (xy 419.004624 -111.50448) (xy 419.060358 -111.502443) (xy 419.115795 -111.508543)
			(xy 419.169752 -111.522649) (xy 419.221081 -111.544461) (xy 419.268687 -111.573515) (xy 419.311555 -111.60919)
			(xy 419.348772 -111.650727) (xy 419.379545 -111.69724) (xy 419.403217 -111.747737) (xy 419.419285 -111.801144)
			(xy 419.427405 -111.85632) (xy 419.427914 -111.884206) (xy 419.427405 -111.912092) (xy 419.419285 -111.967268)
			(xy 419.415236 -111.980726) (xy 422.201594 -111.980726) (xy 422.202135 -111.951988) (xy 422.210754 -111.895161)
			(xy 422.2278 -111.840271) (xy 422.252887 -111.788559) (xy 422.285449 -111.741195) (xy 422.304718 -111.719868)
			(xy 422.311322 -111.71301) (xy 422.318434 -111.694976) (xy 422.318434 -111.606076) (xy 422.311322 -111.588042)
			(xy 422.304718 -111.581184) (xy 422.285473 -111.559835) (xy 422.252908 -111.512476) (xy 422.227815 -111.460768)
			(xy 422.210763 -111.405881) (xy 422.202139 -111.349056) (xy 422.202136 -111.291581) (xy 422.210755 -111.234756)
			(xy 422.227801 -111.179868) (xy 422.252889 -111.128157) (xy 422.285449 -111.080795) (xy 422.304718 -111.059468)
			(xy 422.311322 -111.05261) (xy 422.318434 -111.034576) (xy 422.318434 -110.945676) (xy 422.311322 -110.927642)
			(xy 422.304718 -110.920784) (xy 422.285473 -110.899435) (xy 422.252908 -110.852076) (xy 422.227815 -110.800368)
			(xy 422.210763 -110.745481) (xy 422.202139 -110.688656) (xy 422.202136 -110.631181) (xy 422.210755 -110.574356)
			(xy 422.227801 -110.519468) (xy 422.252889 -110.467757) (xy 422.285449 -110.420395) (xy 422.304718 -110.399068)
			(xy 422.311322 -110.39221) (xy 422.318434 -110.374176) (xy 422.318434 -110.285276) (xy 422.311322 -110.267242)
			(xy 422.304718 -110.260384) (xy 422.285473 -110.239035) (xy 422.252908 -110.191676) (xy 422.227815 -110.139968)
			(xy 422.210763 -110.085081) (xy 422.202139 -110.028256) (xy 422.202136 -109.970781) (xy 422.210755 -109.913956)
			(xy 422.227801 -109.859068) (xy 422.252889 -109.807357) (xy 422.285449 -109.759995) (xy 422.304718 -109.738668)
			(xy 422.311322 -109.73181) (xy 422.318434 -109.713776) (xy 422.318434 -109.624876) (xy 422.311322 -109.606842)
			(xy 422.304718 -109.599984) (xy 422.285456 -109.578649) (xy 422.252889 -109.531289) (xy 422.227796 -109.479579)
			(xy 422.210743 -109.42469) (xy 422.202117 -109.367864) (xy 422.201594 -109.339126) (xy 422.20208 -109.311874)
			(xy 422.209833 -109.257923) (xy 422.225186 -109.205626) (xy 422.247825 -109.156046) (xy 422.277291 -109.110192)
			(xy 422.312982 -109.068999) (xy 422.354173 -109.033305) (xy 422.400025 -109.003837) (xy 422.449603 -108.981194)
			(xy 422.5019 -108.965838) (xy 422.55585 -108.958081) (xy 422.583102 -108.957618) (xy 422.609416 -108.958078)
			(xy 422.661545 -108.965314) (xy 422.712188 -108.979634) (xy 422.760388 -109.000768) (xy 422.805231 -109.028315)
			(xy 422.84587 -109.061756) (xy 422.864026 -109.080808) (xy 422.871535 -109.088224) (xy 422.890825 -109.09674)
			(xy 422.901364 -109.097318) (xy 422.97604 -109.097318) (xy 422.986587 -109.096765) (xy 423.005882 -109.088246)
			(xy 423.013378 -109.080808) (xy 423.031553 -109.061772) (xy 423.072178 -109.028312) (xy 423.117014 -109.000751)
			(xy 423.165211 -108.979609) (xy 423.215856 -108.965288) (xy 423.267987 -108.958059) (xy 423.294302 -108.957618)
			(xy 423.321556 -108.958054) (xy 423.375509 -108.965811) (xy 423.427809 -108.981169) (xy 423.477391 -109.003814)
			(xy 423.523246 -109.033284) (xy 423.564439 -109.068981) (xy 423.600132 -109.110177) (xy 423.6296 -109.156033)
			(xy 423.652241 -109.205617) (xy 423.667594 -109.257918) (xy 423.675348 -109.311872) (xy 423.67581 -109.339126)
			(xy 423.675299 -109.367865) (xy 423.666673 -109.424693) (xy 423.64962 -109.479584) (xy 423.638525 -109.502448)
			(xy 457.714602 -109.502448) (xy 457.718673 -109.446826) (xy 457.730799 -109.392389) (xy 457.750722 -109.340298)
			(xy 457.778018 -109.291663) (xy 457.812104 -109.24752) (xy 457.852253 -109.208811) (xy 457.897611 -109.17636)
			(xy 457.947211 -109.150859) (xy 457.999995 -109.132852) (xy 458.054838 -109.122722) (xy 458.110572 -109.120685)
			(xy 458.166009 -109.126785) (xy 458.219966 -109.140891) (xy 458.271295 -109.162703) (xy 458.318901 -109.191757)
			(xy 458.361769 -109.227432) (xy 458.398986 -109.268969) (xy 458.429759 -109.315482) (xy 458.453431 -109.365979)
			(xy 458.469499 -109.419386) (xy 458.477619 -109.474562) (xy 458.478128 -109.502448) (xy 458.477619 -109.530334)
			(xy 458.469499 -109.58551) (xy 458.453431 -109.638917) (xy 458.429759 -109.689414) (xy 458.398986 -109.735927)
			(xy 458.361769 -109.777464) (xy 458.318901 -109.813139) (xy 458.271295 -109.842193) (xy 458.219966 -109.864005)
			(xy 458.166009 -109.878111) (xy 458.110572 -109.884211) (xy 458.054838 -109.882174) (xy 457.999995 -109.872044)
			(xy 457.947211 -109.854037) (xy 457.897611 -109.828536) (xy 457.852253 -109.796085) (xy 457.812104 -109.757376)
			(xy 457.778018 -109.713233) (xy 457.750722 -109.664598) (xy 457.730799 -109.612507) (xy 457.718673 -109.55807)
			(xy 457.714602 -109.502448) (xy 423.638525 -109.502448) (xy 423.624526 -109.531295) (xy 423.591958 -109.578657)
			(xy 423.572686 -109.599984) (xy 423.566082 -109.606842) (xy 423.55897 -109.624876) (xy 423.55897 -109.713776)
			(xy 423.566082 -109.73181) (xy 423.572686 -109.738668) (xy 423.591982 -109.759973) (xy 423.624546 -109.807339)
			(xy 423.649635 -109.859055) (xy 423.666683 -109.913949) (xy 423.675303 -109.970779) (xy 423.6753 -110.028259)
			(xy 423.666674 -110.085088) (xy 423.649621 -110.139981) (xy 423.624527 -110.191694) (xy 423.591958 -110.239057)
			(xy 423.572686 -110.260384) (xy 423.566082 -110.267242) (xy 423.55897 -110.285276) (xy 423.55897 -110.374176)
			(xy 423.566082 -110.39221) (xy 423.572686 -110.399068) (xy 423.591982 -110.420373) (xy 423.624546 -110.467739)
			(xy 423.649635 -110.519455) (xy 423.666683 -110.574349) (xy 423.673846 -110.621572) (xy 438.8612 -110.621572)
			(xy 438.861649 -110.595257) (xy 438.868887 -110.543128) (xy 438.88321 -110.492485) (xy 438.904346 -110.444286)
			(xy 438.931895 -110.399443) (xy 438.965337 -110.358804) (xy 438.98439 -110.340648) (xy 438.991815 -110.333146)
			(xy 439.000326 -110.313851) (xy 439.0009 -110.30331) (xy 439.0009 -110.228634) (xy 439.000366 -110.218085)
			(xy 438.991834 -110.198789) (xy 438.98439 -110.191296) (xy 438.965338 -110.173137) (xy 438.931881 -110.132508)
			(xy 438.904321 -110.087668) (xy 438.883182 -110.039468) (xy 438.868864 -109.988821) (xy 438.861639 -109.936688)
			(xy 438.8612 -109.910372) (xy 438.861686 -109.883121) (xy 438.869442 -109.829173) (xy 438.884797 -109.776878)
			(xy 438.907439 -109.727301) (xy 438.936905 -109.681451) (xy 438.972596 -109.64026) (xy 439.013787 -109.604569)
			(xy 439.059637 -109.575103) (xy 439.109214 -109.552461) (xy 439.161509 -109.537106) (xy 439.215457 -109.52935)
			(xy 439.269959 -109.52935) (xy 439.323907 -109.537106) (xy 439.376202 -109.552461) (xy 439.425779 -109.575103)
			(xy 439.471629 -109.604569) (xy 439.51282 -109.64026) (xy 439.548511 -109.681451) (xy 439.577977 -109.727301)
			(xy 439.600619 -109.776878) (xy 439.615974 -109.829173) (xy 439.62373 -109.883121) (xy 439.624216 -109.910372)
			(xy 439.623791 -109.936687) (xy 439.616547 -109.988818) (xy 439.602219 -110.039461) (xy 439.581079 -110.08766)
			(xy 439.553525 -110.132502) (xy 439.52008 -110.17314) (xy 439.501026 -110.191296) (xy 439.493628 -110.198821)
			(xy 439.485101 -110.218098) (xy 439.484516 -110.228634) (xy 439.484516 -110.30331) (xy 439.485022 -110.313863)
			(xy 439.493573 -110.333158) (xy 439.501026 -110.340648) (xy 439.520103 -110.358782) (xy 439.553557 -110.399417)
			(xy 439.581113 -110.444262) (xy 439.602247 -110.492467) (xy 439.61656 -110.543118) (xy 439.62378 -110.595255)
			(xy 439.624216 -110.621572) (xy 439.62373 -110.648823) (xy 439.615974 -110.702771) (xy 439.600619 -110.755066)
			(xy 439.577977 -110.804643) (xy 439.548511 -110.850493) (xy 439.51282 -110.891684) (xy 439.471629 -110.927375)
			(xy 439.425779 -110.956841) (xy 439.376202 -110.979483) (xy 439.323907 -110.994838) (xy 439.269959 -111.002594)
			(xy 439.215457 -111.002594) (xy 439.161509 -110.994838) (xy 439.109214 -110.979483) (xy 439.059637 -110.956841)
			(xy 439.013787 -110.927375) (xy 438.972596 -110.891684) (xy 438.936905 -110.850493) (xy 438.907439 -110.804643)
			(xy 438.884797 -110.755066) (xy 438.869442 -110.702771) (xy 438.861686 -110.648823) (xy 438.8612 -110.621572)
			(xy 423.673846 -110.621572) (xy 423.675303 -110.631179) (xy 423.6753 -110.688659) (xy 423.666674 -110.745488)
			(xy 423.649621 -110.800381) (xy 423.624527 -110.852094) (xy 423.591958 -110.899457) (xy 423.572686 -110.920784)
			(xy 423.566082 -110.927642) (xy 423.55897 -110.945676) (xy 423.55897 -111.034576) (xy 423.566082 -111.05261)
			(xy 423.572686 -111.059468) (xy 423.591982 -111.080773) (xy 423.624546 -111.128139) (xy 423.649635 -111.179855)
			(xy 423.666683 -111.234749) (xy 423.675303 -111.291579) (xy 423.6753 -111.349059) (xy 423.666674 -111.405888)
			(xy 423.649621 -111.460781) (xy 423.624527 -111.512494) (xy 423.591958 -111.559857) (xy 423.572686 -111.581184)
			(xy 423.566082 -111.588042) (xy 423.55897 -111.606076) (xy 423.55897 -111.694976) (xy 423.566082 -111.71301)
			(xy 423.572686 -111.719868) (xy 423.591973 -111.741181) (xy 423.624536 -111.788547) (xy 423.649625 -111.840262)
			(xy 423.666672 -111.895156) (xy 423.675291 -111.951986) (xy 423.67581 -111.980726) (xy 423.675346 -112.007978)
			(xy 423.667586 -112.061926) (xy 423.652228 -112.114221) (xy 423.629584 -112.163798) (xy 423.600115 -112.209649)
			(xy 423.564421 -112.250838) (xy 423.523229 -112.28653) (xy 423.505424 -112.297972) (xy 441.369958 -112.297972)
			(xy 441.370388 -112.271657) (xy 441.377628 -112.219526) (xy 441.391953 -112.168882) (xy 441.413093 -112.120682)
			(xy 441.440646 -112.07584) (xy 441.474093 -112.035203) (xy 441.493148 -112.017048) (xy 441.500567 -112.009541)
			(xy 441.509083 -111.99025) (xy 441.509658 -111.97971) (xy 441.509658 -111.905034) (xy 441.509136 -111.894483)
			(xy 441.500597 -111.875187) (xy 441.493148 -111.867696) (xy 441.474088 -111.849546) (xy 441.440633 -111.808914)
			(xy 441.413076 -111.764072) (xy 441.391939 -111.71587) (xy 441.377622 -111.665222) (xy 441.370397 -111.613088)
			(xy 441.369958 -111.586772) (xy 441.370444 -111.559521) (xy 441.3782 -111.505573) (xy 441.393555 -111.453278)
			(xy 441.416197 -111.403701) (xy 441.445663 -111.357851) (xy 441.481354 -111.31666) (xy 441.522545 -111.280969)
			(xy 441.568395 -111.251503) (xy 441.617972 -111.228861) (xy 441.670267 -111.213506) (xy 441.724215 -111.20575)
			(xy 441.778717 -111.20575) (xy 441.832665 -111.213506) (xy 441.88496 -111.228861) (xy 441.934537 -111.251503)
			(xy 441.980387 -111.280969) (xy 442.021578 -111.31666) (xy 442.057269 -111.357851) (xy 442.086735 -111.403701)
			(xy 442.109377 -111.453278) (xy 442.124732 -111.505573) (xy 442.132488 -111.559521) (xy 442.132974 -111.586772)
			(xy 442.132563 -111.613088) (xy 442.125318 -111.665219) (xy 442.110988 -111.715863) (xy 442.089845 -111.764062)
			(xy 442.062289 -111.808904) (xy 442.02884 -111.849541) (xy 442.009784 -111.867696) (xy 442.00238 -111.875215)
			(xy 441.993857 -111.894497) (xy 441.993274 -111.905034) (xy 441.993274 -111.97971) (xy 441.993792 -111.990261)
			(xy 442.002336 -112.009556) (xy 442.009784 -112.017048) (xy 442.028853 -112.03519) (xy 442.062309 -112.075823)
			(xy 442.089867 -112.120665) (xy 442.111003 -112.168869) (xy 442.125317 -112.219519) (xy 442.132538 -112.271655)
			(xy 442.132974 -112.297972) (xy 443.401958 -112.297972) (xy 443.402388 -112.271657) (xy 443.409628 -112.219526)
			(xy 443.423953 -112.168882) (xy 443.445093 -112.120682) (xy 443.472646 -112.07584) (xy 443.506093 -112.035203)
			(xy 443.525148 -112.017048) (xy 443.532567 -112.009541) (xy 443.541083 -111.99025) (xy 443.541658 -111.97971)
			(xy 443.541658 -111.905034) (xy 443.541136 -111.894483) (xy 443.532597 -111.875187) (xy 443.525148 -111.867696)
			(xy 443.506088 -111.849546) (xy 443.472633 -111.808914) (xy 443.445076 -111.764072) (xy 443.423939 -111.71587)
			(xy 443.409622 -111.665222) (xy 443.402397 -111.613088) (xy 443.401958 -111.586772) (xy 443.402444 -111.559521)
			(xy 443.4102 -111.505573) (xy 443.425555 -111.453278) (xy 443.448197 -111.403701) (xy 443.477663 -111.357851)
			(xy 443.513354 -111.31666) (xy 443.554545 -111.280969) (xy 443.600395 -111.251503) (xy 443.649972 -111.228861)
			(xy 443.702267 -111.213506) (xy 443.756215 -111.20575) (xy 443.810717 -111.20575) (xy 443.864665 -111.213506)
			(xy 443.91696 -111.228861) (xy 443.966537 -111.251503) (xy 444.012387 -111.280969) (xy 444.053578 -111.31666)
			(xy 444.089269 -111.357851) (xy 444.118735 -111.403701) (xy 444.141377 -111.453278) (xy 444.156732 -111.505573)
			(xy 444.164488 -111.559521) (xy 444.164974 -111.586772) (xy 444.164563 -111.613088) (xy 444.157318 -111.665219)
			(xy 444.142988 -111.715863) (xy 444.121845 -111.764062) (xy 444.094289 -111.808904) (xy 444.06084 -111.849541)
			(xy 444.041784 -111.867696) (xy 444.03438 -111.875215) (xy 444.025857 -111.894497) (xy 444.025274 -111.905034)
			(xy 444.025274 -111.97971) (xy 444.025792 -111.990261) (xy 444.034336 -112.009556) (xy 444.041784 -112.017048)
			(xy 444.060853 -112.03519) (xy 444.06285 -112.037615) (xy 445.856202 -112.037615) (xy 445.860515 -111.980345)
			(xy 445.87336 -111.924368) (xy 445.894448 -111.870948) (xy 445.923303 -111.821291) (xy 445.959273 -111.776519)
			(xy 445.980058 -111.756698) (xy 445.987456 -111.749173) (xy 445.995984 -111.729896) (xy 445.996568 -111.71936)
			(xy 445.996568 -111.644684) (xy 445.99607 -111.63413) (xy 445.987514 -111.614835) (xy 445.980058 -111.607346)
			(xy 445.960975 -111.589218) (xy 445.927522 -111.548581) (xy 445.899968 -111.503735) (xy 445.878834 -111.455529)
			(xy 445.864523 -111.404877) (xy 445.857304 -111.35274) (xy 445.856868 -111.326422) (xy 445.857354 -111.299171)
			(xy 445.86511 -111.245223) (xy 445.880465 -111.192928) (xy 445.903107 -111.143351) (xy 445.932573 -111.097501)
			(xy 445.968264 -111.05631) (xy 446.009455 -111.020619) (xy 446.055305 -110.991153) (xy 446.104882 -110.968511)
			(xy 446.157177 -110.953156) (xy 446.211125 -110.9454) (xy 446.265627 -110.9454) (xy 446.319575 -110.953156)
			(xy 446.37187 -110.968511) (xy 446.421447 -110.991153) (xy 446.467297 -111.020619) (xy 446.508488 -111.05631)
			(xy 446.544179 -111.097501) (xy 446.573645 -111.143351) (xy 446.596287 -111.192928) (xy 446.611642 -111.245223)
			(xy 446.619398 -111.299171) (xy 446.619884 -111.326422) (xy 446.619436 -111.352737) (xy 446.612198 -111.404866)
			(xy 446.597876 -111.45551) (xy 446.576739 -111.503709) (xy 446.54919 -111.548552) (xy 446.515747 -111.58919)
			(xy 446.496694 -111.607346) (xy 446.489269 -111.614848) (xy 446.480759 -111.634143) (xy 446.480184 -111.644684)
			(xy 446.480184 -111.71936) (xy 446.480726 -111.729908) (xy 446.489253 -111.749203) (xy 446.496694 -111.756698)
			(xy 446.517505 -111.776495) (xy 446.553482 -111.82127) (xy 446.582343 -111.870931) (xy 446.603436 -111.924356)
			(xy 446.616284 -111.980339) (xy 446.620598 -112.037615) (xy 448.394417 -112.037615) (xy 448.39873 -111.980345)
			(xy 448.411576 -111.924367) (xy 448.432666 -111.870947) (xy 448.461522 -111.82129) (xy 448.497494 -111.776518)
			(xy 448.51828 -111.756698) (xy 448.525682 -111.749176) (xy 448.534207 -111.729896) (xy 448.53479 -111.71936)
			(xy 448.53479 -111.644684) (xy 448.534286 -111.634131) (xy 448.525734 -111.614836) (xy 448.51828 -111.607346)
			(xy 448.499201 -111.589214) (xy 448.465747 -111.548578) (xy 448.438192 -111.503733) (xy 448.417057 -111.455528)
			(xy 448.402745 -111.404877) (xy 448.395526 -111.352739) (xy 448.39509 -111.326422) (xy 448.395576 -111.299171)
			(xy 448.403332 -111.245223) (xy 448.418687 -111.192928) (xy 448.441329 -111.143351) (xy 448.470795 -111.097501)
			(xy 448.506486 -111.05631) (xy 448.547677 -111.020619) (xy 448.593527 -110.991153) (xy 448.643104 -110.968511)
			(xy 448.695399 -110.953156) (xy 448.749347 -110.9454) (xy 448.803849 -110.9454) (xy 448.857797 -110.953156)
			(xy 448.910092 -110.968511) (xy 448.959669 -110.991153) (xy 449.005519 -111.020619) (xy 449.04671 -111.05631)
			(xy 449.082401 -111.097501) (xy 449.111867 -111.143351) (xy 449.134509 -111.192928) (xy 449.149864 -111.245223)
			(xy 449.15762 -111.299171) (xy 449.158106 -111.326422) (xy 449.157651 -111.352736) (xy 449.150414 -111.404865)
			(xy 449.136092 -111.455508) (xy 449.114957 -111.503707) (xy 449.087409 -111.54855) (xy 449.053968 -111.58919)
			(xy 449.034916 -111.607346) (xy 449.027494 -111.614851) (xy 449.018981 -111.634143) (xy 449.018406 -111.644684)
			(xy 449.018406 -111.71936) (xy 449.018941 -111.729909) (xy 449.027472 -111.749205) (xy 449.034916 -111.756698)
			(xy 449.055726 -111.776496) (xy 449.091701 -111.821271) (xy 449.12056 -111.870932) (xy 449.141652 -111.924357)
			(xy 449.154499 -111.98034) (xy 449.155522 -111.993923) (xy 452.597351 -111.993923) (xy 452.601664 -111.936653)
			(xy 452.61451 -111.880675) (xy 452.6356 -111.827255) (xy 452.664458 -111.777599) (xy 452.700431 -111.732829)
			(xy 452.721218 -111.71301) (xy 452.72862 -111.705489) (xy 452.737144 -111.686208) (xy 452.737728 -111.675672)
			(xy 452.737728 -111.600996) (xy 452.737206 -111.590446) (xy 452.728665 -111.571151) (xy 452.721218 -111.563658)
			(xy 452.700462 -111.543805) (xy 452.664484 -111.499039) (xy 452.63562 -111.449386) (xy 452.614523 -111.395969)
			(xy 452.60167 -111.339993) (xy 452.597351 -111.282723) (xy 452.601664 -111.225453) (xy 452.61451 -111.169475)
			(xy 452.6356 -111.116055) (xy 452.664458 -111.066399) (xy 452.700431 -111.021629) (xy 452.721218 -111.00181)
			(xy 452.72862 -110.994289) (xy 452.737144 -110.975008) (xy 452.737728 -110.964472) (xy 452.737728 -110.889796)
			(xy 452.737206 -110.879246) (xy 452.728665 -110.859951) (xy 452.721218 -110.852458) (xy 452.702153 -110.834312)
			(xy 452.668696 -110.793681) (xy 452.641137 -110.748839) (xy 452.620001 -110.700636) (xy 452.605686 -110.649986)
			(xy 452.598464 -110.597851) (xy 452.598028 -110.571534) (xy 452.598487 -110.54428) (xy 452.60624 -110.490327)
			(xy 452.621594 -110.438027) (xy 452.644235 -110.388445) (xy 452.673703 -110.34259) (xy 452.709397 -110.301396)
			(xy 452.750591 -110.265702) (xy 452.796447 -110.236234) (xy 452.846029 -110.213593) (xy 452.898329 -110.19824)
			(xy 452.952282 -110.190487) (xy 452.979536 -110.190026) (xy 453.005851 -110.190461) (xy 453.057981 -110.197701)
			(xy 453.108625 -110.212026) (xy 453.156824 -110.233165) (xy 453.201667 -110.260717) (xy 453.242305 -110.294162)
			(xy 453.26046 -110.313216) (xy 453.267992 -110.320604) (xy 453.287264 -110.329136) (xy 453.297798 -110.329726)
			(xy 453.372474 -110.329726) (xy 453.383022 -110.329188) (xy 453.402317 -110.320658) (xy 453.409812 -110.313216)
			(xy 453.427972 -110.294165) (xy 453.4686 -110.260707) (xy 453.51344 -110.233147) (xy 453.56164 -110.212007)
			(xy 453.612286 -110.197689) (xy 453.66442 -110.190464) (xy 453.690736 -110.190026) (xy 453.71799 -110.190444)
			(xy 453.771942 -110.198207) (xy 453.82424 -110.213568) (xy 453.873819 -110.236216) (xy 453.913439 -110.261683)
			(xy 455.214548 -110.261683) (xy 455.214548 -110.209717) (xy 455.222677 -110.158392) (xy 455.238734 -110.10897)
			(xy 455.262325 -110.062668) (xy 455.292869 -110.020627) (xy 455.329613 -109.983881) (xy 455.371653 -109.953335)
			(xy 455.417953 -109.929741) (xy 455.467374 -109.913681) (xy 455.518699 -109.905549) (xy 455.544682 -109.905038)
			(xy 455.571328 -109.905497) (xy 455.623931 -109.914033) (xy 455.674482 -109.930904) (xy 455.721668 -109.955672)
			(xy 455.764266 -109.987694) (xy 455.80117 -110.026139) (xy 455.816716 -110.047786) (xy 455.82508 -110.059072)
			(xy 455.846753 -110.076927) (xy 455.872467 -110.08821) (xy 455.900282 -110.092068) (xy 455.928097 -110.08821)
			(xy 455.953811 -110.076927) (xy 455.975484 -110.059072) (xy 455.983848 -110.047786) (xy 455.999412 -110.026159)
			(xy 456.036331 -109.987743) (xy 456.078931 -109.955744) (xy 456.126112 -109.930989) (xy 456.176652 -109.914121)
			(xy 456.229242 -109.905575) (xy 456.255882 -109.905038) (xy 456.281876 -109.905428) (xy 456.333224 -109.913558)
			(xy 456.382667 -109.929621) (xy 456.42899 -109.953221) (xy 456.471049 -109.983777) (xy 456.507811 -110.020537)
			(xy 456.53837 -110.062595) (xy 456.561972 -110.108916) (xy 456.578038 -110.158359) (xy 456.586171 -110.209706)
			(xy 456.586171 -110.261694) (xy 456.578038 -110.313041) (xy 456.561972 -110.362484) (xy 456.53837 -110.408805)
			(xy 456.507811 -110.450863) (xy 456.471049 -110.487623) (xy 456.42899 -110.518179) (xy 456.382667 -110.541779)
			(xy 456.333224 -110.557842) (xy 456.281876 -110.565972) (xy 456.255882 -110.566454) (xy 456.229238 -110.565951)
			(xy 456.176636 -110.557424) (xy 456.126087 -110.540563) (xy 456.0789 -110.515803) (xy 456.036301 -110.483789)
			(xy 455.999395 -110.44535) (xy 455.983848 -110.423706) (xy 455.975484 -110.41242) (xy 455.953811 -110.394565)
			(xy 455.928097 -110.383282) (xy 455.900282 -110.379424) (xy 455.872467 -110.383282) (xy 455.846753 -110.394565)
			(xy 455.82508 -110.41242) (xy 455.816716 -110.423706) (xy 455.80111 -110.445301) (xy 455.7642 -110.483719)
			(xy 455.721608 -110.515722) (xy 455.674436 -110.540482) (xy 455.623904 -110.557357) (xy 455.57132 -110.565912)
			(xy 455.544682 -110.566454) (xy 455.518699 -110.565851) (xy 455.467374 -110.557719) (xy 455.417953 -110.541659)
			(xy 455.371653 -110.518065) (xy 455.329613 -110.487519) (xy 455.292869 -110.450773) (xy 455.262325 -110.408732)
			(xy 455.238734 -110.36243) (xy 455.222677 -110.313008) (xy 455.214548 -110.261683) (xy 453.913439 -110.261683)
			(xy 453.919671 -110.265689) (xy 453.960862 -110.301388) (xy 453.996553 -110.342585) (xy 454.026018 -110.388442)
			(xy 454.048656 -110.438026) (xy 454.064008 -110.490327) (xy 454.071761 -110.54428) (xy 454.072244 -110.571534)
			(xy 454.071817 -110.59785) (xy 454.064577 -110.649981) (xy 454.050251 -110.700625) (xy 454.029111 -110.748824)
			(xy 454.001557 -110.793666) (xy 453.96811 -110.834303) (xy 453.949054 -110.852458) (xy 453.941677 -110.860001)
			(xy 453.933137 -110.879264) (xy 453.932544 -110.889796) (xy 453.932544 -110.964472) (xy 453.933062 -110.975023)
			(xy 453.941604 -110.994319) (xy 453.949054 -111.00181) (xy 453.969874 -111.021597) (xy 454.005846 -111.066375)
			(xy 454.034702 -111.116038) (xy 454.052798 -111.161885) (xy 455.214523 -111.161885) (xy 455.214523 -111.109915)
			(xy 455.222653 -111.058586) (xy 455.238712 -111.00916) (xy 455.262304 -110.962855) (xy 455.29285 -110.920811)
			(xy 455.329597 -110.884062) (xy 455.37164 -110.853514) (xy 455.417944 -110.829919) (xy 455.467369 -110.813857)
			(xy 455.518697 -110.805725) (xy 455.544682 -110.805214) (xy 455.571327 -110.805683) (xy 455.62393 -110.814219)
			(xy 455.674479 -110.831089) (xy 455.721665 -110.855854) (xy 455.764264 -110.887874) (xy 455.801169 -110.926316)
			(xy 455.816716 -110.947962) (xy 455.82508 -110.959248) (xy 455.846753 -110.977103) (xy 455.872467 -110.988386)
			(xy 455.900282 -110.992244) (xy 455.928097 -110.988386) (xy 455.953811 -110.977103) (xy 455.975484 -110.959248)
			(xy 455.983848 -110.947962) (xy 455.999405 -110.92633) (xy 456.036326 -110.887915) (xy 456.078928 -110.855917)
			(xy 456.12611 -110.831164) (xy 456.176651 -110.814296) (xy 456.229242 -110.805751) (xy 456.255882 -110.805214)
			(xy 456.281874 -110.805652) (xy 456.333218 -110.813781) (xy 456.382658 -110.829843) (xy 456.428977 -110.853441)
			(xy 456.471034 -110.883995) (xy 456.507793 -110.920752) (xy 456.538349 -110.962808) (xy 456.56195 -111.009125)
			(xy 456.578014 -111.058564) (xy 456.586147 -111.109908) (xy 456.586147 -111.161892) (xy 456.578014 -111.213236)
			(xy 456.56195 -111.262675) (xy 456.538349 -111.308992) (xy 456.507793 -111.351048) (xy 456.471034 -111.387805)
			(xy 456.428977 -111.418359) (xy 456.382658 -111.441957) (xy 456.333218 -111.458019) (xy 456.281874 -111.466148)
			(xy 456.255882 -111.46663) (xy 456.229237 -111.466138) (xy 456.176635 -111.45761) (xy 456.126084 -111.440747)
			(xy 456.078897 -111.415985) (xy 456.036299 -111.383969) (xy 455.999394 -111.345527) (xy 455.983848 -111.323882)
			(xy 455.975484 -111.312596) (xy 455.953811 -111.294741) (xy 455.928097 -111.283458) (xy 455.900282 -111.2796)
			(xy 455.872467 -111.283458) (xy 455.846753 -111.294741) (xy 455.82508 -111.312596) (xy 455.816716 -111.323882)
			(xy 455.801133 -111.345494) (xy 455.764215 -111.383907) (xy 455.721618 -111.415906) (xy 455.674441 -111.440662)
			(xy 455.623907 -111.457535) (xy 455.571321 -111.466089) (xy 455.544682 -111.46663) (xy 455.518697 -111.466075)
			(xy 455.467369 -111.457943) (xy 455.417944 -111.441881) (xy 455.37164 -111.418286) (xy 455.329597 -111.387738)
			(xy 455.29285 -111.350989) (xy 455.262304 -111.308945) (xy 455.238712 -111.26264) (xy 455.222653 -111.213214)
			(xy 455.214523 -111.161885) (xy 454.052798 -111.161885) (xy 454.05579 -111.169465) (xy 454.068636 -111.225447)
			(xy 454.072947 -111.282723) (xy 454.068629 -111.339998) (xy 454.055777 -111.395979) (xy 454.034681 -111.449403)
			(xy 454.00582 -111.499063) (xy 453.969843 -111.543837) (xy 453.949054 -111.563658) (xy 453.941677 -111.571201)
			(xy 453.933137 -111.590464) (xy 453.932544 -111.600996) (xy 453.932544 -111.675672) (xy 453.933062 -111.686223)
			(xy 453.941604 -111.705519) (xy 453.949054 -111.71301) (xy 453.969874 -111.732797) (xy 454.005846 -111.777575)
			(xy 454.034702 -111.827238) (xy 454.05579 -111.880665) (xy 454.068636 -111.936647) (xy 454.072947 -111.993923)
			(xy 454.068629 -112.051198) (xy 454.066199 -112.061783) (xy 455.214546 -112.061783) (xy 455.214546 -112.009817)
			(xy 455.222675 -111.958491) (xy 455.238732 -111.909069) (xy 455.262324 -111.862767) (xy 455.292867 -111.820725)
			(xy 455.329612 -111.783979) (xy 455.371652 -111.753433) (xy 455.417952 -111.729839) (xy 455.467374 -111.713779)
			(xy 455.518699 -111.705647) (xy 455.544682 -111.705136) (xy 455.571328 -111.705595) (xy 455.623931 -111.714132)
			(xy 455.674481 -111.731003) (xy 455.721668 -111.755771) (xy 455.764266 -111.787792) (xy 455.80117 -111.826237)
			(xy 455.816716 -111.847884) (xy 455.82508 -111.85917) (xy 455.846753 -111.877025) (xy 455.872467 -111.888308)
			(xy 455.900282 -111.892166) (xy 455.928097 -111.888308) (xy 455.953811 -111.877025) (xy 455.975484 -111.85917)
			(xy 455.983848 -111.847884) (xy 455.999411 -111.826257) (xy 456.03633 -111.787841) (xy 456.078931 -111.755841)
			(xy 456.126112 -111.731087) (xy 456.176651 -111.714219) (xy 456.229242 -111.705673) (xy 456.255882 -111.705136)
			(xy 456.281876 -111.70553) (xy 456.333223 -111.71366) (xy 456.382667 -111.729723) (xy 456.428989 -111.753323)
			(xy 456.471048 -111.783879) (xy 456.472823 -111.785654) (xy 457.757782 -111.785654) (xy 457.761853 -111.730032)
			(xy 457.773979 -111.675595) (xy 457.793902 -111.623504) (xy 457.821198 -111.574869) (xy 457.855284 -111.530726)
			(xy 457.895433 -111.492017) (xy 457.940791 -111.459566) (xy 457.990391 -111.434065) (xy 458.043175 -111.416058)
			(xy 458.098018 -111.405928) (xy 458.153752 -111.403891) (xy 458.209189 -111.409991) (xy 458.263146 -111.424097)
			(xy 458.314475 -111.445909) (xy 458.362081 -111.474963) (xy 458.404949 -111.510638) (xy 458.442166 -111.552175)
			(xy 458.472939 -111.598688) (xy 458.496611 -111.649185) (xy 458.512679 -111.702592) (xy 458.520799 -111.757768)
			(xy 458.521308 -111.785654) (xy 458.520799 -111.81354) (xy 458.512679 -111.868716) (xy 458.496611 -111.922123)
			(xy 458.472939 -111.97262) (xy 458.442166 -112.019133) (xy 458.404949 -112.06067) (xy 458.362081 -112.096345)
			(xy 458.314475 -112.125399) (xy 458.263146 -112.147211) (xy 458.209189 -112.161317) (xy 458.153752 -112.167417)
			(xy 458.098018 -112.16538) (xy 458.043175 -112.15525) (xy 457.990391 -112.137243) (xy 457.940791 -112.111742)
			(xy 457.895433 -112.079291) (xy 457.855284 -112.040582) (xy 457.821198 -111.996439) (xy 457.793902 -111.947804)
			(xy 457.773979 -111.895713) (xy 457.761853 -111.841276) (xy 457.757782 -111.785654) (xy 456.472823 -111.785654)
			(xy 456.50781 -111.820638) (xy 456.538368 -111.862696) (xy 456.56197 -111.909017) (xy 456.578036 -111.958459)
			(xy 456.586169 -112.009806) (xy 456.586169 -112.061794) (xy 456.578036 -112.113141) (xy 456.56197 -112.162583)
			(xy 456.538368 -112.208904) (xy 456.50781 -112.250962) (xy 456.471048 -112.287721) (xy 456.428989 -112.318277)
			(xy 456.382667 -112.341877) (xy 456.333223 -112.35794) (xy 456.281876 -112.36607) (xy 456.255882 -112.366552)
			(xy 456.229238 -112.36605) (xy 456.176636 -112.357523) (xy 456.126086 -112.340661) (xy 456.0789 -112.315902)
			(xy 456.036301 -112.283887) (xy 455.999395 -112.245448) (xy 455.983848 -112.223804) (xy 455.975484 -112.212518)
			(xy 455.953811 -112.194663) (xy 455.928097 -112.18338) (xy 455.900282 -112.179522) (xy 455.872467 -112.18338)
			(xy 455.846753 -112.194663) (xy 455.82508 -112.212518) (xy 455.816716 -112.223804) (xy 455.801109 -112.245399)
			(xy 455.7642 -112.283817) (xy 455.721608 -112.31582) (xy 455.674436 -112.340579) (xy 455.623904 -112.357455)
			(xy 455.57132 -112.36601) (xy 455.544682 -112.366552) (xy 455.518699 -112.365953) (xy 455.467374 -112.357821)
			(xy 455.417952 -112.341761) (xy 455.371652 -112.318167) (xy 455.329612 -112.287621) (xy 455.292867 -112.250875)
			(xy 455.262324 -112.208833) (xy 455.238732 -112.162531) (xy 455.222675 -112.113109) (xy 455.214546 -112.061783)
			(xy 454.066199 -112.061783) (xy 454.055777 -112.107179) (xy 454.034681 -112.160603) (xy 454.00582 -112.210263)
			(xy 453.969843 -112.255037) (xy 453.949054 -112.274858) (xy 453.941677 -112.282401) (xy 453.933137 -112.301664)
			(xy 453.932544 -112.312196) (xy 453.932544 -112.386872) (xy 453.933062 -112.397423) (xy 453.941604 -112.416719)
			(xy 453.949054 -112.42421) (xy 453.968118 -112.442357) (xy 454.001572 -112.48299) (xy 454.029129 -112.527832)
			(xy 454.050265 -112.576034) (xy 454.064581 -112.626683) (xy 454.071806 -112.678818) (xy 454.072244 -112.705134)
			(xy 454.071754 -112.732384) (xy 454.063994 -112.78633) (xy 454.048636 -112.838623) (xy 454.025994 -112.888198)
			(xy 453.996527 -112.934046) (xy 453.972487 -112.961789) (xy 455.214468 -112.961789) (xy 455.214468 -112.909811)
			(xy 455.222598 -112.858473) (xy 455.23866 -112.809039) (xy 455.262257 -112.762726) (xy 455.292808 -112.720674)
			(xy 455.329561 -112.683919) (xy 455.371611 -112.653366) (xy 455.417922 -112.629767) (xy 455.467356 -112.613703)
			(xy 455.518693 -112.605569) (xy 455.544682 -112.605058) (xy 455.571328 -112.605508) (xy 455.623932 -112.614045)
			(xy 455.674484 -112.630917) (xy 455.72167 -112.655687) (xy 455.764268 -112.687711) (xy 455.801171 -112.726158)
			(xy 455.816716 -112.747806) (xy 455.82508 -112.759092) (xy 455.846753 -112.776947) (xy 455.872467 -112.78823)
			(xy 455.900282 -112.792088) (xy 455.928097 -112.78823) (xy 455.953811 -112.776947) (xy 455.975484 -112.759092)
			(xy 455.983848 -112.747806) (xy 455.999388 -112.726162) (xy 456.036315 -112.68775) (xy 456.078921 -112.655755)
			(xy 456.126106 -112.631005) (xy 456.176648 -112.614139) (xy 456.229241 -112.605594) (xy 456.255882 -112.605058)
			(xy 456.28187 -112.605608) (xy 456.333205 -112.613736) (xy 456.382637 -112.629795) (xy 456.428948 -112.653389)
			(xy 456.470997 -112.683938) (xy 456.50775 -112.720689) (xy 456.538301 -112.762737) (xy 456.561898 -112.809046)
			(xy 456.57796 -112.858477) (xy 456.586091 -112.909813) (xy 456.586091 -112.961787) (xy 456.57796 -113.013123)
			(xy 456.561898 -113.062554) (xy 456.538301 -113.108863) (xy 456.50775 -113.150911) (xy 456.470997 -113.187662)
			(xy 456.428948 -113.218211) (xy 456.382637 -113.241805) (xy 456.333205 -113.257864) (xy 456.28187 -113.265992)
			(xy 456.255882 -113.266474) (xy 456.229238 -113.265963) (xy 456.176638 -113.257436) (xy 456.126088 -113.240576)
			(xy 456.078902 -113.215818) (xy 456.036303 -113.183805) (xy 455.999395 -113.145369) (xy 455.983848 -113.123726)
			(xy 455.975484 -113.11244) (xy 455.953811 -113.094585) (xy 455.928097 -113.083302) (xy 455.900282 -113.079444)
			(xy 455.872467 -113.083302) (xy 455.846753 -113.094585) (xy 455.82508 -113.11244) (xy 455.816716 -113.123726)
			(xy 455.801116 -113.145325) (xy 455.764204 -113.183742) (xy 455.721611 -113.215744) (xy 455.674437 -113.240503)
			(xy 455.623904 -113.257378) (xy 455.57132 -113.265932) (xy 455.544682 -113.266474) (xy 455.518693 -113.266031)
			(xy 455.467356 -113.257897) (xy 455.417922 -113.241833) (xy 455.371611 -113.218234) (xy 455.329561 -113.187681)
			(xy 455.292808 -113.150926) (xy 455.262257 -113.108874) (xy 455.23866 -113.062561) (xy 455.222598 -113.013127)
			(xy 455.214468 -112.961789) (xy 453.972487 -112.961789) (xy 453.960836 -112.975235) (xy 453.919648 -113.010926)
			(xy 453.873799 -113.040393) (xy 453.824224 -113.063035) (xy 453.771932 -113.078393) (xy 453.717986 -113.086154)
			(xy 453.690736 -113.086642) (xy 453.66442 -113.086236) (xy 453.612288 -113.078991) (xy 453.561643 -113.064661)
			(xy 453.513444 -113.043517) (xy 453.468602 -113.01596) (xy 453.427966 -112.982509) (xy 453.409812 -112.963452)
			(xy 453.402281 -112.956061) (xy 453.383008 -112.947529) (xy 453.372474 -112.946942) (xy 453.297798 -112.946942)
			(xy 453.287245 -112.947444) (xy 453.267949 -112.955997) (xy 453.26046 -112.963452) (xy 453.242327 -112.98253)
			(xy 453.201691 -113.015983) (xy 453.156846 -113.043538) (xy 453.108641 -113.064672) (xy 453.05799 -113.078985)
			(xy 453.005853 -113.086206) (xy 452.979536 -113.086642) (xy 452.952286 -113.086111) (xy 452.898339 -113.07836)
			(xy 452.846044 -113.06301) (xy 452.796467 -113.040375) (xy 452.750615 -113.010913) (xy 452.709423 -112.975227)
			(xy 452.673729 -112.934041) (xy 452.644259 -112.888195) (xy 452.621614 -112.838621) (xy 452.606255 -112.78633)
			(xy 452.598494 -112.732384) (xy 452.598028 -112.705134) (xy 452.598442 -112.678818) (xy 452.605687 -112.626687)
			(xy 452.620016 -112.576043) (xy 452.641158 -112.527844) (xy 452.668714 -112.483002) (xy 452.702162 -112.442365)
			(xy 452.721218 -112.42421) (xy 452.72862 -112.416689) (xy 452.737144 -112.397408) (xy 452.737728 -112.386872)
			(xy 452.737728 -112.312196) (xy 452.737206 -112.301646) (xy 452.728665 -112.282351) (xy 452.721218 -112.274858)
			(xy 452.700462 -112.255005) (xy 452.664484 -112.210239) (xy 452.63562 -112.160586) (xy 452.614523 -112.107169)
			(xy 452.60167 -112.051193) (xy 452.597351 -111.993923) (xy 449.155522 -111.993923) (xy 449.158813 -112.037615)
			(xy 449.154495 -112.09489) (xy 449.141643 -112.150871) (xy 449.120547 -112.204294) (xy 449.091684 -112.253953)
			(xy 449.055706 -112.298726) (xy 449.034916 -112.318546) (xy 449.027494 -112.326051) (xy 449.018981 -112.345343)
			(xy 449.018406 -112.355884) (xy 449.018406 -112.43056) (xy 449.018941 -112.441109) (xy 449.027472 -112.460405)
			(xy 449.034916 -112.467898) (xy 449.053967 -112.486058) (xy 449.087424 -112.526687) (xy 449.114983 -112.571527)
			(xy 449.136122 -112.619727) (xy 449.15044 -112.670373) (xy 449.157667 -112.722506) (xy 449.158106 -112.748822)
			(xy 449.15762 -112.776073) (xy 449.149864 -112.830021) (xy 449.134509 -112.882316) (xy 449.111867 -112.931893)
			(xy 449.082401 -112.977743) (xy 449.04671 -113.018934) (xy 449.005519 -113.054625) (xy 448.959669 -113.084091)
			(xy 448.910092 -113.106733) (xy 448.857797 -113.122088) (xy 448.803849 -113.129844) (xy 448.749347 -113.129844)
			(xy 448.695399 -113.122088) (xy 448.643104 -113.106733) (xy 448.593527 -113.084091) (xy 448.547677 -113.054625)
			(xy 448.506486 -113.018934) (xy 448.470795 -112.977743) (xy 448.441329 -112.931893) (xy 448.418687 -112.882316)
			(xy 448.403332 -112.830021) (xy 448.395576 -112.776073) (xy 448.39509 -112.748822) (xy 448.395575 -112.722509)
			(xy 448.402807 -112.670381) (xy 448.417123 -112.619739) (xy 448.438252 -112.57154) (xy 448.465795 -112.526696)
			(xy 448.49923 -112.486055) (xy 448.51828 -112.467898) (xy 448.525682 -112.460376) (xy 448.534207 -112.441096)
			(xy 448.53479 -112.43056) (xy 448.53479 -112.355884) (xy 448.534286 -112.345331) (xy 448.525734 -112.326036)
			(xy 448.51828 -112.318546) (xy 448.497514 -112.298704) (xy 448.461539 -112.253935) (xy 448.432679 -112.20428)
			(xy 448.411585 -112.150861) (xy 448.398734 -112.094885) (xy 448.394417 -112.037615) (xy 446.620598 -112.037615)
			(xy 446.61628 -112.094891) (xy 446.603427 -112.150872) (xy 446.58233 -112.204296) (xy 446.553465 -112.253954)
			(xy 446.517485 -112.298727) (xy 446.496694 -112.318546) (xy 446.489269 -112.326048) (xy 446.480759 -112.345343)
			(xy 446.480184 -112.355884) (xy 446.480184 -112.43056) (xy 446.480726 -112.441108) (xy 446.489253 -112.460403)
			(xy 446.496694 -112.467898) (xy 446.51574 -112.486063) (xy 446.549199 -112.52669) (xy 446.576759 -112.571529)
			(xy 446.597899 -112.619728) (xy 446.612218 -112.670374) (xy 446.619445 -112.722506) (xy 446.619884 -112.748822)
			(xy 446.619398 -112.776073) (xy 446.611642 -112.830021) (xy 446.596287 -112.882316) (xy 446.573645 -112.931893)
			(xy 446.544179 -112.977743) (xy 446.508488 -113.018934) (xy 446.467297 -113.054625) (xy 446.421447 -113.084091)
			(xy 446.37187 -113.106733) (xy 446.319575 -113.122088) (xy 446.265627 -113.129844) (xy 446.211125 -113.129844)
			(xy 446.157177 -113.122088) (xy 446.104882 -113.106733) (xy 446.055305 -113.084091) (xy 446.009455 -113.054625)
			(xy 445.968264 -113.018934) (xy 445.932573 -112.977743) (xy 445.903107 -112.931893) (xy 445.880465 -112.882316)
			(xy 445.86511 -112.830021) (xy 445.857354 -112.776073) (xy 445.856868 -112.748822) (xy 445.85736 -112.722509)
			(xy 445.864592 -112.670382) (xy 445.878906 -112.61974) (xy 445.900034 -112.571541) (xy 445.927575 -112.526697)
			(xy 445.961009 -112.486056) (xy 445.980058 -112.467898) (xy 445.987456 -112.460373) (xy 445.995984 -112.441096)
			(xy 445.996568 -112.43056) (xy 445.996568 -112.355884) (xy 445.99607 -112.34533) (xy 445.987514 -112.326035)
			(xy 445.980058 -112.318546) (xy 445.959293 -112.298703) (xy 445.92332 -112.253933) (xy 445.894462 -112.204279)
			(xy 445.873369 -112.15086) (xy 445.860519 -112.094884) (xy 445.856202 -112.037615) (xy 444.06285 -112.037615)
			(xy 444.094309 -112.075823) (xy 444.121867 -112.120665) (xy 444.143003 -112.168869) (xy 444.157317 -112.219519)
			(xy 444.164538 -112.271655) (xy 444.164974 -112.297972) (xy 444.164488 -112.325223) (xy 444.156732 -112.379171)
			(xy 444.141377 -112.431466) (xy 444.118735 -112.481043) (xy 444.089269 -112.526893) (xy 444.053578 -112.568084)
			(xy 444.012387 -112.603775) (xy 443.966537 -112.633241) (xy 443.91696 -112.655883) (xy 443.864665 -112.671238)
			(xy 443.810717 -112.678994) (xy 443.756215 -112.678994) (xy 443.702267 -112.671238) (xy 443.649972 -112.655883)
			(xy 443.600395 -112.633241) (xy 443.554545 -112.603775) (xy 443.513354 -112.568084) (xy 443.477663 -112.526893)
			(xy 443.448197 -112.481043) (xy 443.425555 -112.431466) (xy 443.4102 -112.379171) (xy 443.402444 -112.325223)
			(xy 443.401958 -112.297972) (xy 442.132974 -112.297972) (xy 442.132488 -112.325223) (xy 442.124732 -112.379171)
			(xy 442.109377 -112.431466) (xy 442.086735 -112.481043) (xy 442.057269 -112.526893) (xy 442.021578 -112.568084)
			(xy 441.980387 -112.603775) (xy 441.934537 -112.633241) (xy 441.88496 -112.655883) (xy 441.832665 -112.671238)
			(xy 441.778717 -112.678994) (xy 441.724215 -112.678994) (xy 441.670267 -112.671238) (xy 441.617972 -112.655883)
			(xy 441.568395 -112.633241) (xy 441.522545 -112.603775) (xy 441.481354 -112.568084) (xy 441.445663 -112.526893)
			(xy 441.416197 -112.481043) (xy 441.393555 -112.431466) (xy 441.3782 -112.379171) (xy 441.370444 -112.325223)
			(xy 441.369958 -112.297972) (xy 423.505424 -112.297972) (xy 423.477377 -112.315996) (xy 423.427799 -112.338636)
			(xy 423.375503 -112.353991) (xy 423.321554 -112.361748) (xy 423.294302 -112.362234) (xy 423.267989 -112.361754)
			(xy 423.215861 -112.35452) (xy 423.165219 -112.340203) (xy 423.11702 -112.319073) (xy 423.072176 -112.291529)
			(xy 423.031536 -112.258094) (xy 423.013378 -112.239044) (xy 423.005861 -112.231637) (xy 422.986578 -112.223114)
			(xy 422.97604 -112.222534) (xy 422.901364 -112.222534) (xy 422.890815 -112.223074) (xy 422.871519 -112.2316)
			(xy 422.864026 -112.239044) (xy 422.845859 -112.258088) (xy 422.805231 -112.291545) (xy 422.760393 -112.319104)
			(xy 422.712194 -112.340244) (xy 422.661549 -112.354564) (xy 422.609417 -112.361793) (xy 422.583102 -112.362234)
			(xy 422.555852 -112.36172) (xy 422.501907 -112.353965) (xy 422.449614 -112.338611) (xy 422.400038 -112.315972)
			(xy 422.354189 -112.286509) (xy 422.313 -112.25082) (xy 422.277308 -112.209633) (xy 422.247841 -112.163786)
			(xy 422.225198 -112.114212) (xy 422.209841 -112.061921) (xy 422.202082 -112.007976) (xy 422.201594 -111.980726)
			(xy 419.415236 -111.980726) (xy 419.403217 -112.020675) (xy 419.379545 -112.071172) (xy 419.348772 -112.117685)
			(xy 419.311555 -112.159222) (xy 419.268687 -112.194897) (xy 419.221081 -112.223951) (xy 419.169752 -112.245763)
			(xy 419.115795 -112.259869) (xy 419.060358 -112.265969) (xy 419.004624 -112.263932) (xy 418.949781 -112.253802)
			(xy 418.896997 -112.235795) (xy 418.847397 -112.210294) (xy 418.802039 -112.177843) (xy 418.76189 -112.139134)
			(xy 418.727804 -112.094991) (xy 418.700508 -112.046356) (xy 418.680585 -111.994265) (xy 418.668459 -111.939828)
			(xy 418.664388 -111.884206) (xy 400.999999 -111.884206) (xy 401.000468 -111.912908) (xy 401.000468 -112.510824)
			(xy 412.102552 -112.510824) (xy 412.106623 -112.455202) (xy 412.118749 -112.400765) (xy 412.138672 -112.348674)
			(xy 412.165968 -112.300039) (xy 412.200054 -112.255896) (xy 412.240203 -112.217187) (xy 412.285561 -112.184736)
			(xy 412.335161 -112.159235) (xy 412.387945 -112.141228) (xy 412.442788 -112.131098) (xy 412.498522 -112.129061)
			(xy 412.553959 -112.135161) (xy 412.607916 -112.149267) (xy 412.659245 -112.171079) (xy 412.706851 -112.200133)
			(xy 412.749719 -112.235808) (xy 412.786936 -112.277345) (xy 412.817709 -112.323858) (xy 412.841381 -112.374355)
			(xy 412.857449 -112.427762) (xy 412.865569 -112.482938) (xy 412.865614 -112.485424) (xy 414.951162 -112.485424)
			(xy 414.955233 -112.429802) (xy 414.967359 -112.375365) (xy 414.987282 -112.323274) (xy 415.014578 -112.274639)
			(xy 415.048664 -112.230496) (xy 415.088813 -112.191787) (xy 415.134171 -112.159336) (xy 415.183771 -112.133835)
			(xy 415.236555 -112.115828) (xy 415.291398 -112.105698) (xy 415.347132 -112.103661) (xy 415.402569 -112.109761)
			(xy 415.456526 -112.123867) (xy 415.507855 -112.145679) (xy 415.555461 -112.174733) (xy 415.598329 -112.210408)
			(xy 415.635546 -112.251945) (xy 415.666319 -112.298458) (xy 415.689991 -112.348955) (xy 415.706059 -112.402362)
			(xy 415.708938 -112.421924) (xy 417.755068 -112.421924) (xy 417.759139 -112.366302) (xy 417.771265 -112.311865)
			(xy 417.791188 -112.259774) (xy 417.818484 -112.211139) (xy 417.85257 -112.166996) (xy 417.892719 -112.128287)
			(xy 417.938077 -112.095836) (xy 417.987677 -112.070335) (xy 418.040461 -112.052328) (xy 418.095304 -112.042198)
			(xy 418.151038 -112.040161) (xy 418.206475 -112.046261) (xy 418.260432 -112.060367) (xy 418.311761 -112.082179)
			(xy 418.359367 -112.111233) (xy 418.402235 -112.146908) (xy 418.439452 -112.188445) (xy 418.470225 -112.234958)
			(xy 418.493897 -112.285455) (xy 418.509965 -112.338862) (xy 418.518085 -112.394038) (xy 418.518594 -112.421924)
			(xy 418.518085 -112.44981) (xy 418.509965 -112.504986) (xy 418.493897 -112.558393) (xy 418.470225 -112.60889)
			(xy 418.439452 -112.655403) (xy 418.402235 -112.69694) (xy 418.359367 -112.732615) (xy 418.311761 -112.761669)
			(xy 418.260432 -112.783481) (xy 418.206475 -112.797587) (xy 418.151038 -112.803687) (xy 418.095304 -112.80165)
			(xy 418.040461 -112.79152) (xy 417.987677 -112.773513) (xy 417.938077 -112.748012) (xy 417.892719 -112.715561)
			(xy 417.85257 -112.676852) (xy 417.818484 -112.632709) (xy 417.791188 -112.584074) (xy 417.771265 -112.531983)
			(xy 417.759139 -112.477546) (xy 417.755068 -112.421924) (xy 415.708938 -112.421924) (xy 415.714179 -112.457538)
			(xy 415.714688 -112.485424) (xy 415.714179 -112.51331) (xy 415.706059 -112.568486) (xy 415.689991 -112.621893)
			(xy 415.666319 -112.67239) (xy 415.635546 -112.718903) (xy 415.598329 -112.76044) (xy 415.555461 -112.796115)
			(xy 415.507855 -112.825169) (xy 415.456526 -112.846981) (xy 415.402569 -112.861087) (xy 415.347132 -112.867187)
			(xy 415.291398 -112.86515) (xy 415.236555 -112.85502) (xy 415.183771 -112.837013) (xy 415.134171 -112.811512)
			(xy 415.088813 -112.779061) (xy 415.048664 -112.740352) (xy 415.014578 -112.696209) (xy 414.987282 -112.647574)
			(xy 414.967359 -112.595483) (xy 414.955233 -112.541046) (xy 414.951162 -112.485424) (xy 412.865614 -112.485424)
			(xy 412.866078 -112.510824) (xy 412.865569 -112.53871) (xy 412.857449 -112.593886) (xy 412.841381 -112.647293)
			(xy 412.817709 -112.69779) (xy 412.786936 -112.744303) (xy 412.749719 -112.78584) (xy 412.706851 -112.821515)
			(xy 412.659245 -112.850569) (xy 412.607916 -112.872381) (xy 412.553959 -112.886487) (xy 412.498522 -112.892587)
			(xy 412.442788 -112.89055) (xy 412.387945 -112.88042) (xy 412.335161 -112.862413) (xy 412.285561 -112.836912)
			(xy 412.240203 -112.804461) (xy 412.200054 -112.765752) (xy 412.165968 -112.721609) (xy 412.138672 -112.672974)
			(xy 412.118749 -112.620883) (xy 412.106623 -112.566446) (xy 412.102552 -112.510824) (xy 401.000468 -112.510824)
			(xy 401.000468 -112.776508) (xy 400.999978 -112.806476) (xy 400.992155 -112.865898) (xy 400.976642 -112.923791)
			(xy 400.953706 -112.979164) (xy 400.923739 -113.03107) (xy 400.887252 -113.07862) (xy 400.844872 -113.121)
			(xy 400.797322 -113.157487) (xy 400.745416 -113.187454) (xy 400.690043 -113.21039) (xy 400.63215 -113.225903)
			(xy 400.572728 -113.233726) (xy 400.512792 -113.233726) (xy 400.45337 -113.225903) (xy 400.395477 -113.21039)
			(xy 400.340104 -113.187454) (xy 400.288198 -113.157487) (xy 400.240648 -113.121) (xy 400.198268 -113.07862)
			(xy 400.161781 -113.03107) (xy 400.131814 -112.979164) (xy 400.108878 -112.923791) (xy 400.093365 -112.865898)
			(xy 400.085542 -112.806476) (xy 400.085052 -112.776508) (xy 389.40232 -112.776508) (xy 389.40232 -113.251742)
			(xy 412.606234 -113.251742) (xy 412.610305 -113.19612) (xy 412.622431 -113.141683) (xy 412.642354 -113.089592)
			(xy 412.66965 -113.040957) (xy 412.703736 -112.996814) (xy 412.743885 -112.958105) (xy 412.789243 -112.925654)
			(xy 412.838843 -112.900153) (xy 412.891627 -112.882146) (xy 412.94647 -112.872016) (xy 413.002204 -112.869979)
			(xy 413.057641 -112.876079) (xy 413.111598 -112.890185) (xy 413.162927 -112.911997) (xy 413.210533 -112.941051)
			(xy 413.253401 -112.976726) (xy 413.264949 -112.989614) (xy 418.74008 -112.989614) (xy 418.744151 -112.933992)
			(xy 418.756277 -112.879555) (xy 418.7762 -112.827464) (xy 418.803496 -112.778829) (xy 418.837582 -112.734686)
			(xy 418.877731 -112.695977) (xy 418.923089 -112.663526) (xy 418.972689 -112.638025) (xy 419.025473 -112.620018)
			(xy 419.080316 -112.609888) (xy 419.13605 -112.607851) (xy 419.191487 -112.613951) (xy 419.245444 -112.628057)
			(xy 419.296773 -112.649869) (xy 419.344379 -112.678923) (xy 419.387247 -112.714598) (xy 419.424464 -112.756135)
			(xy 419.455237 -112.802648) (xy 419.478909 -112.853145) (xy 419.494977 -112.906552) (xy 419.503097 -112.961728)
			(xy 419.503606 -112.989614) (xy 419.503097 -113.0175) (xy 419.494977 -113.072676) (xy 419.478909 -113.126083)
			(xy 419.455237 -113.17658) (xy 419.424464 -113.223093) (xy 419.387247 -113.26463) (xy 419.344379 -113.300305)
			(xy 419.296773 -113.329359) (xy 419.245444 -113.351171) (xy 419.191487 -113.365277) (xy 419.13605 -113.371377)
			(xy 419.080316 -113.36934) (xy 419.025473 -113.35921) (xy 418.972689 -113.341203) (xy 418.923089 -113.315702)
			(xy 418.877731 -113.283251) (xy 418.837582 -113.244542) (xy 418.803496 -113.200399) (xy 418.7762 -113.151764)
			(xy 418.756277 -113.099673) (xy 418.744151 -113.045236) (xy 418.74008 -112.989614) (xy 413.264949 -112.989614)
			(xy 413.290618 -113.018263) (xy 413.321391 -113.064776) (xy 413.345063 -113.115273) (xy 413.361131 -113.16868)
			(xy 413.369251 -113.223856) (xy 413.36976 -113.251742) (xy 413.369251 -113.279628) (xy 413.361131 -113.334804)
			(xy 413.345063 -113.388211) (xy 413.323068 -113.43513) (xy 414.954972 -113.43513) (xy 414.959043 -113.379508)
			(xy 414.971169 -113.325071) (xy 414.991092 -113.27298) (xy 415.018388 -113.224345) (xy 415.052474 -113.180202)
			(xy 415.092623 -113.141493) (xy 415.137981 -113.109042) (xy 415.187581 -113.083541) (xy 415.240365 -113.065534)
			(xy 415.295208 -113.055404) (xy 415.350942 -113.053367) (xy 415.406379 -113.059467) (xy 415.460336 -113.073573)
			(xy 415.511665 -113.095385) (xy 415.559271 -113.124439) (xy 415.602139 -113.160114) (xy 415.639356 -113.201651)
			(xy 415.670129 -113.248164) (xy 415.693801 -113.298661) (xy 415.709869 -113.352068) (xy 415.717989 -113.407244)
			(xy 415.718498 -113.43513) (xy 415.718447 -113.437924) (xy 417.657786 -113.437924) (xy 417.661857 -113.382302)
			(xy 417.673983 -113.327865) (xy 417.693906 -113.275774) (xy 417.721202 -113.227139) (xy 417.755288 -113.182996)
			(xy 417.795437 -113.144287) (xy 417.840795 -113.111836) (xy 417.890395 -113.086335) (xy 417.943179 -113.068328)
			(xy 417.998022 -113.058198) (xy 418.053756 -113.056161) (xy 418.109193 -113.062261) (xy 418.16315 -113.076367)
			(xy 418.214479 -113.098179) (xy 418.262085 -113.127233) (xy 418.304953 -113.162908) (xy 418.34217 -113.204445)
			(xy 418.372943 -113.250958) (xy 418.396615 -113.301455) (xy 418.412683 -113.354862) (xy 418.420803 -113.410038)
			(xy 418.421312 -113.437924) (xy 418.420803 -113.46581) (xy 418.412683 -113.520986) (xy 418.396615 -113.574393)
			(xy 418.372943 -113.62489) (xy 418.34217 -113.671403) (xy 418.304953 -113.71294) (xy 418.262085 -113.748615)
			(xy 418.214479 -113.777669) (xy 418.16315 -113.799481) (xy 418.109193 -113.813587) (xy 418.053756 -113.819687)
			(xy 417.998022 -113.81765) (xy 417.943179 -113.80752) (xy 417.890395 -113.789513) (xy 417.840795 -113.764012)
			(xy 417.795437 -113.731561) (xy 417.755288 -113.692852) (xy 417.721202 -113.648709) (xy 417.693906 -113.600074)
			(xy 417.673983 -113.547983) (xy 417.661857 -113.493546) (xy 417.657786 -113.437924) (xy 415.718447 -113.437924)
			(xy 415.717989 -113.463016) (xy 415.709869 -113.518192) (xy 415.693801 -113.571599) (xy 415.670129 -113.622096)
			(xy 415.639356 -113.668609) (xy 415.602139 -113.710146) (xy 415.559271 -113.745821) (xy 415.511665 -113.774875)
			(xy 415.460336 -113.796687) (xy 415.406379 -113.810793) (xy 415.350942 -113.816893) (xy 415.295208 -113.814856)
			(xy 415.240365 -113.804726) (xy 415.187581 -113.786719) (xy 415.137981 -113.761218) (xy 415.092623 -113.728767)
			(xy 415.052474 -113.690058) (xy 415.018388 -113.645915) (xy 414.991092 -113.59728) (xy 414.971169 -113.545189)
			(xy 414.959043 -113.490752) (xy 414.954972 -113.43513) (xy 413.323068 -113.43513) (xy 413.321391 -113.438708)
			(xy 413.290618 -113.485221) (xy 413.253401 -113.526758) (xy 413.210533 -113.562433) (xy 413.162927 -113.591487)
			(xy 413.111598 -113.613299) (xy 413.057641 -113.627405) (xy 413.002204 -113.633505) (xy 412.94647 -113.631468)
			(xy 412.891627 -113.621338) (xy 412.838843 -113.603331) (xy 412.789243 -113.57783) (xy 412.743885 -113.545379)
			(xy 412.703736 -113.50667) (xy 412.66965 -113.462527) (xy 412.642354 -113.413892) (xy 412.622431 -113.361801)
			(xy 412.610305 -113.307364) (xy 412.606234 -113.251742) (xy 389.40232 -113.251742) (xy 389.40232 -114.290094)
			(xy 418.660324 -114.290094) (xy 418.664395 -114.234472) (xy 418.676521 -114.180035) (xy 418.696444 -114.127944)
			(xy 418.72374 -114.079309) (xy 418.757826 -114.035166) (xy 418.797975 -113.996457) (xy 418.843333 -113.964006)
			(xy 418.892933 -113.938505) (xy 418.945717 -113.920498) (xy 419.00056 -113.910368) (xy 419.056294 -113.908331)
			(xy 419.111731 -113.914431) (xy 419.165688 -113.928537) (xy 419.217017 -113.950349) (xy 419.264623 -113.979403)
			(xy 419.307491 -114.015078) (xy 419.344708 -114.056615) (xy 419.363231 -114.084613) (xy 437.749383 -114.084613)
			(xy 437.749388 -114.030111) (xy 437.75715 -113.976165) (xy 437.77251 -113.923872) (xy 437.795156 -113.874298)
			(xy 437.824627 -113.828451) (xy 437.860322 -113.787265) (xy 437.901515 -113.751579) (xy 437.947368 -113.722118)
			(xy 437.996947 -113.699482) (xy 438.049243 -113.684133) (xy 438.103191 -113.676382) (xy 438.130442 -113.675922)
			(xy 438.130696 -113.675922) (xy 438.160133 -113.676472) (xy 438.218307 -113.685537) (xy 438.24652 -113.693956)
			(xy 438.258458 -113.697766) (xy 438.282334 -113.693956) (xy 438.358534 -113.637568) (xy 438.367806 -113.629826)
			(xy 438.37855 -113.608231) (xy 438.379108 -113.596166) (xy 438.379108 -113.591086) (xy 438.379542 -113.563832)
			(xy 438.387301 -113.509879) (xy 438.40266 -113.45758) (xy 438.425305 -113.407998) (xy 438.454776 -113.362145)
			(xy 438.490473 -113.320952) (xy 438.531669 -113.285258) (xy 438.577525 -113.255791) (xy 438.627108 -113.233149)
			(xy 438.679409 -113.217795) (xy 438.733362 -113.21004) (xy 438.760616 -113.209578) (xy 438.789532 -113.210127)
			(xy 438.846703 -113.218846) (xy 438.901903 -113.236096) (xy 438.953865 -113.261481) (xy 439.0014 -113.294421)
			(xy 439.043416 -113.33416) (xy 439.061606 -113.356644) (xy 439.069213 -113.365451) (xy 439.090114 -113.375633)
			(xy 439.101738 -113.376202) (xy 439.181494 -113.376202) (xy 439.193124 -113.375645) (xy 439.214033 -113.365469)
			(xy 439.221626 -113.356644) (xy 439.239813 -113.334157) (xy 439.281833 -113.29442) (xy 439.329368 -113.26148)
			(xy 439.38133 -113.236092) (xy 439.436529 -113.218837) (xy 439.4937 -113.210111) (xy 439.522616 -113.209578)
			(xy 439.549867 -113.210063) (xy 439.603814 -113.217821) (xy 439.656108 -113.233178) (xy 439.705684 -113.25582)
			(xy 439.751534 -113.285286) (xy 439.792724 -113.320978) (xy 439.828415 -113.362168) (xy 439.857881 -113.408017)
			(xy 439.880523 -113.457594) (xy 439.895879 -113.509888) (xy 439.903637 -113.563835) (xy 439.904124 -113.591086)
			(xy 439.903696 -113.618491) (xy 439.895842 -113.672735) (xy 439.880307 -113.725297) (xy 439.857412 -113.775095)
			(xy 439.827627 -113.821106) (xy 439.791566 -113.862381) (xy 439.74997 -113.898072) (xy 439.727086 -113.913158)
			(xy 439.718067 -113.919608) (xy 439.706213 -113.938317) (xy 439.704226 -113.949226) (xy 439.692034 -114.037364)
			(xy 439.698638 -114.0587) (xy 439.706258 -114.067082) (xy 439.724546 -114.088672) (xy 439.73208 -114.097462)
			(xy 439.75286 -114.107627) (xy 439.764424 -114.10823) (xy 439.844434 -114.10823) (xy 439.85607 -114.107721)
			(xy 439.876981 -114.097513) (xy 439.884566 -114.088672) (xy 439.902769 -114.066199) (xy 439.944787 -114.026464)
			(xy 439.99232 -113.993525) (xy 440.044279 -113.968135) (xy 440.099474 -113.950876) (xy 440.156641 -113.942143)
			(xy 440.185556 -113.941606) (xy 440.212812 -113.942038) (xy 440.26677 -113.94979) (xy 440.319075 -113.965143)
			(xy 440.368662 -113.987784) (xy 440.414523 -114.017252) (xy 440.427475 -114.028474) (xy 453.305162 -114.028474)
			(xy 453.309233 -113.972852) (xy 453.321359 -113.918415) (xy 453.341282 -113.866324) (xy 453.368578 -113.817689)
			(xy 453.402664 -113.773546) (xy 453.442813 -113.734837) (xy 453.488171 -113.702386) (xy 453.537771 -113.676885)
			(xy 453.590555 -113.658878) (xy 453.645398 -113.648748) (xy 453.701132 -113.646711) (xy 453.756569 -113.652811)
			(xy 453.810526 -113.666917) (xy 453.861855 -113.688729) (xy 453.909461 -113.717783) (xy 453.952329 -113.753458)
			(xy 453.989546 -113.794995) (xy 454.020319 -113.841508) (xy 454.043991 -113.892005) (xy 454.060059 -113.945412)
			(xy 454.068179 -114.000588) (xy 454.068688 -114.028474) (xy 454.068179 -114.05636) (xy 454.060059 -114.111536)
			(xy 454.043991 -114.164943) (xy 454.020319 -114.21544) (xy 453.989546 -114.261953) (xy 453.952329 -114.30349)
			(xy 453.909461 -114.339165) (xy 453.861855 -114.368219) (xy 453.810526 -114.390031) (xy 453.756569 -114.404137)
			(xy 453.701132 -114.410237) (xy 453.645398 -114.4082) (xy 453.590555 -114.39807) (xy 453.537771 -114.380063)
			(xy 453.488171 -114.354562) (xy 453.442813 -114.322111) (xy 453.402664 -114.283402) (xy 453.368578 -114.239259)
			(xy 453.341282 -114.190624) (xy 453.321359 -114.138533) (xy 453.309233 -114.084096) (xy 453.305162 -114.028474)
			(xy 440.427475 -114.028474) (xy 440.455722 -114.052947) (xy 440.491422 -114.094142) (xy 440.520895 -114.139999)
			(xy 440.543542 -114.189584) (xy 440.558901 -114.241887) (xy 440.566659 -114.295844) (xy 440.566659 -114.350356)
			(xy 440.558901 -114.404313) (xy 440.543542 -114.456616) (xy 440.520895 -114.506201) (xy 440.491422 -114.552058)
			(xy 440.455722 -114.593253) (xy 440.414523 -114.628948) (xy 440.368662 -114.658416) (xy 440.319075 -114.681057)
			(xy 440.26677 -114.69641) (xy 440.212812 -114.704162) (xy 440.185556 -114.704622) (xy 440.156639 -114.704093)
			(xy 440.099467 -114.69537) (xy 440.044267 -114.678116) (xy 439.992305 -114.652727) (xy 439.944771 -114.619784)
			(xy 439.902755 -114.580042) (xy 439.884566 -114.557556) (xy 439.876971 -114.548736) (xy 439.856061 -114.538561)
			(xy 439.844434 -114.537998) (xy 439.764678 -114.537998) (xy 439.753046 -114.53854) (xy 439.732137 -114.548727)
			(xy 439.724546 -114.557556) (xy 439.706318 -114.580008) (xy 439.664307 -114.619747) (xy 439.61678 -114.652691)
			(xy 439.564826 -114.678086) (xy 439.509635 -114.695348) (xy 439.45247 -114.704084) (xy 439.423556 -114.704622)
			(xy 439.396304 -114.704163) (xy 439.342356 -114.696401) (xy 439.290062 -114.681041) (xy 439.240486 -114.658396)
			(xy 439.194636 -114.628926) (xy 439.153447 -114.593232) (xy 439.117756 -114.55204) (xy 439.08829 -114.506188)
			(xy 439.065648 -114.45661) (xy 439.050293 -114.404314) (xy 439.042535 -114.350366) (xy 439.042048 -114.323114)
			(xy 439.042489 -114.29571) (xy 439.050342 -114.241467) (xy 439.065876 -114.188906) (xy 439.088769 -114.139108)
			(xy 439.118552 -114.093098) (xy 439.154611 -114.051822) (xy 439.196204 -114.016129) (xy 439.219086 -114.001042)
			(xy 439.228118 -113.994609) (xy 439.239962 -113.975886) (xy 439.241946 -113.964974) (xy 439.254138 -113.876836)
			(xy 439.247534 -113.8555) (xy 439.239914 -113.847118) (xy 439.221626 -113.825528) (xy 439.214061 -113.81677)
			(xy 439.193304 -113.806588) (xy 439.181748 -113.80597) (xy 439.101738 -113.80597) (xy 439.0901 -113.806463)
			(xy 439.069189 -113.816682) (xy 439.061606 -113.825528) (xy 439.043419 -113.848014) (xy 439.001397 -113.887748)
			(xy 438.953861 -113.920686) (xy 438.9019 -113.946074) (xy 438.846702 -113.96333) (xy 438.789532 -113.972059)
			(xy 438.760616 -113.972594) (xy 438.760362 -113.972594) (xy 438.730925 -113.97203) (xy 438.672752 -113.962975)
			(xy 438.644538 -113.95456) (xy 438.6326 -113.95075) (xy 438.608724 -113.95456) (xy 438.532524 -114.010948)
			(xy 438.523238 -114.018675) (xy 438.512503 -114.040282) (xy 438.51195 -114.05235) (xy 438.51195 -114.05743)
			(xy 438.511413 -114.084681) (xy 438.503652 -114.138627) (xy 438.488293 -114.19092) (xy 438.465648 -114.240495)
			(xy 438.436178 -114.286342) (xy 438.400484 -114.327529) (xy 438.359291 -114.363217) (xy 438.313439 -114.392679)
			(xy 438.26386 -114.415315) (xy 438.211565 -114.430665) (xy 438.157617 -114.438417) (xy 438.103115 -114.438412)
			(xy 438.049169 -114.430651) (xy 437.996876 -114.415291) (xy 437.947302 -114.392646) (xy 437.901455 -114.363176)
			(xy 437.860268 -114.327481) (xy 437.824581 -114.286288) (xy 437.79512 -114.240435) (xy 437.772483 -114.190856)
			(xy 437.757134 -114.138561) (xy 437.749383 -114.084613) (xy 419.363231 -114.084613) (xy 419.375481 -114.103128)
			(xy 419.399153 -114.153625) (xy 419.415221 -114.207032) (xy 419.423341 -114.262208) (xy 419.42385 -114.290094)
			(xy 419.423341 -114.31798) (xy 419.415221 -114.373156) (xy 419.399153 -114.426563) (xy 419.375481 -114.47706)
			(xy 419.344708 -114.523573) (xy 419.307491 -114.56511) (xy 419.264623 -114.600785) (xy 419.217017 -114.629839)
			(xy 419.165688 -114.651651) (xy 419.111731 -114.665757) (xy 419.056294 -114.671857) (xy 419.00056 -114.66982)
			(xy 418.945717 -114.65969) (xy 418.892933 -114.641683) (xy 418.843333 -114.616182) (xy 418.797975 -114.583731)
			(xy 418.757826 -114.545022) (xy 418.72374 -114.500879) (xy 418.696444 -114.452244) (xy 418.676521 -114.400153)
			(xy 418.664395 -114.345716) (xy 418.660324 -114.290094) (xy 389.40232 -114.290094) (xy 389.40232 -114.87531)
			(xy 414.257488 -114.87531) (xy 414.261559 -114.819688) (xy 414.273685 -114.765251) (xy 414.293608 -114.71316)
			(xy 414.320904 -114.664525) (xy 414.35499 -114.620382) (xy 414.395139 -114.581673) (xy 414.440497 -114.549222)
			(xy 414.490097 -114.523721) (xy 414.542881 -114.505714) (xy 414.597724 -114.495584) (xy 414.653458 -114.493547)
			(xy 414.708895 -114.499647) (xy 414.762852 -114.513753) (xy 414.814181 -114.535565) (xy 414.861787 -114.564619)
			(xy 414.904655 -114.600294) (xy 414.941872 -114.641831) (xy 414.972645 -114.688344) (xy 414.996317 -114.738841)
			(xy 415.012385 -114.792248) (xy 415.020505 -114.847424) (xy 415.021014 -114.87531) (xy 415.020505 -114.903196)
			(xy 415.012385 -114.958372) (xy 414.996317 -115.011779) (xy 414.972645 -115.062276) (xy 414.941872 -115.108789)
			(xy 414.904655 -115.150326) (xy 414.861787 -115.186001) (xy 414.814181 -115.215055) (xy 414.762852 -115.236867)
			(xy 414.708895 -115.250973) (xy 414.653458 -115.257073) (xy 414.597724 -115.255036) (xy 414.542881 -115.244906)
			(xy 414.490097 -115.226899) (xy 414.440497 -115.201398) (xy 414.395139 -115.168947) (xy 414.35499 -115.130238)
			(xy 414.320904 -115.086095) (xy 414.293608 -115.03746) (xy 414.273685 -114.985369) (xy 414.261559 -114.930932)
			(xy 414.257488 -114.87531) (xy 389.40232 -114.87531) (xy 389.40232 -115.285774) (xy 415.230816 -115.285774)
			(xy 415.234887 -115.230152) (xy 415.247013 -115.175715) (xy 415.266936 -115.123624) (xy 415.294232 -115.074989)
			(xy 415.328318 -115.030846) (xy 415.368467 -114.992137) (xy 415.413825 -114.959686) (xy 415.463425 -114.934185)
			(xy 415.516209 -114.916178) (xy 415.571052 -114.906048) (xy 415.626786 -114.904011) (xy 415.682223 -114.910111)
			(xy 415.73618 -114.924217) (xy 415.787509 -114.946029) (xy 415.835115 -114.975083) (xy 415.877983 -115.010758)
			(xy 415.9152 -115.052295) (xy 415.945973 -115.098808) (xy 415.969645 -115.149305) (xy 415.985713 -115.202712)
			(xy 415.993833 -115.257888) (xy 415.994342 -115.285774) (xy 415.993833 -115.31366) (xy 415.986872 -115.360958)
			(xy 422.41851 -115.360958) (xy 422.419008 -115.333589) (xy 422.426817 -115.279411) (xy 422.442299 -115.226908)
			(xy 422.465134 -115.177161) (xy 422.494852 -115.131193) (xy 422.51249 -115.11026) (xy 422.512744 -115.110006)
			(xy 422.51834 -115.102926) (xy 422.52458 -115.086004) (xy 422.524936 -115.076986) (xy 422.524936 -115.00993)
			(xy 422.524557 -115.000916) (xy 422.518324 -114.983999) (xy 422.512744 -114.97691) (xy 422.51249 -114.97691)
			(xy 422.51249 -114.976656) (xy 422.494862 -114.955715) (xy 422.465149 -114.909744) (xy 422.442311 -114.859999)
			(xy 422.426817 -114.807501) (xy 422.418986 -114.753327) (xy 422.41851 -114.725958) (xy 422.418939 -114.698705)
			(xy 422.426701 -114.644754) (xy 422.442063 -114.592457) (xy 422.46471 -114.542879) (xy 422.494183 -114.497028)
			(xy 422.52988 -114.455837) (xy 422.571076 -114.420147) (xy 422.616931 -114.390681) (xy 422.666514 -114.368042)
			(xy 422.718813 -114.352689) (xy 422.772765 -114.344935) (xy 422.800018 -114.34445) (xy 422.827389 -114.344893)
			(xy 422.88157 -114.352715) (xy 422.934074 -114.368208) (xy 422.98382 -114.391056) (xy 423.029786 -114.420786)
			(xy 423.050716 -114.43843) (xy 423.05097 -114.438684) (xy 423.058062 -114.444262) (xy 423.074975 -114.450514)
			(xy 423.08399 -114.450876) (xy 423.151046 -114.450876) (xy 423.160061 -114.450498) (xy 423.176978 -114.444266)
			(xy 423.184066 -114.438684) (xy 423.184066 -114.43843) (xy 423.18432 -114.43843) (xy 423.205275 -114.42082)
			(xy 423.251241 -114.391102) (xy 423.300983 -114.36826) (xy 423.353478 -114.352763) (xy 423.40765 -114.344928)
			(xy 423.435018 -114.34445) (xy 423.462268 -114.344961) (xy 423.516212 -114.352719) (xy 423.568504 -114.368074)
			(xy 423.618079 -114.390714) (xy 423.663927 -114.420179) (xy 423.705116 -114.455867) (xy 423.740807 -114.497054)
			(xy 423.770274 -114.5429) (xy 423.792918 -114.592473) (xy 423.808276 -114.644764) (xy 423.816037 -114.698708)
			(xy 423.816526 -114.725958) (xy 423.816053 -114.753328) (xy 423.80824 -114.807508) (xy 423.792753 -114.860011)
			(xy 423.769913 -114.909759) (xy 423.740188 -114.955725) (xy 423.722546 -114.976656) (xy 423.722292 -114.97691)
			(xy 423.716694 -114.983989) (xy 423.710455 -115.000912) (xy 423.7101 -115.00993) (xy 423.7101 -115.076986)
			(xy 423.710464 -115.086002) (xy 423.716707 -115.102919) (xy 423.722292 -115.110006) (xy 423.722546 -115.110006)
			(xy 423.722546 -115.11026) (xy 423.740171 -115.131203) (xy 423.769887 -115.177172) (xy 423.792727 -115.226917)
			(xy 423.808221 -115.279415) (xy 423.816051 -115.333589) (xy 423.816526 -115.360958) (xy 423.816006 -115.388209)
			(xy 423.814192 -115.400836) (xy 435.560722 -115.400836) (xy 435.564793 -115.345214) (xy 435.576919 -115.290777)
			(xy 435.596842 -115.238686) (xy 435.624138 -115.190051) (xy 435.658224 -115.145908) (xy 435.698373 -115.107199)
			(xy 435.743731 -115.074748) (xy 435.793331 -115.049247) (xy 435.846115 -115.03124) (xy 435.900958 -115.02111)
			(xy 435.956692 -115.019073) (xy 436.012129 -115.025173) (xy 436.066086 -115.039279) (xy 436.117415 -115.061091)
			(xy 436.165021 -115.090145) (xy 436.207889 -115.12582) (xy 436.245106 -115.167357) (xy 436.275879 -115.21387)
			(xy 436.299551 -115.264367) (xy 436.315619 -115.317774) (xy 436.323357 -115.370356) (xy 437.661302 -115.370356)
			(xy 437.665373 -115.314734) (xy 437.677499 -115.260297) (xy 437.697422 -115.208206) (xy 437.724718 -115.159571)
			(xy 437.758804 -115.115428) (xy 437.798953 -115.076719) (xy 437.844311 -115.044268) (xy 437.893911 -115.018767)
			(xy 437.946695 -115.00076) (xy 438.001538 -114.99063) (xy 438.057272 -114.988593) (xy 438.112709 -114.994693)
			(xy 438.166666 -115.008799) (xy 438.171718 -115.010946) (xy 454.91984 -115.010946) (xy 454.923911 -114.955324)
			(xy 454.936037 -114.900887) (xy 454.95596 -114.848796) (xy 454.983256 -114.800161) (xy 455.017342 -114.756018)
			(xy 455.057491 -114.717309) (xy 455.102849 -114.684858) (xy 455.152449 -114.659357) (xy 455.205233 -114.64135)
			(xy 455.260076 -114.63122) (xy 455.31581 -114.629183) (xy 455.371247 -114.635283) (xy 455.425204 -114.649389)
			(xy 455.476533 -114.671201) (xy 455.524139 -114.700255) (xy 455.567007 -114.73593) (xy 455.604224 -114.777467)
			(xy 455.634997 -114.82398) (xy 455.658669 -114.874477) (xy 455.674737 -114.927884) (xy 455.682857 -114.98306)
			(xy 455.683366 -115.010946) (xy 455.682857 -115.038832) (xy 455.679933 -115.058698) (xy 456.28636 -115.058698)
			(xy 456.290431 -115.003076) (xy 456.302557 -114.948639) (xy 456.32248 -114.896548) (xy 456.349776 -114.847913)
			(xy 456.383862 -114.80377) (xy 456.424011 -114.765061) (xy 456.469369 -114.73261) (xy 456.518969 -114.707109)
			(xy 456.571753 -114.689102) (xy 456.626596 -114.678972) (xy 456.68233 -114.676935) (xy 456.737767 -114.683035)
			(xy 456.791724 -114.697141) (xy 456.843053 -114.718953) (xy 456.890659 -114.748007) (xy 456.933527 -114.783682)
			(xy 456.970744 -114.825219) (xy 457.001517 -114.871732) (xy 457.025189 -114.922229) (xy 457.041257 -114.975636)
			(xy 457.043426 -114.990372) (xy 457.665072 -114.990372) (xy 457.669143 -114.93475) (xy 457.681269 -114.880313)
			(xy 457.701192 -114.828222) (xy 457.728488 -114.779587) (xy 457.762574 -114.735444) (xy 457.802723 -114.696735)
			(xy 457.848081 -114.664284) (xy 457.897681 -114.638783) (xy 457.950465 -114.620776) (xy 458.005308 -114.610646)
			(xy 458.061042 -114.608609) (xy 458.116479 -114.614709) (xy 458.170436 -114.628815) (xy 458.221765 -114.650627)
			(xy 458.269371 -114.679681) (xy 458.312239 -114.715356) (xy 458.349456 -114.756893) (xy 458.380229 -114.803406)
			(xy 458.403901 -114.853903) (xy 458.419969 -114.90731) (xy 458.428089 -114.962486) (xy 458.428598 -114.990372)
			(xy 458.428089 -115.018258) (xy 458.419969 -115.073434) (xy 458.403901 -115.126841) (xy 458.380229 -115.177338)
			(xy 458.349456 -115.223851) (xy 458.312239 -115.265388) (xy 458.269371 -115.301063) (xy 458.221765 -115.330117)
			(xy 458.170436 -115.351929) (xy 458.116479 -115.366035) (xy 458.061042 -115.372135) (xy 458.005308 -115.370098)
			(xy 457.950465 -115.359968) (xy 457.897681 -115.341961) (xy 457.848081 -115.31646) (xy 457.802723 -115.284009)
			(xy 457.762574 -115.2453) (xy 457.728488 -115.201157) (xy 457.701192 -115.152522) (xy 457.681269 -115.100431)
			(xy 457.669143 -115.045994) (xy 457.665072 -114.990372) (xy 457.043426 -114.990372) (xy 457.049377 -115.030812)
			(xy 457.049886 -115.058698) (xy 457.049377 -115.086584) (xy 457.041257 -115.14176) (xy 457.025189 -115.195167)
			(xy 457.001517 -115.245664) (xy 456.970744 -115.292177) (xy 456.933527 -115.333714) (xy 456.890659 -115.369389)
			(xy 456.843053 -115.398443) (xy 456.791724 -115.420255) (xy 456.737767 -115.434361) (xy 456.68233 -115.440461)
			(xy 456.626596 -115.438424) (xy 456.571753 -115.428294) (xy 456.518969 -115.410287) (xy 456.469369 -115.384786)
			(xy 456.424011 -115.352335) (xy 456.383862 -115.313626) (xy 456.349776 -115.269483) (xy 456.32248 -115.220848)
			(xy 456.302557 -115.168757) (xy 456.290431 -115.11432) (xy 456.28636 -115.058698) (xy 455.679933 -115.058698)
			(xy 455.674737 -115.094008) (xy 455.658669 -115.147415) (xy 455.634997 -115.197912) (xy 455.604224 -115.244425)
			(xy 455.567007 -115.285962) (xy 455.524139 -115.321637) (xy 455.476533 -115.350691) (xy 455.425204 -115.372503)
			(xy 455.371247 -115.386609) (xy 455.31581 -115.392709) (xy 455.260076 -115.390672) (xy 455.205233 -115.380542)
			(xy 455.152449 -115.362535) (xy 455.102849 -115.337034) (xy 455.057491 -115.304583) (xy 455.017342 -115.265874)
			(xy 454.983256 -115.221731) (xy 454.95596 -115.173096) (xy 454.936037 -115.121005) (xy 454.923911 -115.066568)
			(xy 454.91984 -115.010946) (xy 438.171718 -115.010946) (xy 438.217995 -115.030611) (xy 438.265601 -115.059665)
			(xy 438.308469 -115.09534) (xy 438.345686 -115.136877) (xy 438.376459 -115.18339) (xy 438.400131 -115.233887)
			(xy 438.416199 -115.287294) (xy 438.424319 -115.34247) (xy 438.424828 -115.370356) (xy 438.424319 -115.398242)
			(xy 438.416199 -115.453418) (xy 438.400131 -115.506825) (xy 438.376459 -115.557322) (xy 438.345686 -115.603835)
			(xy 438.308469 -115.645372) (xy 438.265601 -115.681047) (xy 438.217995 -115.710101) (xy 438.166666 -115.731913)
			(xy 438.112709 -115.746019) (xy 438.057272 -115.752119) (xy 438.001538 -115.750082) (xy 437.946695 -115.739952)
			(xy 437.893911 -115.721945) (xy 437.844311 -115.696444) (xy 437.798953 -115.663993) (xy 437.758804 -115.625284)
			(xy 437.724718 -115.581141) (xy 437.697422 -115.532506) (xy 437.677499 -115.480415) (xy 437.665373 -115.425978)
			(xy 437.661302 -115.370356) (xy 436.323357 -115.370356) (xy 436.323739 -115.37295) (xy 436.324248 -115.400836)
			(xy 436.323739 -115.428722) (xy 436.315619 -115.483898) (xy 436.299551 -115.537305) (xy 436.275879 -115.587802)
			(xy 436.245106 -115.634315) (xy 436.207889 -115.675852) (xy 436.165021 -115.711527) (xy 436.117415 -115.740581)
			(xy 436.066086 -115.762393) (xy 436.012129 -115.776499) (xy 435.956692 -115.782599) (xy 435.900958 -115.780562)
			(xy 435.846115 -115.770432) (xy 435.793331 -115.752425) (xy 435.743731 -115.726924) (xy 435.698373 -115.694473)
			(xy 435.658224 -115.655764) (xy 435.624138 -115.611621) (xy 435.596842 -115.562986) (xy 435.576919 -115.510895)
			(xy 435.564793 -115.456458) (xy 435.560722 -115.400836) (xy 423.814192 -115.400836) (xy 423.808255 -115.442157)
			(xy 423.792905 -115.494453) (xy 423.770269 -115.544031) (xy 423.740807 -115.589884) (xy 423.705119 -115.631077)
			(xy 423.663932 -115.666771) (xy 423.618084 -115.69624) (xy 423.568509 -115.718884) (xy 423.516216 -115.734242)
			(xy 423.462269 -115.742001) (xy 423.435018 -115.742466) (xy 423.407648 -115.741998) (xy 423.353468 -115.734182)
			(xy 423.300965 -115.718694) (xy 423.251218 -115.695852) (xy 423.205251 -115.666127) (xy 423.18432 -115.648486)
			(xy 423.184066 -115.648232) (xy 423.176971 -115.642659) (xy 423.16006 -115.636406) (xy 423.151046 -115.63604)
			(xy 423.08399 -115.63604) (xy 423.074972 -115.636383) (xy 423.058054 -115.642639) (xy 423.05097 -115.648232)
			(xy 423.05097 -115.648486) (xy 423.050716 -115.648486) (xy 423.029787 -115.666129) (xy 422.983814 -115.695841)
			(xy 422.934065 -115.718676) (xy 422.881564 -115.734166) (xy 422.827387 -115.741993) (xy 422.800018 -115.742466)
			(xy 422.772764 -115.742028) (xy 422.71881 -115.734272) (xy 422.666509 -115.718916) (xy 422.616926 -115.696273)
			(xy 422.571071 -115.666803) (xy 422.529877 -115.631106) (xy 422.494183 -115.58991) (xy 422.464716 -115.544053)
			(xy 422.442075 -115.494469) (xy 422.426723 -115.442167) (xy 422.41897 -115.388212) (xy 422.41851 -115.360958)
			(xy 415.986872 -115.360958) (xy 415.985713 -115.368836) (xy 415.969645 -115.422243) (xy 415.945973 -115.47274)
			(xy 415.9152 -115.519253) (xy 415.877983 -115.56079) (xy 415.835115 -115.596465) (xy 415.787509 -115.625519)
			(xy 415.73618 -115.647331) (xy 415.682223 -115.661437) (xy 415.626786 -115.667537) (xy 415.571052 -115.6655)
			(xy 415.516209 -115.65537) (xy 415.463425 -115.637363) (xy 415.413825 -115.611862) (xy 415.368467 -115.579411)
			(xy 415.328318 -115.540702) (xy 415.294232 -115.496559) (xy 415.266936 -115.447924) (xy 415.247013 -115.395833)
			(xy 415.234887 -115.341396) (xy 415.230816 -115.285774) (xy 389.40232 -115.285774) (xy 389.40232 -115.801394)
			(xy 404.147272 -115.801394) (xy 404.151343 -115.745772) (xy 404.163469 -115.691335) (xy 404.183392 -115.639244)
			(xy 404.210688 -115.590609) (xy 404.244774 -115.546466) (xy 404.284923 -115.507757) (xy 404.330281 -115.475306)
			(xy 404.379881 -115.449805) (xy 404.432665 -115.431798) (xy 404.487508 -115.421668) (xy 404.543242 -115.419631)
			(xy 404.598679 -115.425731) (xy 404.652636 -115.439837) (xy 404.703965 -115.461649) (xy 404.751571 -115.490703)
			(xy 404.794439 -115.526378) (xy 404.831656 -115.567915) (xy 404.862429 -115.614428) (xy 404.886101 -115.664925)
			(xy 404.902169 -115.718332) (xy 404.910289 -115.773508) (xy 404.910798 -115.801394) (xy 404.910289 -115.82928)
			(xy 404.902169 -115.884456) (xy 404.89086 -115.922044) (xy 411.503366 -115.922044) (xy 411.507437 -115.866422)
			(xy 411.519563 -115.811985) (xy 411.539486 -115.759894) (xy 411.566782 -115.711259) (xy 411.600868 -115.667116)
			(xy 411.641017 -115.628407) (xy 411.686375 -115.595956) (xy 411.735975 -115.570455) (xy 411.788759 -115.552448)
			(xy 411.843602 -115.542318) (xy 411.899336 -115.540281) (xy 411.954773 -115.546381) (xy 412.00873 -115.560487)
			(xy 412.060059 -115.582299) (xy 412.107665 -115.611353) (xy 412.150533 -115.647028) (xy 412.18775 -115.688565)
			(xy 412.218523 -115.735078) (xy 412.242195 -115.785575) (xy 412.256354 -115.832636) (xy 441.279278 -115.832636)
			(xy 441.283349 -115.777014) (xy 441.295475 -115.722577) (xy 441.315398 -115.670486) (xy 441.342694 -115.621851)
			(xy 441.37678 -115.577708) (xy 441.416929 -115.538999) (xy 441.462287 -115.506548) (xy 441.511887 -115.481047)
			(xy 441.564671 -115.46304) (xy 441.619514 -115.45291) (xy 441.675248 -115.450873) (xy 441.730685 -115.456973)
			(xy 441.784642 -115.471079) (xy 441.835971 -115.492891) (xy 441.883577 -115.521945) (xy 441.926445 -115.55762)
			(xy 441.963662 -115.599157) (xy 441.994435 -115.64567) (xy 442.018107 -115.696167) (xy 442.034175 -115.749574)
			(xy 442.042295 -115.80475) (xy 442.042804 -115.832636) (xy 442.042295 -115.860522) (xy 442.034175 -115.915698)
			(xy 442.018107 -115.969105) (xy 441.994435 -116.019602) (xy 441.963662 -116.066115) (xy 441.926445 -116.107652)
			(xy 441.883577 -116.143327) (xy 441.835971 -116.172381) (xy 441.784642 -116.194193) (xy 441.730685 -116.208299)
			(xy 441.675248 -116.214399) (xy 441.619514 -116.212362) (xy 441.564671 -116.202232) (xy 441.511887 -116.184225)
			(xy 441.462287 -116.158724) (xy 441.416929 -116.126273) (xy 441.37678 -116.087564) (xy 441.342694 -116.043421)
			(xy 441.315398 -115.994786) (xy 441.295475 -115.942695) (xy 441.283349 -115.888258) (xy 441.279278 -115.832636)
			(xy 412.256354 -115.832636) (xy 412.258263 -115.838982) (xy 412.266383 -115.894158) (xy 412.266892 -115.922044)
			(xy 412.266383 -115.94993) (xy 412.258263 -116.005106) (xy 412.242195 -116.058513) (xy 412.218523 -116.10901)
			(xy 412.18775 -116.155523) (xy 412.150533 -116.19706) (xy 412.107665 -116.232735) (xy 412.060059 -116.261789)
			(xy 412.00873 -116.283601) (xy 411.954773 -116.297707) (xy 411.899336 -116.303807) (xy 411.843602 -116.30177)
			(xy 411.788759 -116.29164) (xy 411.735975 -116.273633) (xy 411.686375 -116.248132) (xy 411.641017 -116.215681)
			(xy 411.600868 -116.176972) (xy 411.566782 -116.132829) (xy 411.539486 -116.084194) (xy 411.519563 -116.032103)
			(xy 411.507437 -115.977666) (xy 411.503366 -115.922044) (xy 404.89086 -115.922044) (xy 404.886101 -115.937863)
			(xy 404.862429 -115.98836) (xy 404.831656 -116.034873) (xy 404.794439 -116.07641) (xy 404.751571 -116.112085)
			(xy 404.703965 -116.141139) (xy 404.652636 -116.162951) (xy 404.598679 -116.177057) (xy 404.543242 -116.183157)
			(xy 404.487508 -116.18112) (xy 404.432665 -116.17099) (xy 404.379881 -116.152983) (xy 404.330281 -116.127482)
			(xy 404.284923 -116.095031) (xy 404.244774 -116.056322) (xy 404.210688 -116.012179) (xy 404.183392 -115.963544)
			(xy 404.163469 -115.911453) (xy 404.151343 -115.857016) (xy 404.147272 -115.801394) (xy 389.40232 -115.801394)
			(xy 389.40232 -116.44757) (xy 414.457132 -116.44757) (xy 414.461203 -116.391948) (xy 414.473329 -116.337511)
			(xy 414.493252 -116.28542) (xy 414.520548 -116.236785) (xy 414.554634 -116.192642) (xy 414.594783 -116.153933)
			(xy 414.640141 -116.121482) (xy 414.689741 -116.095981) (xy 414.742525 -116.077974) (xy 414.797368 -116.067844)
			(xy 414.853102 -116.065807) (xy 414.908539 -116.071907) (xy 414.962496 -116.086013) (xy 415.013825 -116.107825)
			(xy 415.061431 -116.136879) (xy 415.104299 -116.172554) (xy 415.141516 -116.214091) (xy 415.172289 -116.260604)
			(xy 415.195961 -116.311101) (xy 415.212029 -116.364508) (xy 415.220149 -116.419684) (xy 415.220658 -116.44757)
			(xy 415.220149 -116.475456) (xy 415.219879 -116.477288) (xy 419.604442 -116.477288) (xy 419.608513 -116.421666)
			(xy 419.620639 -116.367229) (xy 419.640562 -116.315138) (xy 419.667858 -116.266503) (xy 419.701944 -116.22236)
			(xy 419.742093 -116.183651) (xy 419.787451 -116.1512) (xy 419.837051 -116.125699) (xy 419.889835 -116.107692)
			(xy 419.944678 -116.097562) (xy 420.000412 -116.095525) (xy 420.055849 -116.101625) (xy 420.109806 -116.115731)
			(xy 420.161135 -116.137543) (xy 420.208741 -116.166597) (xy 420.251609 -116.202272) (xy 420.288826 -116.243809)
			(xy 420.319599 -116.290322) (xy 420.343271 -116.340819) (xy 420.359339 -116.394226) (xy 420.367459 -116.449402)
			(xy 420.367968 -116.477288) (xy 420.367459 -116.505174) (xy 420.359339 -116.56035) (xy 420.343271 -116.613757)
			(xy 420.319599 -116.664254) (xy 420.288826 -116.710767) (xy 420.251609 -116.752304) (xy 420.208741 -116.787979)
			(xy 420.161135 -116.817033) (xy 420.109806 -116.838845) (xy 420.055849 -116.852951) (xy 420.000412 -116.859051)
			(xy 419.944678 -116.857014) (xy 419.889835 -116.846884) (xy 419.837051 -116.828877) (xy 419.787451 -116.803376)
			(xy 419.742093 -116.770925) (xy 419.701944 -116.732216) (xy 419.667858 -116.688073) (xy 419.640562 -116.639438)
			(xy 419.620639 -116.587347) (xy 419.608513 -116.53291) (xy 419.604442 -116.477288) (xy 415.219879 -116.477288)
			(xy 415.212029 -116.530632) (xy 415.195961 -116.584039) (xy 415.172289 -116.634536) (xy 415.141516 -116.681049)
			(xy 415.104299 -116.722586) (xy 415.061431 -116.758261) (xy 415.013825 -116.787315) (xy 414.962496 -116.809127)
			(xy 414.908539 -116.823233) (xy 414.853102 -116.829333) (xy 414.797368 -116.827296) (xy 414.742525 -116.817166)
			(xy 414.689741 -116.799159) (xy 414.640141 -116.773658) (xy 414.594783 -116.741207) (xy 414.554634 -116.702498)
			(xy 414.520548 -116.658355) (xy 414.493252 -116.60972) (xy 414.473329 -116.557629) (xy 414.461203 -116.503192)
			(xy 414.457132 -116.44757) (xy 389.40232 -116.44757) (xy 389.40232 -117.723666) (xy 417.989764 -117.723666)
			(xy 417.993835 -117.668044) (xy 418.005961 -117.613607) (xy 418.025884 -117.561516) (xy 418.05318 -117.512881)
			(xy 418.087266 -117.468738) (xy 418.127415 -117.430029) (xy 418.172773 -117.397578) (xy 418.222373 -117.372077)
			(xy 418.275157 -117.35407) (xy 418.33 -117.34394) (xy 418.385734 -117.341903) (xy 418.441171 -117.348003)
			(xy 418.495128 -117.362109) (xy 418.546457 -117.383921) (xy 418.594063 -117.412975) (xy 418.636931 -117.44865)
			(xy 418.674148 -117.490187) (xy 418.704921 -117.5367) (xy 418.728593 -117.587197) (xy 418.744661 -117.640604)
			(xy 418.752781 -117.69578) (xy 418.75329 -117.723666) (xy 418.752781 -117.751552) (xy 418.751652 -117.759226)
			(xy 422.774872 -117.759226) (xy 422.774872 -116.895626) (xy 422.775362 -116.865642) (xy 422.78319 -116.806186)
			(xy 422.798711 -116.748261) (xy 422.82166 -116.692857) (xy 422.851644 -116.640923) (xy 422.88815 -116.593347)
			(xy 422.930555 -116.550942) (xy 422.978131 -116.514436) (xy 423.030065 -116.484452) (xy 423.085469 -116.461503)
			(xy 423.143394 -116.445982) (xy 423.20285 -116.438154) (xy 423.262818 -116.438154) (xy 423.322274 -116.445982)
			(xy 423.380199 -116.461503) (xy 423.435603 -116.484452) (xy 423.487537 -116.514436) (xy 423.535113 -116.550942)
			(xy 423.577518 -116.593347) (xy 423.614024 -116.640923) (xy 423.630708 -116.66982) (xy 437.67324 -116.66982)
			(xy 437.677311 -116.614198) (xy 437.689437 -116.559761) (xy 437.70936 -116.50767) (xy 437.736656 -116.459035)
			(xy 437.770742 -116.414892) (xy 437.810891 -116.376183) (xy 437.856249 -116.343732) (xy 437.905849 -116.318231)
			(xy 437.958633 -116.300224) (xy 438.013476 -116.290094) (xy 438.06921 -116.288057) (xy 438.124647 -116.294157)
			(xy 438.178604 -116.308263) (xy 438.229933 -116.330075) (xy 438.277539 -116.359129) (xy 438.320407 -116.394804)
			(xy 438.357624 -116.436341) (xy 438.388397 -116.482854) (xy 438.412069 -116.533351) (xy 438.428137 -116.586758)
			(xy 438.43438 -116.62918) (xy 453.438004 -116.62918) (xy 453.442075 -116.573558) (xy 453.454201 -116.519121)
			(xy 453.474124 -116.46703) (xy 453.50142 -116.418395) (xy 453.535506 -116.374252) (xy 453.575655 -116.335543)
			(xy 453.621013 -116.303092) (xy 453.670613 -116.277591) (xy 453.723397 -116.259584) (xy 453.77824 -116.249454)
			(xy 453.833974 -116.247417) (xy 453.889411 -116.253517) (xy 453.943368 -116.267623) (xy 453.994697 -116.289435)
			(xy 454.042303 -116.318489) (xy 454.085171 -116.354164) (xy 454.122388 -116.395701) (xy 454.153161 -116.442214)
			(xy 454.176833 -116.492711) (xy 454.192901 -116.546118) (xy 454.201021 -116.601294) (xy 454.20153 -116.62918)
			(xy 454.201021 -116.657066) (xy 454.192901 -116.712242) (xy 454.176833 -116.765649) (xy 454.153161 -116.816146)
			(xy 454.122388 -116.862659) (xy 454.085171 -116.904196) (xy 454.042303 -116.939871) (xy 453.994697 -116.968925)
			(xy 453.943368 -116.990737) (xy 453.889411 -117.004843) (xy 453.833974 -117.010943) (xy 453.77824 -117.008906)
			(xy 453.723397 -116.998776) (xy 453.670613 -116.980769) (xy 453.621013 -116.955268) (xy 453.575655 -116.922817)
			(xy 453.535506 -116.884108) (xy 453.50142 -116.839965) (xy 453.474124 -116.79133) (xy 453.454201 -116.739239)
			(xy 453.442075 -116.684802) (xy 453.438004 -116.62918) (xy 438.43438 -116.62918) (xy 438.436257 -116.641934)
			(xy 438.436766 -116.66982) (xy 438.436257 -116.697706) (xy 438.428137 -116.752882) (xy 438.412069 -116.806289)
			(xy 438.388397 -116.856786) (xy 438.357624 -116.903299) (xy 438.320407 -116.944836) (xy 438.277539 -116.980511)
			(xy 438.229933 -117.009565) (xy 438.178604 -117.031377) (xy 438.124647 -117.045483) (xy 438.06921 -117.051583)
			(xy 438.013476 -117.049546) (xy 437.958633 -117.039416) (xy 437.905849 -117.021409) (xy 437.856249 -116.995908)
			(xy 437.810891 -116.963457) (xy 437.770742 -116.924748) (xy 437.736656 -116.880605) (xy 437.70936 -116.83197)
			(xy 437.689437 -116.779879) (xy 437.677311 -116.725442) (xy 437.67324 -116.66982) (xy 423.630708 -116.66982)
			(xy 423.644008 -116.692857) (xy 423.666957 -116.748261) (xy 423.682478 -116.806186) (xy 423.690306 -116.865642)
			(xy 423.690796 -116.895626) (xy 423.690796 -117.390446) (xy 439.042618 -117.390446) (xy 439.042618 -117.335954)
			(xy 439.050373 -117.282015) (xy 439.065724 -117.22973) (xy 439.088359 -117.180161) (xy 439.117818 -117.134317)
			(xy 439.153501 -117.093133) (xy 439.194682 -117.057445) (xy 439.240522 -117.027981) (xy 439.290089 -117.005339)
			(xy 439.342372 -116.989982) (xy 439.39631 -116.982221) (xy 439.423556 -116.981732) (xy 439.452472 -116.98227)
			(xy 439.509643 -116.990993) (xy 439.564842 -117.008246) (xy 439.616804 -117.033634) (xy 439.664339 -117.066575)
			(xy 439.706356 -117.106314) (xy 439.724546 -117.128798) (xy 439.732143 -117.137616) (xy 439.753051 -117.147794)
			(xy 439.764678 -117.148356) (xy 439.844434 -117.148356) (xy 439.856069 -117.147838) (xy 439.876979 -117.137636)
			(xy 439.884566 -117.128798) (xy 439.902776 -117.10633) (xy 439.944792 -117.066594) (xy 439.992323 -117.033653)
			(xy 440.04428 -117.008262) (xy 440.099474 -116.991003) (xy 440.156641 -116.982269) (xy 440.185556 -116.981732)
			(xy 440.212814 -116.982112) (xy 440.266775 -116.989865) (xy 440.319084 -117.005218) (xy 440.368675 -117.027861)
			(xy 440.414538 -117.057331) (xy 440.455741 -117.093028) (xy 440.464067 -117.102636) (xy 441.279278 -117.102636)
			(xy 441.283349 -117.047014) (xy 441.295475 -116.992577) (xy 441.315398 -116.940486) (xy 441.342694 -116.891851)
			(xy 441.37678 -116.847708) (xy 441.416929 -116.808999) (xy 441.462287 -116.776548) (xy 441.511887 -116.751047)
			(xy 441.564671 -116.73304) (xy 441.619514 -116.72291) (xy 441.675248 -116.720873) (xy 441.730685 -116.726973)
			(xy 441.784642 -116.741079) (xy 441.835971 -116.762891) (xy 441.883577 -116.791945) (xy 441.926445 -116.82762)
			(xy 441.963662 -116.869157) (xy 441.994435 -116.91567) (xy 442.018107 -116.966167) (xy 442.034175 -117.019574)
			(xy 442.042295 -117.07475) (xy 442.042804 -117.102636) (xy 442.042295 -117.130522) (xy 442.034175 -117.185698)
			(xy 442.018107 -117.239105) (xy 442.013854 -117.248178) (xy 456.038964 -117.248178) (xy 456.043035 -117.192556)
			(xy 456.055161 -117.138119) (xy 456.075084 -117.086028) (xy 456.10238 -117.037393) (xy 456.136466 -116.99325)
			(xy 456.176615 -116.954541) (xy 456.221973 -116.92209) (xy 456.271573 -116.896589) (xy 456.324357 -116.878582)
			(xy 456.3792 -116.868452) (xy 456.434934 -116.866415) (xy 456.490371 -116.872515) (xy 456.544328 -116.886621)
			(xy 456.595657 -116.908433) (xy 456.643263 -116.937487) (xy 456.686131 -116.973162) (xy 456.723348 -117.014699)
			(xy 456.754121 -117.061212) (xy 456.777793 -117.111709) (xy 456.793861 -117.165116) (xy 456.801981 -117.220292)
			(xy 456.80249 -117.248178) (xy 456.801981 -117.276064) (xy 456.793861 -117.33124) (xy 456.777793 -117.384647)
			(xy 456.754121 -117.435144) (xy 456.723348 -117.481657) (xy 456.686131 -117.523194) (xy 456.643263 -117.558869)
			(xy 456.595657 -117.587923) (xy 456.544328 -117.609735) (xy 456.490371 -117.623841) (xy 456.434934 -117.629941)
			(xy 456.3792 -117.627904) (xy 456.324357 -117.617774) (xy 456.271573 -117.599767) (xy 456.221973 -117.574266)
			(xy 456.176615 -117.541815) (xy 456.136466 -117.503106) (xy 456.10238 -117.458963) (xy 456.075084 -117.410328)
			(xy 456.055161 -117.358237) (xy 456.043035 -117.3038) (xy 456.038964 -117.248178) (xy 442.013854 -117.248178)
			(xy 441.994435 -117.289602) (xy 441.963662 -117.336115) (xy 441.926445 -117.377652) (xy 441.883577 -117.413327)
			(xy 441.835971 -117.442381) (xy 441.784642 -117.464193) (xy 441.730685 -117.478299) (xy 441.675248 -117.484399)
			(xy 441.619514 -117.482362) (xy 441.564671 -117.472232) (xy 441.511887 -117.454225) (xy 441.462287 -117.428724)
			(xy 441.416929 -117.396273) (xy 441.37678 -117.357564) (xy 441.342694 -117.313421) (xy 441.315398 -117.264786)
			(xy 441.295475 -117.212695) (xy 441.283349 -117.158258) (xy 441.279278 -117.102636) (xy 440.464067 -117.102636)
			(xy 440.491443 -117.134226) (xy 440.520918 -117.180087) (xy 440.543566 -117.229675) (xy 440.558926 -117.281982)
			(xy 440.566685 -117.335942) (xy 440.566685 -117.390458) (xy 440.558926 -117.444418) (xy 440.543566 -117.496725)
			(xy 440.520918 -117.546313) (xy 440.491443 -117.592174) (xy 440.455741 -117.633372) (xy 440.414538 -117.669069)
			(xy 440.368675 -117.698539) (xy 440.319084 -117.721182) (xy 440.266775 -117.736535) (xy 440.212814 -117.744288)
			(xy 440.185556 -117.744748) (xy 440.15664 -117.744209) (xy 440.099468 -117.735487) (xy 440.044269 -117.718235)
			(xy 439.992307 -117.692847) (xy 439.944773 -117.659906) (xy 439.902756 -117.620167) (xy 439.884566 -117.597682)
			(xy 439.876967 -117.588866) (xy 439.85606 -117.578688) (xy 439.844434 -117.578124) (xy 439.764678 -117.578124)
			(xy 439.753045 -117.578656) (xy 439.732135 -117.588849) (xy 439.724546 -117.597682) (xy 439.706324 -117.62014)
			(xy 439.664312 -117.659877) (xy 439.616783 -117.69282) (xy 439.564828 -117.718213) (xy 439.509635 -117.735475)
			(xy 439.45247 -117.74421) (xy 439.423556 -117.744748) (xy 439.39631 -117.744179) (xy 439.342372 -117.736418)
			(xy 439.290089 -117.721061) (xy 439.240522 -117.698419) (xy 439.194682 -117.668955) (xy 439.153501 -117.633267)
			(xy 439.117818 -117.592083) (xy 439.088359 -117.546239) (xy 439.065724 -117.49667) (xy 439.050373 -117.444385)
			(xy 439.042618 -117.390446) (xy 423.690796 -117.390446) (xy 423.690796 -117.759226) (xy 423.690306 -117.78921)
			(xy 423.682478 -117.848666) (xy 423.666957 -117.906591) (xy 423.644008 -117.961995) (xy 423.614024 -118.013929)
			(xy 423.577518 -118.061505) (xy 423.535113 -118.10391) (xy 423.487537 -118.140416) (xy 423.435603 -118.1704)
			(xy 423.380199 -118.193349) (xy 423.322274 -118.20887) (xy 423.262818 -118.216698) (xy 423.20285 -118.216698)
			(xy 423.143394 -118.20887) (xy 423.085469 -118.193349) (xy 423.030065 -118.1704) (xy 422.978131 -118.140416)
			(xy 422.930555 -118.10391) (xy 422.88815 -118.061505) (xy 422.851644 -118.013929) (xy 422.82166 -117.961995)
			(xy 422.798711 -117.906591) (xy 422.78319 -117.848666) (xy 422.775362 -117.78921) (xy 422.774872 -117.759226)
			(xy 418.751652 -117.759226) (xy 418.744661 -117.806728) (xy 418.728593 -117.860135) (xy 418.704921 -117.910632)
			(xy 418.674148 -117.957145) (xy 418.636931 -117.998682) (xy 418.594063 -118.034357) (xy 418.546457 -118.063411)
			(xy 418.495128 -118.085223) (xy 418.441171 -118.099329) (xy 418.385734 -118.105429) (xy 418.33 -118.103392)
			(xy 418.275157 -118.093262) (xy 418.222373 -118.075255) (xy 418.172773 -118.049754) (xy 418.127415 -118.017303)
			(xy 418.087266 -117.978594) (xy 418.05318 -117.934451) (xy 418.025884 -117.885816) (xy 418.005961 -117.833725)
			(xy 417.993835 -117.779288) (xy 417.989764 -117.723666) (xy 389.40232 -117.723666) (xy 389.40232 -118.194328)
			(xy 403.844504 -118.194328) (xy 403.848575 -118.138706) (xy 403.860701 -118.084269) (xy 403.880624 -118.032178)
			(xy 403.90792 -117.983543) (xy 403.942006 -117.9394) (xy 403.982155 -117.900691) (xy 404.027513 -117.86824)
			(xy 404.077113 -117.842739) (xy 404.129897 -117.824732) (xy 404.18474 -117.814602) (xy 404.240474 -117.812565)
			(xy 404.295911 -117.818665) (xy 404.349868 -117.832771) (xy 404.401197 -117.854583) (xy 404.448803 -117.883637)
			(xy 404.491671 -117.919312) (xy 404.528888 -117.960849) (xy 404.559661 -118.007362) (xy 404.583333 -118.057859)
			(xy 404.599401 -118.111266) (xy 404.607521 -118.166442) (xy 404.60803 -118.194328) (xy 404.607521 -118.222214)
			(xy 404.599401 -118.27739) (xy 404.583333 -118.330797) (xy 404.582771 -118.331996) (xy 411.195772 -118.331996)
			(xy 411.199843 -118.276374) (xy 411.211969 -118.221937) (xy 411.231892 -118.169846) (xy 411.259188 -118.121211)
			(xy 411.293274 -118.077068) (xy 411.333423 -118.038359) (xy 411.378781 -118.005908) (xy 411.428381 -117.980407)
			(xy 411.481165 -117.9624) (xy 411.536008 -117.95227) (xy 411.591742 -117.950233) (xy 411.647179 -117.956333)
			(xy 411.701136 -117.970439) (xy 411.752465 -117.992251) (xy 411.800071 -118.021305) (xy 411.842939 -118.05698)
			(xy 411.880156 -118.098517) (xy 411.910929 -118.14503) (xy 411.934601 -118.195527) (xy 411.950669 -118.248934)
			(xy 411.958789 -118.30411) (xy 411.959298 -118.331996) (xy 411.958789 -118.359882) (xy 411.950669 -118.415058)
			(xy 411.934601 -118.468465) (xy 411.910929 -118.518962) (xy 411.880156 -118.565475) (xy 411.842939 -118.607012)
			(xy 411.800071 -118.642687) (xy 411.752465 -118.671741) (xy 411.701136 -118.693553) (xy 411.647179 -118.707659)
			(xy 411.591742 -118.713759) (xy 411.536008 -118.711722) (xy 411.481165 -118.701592) (xy 411.428381 -118.683585)
			(xy 411.378781 -118.658084) (xy 411.333423 -118.625633) (xy 411.293274 -118.586924) (xy 411.259188 -118.542781)
			(xy 411.231892 -118.494146) (xy 411.211969 -118.442055) (xy 411.199843 -118.387618) (xy 411.195772 -118.331996)
			(xy 404.582771 -118.331996) (xy 404.559661 -118.381294) (xy 404.528888 -118.427807) (xy 404.491671 -118.469344)
			(xy 404.448803 -118.505019) (xy 404.401197 -118.534073) (xy 404.349868 -118.555885) (xy 404.295911 -118.569991)
			(xy 404.240474 -118.576091) (xy 404.18474 -118.574054) (xy 404.129897 -118.563924) (xy 404.077113 -118.545917)
			(xy 404.027513 -118.520416) (xy 403.982155 -118.487965) (xy 403.942006 -118.449256) (xy 403.90792 -118.405113)
			(xy 403.880624 -118.356478) (xy 403.860701 -118.304387) (xy 403.848575 -118.24995) (xy 403.844504 -118.194328)
			(xy 389.40232 -118.194328) (xy 389.40232 -120.086374) (xy 401.939252 -120.086374) (xy 401.939252 -119.222774)
			(xy 401.939742 -119.192806) (xy 401.947565 -119.133384) (xy 401.963078 -119.075491) (xy 401.986014 -119.020118)
			(xy 402.015981 -118.968212) (xy 402.052468 -118.920662) (xy 402.094848 -118.878282) (xy 402.142398 -118.841795)
			(xy 402.194304 -118.811828) (xy 402.249677 -118.788892) (xy 402.30757 -118.773379) (xy 402.366992 -118.765556)
			(xy 402.426928 -118.765556) (xy 402.48635 -118.773379) (xy 402.544243 -118.788892) (xy 402.599616 -118.811828)
			(xy 402.651522 -118.841795) (xy 402.699072 -118.878282) (xy 402.741452 -118.920662) (xy 402.777939 -118.968212)
			(xy 402.807906 -119.020118) (xy 402.830842 -119.075491) (xy 402.846355 -119.133384) (xy 402.854178 -119.192806)
			(xy 402.854668 -119.222774) (xy 402.854668 -119.567198) (xy 414.899348 -119.567198) (xy 414.899348 -118.703598)
			(xy 414.899838 -118.673614) (xy 414.907666 -118.614158) (xy 414.923187 -118.556233) (xy 414.946136 -118.500829)
			(xy 414.97612 -118.448895) (xy 415.012626 -118.401319) (xy 415.055031 -118.358914) (xy 415.102607 -118.322408)
			(xy 415.154541 -118.292424) (xy 415.209945 -118.269475) (xy 415.26787 -118.253954) (xy 415.327326 -118.246126)
			(xy 415.387294 -118.246126) (xy 415.44675 -118.253954) (xy 415.504675 -118.269475) (xy 415.560079 -118.292424)
			(xy 415.612013 -118.322408) (xy 415.659589 -118.358914) (xy 415.701994 -118.401319) (xy 415.7385 -118.448895)
			(xy 415.768484 -118.500829) (xy 415.791433 -118.556233) (xy 415.806954 -118.614158) (xy 415.814782 -118.673614)
			(xy 415.815272 -118.703598) (xy 415.815272 -119.567198) (xy 415.814782 -119.597182) (xy 415.806954 -119.656638)
			(xy 415.791433 -119.714563) (xy 415.768484 -119.769967) (xy 415.7385 -119.821901) (xy 415.701994 -119.869477)
			(xy 415.659589 -119.911882) (xy 415.612013 -119.948388) (xy 415.560079 -119.978372) (xy 415.504675 -120.001321)
			(xy 415.44675 -120.016842) (xy 415.387294 -120.02467) (xy 415.327326 -120.02467) (xy 415.26787 -120.016842)
			(xy 415.209945 -120.001321) (xy 415.154541 -119.978372) (xy 415.102607 -119.948388) (xy 415.055031 -119.911882)
			(xy 415.012626 -119.869477) (xy 414.97612 -119.821901) (xy 414.946136 -119.769967) (xy 414.923187 -119.714563)
			(xy 414.907666 -119.656638) (xy 414.899838 -119.597182) (xy 414.899348 -119.567198) (xy 402.854668 -119.567198)
			(xy 402.854668 -120.086374) (xy 402.854178 -120.116342) (xy 402.846355 -120.175764) (xy 402.830842 -120.233657)
			(xy 402.807906 -120.28903) (xy 402.777939 -120.340936) (xy 402.741452 -120.388486) (xy 402.699072 -120.430866)
			(xy 402.651522 -120.467353) (xy 402.599616 -120.49732) (xy 402.544243 -120.520256) (xy 402.48635 -120.535769)
			(xy 402.426928 -120.543592) (xy 402.366992 -120.543592) (xy 402.30757 -120.535769) (xy 402.249677 -120.520256)
			(xy 402.194304 -120.49732) (xy 402.142398 -120.467353) (xy 402.094848 -120.430866) (xy 402.052468 -120.388486)
			(xy 402.015981 -120.340936) (xy 401.986014 -120.28903) (xy 401.963078 -120.233657) (xy 401.947565 -120.175764)
			(xy 401.939742 -120.116342) (xy 401.939252 -120.086374) (xy 389.40232 -120.086374) (xy 389.40232 -121.886472)
			(xy 400.085052 -121.886472) (xy 400.085052 -121.022872) (xy 400.085542 -120.992904) (xy 400.093365 -120.933482)
			(xy 400.108878 -120.875589) (xy 400.131814 -120.820216) (xy 400.161781 -120.76831) (xy 400.198268 -120.72076)
			(xy 400.240648 -120.67838) (xy 400.288198 -120.641893) (xy 400.340104 -120.611926) (xy 400.395477 -120.58899)
			(xy 400.45337 -120.573477) (xy 400.512792 -120.565654) (xy 400.572728 -120.565654) (xy 400.63215 -120.573477)
			(xy 400.690043 -120.58899) (xy 400.745416 -120.611926) (xy 400.797322 -120.641893) (xy 400.844872 -120.67838)
			(xy 400.887252 -120.72076) (xy 400.923739 -120.76831) (xy 400.953706 -120.820216) (xy 400.976642 -120.875589)
			(xy 400.992155 -120.933482) (xy 400.999978 -120.992904) (xy 401.000468 -121.022872) (xy 401.000468 -121.367296)
			(xy 413.045148 -121.367296) (xy 413.045148 -120.503696) (xy 413.045638 -120.473712) (xy 413.053466 -120.414256)
			(xy 413.068987 -120.356331) (xy 413.091936 -120.300927) (xy 413.12192 -120.248993) (xy 413.158426 -120.201417)
			(xy 413.200831 -120.159012) (xy 413.248407 -120.122506) (xy 413.300341 -120.092522) (xy 413.355745 -120.069573)
			(xy 413.41367 -120.054052) (xy 413.473126 -120.046224) (xy 413.533094 -120.046224) (xy 413.59255 -120.054052)
			(xy 413.650475 -120.069573) (xy 413.705879 -120.092522) (xy 413.757813 -120.122506) (xy 413.805389 -120.159012)
			(xy 413.847794 -120.201417) (xy 413.8843 -120.248993) (xy 413.914284 -120.300927) (xy 413.937233 -120.356331)
			(xy 413.952754 -120.414256) (xy 413.960582 -120.473712) (xy 413.961072 -120.503696) (xy 413.961072 -121.367296)
			(xy 413.960582 -121.39728) (xy 413.952754 -121.456736) (xy 413.937233 -121.514661) (xy 413.914284 -121.570065)
			(xy 413.8843 -121.621999) (xy 413.847794 -121.669575) (xy 413.805389 -121.71198) (xy 413.757813 -121.748486)
			(xy 413.705879 -121.77847) (xy 413.650475 -121.801419) (xy 413.59255 -121.81694) (xy 413.533094 -121.824768)
			(xy 413.473126 -121.824768) (xy 413.41367 -121.81694) (xy 413.355745 -121.801419) (xy 413.300341 -121.77847)
			(xy 413.248407 -121.748486) (xy 413.200831 -121.71198) (xy 413.158426 -121.669575) (xy 413.12192 -121.621999)
			(xy 413.091936 -121.570065) (xy 413.068987 -121.514661) (xy 413.053466 -121.456736) (xy 413.045638 -121.39728)
			(xy 413.045148 -121.367296) (xy 401.000468 -121.367296) (xy 401.000468 -121.886472) (xy 400.999978 -121.91644)
			(xy 400.992155 -121.975862) (xy 400.976642 -122.033755) (xy 400.953706 -122.089128) (xy 400.923739 -122.141034)
			(xy 400.887252 -122.188584) (xy 400.844872 -122.230964) (xy 400.797322 -122.267451) (xy 400.745416 -122.297418)
			(xy 400.690043 -122.320354) (xy 400.63215 -122.335867) (xy 400.572728 -122.34369) (xy 400.512792 -122.34369)
			(xy 400.45337 -122.335867) (xy 400.395477 -122.320354) (xy 400.340104 -122.297418) (xy 400.288198 -122.267451)
			(xy 400.240648 -122.230964) (xy 400.198268 -122.188584) (xy 400.161781 -122.141034) (xy 400.131814 -122.089128)
			(xy 400.108878 -122.033755) (xy 400.093365 -121.975862) (xy 400.085542 -121.91644) (xy 400.085052 -121.886472)
			(xy 389.40232 -121.886472) (xy 389.40232 -123.686316) (xy 401.939252 -123.686316) (xy 401.939252 -122.822716)
			(xy 401.939742 -122.792748) (xy 401.947565 -122.733326) (xy 401.963078 -122.675433) (xy 401.986014 -122.62006)
			(xy 402.015981 -122.568154) (xy 402.052468 -122.520604) (xy 402.094848 -122.478224) (xy 402.142398 -122.441737)
			(xy 402.194304 -122.41177) (xy 402.249677 -122.388834) (xy 402.30757 -122.373321) (xy 402.366992 -122.365498)
			(xy 402.426928 -122.365498) (xy 402.48635 -122.373321) (xy 402.544243 -122.388834) (xy 402.599616 -122.41177)
			(xy 402.651522 -122.441737) (xy 402.699072 -122.478224) (xy 402.741452 -122.520604) (xy 402.777939 -122.568154)
			(xy 402.807906 -122.62006) (xy 402.830842 -122.675433) (xy 402.846355 -122.733326) (xy 402.854178 -122.792748)
			(xy 402.854668 -122.822716) (xy 402.854668 -123.16714) (xy 414.899348 -123.16714) (xy 414.899348 -122.30354)
			(xy 414.899838 -122.273556) (xy 414.907666 -122.2141) (xy 414.923187 -122.156175) (xy 414.946136 -122.100771)
			(xy 414.97612 -122.048837) (xy 415.012626 -122.001261) (xy 415.055031 -121.958856) (xy 415.102607 -121.92235)
			(xy 415.154541 -121.892366) (xy 415.209945 -121.869417) (xy 415.26787 -121.853896) (xy 415.327326 -121.846068)
			(xy 415.387294 -121.846068) (xy 415.44675 -121.853896) (xy 415.504675 -121.869417) (xy 415.560079 -121.892366)
			(xy 415.612013 -121.92235) (xy 415.659589 -121.958856) (xy 415.701994 -122.001261) (xy 415.7385 -122.048837)
			(xy 415.768484 -122.100771) (xy 415.791433 -122.156175) (xy 415.806954 -122.2141) (xy 415.814782 -122.273556)
			(xy 415.815272 -122.30354) (xy 415.815272 -123.16714) (xy 415.814782 -123.197124) (xy 415.806954 -123.25658)
			(xy 415.791433 -123.314505) (xy 415.768484 -123.369909) (xy 415.7385 -123.421843) (xy 415.701994 -123.469419)
			(xy 415.659589 -123.511824) (xy 415.612013 -123.54833) (xy 415.560079 -123.578314) (xy 415.504675 -123.601263)
			(xy 415.44675 -123.616784) (xy 415.387294 -123.624612) (xy 415.327326 -123.624612) (xy 415.26787 -123.616784)
			(xy 415.209945 -123.601263) (xy 415.154541 -123.578314) (xy 415.102607 -123.54833) (xy 415.055031 -123.511824)
			(xy 415.012626 -123.469419) (xy 414.97612 -123.421843) (xy 414.946136 -123.369909) (xy 414.923187 -123.314505)
			(xy 414.907666 -123.25658) (xy 414.899838 -123.197124) (xy 414.899348 -123.16714) (xy 402.854668 -123.16714)
			(xy 402.854668 -123.686316) (xy 402.854178 -123.716284) (xy 402.846355 -123.775706) (xy 402.830842 -123.833599)
			(xy 402.807906 -123.888972) (xy 402.777939 -123.940878) (xy 402.741452 -123.988428) (xy 402.699072 -124.030808)
			(xy 402.651522 -124.067295) (xy 402.599616 -124.097262) (xy 402.544243 -124.120198) (xy 402.48635 -124.135711)
			(xy 402.426928 -124.143534) (xy 402.366992 -124.143534) (xy 402.30757 -124.135711) (xy 402.249677 -124.120198)
			(xy 402.194304 -124.097262) (xy 402.142398 -124.067295) (xy 402.094848 -124.030808) (xy 402.052468 -123.988428)
			(xy 402.015981 -123.940878) (xy 401.986014 -123.888972) (xy 401.963078 -123.833599) (xy 401.947565 -123.775706)
			(xy 401.939742 -123.716284) (xy 401.939252 -123.686316) (xy 389.40232 -123.686316) (xy 389.40232 -125.486414)
			(xy 400.085052 -125.486414) (xy 400.085052 -124.622814) (xy 400.085542 -124.592846) (xy 400.093365 -124.533424)
			(xy 400.108878 -124.475531) (xy 400.131814 -124.420158) (xy 400.161781 -124.368252) (xy 400.198268 -124.320702)
			(xy 400.240648 -124.278322) (xy 400.288198 -124.241835) (xy 400.340104 -124.211868) (xy 400.395477 -124.188932)
			(xy 400.45337 -124.173419) (xy 400.512792 -124.165596) (xy 400.572728 -124.165596) (xy 400.63215 -124.173419)
			(xy 400.690043 -124.188932) (xy 400.745416 -124.211868) (xy 400.797322 -124.241835) (xy 400.844872 -124.278322)
			(xy 400.887252 -124.320702) (xy 400.923739 -124.368252) (xy 400.953706 -124.420158) (xy 400.976642 -124.475531)
			(xy 400.992155 -124.533424) (xy 400.999978 -124.592846) (xy 401.000468 -124.622814) (xy 401.000468 -124.967238)
			(xy 413.045148 -124.967238) (xy 413.045148 -124.103638) (xy 413.045638 -124.073654) (xy 413.053466 -124.014198)
			(xy 413.068987 -123.956273) (xy 413.091936 -123.900869) (xy 413.12192 -123.848935) (xy 413.158426 -123.801359)
			(xy 413.200831 -123.758954) (xy 413.248407 -123.722448) (xy 413.300341 -123.692464) (xy 413.355745 -123.669515)
			(xy 413.41367 -123.653994) (xy 413.473126 -123.646166) (xy 413.533094 -123.646166) (xy 413.59255 -123.653994)
			(xy 413.650475 -123.669515) (xy 413.705879 -123.692464) (xy 413.757813 -123.722448) (xy 413.805389 -123.758954)
			(xy 413.847794 -123.801359) (xy 413.8843 -123.848935) (xy 413.914284 -123.900869) (xy 413.937233 -123.956273)
			(xy 413.952754 -124.014198) (xy 413.960582 -124.073654) (xy 413.961072 -124.103638) (xy 413.961072 -124.967238)
			(xy 413.960582 -124.997222) (xy 413.952754 -125.056678) (xy 413.937233 -125.114603) (xy 413.914284 -125.170007)
			(xy 413.8843 -125.221941) (xy 413.847794 -125.269517) (xy 413.805389 -125.311922) (xy 413.757813 -125.348428)
			(xy 413.705879 -125.378412) (xy 413.650475 -125.401361) (xy 413.59255 -125.416882) (xy 413.533094 -125.42471)
			(xy 413.473126 -125.42471) (xy 413.41367 -125.416882) (xy 413.355745 -125.401361) (xy 413.300341 -125.378412)
			(xy 413.248407 -125.348428) (xy 413.200831 -125.311922) (xy 413.158426 -125.269517) (xy 413.12192 -125.221941)
			(xy 413.091936 -125.170007) (xy 413.068987 -125.114603) (xy 413.053466 -125.056678) (xy 413.045638 -124.997222)
			(xy 413.045148 -124.967238) (xy 401.000468 -124.967238) (xy 401.000468 -125.486414) (xy 400.999978 -125.516382)
			(xy 400.992155 -125.575804) (xy 400.976642 -125.633697) (xy 400.953706 -125.68907) (xy 400.923739 -125.740976)
			(xy 400.887252 -125.788526) (xy 400.844872 -125.830906) (xy 400.797322 -125.867393) (xy 400.745416 -125.89736)
			(xy 400.690043 -125.920296) (xy 400.63215 -125.935809) (xy 400.572728 -125.943632) (xy 400.512792 -125.943632)
			(xy 400.45337 -125.935809) (xy 400.395477 -125.920296) (xy 400.340104 -125.89736) (xy 400.288198 -125.867393)
			(xy 400.240648 -125.830906) (xy 400.198268 -125.788526) (xy 400.161781 -125.740976) (xy 400.131814 -125.68907)
			(xy 400.108878 -125.633697) (xy 400.093365 -125.575804) (xy 400.085542 -125.516382) (xy 400.085052 -125.486414)
			(xy 389.40232 -125.486414) (xy 389.40232 -125.560074) (xy 389.402574 -125.5649) (xy 389.402574 -125.565154)
			(xy 389.403536 -125.571879) (xy 389.408566 -125.584492) (xy 389.41248 -125.590046) (xy 389.417052 -125.59538)
			(xy 389.951214 -126.129542) (xy 389.957558 -126.135432) (xy 389.973138 -126.142952) (xy 389.981694 -126.144274)
			(xy 389.984488 -126.144528) (xy 393.473178 -126.144528) (xy 393.478004 -126.144274) (xy 393.478258 -126.144274)
			(xy 393.484987 -126.143323) (xy 393.497613 -126.138307) (xy 393.50315 -126.134368) (xy 393.508484 -126.129796)
			(xy 393.88669 -125.75159) (xy 393.894084 -125.744732) (xy 393.912683 -125.73698) (xy 393.922758 -125.736604)
			(xy 394.118592 -125.736604) (xy 394.125704 -125.736096) (xy 394.222986 -125.638814) (xy 394.241765 -125.620697)
			(xy 394.28396 -125.590004) (xy 394.33044 -125.566295) (xy 394.380059 -125.550156) (xy 394.431593 -125.541984)
			(xy 394.457682 -125.541532) (xy 396.188184 -125.541532) (xy 396.214272 -125.542017) (xy 396.265805 -125.550181)
			(xy 396.315425 -125.566311) (xy 396.361908 -125.590009) (xy 396.404109 -125.620691) (xy 396.42288 -125.638814)
			(xy 397.00708 -126.223014) (xy 397.014479 -126.229857) (xy 397.033078 -126.237576) (xy 397.043148 -126.238)
			(xy 416.272472 -126.238) (xy 416.282536 -126.237564) (xy 416.301122 -126.229831) (xy 416.30854 -126.223014)
			(xy 418.144706 -124.387102) (xy 418.151552 -124.379703) (xy 418.159286 -124.361105) (xy 418.159692 -124.351034)
			(xy 418.159692 -118.900448) (xy 418.157914 -118.897146) (xy 418.146492 -118.875798) (xy 418.128532 -118.830836)
			(xy 418.116399 -118.783964) (xy 418.110289 -118.735934) (xy 418.109908 -118.711726) (xy 418.109908 -118.711218)
			(xy 418.11037 -118.683965) (xy 418.118125 -118.630013) (xy 418.13348 -118.577714) (xy 418.156121 -118.528132)
			(xy 418.185589 -118.482278) (xy 418.221283 -118.441085) (xy 418.262476 -118.40539) (xy 418.30833 -118.375922)
			(xy 418.357912 -118.35328) (xy 418.410211 -118.337926) (xy 418.464163 -118.33017) (xy 418.491416 -118.32971)
			(xy 418.518516 -118.330187) (xy 418.57217 -118.33786) (xy 418.624199 -118.353051) (xy 418.673553 -118.375452)
			(xy 418.71924 -118.404613) (xy 418.760339 -118.439947) (xy 418.796024 -118.480743) (xy 418.825576 -118.526178)
			(xy 418.848399 -118.575339) (xy 418.864034 -118.627235) (xy 418.872167 -118.680821) (xy 418.872924 -118.707916)
			(xy 418.872924 -118.712234) (xy 418.87227 -118.742896) (xy 418.862379 -118.803418) (xy 418.842936 -118.861579)
			(xy 418.829236 -118.889018) (xy 418.82441 -118.897654) (xy 418.82314 -118.900194) (xy 418.82314 -119.559324)
			(xy 429.3743 -119.559324) (xy 429.3743 -118.695724) (xy 429.37479 -118.66574) (xy 429.382618 -118.606284)
			(xy 429.398139 -118.548359) (xy 429.421088 -118.492955) (xy 429.451072 -118.441021) (xy 429.487578 -118.393445)
			(xy 429.529983 -118.35104) (xy 429.577559 -118.314534) (xy 429.629493 -118.28455) (xy 429.684897 -118.261601)
			(xy 429.742822 -118.24608) (xy 429.802278 -118.238252) (xy 429.862246 -118.238252) (xy 429.921702 -118.24608)
			(xy 429.979627 -118.261601) (xy 430.035031 -118.28455) (xy 430.086965 -118.314534) (xy 430.134541 -118.35104)
			(xy 430.176946 -118.393445) (xy 430.213452 -118.441021) (xy 430.228962 -118.467886) (xy 445.782444 -118.467886)
			(xy 445.786515 -118.412264) (xy 445.798641 -118.357827) (xy 445.818564 -118.305736) (xy 445.84586 -118.257101)
			(xy 445.879946 -118.212958) (xy 445.920095 -118.174249) (xy 445.965453 -118.141798) (xy 446.015053 -118.116297)
			(xy 446.067837 -118.09829) (xy 446.12268 -118.08816) (xy 446.178414 -118.086123) (xy 446.233851 -118.092223)
			(xy 446.287808 -118.106329) (xy 446.339137 -118.128141) (xy 446.386743 -118.157195) (xy 446.429611 -118.19287)
			(xy 446.466828 -118.234407) (xy 446.497601 -118.28092) (xy 446.521273 -118.331417) (xy 446.537341 -118.384824)
			(xy 446.545461 -118.44) (xy 446.54597 -118.467886) (xy 446.545461 -118.495772) (xy 446.537341 -118.550948)
			(xy 446.521273 -118.604355) (xy 446.497601 -118.654852) (xy 446.466828 -118.701365) (xy 446.429611 -118.742902)
			(xy 446.408777 -118.76024) (xy 448.838826 -118.76024) (xy 448.842897 -118.704618) (xy 448.855023 -118.650181)
			(xy 448.874946 -118.59809) (xy 448.902242 -118.549455) (xy 448.936328 -118.505312) (xy 448.976477 -118.466603)
			(xy 449.021835 -118.434152) (xy 449.071435 -118.408651) (xy 449.124219 -118.390644) (xy 449.179062 -118.380514)
			(xy 449.234796 -118.378477) (xy 449.290233 -118.384577) (xy 449.34419 -118.398683) (xy 449.395519 -118.420495)
			(xy 449.443125 -118.449549) (xy 449.485993 -118.485224) (xy 449.52321 -118.526761) (xy 449.553983 -118.573274)
			(xy 449.577655 -118.623771) (xy 449.593723 -118.677178) (xy 449.601843 -118.732354) (xy 449.602352 -118.76024)
			(xy 450.864476 -118.76024) (xy 450.868547 -118.704618) (xy 450.880673 -118.650181) (xy 450.900596 -118.59809)
			(xy 450.927892 -118.549455) (xy 450.961978 -118.505312) (xy 451.002127 -118.466603) (xy 451.047485 -118.434152)
			(xy 451.097085 -118.408651) (xy 451.149869 -118.390644) (xy 451.204712 -118.380514) (xy 451.260446 -118.378477)
			(xy 451.315883 -118.384577) (xy 451.36984 -118.398683) (xy 451.421169 -118.420495) (xy 451.468775 -118.449549)
			(xy 451.511643 -118.485224) (xy 451.54886 -118.526761) (xy 451.579633 -118.573274) (xy 451.603305 -118.623771)
			(xy 451.619373 -118.677178) (xy 451.627493 -118.732354) (xy 451.628002 -118.76024) (xy 451.627493 -118.788126)
			(xy 451.619373 -118.843302) (xy 451.603305 -118.896709) (xy 451.579633 -118.947206) (xy 451.54886 -118.993719)
			(xy 451.511643 -119.035256) (xy 451.468775 -119.070931) (xy 451.421169 -119.099985) (xy 451.36984 -119.121797)
			(xy 451.315883 -119.135903) (xy 451.260446 -119.142003) (xy 451.204712 -119.139966) (xy 451.149869 -119.129836)
			(xy 451.097085 -119.111829) (xy 451.047485 -119.086328) (xy 451.002127 -119.053877) (xy 450.961978 -119.015168)
			(xy 450.927892 -118.971025) (xy 450.900596 -118.92239) (xy 450.880673 -118.870299) (xy 450.868547 -118.815862)
			(xy 450.864476 -118.76024) (xy 449.602352 -118.76024) (xy 449.601843 -118.788126) (xy 449.593723 -118.843302)
			(xy 449.577655 -118.896709) (xy 449.553983 -118.947206) (xy 449.52321 -118.993719) (xy 449.485993 -119.035256)
			(xy 449.443125 -119.070931) (xy 449.395519 -119.099985) (xy 449.34419 -119.121797) (xy 449.290233 -119.135903)
			(xy 449.234796 -119.142003) (xy 449.179062 -119.139966) (xy 449.124219 -119.129836) (xy 449.071435 -119.111829)
			(xy 449.021835 -119.086328) (xy 448.976477 -119.053877) (xy 448.936328 -119.015168) (xy 448.902242 -118.971025)
			(xy 448.874946 -118.92239) (xy 448.855023 -118.870299) (xy 448.842897 -118.815862) (xy 448.838826 -118.76024)
			(xy 446.408777 -118.76024) (xy 446.386743 -118.778577) (xy 446.339137 -118.807631) (xy 446.287808 -118.829443)
			(xy 446.233851 -118.843549) (xy 446.178414 -118.849649) (xy 446.12268 -118.847612) (xy 446.067837 -118.837482)
			(xy 446.015053 -118.819475) (xy 445.965453 -118.793974) (xy 445.920095 -118.761523) (xy 445.879946 -118.722814)
			(xy 445.84586 -118.678671) (xy 445.818564 -118.630036) (xy 445.798641 -118.577945) (xy 445.786515 -118.523508)
			(xy 445.782444 -118.467886) (xy 430.228962 -118.467886) (xy 430.243436 -118.492955) (xy 430.266385 -118.548359)
			(xy 430.281906 -118.606284) (xy 430.289734 -118.66574) (xy 430.290224 -118.695724) (xy 430.290224 -119.407557)
			(xy 442.799609 -119.407557) (xy 442.799609 -119.353043) (xy 442.807368 -119.299083) (xy 442.822727 -119.246777)
			(xy 442.845374 -119.197189) (xy 442.874848 -119.151329) (xy 442.910548 -119.110131) (xy 442.951749 -119.074433)
			(xy 442.99761 -119.044962) (xy 443.0472 -119.022318) (xy 443.099507 -119.006962) (xy 443.153467 -118.999207)
			(xy 443.180724 -118.998746) (xy 443.208095 -118.999187) (xy 443.262276 -119.007009) (xy 443.31478 -119.022503)
			(xy 443.364526 -119.045351) (xy 443.410492 -119.075082) (xy 443.431422 -119.092726) (xy 443.431676 -119.09298)
			(xy 443.438758 -119.098572) (xy 443.455679 -119.104813) (xy 443.464696 -119.105172) (xy 443.531752 -119.105172)
			(xy 443.540767 -119.104798) (xy 443.557685 -119.098563) (xy 443.564772 -119.09298) (xy 443.564772 -119.092726)
			(xy 443.565026 -119.092726) (xy 443.585979 -119.075112) (xy 443.631945 -119.045396) (xy 443.681688 -119.022554)
			(xy 443.734184 -119.007058) (xy 443.788356 -118.999223) (xy 443.815724 -118.998746) (xy 443.842971 -118.999326)
			(xy 443.896909 -119.007084) (xy 443.949195 -119.022439) (xy 443.998763 -119.045079) (xy 444.044605 -119.074543)
			(xy 444.085787 -119.11023) (xy 444.121472 -119.151414) (xy 444.150932 -119.197258) (xy 444.173569 -119.246828)
			(xy 444.188921 -119.299114) (xy 444.196676 -119.353053) (xy 444.196676 -119.407547) (xy 444.188921 -119.461486)
			(xy 444.184358 -119.477028) (xy 447.903344 -119.477028) (xy 447.907415 -119.421406) (xy 447.919541 -119.366969)
			(xy 447.939464 -119.314878) (xy 447.96676 -119.266243) (xy 448.000846 -119.2221) (xy 448.040995 -119.183391)
			(xy 448.086353 -119.15094) (xy 448.135953 -119.125439) (xy 448.188737 -119.107432) (xy 448.24358 -119.097302)
			(xy 448.299314 -119.095265) (xy 448.354751 -119.101365) (xy 448.408708 -119.115471) (xy 448.460037 -119.137283)
			(xy 448.507643 -119.166337) (xy 448.550511 -119.202012) (xy 448.587728 -119.243549) (xy 448.618501 -119.290062)
			(xy 448.642173 -119.340559) (xy 448.658241 -119.393966) (xy 448.666361 -119.449142) (xy 448.66687 -119.477028)
			(xy 448.666361 -119.504914) (xy 448.658241 -119.56009) (xy 448.642173 -119.613497) (xy 448.618501 -119.663994)
			(xy 448.587728 -119.710507) (xy 448.580265 -119.718836) (xy 455.836526 -119.718836) (xy 455.840597 -119.663214)
			(xy 455.852723 -119.608777) (xy 455.872646 -119.556686) (xy 455.899942 -119.508051) (xy 455.934028 -119.463908)
			(xy 455.974177 -119.425199) (xy 456.019535 -119.392748) (xy 456.069135 -119.367247) (xy 456.121919 -119.34924)
			(xy 456.176762 -119.33911) (xy 456.232496 -119.337073) (xy 456.287933 -119.343173) (xy 456.34189 -119.357279)
			(xy 456.393219 -119.379091) (xy 456.440825 -119.408145) (xy 456.483693 -119.44382) (xy 456.52091 -119.485357)
			(xy 456.551683 -119.53187) (xy 456.575355 -119.582367) (xy 456.591423 -119.635774) (xy 456.599543 -119.69095)
			(xy 456.600052 -119.718836) (xy 456.599543 -119.746722) (xy 456.591423 -119.801898) (xy 456.575355 -119.855305)
			(xy 456.551683 -119.905802) (xy 456.52091 -119.952315) (xy 456.483693 -119.993852) (xy 456.440825 -120.029527)
			(xy 456.393219 -120.058581) (xy 456.34189 -120.080393) (xy 456.287933 -120.094499) (xy 456.232496 -120.100599)
			(xy 456.176762 -120.098562) (xy 456.121919 -120.088432) (xy 456.069135 -120.070425) (xy 456.019535 -120.044924)
			(xy 455.974177 -120.012473) (xy 455.934028 -119.973764) (xy 455.899942 -119.929621) (xy 455.872646 -119.880986)
			(xy 455.852723 -119.828895) (xy 455.840597 -119.774458) (xy 455.836526 -119.718836) (xy 448.580265 -119.718836)
			(xy 448.550511 -119.752044) (xy 448.507643 -119.787719) (xy 448.460037 -119.816773) (xy 448.408708 -119.838585)
			(xy 448.354751 -119.852691) (xy 448.299314 -119.858791) (xy 448.24358 -119.856754) (xy 448.188737 -119.846624)
			(xy 448.135953 -119.828617) (xy 448.086353 -119.803116) (xy 448.040995 -119.770665) (xy 448.000846 -119.731956)
			(xy 447.96676 -119.687813) (xy 447.939464 -119.639178) (xy 447.919541 -119.587087) (xy 447.907415 -119.53265)
			(xy 447.903344 -119.477028) (xy 444.184358 -119.477028) (xy 444.173569 -119.513772) (xy 444.150932 -119.563342)
			(xy 444.121472 -119.609186) (xy 444.085787 -119.65037) (xy 444.044605 -119.686057) (xy 443.998763 -119.715521)
			(xy 443.949195 -119.738161) (xy 443.896909 -119.753516) (xy 443.842971 -119.761274) (xy 443.815724 -119.761762)
			(xy 443.788354 -119.761291) (xy 443.734175 -119.753476) (xy 443.681671 -119.737988) (xy 443.631924 -119.715148)
			(xy 443.585957 -119.685423) (xy 443.565026 -119.667782) (xy 443.564772 -119.667528) (xy 443.557675 -119.661957)
			(xy 443.540766 -119.655703) (xy 443.531752 -119.655336) (xy 443.464696 -119.655336) (xy 443.455678 -119.655683)
			(xy 443.438761 -119.661937) (xy 443.431676 -119.667528) (xy 443.431676 -119.667782) (xy 443.431422 -119.667782)
			(xy 443.41049 -119.685421) (xy 443.364518 -119.715134) (xy 443.31477 -119.73797) (xy 443.262269 -119.753461)
			(xy 443.208093 -119.761288) (xy 443.180724 -119.761762) (xy 443.153467 -119.761393) (xy 443.099507 -119.753638)
			(xy 443.0472 -119.738282) (xy 442.99761 -119.715638) (xy 442.951749 -119.686167) (xy 442.910548 -119.650469)
			(xy 442.874848 -119.609271) (xy 442.845374 -119.563411) (xy 442.822727 -119.513823) (xy 442.807368 -119.461517)
			(xy 442.799609 -119.407557) (xy 430.290224 -119.407557) (xy 430.290224 -119.559324) (xy 430.289734 -119.589308)
			(xy 430.281906 -119.648764) (xy 430.266385 -119.706689) (xy 430.243436 -119.762093) (xy 430.213452 -119.814027)
			(xy 430.176946 -119.861603) (xy 430.145469 -119.89308) (xy 445.869058 -119.89308) (xy 445.873129 -119.837458)
			(xy 445.885255 -119.783021) (xy 445.905178 -119.73093) (xy 445.932474 -119.682295) (xy 445.96656 -119.638152)
			(xy 446.006709 -119.599443) (xy 446.052067 -119.566992) (xy 446.101667 -119.541491) (xy 446.154451 -119.523484)
			(xy 446.209294 -119.513354) (xy 446.265028 -119.511317) (xy 446.320465 -119.517417) (xy 446.374422 -119.531523)
			(xy 446.425751 -119.553335) (xy 446.473357 -119.582389) (xy 446.516225 -119.618064) (xy 446.553442 -119.659601)
			(xy 446.584215 -119.706114) (xy 446.607887 -119.756611) (xy 446.623955 -119.810018) (xy 446.632075 -119.865194)
			(xy 446.632584 -119.89308) (xy 446.632075 -119.920966) (xy 446.623955 -119.976142) (xy 446.607887 -120.029549)
			(xy 446.584215 -120.080046) (xy 446.553442 -120.126559) (xy 446.516225 -120.168096) (xy 446.473357 -120.203771)
			(xy 446.425751 -120.232825) (xy 446.374422 -120.254637) (xy 446.320465 -120.268743) (xy 446.265028 -120.274843)
			(xy 446.209294 -120.272806) (xy 446.154451 -120.262676) (xy 446.101667 -120.244669) (xy 446.052067 -120.219168)
			(xy 446.006709 -120.186717) (xy 445.96656 -120.148008) (xy 445.932474 -120.103865) (xy 445.905178 -120.05523)
			(xy 445.885255 -120.003139) (xy 445.873129 -119.948702) (xy 445.869058 -119.89308) (xy 430.145469 -119.89308)
			(xy 430.134541 -119.904008) (xy 430.086965 -119.940514) (xy 430.035031 -119.970498) (xy 429.979627 -119.993447)
			(xy 429.921702 -120.008968) (xy 429.862246 -120.016796) (xy 429.802278 -120.016796) (xy 429.742822 -120.008968)
			(xy 429.684897 -119.993447) (xy 429.629493 -119.970498) (xy 429.577559 -119.940514) (xy 429.529983 -119.904008)
			(xy 429.487578 -119.861603) (xy 429.451072 -119.814027) (xy 429.421088 -119.762093) (xy 429.398139 -119.706689)
			(xy 429.382618 -119.648764) (xy 429.37479 -119.589308) (xy 429.3743 -119.559324) (xy 418.82314 -119.559324)
			(xy 418.82314 -121.365772) (xy 432.016408 -121.365772) (xy 432.016408 -120.502172) (xy 432.016898 -120.472188)
			(xy 432.024726 -120.412732) (xy 432.040247 -120.354807) (xy 432.063196 -120.299403) (xy 432.09318 -120.247469)
			(xy 432.129686 -120.199893) (xy 432.172091 -120.157488) (xy 432.219667 -120.120982) (xy 432.271601 -120.090998)
			(xy 432.327005 -120.068049) (xy 432.38493 -120.052528) (xy 432.444386 -120.0447) (xy 432.504354 -120.0447)
			(xy 432.56381 -120.052528) (xy 432.621735 -120.068049) (xy 432.677139 -120.090998) (xy 432.729073 -120.120982)
			(xy 432.776649 -120.157488) (xy 432.819054 -120.199893) (xy 432.85556 -120.247469) (xy 432.885544 -120.299403)
			(xy 432.908493 -120.354807) (xy 432.924014 -120.412732) (xy 432.931842 -120.472188) (xy 432.932332 -120.502172)
			(xy 432.932332 -121.365772) (xy 432.931842 -121.395756) (xy 432.924014 -121.455212) (xy 432.908493 -121.513137)
			(xy 432.885544 -121.568541) (xy 432.85556 -121.620475) (xy 432.819054 -121.668051) (xy 432.776649 -121.710456)
			(xy 432.729073 -121.746962) (xy 432.677139 -121.776946) (xy 432.621735 -121.799895) (xy 432.56381 -121.815416)
			(xy 432.504354 -121.823244) (xy 432.444386 -121.823244) (xy 432.38493 -121.815416) (xy 432.327005 -121.799895)
			(xy 432.271601 -121.776946) (xy 432.219667 -121.746962) (xy 432.172091 -121.710456) (xy 432.129686 -121.668051)
			(xy 432.09318 -121.620475) (xy 432.063196 -121.568541) (xy 432.040247 -121.513137) (xy 432.024726 -121.455212)
			(xy 432.016898 -121.395756) (xy 432.016408 -121.365772) (xy 418.82314 -121.365772) (xy 418.82314 -123.159266)
			(xy 429.3743 -123.159266) (xy 429.3743 -122.295666) (xy 429.37479 -122.265682) (xy 429.382618 -122.206226)
			(xy 429.398139 -122.148301) (xy 429.421088 -122.092897) (xy 429.451072 -122.040963) (xy 429.487578 -121.993387)
			(xy 429.529983 -121.950982) (xy 429.577559 -121.914476) (xy 429.629493 -121.884492) (xy 429.684897 -121.861543)
			(xy 429.742822 -121.846022) (xy 429.802278 -121.838194) (xy 429.862246 -121.838194) (xy 429.921702 -121.846022)
			(xy 429.979627 -121.861543) (xy 430.035031 -121.884492) (xy 430.086965 -121.914476) (xy 430.134541 -121.950982)
			(xy 430.176946 -121.993387) (xy 430.213452 -122.040963) (xy 430.243436 -122.092897) (xy 430.266385 -122.148301)
			(xy 430.278103 -122.192034) (xy 437.750712 -122.192034) (xy 437.751195 -122.164664) (xy 437.759008 -122.110486)
			(xy 437.774493 -122.057983) (xy 437.797331 -122.008236) (xy 437.827052 -121.962268) (xy 437.844692 -121.941336)
			(xy 437.844946 -121.941082) (xy 437.850552 -121.934009) (xy 437.856786 -121.917082) (xy 437.857138 -121.908062)
			(xy 437.857138 -121.841006) (xy 437.85677 -121.83199) (xy 437.850529 -121.815074) (xy 437.844946 -121.807986)
			(xy 437.844692 -121.807986) (xy 437.844692 -121.807732) (xy 437.827086 -121.786772) (xy 437.797363 -121.740808)
			(xy 437.774517 -121.691066) (xy 437.75902 -121.638568) (xy 437.751189 -121.584394) (xy 437.751185 -121.529657)
			(xy 437.759009 -121.475482) (xy 437.774499 -121.422982) (xy 437.797338 -121.373237) (xy 437.827055 -121.327269)
			(xy 437.844692 -121.306336) (xy 437.844946 -121.306082) (xy 437.850552 -121.299009) (xy 437.856786 -121.282082)
			(xy 437.857138 -121.273062) (xy 437.857138 -121.206006) (xy 437.85677 -121.19699) (xy 437.850529 -121.180074)
			(xy 437.844946 -121.172986) (xy 437.844692 -121.172986) (xy 437.844692 -121.172732) (xy 437.827086 -121.151772)
			(xy 437.797363 -121.105808) (xy 437.774517 -121.056066) (xy 437.75902 -121.003568) (xy 437.751189 -120.949394)
			(xy 437.751185 -120.894657) (xy 437.759009 -120.840482) (xy 437.774499 -120.787982) (xy 437.797338 -120.738237)
			(xy 437.827055 -120.692269) (xy 437.844692 -120.671336) (xy 437.844946 -120.671082) (xy 437.850552 -120.664009)
			(xy 437.856786 -120.647082) (xy 437.857138 -120.638062) (xy 437.857138 -120.571006) (xy 437.85677 -120.56199)
			(xy 437.850529 -120.545074) (xy 437.844946 -120.537986) (xy 437.844692 -120.537986) (xy 437.844692 -120.537732)
			(xy 437.827053 -120.5168) (xy 437.797342 -120.470827) (xy 437.774506 -120.421079) (xy 437.759015 -120.368579)
			(xy 437.751186 -120.314403) (xy 437.750712 -120.287034) (xy 437.751198 -120.259783) (xy 437.758954 -120.205835)
			(xy 437.774309 -120.15354) (xy 437.796951 -120.103963) (xy 437.826417 -120.058113) (xy 437.862108 -120.016922)
			(xy 437.903299 -119.981231) (xy 437.949149 -119.951765) (xy 437.998726 -119.929123) (xy 438.051021 -119.913768)
			(xy 438.104969 -119.906012) (xy 438.159471 -119.906012) (xy 438.213419 -119.913768) (xy 438.265714 -119.929123)
			(xy 438.315291 -119.951765) (xy 438.361141 -119.981231) (xy 438.402332 -120.016922) (xy 438.438023 -120.058113)
			(xy 438.467489 -120.103963) (xy 438.490131 -120.15354) (xy 438.505486 -120.205835) (xy 438.513242 -120.259783)
			(xy 438.513728 -120.287034) (xy 438.513299 -120.314406) (xy 438.505475 -120.368587) (xy 438.489978 -120.421091)
			(xy 438.467128 -120.470838) (xy 438.452773 -120.493028) (xy 447.904106 -120.493028) (xy 447.908177 -120.437406)
			(xy 447.920303 -120.382969) (xy 447.940226 -120.330878) (xy 447.967522 -120.282243) (xy 448.001608 -120.2381)
			(xy 448.041757 -120.199391) (xy 448.087115 -120.16694) (xy 448.136715 -120.141439) (xy 448.189499 -120.123432)
			(xy 448.244342 -120.113302) (xy 448.300076 -120.111265) (xy 448.355513 -120.117365) (xy 448.40947 -120.131471)
			(xy 448.460799 -120.153283) (xy 448.508405 -120.182337) (xy 448.551273 -120.218012) (xy 448.58849 -120.259549)
			(xy 448.619263 -120.306062) (xy 448.642935 -120.356559) (xy 448.659003 -120.409966) (xy 448.667123 -120.465142)
			(xy 448.667632 -120.493028) (xy 448.667123 -120.520914) (xy 448.659003 -120.57609) (xy 448.642935 -120.629497)
			(xy 448.619263 -120.679994) (xy 448.58849 -120.726507) (xy 448.551273 -120.768044) (xy 448.522198 -120.79224)
			(xy 448.836032 -120.79224) (xy 448.840103 -120.736618) (xy 448.852229 -120.682181) (xy 448.872152 -120.63009)
			(xy 448.899448 -120.581455) (xy 448.933534 -120.537312) (xy 448.973683 -120.498603) (xy 449.019041 -120.466152)
			(xy 449.068641 -120.440651) (xy 449.121425 -120.422644) (xy 449.176268 -120.412514) (xy 449.232002 -120.410477)
			(xy 449.287439 -120.416577) (xy 449.341396 -120.430683) (xy 449.392725 -120.452495) (xy 449.440331 -120.481549)
			(xy 449.483199 -120.517224) (xy 449.520416 -120.558761) (xy 449.551189 -120.605274) (xy 449.574861 -120.655771)
			(xy 449.590929 -120.709178) (xy 449.599049 -120.764354) (xy 449.599558 -120.79224) (xy 450.991476 -120.79224)
			(xy 450.995547 -120.736618) (xy 451.007673 -120.682181) (xy 451.027596 -120.63009) (xy 451.054892 -120.581455)
			(xy 451.088978 -120.537312) (xy 451.129127 -120.498603) (xy 451.174485 -120.466152) (xy 451.224085 -120.440651)
			(xy 451.276869 -120.422644) (xy 451.331712 -120.412514) (xy 451.387446 -120.410477) (xy 451.442883 -120.416577)
			(xy 451.49684 -120.430683) (xy 451.548169 -120.452495) (xy 451.595775 -120.481549) (xy 451.638643 -120.517224)
			(xy 451.646777 -120.526302) (xy 454.293476 -120.526302) (xy 454.297547 -120.47068) (xy 454.309673 -120.416243)
			(xy 454.329596 -120.364152) (xy 454.356892 -120.315517) (xy 454.390978 -120.271374) (xy 454.431127 -120.232665)
			(xy 454.476485 -120.200214) (xy 454.526085 -120.174713) (xy 454.578869 -120.156706) (xy 454.633712 -120.146576)
			(xy 454.689446 -120.144539) (xy 454.744883 -120.150639) (xy 454.79884 -120.164745) (xy 454.850169 -120.186557)
			(xy 454.897775 -120.215611) (xy 454.940643 -120.251286) (xy 454.97786 -120.292823) (xy 455.008633 -120.339336)
			(xy 455.032305 -120.389833) (xy 455.048373 -120.44324) (xy 455.056493 -120.498416) (xy 455.057002 -120.526302)
			(xy 455.056493 -120.554188) (xy 455.048373 -120.609364) (xy 455.032305 -120.662771) (xy 455.008633 -120.713268)
			(xy 454.97786 -120.759781) (xy 454.940643 -120.801318) (xy 454.897775 -120.836993) (xy 454.850169 -120.866047)
			(xy 454.79884 -120.887859) (xy 454.744883 -120.901965) (xy 454.689446 -120.908065) (xy 454.633712 -120.906028)
			(xy 454.578869 -120.895898) (xy 454.526085 -120.877891) (xy 454.476485 -120.85239) (xy 454.431127 -120.819939)
			(xy 454.390978 -120.78123) (xy 454.356892 -120.737087) (xy 454.329596 -120.688452) (xy 454.309673 -120.636361)
			(xy 454.297547 -120.581924) (xy 454.293476 -120.526302) (xy 451.646777 -120.526302) (xy 451.67586 -120.558761)
			(xy 451.706633 -120.605274) (xy 451.730305 -120.655771) (xy 451.746373 -120.709178) (xy 451.754493 -120.764354)
			(xy 451.755002 -120.79224) (xy 451.754493 -120.820126) (xy 451.746373 -120.875302) (xy 451.730305 -120.928709)
			(xy 451.706633 -120.979206) (xy 451.67586 -121.025719) (xy 451.638643 -121.067256) (xy 451.595775 -121.102931)
			(xy 451.548169 -121.131985) (xy 451.49684 -121.153797) (xy 451.442883 -121.167903) (xy 451.387446 -121.174003)
			(xy 451.331712 -121.171966) (xy 451.276869 -121.161836) (xy 451.224085 -121.143829) (xy 451.174485 -121.118328)
			(xy 451.129127 -121.085877) (xy 451.088978 -121.047168) (xy 451.054892 -121.003025) (xy 451.027596 -120.95439)
			(xy 451.007673 -120.902299) (xy 450.995547 -120.847862) (xy 450.991476 -120.79224) (xy 449.599558 -120.79224)
			(xy 449.599049 -120.820126) (xy 449.590929 -120.875302) (xy 449.574861 -120.928709) (xy 449.551189 -120.979206)
			(xy 449.520416 -121.025719) (xy 449.483199 -121.067256) (xy 449.440331 -121.102931) (xy 449.392725 -121.131985)
			(xy 449.341396 -121.153797) (xy 449.287439 -121.167903) (xy 449.232002 -121.174003) (xy 449.176268 -121.171966)
			(xy 449.121425 -121.161836) (xy 449.068641 -121.143829) (xy 449.019041 -121.118328) (xy 448.973683 -121.085877)
			(xy 448.933534 -121.047168) (xy 448.899448 -121.003025) (xy 448.872152 -120.95439) (xy 448.852229 -120.902299)
			(xy 448.840103 -120.847862) (xy 448.836032 -120.79224) (xy 448.522198 -120.79224) (xy 448.508405 -120.803719)
			(xy 448.460799 -120.832773) (xy 448.40947 -120.854585) (xy 448.355513 -120.868691) (xy 448.300076 -120.874791)
			(xy 448.244342 -120.872754) (xy 448.189499 -120.862624) (xy 448.136715 -120.844617) (xy 448.087115 -120.819116)
			(xy 448.041757 -120.786665) (xy 448.001608 -120.747956) (xy 447.967522 -120.703813) (xy 447.940226 -120.655178)
			(xy 447.920303 -120.603087) (xy 447.908177 -120.54865) (xy 447.904106 -120.493028) (xy 438.452773 -120.493028)
			(xy 438.437394 -120.516802) (xy 438.419748 -120.537732) (xy 438.419494 -120.537986) (xy 438.413906 -120.545072)
			(xy 438.407661 -120.561989) (xy 438.407302 -120.571006) (xy 438.407302 -120.638062) (xy 438.407677 -120.647077)
			(xy 438.413912 -120.663994) (xy 438.419494 -120.671082) (xy 438.419748 -120.671082) (xy 438.419748 -120.671336)
			(xy 438.437423 -120.692241) (xy 438.467148 -120.738213) (xy 438.489993 -120.787964) (xy 438.505488 -120.84047)
			(xy 438.513314 -120.894653) (xy 438.51331 -120.949398) (xy 438.505477 -121.00358) (xy 438.489975 -121.056084)
			(xy 438.467124 -121.105832) (xy 438.437392 -121.1518) (xy 438.419748 -121.172732) (xy 438.419494 -121.172986)
			(xy 438.413906 -121.180072) (xy 438.407661 -121.196989) (xy 438.407591 -121.198756) (xy 438.785417 -121.198756)
			(xy 438.785417 -121.144244) (xy 438.793175 -121.090287) (xy 438.808533 -121.037983) (xy 438.831178 -120.988398)
			(xy 438.86065 -120.942539) (xy 438.896348 -120.901342) (xy 438.937546 -120.865645) (xy 438.983405 -120.836174)
			(xy 439.032991 -120.81353) (xy 439.085295 -120.798173) (xy 439.139252 -120.790416) (xy 439.166508 -120.789954)
			(xy 439.193879 -120.790402) (xy 439.248059 -120.798222) (xy 439.300563 -120.813715) (xy 439.35031 -120.836561)
			(xy 439.396275 -120.86629) (xy 439.417206 -120.883934) (xy 439.41746 -120.884188) (xy 439.424555 -120.889763)
			(xy 439.441465 -120.896017) (xy 439.45048 -120.89638) (xy 439.517536 -120.89638) (xy 439.526555 -120.896044)
			(xy 439.543472 -120.889782) (xy 439.550556 -120.884188) (xy 439.550556 -120.883934) (xy 439.55081 -120.883934)
			(xy 439.571732 -120.866282) (xy 439.617707 -120.836571) (xy 439.667457 -120.813737) (xy 439.71996 -120.798249)
			(xy 439.774138 -120.790425) (xy 439.801508 -120.789954) (xy 439.828756 -120.790517) (xy 439.882698 -120.798273)
			(xy 439.934986 -120.813628) (xy 439.984557 -120.836267) (xy 440.030402 -120.865731) (xy 440.071587 -120.901418)
			(xy 440.107274 -120.942604) (xy 440.136737 -120.98845) (xy 440.159375 -121.038021) (xy 440.174728 -121.09031)
			(xy 440.182484 -121.144252) (xy 440.182484 -121.198748) (xy 440.174728 -121.25269) (xy 440.159375 -121.304979)
			(xy 440.136737 -121.35455) (xy 440.107274 -121.400396) (xy 440.071587 -121.441582) (xy 440.030402 -121.477269)
			(xy 439.984557 -121.506733) (xy 439.934986 -121.529372) (xy 439.882698 -121.544727) (xy 439.828756 -121.552483)
			(xy 439.801508 -121.55297) (xy 439.774138 -121.552507) (xy 439.719958 -121.544689) (xy 439.667455 -121.5292)
			(xy 439.617708 -121.506357) (xy 439.571741 -121.476632) (xy 439.55081 -121.45899) (xy 439.550556 -121.458736)
			(xy 439.543463 -121.453159) (xy 439.526551 -121.446908) (xy 439.517536 -121.446544) (xy 439.45048 -121.446544)
			(xy 439.441461 -121.446882) (xy 439.424544 -121.453142) (xy 439.41746 -121.458736) (xy 439.41746 -121.45899)
			(xy 439.417206 -121.45899) (xy 439.396281 -121.476638) (xy 439.350307 -121.506349) (xy 439.300557 -121.529183)
			(xy 439.248055 -121.544672) (xy 439.193878 -121.552498) (xy 439.166508 -121.55297) (xy 439.139252 -121.552584)
			(xy 439.085295 -121.544827) (xy 439.032991 -121.52947) (xy 438.983405 -121.506826) (xy 438.937546 -121.477355)
			(xy 438.896348 -121.441658) (xy 438.86065 -121.400461) (xy 438.831178 -121.354602) (xy 438.808533 -121.305017)
			(xy 438.793175 -121.252713) (xy 438.785417 -121.198756) (xy 438.407591 -121.198756) (xy 438.407302 -121.206006)
			(xy 438.407302 -121.273062) (xy 438.407677 -121.282077) (xy 438.413912 -121.298994) (xy 438.419494 -121.306082)
			(xy 438.419748 -121.306082) (xy 438.419748 -121.306336) (xy 438.437423 -121.327241) (xy 438.467148 -121.373213)
			(xy 438.489993 -121.422964) (xy 438.505488 -121.47547) (xy 438.513314 -121.529653) (xy 438.51331 -121.584398)
			(xy 438.505477 -121.63858) (xy 438.489975 -121.691084) (xy 438.476179 -121.721118) (xy 440.2963 -121.721118)
			(xy 440.296777 -121.693748) (xy 440.304592 -121.63957) (xy 440.320079 -121.587067) (xy 440.342918 -121.537319)
			(xy 440.37264 -121.491352) (xy 440.39028 -121.47042) (xy 440.390534 -121.470166) (xy 440.396103 -121.463067)
			(xy 440.402359 -121.44616) (xy 440.402726 -121.437146) (xy 440.402726 -121.37009) (xy 440.402368 -121.361073)
			(xy 440.39612 -121.344157) (xy 440.390534 -121.33707) (xy 440.39028 -121.33707) (xy 440.39028 -121.336816)
			(xy 440.372632 -121.315891) (xy 440.342922 -121.269916) (xy 440.320088 -121.220167) (xy 440.304599 -121.167665)
			(xy 440.296773 -121.113488) (xy 440.2963 -121.086118) (xy 440.296772 -121.058865) (xy 440.304527 -121.004914)
			(xy 440.319881 -120.952616) (xy 440.342522 -120.903035) (xy 440.371989 -120.857182) (xy 440.407682 -120.815989)
			(xy 440.448874 -120.780295) (xy 440.494727 -120.750827) (xy 440.544307 -120.728184) (xy 440.596604 -120.712829)
			(xy 440.650555 -120.705073) (xy 440.677808 -120.70461) (xy 440.704687 -120.705028) (xy 440.757911 -120.712581)
			(xy 440.809546 -120.727536) (xy 440.858568 -120.749596) (xy 440.904005 -120.778325) (xy 440.944956 -120.813151)
			(xy 440.980608 -120.853384) (xy 440.995816 -120.875552) (xy 441.001846 -120.883889) (xy 441.019046 -120.895152)
			(xy 441.02909 -120.897396) (xy 441.111386 -120.912636) (xy 441.131452 -120.908064) (xy 441.139834 -120.901968)
			(xy 441.164289 -120.885159) (xy 441.217296 -120.858489) (xy 441.273792 -120.840343) (xy 441.332415 -120.831158)
			(xy 441.362084 -120.830594) (xy 441.389337 -120.83107) (xy 441.443287 -120.838825) (xy 441.495585 -120.854179)
			(xy 441.545165 -120.87682) (xy 441.591018 -120.906286) (xy 441.632211 -120.941979) (xy 441.667905 -120.98317)
			(xy 441.697373 -121.029023) (xy 441.720016 -121.078602) (xy 441.735372 -121.130899) (xy 441.743129 -121.184849)
			(xy 441.743592 -121.212102) (xy 441.743141 -121.238772) (xy 445.884298 -121.238772) (xy 445.888369 -121.18315)
			(xy 445.900495 -121.128713) (xy 445.920418 -121.076622) (xy 445.947714 -121.027987) (xy 445.9818 -120.983844)
			(xy 446.021949 -120.945135) (xy 446.067307 -120.912684) (xy 446.116907 -120.887183) (xy 446.169691 -120.869176)
			(xy 446.224534 -120.859046) (xy 446.280268 -120.857009) (xy 446.335705 -120.863109) (xy 446.389662 -120.877215)
			(xy 446.440991 -120.899027) (xy 446.488597 -120.928081) (xy 446.531465 -120.963756) (xy 446.568682 -121.005293)
			(xy 446.599455 -121.051806) (xy 446.623127 -121.102303) (xy 446.639195 -121.15571) (xy 446.647315 -121.210886)
			(xy 446.647824 -121.238772) (xy 446.647315 -121.266658) (xy 446.639195 -121.321834) (xy 446.623127 -121.375241)
			(xy 446.599455 -121.425738) (xy 446.568682 -121.472251) (xy 446.531465 -121.513788) (xy 446.488597 -121.549463)
			(xy 446.440991 -121.578517) (xy 446.389662 -121.600329) (xy 446.335705 -121.614435) (xy 446.280268 -121.620535)
			(xy 446.224534 -121.618498) (xy 446.169691 -121.608368) (xy 446.116907 -121.590361) (xy 446.067307 -121.56486)
			(xy 446.021949 -121.532409) (xy 445.9818 -121.4937) (xy 445.947714 -121.449557) (xy 445.920418 -121.400922)
			(xy 445.900495 -121.348831) (xy 445.888369 -121.294394) (xy 445.884298 -121.238772) (xy 441.743141 -121.238772)
			(xy 441.743129 -121.239472) (xy 441.735311 -121.293652) (xy 441.719821 -121.346155) (xy 441.696979 -121.395902)
			(xy 441.667253 -121.441868) (xy 441.649612 -121.4628) (xy 441.649358 -121.463054) (xy 441.643779 -121.470146)
			(xy 441.637529 -121.487059) (xy 441.637166 -121.496074) (xy 441.637166 -121.56313) (xy 441.637516 -121.572147)
			(xy 441.643769 -121.589064) (xy 441.649358 -121.59615) (xy 441.649612 -121.59615) (xy 441.649612 -121.596404)
			(xy 441.667268 -121.617322) (xy 441.696977 -121.663299) (xy 441.71981 -121.71305) (xy 441.735297 -121.765554)
			(xy 441.74312 -121.819732) (xy 441.743592 -121.847102) (xy 441.743146 -121.874356) (xy 441.735389 -121.928308)
			(xy 441.720032 -121.980607) (xy 441.697388 -122.030188) (xy 441.667918 -122.076042) (xy 441.632223 -122.117235)
			(xy 441.591028 -122.152929) (xy 441.545173 -122.182396) (xy 441.49559 -122.205038) (xy 441.44329 -122.220393)
			(xy 441.389338 -122.228148) (xy 441.362084 -122.22861) (xy 441.335206 -122.228189) (xy 441.281982 -122.220635)
			(xy 441.230347 -122.20568) (xy 441.181325 -122.18362) (xy 441.135888 -122.154893) (xy 441.094937 -122.120067)
			(xy 441.059284 -122.079835) (xy 441.044076 -122.057668) (xy 441.038004 -122.049367) (xy 441.020834 -122.038085)
			(xy 441.010802 -122.035824) (xy 440.928506 -122.020584) (xy 440.90844 -122.025156) (xy 440.900058 -122.031252)
			(xy 440.875599 -122.048055) (xy 440.822594 -122.074728) (xy 440.7661 -122.092877) (xy 440.707477 -122.102062)
			(xy 440.677808 -122.102626) (xy 440.650558 -122.102115) (xy 440.596612 -122.09436) (xy 440.544319 -122.079007)
			(xy 440.494743 -122.056368) (xy 440.448893 -122.026904) (xy 440.407703 -121.991215) (xy 440.372012 -121.950028)
			(xy 440.342545 -121.90418) (xy 440.319902 -121.854606) (xy 440.304546 -121.802314) (xy 440.296787 -121.748368)
			(xy 440.2963 -121.721118) (xy 438.476179 -121.721118) (xy 438.467124 -121.740832) (xy 438.437392 -121.7868)
			(xy 438.419748 -121.807732) (xy 438.419494 -121.807986) (xy 438.413906 -121.815072) (xy 438.407661 -121.831989)
			(xy 438.407302 -121.841006) (xy 438.407302 -121.908062) (xy 438.407677 -121.917077) (xy 438.413912 -121.933994)
			(xy 438.419494 -121.941082) (xy 438.419748 -121.941082) (xy 438.419748 -121.941336) (xy 438.437362 -121.962288)
			(xy 438.46708 -122.008255) (xy 438.489921 -122.057997) (xy 438.505418 -122.110493) (xy 438.513251 -122.164666)
			(xy 438.513728 -122.192034) (xy 438.513242 -122.219285) (xy 438.505486 -122.273233) (xy 438.490131 -122.325528)
			(xy 438.467489 -122.375105) (xy 438.438023 -122.420955) (xy 438.402332 -122.462146) (xy 438.361141 -122.497837)
			(xy 438.315291 -122.527303) (xy 438.265714 -122.549945) (xy 438.213419 -122.5653) (xy 438.159471 -122.573056)
			(xy 438.104969 -122.573056) (xy 438.051021 -122.5653) (xy 437.998726 -122.549945) (xy 437.949149 -122.527303)
			(xy 437.903299 -122.497837) (xy 437.862108 -122.462146) (xy 437.826417 -122.420955) (xy 437.796951 -122.375105)
			(xy 437.774309 -122.325528) (xy 437.758954 -122.273233) (xy 437.751198 -122.219285) (xy 437.750712 -122.192034)
			(xy 430.278103 -122.192034) (xy 430.281906 -122.206226) (xy 430.289734 -122.265682) (xy 430.290224 -122.295666)
			(xy 430.290224 -123.159266) (xy 430.289734 -123.18925) (xy 430.281906 -123.248706) (xy 430.266385 -123.306631)
			(xy 430.243436 -123.362035) (xy 430.241985 -123.364548) (xy 442.364398 -123.364548) (xy 442.364398 -123.310052)
			(xy 442.372153 -123.25611) (xy 442.387506 -123.20382) (xy 442.410144 -123.154248) (xy 442.439605 -123.108401)
			(xy 442.475292 -123.067214) (xy 442.516476 -123.031525) (xy 442.56232 -123.002059) (xy 442.61189 -122.979417)
			(xy 442.664178 -122.96406) (xy 442.71812 -122.9563) (xy 442.745368 -122.955812) (xy 442.772738 -122.956294)
			(xy 442.826916 -122.964107) (xy 442.879419 -122.979593) (xy 442.929166 -123.002431) (xy 442.975134 -123.032152)
			(xy 442.996066 -123.049792) (xy 442.99632 -123.050046) (xy 443.003393 -123.055653) (xy 443.02032 -123.061886)
			(xy 443.02934 -123.062238) (xy 443.096396 -123.062238) (xy 443.105412 -123.061871) (xy 443.122328 -123.055629)
			(xy 443.129416 -123.050046) (xy 443.129416 -123.049792) (xy 443.12967 -123.049792) (xy 443.150603 -123.032151)
			(xy 443.196571 -123.002427) (xy 443.246317 -122.979581) (xy 443.298819 -122.964085) (xy 443.352997 -122.956256)
			(xy 443.407739 -122.956256) (xy 443.461917 -122.964085) (xy 443.514419 -122.979581) (xy 443.564165 -123.002427)
			(xy 443.610133 -123.032151) (xy 443.631066 -123.049792) (xy 443.63132 -123.050046) (xy 443.638393 -123.055653)
			(xy 443.65532 -123.061886) (xy 443.66434 -123.062238) (xy 443.731396 -123.062238) (xy 443.740412 -123.061871)
			(xy 443.757328 -123.055629) (xy 443.764416 -123.050046) (xy 443.764416 -123.049792) (xy 443.76467 -123.049792)
			(xy 443.785602 -123.032152) (xy 443.831575 -123.002441) (xy 443.881322 -122.979605) (xy 443.933823 -122.964114)
			(xy 443.987999 -122.956286) (xy 444.015368 -122.955812) (xy 444.042624 -122.956233) (xy 444.096581 -122.963986)
			(xy 444.148886 -122.97934) (xy 444.198472 -123.001982) (xy 444.244332 -123.031451) (xy 444.285531 -123.067147)
			(xy 444.32123 -123.108342) (xy 444.350702 -123.154199) (xy 444.373348 -123.203784) (xy 444.388707 -123.256088)
			(xy 444.396465 -123.310044) (xy 444.396465 -123.364556) (xy 444.388707 -123.418512) (xy 444.373348 -123.470816)
			(xy 444.350702 -123.520401) (xy 444.32123 -123.566258) (xy 444.285531 -123.607453) (xy 444.244332 -123.643149)
			(xy 444.198472 -123.672618) (xy 444.148886 -123.69526) (xy 444.096581 -123.710614) (xy 444.042624 -123.718367)
			(xy 444.015368 -123.718828) (xy 443.987996 -123.718398) (xy 443.933815 -123.710574) (xy 443.881311 -123.695078)
			(xy 443.831564 -123.672227) (xy 443.7856 -123.642494) (xy 443.76467 -123.624848) (xy 443.764416 -123.624594)
			(xy 443.75733 -123.619007) (xy 443.740413 -123.612761) (xy 443.731396 -123.612402) (xy 443.66434 -123.612402)
			(xy 443.655325 -123.612778) (xy 443.638408 -123.619012) (xy 443.63132 -123.624594) (xy 443.631066 -123.624848)
			(xy 443.610133 -123.642489) (xy 443.564165 -123.672213) (xy 443.514419 -123.695059) (xy 443.461917 -123.710555)
			(xy 443.407739 -123.718384) (xy 443.352997 -123.718384) (xy 443.298819 -123.710555) (xy 443.246317 -123.695059)
			(xy 443.196571 -123.672213) (xy 443.150603 -123.642489) (xy 443.12967 -123.624848) (xy 443.129416 -123.624594)
			(xy 443.12233 -123.619007) (xy 443.105413 -123.612761) (xy 443.096396 -123.612402) (xy 443.02934 -123.612402)
			(xy 443.020325 -123.612778) (xy 443.003408 -123.619012) (xy 442.99632 -123.624594) (xy 442.99632 -123.624848)
			(xy 442.996066 -123.624848) (xy 442.975113 -123.642462) (xy 442.929147 -123.672179) (xy 442.879405 -123.695021)
			(xy 442.826908 -123.710518) (xy 442.772736 -123.718351) (xy 442.745368 -123.718828) (xy 442.71812 -123.7183)
			(xy 442.664178 -123.71054) (xy 442.61189 -123.695183) (xy 442.56232 -123.672541) (xy 442.516476 -123.643075)
			(xy 442.475292 -123.607386) (xy 442.439605 -123.566199) (xy 442.410144 -123.520352) (xy 442.387506 -123.47078)
			(xy 442.372153 -123.41849) (xy 442.364398 -123.364548) (xy 430.241985 -123.364548) (xy 430.213452 -123.413969)
			(xy 430.176946 -123.461545) (xy 430.134541 -123.50395) (xy 430.086965 -123.540456) (xy 430.035031 -123.57044)
			(xy 429.979627 -123.593389) (xy 429.921702 -123.60891) (xy 429.862246 -123.616738) (xy 429.802278 -123.616738)
			(xy 429.742822 -123.60891) (xy 429.684897 -123.593389) (xy 429.629493 -123.57044) (xy 429.577559 -123.540456)
			(xy 429.529983 -123.50395) (xy 429.487578 -123.461545) (xy 429.451072 -123.413969) (xy 429.421088 -123.362035)
			(xy 429.398139 -123.306631) (xy 429.382618 -123.248706) (xy 429.37479 -123.18925) (xy 429.3743 -123.159266)
			(xy 418.82314 -123.159266) (xy 418.82314 -124.510038) (xy 418.822614 -124.536062) (xy 418.814448 -124.587466)
			(xy 418.798355 -124.636964) (xy 418.774729 -124.683342) (xy 418.74415 -124.725461) (xy 418.726112 -124.744226)
			(xy 418.504624 -124.965714) (xy 432.016408 -124.965714) (xy 432.016408 -124.102114) (xy 432.016898 -124.07213)
			(xy 432.024726 -124.012674) (xy 432.040247 -123.954749) (xy 432.063196 -123.899345) (xy 432.09318 -123.847411)
			(xy 432.129686 -123.799835) (xy 432.172091 -123.75743) (xy 432.219667 -123.720924) (xy 432.271601 -123.69094)
			(xy 432.327005 -123.667991) (xy 432.38493 -123.65247) (xy 432.444386 -123.644642) (xy 432.504354 -123.644642)
			(xy 432.56381 -123.65247) (xy 432.621735 -123.667991) (xy 432.677139 -123.69094) (xy 432.729073 -123.720924)
			(xy 432.776649 -123.75743) (xy 432.819054 -123.799835) (xy 432.836238 -123.82223) (xy 445.742305 -123.82223)
			(xy 445.742308 -123.767732) (xy 445.750066 -123.713789) (xy 445.765422 -123.6615) (xy 445.788064 -123.611928)
			(xy 445.81753 -123.566082) (xy 445.85322 -123.524897) (xy 445.894408 -123.48921) (xy 445.940256 -123.459748)
			(xy 445.98983 -123.437111) (xy 446.042121 -123.421759) (xy 446.096065 -123.414005) (xy 446.123314 -123.41352)
			(xy 446.123822 -123.41352) (xy 446.134194 -123.4136) (xy 446.154906 -123.414744) (xy 446.165224 -123.415806)
			(xy 446.179773 -123.416855) (xy 446.208463 -123.411663) (xy 446.23452 -123.398583) (xy 446.255824 -123.378678)
			(xy 446.270643 -123.353569) (xy 446.27777 -123.325298) (xy 446.276627 -123.296165) (xy 446.272412 -123.282202)
			(xy 446.263052 -123.252595) (xy 446.252974 -123.191327) (xy 446.252346 -123.160282) (xy 446.252346 -123.160028)
			(xy 446.252825 -123.132772) (xy 446.260579 -123.078814) (xy 446.275934 -123.026509) (xy 446.298576 -122.976922)
			(xy 446.328045 -122.931062) (xy 446.363741 -122.889863) (xy 446.404937 -122.854164) (xy 446.450795 -122.824691)
			(xy 446.50038 -122.802045) (xy 446.552684 -122.786686) (xy 446.606641 -122.778927) (xy 446.661153 -122.778927)
			(xy 446.71511 -122.786684) (xy 446.767414 -122.802042) (xy 446.816999 -122.824688) (xy 446.862857 -122.85416)
			(xy 446.904054 -122.889859) (xy 446.939751 -122.931057) (xy 446.969221 -122.976916) (xy 446.991864 -123.026503)
			(xy 447.007219 -123.078808) (xy 447.014975 -123.132765) (xy 447.014971 -123.187277) (xy 447.00721 -123.241234)
			(xy 446.991849 -123.293537) (xy 446.9692 -123.343121) (xy 446.939725 -123.388977) (xy 446.904024 -123.430172)
			(xy 446.862823 -123.465866) (xy 446.816962 -123.495332) (xy 446.767374 -123.517972) (xy 446.715068 -123.533325)
			(xy 446.66111 -123.541076) (xy 446.633854 -123.541536) (xy 446.633346 -123.541536) (xy 446.622974 -123.541459)
			(xy 446.602262 -123.540313) (xy 446.591944 -123.53925) (xy 446.577396 -123.53823) (xy 446.548715 -123.543427)
			(xy 446.522667 -123.556507) (xy 446.501368 -123.576405) (xy 446.48655 -123.601505) (xy 446.479417 -123.629767)
			(xy 446.480549 -123.658893) (xy 446.484756 -123.672854) (xy 446.494108 -123.702463) (xy 446.504191 -123.763729)
			(xy 446.504822 -123.794774) (xy 446.504822 -123.795028) (xy 446.504292 -123.822277) (xy 446.496532 -123.87622)
			(xy 446.481174 -123.928509) (xy 446.458532 -123.978081) (xy 446.429065 -124.023925) (xy 446.393373 -124.06511)
			(xy 446.352184 -124.100795) (xy 446.306335 -124.130256) (xy 446.256761 -124.152892) (xy 446.204469 -124.168243)
			(xy 446.150526 -124.175995) (xy 446.096028 -124.175992) (xy 446.042085 -124.168233) (xy 445.989795 -124.152876)
			(xy 445.940224 -124.130234) (xy 445.894379 -124.100767) (xy 445.853194 -124.065077) (xy 445.817507 -124.023888)
			(xy 445.788046 -123.97804) (xy 445.765409 -123.928465) (xy 445.750058 -123.876174) (xy 445.742305 -123.82223)
			(xy 432.836238 -123.82223) (xy 432.85556 -123.847411) (xy 432.885544 -123.899345) (xy 432.908493 -123.954749)
			(xy 432.924014 -124.012674) (xy 432.931842 -124.07213) (xy 432.932332 -124.102114) (xy 432.932332 -124.215144)
			(xy 442.906656 -124.215144) (xy 442.910727 -124.159522) (xy 442.922853 -124.105085) (xy 442.942776 -124.052994)
			(xy 442.970072 -124.004359) (xy 443.004158 -123.960216) (xy 443.044307 -123.921507) (xy 443.089665 -123.889056)
			(xy 443.139265 -123.863555) (xy 443.192049 -123.845548) (xy 443.246892 -123.835418) (xy 443.302626 -123.833381)
			(xy 443.358063 -123.839481) (xy 443.41202 -123.853587) (xy 443.463349 -123.875399) (xy 443.510955 -123.904453)
			(xy 443.553823 -123.940128) (xy 443.59104 -123.981665) (xy 443.621813 -124.028178) (xy 443.645485 -124.078675)
			(xy 443.661553 -124.132082) (xy 443.669673 -124.187258) (xy 443.670182 -124.215144) (xy 443.669673 -124.24303)
			(xy 443.661553 -124.298206) (xy 443.645485 -124.351613) (xy 443.621813 -124.40211) (xy 443.59104 -124.448623)
			(xy 443.553823 -124.49016) (xy 443.510955 -124.525835) (xy 443.463349 -124.554889) (xy 443.41202 -124.576701)
			(xy 443.358063 -124.590807) (xy 443.302626 -124.596907) (xy 443.246892 -124.59487) (xy 443.192049 -124.58474)
			(xy 443.139265 -124.566733) (xy 443.089665 -124.541232) (xy 443.044307 -124.508781) (xy 443.004158 -124.470072)
			(xy 442.970072 -124.425929) (xy 442.942776 -124.377294) (xy 442.922853 -124.325203) (xy 442.910727 -124.270766)
			(xy 442.906656 -124.215144) (xy 432.932332 -124.215144) (xy 432.932332 -124.965714) (xy 432.931842 -124.995698)
			(xy 432.924014 -125.055154) (xy 432.908493 -125.113079) (xy 432.885544 -125.168483) (xy 432.85556 -125.220417)
			(xy 432.819054 -125.267993) (xy 432.776649 -125.310398) (xy 432.729073 -125.346904) (xy 432.677139 -125.376888)
			(xy 432.621735 -125.399837) (xy 432.56381 -125.415358) (xy 432.504354 -125.423186) (xy 432.444386 -125.423186)
			(xy 432.38493 -125.415358) (xy 432.327005 -125.399837) (xy 432.271601 -125.376888) (xy 432.219667 -125.346904)
			(xy 432.172091 -125.310398) (xy 432.129686 -125.267993) (xy 432.09318 -125.220417) (xy 432.063196 -125.168483)
			(xy 432.040247 -125.113079) (xy 432.024726 -125.055154) (xy 432.016898 -124.995698) (xy 432.016408 -124.965714)
			(xy 418.504624 -124.965714) (xy 417.578794 -125.891544) (xy 443.47511 -125.891544) (xy 443.475537 -125.865229)
			(xy 443.48278 -125.813098) (xy 443.497106 -125.762455) (xy 443.518246 -125.714256) (xy 443.5458 -125.669413)
			(xy 443.579245 -125.628775) (xy 443.5983 -125.61062) (xy 443.605695 -125.603093) (xy 443.614223 -125.583817)
			(xy 443.61481 -125.573282) (xy 443.61481 -125.498606) (xy 443.614288 -125.488056) (xy 443.605748 -125.46876)
			(xy 443.5983 -125.461268) (xy 443.579236 -125.443121) (xy 443.54578 -125.402489) (xy 443.518222 -125.357647)
			(xy 443.497085 -125.309445) (xy 443.482769 -125.258796) (xy 443.475547 -125.206661) (xy 443.47511 -125.180344)
			(xy 443.475596 -125.153093) (xy 443.483352 -125.099145) (xy 443.498707 -125.04685) (xy 443.521349 -124.997273)
			(xy 443.550815 -124.951423) (xy 443.586506 -124.910232) (xy 443.627697 -124.874541) (xy 443.673547 -124.845075)
			(xy 443.723124 -124.822433) (xy 443.775419 -124.807078) (xy 443.829367 -124.799322) (xy 443.883869 -124.799322)
			(xy 443.937817 -124.807078) (xy 443.990112 -124.822433) (xy 444.039689 -124.845075) (xy 444.085539 -124.874541)
			(xy 444.12673 -124.910232) (xy 444.162421 -124.951423) (xy 444.191887 -124.997273) (xy 444.214529 -125.04685)
			(xy 444.229884 -125.099145) (xy 444.23764 -125.153093) (xy 444.238126 -125.180344) (xy 444.23768 -125.206659)
			(xy 444.230439 -125.258788) (xy 444.216115 -125.30943) (xy 444.194979 -125.357629) (xy 444.16743 -125.402472)
			(xy 444.133989 -125.443111) (xy 444.114936 -125.461268) (xy 444.107552 -125.468804) (xy 444.099016 -125.488073)
			(xy 444.098426 -125.498606) (xy 444.098426 -125.573282) (xy 444.098944 -125.583833) (xy 444.107486 -125.603129)
			(xy 444.114936 -125.61062) (xy 444.134001 -125.628766) (xy 444.167456 -125.669398) (xy 444.195013 -125.714241)
			(xy 444.216149 -125.762444) (xy 444.230465 -125.813092) (xy 444.237688 -125.865227) (xy 444.238126 -125.891544)
			(xy 444.23764 -125.918795) (xy 444.229884 -125.972743) (xy 444.214529 -126.025038) (xy 444.191887 -126.074615)
			(xy 444.162421 -126.120465) (xy 444.12673 -126.161656) (xy 444.085539 -126.197347) (xy 444.039689 -126.226813)
			(xy 443.990112 -126.249455) (xy 443.937817 -126.26481) (xy 443.883869 -126.272566) (xy 443.829367 -126.272566)
			(xy 443.775419 -126.26481) (xy 443.723124 -126.249455) (xy 443.673547 -126.226813) (xy 443.627697 -126.197347)
			(xy 443.586506 -126.161656) (xy 443.550815 -126.120465) (xy 443.521349 -126.074615) (xy 443.498707 -126.025038)
			(xy 443.483352 -125.972743) (xy 443.475596 -125.918795) (xy 443.47511 -125.891544) (xy 417.578794 -125.891544)
			(xy 416.665664 -126.804674) (xy 416.648377 -126.821341) (xy 416.609872 -126.850029) (xy 416.588956 -126.861824)
			(xy 416.5811 -126.866503) (xy 416.569097 -126.880279) (xy 416.562694 -126.897392) (xy 416.562286 -126.906528)
			(xy 416.562286 -126.936754) (xy 416.567112 -126.942342) (xy 416.567366 -126.942342) (xy 416.574712 -126.949149)
			(xy 416.593175 -126.956866) (xy 416.60318 -126.957328) (xy 416.739832 -126.957328) (xy 416.758152 -126.957542)
			(xy 416.794563 -126.961612) (xy 416.812476 -126.965456) (xy 416.812984 -126.965456) (xy 416.814508 -126.965964)
			(xy 416.829748 -126.96952) (xy 416.84067 -126.97333) (xy 416.840924 -126.97333) (xy 416.844226 -126.9746)
			(xy 416.84448 -126.9746) (xy 416.84575 -126.975108) (xy 416.847528 -126.975616) (xy 416.849052 -126.976124)
			(xy 416.850068 -126.976632) (xy 416.878518 -126.987747) (xy 416.930943 -127.019072) (xy 416.954208 -127.038862)
			(xy 416.95624 -127.040894) (xy 416.958018 -127.042164) (xy 416.958272 -127.042418) (xy 416.967162 -127.051054)
			(xy 418.088064 -128.17221) (xy 418.093652 -128.177036) (xy 420.98595 -128.177036) (xy 420.996015 -128.176602)
			(xy 421.0146 -128.168868) (xy 421.022018 -128.16205) (xy 422.177972 -127.005842) (xy 422.196752 -126.987729)
			(xy 422.238949 -126.957044) (xy 422.28543 -126.933345) (xy 422.335049 -126.917217) (xy 422.386581 -126.909058)
			(xy 422.412668 -126.90856) (xy 446.093088 -126.90856) (xy 446.103158 -126.908138) (xy 446.121762 -126.900422)
			(xy 446.129156 -126.893574) (xy 449.217288 -123.805442) (xy 449.236066 -123.787324) (xy 449.278261 -123.756628)
			(xy 449.324741 -123.732918) (xy 449.37436 -123.716777) (xy 449.425895 -123.708605) (xy 449.451984 -123.70816)
			(xy 450.672454 -123.70816) (xy 450.698539 -123.70865) (xy 450.750066 -123.716825) (xy 450.799678 -123.732964)
			(xy 450.846153 -123.756669) (xy 450.888344 -123.787357) (xy 450.90715 -123.805442) (xy 451.231508 -124.130054)
			(xy 451.238905 -124.136904) (xy 451.257503 -124.144643) (xy 451.267576 -124.14504) (xy 453.288908 -124.14504)
			(xy 453.298976 -124.144614) (xy 453.317573 -124.136891) (xy 453.324976 -124.130054) (xy 457.66101 -119.793766)
			(xy 457.667861 -119.78637) (xy 457.675597 -119.767771) (xy 457.675996 -119.757698) (xy 457.675996 -117.977666)
			(xy 457.675566 -117.967599) (xy 457.667843 -117.949004) (xy 457.66101 -117.941598) (xy 457.33589 -117.616478)
			(xy 457.329286 -117.614446) (xy 457.303282 -117.606281) (xy 457.253722 -117.583599) (xy 457.207893 -117.554096)
			(xy 457.166729 -117.518372) (xy 457.131066 -117.477155) (xy 457.101631 -117.431283) (xy 457.079022 -117.38169)
			(xy 457.0637 -117.329384) (xy 457.055976 -117.27543) (xy 457.055474 -117.248178) (xy 457.055961 -117.220927)
			(xy 457.06372 -117.166981) (xy 457.079077 -117.114688) (xy 457.101719 -117.065112) (xy 457.131186 -117.019263)
			(xy 457.166877 -116.978074) (xy 457.208067 -116.942383) (xy 457.253916 -116.912917) (xy 457.303492 -116.890276)
			(xy 457.355785 -116.874919) (xy 457.409731 -116.867161) (xy 457.436982 -116.86667) (xy 457.464213 -116.867146)
			(xy 457.518124 -116.874874) (xy 457.570388 -116.890189) (xy 457.619943 -116.912781) (xy 457.665781 -116.94219)
			(xy 457.706972 -116.977818) (xy 457.742678 -117.018942) (xy 457.772174 -117.064725) (xy 457.794859 -117.114237)
			(xy 457.802996 -117.140228) (xy 457.805028 -117.146832) (xy 457.930504 -117.272308) (xy 457.93639 -117.272997)
			(xy 457.948195 -117.271976) (xy 457.953872 -117.270276) (xy 457.996036 -117.256306) (xy 457.996544 -117.256052)
			(xy 458.030326 -117.244114) (xy 458.03551 -117.241754) (xy 458.044737 -117.23508) (xy 458.048614 -117.230906)
			(xy 458.052678 -117.22608) (xy 458.065124 -117.211094) (xy 458.065124 -117.21084) (xy 458.071982 -117.203982)
			(xy 458.075792 -117.187472) (xy 458.0763 -117.185694) (xy 458.081182 -117.159292) (xy 458.097373 -117.108102)
			(xy 458.120569 -117.059681) (xy 458.150315 -117.014984) (xy 458.186025 -116.97489) (xy 458.226995 -116.94019)
			(xy 458.272418 -116.911565) (xy 458.321401 -116.889581) (xy 458.37298 -116.874669) (xy 458.426137 -116.867124)
			(xy 458.452982 -116.86667) (xy 458.479956 -116.867142) (xy 458.533364 -116.87475) (xy 458.585169 -116.889805)
			(xy 458.634338 -116.912005) (xy 458.679889 -116.940908) (xy 458.720917 -116.975939) (xy 458.756602 -117.016398)
			(xy 458.786234 -117.061479) (xy 458.809222 -117.110284) (xy 458.825108 -117.16184) (xy 458.833574 -117.215119)
			(xy 458.83449 -117.242082) (xy 458.83449 -117.249448) (xy 458.83404 -117.274357) (xy 458.827454 -117.323738)
			(xy 458.814479 -117.371838) (xy 458.80528 -117.39499) (xy 458.803502 -117.399308) (xy 458.800962 -117.411246)
			(xy 458.799351 -117.420709) (xy 458.802489 -117.439633) (xy 458.807058 -117.448076) (xy 458.809852 -117.452648)
			(xy 458.824076 -117.475762) (xy 458.826473 -117.478983) (xy 458.832083 -117.484727) (xy 458.835252 -117.487192)
			(xy 458.893164 -117.487192) (xy 458.903229 -117.486757) (xy 458.921816 -117.479025) (xy 458.929232 -117.472206)
			(xy 459.941422 -116.46027) (xy 459.948272 -116.452874) (xy 459.956008 -116.434275) (xy 459.956408 -116.424202)
			(xy 459.956408 -115.316) (xy 459.952725 -115.311357) (xy 459.94361 -115.30379) (xy 459.938374 -115.301014)
			(xy 459.857602 -115.260628) (xy 459.852277 -115.258161) (xy 459.840861 -115.255457) (xy 459.834996 -115.255294)
			(xy 459.833472 -115.255294) (xy 459.825896 -115.255608) (xy 459.81143 -115.260127) (xy 459.805024 -115.264184)
			(xy 459.803246 -115.265454) (xy 459.778301 -115.283496) (xy 459.72381 -115.312139) (xy 459.665426 -115.331658)
			(xy 459.604664 -115.341544) (xy 459.573884 -115.342162) (xy 459.546637 -115.341675) (xy 459.492697 -115.333917)
			(xy 459.440411 -115.318563) (xy 459.390842 -115.295923) (xy 459.344999 -115.26646) (xy 459.303816 -115.230773)
			(xy 459.26813 -115.189588) (xy 459.238669 -115.143744) (xy 459.216032 -115.094174) (xy 459.200679 -115.041887)
			(xy 459.192924 -114.987947) (xy 459.192924 -114.933453) (xy 459.200679 -114.879513) (xy 459.216032 -114.827226)
			(xy 459.238669 -114.777656) (xy 459.26813 -114.731812) (xy 459.303816 -114.690627) (xy 459.344999 -114.65494)
			(xy 459.390842 -114.625477) (xy 459.440411 -114.602837) (xy 459.492697 -114.587483) (xy 459.546637 -114.579725)
			(xy 459.573884 -114.579146) (xy 459.604739 -114.579737) (xy 459.665645 -114.589661) (xy 459.724162 -114.609251)
			(xy 459.778766 -114.637998) (xy 459.803754 -114.656108) (xy 459.834234 -114.666268) (xy 459.842362 -114.665506)
			(xy 459.84287 -114.665506) (xy 459.85049 -114.664236) (xy 459.938374 -114.620294) (xy 459.943595 -114.617498)
			(xy 459.952694 -114.609922) (xy 459.956408 -114.605308) (xy 459.956408 -113.922302) (xy 459.952626 -113.917556)
			(xy 459.943252 -113.909858) (xy 459.937866 -113.907062) (xy 459.9305 -113.903506) (xy 459.860396 -113.868708)
			(xy 459.85379 -113.865643) (xy 459.839463 -113.863065) (xy 459.832202 -113.863628) (xy 459.82509 -113.864644)
			(xy 459.8035 -113.87201) (xy 459.79715 -113.876582) (xy 459.772492 -113.893934) (xy 459.718849 -113.921456)
			(xy 459.661541 -113.940187) (xy 459.601998 -113.949659) (xy 459.571852 -113.950242) (xy 459.544601 -113.949753)
			(xy 459.490653 -113.94199) (xy 459.43836 -113.926629) (xy 459.388784 -113.903984) (xy 459.342936 -113.874513)
			(xy 459.301747 -113.838819) (xy 459.266058 -113.797626) (xy 459.236593 -113.751774) (xy 459.213954 -113.702195)
			(xy 459.1986 -113.6499) (xy 459.190844 -113.595951) (xy 459.190844 -113.541449) (xy 459.1986 -113.4875)
			(xy 459.213954 -113.435205) (xy 459.236593 -113.385626) (xy 459.266058 -113.339774) (xy 459.301747 -113.298581)
			(xy 459.342936 -113.262887) (xy 459.388784 -113.233416) (xy 459.43836 -113.210771) (xy 459.490653 -113.19541)
			(xy 459.544601 -113.187647) (xy 459.571852 -113.187226) (xy 459.571852 -113.186972) (xy 459.601955 -113.187535)
			(xy 459.661416 -113.196984) (xy 459.718655 -113.215654) (xy 459.772251 -113.243082) (xy 459.796896 -113.260378)
			(xy 459.8035 -113.265458) (xy 459.821026 -113.2713) (xy 459.828143 -113.273431) (xy 459.842985 -113.27394)
			(xy 459.850236 -113.272316) (xy 459.8543 -113.271046) (xy 459.858872 -113.269522) (xy 459.939136 -113.229898)
			(xy 459.944137 -113.227179) (xy 459.952859 -113.21987) (xy 459.956408 -113.21542) (xy 459.956408 -112.654334)
			(xy 459.952727 -112.649689) (xy 459.943614 -112.642117) (xy 459.938374 -112.639348) (xy 459.857094 -112.598962)
			(xy 459.852268 -112.59693) (xy 459.841091 -112.593375) (xy 459.817783 -112.595748) (xy 459.807564 -112.601502)
			(xy 459.802992 -112.604296) (xy 459.801214 -112.605566) (xy 459.776516 -112.62281) (xy 459.722833 -112.650124)
			(xy 459.665526 -112.668671) (xy 459.63586 -112.673892) (xy 459.622166 -112.675902) (xy 459.59458 -112.678188)
			(xy 459.580742 -112.678464) (xy 459.578202 -112.678464) (xy 459.575662 -112.678464) (xy 459.575154 -112.678464)
			(xy 459.547985 -112.677859) (xy 459.494229 -112.669901) (xy 459.442146 -112.654395) (xy 459.392791 -112.631654)
			(xy 459.347162 -112.60214) (xy 459.306184 -112.566449) (xy 459.270686 -112.525303) (xy 459.241386 -112.479537)
			(xy 459.218877 -112.430075) (xy 459.203615 -112.37792) (xy 459.19591 -112.324127) (xy 459.195424 -112.296956)
			(xy 459.195913 -112.269708) (xy 459.203675 -112.215766) (xy 459.219034 -112.163479) (xy 459.241678 -112.113909)
			(xy 459.271146 -112.068067) (xy 459.306838 -112.026884) (xy 459.348028 -111.991201) (xy 459.393876 -111.961742)
			(xy 459.44345 -111.939108) (xy 459.495741 -111.923759) (xy 459.549684 -111.916008) (xy 459.576932 -111.915448)
			(xy 459.607394 -111.916047) (xy 459.667542 -111.925738) (xy 459.725384 -111.944869) (xy 459.779448 -111.972953)
			(xy 459.804262 -111.990632) (xy 459.810104 -111.99495) (xy 459.823312 -111.999776) (xy 459.83017 -112.000538)
			(xy 459.83713 -112.000886) (xy 459.850794 -111.998183) (xy 459.857094 -111.995204) (xy 459.938628 -111.95431)
			(xy 459.943794 -111.951511) (xy 459.952775 -111.943941) (xy 459.956408 -111.939324) (xy 459.956408 -110.813088)
			(xy 459.952143 -110.807861) (xy 459.941468 -110.799621) (xy 459.935326 -110.796832) (xy 459.849728 -110.763304)
			(xy 459.841159 -110.760818) (xy 459.823336 -110.761331) (xy 459.81493 -110.76432) (xy 459.790546 -110.77448)
			(xy 459.783434 -110.781846) (xy 459.765413 -110.799747) (xy 459.725454 -110.831108) (xy 459.681686 -110.856888)
			(xy 459.634884 -110.87663) (xy 459.585875 -110.889986) (xy 459.535528 -110.896718) (xy 459.51013 -110.897162)
			(xy 459.482879 -110.896701) (xy 459.428931 -110.888948) (xy 459.376636 -110.873597) (xy 459.327058 -110.850959)
			(xy 459.281207 -110.821495) (xy 459.240016 -110.785806) (xy 459.204323 -110.744617) (xy 459.174856 -110.698768)
			(xy 459.152214 -110.649192) (xy 459.136858 -110.596898) (xy 459.129101 -110.542951) (xy 459.129101 -110.488449)
			(xy 459.136858 -110.434502) (xy 459.152214 -110.382208) (xy 459.174856 -110.332632) (xy 459.204323 -110.286783)
			(xy 459.240016 -110.245594) (xy 459.281207 -110.209905) (xy 459.327058 -110.180441) (xy 459.376636 -110.157803)
			(xy 459.428931 -110.142452) (xy 459.482879 -110.134699) (xy 459.51013 -110.134146) (xy 459.535528 -110.134566)
			(xy 459.585874 -110.14131) (xy 459.63488 -110.154675) (xy 459.68168 -110.174423) (xy 459.725446 -110.200207)
			(xy 459.765403 -110.23157) (xy 459.783434 -110.249462) (xy 459.790546 -110.256828) (xy 459.81493 -110.266988)
			(xy 459.823338 -110.269965) (xy 459.841158 -110.270478) (xy 459.849728 -110.268004) (xy 459.935326 -110.234476)
			(xy 459.941491 -110.231723) (xy 459.952183 -110.223486) (xy 459.956408 -110.21822) (xy 459.956408 -102.922578)
			(xy 459.955981 -102.912509) (xy 459.948262 -102.89391) (xy 459.941422 -102.88651) (xy 452.204074 -95.149162)
			(xy 452.196677 -95.142313) (xy 452.178078 -95.134578) (xy 452.168006 -95.134176) (xy 445.682878 -95.134176)
			(xy 445.656853 -95.133651) (xy 445.605447 -95.125488) (xy 445.555946 -95.109398) (xy 445.509565 -95.085776)
			(xy 445.467442 -95.0552) (xy 445.44869 -95.037148) (xy 445.032892 -94.62135) (xy 445.026288 -94.619318)
			(xy 445.000316 -94.611134) (xy 444.950823 -94.58843) (xy 444.905056 -94.558926) (xy 444.863944 -94.523221)
			(xy 444.82832 -94.482038) (xy 444.798907 -94.436212) (xy 444.776301 -94.386674) (xy 444.760961 -94.334426)
			(xy 444.753198 -94.28053) (xy 444.75273 -94.253304) (xy 444.753193 -94.226052) (xy 444.76095 -94.172103)
			(xy 444.776306 -94.119806) (xy 444.798949 -94.070228) (xy 444.828417 -94.024377) (xy 444.864111 -93.983187)
			(xy 444.905305 -93.947497) (xy 444.951158 -93.918032) (xy 445.000738 -93.895394) (xy 445.053036 -93.880043)
			(xy 445.106986 -93.872291) (xy 445.134238 -93.871796) (xy 445.161466 -93.872276) (xy 445.21537 -93.88001)
			(xy 445.267627 -93.895332) (xy 445.317174 -93.917928) (xy 445.363005 -93.94734) (xy 445.404187 -93.98297)
			(xy 445.439885 -94.024094) (xy 445.469372 -94.069876) (xy 445.492049 -94.119386) (xy 445.500252 -94.145354)
			(xy 445.502284 -94.151958) (xy 445.805814 -94.455742) (xy 445.81321 -94.462593) (xy 445.831809 -94.470331)
			(xy 445.841882 -94.470728) (xy 452.32701 -94.470728) (xy 452.353032 -94.47126) (xy 452.404431 -94.479434)
			(xy 452.453923 -94.495535) (xy 452.500294 -94.519165) (xy 452.542406 -94.549747) (xy 452.561198 -94.567756)
			(xy 460.522828 -102.529386) (xy 460.540862 -102.548156) (xy 460.571446 -102.590271) (xy 460.595076 -102.636647)
			(xy 460.611171 -102.686145) (xy 460.619337 -102.73755) (xy 460.619856 -102.763574) (xy 460.619856 -116.583206)
			(xy 460.619324 -116.609228) (xy 460.61115 -116.660627) (xy 460.59505 -116.710119) (xy 460.571419 -116.75649)
			(xy 460.540836 -116.798601) (xy 460.522828 -116.817394) (xy 459.286356 -118.053866) (xy 459.267576 -118.07198)
			(xy 459.22538 -118.102668) (xy 459.178899 -118.12637) (xy 459.12928 -118.142502) (xy 459.077748 -118.150665)
			(xy 459.05166 -118.151148) (xy 458.350366 -118.151148) (xy 458.347437 -118.153405) (xy 458.342208 -118.158633)
			(xy 458.339952 -118.161562) (xy 458.339952 -119.916194) (xy 458.339466 -119.942281) (xy 458.3313 -119.993813)
			(xy 458.315169 -120.043432) (xy 458.291469 -120.089913) (xy 458.260786 -120.132112) (xy 458.24267 -120.15089)
			(xy 453.6821 -124.71146) (xy 453.663329 -124.729492) (xy 453.621212 -124.760071) (xy 453.574836 -124.783697)
			(xy 453.525339 -124.799788) (xy 453.473935 -124.807951) (xy 453.447912 -124.808488) (xy 451.108572 -124.808488)
			(xy 451.082547 -124.807962) (xy 451.031141 -124.799799) (xy 450.981641 -124.783709) (xy 450.93526 -124.760087)
			(xy 450.893137 -124.729511) (xy 450.874384 -124.71146) (xy 450.550026 -124.387102) (xy 450.542623 -124.380267)
			(xy 450.524025 -124.372559) (xy 450.513958 -124.372116) (xy 450.019928 -124.372116) (xy 450.014216 -124.376632)
			(xy 450.005449 -124.38825) (xy 450.002656 -124.394976) (xy 449.993004 -124.42571) (xy 449.993004 -124.426472)
			(xy 449.978272 -124.448062) (xy 449.974307 -124.4543) (xy 449.969798 -124.468368) (xy 449.969382 -124.475748)
			(xy 449.969382 -124.50064) (xy 449.97243 -124.509022) (xy 449.982608 -124.538447) (xy 449.994357 -124.599586)
			(xy 449.995798 -124.630688) (xy 449.995798 -124.643388) (xy 449.995121 -124.670455) (xy 449.987065 -124.723995)
			(xy 449.971524 -124.775859) (xy 449.948811 -124.825007) (xy 449.919381 -124.870452) (xy 449.883824 -124.911282)
			(xy 449.842855 -124.946679) (xy 449.797295 -124.975931) (xy 449.748058 -124.998452) (xy 449.72224 -125.006608)
			(xy 449.715636 -125.00864) (xy 446.354708 -128.369568) (xy 446.335937 -128.3876) (xy 446.29382 -128.41818)
			(xy 446.247444 -128.441806) (xy 446.197947 -128.457898) (xy 446.146543 -128.466062) (xy 446.12052 -128.466596)
			(xy 422.298368 -128.466596) (xy 422.2883 -128.467025) (xy 422.269704 -128.474747) (xy 422.2623 -128.481582)
			(xy 421.562784 -129.181352) (xy 421.544013 -129.199383) (xy 421.501896 -129.229961) (xy 421.45552 -129.253585)
			(xy 421.406022 -129.269675) (xy 421.354619 -129.277835) (xy 421.328596 -129.27838) (xy 417.359846 -129.27838)
			(xy 417.333822 -129.277852) (xy 417.282419 -129.269686) (xy 417.232921 -129.253592) (xy 417.186543 -129.229967)
			(xy 417.144424 -129.199389) (xy 417.125658 -129.181352) (xy 416.029902 -128.085342) (xy 416.022506 -128.078491)
			(xy 416.003907 -128.070749) (xy 415.993834 -128.070356) (xy 412.58998 -128.070356) (xy 412.58088 -128.077962)
			(xy 412.570291 -128.099152) (xy 412.56966 -128.110996) (xy 412.56966 -130.777234) (xy 414.899348 -130.777234)
			(xy 414.899348 -129.913634) (xy 414.899838 -129.88365) (xy 414.907666 -129.824194) (xy 414.923187 -129.766269)
			(xy 414.946136 -129.710865) (xy 414.97612 -129.658931) (xy 415.012626 -129.611355) (xy 415.055031 -129.56895)
			(xy 415.102607 -129.532444) (xy 415.154541 -129.50246) (xy 415.209945 -129.479511) (xy 415.26787 -129.46399)
			(xy 415.327326 -129.456162) (xy 415.387294 -129.456162) (xy 415.44675 -129.46399) (xy 415.504675 -129.479511)
			(xy 415.560079 -129.50246) (xy 415.612013 -129.532444) (xy 415.659589 -129.56895) (xy 415.701994 -129.611355)
			(xy 415.7385 -129.658931) (xy 415.768484 -129.710865) (xy 415.791433 -129.766269) (xy 415.806954 -129.824194)
			(xy 415.814782 -129.88365) (xy 415.815272 -129.913634) (xy 415.815272 -130.769106) (xy 429.3743 -130.769106)
			(xy 429.3743 -129.905506) (xy 429.37479 -129.875522) (xy 429.382618 -129.816066) (xy 429.398139 -129.758141)
			(xy 429.421088 -129.702737) (xy 429.451072 -129.650803) (xy 429.487578 -129.603227) (xy 429.529983 -129.560822)
			(xy 429.577559 -129.524316) (xy 429.629493 -129.494332) (xy 429.684897 -129.471383) (xy 429.742822 -129.455862)
			(xy 429.802278 -129.448034) (xy 429.862246 -129.448034) (xy 429.921702 -129.455862) (xy 429.979627 -129.471383)
			(xy 430.035031 -129.494332) (xy 430.086965 -129.524316) (xy 430.134541 -129.560822) (xy 430.176946 -129.603227)
			(xy 430.213452 -129.650803) (xy 430.243436 -129.702737) (xy 430.266385 -129.758141) (xy 430.281906 -129.816066)
			(xy 430.289734 -129.875522) (xy 430.290224 -129.905506) (xy 430.290224 -130.769106) (xy 430.289734 -130.79909)
			(xy 430.281906 -130.858546) (xy 430.266385 -130.916471) (xy 430.243436 -130.971875) (xy 430.213452 -131.023809)
			(xy 430.176946 -131.071385) (xy 430.134541 -131.11379) (xy 430.086965 -131.150296) (xy 430.035031 -131.18028)
			(xy 429.979627 -131.203229) (xy 429.921702 -131.21875) (xy 429.862246 -131.226578) (xy 429.802278 -131.226578)
			(xy 429.742822 -131.21875) (xy 429.684897 -131.203229) (xy 429.629493 -131.18028) (xy 429.577559 -131.150296)
			(xy 429.529983 -131.11379) (xy 429.487578 -131.071385) (xy 429.451072 -131.023809) (xy 429.421088 -130.971875)
			(xy 429.398139 -130.916471) (xy 429.382618 -130.858546) (xy 429.37479 -130.79909) (xy 429.3743 -130.769106)
			(xy 415.815272 -130.769106) (xy 415.815272 -130.777234) (xy 415.814782 -130.807218) (xy 415.806954 -130.866674)
			(xy 415.791433 -130.924599) (xy 415.768484 -130.980003) (xy 415.7385 -131.031937) (xy 415.701994 -131.079513)
			(xy 415.659589 -131.121918) (xy 415.612013 -131.158424) (xy 415.560079 -131.188408) (xy 415.504675 -131.211357)
			(xy 415.44675 -131.226878) (xy 415.387294 -131.234706) (xy 415.327326 -131.234706) (xy 415.26787 -131.226878)
			(xy 415.209945 -131.211357) (xy 415.154541 -131.188408) (xy 415.102607 -131.158424) (xy 415.055031 -131.121918)
			(xy 415.012626 -131.079513) (xy 414.97612 -131.031937) (xy 414.946136 -130.980003) (xy 414.923187 -130.924599)
			(xy 414.907666 -130.866674) (xy 414.899838 -130.807218) (xy 414.899348 -130.777234) (xy 412.56966 -130.777234)
			(xy 412.56966 -132.577332) (xy 413.045148 -132.577332) (xy 413.045148 -131.713732) (xy 413.045638 -131.683748)
			(xy 413.053466 -131.624292) (xy 413.068987 -131.566367) (xy 413.091936 -131.510963) (xy 413.12192 -131.459029)
			(xy 413.158426 -131.411453) (xy 413.200831 -131.369048) (xy 413.248407 -131.332542) (xy 413.300341 -131.302558)
			(xy 413.355745 -131.279609) (xy 413.41367 -131.264088) (xy 413.473126 -131.25626) (xy 413.533094 -131.25626)
			(xy 413.59255 -131.264088) (xy 413.650475 -131.279609) (xy 413.705879 -131.302558) (xy 413.757813 -131.332542)
			(xy 413.805389 -131.369048) (xy 413.847794 -131.411453) (xy 413.8843 -131.459029) (xy 413.914284 -131.510963)
			(xy 413.937233 -131.566367) (xy 413.952754 -131.624292) (xy 413.960582 -131.683748) (xy 413.961072 -131.713732)
			(xy 413.961072 -132.575808) (xy 432.016408 -132.575808) (xy 432.016408 -131.712208) (xy 432.016898 -131.682224)
			(xy 432.024726 -131.622768) (xy 432.040247 -131.564843) (xy 432.063196 -131.509439) (xy 432.09318 -131.457505)
			(xy 432.129686 -131.409929) (xy 432.172091 -131.367524) (xy 432.219667 -131.331018) (xy 432.271601 -131.301034)
			(xy 432.327005 -131.278085) (xy 432.38493 -131.262564) (xy 432.444386 -131.254736) (xy 432.504354 -131.254736)
			(xy 432.56381 -131.262564) (xy 432.621735 -131.278085) (xy 432.677139 -131.301034) (xy 432.729073 -131.331018)
			(xy 432.776649 -131.367524) (xy 432.819054 -131.409929) (xy 432.85556 -131.457505) (xy 432.885544 -131.509439)
			(xy 432.908493 -131.564843) (xy 432.924014 -131.622768) (xy 432.931842 -131.682224) (xy 432.932332 -131.712208)
			(xy 432.932332 -132.575808) (xy 432.931842 -132.605792) (xy 432.924014 -132.665248) (xy 432.908493 -132.723173)
			(xy 432.885544 -132.778577) (xy 432.85556 -132.830511) (xy 432.819054 -132.878087) (xy 432.776649 -132.920492)
			(xy 432.729073 -132.956998) (xy 432.677139 -132.986982) (xy 432.621735 -133.009931) (xy 432.56381 -133.025452)
			(xy 432.504354 -133.03328) (xy 432.444386 -133.03328) (xy 432.38493 -133.025452) (xy 432.327005 -133.009931)
			(xy 432.271601 -132.986982) (xy 432.219667 -132.956998) (xy 432.172091 -132.920492) (xy 432.129686 -132.878087)
			(xy 432.09318 -132.830511) (xy 432.063196 -132.778577) (xy 432.040247 -132.723173) (xy 432.024726 -132.665248)
			(xy 432.016898 -132.605792) (xy 432.016408 -132.575808) (xy 413.961072 -132.575808) (xy 413.961072 -132.577332)
			(xy 413.960582 -132.607316) (xy 413.952754 -132.666772) (xy 413.937233 -132.724697) (xy 413.914284 -132.780101)
			(xy 413.8843 -132.832035) (xy 413.847794 -132.879611) (xy 413.805389 -132.922016) (xy 413.757813 -132.958522)
			(xy 413.705879 -132.988506) (xy 413.650475 -133.011455) (xy 413.59255 -133.026976) (xy 413.533094 -133.034804)
			(xy 413.473126 -133.034804) (xy 413.41367 -133.026976) (xy 413.355745 -133.011455) (xy 413.300341 -132.988506)
			(xy 413.248407 -132.958522) (xy 413.200831 -132.922016) (xy 413.158426 -132.879611) (xy 413.12192 -132.832035)
			(xy 413.091936 -132.780101) (xy 413.068987 -132.724697) (xy 413.053466 -132.666772) (xy 413.045638 -132.607316)
			(xy 413.045148 -132.577332) (xy 412.56966 -132.577332) (xy 412.56966 -134.377176) (xy 414.899348 -134.377176)
			(xy 414.899348 -133.513576) (xy 414.899838 -133.483592) (xy 414.907666 -133.424136) (xy 414.923187 -133.366211)
			(xy 414.946136 -133.310807) (xy 414.97612 -133.258873) (xy 415.012626 -133.211297) (xy 415.055031 -133.168892)
			(xy 415.102607 -133.132386) (xy 415.154541 -133.102402) (xy 415.209945 -133.079453) (xy 415.26787 -133.063932)
			(xy 415.327326 -133.056104) (xy 415.387294 -133.056104) (xy 415.44675 -133.063932) (xy 415.504675 -133.079453)
			(xy 415.560079 -133.102402) (xy 415.612013 -133.132386) (xy 415.659589 -133.168892) (xy 415.701994 -133.211297)
			(xy 415.7385 -133.258873) (xy 415.768484 -133.310807) (xy 415.791433 -133.366211) (xy 415.806954 -133.424136)
			(xy 415.814782 -133.483592) (xy 415.815272 -133.513576) (xy 415.815272 -134.369302) (xy 429.3743 -134.369302)
			(xy 429.3743 -133.505702) (xy 429.37479 -133.475718) (xy 429.382618 -133.416262) (xy 429.398139 -133.358337)
			(xy 429.421088 -133.302933) (xy 429.451072 -133.250999) (xy 429.487578 -133.203423) (xy 429.529983 -133.161018)
			(xy 429.577559 -133.124512) (xy 429.629493 -133.094528) (xy 429.684897 -133.071579) (xy 429.742822 -133.056058)
			(xy 429.802278 -133.04823) (xy 429.862246 -133.04823) (xy 429.921702 -133.056058) (xy 429.979627 -133.071579)
			(xy 430.035031 -133.094528) (xy 430.086965 -133.124512) (xy 430.134541 -133.161018) (xy 430.176946 -133.203423)
			(xy 430.213452 -133.250999) (xy 430.243436 -133.302933) (xy 430.266385 -133.358337) (xy 430.281906 -133.416262)
			(xy 430.289734 -133.475718) (xy 430.290224 -133.505702) (xy 430.290224 -134.369302) (xy 430.289734 -134.399286)
			(xy 430.281906 -134.458742) (xy 430.266385 -134.516667) (xy 430.243436 -134.572071) (xy 430.213452 -134.624005)
			(xy 430.176946 -134.671581) (xy 430.134541 -134.713986) (xy 430.086965 -134.750492) (xy 430.035031 -134.780476)
			(xy 429.979627 -134.803425) (xy 429.921702 -134.818946) (xy 429.862246 -134.826774) (xy 429.802278 -134.826774)
			(xy 429.742822 -134.818946) (xy 429.684897 -134.803425) (xy 429.629493 -134.780476) (xy 429.577559 -134.750492)
			(xy 429.529983 -134.713986) (xy 429.487578 -134.671581) (xy 429.451072 -134.624005) (xy 429.421088 -134.572071)
			(xy 429.398139 -134.516667) (xy 429.382618 -134.458742) (xy 429.37479 -134.399286) (xy 429.3743 -134.369302)
			(xy 415.815272 -134.369302) (xy 415.815272 -134.377176) (xy 415.814782 -134.40716) (xy 415.806954 -134.466616)
			(xy 415.791433 -134.524541) (xy 415.768484 -134.579945) (xy 415.7385 -134.631879) (xy 415.701994 -134.679455)
			(xy 415.659589 -134.72186) (xy 415.612013 -134.758366) (xy 415.560079 -134.78835) (xy 415.504675 -134.811299)
			(xy 415.44675 -134.82682) (xy 415.387294 -134.834648) (xy 415.327326 -134.834648) (xy 415.26787 -134.82682)
			(xy 415.209945 -134.811299) (xy 415.154541 -134.78835) (xy 415.102607 -134.758366) (xy 415.055031 -134.72186)
			(xy 415.012626 -134.679455) (xy 414.97612 -134.631879) (xy 414.946136 -134.579945) (xy 414.923187 -134.524541)
			(xy 414.907666 -134.466616) (xy 414.899838 -134.40716) (xy 414.899348 -134.377176) (xy 412.56966 -134.377176)
			(xy 412.56966 -136.177274) (xy 413.045148 -136.177274) (xy 413.045148 -135.313674) (xy 413.045638 -135.28369)
			(xy 413.053466 -135.224234) (xy 413.068987 -135.166309) (xy 413.091936 -135.110905) (xy 413.12192 -135.058971)
			(xy 413.158426 -135.011395) (xy 413.200831 -134.96899) (xy 413.248407 -134.932484) (xy 413.300341 -134.9025)
			(xy 413.355745 -134.879551) (xy 413.41367 -134.86403) (xy 413.473126 -134.856202) (xy 413.533094 -134.856202)
			(xy 413.59255 -134.86403) (xy 413.650475 -134.879551) (xy 413.705879 -134.9025) (xy 413.757813 -134.932484)
			(xy 413.805389 -134.96899) (xy 413.847794 -135.011395) (xy 413.8843 -135.058971) (xy 413.914284 -135.110905)
			(xy 413.937233 -135.166309) (xy 413.952754 -135.224234) (xy 413.960582 -135.28369) (xy 413.961072 -135.313674)
			(xy 413.961072 -136.17575) (xy 432.016408 -136.17575) (xy 432.016408 -135.31215) (xy 432.016898 -135.282166)
			(xy 432.024726 -135.22271) (xy 432.040247 -135.164785) (xy 432.063196 -135.109381) (xy 432.09318 -135.057447)
			(xy 432.129686 -135.009871) (xy 432.172091 -134.967466) (xy 432.219667 -134.93096) (xy 432.271601 -134.900976)
			(xy 432.327005 -134.878027) (xy 432.38493 -134.862506) (xy 432.444386 -134.854678) (xy 432.504354 -134.854678)
			(xy 432.56381 -134.862506) (xy 432.621735 -134.878027) (xy 432.677139 -134.900976) (xy 432.729073 -134.93096)
			(xy 432.776649 -134.967466) (xy 432.819054 -135.009871) (xy 432.85556 -135.057447) (xy 432.885544 -135.109381)
			(xy 432.908493 -135.164785) (xy 432.924014 -135.22271) (xy 432.931842 -135.282166) (xy 432.932332 -135.31215)
			(xy 432.932332 -136.17575) (xy 432.931842 -136.205734) (xy 432.924014 -136.26519) (xy 432.908493 -136.323115)
			(xy 432.885544 -136.378519) (xy 432.85556 -136.430453) (xy 432.819054 -136.478029) (xy 432.776649 -136.520434)
			(xy 432.729073 -136.55694) (xy 432.677139 -136.586924) (xy 432.621735 -136.609873) (xy 432.56381 -136.625394)
			(xy 432.504354 -136.633222) (xy 432.444386 -136.633222) (xy 432.38493 -136.625394) (xy 432.327005 -136.609873)
			(xy 432.271601 -136.586924) (xy 432.219667 -136.55694) (xy 432.172091 -136.520434) (xy 432.129686 -136.478029)
			(xy 432.09318 -136.430453) (xy 432.063196 -136.378519) (xy 432.040247 -136.323115) (xy 432.024726 -136.26519)
			(xy 432.016898 -136.205734) (xy 432.016408 -136.17575) (xy 413.961072 -136.17575) (xy 413.961072 -136.177274)
			(xy 413.960582 -136.207258) (xy 413.952754 -136.266714) (xy 413.937233 -136.324639) (xy 413.914284 -136.380043)
			(xy 413.8843 -136.431977) (xy 413.847794 -136.479553) (xy 413.805389 -136.521958) (xy 413.757813 -136.558464)
			(xy 413.705879 -136.588448) (xy 413.650475 -136.611397) (xy 413.59255 -136.626918) (xy 413.533094 -136.634746)
			(xy 413.473126 -136.634746) (xy 413.41367 -136.626918) (xy 413.355745 -136.611397) (xy 413.300341 -136.588448)
			(xy 413.248407 -136.558464) (xy 413.200831 -136.521958) (xy 413.158426 -136.479553) (xy 413.12192 -136.431977)
			(xy 413.091936 -136.380043) (xy 413.068987 -136.324639) (xy 413.053466 -136.266714) (xy 413.045638 -136.207258)
			(xy 413.045148 -136.177274) (xy 412.56966 -136.177274) (xy 412.56966 -137.029444) (xy 412.570168 -137.036556)
			(xy 412.663894 -137.130282) (xy 412.671292 -137.137131) (xy 412.689889 -137.144871) (xy 412.699962 -137.145268)
			(xy 428.791624 -137.145268) (xy 428.797212 -137.140442) (xy 428.798228 -137.139426) (xy 428.836836 -137.094976)
			(xy 428.849536 -137.080498) (xy 428.855218 -137.073376) (xy 428.861602 -137.056326) (xy 428.861982 -137.047224)
			(xy 428.861982 -137.04189) (xy 428.861728 -137.040112) (xy 428.861728 -137.039858) (xy 428.861474 -137.037826)
			(xy 428.86122 -137.03554) (xy 428.860966 -137.033254) (xy 428.860966 -137.031222) (xy 428.860204 -137.027158)
			(xy 428.85995 -137.024364) (xy 428.85995 -137.02284) (xy 428.859696 -137.021316) (xy 428.859696 -137.020046)
			(xy 428.858934 -137.011918) (xy 428.858934 -137.009886) (xy 428.85868 -137.0076) (xy 428.85868 -137.006838)
			(xy 428.858172 -136.992868) (xy 428.858172 -136.984994) (xy 428.858726 -136.957789) (xy 428.866599 -136.903949)
			(xy 428.882041 -136.851774) (xy 428.904738 -136.802322) (xy 428.934232 -136.756596) (xy 428.969923 -136.715524)
			(xy 429.011086 -136.67994) (xy 429.056888 -136.650565) (xy 429.106399 -136.627995) (xy 429.158614 -136.612688)
			(xy 429.212474 -136.604955) (xy 429.23968 -136.604502) (xy 429.266934 -136.604964) (xy 429.320886 -136.612719)
			(xy 429.373186 -136.628073) (xy 429.422768 -136.650715) (xy 429.468623 -136.680182) (xy 429.509817 -136.715876)
			(xy 429.545512 -136.757069) (xy 429.574981 -136.802923) (xy 429.597623 -136.852505) (xy 429.612979 -136.904804)
			(xy 429.620735 -136.958756) (xy 429.621188 -136.98601) (xy 429.621188 -137.000996) (xy 429.619335 -137.031883)
			(xy 429.606895 -137.092492) (xy 429.584849 -137.150304) (xy 429.553774 -137.203808) (xy 429.534574 -137.228072)
			(xy 429.528732 -137.235184) (xy 429.523144 -137.251694) (xy 429.523144 -137.2616) (xy 429.52416 -137.295128)
			(xy 429.524414 -137.297668) (xy 430.237646 -138.0109) (xy 430.244758 -138.011408) (xy 443.529212 -138.011408)
			(xy 443.536578 -138.0109) (xy 444.308992 -137.238486) (xy 444.332556 -137.215589) (xy 444.38394 -137.174637)
			(xy 444.439583 -137.139691) (xy 444.498786 -137.111191) (xy 444.560807 -137.089494) (xy 444.624866 -137.074873)
			(xy 444.690159 -137.067511) (xy 444.723012 -137.067036) (xy 444.723266 -137.067036) (xy 444.75812 -137.067535)
			(xy 444.827337 -137.075803) (xy 444.895084 -137.092227) (xy 444.960403 -137.116573) (xy 445.022371 -137.148498)
			(xy 445.080113 -137.187552) (xy 445.132813 -137.233181) (xy 445.179725 -137.284742) (xy 445.220188 -137.341506)
			(xy 445.253629 -137.402669) (xy 445.26708 -137.434828) (xy 445.272668 -137.449052) (xy 445.276478 -137.451592)
			(xy 445.28867 -137.459974) (xy 445.292474 -137.462471) (xy 445.300779 -137.466186) (xy 445.30518 -137.46734)
			(xy 445.315086 -137.46988) (xy 445.324992 -137.468356) (xy 445.33743 -137.466561) (xy 445.362469 -137.4644)
			(xy 445.37503 -137.464038) (xy 445.383158 -137.464038) (xy 445.414914 -137.464671) (xy 445.477551 -137.475177)
			(xy 445.537591 -137.495892) (xy 445.565784 -137.51052) (xy 445.574928 -137.5156) (xy 445.586612 -137.518902)
			(xy 445.591782 -137.520178) (xy 445.602409 -137.520821) (xy 445.607694 -137.520172) (xy 445.632332 -137.495534)
			(xy 445.655896 -137.472636) (xy 445.70728 -137.431682) (xy 445.762922 -137.396734) (xy 445.822126 -137.36823)
			(xy 445.884146 -137.346529) (xy 445.948205 -137.331903) (xy 446.013498 -137.324535) (xy 446.046352 -137.324084)
			(xy 446.046606 -137.324084) (xy 446.081529 -137.324589) (xy 446.150881 -137.33289) (xy 446.218755 -137.349372)
			(xy 446.28419 -137.373804) (xy 446.346258 -137.405837) (xy 446.404079 -137.44502) (xy 446.456835 -137.490795)
			(xy 446.503778 -137.542515) (xy 446.52438 -137.570718) (xy 446.52438 -137.571226) (xy 446.533524 -137.583672)
			(xy 446.536705 -137.585477) (xy 446.543462 -137.588279) (xy 446.546986 -137.58926) (xy 446.54724 -137.58926)
			(xy 446.560702 -137.592562) (xy 446.56121 -137.592562) (xy 446.569846 -137.594594) (xy 446.575927 -137.59566)
			(xy 446.588259 -137.595148) (xy 446.59423 -137.593578) (xy 446.60058 -137.591546) (xy 446.603374 -137.590276)
			(xy 446.630107 -137.577414) (xy 446.686566 -137.559208) (xy 446.745164 -137.549963) (xy 446.774824 -137.549382)
			(xy 446.775078 -137.549382) (xy 446.801608 -137.549842) (xy 446.854156 -137.557198) (xy 446.90518 -137.571757)
			(xy 446.953697 -137.593239) (xy 446.998774 -137.62123) (xy 447.039542 -137.655192) (xy 447.075216 -137.69447)
			(xy 447.105109 -137.738308) (xy 447.128647 -137.785863) (xy 447.145374 -137.836217) (xy 447.154971 -137.888403)
			(xy 447.156586 -137.914888) (xy 447.157348 -137.921492) (xy 447.158651 -137.927867) (xy 447.164059 -137.939695)
			(xy 447.168016 -137.94486) (xy 447.172334 -137.949432) (xy 447.191638 -137.96772) (xy 447.222118 -137.99693)
			(xy 447.226944 -138.000994) (xy 447.227198 -138.001248) (xy 447.233938 -138.005919) (xy 447.249484 -138.011107)
			(xy 447.257678 -138.011408) (xy 460.030576 -138.011408) (xy 460.040228 -138.010392) (xy 460.047474 -138.008768)
			(xy 460.06065 -138.001934) (xy 460.066136 -137.99693) (xy 460.951834 -137.111232) (xy 460.956814 -137.10573)
			(xy 460.963643 -137.09256) (xy 460.965296 -137.085324) (xy 460.966312 -137.075672) (xy 460.966312 -75.56246)
			(xy 460.966743 -75.552393) (xy 460.974469 -75.533801) (xy 460.981298 -75.526392) (xy 464.807046 -71.700644)
			(xy 464.812027 -71.695142) (xy 464.818857 -71.681973) (xy 464.820508 -71.674736) (xy 464.821524 -71.665084)
			(xy 464.821524 -2.384806) (xy 464.821103 -2.374735) (xy 464.813393 -2.356126) (xy 464.806538 -2.348738)
			(xy 464.098386 -1.640586) (xy 464.090991 -1.633732) (xy 464.072392 -1.62599) (xy 464.062318 -1.6256)
			(xy 445.505586 -1.6256) (xy 445.47028 -1.639824) (xy 445.448806 -1.659707) (xy 445.400938 -1.693371)
			(xy 445.348495 -1.719338) (xy 445.292704 -1.737) (xy 445.234872 -1.745944) (xy 445.205612 -1.746504)
			(xy 445.20485 -1.746504) (xy 445.172319 -1.745803) (xy 445.10821 -1.734696) (xy 445.077342 -1.724406)
			(xy 445.060324 -1.721358) (xy 445.050261 -1.721797) (xy 445.031682 -1.729537) (xy 445.024256 -1.736344)
			(xy 444.78829 -1.97231) (xy 444.781435 -1.979705) (xy 444.77369 -1.998304) (xy 444.773304 -2.008378)
			(xy 444.773304 -11.850116) (xy 444.772834 -11.903966) (xy 444.76515 -12.01139) (xy 444.749821 -12.117993)
			(xy 444.726927 -12.223231) (xy 444.696583 -12.326567) (xy 444.658944 -12.427475) (xy 444.614203 -12.525441)
			(xy 444.562586 -12.619966) (xy 444.504358 -12.710567) (xy 444.439815 -12.796783) (xy 444.369285 -12.878175)
			(xy 444.293129 -12.954329) (xy 444.211733 -13.024855) (xy 444.125514 -13.089395) (xy 444.03491 -13.147619)
			(xy 443.940384 -13.199231) (xy 443.842416 -13.243969) (xy 443.741506 -13.281603) (xy 443.638169 -13.311942)
			(xy 443.53293 -13.334833) (xy 443.426327 -13.350157) (xy 443.318902 -13.357836) (xy 443.265052 -13.358368)
			(xy 435.265068 -13.358368) (xy 435.211218 -13.357887) (xy 435.103794 -13.350201) (xy 434.997191 -13.334872)
			(xy 434.891953 -13.311977) (xy 434.788617 -13.281633) (xy 434.687708 -13.243995) (xy 434.589742 -13.199254)
			(xy 434.495217 -13.147638) (xy 434.404615 -13.08941) (xy 434.318398 -13.024868) (xy 434.237005 -12.954339)
			(xy 434.16085 -12.878184) (xy 434.090322 -12.79679) (xy 434.025781 -12.710572) (xy 433.967554 -12.619969)
			(xy 433.915939 -12.525444) (xy 433.871199 -12.427477) (xy 433.833562 -12.326568) (xy 433.803219 -12.223232)
			(xy 433.780325 -12.117994) (xy 433.764997 -12.011391) (xy 433.757313 -11.903966) (xy 433.756816 -11.850116)
			(xy 433.756816 -3.357118) (xy 433.7564 -3.347093) (xy 433.748734 -3.328567) (xy 433.734561 -3.314386)
			(xy 433.716041 -3.306707) (xy 433.706016 -3.306318) (xy 418.824156 -3.306318) (xy 418.814156 -3.306814)
			(xy 418.795682 -3.314482) (xy 418.781547 -3.328634) (xy 418.773902 -3.347117) (xy 418.773356 -3.357118)
			(xy 418.773356 -11.850116) (xy 418.772875 -11.903966) (xy 418.765191 -12.011391) (xy 418.749863 -12.117995)
			(xy 418.726968 -12.223233) (xy 418.696625 -12.32657) (xy 418.658987 -12.427479) (xy 418.614246 -12.525446)
			(xy 418.562631 -12.619971) (xy 418.504403 -12.710574) (xy 418.439861 -12.796791) (xy 418.369332 -12.878185)
			(xy 418.293176 -12.95434) (xy 418.211782 -13.024868) (xy 418.125564 -13.08941) (xy 418.034961 -13.147637)
			(xy 417.940435 -13.199252) (xy 417.842468 -13.243992) (xy 417.741558 -13.281629) (xy 417.638221 -13.311971)
			(xy 417.532983 -13.334865) (xy 417.426379 -13.350192) (xy 417.318954 -13.357876) (xy 417.265104 -13.358368)
			(xy 409.26512 -13.358368) (xy 409.211269 -13.357899) (xy 409.103841 -13.350217) (xy 408.997234 -13.334891)
			(xy 408.891993 -13.311999) (xy 408.788652 -13.281657) (xy 408.68774 -13.24402) (xy 408.58977 -13.19928)
			(xy 408.495241 -13.147665) (xy 408.404635 -13.089437) (xy 408.318414 -13.024895) (xy 408.237017 -12.954366)
			(xy 408.160859 -12.878209) (xy 408.090328 -12.796814) (xy 408.025783 -12.710594) (xy 407.967554 -12.61999)
			(xy 407.915936 -12.525462) (xy 407.871194 -12.427493) (xy 407.833555 -12.326582) (xy 407.80321 -12.223242)
			(xy 407.780315 -12.118001) (xy 407.764986 -12.011395) (xy 407.757302 -11.903967) (xy 407.756868 -11.850116)
			(xy 407.756868 -1.88595) (xy 407.756435 -1.875885) (xy 407.748704 -1.857296) (xy 407.741882 -1.849882)
			(xy 407.405586 -1.513586) (xy 407.398191 -1.506732) (xy 407.379592 -1.49899) (xy 407.369518 -1.4986)
			(xy 393.340082 -1.4986) (xy 393.330013 -1.499027) (xy 393.311414 -1.506746) (xy 393.304014 -1.513586)
			(xy 392.78814 -2.02946) (xy 392.781299 -2.03686) (xy 392.77358 -2.055458) (xy 392.773154 -2.065528)
			(xy 392.773154 -11.850116) (xy 392.772673 -11.903966) (xy 392.764989 -12.011391) (xy 392.749661 -12.117994)
			(xy 392.726766 -12.223233) (xy 392.696423 -12.32657) (xy 392.658785 -12.427479) (xy 392.614044 -12.525445)
			(xy 392.562429 -12.619971) (xy 392.504201 -12.710573) (xy 392.439659 -12.796791) (xy 392.36913 -12.878185)
			(xy 392.292974 -12.954339) (xy 392.21158 -13.024867) (xy 392.125362 -13.089409) (xy 392.034759 -13.147636)
			(xy 391.940233 -13.19925) (xy 391.842266 -13.24399) (xy 391.741356 -13.281627) (xy 391.638019 -13.31197)
			(xy 391.532781 -13.334863) (xy 391.426177 -13.35019) (xy 391.318752 -13.357874) (xy 391.264902 -13.358368)
			(xy 383.264918 -13.358368) (xy 383.211067 -13.357899) (xy 383.103639 -13.350217) (xy 382.997032 -13.334891)
			(xy 382.891791 -13.311998) (xy 382.788451 -13.281656) (xy 382.687539 -13.244019) (xy 382.589569 -13.199279)
			(xy 382.49504 -13.147664) (xy 382.404434 -13.089437) (xy 382.318213 -13.024894) (xy 382.236816 -12.954365)
			(xy 382.160658 -12.878209) (xy 382.090127 -12.796813) (xy 382.025583 -12.710594) (xy 381.967353 -12.619989)
			(xy 381.915736 -12.525462) (xy 381.870994 -12.427493) (xy 381.833355 -12.326581) (xy 381.80301 -12.223242)
			(xy 381.780115 -12.118001) (xy 381.764786 -12.011395) (xy 381.757102 -11.903967) (xy 381.756666 -11.850116)
			(xy 381.756666 -3.357118) (xy 381.756249 -3.347097) (xy 381.748581 -3.32858) (xy 381.734407 -3.31441)
			(xy 381.715887 -3.306748) (xy 381.705866 -3.306318) (xy 366.824006 -3.306318) (xy 366.813985 -3.306737)
			(xy 366.795469 -3.314406) (xy 366.781299 -3.328579) (xy 366.773634 -3.347097) (xy 366.773206 -3.357118)
			(xy 366.773206 -4.48183) (xy 377.965206 -4.48183) (xy 377.969277 -4.426208) (xy 377.981403 -4.371771)
			(xy 378.001326 -4.31968) (xy 378.028622 -4.271045) (xy 378.062708 -4.226902) (xy 378.102857 -4.188193)
			(xy 378.148215 -4.155742) (xy 378.197815 -4.130241) (xy 378.250599 -4.112234) (xy 378.305442 -4.102104)
			(xy 378.361176 -4.100067) (xy 378.416613 -4.106167) (xy 378.47057 -4.120273) (xy 378.521899 -4.142085)
			(xy 378.569505 -4.171139) (xy 378.612373 -4.206814) (xy 378.64959 -4.248351) (xy 378.680363 -4.294864)
			(xy 378.704035 -4.345361) (xy 378.720103 -4.398768) (xy 378.728223 -4.453944) (xy 378.728732 -4.48183)
			(xy 378.728223 -4.509716) (xy 378.720103 -4.564892) (xy 378.704035 -4.618299) (xy 378.680363 -4.668796)
			(xy 378.64959 -4.715309) (xy 378.612373 -4.756846) (xy 378.569505 -4.792521) (xy 378.521899 -4.821575)
			(xy 378.485784 -4.836922) (xy 380.267716 -4.836922) (xy 380.271787 -4.7813) (xy 380.283913 -4.726863)
			(xy 380.303836 -4.674772) (xy 380.331132 -4.626137) (xy 380.365218 -4.581994) (xy 380.405367 -4.543285)
			(xy 380.450725 -4.510834) (xy 380.500325 -4.485333) (xy 380.553109 -4.467326) (xy 380.607952 -4.457196)
			(xy 380.663686 -4.455159) (xy 380.719123 -4.461259) (xy 380.77308 -4.475365) (xy 380.824409 -4.497177)
			(xy 380.872015 -4.526231) (xy 380.914883 -4.561906) (xy 380.9521 -4.603443) (xy 380.982873 -4.649956)
			(xy 381.006545 -4.700453) (xy 381.022613 -4.75386) (xy 381.030733 -4.809036) (xy 381.031242 -4.836922)
			(xy 381.030733 -4.864808) (xy 381.022613 -4.919984) (xy 381.006545 -4.973391) (xy 380.982873 -5.023888)
			(xy 380.9521 -5.070401) (xy 380.914883 -5.111938) (xy 380.872015 -5.147613) (xy 380.824409 -5.176667)
			(xy 380.77308 -5.198479) (xy 380.719123 -5.212585) (xy 380.663686 -5.218685) (xy 380.607952 -5.216648)
			(xy 380.553109 -5.206518) (xy 380.500325 -5.188511) (xy 380.450725 -5.16301) (xy 380.405367 -5.130559)
			(xy 380.365218 -5.09185) (xy 380.331132 -5.047707) (xy 380.303836 -4.999072) (xy 380.283913 -4.946981)
			(xy 380.271787 -4.892544) (xy 380.267716 -4.836922) (xy 378.485784 -4.836922) (xy 378.47057 -4.843387)
			(xy 378.416613 -4.857493) (xy 378.361176 -4.863593) (xy 378.305442 -4.861556) (xy 378.250599 -4.851426)
			(xy 378.197815 -4.833419) (xy 378.148215 -4.807918) (xy 378.102857 -4.775467) (xy 378.062708 -4.736758)
			(xy 378.028622 -4.692615) (xy 378.001326 -4.64398) (xy 377.981403 -4.591889) (xy 377.969277 -4.537452)
			(xy 377.965206 -4.48183) (xy 366.773206 -4.48183) (xy 366.773206 -5.852922) (xy 378.220984 -5.852922)
			(xy 378.225055 -5.7973) (xy 378.237181 -5.742863) (xy 378.257104 -5.690772) (xy 378.2844 -5.642137)
			(xy 378.318486 -5.597994) (xy 378.358635 -5.559285) (xy 378.403993 -5.526834) (xy 378.453593 -5.501333)
			(xy 378.506377 -5.483326) (xy 378.56122 -5.473196) (xy 378.616954 -5.471159) (xy 378.672391 -5.477259)
			(xy 378.726348 -5.491365) (xy 378.777677 -5.513177) (xy 378.825283 -5.542231) (xy 378.868151 -5.577906)
			(xy 378.905368 -5.619443) (xy 378.936141 -5.665956) (xy 378.959813 -5.716453) (xy 378.975881 -5.76986)
			(xy 378.984001 -5.825036) (xy 378.98451 -5.852922) (xy 380.267716 -5.852922) (xy 380.271787 -5.7973)
			(xy 380.283913 -5.742863) (xy 380.303836 -5.690772) (xy 380.331132 -5.642137) (xy 380.365218 -5.597994)
			(xy 380.405367 -5.559285) (xy 380.450725 -5.526834) (xy 380.500325 -5.501333) (xy 380.553109 -5.483326)
			(xy 380.607952 -5.473196) (xy 380.663686 -5.471159) (xy 380.719123 -5.477259) (xy 380.77308 -5.491365)
			(xy 380.824409 -5.513177) (xy 380.872015 -5.542231) (xy 380.914883 -5.577906) (xy 380.9521 -5.619443)
			(xy 380.982873 -5.665956) (xy 381.006545 -5.716453) (xy 381.022613 -5.76986) (xy 381.030733 -5.825036)
			(xy 381.031242 -5.852922) (xy 381.030733 -5.880808) (xy 381.022613 -5.935984) (xy 381.006545 -5.989391)
			(xy 380.982873 -6.039888) (xy 380.9521 -6.086401) (xy 380.914883 -6.127938) (xy 380.872015 -6.163613)
			(xy 380.824409 -6.192667) (xy 380.77308 -6.214479) (xy 380.719123 -6.228585) (xy 380.663686 -6.234685)
			(xy 380.607952 -6.232648) (xy 380.553109 -6.222518) (xy 380.500325 -6.204511) (xy 380.450725 -6.17901)
			(xy 380.405367 -6.146559) (xy 380.365218 -6.10785) (xy 380.331132 -6.063707) (xy 380.303836 -6.015072)
			(xy 380.283913 -5.962981) (xy 380.271787 -5.908544) (xy 380.267716 -5.852922) (xy 378.98451 -5.852922)
			(xy 378.984001 -5.880808) (xy 378.975881 -5.935984) (xy 378.959813 -5.989391) (xy 378.936141 -6.039888)
			(xy 378.905368 -6.086401) (xy 378.868151 -6.127938) (xy 378.825283 -6.163613) (xy 378.777677 -6.192667)
			(xy 378.726348 -6.214479) (xy 378.672391 -6.228585) (xy 378.616954 -6.234685) (xy 378.56122 -6.232648)
			(xy 378.506377 -6.222518) (xy 378.453593 -6.204511) (xy 378.403993 -6.17901) (xy 378.358635 -6.146559)
			(xy 378.318486 -6.10785) (xy 378.2844 -6.063707) (xy 378.257104 -6.015072) (xy 378.237181 -5.962981)
			(xy 378.225055 -5.908544) (xy 378.220984 -5.852922) (xy 366.773206 -5.852922) (xy 366.773206 -6.71195)
			(xy 369.906548 -6.71195) (xy 369.910619 -6.656328) (xy 369.922745 -6.601891) (xy 369.942668 -6.5498)
			(xy 369.969964 -6.501165) (xy 370.00405 -6.457022) (xy 370.044199 -6.418313) (xy 370.089557 -6.385862)
			(xy 370.139157 -6.360361) (xy 370.191941 -6.342354) (xy 370.246784 -6.332224) (xy 370.302518 -6.330187)
			(xy 370.357955 -6.336287) (xy 370.411912 -6.350393) (xy 370.463241 -6.372205) (xy 370.510847 -6.401259)
			(xy 370.553715 -6.436934) (xy 370.590932 -6.478471) (xy 370.621705 -6.524984) (xy 370.645377 -6.575481)
			(xy 370.661445 -6.628888) (xy 370.669565 -6.684064) (xy 370.670074 -6.71195) (xy 370.669565 -6.739836)
			(xy 370.661445 -6.795012) (xy 370.645377 -6.848419) (xy 370.621705 -6.898916) (xy 370.590932 -6.945429)
			(xy 370.553715 -6.986966) (xy 370.510847 -7.022641) (xy 370.463241 -7.051695) (xy 370.411912 -7.073507)
			(xy 370.357955 -7.087613) (xy 370.302518 -7.093713) (xy 370.246784 -7.091676) (xy 370.191941 -7.081546)
			(xy 370.139157 -7.063539) (xy 370.089557 -7.038038) (xy 370.044199 -7.005587) (xy 370.00405 -6.966878)
			(xy 369.969964 -6.922735) (xy 369.942668 -6.8741) (xy 369.922745 -6.822009) (xy 369.910619 -6.767572)
			(xy 369.906548 -6.71195) (xy 366.773206 -6.71195) (xy 366.773206 -7.473696) (xy 378.034548 -7.473696)
			(xy 378.038619 -7.418074) (xy 378.050745 -7.363637) (xy 378.070668 -7.311546) (xy 378.097964 -7.262911)
			(xy 378.13205 -7.218768) (xy 378.172199 -7.180059) (xy 378.217557 -7.147608) (xy 378.267157 -7.122107)
			(xy 378.319941 -7.1041) (xy 378.374784 -7.09397) (xy 378.430518 -7.091933) (xy 378.485955 -7.098033)
			(xy 378.539912 -7.112139) (xy 378.591241 -7.133951) (xy 378.638847 -7.163005) (xy 378.681715 -7.19868)
			(xy 378.718932 -7.240217) (xy 378.749705 -7.28673) (xy 378.773377 -7.337227) (xy 378.789445 -7.390634)
			(xy 378.797565 -7.44581) (xy 378.798074 -7.473696) (xy 378.797565 -7.501582) (xy 378.789445 -7.556758)
			(xy 378.773377 -7.610165) (xy 378.749705 -7.660662) (xy 378.718932 -7.707175) (xy 378.681715 -7.748712)
			(xy 378.638847 -7.784387) (xy 378.591241 -7.813441) (xy 378.539912 -7.835253) (xy 378.485955 -7.849359)
			(xy 378.430518 -7.855459) (xy 378.374784 -7.853422) (xy 378.319941 -7.843292) (xy 378.267157 -7.825285)
			(xy 378.217557 -7.799784) (xy 378.172199 -7.767333) (xy 378.13205 -7.728624) (xy 378.097964 -7.684481)
			(xy 378.070668 -7.635846) (xy 378.050745 -7.583755) (xy 378.038619 -7.529318) (xy 378.034548 -7.473696)
			(xy 366.773206 -7.473696) (xy 366.773206 -8.005572) (xy 369.78412 -8.005572) (xy 369.788191 -7.94995)
			(xy 369.800317 -7.895513) (xy 369.82024 -7.843422) (xy 369.847536 -7.794787) (xy 369.881622 -7.750644)
			(xy 369.921771 -7.711935) (xy 369.967129 -7.679484) (xy 370.016729 -7.653983) (xy 370.069513 -7.635976)
			(xy 370.124356 -7.625846) (xy 370.18009 -7.623809) (xy 370.235527 -7.629909) (xy 370.289484 -7.644015)
			(xy 370.340813 -7.665827) (xy 370.388419 -7.694881) (xy 370.431287 -7.730556) (xy 370.468504 -7.772093)
			(xy 370.499277 -7.818606) (xy 370.522949 -7.869103) (xy 370.527708 -7.884922) (xy 380.267716 -7.884922)
			(xy 380.271787 -7.8293) (xy 380.283913 -7.774863) (xy 380.303836 -7.722772) (xy 380.331132 -7.674137)
			(xy 380.365218 -7.629994) (xy 380.405367 -7.591285) (xy 380.450725 -7.558834) (xy 380.500325 -7.533333)
			(xy 380.553109 -7.515326) (xy 380.607952 -7.505196) (xy 380.663686 -7.503159) (xy 380.719123 -7.509259)
			(xy 380.77308 -7.523365) (xy 380.824409 -7.545177) (xy 380.872015 -7.574231) (xy 380.914883 -7.609906)
			(xy 380.9521 -7.651443) (xy 380.982873 -7.697956) (xy 381.006545 -7.748453) (xy 381.022613 -7.80186)
			(xy 381.030733 -7.857036) (xy 381.031242 -7.884922) (xy 381.030733 -7.912808) (xy 381.022613 -7.967984)
			(xy 381.006545 -8.021391) (xy 380.982873 -8.071888) (xy 380.9521 -8.118401) (xy 380.914883 -8.159938)
			(xy 380.872015 -8.195613) (xy 380.824409 -8.224667) (xy 380.77308 -8.246479) (xy 380.719123 -8.260585)
			(xy 380.663686 -8.266685) (xy 380.607952 -8.264648) (xy 380.553109 -8.254518) (xy 380.500325 -8.236511)
			(xy 380.450725 -8.21101) (xy 380.405367 -8.178559) (xy 380.365218 -8.13985) (xy 380.331132 -8.095707)
			(xy 380.303836 -8.047072) (xy 380.283913 -7.994981) (xy 380.271787 -7.940544) (xy 380.267716 -7.884922)
			(xy 370.527708 -7.884922) (xy 370.539017 -7.92251) (xy 370.547137 -7.977686) (xy 370.547646 -8.005572)
			(xy 370.547137 -8.033458) (xy 370.539017 -8.088634) (xy 370.522949 -8.142041) (xy 370.499277 -8.192538)
			(xy 370.468504 -8.239051) (xy 370.431287 -8.280588) (xy 370.388419 -8.316263) (xy 370.340813 -8.345317)
			(xy 370.289484 -8.367129) (xy 370.235527 -8.381235) (xy 370.18009 -8.387335) (xy 370.124356 -8.385298)
			(xy 370.069513 -8.375168) (xy 370.016729 -8.357161) (xy 369.967129 -8.33166) (xy 369.921771 -8.299209)
			(xy 369.881622 -8.2605) (xy 369.847536 -8.216357) (xy 369.82024 -8.167722) (xy 369.800317 -8.115631)
			(xy 369.788191 -8.061194) (xy 369.78412 -8.005572) (xy 366.773206 -8.005572) (xy 366.773206 -8.72115)
			(xy 367.83899 -8.72115) (xy 367.83899 -8.66665) (xy 367.846746 -8.612705) (xy 367.8621 -8.560413)
			(xy 367.88474 -8.510838) (xy 367.914204 -8.464989) (xy 367.949894 -8.423801) (xy 367.991081 -8.38811)
			(xy 368.036929 -8.358645) (xy 368.086503 -8.336004) (xy 368.138795 -8.320648) (xy 368.19274 -8.312891)
			(xy 368.21999 -8.312404) (xy 368.247564 -8.312875) (xy 368.302137 -8.320826) (xy 368.354997 -8.33655)
			(xy 368.405043 -8.359719) (xy 368.451233 -8.389851) (xy 368.492604 -8.426317) (xy 368.51082 -8.447024)
			(xy 368.51989 -8.456921) (xy 368.54202 -8.472092) (xy 368.567338 -8.480975) (xy 368.594096 -8.482959)
			(xy 368.620447 -8.477904) (xy 368.644572 -8.466161) (xy 368.664807 -8.448541) (xy 368.672618 -8.437626)
			(xy 368.687907 -8.415612) (xy 368.723579 -8.375614) (xy 368.764497 -8.341) (xy 368.809855 -8.312452)
			(xy 368.858762 -8.290531) (xy 368.910255 -8.27567) (xy 368.963321 -8.268159) (xy 368.990118 -8.2677)
			(xy 369.017369 -8.268171) (xy 369.071316 -8.27593) (xy 369.12361 -8.291287) (xy 369.173186 -8.313929)
			(xy 369.219035 -8.343397) (xy 369.260224 -8.379089) (xy 369.295914 -8.42028) (xy 369.325379 -8.46613)
			(xy 369.34802 -8.515707) (xy 369.363374 -8.568002) (xy 369.37113 -8.621949) (xy 369.37113 -8.676451)
			(xy 369.363374 -8.730398) (xy 369.34802 -8.782693) (xy 369.325379 -8.83227) (xy 369.295914 -8.87812)
			(xy 369.260224 -8.919311) (xy 369.219035 -8.955003) (xy 369.173186 -8.984471) (xy 369.12361 -9.007113)
			(xy 369.071316 -9.02247) (xy 369.017369 -9.030229) (xy 368.990118 -9.030716) (xy 368.962544 -9.030232)
			(xy 368.907972 -9.022283) (xy 368.855113 -9.006561) (xy 368.805067 -8.983394) (xy 368.758877 -8.953265)
			(xy 368.717505 -8.916801) (xy 368.699288 -8.896096) (xy 368.69032 -8.886099) (xy 368.668165 -8.870927)
			(xy 368.642823 -8.86205) (xy 368.616044 -8.86008) (xy 368.589676 -8.865153) (xy 368.565539 -8.876919)
			(xy 368.5453 -8.894566) (xy 368.53749 -8.905494) (xy 368.522266 -8.927555) (xy 368.486583 -8.967552)
			(xy 368.445653 -9.002161) (xy 368.400284 -9.030704) (xy 368.351366 -9.052616) (xy 368.299864 -9.067468)
			(xy 368.24679 -9.074967) (xy 368.21999 -9.07542) (xy 368.19274 -9.074909) (xy 368.138795 -9.067152)
			(xy 368.086503 -9.051796) (xy 368.036929 -9.029155) (xy 367.991081 -8.99969) (xy 367.949894 -8.963999)
			(xy 367.914204 -8.922811) (xy 367.88474 -8.876962) (xy 367.8621 -8.827387) (xy 367.846746 -8.775095)
			(xy 367.83899 -8.72115) (xy 366.773206 -8.72115) (xy 366.773206 -10.35812) (xy 375.53087 -10.35812)
			(xy 375.534941 -10.302498) (xy 375.547067 -10.248061) (xy 375.56699 -10.19597) (xy 375.594286 -10.147335)
			(xy 375.628372 -10.103192) (xy 375.668521 -10.064483) (xy 375.713879 -10.032032) (xy 375.763479 -10.006531)
			(xy 375.816263 -9.988524) (xy 375.871106 -9.978394) (xy 375.92684 -9.976357) (xy 375.982277 -9.982457)
			(xy 376.036234 -9.996563) (xy 376.087563 -10.018375) (xy 376.135169 -10.047429) (xy 376.178037 -10.083104)
			(xy 376.215254 -10.124641) (xy 376.246027 -10.171154) (xy 376.269699 -10.221651) (xy 376.285767 -10.275058)
			(xy 376.293887 -10.330234) (xy 376.294396 -10.35812) (xy 376.293887 -10.386006) (xy 376.285767 -10.441182)
			(xy 376.269699 -10.494589) (xy 376.246027 -10.545086) (xy 376.215254 -10.591599) (xy 376.178037 -10.633136)
			(xy 376.135169 -10.668811) (xy 376.087563 -10.697865) (xy 376.036234 -10.719677) (xy 375.982277 -10.733783)
			(xy 375.92684 -10.739883) (xy 375.871106 -10.737846) (xy 375.816263 -10.727716) (xy 375.763479 -10.709709)
			(xy 375.713879 -10.684208) (xy 375.668521 -10.651757) (xy 375.628372 -10.613048) (xy 375.594286 -10.568905)
			(xy 375.56699 -10.52027) (xy 375.547067 -10.468179) (xy 375.534941 -10.413742) (xy 375.53087 -10.35812)
			(xy 366.773206 -10.35812) (xy 366.773206 -10.954512) (xy 369.191284 -10.954512) (xy 369.195355 -10.89889)
			(xy 369.207481 -10.844453) (xy 369.227404 -10.792362) (xy 369.2547 -10.743727) (xy 369.288786 -10.699584)
			(xy 369.328935 -10.660875) (xy 369.374293 -10.628424) (xy 369.423893 -10.602923) (xy 369.476677 -10.584916)
			(xy 369.53152 -10.574786) (xy 369.587254 -10.572749) (xy 369.642691 -10.578849) (xy 369.696648 -10.592955)
			(xy 369.747977 -10.614767) (xy 369.795583 -10.643821) (xy 369.838451 -10.679496) (xy 369.875668 -10.721033)
			(xy 369.906441 -10.767546) (xy 369.930113 -10.818043) (xy 369.946181 -10.87145) (xy 369.954301 -10.926626)
			(xy 369.95481 -10.954512) (xy 369.954301 -10.982398) (xy 369.946181 -11.037574) (xy 369.930113 -11.090981)
			(xy 369.906441 -11.141478) (xy 369.875668 -11.187991) (xy 369.838451 -11.229528) (xy 369.795583 -11.265203)
			(xy 369.747977 -11.294257) (xy 369.696648 -11.316069) (xy 369.642691 -11.330175) (xy 369.587254 -11.336275)
			(xy 369.53152 -11.334238) (xy 369.476677 -11.324108) (xy 369.423893 -11.306101) (xy 369.374293 -11.2806)
			(xy 369.328935 -11.248149) (xy 369.288786 -11.20944) (xy 369.2547 -11.165297) (xy 369.227404 -11.116662)
			(xy 369.207481 -11.064571) (xy 369.195355 -11.010134) (xy 369.191284 -10.954512) (xy 366.773206 -10.954512)
			(xy 366.773206 -11.850116) (xy 366.772736 -11.903966) (xy 366.765052 -12.01139) (xy 366.749723 -12.117993)
			(xy 366.726829 -12.223231) (xy 366.696485 -12.326567) (xy 366.658846 -12.427475) (xy 366.614105 -12.525441)
			(xy 366.562488 -12.619966) (xy 366.50426 -12.710567) (xy 366.439717 -12.796784) (xy 366.369187 -12.878176)
			(xy 366.293031 -12.954329) (xy 366.211635 -13.024856) (xy 366.125416 -13.089396) (xy 366.034813 -13.14762)
			(xy 365.940286 -13.199233) (xy 365.842318 -13.24397) (xy 365.741408 -13.281604) (xy 365.638071 -13.311944)
			(xy 365.532832 -13.334834) (xy 365.426229 -13.350158) (xy 365.318804 -13.357838) (xy 365.264954 -13.358368)
			(xy 357.26497 -13.358368) (xy 357.21112 -13.357887) (xy 357.103695 -13.350201) (xy 356.997092 -13.334872)
			(xy 356.891855 -13.311978) (xy 356.788518 -13.281634) (xy 356.68761 -13.243995) (xy 356.589643 -13.199254)
			(xy 356.495118 -13.147638) (xy 356.404516 -13.089411) (xy 356.318299 -13.024868) (xy 356.236905 -12.95434)
			(xy 356.160751 -12.878184) (xy 356.090223 -12.79679) (xy 356.025681 -12.710572) (xy 355.967455 -12.61997)
			(xy 355.91584 -12.525444) (xy 355.871099 -12.427477) (xy 355.833462 -12.326569) (xy 355.803119 -12.223232)
			(xy 355.780225 -12.117994) (xy 355.764897 -12.011391) (xy 355.757213 -11.903966) (xy 355.756718 -11.850116)
			(xy 355.756718 -3.357118) (xy 355.756234 -3.347107) (xy 355.748578 -3.328605) (xy 355.734425 -3.314442)
			(xy 355.715929 -3.306774) (xy 355.705918 -3.306318) (xy 328.724006 -3.306318) (xy 328.713985 -3.306737)
			(xy 328.695469 -3.314406) (xy 328.681299 -3.328579) (xy 328.673634 -3.347097) (xy 328.673206 -3.357118)
			(xy 328.673206 -5.776468) (xy 335.944462 -5.776468) (xy 335.948533 -5.720846) (xy 335.960659 -5.666409)
			(xy 335.980582 -5.614318) (xy 336.007878 -5.565683) (xy 336.041964 -5.52154) (xy 336.082113 -5.482831)
			(xy 336.127471 -5.45038) (xy 336.177071 -5.424879) (xy 336.229855 -5.406872) (xy 336.284698 -5.396742)
			(xy 336.340432 -5.394705) (xy 336.395869 -5.400805) (xy 336.449826 -5.414911) (xy 336.501155 -5.436723)
			(xy 336.548761 -5.465777) (xy 336.591629 -5.501452) (xy 336.628846 -5.542989) (xy 336.659619 -5.589502)
			(xy 336.683291 -5.639999) (xy 336.699359 -5.693406) (xy 336.707284 -5.747258) (xy 339.126066 -5.747258)
			(xy 339.130137 -5.691636) (xy 339.142263 -5.637199) (xy 339.162186 -5.585108) (xy 339.189482 -5.536473)
			(xy 339.223568 -5.49233) (xy 339.263717 -5.453621) (xy 339.309075 -5.42117) (xy 339.358675 -5.395669)
			(xy 339.411459 -5.377662) (xy 339.466302 -5.367532) (xy 339.522036 -5.365495) (xy 339.577473 -5.371595)
			(xy 339.63143 -5.385701) (xy 339.682759 -5.407513) (xy 339.730365 -5.436567) (xy 339.773233 -5.472242)
			(xy 339.81045 -5.513779) (xy 339.841223 -5.560292) (xy 339.864895 -5.610789) (xy 339.880963 -5.664196)
			(xy 339.889083 -5.719372) (xy 339.889592 -5.747258) (xy 339.889083 -5.775144) (xy 339.880963 -5.83032)
			(xy 339.864895 -5.883727) (xy 339.841223 -5.934224) (xy 339.81045 -5.980737) (xy 339.773233 -6.022274)
			(xy 339.730365 -6.057949) (xy 339.682759 -6.087003) (xy 339.63143 -6.108815) (xy 339.577473 -6.122921)
			(xy 339.522036 -6.129021) (xy 339.466302 -6.126984) (xy 339.411459 -6.116854) (xy 339.358675 -6.098847)
			(xy 339.309075 -6.073346) (xy 339.263717 -6.040895) (xy 339.223568 -6.002186) (xy 339.189482 -5.958043)
			(xy 339.162186 -5.909408) (xy 339.142263 -5.857317) (xy 339.130137 -5.80288) (xy 339.126066 -5.747258)
			(xy 336.707284 -5.747258) (xy 336.707479 -5.748582) (xy 336.707988 -5.776468) (xy 336.707479 -5.804354)
			(xy 336.699359 -5.85953) (xy 336.683291 -5.912937) (xy 336.659619 -5.963434) (xy 336.628846 -6.009947)
			(xy 336.591629 -6.051484) (xy 336.548761 -6.087159) (xy 336.501155 -6.116213) (xy 336.449826 -6.138025)
			(xy 336.395869 -6.152131) (xy 336.340432 -6.158231) (xy 336.284698 -6.156194) (xy 336.229855 -6.146064)
			(xy 336.177071 -6.128057) (xy 336.127471 -6.102556) (xy 336.082113 -6.070105) (xy 336.041964 -6.031396)
			(xy 336.007878 -5.987253) (xy 335.980582 -5.938618) (xy 335.960659 -5.886527) (xy 335.948533 -5.83209)
			(xy 335.944462 -5.776468) (xy 328.673206 -5.776468) (xy 328.673206 -6.68655) (xy 330.361288 -6.68655)
			(xy 330.365359 -6.630928) (xy 330.377485 -6.576491) (xy 330.397408 -6.5244) (xy 330.424704 -6.475765)
			(xy 330.45879 -6.431622) (xy 330.498939 -6.392913) (xy 330.544297 -6.360462) (xy 330.593897 -6.334961)
			(xy 330.646681 -6.316954) (xy 330.701524 -6.306824) (xy 330.757258 -6.304787) (xy 330.812695 -6.310887)
			(xy 330.866652 -6.324993) (xy 330.917981 -6.346805) (xy 330.965587 -6.375859) (xy 331.008455 -6.411534)
			(xy 331.045672 -6.453071) (xy 331.076445 -6.499584) (xy 331.100117 -6.550081) (xy 331.116185 -6.603488)
			(xy 331.124305 -6.658664) (xy 331.124814 -6.68655) (xy 331.124305 -6.714436) (xy 331.116185 -6.769612)
			(xy 331.100117 -6.823019) (xy 331.076445 -6.873516) (xy 331.045672 -6.920029) (xy 331.025465 -6.942582)
			(xy 337.010754 -6.942582) (xy 337.014825 -6.88696) (xy 337.026951 -6.832523) (xy 337.046874 -6.780432)
			(xy 337.07417 -6.731797) (xy 337.108256 -6.687654) (xy 337.148405 -6.648945) (xy 337.193763 -6.616494)
			(xy 337.243363 -6.590993) (xy 337.296147 -6.572986) (xy 337.35099 -6.562856) (xy 337.406724 -6.560819)
			(xy 337.462161 -6.566919) (xy 337.516118 -6.581025) (xy 337.567447 -6.602837) (xy 337.615053 -6.631891)
			(xy 337.657921 -6.667566) (xy 337.695138 -6.709103) (xy 337.715339 -6.739636) (xy 339.101936 -6.739636)
			(xy 339.106007 -6.684014) (xy 339.118133 -6.629577) (xy 339.138056 -6.577486) (xy 339.165352 -6.528851)
			(xy 339.199438 -6.484708) (xy 339.239587 -6.445999) (xy 339.284945 -6.413548) (xy 339.334545 -6.388047)
			(xy 339.387329 -6.37004) (xy 339.442172 -6.35991) (xy 339.497906 -6.357873) (xy 339.553343 -6.363973)
			(xy 339.6073 -6.378079) (xy 339.658629 -6.399891) (xy 339.706235 -6.428945) (xy 339.749103 -6.46462)
			(xy 339.78632 -6.506157) (xy 339.817093 -6.55267) (xy 339.840765 -6.603167) (xy 339.856833 -6.656574)
			(xy 339.864953 -6.71175) (xy 339.865462 -6.739636) (xy 339.864953 -6.767522) (xy 339.856833 -6.822698)
			(xy 339.840765 -6.876105) (xy 339.817093 -6.926602) (xy 339.78632 -6.973115) (xy 339.749103 -7.014652)
			(xy 339.706235 -7.050327) (xy 339.658629 -7.079381) (xy 339.6073 -7.101193) (xy 339.553343 -7.115299)
			(xy 339.497906 -7.121399) (xy 339.442172 -7.119362) (xy 339.387329 -7.109232) (xy 339.334545 -7.091225)
			(xy 339.284945 -7.065724) (xy 339.239587 -7.033273) (xy 339.199438 -6.994564) (xy 339.165352 -6.950421)
			(xy 339.138056 -6.901786) (xy 339.118133 -6.849695) (xy 339.106007 -6.795258) (xy 339.101936 -6.739636)
			(xy 337.715339 -6.739636) (xy 337.725911 -6.755616) (xy 337.749583 -6.806113) (xy 337.765651 -6.85952)
			(xy 337.773771 -6.914696) (xy 337.77428 -6.942582) (xy 337.773771 -6.970468) (xy 337.765651 -7.025644)
			(xy 337.749583 -7.079051) (xy 337.725911 -7.129548) (xy 337.695138 -7.176061) (xy 337.657921 -7.217598)
			(xy 337.615053 -7.253273) (xy 337.567447 -7.282327) (xy 337.516118 -7.304139) (xy 337.462161 -7.318245)
			(xy 337.406724 -7.324345) (xy 337.35099 -7.322308) (xy 337.296147 -7.312178) (xy 337.243363 -7.294171)
			(xy 337.193763 -7.26867) (xy 337.148405 -7.236219) (xy 337.108256 -7.19751) (xy 337.07417 -7.153367)
			(xy 337.046874 -7.104732) (xy 337.026951 -7.052641) (xy 337.014825 -6.998204) (xy 337.010754 -6.942582)
			(xy 331.025465 -6.942582) (xy 331.008455 -6.961566) (xy 330.965587 -6.997241) (xy 330.917981 -7.026295)
			(xy 330.866652 -7.048107) (xy 330.812695 -7.062213) (xy 330.757258 -7.068313) (xy 330.701524 -7.066276)
			(xy 330.646681 -7.056146) (xy 330.593897 -7.038139) (xy 330.544297 -7.012638) (xy 330.498939 -6.980187)
			(xy 330.45879 -6.941478) (xy 330.424704 -6.897335) (xy 330.397408 -6.8487) (xy 330.377485 -6.796609)
			(xy 330.365359 -6.742172) (xy 330.361288 -6.68655) (xy 328.673206 -6.68655) (xy 328.673206 -7.916672)
			(xy 330.525372 -7.916672) (xy 330.529443 -7.86105) (xy 330.541569 -7.806613) (xy 330.561492 -7.754522)
			(xy 330.588788 -7.705887) (xy 330.622874 -7.661744) (xy 330.663023 -7.623035) (xy 330.708381 -7.590584)
			(xy 330.757981 -7.565083) (xy 330.810765 -7.547076) (xy 330.865608 -7.536946) (xy 330.921342 -7.534909)
			(xy 330.976779 -7.541009) (xy 331.030736 -7.555115) (xy 331.082065 -7.576927) (xy 331.129671 -7.605981)
			(xy 331.172539 -7.641656) (xy 331.209756 -7.683193) (xy 331.240529 -7.729706) (xy 331.246612 -7.742682)
			(xy 339.120224 -7.742682) (xy 339.124295 -7.68706) (xy 339.136421 -7.632623) (xy 339.156344 -7.580532)
			(xy 339.18364 -7.531897) (xy 339.217726 -7.487754) (xy 339.257875 -7.449045) (xy 339.303233 -7.416594)
			(xy 339.352833 -7.391093) (xy 339.405617 -7.373086) (xy 339.46046 -7.362956) (xy 339.516194 -7.360919)
			(xy 339.571631 -7.367019) (xy 339.625588 -7.381125) (xy 339.676917 -7.402937) (xy 339.724523 -7.431991)
			(xy 339.767391 -7.467666) (xy 339.804608 -7.509203) (xy 339.835381 -7.555716) (xy 339.859053 -7.606213)
			(xy 339.875121 -7.65962) (xy 339.883241 -7.714796) (xy 339.88375 -7.742682) (xy 339.883241 -7.770568)
			(xy 339.875121 -7.825744) (xy 339.859053 -7.879151) (xy 339.835381 -7.929648) (xy 339.804608 -7.976161)
			(xy 339.767391 -8.017698) (xy 339.724523 -8.053373) (xy 339.676917 -8.082427) (xy 339.625588 -8.104239)
			(xy 339.571631 -8.118345) (xy 339.516194 -8.124445) (xy 339.46046 -8.122408) (xy 339.405617 -8.112278)
			(xy 339.352833 -8.094271) (xy 339.303233 -8.06877) (xy 339.257875 -8.036319) (xy 339.217726 -7.99761)
			(xy 339.18364 -7.953467) (xy 339.156344 -7.904832) (xy 339.136421 -7.852741) (xy 339.124295 -7.798304)
			(xy 339.120224 -7.742682) (xy 331.246612 -7.742682) (xy 331.264201 -7.780203) (xy 331.280269 -7.83361)
			(xy 331.288389 -7.888786) (xy 331.288898 -7.916672) (xy 331.288389 -7.944558) (xy 331.280269 -7.999734)
			(xy 331.264201 -8.053141) (xy 331.240529 -8.103638) (xy 331.209756 -8.150151) (xy 331.172539 -8.191688)
			(xy 331.129671 -8.227363) (xy 331.082065 -8.256417) (xy 331.079159 -8.257652) (xy 336.93174 -8.257652)
			(xy 336.93174 -8.203148) (xy 336.939496 -8.149198) (xy 336.954851 -8.096901) (xy 336.977491 -8.047321)
			(xy 337.006957 -8.001468) (xy 337.042648 -7.960275) (xy 337.083838 -7.92458) (xy 337.129688 -7.89511)
			(xy 337.179265 -7.872464) (xy 337.231561 -7.857104) (xy 337.28551 -7.849342) (xy 337.312762 -7.848854)
			(xy 337.340914 -7.849367) (xy 337.396609 -7.857623) (xy 337.450485 -7.873978) (xy 337.501372 -7.898075)
			(xy 337.548163 -7.929391) (xy 337.589843 -7.967245) (xy 337.625504 -8.010815) (xy 337.654374 -8.059155)
			(xy 337.675823 -8.111213) (xy 337.683094 -8.138414) (xy 337.687124 -8.152573) (xy 337.702124 -8.177891)
			(xy 337.723719 -8.197883) (xy 337.750117 -8.210889) (xy 337.779127 -8.215831) (xy 337.808343 -8.212299)
			(xy 337.835339 -8.200585) (xy 337.846924 -8.1915) (xy 337.867602 -8.174655) (xy 337.912819 -8.146369)
			(xy 337.961536 -8.12466) (xy 338.012804 -8.109952) (xy 338.06562 -8.102531) (xy 338.092288 -8.102092)
			(xy 338.092542 -8.102092) (xy 338.119791 -8.102581) (xy 338.173734 -8.110342) (xy 338.226024 -8.125701)
			(xy 338.275596 -8.148344) (xy 338.321441 -8.177812) (xy 338.362626 -8.213503) (xy 338.398313 -8.254692)
			(xy 338.427776 -8.300541) (xy 338.450414 -8.350115) (xy 338.465767 -8.402407) (xy 338.473522 -8.456351)
			(xy 338.473522 -8.510849) (xy 338.465767 -8.564793) (xy 338.450414 -8.617085) (xy 338.427776 -8.666659)
			(xy 338.398313 -8.712508) (xy 338.362626 -8.753697) (xy 338.321441 -8.789388) (xy 338.275596 -8.818856)
			(xy 338.226024 -8.841499) (xy 338.173734 -8.856858) (xy 338.119791 -8.864619) (xy 338.092542 -8.865108)
			(xy 338.064389 -8.864621) (xy 338.008691 -8.856363) (xy 337.954813 -8.840007) (xy 337.903924 -8.815908)
			(xy 337.857132 -8.784589) (xy 337.815453 -8.746731) (xy 337.779792 -8.703157) (xy 337.750925 -8.654813)
			(xy 337.729479 -8.602751) (xy 337.72221 -8.575548) (xy 337.718189 -8.561387) (xy 337.703183 -8.536074)
			(xy 337.681585 -8.516087) (xy 337.655187 -8.503084) (xy 337.626178 -8.498142) (xy 337.596964 -8.501671)
			(xy 337.569966 -8.51338) (xy 337.55838 -8.522462) (xy 337.537696 -8.539299) (xy 337.492481 -8.567588)
			(xy 337.443766 -8.589299) (xy 337.392499 -8.604009) (xy 337.339683 -8.61143) (xy 337.313016 -8.61187)
			(xy 337.312762 -8.61187) (xy 337.28551 -8.611458) (xy 337.231561 -8.603696) (xy 337.179265 -8.588336)
			(xy 337.129688 -8.56569) (xy 337.083838 -8.53622) (xy 337.042648 -8.500525) (xy 337.006957 -8.459332)
			(xy 336.977491 -8.413479) (xy 336.954851 -8.363899) (xy 336.939496 -8.311602) (xy 336.93174 -8.257652)
			(xy 331.079159 -8.257652) (xy 331.030736 -8.278229) (xy 330.976779 -8.292335) (xy 330.921342 -8.298435)
			(xy 330.865608 -8.296398) (xy 330.810765 -8.286268) (xy 330.757981 -8.268261) (xy 330.708381 -8.24276)
			(xy 330.663023 -8.210309) (xy 330.622874 -8.1716) (xy 330.588788 -8.127457) (xy 330.561492 -8.078822)
			(xy 330.541569 -8.026731) (xy 330.529443 -7.972294) (xy 330.525372 -7.916672) (xy 328.673206 -7.916672)
			(xy 328.673206 -8.577072) (xy 329.255372 -8.577072) (xy 329.259443 -8.52145) (xy 329.271569 -8.467013)
			(xy 329.291492 -8.414922) (xy 329.318788 -8.366287) (xy 329.352874 -8.322144) (xy 329.393023 -8.283435)
			(xy 329.438381 -8.250984) (xy 329.487981 -8.225483) (xy 329.540765 -8.207476) (xy 329.595608 -8.197346)
			(xy 329.651342 -8.195309) (xy 329.706779 -8.201409) (xy 329.760736 -8.215515) (xy 329.812065 -8.237327)
			(xy 329.859671 -8.266381) (xy 329.902539 -8.302056) (xy 329.939756 -8.343593) (xy 329.970529 -8.390106)
			(xy 329.994201 -8.440603) (xy 330.010269 -8.49401) (xy 330.018389 -8.549186) (xy 330.018898 -8.577072)
			(xy 330.018389 -8.604958) (xy 330.010269 -8.660134) (xy 329.994201 -8.713541) (xy 329.970529 -8.764038)
			(xy 329.939756 -8.810551) (xy 329.902539 -8.852088) (xy 329.859671 -8.887763) (xy 329.812065 -8.916817)
			(xy 329.760736 -8.938629) (xy 329.706779 -8.952735) (xy 329.651342 -8.958835) (xy 329.595608 -8.956798)
			(xy 329.540765 -8.946668) (xy 329.487981 -8.928661) (xy 329.438381 -8.90316) (xy 329.393023 -8.870709)
			(xy 329.352874 -8.832) (xy 329.318788 -8.787857) (xy 329.291492 -8.739222) (xy 329.271569 -8.687131)
			(xy 329.259443 -8.632694) (xy 329.255372 -8.577072) (xy 328.673206 -8.577072) (xy 328.673206 -9.535922)
			(xy 332.574644 -9.535922) (xy 332.578715 -9.4803) (xy 332.590841 -9.425863) (xy 332.610764 -9.373772)
			(xy 332.63806 -9.325137) (xy 332.672146 -9.280994) (xy 332.712295 -9.242285) (xy 332.757653 -9.209834)
			(xy 332.807253 -9.184333) (xy 332.860037 -9.166326) (xy 332.91488 -9.156196) (xy 332.970614 -9.154159)
			(xy 333.026051 -9.160259) (xy 333.080008 -9.174365) (xy 333.131337 -9.196177) (xy 333.178943 -9.225231)
			(xy 333.221811 -9.260906) (xy 333.259028 -9.302443) (xy 333.289801 -9.348956) (xy 333.313473 -9.399453)
			(xy 333.329541 -9.45286) (xy 333.337661 -9.508036) (xy 333.33811 -9.53262) (xy 335.622644 -9.53262)
			(xy 335.626715 -9.476998) (xy 335.638841 -9.422561) (xy 335.658764 -9.37047) (xy 335.68606 -9.321835)
			(xy 335.720146 -9.277692) (xy 335.760295 -9.238983) (xy 335.805653 -9.206532) (xy 335.855253 -9.181031)
			(xy 335.908037 -9.163024) (xy 335.96288 -9.152894) (xy 336.018614 -9.150857) (xy 336.074051 -9.156957)
			(xy 336.128008 -9.171063) (xy 336.179337 -9.192875) (xy 336.226943 -9.221929) (xy 336.269811 -9.257604)
			(xy 336.307028 -9.299141) (xy 336.337801 -9.345654) (xy 336.361473 -9.396151) (xy 336.377541 -9.449558)
			(xy 336.385661 -9.504734) (xy 336.38617 -9.53262) (xy 336.385661 -9.560506) (xy 336.377541 -9.615682)
			(xy 336.361473 -9.669089) (xy 336.337801 -9.719586) (xy 336.307028 -9.766099) (xy 336.269811 -9.807636)
			(xy 336.226943 -9.843311) (xy 336.179337 -9.872365) (xy 336.128008 -9.894177) (xy 336.074051 -9.908283)
			(xy 336.018614 -9.914383) (xy 335.96288 -9.912346) (xy 335.908037 -9.902216) (xy 335.855253 -9.884209)
			(xy 335.805653 -9.858708) (xy 335.760295 -9.826257) (xy 335.720146 -9.787548) (xy 335.68606 -9.743405)
			(xy 335.658764 -9.69477) (xy 335.638841 -9.642679) (xy 335.626715 -9.588242) (xy 335.622644 -9.53262)
			(xy 333.33811 -9.53262) (xy 333.33817 -9.535922) (xy 333.337661 -9.563808) (xy 333.329541 -9.618984)
			(xy 333.313473 -9.672391) (xy 333.289801 -9.722888) (xy 333.259028 -9.769401) (xy 333.221811 -9.810938)
			(xy 333.178943 -9.846613) (xy 333.131337 -9.875667) (xy 333.080008 -9.897479) (xy 333.026051 -9.911585)
			(xy 332.970614 -9.917685) (xy 332.91488 -9.915648) (xy 332.860037 -9.905518) (xy 332.807253 -9.887511)
			(xy 332.757653 -9.86201) (xy 332.712295 -9.829559) (xy 332.672146 -9.79085) (xy 332.63806 -9.746707)
			(xy 332.610764 -9.698072) (xy 332.590841 -9.645981) (xy 332.578715 -9.591544) (xy 332.574644 -9.535922)
			(xy 328.673206 -9.535922) (xy 328.673206 -11.543792) (xy 333.59928 -11.543792) (xy 333.603351 -11.48817)
			(xy 333.615477 -11.433733) (xy 333.6354 -11.381642) (xy 333.662696 -11.333007) (xy 333.696782 -11.288864)
			(xy 333.736931 -11.250155) (xy 333.782289 -11.217704) (xy 333.831889 -11.192203) (xy 333.884673 -11.174196)
			(xy 333.939516 -11.164066) (xy 333.99525 -11.162029) (xy 334.050687 -11.168129) (xy 334.104644 -11.182235)
			(xy 334.155973 -11.204047) (xy 334.203579 -11.233101) (xy 334.246447 -11.268776) (xy 334.283664 -11.310313)
			(xy 334.314437 -11.356826) (xy 334.338109 -11.407323) (xy 334.354177 -11.46073) (xy 334.362297 -11.515906)
			(xy 334.362806 -11.543792) (xy 334.608168 -11.543792) (xy 334.612239 -11.48817) (xy 334.624365 -11.433733)
			(xy 334.644288 -11.381642) (xy 334.671584 -11.333007) (xy 334.70567 -11.288864) (xy 334.745819 -11.250155)
			(xy 334.791177 -11.217704) (xy 334.840777 -11.192203) (xy 334.893561 -11.174196) (xy 334.948404 -11.164066)
			(xy 335.004138 -11.162029) (xy 335.059575 -11.168129) (xy 335.113532 -11.182235) (xy 335.164861 -11.204047)
			(xy 335.212467 -11.233101) (xy 335.255335 -11.268776) (xy 335.292552 -11.310313) (xy 335.323325 -11.356826)
			(xy 335.346997 -11.407323) (xy 335.363065 -11.46073) (xy 335.371185 -11.515906) (xy 335.371694 -11.543792)
			(xy 335.371185 -11.571678) (xy 335.363065 -11.626854) (xy 335.346997 -11.680261) (xy 335.323325 -11.730758)
			(xy 335.292552 -11.777271) (xy 335.255335 -11.818808) (xy 335.212467 -11.854483) (xy 335.164861 -11.883537)
			(xy 335.113532 -11.905349) (xy 335.059575 -11.919455) (xy 335.004138 -11.925555) (xy 334.948404 -11.923518)
			(xy 334.893561 -11.913388) (xy 334.840777 -11.895381) (xy 334.791177 -11.86988) (xy 334.745819 -11.837429)
			(xy 334.70567 -11.79872) (xy 334.671584 -11.754577) (xy 334.644288 -11.705942) (xy 334.624365 -11.653851)
			(xy 334.612239 -11.599414) (xy 334.608168 -11.543792) (xy 334.362806 -11.543792) (xy 334.362297 -11.571678)
			(xy 334.354177 -11.626854) (xy 334.338109 -11.680261) (xy 334.314437 -11.730758) (xy 334.283664 -11.777271)
			(xy 334.246447 -11.818808) (xy 334.203579 -11.854483) (xy 334.155973 -11.883537) (xy 334.104644 -11.905349)
			(xy 334.050687 -11.919455) (xy 333.99525 -11.925555) (xy 333.939516 -11.923518) (xy 333.884673 -11.913388)
			(xy 333.831889 -11.895381) (xy 333.782289 -11.86988) (xy 333.736931 -11.837429) (xy 333.696782 -11.79872)
			(xy 333.662696 -11.754577) (xy 333.6354 -11.705942) (xy 333.615477 -11.653851) (xy 333.603351 -11.599414)
			(xy 333.59928 -11.543792) (xy 328.673206 -11.543792) (xy 328.673206 -11.850116) (xy 328.672736 -11.903966)
			(xy 328.665052 -12.01139) (xy 328.649723 -12.117993) (xy 328.626829 -12.223231) (xy 328.596485 -12.326567)
			(xy 328.558846 -12.427475) (xy 328.514105 -12.525441) (xy 328.462488 -12.619966) (xy 328.40426 -12.710567)
			(xy 328.339717 -12.796784) (xy 328.269187 -12.878176) (xy 328.193031 -12.954329) (xy 328.111635 -13.024856)
			(xy 328.025416 -13.089396) (xy 327.934813 -13.14762) (xy 327.840286 -13.199233) (xy 327.742318 -13.24397)
			(xy 327.641408 -13.281604) (xy 327.538071 -13.311944) (xy 327.432832 -13.334834) (xy 327.326229 -13.350158)
			(xy 327.218804 -13.357838) (xy 327.164954 -13.358368) (xy 319.16497 -13.358368) (xy 319.11112 -13.357887)
			(xy 319.003695 -13.350201) (xy 318.897092 -13.334872) (xy 318.791855 -13.311978) (xy 318.688518 -13.281634)
			(xy 318.58761 -13.243995) (xy 318.489643 -13.199254) (xy 318.395118 -13.147638) (xy 318.304516 -13.089411)
			(xy 318.218299 -13.024868) (xy 318.136905 -12.95434) (xy 318.060751 -12.878184) (xy 317.990223 -12.79679)
			(xy 317.925681 -12.710572) (xy 317.867455 -12.61997) (xy 317.81584 -12.525444) (xy 317.771099 -12.427477)
			(xy 317.733462 -12.326569) (xy 317.703119 -12.223232) (xy 317.680225 -12.117994) (xy 317.664897 -12.011391)
			(xy 317.657213 -11.903966) (xy 317.656718 -11.850116) (xy 317.656718 -3.357118) (xy 317.656234 -3.347107)
			(xy 317.648578 -3.328605) (xy 317.634425 -3.314442) (xy 317.615929 -3.306774) (xy 317.605918 -3.306318)
			(xy 302.724058 -3.306318) (xy 302.714057 -3.306814) (xy 302.695583 -3.314481) (xy 302.681448 -3.328633)
			(xy 302.673802 -3.347117) (xy 302.673258 -3.357118) (xy 302.673258 -11.850116) (xy 302.672777 -11.903966)
			(xy 302.665093 -12.011391) (xy 302.649765 -12.117995) (xy 302.62687 -12.223233) (xy 302.596527 -12.32657)
			(xy 302.558889 -12.427479) (xy 302.514148 -12.525446) (xy 302.462533 -12.619972) (xy 302.404305 -12.710574)
			(xy 302.339763 -12.796792) (xy 302.269234 -12.878186) (xy 302.193079 -12.954341) (xy 302.111684 -13.024869)
			(xy 302.025466 -13.089411) (xy 301.934863 -13.147638) (xy 301.840337 -13.199253) (xy 301.74237 -13.243993)
			(xy 301.641461 -13.28163) (xy 301.538123 -13.311973) (xy 301.432885 -13.334866) (xy 301.326281 -13.350194)
			(xy 301.218856 -13.357877) (xy 301.165006 -13.358368) (xy 293.165022 -13.358368) (xy 293.111171 -13.357899)
			(xy 293.003742 -13.350218) (xy 292.897136 -13.334891) (xy 292.791894 -13.311999) (xy 292.688554 -13.281657)
			(xy 292.587641 -13.24402) (xy 292.489671 -13.19928) (xy 292.395142 -13.147665) (xy 292.304536 -13.089438)
			(xy 292.218315 -13.024895) (xy 292.136918 -12.954366) (xy 292.06076 -12.87821) (xy 291.990228 -12.796815)
			(xy 291.925684 -12.710595) (xy 291.867454 -12.619991) (xy 291.815837 -12.525463) (xy 291.771094 -12.427494)
			(xy 291.733455 -12.326582) (xy 291.70311 -12.223243) (xy 291.680215 -12.118002) (xy 291.664886 -12.011395)
			(xy 291.657202 -11.903967) (xy 291.65677 -11.850116) (xy 291.65677 -1.940052) (xy 291.656337 -1.929986)
			(xy 291.648607 -1.911397) (xy 291.641784 -1.903984) (xy 291.225986 -1.488186) (xy 291.218591 -1.481332)
			(xy 291.199992 -1.47359) (xy 291.189918 -1.4732) (xy 277.211282 -1.4732) (xy 277.201213 -1.473627)
			(xy 277.182614 -1.481346) (xy 277.175214 -1.488186) (xy 276.688296 -1.975104) (xy 276.681451 -1.982503)
			(xy 276.673718 -2.001101) (xy 276.67331 -2.011172) (xy 276.67331 -11.850116) (xy 276.67284 -11.903966)
			(xy 276.665156 -12.011391) (xy 276.649827 -12.117994) (xy 276.626933 -12.223231) (xy 276.596589 -12.326568)
			(xy 276.55895 -12.427476) (xy 276.514209 -12.525442) (xy 276.462593 -12.619967) (xy 276.404364 -12.710568)
			(xy 276.339821 -12.796785) (xy 276.269291 -12.878177) (xy 276.193135 -12.954331) (xy 276.11174 -13.024857)
			(xy 276.025521 -13.089397) (xy 275.934917 -13.147622) (xy 275.84039 -13.199235) (xy 275.742422 -13.243972)
			(xy 275.641513 -13.281607) (xy 275.538175 -13.311947) (xy 275.432936 -13.334837) (xy 275.326333 -13.350162)
			(xy 275.218908 -13.357842) (xy 275.165058 -13.358368) (xy 267.165074 -13.358368) (xy 267.111224 -13.357887)
			(xy 267.003799 -13.350202) (xy 266.897196 -13.334873) (xy 266.791958 -13.311978) (xy 266.688621 -13.281635)
			(xy 266.587712 -13.243996) (xy 266.489746 -13.199255) (xy 266.395221 -13.14764) (xy 266.304618 -13.089412)
			(xy 266.218401 -13.02487) (xy 266.137007 -12.954341) (xy 266.060852 -12.878186) (xy 265.990324 -12.796792)
			(xy 265.925782 -12.710574) (xy 265.867555 -12.619971) (xy 265.81594 -12.525445) (xy 265.7712 -12.427478)
			(xy 265.733562 -12.326569) (xy 265.703219 -12.223232) (xy 265.680325 -12.117994) (xy 265.664997 -12.011391)
			(xy 265.657313 -11.903966) (xy 265.656822 -11.850116) (xy 265.656822 -3.357118) (xy 265.656338 -3.347106)
			(xy 265.648682 -3.328605) (xy 265.634529 -3.31444) (xy 265.616033 -3.30677) (xy 265.606022 -3.306318)
			(xy 250.724162 -3.306318) (xy 250.714161 -3.306813) (xy 250.695685 -3.31448) (xy 250.681548 -3.328632)
			(xy 250.673902 -3.347116) (xy 250.673362 -3.357118) (xy 250.673362 -11.850116) (xy 250.672881 -11.903966)
			(xy 250.665197 -12.011391) (xy 250.649869 -12.117995) (xy 250.626974 -12.223233) (xy 250.596631 -12.326571)
			(xy 250.558993 -12.42748) (xy 250.514252 -12.525447) (xy 250.462637 -12.619972) (xy 250.404409 -12.710575)
			(xy 250.339867 -12.796793) (xy 250.269338 -12.878187) (xy 250.193183 -12.954342) (xy 250.111789 -13.024871)
			(xy 250.02557 -13.089413) (xy 249.934967 -13.14764) (xy 249.840441 -13.199255) (xy 249.742474 -13.243995)
			(xy 249.641565 -13.281633) (xy 249.538228 -13.311976) (xy 249.432989 -13.33487) (xy 249.326385 -13.350197)
			(xy 249.21896 -13.357881) (xy 249.16511 -13.358368) (xy 241.164872 -13.358368) (xy 241.111026 -13.357873)
			(xy 241.003611 -13.350162) (xy 240.897019 -13.334811) (xy 240.791793 -13.311898) (xy 240.688469 -13.281539)
			(xy 240.587573 -13.243889) (xy 240.489619 -13.199139) (xy 240.395106 -13.147518) (xy 240.304514 -13.089288)
			(xy 240.218306 -13.024746) (xy 240.13692 -12.954221) (xy 240.060771 -12.878071) (xy 239.990246 -12.796684)
			(xy 239.925705 -12.710476) (xy 239.867476 -12.619884) (xy 239.815855 -12.52537) (xy 239.771107 -12.427416)
			(xy 239.733457 -12.32652) (xy 239.703099 -12.223195) (xy 239.680186 -12.117969) (xy 239.664836 -12.011377)
			(xy 239.657127 -11.903962) (xy 239.65662 -11.850116) (xy 239.65662 -2.009902) (xy 239.656198 -1.999831)
			(xy 239.648486 -1.981224) (xy 239.641634 -1.973834) (xy 239.186466 -1.518666) (xy 239.179053 -1.511991)
			(xy 239.160617 -1.504426) (xy 239.150652 -1.503934) (xy 239.13846 -1.505458) (xy 239.115899 -1.510691)
			(xy 239.069924 -1.516289) (xy 239.046766 -1.516634) (xy 239.01989 -1.516172) (xy 238.966671 -1.508618)
			(xy 238.915039 -1.493666) (xy 238.86602 -1.471612) (xy 238.820583 -1.442892) (xy 238.779629 -1.408076)
			(xy 238.743971 -1.367854) (xy 238.714314 -1.323024) (xy 238.702342 -1.298956) (xy 238.697889 -1.290494)
			(xy 238.683944 -1.277432) (xy 238.666175 -1.270405) (xy 238.656622 -1.27) (xy 213.43493 -1.27) (xy 213.425537 -1.270557)
			(xy 213.408139 -1.277693) (xy 213.3945 -1.290638) (xy 213.386466 -1.30764) (xy 213.3854 -1.31699)
			(xy 213.3854 -1.326134) (xy 213.387432 -1.364488) (xy 213.387432 -1.364996) (xy 213.386947 -1.392248)
			(xy 213.379191 -1.446198) (xy 213.363836 -1.498494) (xy 213.341195 -1.548073) (xy 213.31173 -1.593926)
			(xy 213.276038 -1.635119) (xy 213.234848 -1.670813) (xy 213.188998 -1.700282) (xy 213.13942 -1.722926)
			(xy 213.087125 -1.738285) (xy 213.033176 -1.746045) (xy 213.005924 -1.746504) (xy 213.005416 -1.746504)
			(xy 212.985128 -1.746223) (xy 212.944783 -1.741899) (xy 212.924898 -1.737868) (xy 212.916572 -1.736389)
			(xy 212.899792 -1.738413) (xy 212.884596 -1.745813) (xy 212.878416 -1.751584) (xy 212.639148 -1.990852)
			(xy 212.632305 -1.998251) (xy 212.624582 -2.01685) (xy 212.624162 -2.02692) (xy 212.624162 -3.306318)
			(xy 212.614161 -3.306813) (xy 212.595685 -3.31448) (xy 212.581548 -3.328632) (xy 212.573902 -3.347116)
			(xy 212.573362 -3.357118) (xy 212.573362 -11.850116) (xy 212.572881 -11.903966) (xy 212.565197 -12.011391)
			(xy 212.549869 -12.117995) (xy 212.526974 -12.223233) (xy 212.496631 -12.326571) (xy 212.458993 -12.42748)
			(xy 212.414252 -12.525447) (xy 212.362637 -12.619972) (xy 212.304409 -12.710575) (xy 212.239867 -12.796793)
			(xy 212.169338 -12.878187) (xy 212.093183 -12.954342) (xy 212.011789 -13.024871) (xy 211.92557 -13.089413)
			(xy 211.834967 -13.14764) (xy 211.740441 -13.199255) (xy 211.642474 -13.243995) (xy 211.541565 -13.281633)
			(xy 211.438228 -13.311976) (xy 211.332989 -13.33487) (xy 211.226385 -13.350197) (xy 211.11896 -13.357881)
			(xy 211.06511 -13.358368) (xy 203.064872 -13.358368) (xy 203.011026 -13.357873) (xy 202.903611 -13.350162)
			(xy 202.797019 -13.334811) (xy 202.691793 -13.311898) (xy 202.588469 -13.281539) (xy 202.487573 -13.243889)
			(xy 202.389619 -13.199139) (xy 202.295106 -13.147518) (xy 202.204514 -13.089288) (xy 202.118306 -13.024746)
			(xy 202.03692 -12.954221) (xy 201.960771 -12.878071) (xy 201.890246 -12.796684) (xy 201.825705 -12.710476)
			(xy 201.767476 -12.619884) (xy 201.715855 -12.52537) (xy 201.671107 -12.427416) (xy 201.633457 -12.32652)
			(xy 201.603099 -12.223195) (xy 201.580186 -12.117969) (xy 201.564836 -12.011377) (xy 201.557127 -11.903962)
			(xy 201.55662 -11.850116) (xy 201.55662 -3.357118) (xy 201.556136 -3.347106) (xy 201.54848 -3.328605)
			(xy 201.534327 -3.314441) (xy 201.515831 -3.306772) (xy 201.50582 -3.306318) (xy 186.62396 -3.306318)
			(xy 186.613959 -3.306813) (xy 186.595484 -3.31448) (xy 186.581348 -3.328633) (xy 186.573702 -3.347116)
			(xy 186.57316 -3.357118) (xy 186.57316 -11.850116) (xy 186.572679 -11.903966) (xy 186.564995 -12.011391)
			(xy 186.549667 -12.117995) (xy 186.526772 -12.223233) (xy 186.496429 -12.32657) (xy 186.458791 -12.427479)
			(xy 186.41405 -12.525446) (xy 186.362435 -12.619972) (xy 186.304207 -12.710575) (xy 186.239665 -12.796793)
			(xy 186.169136 -12.878187) (xy 186.092981 -12.954342) (xy 186.011586 -13.02487) (xy 185.925368 -13.089412)
			(xy 185.834765 -13.147639) (xy 185.740239 -13.199254) (xy 185.642272 -13.243994) (xy 185.541363 -13.281632)
			(xy 185.438026 -13.311974) (xy 185.332787 -13.334868) (xy 185.226183 -13.350196) (xy 185.118758 -13.357879)
			(xy 185.064908 -13.358368) (xy 177.064924 -13.358368) (xy 177.011073 -13.3579) (xy 176.903644 -13.350218)
			(xy 176.797038 -13.334892) (xy 176.691796 -13.311999) (xy 176.588455 -13.281658) (xy 176.487543 -13.244021)
			(xy 176.389572 -13.199281) (xy 176.295043 -13.147666) (xy 176.204437 -13.089439) (xy 176.118216 -13.024896)
			(xy 176.036819 -12.954367) (xy 175.96066 -12.878211) (xy 175.890129 -12.796815) (xy 175.825584 -12.710596)
			(xy 175.767354 -12.619991) (xy 175.715737 -12.525463) (xy 175.670994 -12.427494) (xy 175.633355 -12.326583)
			(xy 175.60301 -12.223243) (xy 175.580115 -12.118002) (xy 175.564787 -12.011396) (xy 175.557102 -11.903967)
			(xy 175.556672 -11.850116) (xy 175.556672 -1.968754) (xy 175.55624 -1.958688) (xy 175.548511 -1.940098)
			(xy 175.541686 -1.932686) (xy 174.919386 -1.310386) (xy 174.911991 -1.303532) (xy 174.893392 -1.29579)
			(xy 174.883318 -1.2954) (xy 161.285682 -1.2954) (xy 161.275613 -1.295827) (xy 161.257014 -1.303546)
			(xy 161.249614 -1.310386) (xy 160.588198 -1.971802) (xy 160.581352 -1.979201) (xy 160.573619 -1.997799)
			(xy 160.573212 -2.00787) (xy 160.573212 -11.850116) (xy 160.572742 -11.903966) (xy 160.565058 -12.011391)
			(xy 160.549729 -12.117994) (xy 160.526835 -12.223232) (xy 160.496491 -12.326568) (xy 160.458852 -12.427476)
			(xy 160.414111 -12.525443) (xy 160.362495 -12.619967) (xy 160.304266 -12.710569) (xy 160.239723 -12.796786)
			(xy 160.169193 -12.878178) (xy 160.093037 -12.954332) (xy 160.011642 -13.024858) (xy 159.925423 -13.089398)
			(xy 159.834819 -13.147623) (xy 159.740292 -13.199236) (xy 159.642325 -13.243974) (xy 159.541415 -13.281609)
			(xy 159.438077 -13.311949) (xy 159.332839 -13.334839) (xy 159.226235 -13.350164) (xy 159.11881 -13.357844)
			(xy 159.06496 -13.358368) (xy 151.064976 -13.358368) (xy 151.011126 -13.357887) (xy 150.903701 -13.350202)
			(xy 150.797098 -13.334873) (xy 150.691859 -13.311979) (xy 150.588523 -13.281635) (xy 150.487614 -13.243997)
			(xy 150.389647 -13.199256) (xy 150.295122 -13.14764) (xy 150.204519 -13.089413) (xy 150.118302 -13.02487)
			(xy 150.036908 -12.954342) (xy 149.960753 -12.878186) (xy 149.890225 -12.796792) (xy 149.825683 -12.710574)
			(xy 149.767456 -12.619971) (xy 149.71584 -12.525446) (xy 149.6711 -12.427479) (xy 149.633462 -12.32657)
			(xy 149.603119 -12.223233) (xy 149.580225 -12.117994) (xy 149.564897 -12.011391) (xy 149.557213 -11.903966)
			(xy 149.556724 -11.850116) (xy 149.556724 -3.357118) (xy 149.55624 -3.347106) (xy 149.548584 -3.328604)
			(xy 149.534431 -3.31444) (xy 149.515935 -3.306769) (xy 149.505924 -3.306318) (xy 134.624064 -3.306318)
			(xy 134.614062 -3.306812) (xy 134.595586 -3.314479) (xy 134.581449 -3.328631) (xy 134.573802 -3.347116)
			(xy 134.573264 -3.357118) (xy 134.573264 -11.850116) (xy 134.572783 -11.903966) (xy 134.565099 -12.011391)
			(xy 134.549771 -12.117995) (xy 134.526876 -12.223234) (xy 134.496533 -12.326571) (xy 134.458895 -12.42748)
			(xy 134.414154 -12.525447) (xy 134.362539 -12.619973) (xy 134.304312 -12.710576) (xy 134.239769 -12.796794)
			(xy 134.16924 -12.878188) (xy 134.093085 -12.954343) (xy 134.011691 -13.024872) (xy 133.925472 -13.089414)
			(xy 133.834869 -13.147641) (xy 133.740344 -13.199256) (xy 133.642376 -13.243997) (xy 133.541467 -13.281634)
			(xy 133.43813 -13.311977) (xy 133.332891 -13.334871) (xy 133.226288 -13.350199) (xy 133.118862 -13.357883)
			(xy 133.065012 -13.358368) (xy 125.065028 -13.358368) (xy 125.011177 -13.3579) (xy 124.903748 -13.350218)
			(xy 124.797141 -13.334892) (xy 124.691899 -13.312) (xy 124.588558 -13.281659) (xy 124.487646 -13.244022)
			(xy 124.389675 -13.199282) (xy 124.295146 -13.147667) (xy 124.204539 -13.08944) (xy 124.118318 -13.024898)
			(xy 124.03692 -12.954368) (xy 123.960762 -12.878212) (xy 123.89023 -12.796817) (xy 123.825685 -12.710597)
			(xy 123.767455 -12.619992) (xy 123.715837 -12.525464) (xy 123.671095 -12.427495) (xy 123.633455 -12.326583)
			(xy 123.603111 -12.223244) (xy 123.580215 -12.118002) (xy 123.564887 -12.011396) (xy 123.557202 -11.903967)
			(xy 123.556776 -11.850116) (xy 123.556776 -3.357118) (xy 123.556359 -3.347096) (xy 123.548691 -3.328577)
			(xy 123.534518 -3.314405) (xy 123.515998 -3.30674) (xy 123.505976 -3.306318) (xy 96.524064 -3.306318)
			(xy 96.514062 -3.306812) (xy 96.495586 -3.314479) (xy 96.481449 -3.328631) (xy 96.473802 -3.347116)
			(xy 96.473264 -3.357118) (xy 96.473264 -5.747258) (xy 103.958388 -5.747258) (xy 103.962459 -5.691636)
			(xy 103.974585 -5.637199) (xy 103.994508 -5.585108) (xy 104.021804 -5.536473) (xy 104.05589 -5.49233)
			(xy 104.096039 -5.453621) (xy 104.141397 -5.42117) (xy 104.190997 -5.395669) (xy 104.243781 -5.377662)
			(xy 104.298624 -5.367532) (xy 104.354358 -5.365495) (xy 104.409795 -5.371595) (xy 104.463752 -5.385701)
			(xy 104.515081 -5.407513) (xy 104.562687 -5.436567) (xy 104.605555 -5.472242) (xy 104.642772 -5.513779)
			(xy 104.673545 -5.560292) (xy 104.697217 -5.610789) (xy 104.713285 -5.664196) (xy 104.721405 -5.719372)
			(xy 104.721914 -5.747258) (xy 106.926124 -5.747258) (xy 106.930195 -5.691636) (xy 106.942321 -5.637199)
			(xy 106.962244 -5.585108) (xy 106.98954 -5.536473) (xy 107.023626 -5.49233) (xy 107.063775 -5.453621)
			(xy 107.109133 -5.42117) (xy 107.158733 -5.395669) (xy 107.211517 -5.377662) (xy 107.26636 -5.367532)
			(xy 107.322094 -5.365495) (xy 107.377531 -5.371595) (xy 107.431488 -5.385701) (xy 107.482817 -5.407513)
			(xy 107.530423 -5.436567) (xy 107.573291 -5.472242) (xy 107.610508 -5.513779) (xy 107.641281 -5.560292)
			(xy 107.664953 -5.610789) (xy 107.681021 -5.664196) (xy 107.689141 -5.719372) (xy 107.68965 -5.747258)
			(xy 107.689141 -5.775144) (xy 107.681021 -5.83032) (xy 107.664953 -5.883727) (xy 107.641281 -5.934224)
			(xy 107.610508 -5.980737) (xy 107.573291 -6.022274) (xy 107.530423 -6.057949) (xy 107.482817 -6.087003)
			(xy 107.431488 -6.108815) (xy 107.377531 -6.122921) (xy 107.322094 -6.129021) (xy 107.26636 -6.126984)
			(xy 107.211517 -6.116854) (xy 107.158733 -6.098847) (xy 107.109133 -6.073346) (xy 107.063775 -6.040895)
			(xy 107.023626 -6.002186) (xy 106.98954 -5.958043) (xy 106.962244 -5.909408) (xy 106.942321 -5.857317)
			(xy 106.930195 -5.80288) (xy 106.926124 -5.747258) (xy 104.721914 -5.747258) (xy 104.721405 -5.775144)
			(xy 104.713285 -5.83032) (xy 104.697217 -5.883727) (xy 104.673545 -5.934224) (xy 104.642772 -5.980737)
			(xy 104.605555 -6.022274) (xy 104.562687 -6.057949) (xy 104.515081 -6.087003) (xy 104.463752 -6.108815)
			(xy 104.409795 -6.122921) (xy 104.354358 -6.129021) (xy 104.298624 -6.126984) (xy 104.243781 -6.116854)
			(xy 104.190997 -6.098847) (xy 104.141397 -6.073346) (xy 104.096039 -6.040895) (xy 104.05589 -6.002186)
			(xy 104.021804 -5.958043) (xy 103.994508 -5.909408) (xy 103.974585 -5.857317) (xy 103.962459 -5.80288)
			(xy 103.958388 -5.747258) (xy 96.473264 -5.747258) (xy 96.473264 -6.931152) (xy 98.156774 -6.931152)
			(xy 98.160845 -6.87553) (xy 98.172971 -6.821093) (xy 98.192894 -6.769002) (xy 98.22019 -6.720367)
			(xy 98.254276 -6.676224) (xy 98.294425 -6.637515) (xy 98.339783 -6.605064) (xy 98.389383 -6.579563)
			(xy 98.442167 -6.561556) (xy 98.49701 -6.551426) (xy 98.552744 -6.549389) (xy 98.608181 -6.555489)
			(xy 98.662138 -6.569595) (xy 98.713467 -6.591407) (xy 98.761073 -6.620461) (xy 98.803941 -6.656136)
			(xy 98.841158 -6.697673) (xy 98.871931 -6.744186) (xy 98.895603 -6.794683) (xy 98.911671 -6.84809)
			(xy 98.919791 -6.903266) (xy 98.9203 -6.931152) (xy 98.919791 -6.959038) (xy 98.916494 -6.981444)
			(xy 104.810812 -6.981444) (xy 104.814883 -6.925822) (xy 104.827009 -6.871385) (xy 104.846932 -6.819294)
			(xy 104.874228 -6.770659) (xy 104.908314 -6.726516) (xy 104.948463 -6.687807) (xy 104.993821 -6.655356)
			(xy 105.043421 -6.629855) (xy 105.096205 -6.611848) (xy 105.151048 -6.601718) (xy 105.206782 -6.599681)
			(xy 105.262219 -6.605781) (xy 105.316176 -6.619887) (xy 105.367505 -6.641699) (xy 105.415111 -6.670753)
			(xy 105.457979 -6.706428) (xy 105.487733 -6.739636) (xy 106.901994 -6.739636) (xy 106.906065 -6.684014)
			(xy 106.918191 -6.629577) (xy 106.938114 -6.577486) (xy 106.96541 -6.528851) (xy 106.999496 -6.484708)
			(xy 107.039645 -6.445999) (xy 107.085003 -6.413548) (xy 107.134603 -6.388047) (xy 107.187387 -6.37004)
			(xy 107.24223 -6.35991) (xy 107.297964 -6.357873) (xy 107.353401 -6.363973) (xy 107.407358 -6.378079)
			(xy 107.458687 -6.399891) (xy 107.506293 -6.428945) (xy 107.549161 -6.46462) (xy 107.586378 -6.506157)
			(xy 107.617151 -6.55267) (xy 107.640823 -6.603167) (xy 107.656891 -6.656574) (xy 107.665011 -6.71175)
			(xy 107.66552 -6.739636) (xy 107.665011 -6.767522) (xy 107.656891 -6.822698) (xy 107.640823 -6.876105)
			(xy 107.617151 -6.926602) (xy 107.586378 -6.973115) (xy 107.549161 -7.014652) (xy 107.506293 -7.050327)
			(xy 107.458687 -7.079381) (xy 107.407358 -7.101193) (xy 107.353401 -7.115299) (xy 107.297964 -7.121399)
			(xy 107.24223 -7.119362) (xy 107.187387 -7.109232) (xy 107.134603 -7.091225) (xy 107.085003 -7.065724)
			(xy 107.039645 -7.033273) (xy 106.999496 -6.994564) (xy 106.96541 -6.950421) (xy 106.938114 -6.901786)
			(xy 106.918191 -6.849695) (xy 106.906065 -6.795258) (xy 106.901994 -6.739636) (xy 105.487733 -6.739636)
			(xy 105.495196 -6.747965) (xy 105.525969 -6.794478) (xy 105.549641 -6.844975) (xy 105.565709 -6.898382)
			(xy 105.573829 -6.953558) (xy 105.574338 -6.981444) (xy 105.573829 -7.00933) (xy 105.565709 -7.064506)
			(xy 105.549641 -7.117913) (xy 105.525969 -7.16841) (xy 105.495196 -7.214923) (xy 105.457979 -7.25646)
			(xy 105.415111 -7.292135) (xy 105.367505 -7.321189) (xy 105.316176 -7.343001) (xy 105.262219 -7.357107)
			(xy 105.206782 -7.363207) (xy 105.151048 -7.36117) (xy 105.096205 -7.35104) (xy 105.043421 -7.333033)
			(xy 104.993821 -7.307532) (xy 104.948463 -7.275081) (xy 104.908314 -7.236372) (xy 104.874228 -7.192229)
			(xy 104.846932 -7.143594) (xy 104.827009 -7.091503) (xy 104.814883 -7.037066) (xy 104.810812 -6.981444)
			(xy 98.916494 -6.981444) (xy 98.911671 -7.014214) (xy 98.895603 -7.067621) (xy 98.871931 -7.118118)
			(xy 98.841158 -7.164631) (xy 98.803941 -7.206168) (xy 98.761073 -7.241843) (xy 98.713467 -7.270897)
			(xy 98.662138 -7.292709) (xy 98.608181 -7.306815) (xy 98.552744 -7.312915) (xy 98.49701 -7.310878)
			(xy 98.442167 -7.300748) (xy 98.389383 -7.282741) (xy 98.339783 -7.25724) (xy 98.294425 -7.224789)
			(xy 98.254276 -7.18608) (xy 98.22019 -7.141937) (xy 98.192894 -7.093302) (xy 98.172971 -7.041211)
			(xy 98.160845 -6.986774) (xy 98.156774 -6.931152) (xy 96.473264 -6.931152) (xy 96.473264 -7.916672)
			(xy 98.32543 -7.916672) (xy 98.329501 -7.86105) (xy 98.341627 -7.806613) (xy 98.36155 -7.754522)
			(xy 98.388846 -7.705887) (xy 98.422932 -7.661744) (xy 98.463081 -7.623035) (xy 98.508439 -7.590584)
			(xy 98.558039 -7.565083) (xy 98.610823 -7.547076) (xy 98.665666 -7.536946) (xy 98.7214 -7.534909)
			(xy 98.776837 -7.541009) (xy 98.830794 -7.555115) (xy 98.882123 -7.576927) (xy 98.929729 -7.605981)
			(xy 98.972597 -7.641656) (xy 99.009814 -7.683193) (xy 99.040587 -7.729706) (xy 99.04667 -7.742682)
			(xy 106.920282 -7.742682) (xy 106.924353 -7.68706) (xy 106.936479 -7.632623) (xy 106.956402 -7.580532)
			(xy 106.983698 -7.531897) (xy 107.017784 -7.487754) (xy 107.057933 -7.449045) (xy 107.103291 -7.416594)
			(xy 107.152891 -7.391093) (xy 107.205675 -7.373086) (xy 107.260518 -7.362956) (xy 107.316252 -7.360919)
			(xy 107.371689 -7.367019) (xy 107.425646 -7.381125) (xy 107.476975 -7.402937) (xy 107.524581 -7.431991)
			(xy 107.567449 -7.467666) (xy 107.604666 -7.509203) (xy 107.635439 -7.555716) (xy 107.659111 -7.606213)
			(xy 107.675179 -7.65962) (xy 107.683299 -7.714796) (xy 107.683808 -7.742682) (xy 107.683299 -7.770568)
			(xy 107.675179 -7.825744) (xy 107.659111 -7.879151) (xy 107.635439 -7.929648) (xy 107.604666 -7.976161)
			(xy 107.567449 -8.017698) (xy 107.524581 -8.053373) (xy 107.476975 -8.082427) (xy 107.425646 -8.104239)
			(xy 107.371689 -8.118345) (xy 107.316252 -8.124445) (xy 107.260518 -8.122408) (xy 107.205675 -8.112278)
			(xy 107.152891 -8.094271) (xy 107.103291 -8.06877) (xy 107.057933 -8.036319) (xy 107.017784 -7.99761)
			(xy 106.983698 -7.953467) (xy 106.956402 -7.904832) (xy 106.936479 -7.852741) (xy 106.924353 -7.798304)
			(xy 106.920282 -7.742682) (xy 99.04667 -7.742682) (xy 99.064259 -7.780203) (xy 99.080327 -7.83361)
			(xy 99.088447 -7.888786) (xy 99.088956 -7.916672) (xy 99.088447 -7.944558) (xy 99.080327 -7.999734)
			(xy 99.064259 -8.053141) (xy 99.040587 -8.103638) (xy 99.009814 -8.150151) (xy 98.972597 -8.191688)
			(xy 98.929729 -8.227363) (xy 98.882123 -8.256417) (xy 98.830794 -8.278229) (xy 98.776837 -8.292335)
			(xy 98.7214 -8.298435) (xy 98.665666 -8.296398) (xy 98.610823 -8.286268) (xy 98.558039 -8.268261)
			(xy 98.508439 -8.24276) (xy 98.463081 -8.210309) (xy 98.422932 -8.1716) (xy 98.388846 -8.127457)
			(xy 98.36155 -8.078822) (xy 98.341627 -8.026731) (xy 98.329501 -7.972294) (xy 98.32543 -7.916672)
			(xy 96.473264 -7.916672) (xy 96.473264 -8.577072) (xy 97.05543 -8.577072) (xy 97.059501 -8.52145)
			(xy 97.071627 -8.467013) (xy 97.09155 -8.414922) (xy 97.118846 -8.366287) (xy 97.152932 -8.322144)
			(xy 97.193081 -8.283435) (xy 97.238439 -8.250984) (xy 97.288039 -8.225483) (xy 97.340823 -8.207476)
			(xy 97.395666 -8.197346) (xy 97.4514 -8.195309) (xy 97.506837 -8.201409) (xy 97.560794 -8.215515)
			(xy 97.612123 -8.237327) (xy 97.659729 -8.266381) (xy 97.699828 -8.299752) (xy 104.750581 -8.299752)
			(xy 104.750581 -8.245248) (xy 104.758338 -8.1913) (xy 104.773694 -8.139004) (xy 104.796336 -8.089426)
			(xy 104.825804 -8.043575) (xy 104.861497 -8.002385) (xy 104.902688 -7.966694) (xy 104.94854 -7.937228)
			(xy 104.998119 -7.914588) (xy 105.050415 -7.899235) (xy 105.104364 -7.89148) (xy 105.131616 -7.891018)
			(xy 105.16089 -7.891548) (xy 105.218749 -7.900509) (xy 105.27456 -7.918202) (xy 105.327014 -7.944212)
			(xy 105.374879 -7.977929) (xy 105.417033 -8.018562) (xy 105.452485 -8.065157) (xy 105.480405 -8.11662)
			(xy 105.490772 -8.144002) (xy 105.495899 -8.156931) (xy 105.512004 -8.179593) (xy 105.53362 -8.197078)
			(xy 105.559148 -8.208091) (xy 105.586699 -8.211819) (xy 105.614236 -8.207984) (xy 105.63972 -8.196871)
			(xy 105.650792 -8.188452) (xy 105.671338 -8.172191) (xy 105.71604 -8.144855) (xy 105.76406 -8.123891)
			(xy 105.814497 -8.109692) (xy 105.866401 -8.102525) (xy 105.8926 -8.102092) (xy 105.919851 -8.102578)
			(xy 105.973799 -8.110334) (xy 106.026094 -8.125689) (xy 106.075671 -8.148331) (xy 106.121521 -8.177797)
			(xy 106.162712 -8.213488) (xy 106.198403 -8.254679) (xy 106.227869 -8.300529) (xy 106.250511 -8.350106)
			(xy 106.265866 -8.402401) (xy 106.273622 -8.456349) (xy 106.273622 -8.510851) (xy 106.265866 -8.564799)
			(xy 106.250511 -8.617094) (xy 106.227869 -8.666671) (xy 106.198403 -8.712521) (xy 106.162712 -8.753712)
			(xy 106.121521 -8.789403) (xy 106.075671 -8.818869) (xy 106.026094 -8.841511) (xy 105.973799 -8.856866)
			(xy 105.919851 -8.864622) (xy 105.8926 -8.865108) (xy 105.863327 -8.864547) (xy 105.805471 -8.85559)
			(xy 105.749661 -8.8379) (xy 105.697208 -8.811894) (xy 105.649343 -8.778181) (xy 105.607189 -8.737553)
			(xy 105.571735 -8.690963) (xy 105.543813 -8.639504) (xy 105.533444 -8.612124) (xy 105.528286 -8.599208)
			(xy 105.512189 -8.576544) (xy 105.490579 -8.559057) (xy 105.465056 -8.548042) (xy 105.437509 -8.544312)
			(xy 105.409976 -8.548145) (xy 105.384494 -8.559256) (xy 105.373424 -8.567674) (xy 105.352864 -8.583917)
			(xy 105.308167 -8.611257) (xy 105.260151 -8.632227) (xy 105.209717 -8.64643) (xy 105.157814 -8.6536)
			(xy 105.131616 -8.654034) (xy 105.104364 -8.65352) (xy 105.050415 -8.645765) (xy 104.998119 -8.630412)
			(xy 104.94854 -8.607772) (xy 104.902688 -8.578306) (xy 104.861497 -8.542615) (xy 104.825804 -8.501425)
			(xy 104.796336 -8.455574) (xy 104.773694 -8.405996) (xy 104.758338 -8.3537) (xy 104.750581 -8.299752)
			(xy 97.699828 -8.299752) (xy 97.702597 -8.302056) (xy 97.739814 -8.343593) (xy 97.770587 -8.390106)
			(xy 97.794259 -8.440603) (xy 97.810327 -8.49401) (xy 97.818447 -8.549186) (xy 97.818956 -8.577072)
			(xy 97.818447 -8.604958) (xy 97.810327 -8.660134) (xy 97.794259 -8.713541) (xy 97.770587 -8.764038)
			(xy 97.739814 -8.810551) (xy 97.702597 -8.852088) (xy 97.659729 -8.887763) (xy 97.612123 -8.916817)
			(xy 97.560794 -8.938629) (xy 97.506837 -8.952735) (xy 97.4514 -8.958835) (xy 97.395666 -8.956798)
			(xy 97.340823 -8.946668) (xy 97.288039 -8.928661) (xy 97.238439 -8.90316) (xy 97.193081 -8.870709)
			(xy 97.152932 -8.832) (xy 97.118846 -8.787857) (xy 97.09155 -8.739222) (xy 97.071627 -8.687131) (xy 97.059501 -8.632694)
			(xy 97.05543 -8.577072) (xy 96.473264 -8.577072) (xy 96.473264 -9.535922) (xy 100.374702 -9.535922)
			(xy 100.378773 -9.4803) (xy 100.390899 -9.425863) (xy 100.410822 -9.373772) (xy 100.438118 -9.325137)
			(xy 100.472204 -9.280994) (xy 100.512353 -9.242285) (xy 100.557711 -9.209834) (xy 100.607311 -9.184333)
			(xy 100.660095 -9.166326) (xy 100.714938 -9.156196) (xy 100.770672 -9.154159) (xy 100.826109 -9.160259)
			(xy 100.880066 -9.174365) (xy 100.931395 -9.196177) (xy 100.979001 -9.225231) (xy 101.021869 -9.260906)
			(xy 101.059086 -9.302443) (xy 101.089859 -9.348956) (xy 101.113531 -9.399453) (xy 101.129599 -9.45286)
			(xy 101.137719 -9.508036) (xy 101.138168 -9.53262) (xy 103.422702 -9.53262) (xy 103.426773 -9.476998)
			(xy 103.438899 -9.422561) (xy 103.458822 -9.37047) (xy 103.486118 -9.321835) (xy 103.520204 -9.277692)
			(xy 103.560353 -9.238983) (xy 103.605711 -9.206532) (xy 103.655311 -9.181031) (xy 103.708095 -9.163024)
			(xy 103.762938 -9.152894) (xy 103.818672 -9.150857) (xy 103.874109 -9.156957) (xy 103.928066 -9.171063)
			(xy 103.979395 -9.192875) (xy 104.027001 -9.221929) (xy 104.069869 -9.257604) (xy 104.107086 -9.299141)
			(xy 104.137859 -9.345654) (xy 104.161531 -9.396151) (xy 104.177599 -9.449558) (xy 104.185719 -9.504734)
			(xy 104.186228 -9.53262) (xy 104.185719 -9.560506) (xy 104.177599 -9.615682) (xy 104.161531 -9.669089)
			(xy 104.137859 -9.719586) (xy 104.107086 -9.766099) (xy 104.069869 -9.807636) (xy 104.027001 -9.843311)
			(xy 103.979395 -9.872365) (xy 103.928066 -9.894177) (xy 103.874109 -9.908283) (xy 103.818672 -9.914383)
			(xy 103.762938 -9.912346) (xy 103.708095 -9.902216) (xy 103.655311 -9.884209) (xy 103.605711 -9.858708)
			(xy 103.560353 -9.826257) (xy 103.520204 -9.787548) (xy 103.486118 -9.743405) (xy 103.458822 -9.69477)
			(xy 103.438899 -9.642679) (xy 103.426773 -9.588242) (xy 103.422702 -9.53262) (xy 101.138168 -9.53262)
			(xy 101.138228 -9.535922) (xy 101.137719 -9.563808) (xy 101.129599 -9.618984) (xy 101.113531 -9.672391)
			(xy 101.089859 -9.722888) (xy 101.059086 -9.769401) (xy 101.021869 -9.810938) (xy 100.979001 -9.846613)
			(xy 100.931395 -9.875667) (xy 100.880066 -9.897479) (xy 100.826109 -9.911585) (xy 100.770672 -9.917685)
			(xy 100.714938 -9.915648) (xy 100.660095 -9.905518) (xy 100.607311 -9.887511) (xy 100.557711 -9.86201)
			(xy 100.512353 -9.829559) (xy 100.472204 -9.79085) (xy 100.438118 -9.746707) (xy 100.410822 -9.698072)
			(xy 100.390899 -9.645981) (xy 100.378773 -9.591544) (xy 100.374702 -9.535922) (xy 96.473264 -9.535922)
			(xy 96.473264 -11.543792) (xy 101.399338 -11.543792) (xy 101.403409 -11.48817) (xy 101.415535 -11.433733)
			(xy 101.435458 -11.381642) (xy 101.462754 -11.333007) (xy 101.49684 -11.288864) (xy 101.536989 -11.250155)
			(xy 101.582347 -11.217704) (xy 101.631947 -11.192203) (xy 101.684731 -11.174196) (xy 101.739574 -11.164066)
			(xy 101.795308 -11.162029) (xy 101.850745 -11.168129) (xy 101.904702 -11.182235) (xy 101.956031 -11.204047)
			(xy 102.003637 -11.233101) (xy 102.046505 -11.268776) (xy 102.083722 -11.310313) (xy 102.114495 -11.356826)
			(xy 102.138167 -11.407323) (xy 102.154235 -11.46073) (xy 102.162355 -11.515906) (xy 102.162864 -11.543792)
			(xy 102.408226 -11.543792) (xy 102.412297 -11.48817) (xy 102.424423 -11.433733) (xy 102.444346 -11.381642)
			(xy 102.471642 -11.333007) (xy 102.505728 -11.288864) (xy 102.545877 -11.250155) (xy 102.591235 -11.217704)
			(xy 102.640835 -11.192203) (xy 102.693619 -11.174196) (xy 102.748462 -11.164066) (xy 102.804196 -11.162029)
			(xy 102.859633 -11.168129) (xy 102.91359 -11.182235) (xy 102.964919 -11.204047) (xy 103.012525 -11.233101)
			(xy 103.055393 -11.268776) (xy 103.09261 -11.310313) (xy 103.123383 -11.356826) (xy 103.147055 -11.407323)
			(xy 103.163123 -11.46073) (xy 103.171243 -11.515906) (xy 103.171752 -11.543792) (xy 103.171243 -11.571678)
			(xy 103.163123 -11.626854) (xy 103.147055 -11.680261) (xy 103.123383 -11.730758) (xy 103.09261 -11.777271)
			(xy 103.055393 -11.818808) (xy 103.012525 -11.854483) (xy 102.964919 -11.883537) (xy 102.91359 -11.905349)
			(xy 102.859633 -11.919455) (xy 102.804196 -11.925555) (xy 102.748462 -11.923518) (xy 102.693619 -11.913388)
			(xy 102.640835 -11.895381) (xy 102.591235 -11.86988) (xy 102.545877 -11.837429) (xy 102.505728 -11.79872)
			(xy 102.471642 -11.754577) (xy 102.444346 -11.705942) (xy 102.424423 -11.653851) (xy 102.412297 -11.599414)
			(xy 102.408226 -11.543792) (xy 102.162864 -11.543792) (xy 102.162355 -11.571678) (xy 102.154235 -11.626854)
			(xy 102.138167 -11.680261) (xy 102.114495 -11.730758) (xy 102.083722 -11.777271) (xy 102.046505 -11.818808)
			(xy 102.003637 -11.854483) (xy 101.956031 -11.883537) (xy 101.904702 -11.905349) (xy 101.850745 -11.919455)
			(xy 101.795308 -11.925555) (xy 101.739574 -11.923518) (xy 101.684731 -11.913388) (xy 101.631947 -11.895381)
			(xy 101.582347 -11.86988) (xy 101.536989 -11.837429) (xy 101.49684 -11.79872) (xy 101.462754 -11.754577)
			(xy 101.435458 -11.705942) (xy 101.415535 -11.653851) (xy 101.403409 -11.599414) (xy 101.399338 -11.543792)
			(xy 96.473264 -11.543792) (xy 96.473264 -11.850116) (xy 96.472783 -11.903966) (xy 96.465099 -12.011391)
			(xy 96.449771 -12.117995) (xy 96.426876 -12.223234) (xy 96.396533 -12.326571) (xy 96.358895 -12.42748)
			(xy 96.314154 -12.525447) (xy 96.262539 -12.619973) (xy 96.204312 -12.710576) (xy 96.139769 -12.796794)
			(xy 96.06924 -12.878188) (xy 95.993085 -12.954343) (xy 95.911691 -13.024872) (xy 95.825472 -13.089414)
			(xy 95.734869 -13.147641) (xy 95.640344 -13.199256) (xy 95.542376 -13.243997) (xy 95.441467 -13.281634)
			(xy 95.33813 -13.311977) (xy 95.232891 -13.334871) (xy 95.126288 -13.350199) (xy 95.018862 -13.357883)
			(xy 94.965012 -13.358368) (xy 86.965028 -13.358368) (xy 86.911177 -13.3579) (xy 86.803748 -13.350218)
			(xy 86.697141 -13.334892) (xy 86.591899 -13.312) (xy 86.488558 -13.281659) (xy 86.387646 -13.244022)
			(xy 86.289675 -13.199282) (xy 86.195146 -13.147667) (xy 86.104539 -13.08944) (xy 86.018318 -13.024898)
			(xy 85.93692 -12.954368) (xy 85.860762 -12.878212) (xy 85.79023 -12.796817) (xy 85.725685 -12.710597)
			(xy 85.667455 -12.619992) (xy 85.615837 -12.525464) (xy 85.571095 -12.427495) (xy 85.533455 -12.326583)
			(xy 85.503111 -12.223244) (xy 85.480215 -12.118002) (xy 85.464887 -12.011396) (xy 85.457202 -11.903967)
			(xy 85.456776 -11.850116) (xy 85.456776 -3.357118) (xy 85.456359 -3.347096) (xy 85.448691 -3.328577)
			(xy 85.434518 -3.314405) (xy 85.415998 -3.30674) (xy 85.405976 -3.306318) (xy 84.29244 -3.306318)
			(xy 84.284937 -3.30655) (xy 84.270591 -3.310944) (xy 84.264246 -3.314954) (xy 84.263738 -3.314954)
			(xy 84.251546 -3.322574) (xy 84.228999 -3.336094) (xy 84.180976 -3.35749) (xy 84.130471 -3.372089)
			(xy 84.078439 -3.379616) (xy 84.052156 -3.380232) (xy 84.0486 -3.380232) (xy 84.020607 -3.379686)
			(xy 83.965236 -3.371391) (xy 83.911675 -3.355083) (xy 83.861077 -3.331112) (xy 83.837526 -3.31597)
			(xy 83.835748 -3.3147) (xy 83.831684 -3.312414) (xy 83.826054 -3.309594) (xy 83.813848 -3.30652)
			(xy 83.807554 -3.306318) (xy 82.159602 -3.306318) (xy 82.154014 -3.306572) (xy 82.143812 -3.30824)
			(xy 82.125867 -3.318468) (xy 82.119216 -3.326384) (xy 82.115406 -3.332226) (xy 82.100674 -3.358388)
			(xy 82.071972 -3.409188) (xy 82.070956 -3.41122) (xy 82.06834 -3.416897) (xy 82.065642 -3.429099)
			(xy 82.065622 -3.43535) (xy 82.065876 -3.442208) (xy 82.069686 -3.455416) (xy 82.073242 -3.461004)
			(xy 82.07375 -3.46202) (xy 82.075274 -3.464306) (xy 82.077306 -3.467608) (xy 82.07756 -3.46837) (xy 82.089743 -3.490224)
			(xy 82.108917 -3.536438) (xy 82.121896 -3.584759) (xy 82.128456 -3.634361) (xy 82.128868 -3.659378)
			(xy 82.128868 -3.668014) (xy 82.127823 -3.694874) (xy 82.119118 -3.747918) (xy 82.103053 -3.799214)
			(xy 82.079946 -3.847747) (xy 82.050255 -3.892556) (xy 82.014567 -3.932753) (xy 81.973589 -3.967541)
			(xy 81.928134 -3.996232) (xy 81.886967 -4.014724) (xy 83.667852 -4.014724) (xy 83.671923 -3.959102)
			(xy 83.684049 -3.904665) (xy 83.703972 -3.852574) (xy 83.731268 -3.803939) (xy 83.765354 -3.759796)
			(xy 83.805503 -3.721087) (xy 83.850861 -3.688636) (xy 83.900461 -3.663135) (xy 83.953245 -3.645128)
			(xy 84.008088 -3.634998) (xy 84.063822 -3.632961) (xy 84.119259 -3.639061) (xy 84.173216 -3.653167)
			(xy 84.224545 -3.674979) (xy 84.272151 -3.704033) (xy 84.315019 -3.739708) (xy 84.352236 -3.781245)
			(xy 84.383009 -3.827758) (xy 84.406681 -3.878255) (xy 84.422749 -3.931662) (xy 84.430869 -3.986838)
			(xy 84.431378 -4.014724) (xy 84.430869 -4.04261) (xy 84.422749 -4.097786) (xy 84.406681 -4.151193)
			(xy 84.383009 -4.20169) (xy 84.352236 -4.248203) (xy 84.315019 -4.28974) (xy 84.272151 -4.325415)
			(xy 84.224545 -4.354469) (xy 84.173216 -4.376281) (xy 84.119259 -4.390387) (xy 84.063822 -4.396487)
			(xy 84.008088 -4.39445) (xy 83.953245 -4.38432) (xy 83.900461 -4.366313) (xy 83.850861 -4.340812)
			(xy 83.805503 -4.308361) (xy 83.765354 -4.269652) (xy 83.731268 -4.225509) (xy 83.703972 -4.176874)
			(xy 83.684049 -4.124783) (xy 83.671923 -4.070346) (xy 83.667852 -4.014724) (xy 81.886967 -4.014724)
			(xy 81.8791 -4.018258) (xy 81.82746 -4.033182) (xy 81.774237 -4.040709) (xy 81.74736 -4.04114) (xy 81.72011 -4.040652)
			(xy 81.666165 -4.032891) (xy 81.613873 -4.017532) (xy 81.564299 -3.994889) (xy 81.518451 -3.965422)
			(xy 81.477263 -3.929731) (xy 81.441573 -3.888543) (xy 81.412107 -3.842694) (xy 81.389465 -3.79312)
			(xy 81.374108 -3.740827) (xy 81.366348 -3.686882) (xy 81.365852 -3.659632) (xy 81.365852 -3.65887)
			(xy 81.366278 -3.632793) (xy 81.373338 -3.581119) (xy 81.387363 -3.530887) (xy 81.408093 -3.48303)
			(xy 81.421224 -3.460496) (xy 81.425542 -3.453384) (xy 81.42732 -3.446018) (xy 81.429065 -3.436698)
			(xy 81.426463 -3.417932) (xy 81.42224 -3.409442) (xy 81.414366 -3.395218) (xy 81.387696 -3.347212)
			(xy 81.387188 -3.346704) (xy 81.380838 -3.335528) (xy 81.37398 -3.326892) (xy 81.368138 -3.32105)
			(xy 81.365289 -3.318342) (xy 81.358913 -3.313743) (xy 81.355438 -3.311906) (xy 81.350011 -3.309325)
			(xy 81.338331 -3.306505) (xy 81.332324 -3.306318) (xy 74.065892 -3.306318) (xy 74.055994 -3.306839)
			(xy 74.037703 -3.314424) (xy 74.030332 -3.32105) (xy 74.02322 -3.328162) (xy 74.015346 -3.346704)
			(xy 74.015346 -3.356864) (xy 74.014722 -3.38402) (xy 74.006732 -3.437748) (xy 73.991201 -3.4898)
			(xy 73.968445 -3.539122) (xy 73.938923 -3.584718) (xy 73.903233 -3.625666) (xy 73.862096 -3.661138)
			(xy 73.816343 -3.690416) (xy 73.7669 -3.712909) (xy 73.714767 -3.728162) (xy 73.660997 -3.735866)
			(xy 73.606679 -3.735866) (xy 73.552909 -3.728162) (xy 73.500776 -3.712909) (xy 73.451333 -3.690416)
			(xy 73.40558 -3.661138) (xy 73.364443 -3.625666) (xy 73.328753 -3.584718) (xy 73.299231 -3.539122)
			(xy 73.276475 -3.4898) (xy 73.260944 -3.437748) (xy 73.252954 -3.38402) (xy 73.25233 -3.356864) (xy 73.25233 -3.346704)
			(xy 73.244456 -3.328162) (xy 73.237344 -3.32105) (xy 73.229988 -3.3144) (xy 73.211688 -3.306812)
			(xy 73.201784 -3.306318) (xy 70.524116 -3.306318) (xy 70.514094 -3.306735) (xy 70.495574 -3.314403)
			(xy 70.481402 -3.328576) (xy 70.473734 -3.347096) (xy 70.473316 -3.357118) (xy 70.473316 -5.030724)
			(xy 81.62112 -5.030724) (xy 81.625191 -4.975102) (xy 81.637317 -4.920665) (xy 81.65724 -4.868574)
			(xy 81.684536 -4.819939) (xy 81.718622 -4.775796) (xy 81.758771 -4.737087) (xy 81.804129 -4.704636)
			(xy 81.853729 -4.679135) (xy 81.906513 -4.661128) (xy 81.961356 -4.650998) (xy 82.01709 -4.648961)
			(xy 82.072527 -4.655061) (xy 82.126484 -4.669167) (xy 82.177813 -4.690979) (xy 82.225419 -4.720033)
			(xy 82.268287 -4.755708) (xy 82.305504 -4.797245) (xy 82.336277 -4.843758) (xy 82.359949 -4.894255)
			(xy 82.376017 -4.947662) (xy 82.384137 -5.002838) (xy 82.384646 -5.030724) (xy 83.667852 -5.030724)
			(xy 83.671923 -4.975102) (xy 83.684049 -4.920665) (xy 83.703972 -4.868574) (xy 83.731268 -4.819939)
			(xy 83.765354 -4.775796) (xy 83.805503 -4.737087) (xy 83.850861 -4.704636) (xy 83.900461 -4.679135)
			(xy 83.953245 -4.661128) (xy 84.008088 -4.650998) (xy 84.063822 -4.648961) (xy 84.119259 -4.655061)
			(xy 84.173216 -4.669167) (xy 84.224545 -4.690979) (xy 84.272151 -4.720033) (xy 84.315019 -4.755708)
			(xy 84.352236 -4.797245) (xy 84.383009 -4.843758) (xy 84.406681 -4.894255) (xy 84.422749 -4.947662)
			(xy 84.430869 -5.002838) (xy 84.431378 -5.030724) (xy 84.430869 -5.05861) (xy 84.422749 -5.113786)
			(xy 84.406681 -5.167193) (xy 84.383009 -5.21769) (xy 84.352236 -5.264203) (xy 84.315019 -5.30574)
			(xy 84.272151 -5.341415) (xy 84.224545 -5.370469) (xy 84.173216 -5.392281) (xy 84.119259 -5.406387)
			(xy 84.063822 -5.412487) (xy 84.008088 -5.41045) (xy 83.953245 -5.40032) (xy 83.900461 -5.382313)
			(xy 83.850861 -5.356812) (xy 83.805503 -5.324361) (xy 83.765354 -5.285652) (xy 83.731268 -5.241509)
			(xy 83.703972 -5.192874) (xy 83.684049 -5.140783) (xy 83.671923 -5.086346) (xy 83.667852 -5.030724)
			(xy 82.384646 -5.030724) (xy 82.384137 -5.05861) (xy 82.376017 -5.113786) (xy 82.359949 -5.167193)
			(xy 82.336277 -5.21769) (xy 82.305504 -5.264203) (xy 82.268287 -5.30574) (xy 82.225419 -5.341415)
			(xy 82.177813 -5.370469) (xy 82.126484 -5.392281) (xy 82.072527 -5.406387) (xy 82.01709 -5.412487)
			(xy 81.961356 -5.41045) (xy 81.906513 -5.40032) (xy 81.853729 -5.382313) (xy 81.804129 -5.356812)
			(xy 81.758771 -5.324361) (xy 81.718622 -5.285652) (xy 81.684536 -5.241509) (xy 81.65724 -5.192874)
			(xy 81.637317 -5.140783) (xy 81.625191 -5.086346) (xy 81.62112 -5.030724) (xy 70.473316 -5.030724)
			(xy 70.473316 -5.889752) (xy 73.306684 -5.889752) (xy 73.310755 -5.83413) (xy 73.322881 -5.779693)
			(xy 73.342804 -5.727602) (xy 73.3701 -5.678967) (xy 73.404186 -5.634824) (xy 73.444335 -5.596115)
			(xy 73.489693 -5.563664) (xy 73.539293 -5.538163) (xy 73.592077 -5.520156) (xy 73.64692 -5.510026)
			(xy 73.702654 -5.507989) (xy 73.758091 -5.514089) (xy 73.812048 -5.528195) (xy 73.863377 -5.550007)
			(xy 73.910983 -5.579061) (xy 73.953851 -5.614736) (xy 73.991068 -5.656273) (xy 74.021841 -5.702786)
			(xy 74.045513 -5.753283) (xy 74.061581 -5.80669) (xy 74.069701 -5.861866) (xy 74.07021 -5.889752)
			(xy 74.069701 -5.917638) (xy 74.061581 -5.972814) (xy 74.045513 -6.026221) (xy 74.021841 -6.076718)
			(xy 73.991068 -6.123231) (xy 73.953851 -6.164768) (xy 73.910983 -6.200443) (xy 73.863377 -6.229497)
			(xy 73.812048 -6.251309) (xy 73.758091 -6.265415) (xy 73.702654 -6.271515) (xy 73.64692 -6.269478)
			(xy 73.592077 -6.259348) (xy 73.539293 -6.241341) (xy 73.489693 -6.21584) (xy 73.444335 -6.183389)
			(xy 73.404186 -6.14468) (xy 73.3701 -6.100537) (xy 73.342804 -6.051902) (xy 73.322881 -5.999811)
			(xy 73.310755 -5.945374) (xy 73.306684 -5.889752) (xy 70.473316 -5.889752) (xy 70.473316 -6.651498)
			(xy 81.434684 -6.651498) (xy 81.438755 -6.595876) (xy 81.450881 -6.541439) (xy 81.470804 -6.489348)
			(xy 81.4981 -6.440713) (xy 81.532186 -6.39657) (xy 81.572335 -6.357861) (xy 81.617693 -6.32541) (xy 81.667293 -6.299909)
			(xy 81.720077 -6.281902) (xy 81.77492 -6.271772) (xy 81.830654 -6.269735) (xy 81.886091 -6.275835)
			(xy 81.940048 -6.289941) (xy 81.991377 -6.311753) (xy 82.038983 -6.340807) (xy 82.081851 -6.376482)
			(xy 82.119068 -6.418019) (xy 82.149841 -6.464532) (xy 82.173513 -6.515029) (xy 82.189581 -6.568436)
			(xy 82.197701 -6.623612) (xy 82.19821 -6.651498) (xy 82.197701 -6.679384) (xy 82.189581 -6.73456)
			(xy 82.173513 -6.787967) (xy 82.149841 -6.838464) (xy 82.119068 -6.884977) (xy 82.081851 -6.926514)
			(xy 82.038983 -6.962189) (xy 81.991377 -6.991243) (xy 81.940048 -7.013055) (xy 81.886091 -7.027161)
			(xy 81.830654 -7.033261) (xy 81.77492 -7.031224) (xy 81.720077 -7.021094) (xy 81.667293 -7.003087)
			(xy 81.617693 -6.977586) (xy 81.572335 -6.945135) (xy 81.532186 -6.906426) (xy 81.4981 -6.862283)
			(xy 81.470804 -6.813648) (xy 81.450881 -6.761557) (xy 81.438755 -6.70712) (xy 81.434684 -6.651498)
			(xy 70.473316 -6.651498) (xy 70.473316 -7.183374) (xy 73.184256 -7.183374) (xy 73.188327 -7.127752)
			(xy 73.200453 -7.073315) (xy 73.220376 -7.021224) (xy 73.247672 -6.972589) (xy 73.281758 -6.928446)
			(xy 73.321907 -6.889737) (xy 73.367265 -6.857286) (xy 73.416865 -6.831785) (xy 73.469649 -6.813778)
			(xy 73.524492 -6.803648) (xy 73.580226 -6.801611) (xy 73.635663 -6.807711) (xy 73.68962 -6.821817)
			(xy 73.740949 -6.843629) (xy 73.788555 -6.872683) (xy 73.831423 -6.908358) (xy 73.86864 -6.949895)
			(xy 73.899413 -6.996408) (xy 73.923085 -7.046905) (xy 73.927844 -7.062724) (xy 83.667852 -7.062724)
			(xy 83.671923 -7.007102) (xy 83.684049 -6.952665) (xy 83.703972 -6.900574) (xy 83.731268 -6.851939)
			(xy 83.765354 -6.807796) (xy 83.805503 -6.769087) (xy 83.850861 -6.736636) (xy 83.900461 -6.711135)
			(xy 83.953245 -6.693128) (xy 84.008088 -6.682998) (xy 84.063822 -6.680961) (xy 84.119259 -6.687061)
			(xy 84.173216 -6.701167) (xy 84.224545 -6.722979) (xy 84.272151 -6.752033) (xy 84.315019 -6.787708)
			(xy 84.352236 -6.829245) (xy 84.383009 -6.875758) (xy 84.406681 -6.926255) (xy 84.422749 -6.979662)
			(xy 84.430869 -7.034838) (xy 84.431378 -7.062724) (xy 84.430869 -7.09061) (xy 84.422749 -7.145786)
			(xy 84.406681 -7.199193) (xy 84.383009 -7.24969) (xy 84.352236 -7.296203) (xy 84.315019 -7.33774)
			(xy 84.272151 -7.373415) (xy 84.224545 -7.402469) (xy 84.173216 -7.424281) (xy 84.119259 -7.438387)
			(xy 84.063822 -7.444487) (xy 84.008088 -7.44245) (xy 83.953245 -7.43232) (xy 83.900461 -7.414313)
			(xy 83.850861 -7.388812) (xy 83.805503 -7.356361) (xy 83.765354 -7.317652) (xy 83.731268 -7.273509)
			(xy 83.703972 -7.224874) (xy 83.684049 -7.172783) (xy 83.671923 -7.118346) (xy 83.667852 -7.062724)
			(xy 73.927844 -7.062724) (xy 73.939153 -7.100312) (xy 73.947273 -7.155488) (xy 73.947782 -7.183374)
			(xy 73.947273 -7.21126) (xy 73.939153 -7.266436) (xy 73.923085 -7.319843) (xy 73.899413 -7.37034)
			(xy 73.86864 -7.416853) (xy 73.831423 -7.45839) (xy 73.788555 -7.494065) (xy 73.740949 -7.523119)
			(xy 73.68962 -7.544931) (xy 73.635663 -7.559037) (xy 73.580226 -7.565137) (xy 73.524492 -7.5631)
			(xy 73.469649 -7.55297) (xy 73.416865 -7.534963) (xy 73.367265 -7.509462) (xy 73.321907 -7.477011)
			(xy 73.281758 -7.438302) (xy 73.247672 -7.394159) (xy 73.220376 -7.345524) (xy 73.200453 -7.293433)
			(xy 73.188327 -7.238996) (xy 73.184256 -7.183374) (xy 70.473316 -7.183374) (xy 70.473316 -8.653272)
			(xy 71.923146 -8.653272) (xy 71.927217 -8.59765) (xy 71.939343 -8.543213) (xy 71.959266 -8.491122)
			(xy 71.986562 -8.442487) (xy 72.020648 -8.398344) (xy 72.060797 -8.359635) (xy 72.106155 -8.327184)
			(xy 72.155755 -8.301683) (xy 72.208539 -8.283676) (xy 72.263382 -8.273546) (xy 72.319116 -8.271509)
			(xy 72.374553 -8.277609) (xy 72.42851 -8.291715) (xy 72.479839 -8.313527) (xy 72.527445 -8.342581)
			(xy 72.570313 -8.378256) (xy 72.60753 -8.419793) (xy 72.638303 -8.466306) (xy 72.661975 -8.516803)
			(xy 72.678043 -8.57021) (xy 72.686163 -8.625386) (xy 72.686672 -8.653272) (xy 72.686163 -8.681158)
			(xy 72.678043 -8.736334) (xy 72.661975 -8.789741) (xy 72.638303 -8.840238) (xy 72.60753 -8.886751)
			(xy 72.570313 -8.928288) (xy 72.527445 -8.963963) (xy 72.479839 -8.993017) (xy 72.42851 -9.014829)
			(xy 72.374553 -9.028935) (xy 72.319116 -9.035035) (xy 72.263382 -9.032998) (xy 72.208539 -9.022868)
			(xy 72.155755 -9.004861) (xy 72.106155 -8.97936) (xy 72.060797 -8.946909) (xy 72.020648 -8.9082)
			(xy 71.986562 -8.864057) (xy 71.959266 -8.815422) (xy 71.939343 -8.763331) (xy 71.927217 -8.708894)
			(xy 71.923146 -8.653272) (xy 70.473316 -8.653272) (xy 70.473316 -9.33069) (xy 73.22642 -9.33069)
			(xy 73.230491 -9.275068) (xy 73.242617 -9.220631) (xy 73.26254 -9.16854) (xy 73.289836 -9.119905)
			(xy 73.323922 -9.075762) (xy 73.364071 -9.037053) (xy 73.409429 -9.004602) (xy 73.459029 -8.979101)
			(xy 73.511813 -8.961094) (xy 73.566656 -8.950964) (xy 73.62239 -8.948927) (xy 73.677827 -8.955027)
			(xy 73.731784 -8.969133) (xy 73.783113 -8.990945) (xy 73.830719 -9.019999) (xy 73.873587 -9.055674)
			(xy 73.910804 -9.097211) (xy 73.941577 -9.143724) (xy 73.965249 -9.194221) (xy 73.981317 -9.247628)
			(xy 73.989437 -9.302804) (xy 73.989946 -9.33069) (xy 73.989437 -9.358576) (xy 73.981317 -9.413752)
			(xy 73.965249 -9.467159) (xy 73.941577 -9.517656) (xy 73.929492 -9.535922) (xy 78.931006 -9.535922)
			(xy 78.935077 -9.4803) (xy 78.947203 -9.425863) (xy 78.967126 -9.373772) (xy 78.994422 -9.325137)
			(xy 79.028508 -9.280994) (xy 79.068657 -9.242285) (xy 79.114015 -9.209834) (xy 79.163615 -9.184333)
			(xy 79.216399 -9.166326) (xy 79.271242 -9.156196) (xy 79.326976 -9.154159) (xy 79.382413 -9.160259)
			(xy 79.43637 -9.174365) (xy 79.487699 -9.196177) (xy 79.535305 -9.225231) (xy 79.578173 -9.260906)
			(xy 79.61539 -9.302443) (xy 79.646163 -9.348956) (xy 79.669835 -9.399453) (xy 79.685903 -9.45286)
			(xy 79.694023 -9.508036) (xy 79.694532 -9.535922) (xy 79.694023 -9.563808) (xy 79.685903 -9.618984)
			(xy 79.669835 -9.672391) (xy 79.646163 -9.722888) (xy 79.61539 -9.769401) (xy 79.578173 -9.810938)
			(xy 79.535305 -9.846613) (xy 79.487699 -9.875667) (xy 79.43637 -9.897479) (xy 79.382413 -9.911585)
			(xy 79.326976 -9.917685) (xy 79.271242 -9.915648) (xy 79.216399 -9.905518) (xy 79.163615 -9.887511)
			(xy 79.114015 -9.86201) (xy 79.068657 -9.829559) (xy 79.028508 -9.79085) (xy 78.994422 -9.746707)
			(xy 78.967126 -9.698072) (xy 78.947203 -9.645981) (xy 78.935077 -9.591544) (xy 78.931006 -9.535922)
			(xy 73.929492 -9.535922) (xy 73.910804 -9.564169) (xy 73.873587 -9.605706) (xy 73.830719 -9.641381)
			(xy 73.783113 -9.670435) (xy 73.731784 -9.692247) (xy 73.677827 -9.706353) (xy 73.62239 -9.712453)
			(xy 73.566656 -9.710416) (xy 73.511813 -9.700286) (xy 73.459029 -9.682279) (xy 73.409429 -9.656778)
			(xy 73.364071 -9.624327) (xy 73.323922 -9.585618) (xy 73.289836 -9.541475) (xy 73.26254 -9.49284)
			(xy 73.242617 -9.440749) (xy 73.230491 -9.386312) (xy 73.22642 -9.33069) (xy 70.473316 -9.33069)
			(xy 70.473316 -11.850116) (xy 70.472846 -11.903966) (xy 70.465162 -12.011391) (xy 70.449833 -12.117994)
			(xy 70.426939 -12.223232) (xy 70.396595 -12.326568) (xy 70.358956 -12.427477) (xy 70.314215 -12.525443)
			(xy 70.262599 -12.619968) (xy 70.204371 -12.71057) (xy 70.139827 -12.796787) (xy 70.069298 -12.878179)
			(xy 69.993141 -12.954333) (xy 69.911746 -13.02486) (xy 69.825527 -13.0894) (xy 69.734923 -13.147625)
			(xy 69.640397 -13.199238) (xy 69.542429 -13.243976) (xy 69.441519 -13.281611) (xy 69.338181 -13.311952)
			(xy 69.232943 -13.334842) (xy 69.126339 -13.350167) (xy 69.018914 -13.357848) (xy 68.965064 -13.358368)
			(xy 60.96508 -13.358368) (xy 60.91123 -13.357887) (xy 60.803805 -13.350202) (xy 60.697201 -13.334874)
			(xy 60.591963 -13.31198) (xy 60.488626 -13.281636) (xy 60.387717 -13.243998) (xy 60.28975 -13.199257)
			(xy 60.195224 -13.147642) (xy 60.104621 -13.089414) (xy 60.018403 -13.024872) (xy 59.937009 -12.954343)
			(xy 59.860854 -12.878188) (xy 59.790326 -12.796794) (xy 59.725783 -12.710575) (xy 59.667556 -12.619973)
			(xy 59.615941 -12.525447) (xy 59.5712 -12.42748) (xy 59.533563 -12.326571) (xy 59.503219 -12.223233)
			(xy 59.480325 -12.117995) (xy 59.464997 -12.011391) (xy 59.457313 -11.903966) (xy 59.456828 -11.850116)
			(xy 59.456828 -3.357118) (xy 59.456344 -3.347106) (xy 59.448688 -3.328603) (xy 59.434536 -3.314438)
			(xy 59.41604 -3.306765) (xy 59.406028 -3.306318) (xy 44.524168 -3.306318) (xy 44.514166 -3.306812)
			(xy 44.495688 -3.314478) (xy 44.48155 -3.32863) (xy 44.473902 -3.347115) (xy 44.473368 -3.357118)
			(xy 44.473368 -11.850116) (xy 44.472887 -11.903966) (xy 44.465203 -12.011392) (xy 44.449875 -12.117995)
			(xy 44.42698 -12.223234) (xy 44.396637 -12.326571) (xy 44.358999 -12.427481) (xy 44.314259 -12.525448)
			(xy 44.262643 -12.619974) (xy 44.204416 -12.710577) (xy 44.139873 -12.796795) (xy 44.069345 -12.878189)
			(xy 43.993189 -12.954345) (xy 43.911795 -13.024873) (xy 43.825577 -13.089416) (xy 43.734974 -13.147643)
			(xy 43.640448 -13.199259) (xy 43.542481 -13.243999) (xy 43.441571 -13.281637) (xy 43.338234 -13.31198)
			(xy 43.232995 -13.334875) (xy 43.126392 -13.350203) (xy 43.018966 -13.357887) (xy 42.965116 -13.358368)
			(xy 34.964878 -13.358368) (xy 34.911028 -13.357887) (xy 34.803603 -13.350202) (xy 34.696999 -13.334874)
			(xy 34.591761 -13.311979) (xy 34.488424 -13.281636) (xy 34.387515 -13.243998) (xy 34.289548 -13.199257)
			(xy 34.195023 -13.147641) (xy 34.10442 -13.089414) (xy 34.018202 -13.024871) (xy 33.936809 -12.954342)
			(xy 33.860653 -12.878187) (xy 33.790125 -12.796793) (xy 33.725583 -12.710575) (xy 33.667356 -12.619972)
			(xy 33.615741 -12.525446) (xy 33.571 -12.427479) (xy 33.533362 -12.32657) (xy 33.503019 -12.223233)
			(xy 33.480125 -12.117995) (xy 33.464797 -12.011391) (xy 33.457113 -11.903966) (xy 33.456626 -11.850116)
			(xy 33.456626 -3.357118) (xy 33.456142 -3.347106) (xy 33.448486 -3.328604) (xy 33.434333 -3.314439)
			(xy 33.415838 -3.306767) (xy 33.405826 -3.306318) (xy 18.523966 -3.306318) (xy 18.513964 -3.306812)
			(xy 18.495487 -3.314478) (xy 18.481349 -3.328631) (xy 18.473702 -3.347116) (xy 18.473166 -3.357118)
			(xy 18.473166 -11.850116) (xy 18.472686 -11.903966) (xy 18.465003 -12.011393) (xy 18.449676 -12.117997)
			(xy 18.426783 -12.223237) (xy 18.39644 -12.326575) (xy 18.358803 -12.427485) (xy 18.314063 -12.525453)
			(xy 18.262447 -12.61998) (xy 18.20422 -12.710584) (xy 18.139678 -12.796803) (xy 18.069149 -12.878198)
			(xy 17.992993 -12.954354) (xy 17.911599 -13.024883) (xy 17.82538 -13.089426) (xy 17.734777 -13.147653)
			(xy 17.64025 -13.199269) (xy 17.542282 -13.24401) (xy 17.441372 -13.281648) (xy 17.338034 -13.311991)
			(xy 17.232795 -13.334884) (xy 17.126191 -13.350212) (xy 17.018764 -13.357896) (xy 16.964914 -13.358368)
			(xy 8.96493 -13.358368) (xy 8.911079 -13.357899) (xy 8.803653 -13.350215) (xy 8.697048 -13.334888)
			(xy 8.591808 -13.311994) (xy 8.48847 -13.281651) (xy 8.387559 -13.244014) (xy 8.289591 -13.199273)
			(xy 8.195064 -13.147657) (xy 8.10446 -13.089429) (xy 8.018241 -13.024887) (xy 7.936846 -12.954357)
			(xy 7.86069 -12.878201) (xy 7.790161 -12.796806) (xy 7.725618 -12.710587) (xy 7.667391 -12.619983)
			(xy 7.615775 -12.525455) (xy 7.571035 -12.427487) (xy 7.533397 -12.326576) (xy 7.503055 -12.223238)
			(xy 7.480161 -12.117998) (xy 7.464834 -12.011393) (xy 7.457151 -11.903967) (xy 7.456678 -11.850116)
			(xy 7.456678 -2.181098) (xy 7.456505 -2.17509) (xy 7.453669 -2.163414) (xy 7.45109 -2.157984) (xy 7.44925 -2.15451)
			(xy 7.444656 -2.148131) (xy 7.441946 -2.145284) (xy 7.238238 -1.941576) (xy 7.231391 -1.934178) (xy 7.223659 -1.91558)
			(xy 7.223252 -1.905508) (xy 7.223252 -1.342136) (xy 7.223084 -1.336127) (xy 7.22026 -1.324444) (xy 7.217664 -1.319022)
			(xy 7.215826 -1.315547) (xy 7.211233 -1.309167) (xy 7.20852 -1.306322) (xy 7.208266 -1.306068) (xy 6.971792 -1.06934)
			(xy 6.739128 -0.836676) (xy 6.736279 -0.833967) (xy 6.729904 -0.829368) (xy 6.726428 -0.827532) (xy 6.721001 -0.82495)
			(xy 6.709321 -0.822132) (xy 6.703314 -0.821944) (xy 6.079998 -0.821944) (xy 6.069929 -0.821519) (xy 6.051331 -0.813798)
			(xy 6.04393 -0.806958) (xy 5.844794 -0.607822) (xy 5.841942 -0.605117) (xy 5.835563 -0.600526) (xy 5.832094 -0.598678)
			(xy 5.826668 -0.596092) (xy 5.814988 -0.593261) (xy 5.80898 -0.59309) (xy 1.626362 -0.59309) (xy 1.620352 -0.593256)
			(xy 1.608668 -0.596077) (xy 1.603248 -0.598678) (xy 1.599775 -0.600519) (xy 1.593397 -0.605114) (xy 1.590548 -0.607822)
			(xy 0.730504 -1.467866) (xy 0.727798 -1.470717) (xy 0.723204 -1.477095) (xy 0.72136 -1.480566) (xy 0.718777 -1.485993)
			(xy 0.715955 -1.497673) (xy 0.715772 -1.50368) (xy 0.715772 -14.05636) (xy 6.84225 -14.05636) (xy 6.846321 -14.000738)
			(xy 6.858447 -13.946301) (xy 6.87837 -13.89421) (xy 6.905666 -13.845575) (xy 6.939752 -13.801432)
			(xy 6.979901 -13.762723) (xy 7.025259 -13.730272) (xy 7.074859 -13.704771) (xy 7.127643 -13.686764)
			(xy 7.182486 -13.676634) (xy 7.23822 -13.674597) (xy 7.293657 -13.680697) (xy 7.347614 -13.694803)
			(xy 7.398943 -13.716615) (xy 7.446549 -13.745669) (xy 7.489417 -13.781344) (xy 7.526634 -13.822881)
			(xy 7.557407 -13.869394) (xy 7.581079 -13.919891) (xy 7.597147 -13.973298) (xy 7.605267 -14.028474)
			(xy 7.605776 -14.05636) (xy 7.605267 -14.084246) (xy 7.597147 -14.139422) (xy 7.581079 -14.192829)
			(xy 7.557407 -14.243326) (xy 7.526634 -14.289839) (xy 7.489417 -14.331376) (xy 7.446549 -14.367051)
			(xy 7.398943 -14.396105) (xy 7.347614 -14.417917) (xy 7.293657 -14.432023) (xy 7.23822 -14.438123)
			(xy 7.182486 -14.436086) (xy 7.127643 -14.425956) (xy 7.074859 -14.407949) (xy 7.025259 -14.382448)
			(xy 6.979901 -14.349997) (xy 6.939752 -14.311288) (xy 6.905666 -14.267145) (xy 6.87837 -14.21851)
			(xy 6.858447 -14.166419) (xy 6.846321 -14.111982) (xy 6.84225 -14.05636) (xy 0.715772 -14.05636)
			(xy 0.715772 -15.128748) (xy 7.834882 -15.128748) (xy 7.838953 -15.073126) (xy 7.851079 -15.018689)
			(xy 7.871002 -14.966598) (xy 7.898298 -14.917963) (xy 7.932384 -14.87382) (xy 7.972533 -14.835111)
			(xy 8.017891 -14.80266) (xy 8.067491 -14.777159) (xy 8.120275 -14.759152) (xy 8.175118 -14.749022)
			(xy 8.230852 -14.746985) (xy 8.286289 -14.753085) (xy 8.340246 -14.767191) (xy 8.391575 -14.789003)
			(xy 8.439181 -14.818057) (xy 8.482049 -14.853732) (xy 8.519266 -14.895269) (xy 8.550039 -14.941782)
			(xy 8.573711 -14.992279) (xy 8.589779 -15.045686) (xy 8.597899 -15.100862) (xy 8.598408 -15.128748)
			(xy 8.597899 -15.156634) (xy 8.589779 -15.21181) (xy 8.573711 -15.265217) (xy 8.550039 -15.315714)
			(xy 8.519266 -15.362227) (xy 8.482049 -15.403764) (xy 8.439181 -15.439439) (xy 8.391575 -15.468493)
			(xy 8.340246 -15.490305) (xy 8.286289 -15.504411) (xy 8.230852 -15.510511) (xy 8.175118 -15.508474)
			(xy 8.120275 -15.498344) (xy 8.067491 -15.480337) (xy 8.017891 -15.454836) (xy 7.972533 -15.422385)
			(xy 7.932384 -15.383676) (xy 7.898298 -15.339533) (xy 7.871002 -15.290898) (xy 7.851079 -15.238807)
			(xy 7.838953 -15.18437) (xy 7.834882 -15.128748) (xy 0.715772 -15.128748) (xy 0.715772 -15.649956)
			(xy 16.485374 -15.649956) (xy 16.489344 -15.519822) (xy 16.50124 -15.390172) (xy 16.521019 -15.261489)
			(xy 16.548605 -15.13425) (xy 16.583898 -15.008931) (xy 16.626764 -14.885995) (xy 16.677046 -14.765902)
			(xy 16.734555 -14.649098) (xy 16.799079 -14.536016) (xy 16.870376 -14.427079) (xy 16.948181 -14.322691)
			(xy 17.032206 -14.22324) (xy 17.122138 -14.129097) (xy 17.217642 -14.040612) (xy 17.318362 -13.958113)
			(xy 17.423924 -13.881908) (xy 17.533936 -13.812281) (xy 17.647988 -13.74949) (xy 17.765656 -13.693768)
			(xy 17.886502 -13.645324) (xy 18.010077 -13.604337) (xy 18.13592 -13.57096) (xy 18.263565 -13.545317)
			(xy 18.392535 -13.527503) (xy 18.522351 -13.517585) (xy 18.65253 -13.5156) (xy 18.782589 -13.521554)
			(xy 18.912042 -13.535427) (xy 19.040409 -13.557165) (xy 19.167212 -13.586689) (xy 19.291979 -13.623888)
			(xy 19.414246 -13.668624) (xy 19.533559 -13.720732) (xy 19.649472 -13.780015) (xy 19.761557 -13.846256)
			(xy 19.869394 -13.919206) (xy 19.972583 -13.998594) (xy 20.070741 -14.084126) (xy 20.163502 -14.175483)
			(xy 20.250521 -14.272325) (xy 20.331474 -14.374292) (xy 20.40606 -14.481004) (xy 20.474001 -14.592065)
			(xy 20.535046 -14.707061) (xy 20.588967 -14.825565) (xy 20.635562 -14.947136) (xy 20.67466 -15.071321)
			(xy 20.706114 -15.197659) (xy 20.729808 -15.32568) (xy 20.745652 -15.454906) (xy 20.75359 -15.584859)
			(xy 20.754086 -15.649956) (xy 42.485322 -15.649956) (xy 42.489292 -15.519822) (xy 42.501188 -15.390172)
			(xy 42.520967 -15.261489) (xy 42.548553 -15.13425) (xy 42.583846 -15.008931) (xy 42.626712 -14.885995)
			(xy 42.676994 -14.765902) (xy 42.734503 -14.649098) (xy 42.799027 -14.536016) (xy 42.870324 -14.427079)
			(xy 42.948129 -14.322691) (xy 43.032154 -14.22324) (xy 43.122086 -14.129097) (xy 43.21759 -14.040612)
			(xy 43.31831 -13.958113) (xy 43.423872 -13.881908) (xy 43.533884 -13.812281) (xy 43.647936 -13.74949)
			(xy 43.765604 -13.693768) (xy 43.88645 -13.645324) (xy 44.010025 -13.604337) (xy 44.135868 -13.57096)
			(xy 44.263513 -13.545317) (xy 44.392483 -13.527503) (xy 44.522299 -13.517585) (xy 44.652478 -13.5156)
			(xy 44.782537 -13.521554) (xy 44.91199 -13.535427) (xy 45.040357 -13.557165) (xy 45.16716 -13.586689)
			(xy 45.291927 -13.623888) (xy 45.414194 -13.668624) (xy 45.533507 -13.720732) (xy 45.64942 -13.780015)
			(xy 45.761505 -13.846256) (xy 45.869342 -13.919206) (xy 45.972531 -13.998594) (xy 46.070689 -14.084126)
			(xy 46.087114 -14.100302) (xy 51.242974 -14.100302) (xy 51.247045 -14.04468) (xy 51.259171 -13.990243)
			(xy 51.279094 -13.938152) (xy 51.30639 -13.889517) (xy 51.340476 -13.845374) (xy 51.380625 -13.806665)
			(xy 51.425983 -13.774214) (xy 51.475583 -13.748713) (xy 51.528367 -13.730706) (xy 51.58321 -13.720576)
			(xy 51.638944 -13.718539) (xy 51.694381 -13.724639) (xy 51.748338 -13.738745) (xy 51.799667 -13.760557)
			(xy 51.847273 -13.789611) (xy 51.890141 -13.825286) (xy 51.927358 -13.866823) (xy 51.958131 -13.913336)
			(xy 51.981803 -13.963833) (xy 51.997871 -14.01724) (xy 52.005991 -14.072416) (xy 52.0065 -14.100302)
			(xy 52.005991 -14.128188) (xy 51.997871 -14.183364) (xy 51.981803 -14.236771) (xy 51.958131 -14.287268)
			(xy 51.927358 -14.333781) (xy 51.890141 -14.375318) (xy 51.847273 -14.410993) (xy 51.799667 -14.440047)
			(xy 51.748338 -14.461859) (xy 51.694381 -14.475965) (xy 51.638944 -14.482065) (xy 51.58321 -14.480028)
			(xy 51.528367 -14.469898) (xy 51.475583 -14.451891) (xy 51.425983 -14.42639) (xy 51.380625 -14.393939)
			(xy 51.340476 -14.35523) (xy 51.30639 -14.311087) (xy 51.279094 -14.262452) (xy 51.259171 -14.210361)
			(xy 51.247045 -14.155924) (xy 51.242974 -14.100302) (xy 46.087114 -14.100302) (xy 46.16345 -14.175483)
			(xy 46.250469 -14.272325) (xy 46.331422 -14.374292) (xy 46.406008 -14.481004) (xy 46.473949 -14.592065)
			(xy 46.534994 -14.707061) (xy 46.588915 -14.825565) (xy 46.63551 -14.947136) (xy 46.674608 -15.071321)
			(xy 46.706062 -15.197659) (xy 46.729756 -15.32568) (xy 46.738568 -15.397551) (xy 51.90438 -15.397551)
			(xy 51.90438 -15.343049) (xy 51.912136 -15.289103) (xy 51.927491 -15.236809) (xy 51.950131 -15.187232)
			(xy 51.979596 -15.141382) (xy 52.015287 -15.100193) (xy 52.056476 -15.064501) (xy 52.102325 -15.035035)
			(xy 52.151901 -15.012393) (xy 52.204195 -14.997038) (xy 52.258141 -14.98928) (xy 52.285392 -14.988794)
			(xy 52.31501 -14.989396) (xy 52.373535 -14.998549) (xy 52.429941 -15.016637) (xy 52.482876 -15.043224)
			(xy 52.531065 -15.077673) (xy 52.5526 -15.098014) (xy 52.560524 -15.105065) (xy 52.580347 -15.112546)
			(xy 52.590954 -15.112492) (xy 52.676298 -15.10792) (xy 52.695094 -15.098522) (xy 52.701952 -15.090394)
			(xy 52.720189 -15.069186) (xy 52.761774 -15.031783) (xy 52.808373 -15.000848) (xy 52.858987 -14.977046)
			(xy 52.912533 -14.960886) (xy 52.967864 -14.952713) (xy 52.99583 -14.952218) (xy 53.023082 -14.952654)
			(xy 53.07703 -14.960414) (xy 53.129325 -14.975773) (xy 53.178901 -14.998418) (xy 53.224751 -15.027887)
			(xy 53.265941 -15.063581) (xy 53.301631 -15.104773) (xy 53.331097 -15.150625) (xy 53.353737 -15.200204)
			(xy 53.369092 -15.252499) (xy 53.376848 -15.306448) (xy 53.376848 -15.360952) (xy 53.369092 -15.414901)
			(xy 53.353737 -15.467196) (xy 53.331097 -15.516775) (xy 53.301631 -15.562627) (xy 53.265941 -15.603819)
			(xy 53.224751 -15.639513) (xy 53.208503 -15.649956) (xy 68.485524 -15.649956) (xy 68.489494 -15.519822)
			(xy 68.50139 -15.390172) (xy 68.521169 -15.261489) (xy 68.548755 -15.13425) (xy 68.584048 -15.008931)
			(xy 68.626914 -14.885995) (xy 68.677196 -14.765902) (xy 68.734705 -14.649098) (xy 68.799229 -14.536016)
			(xy 68.870526 -14.427079) (xy 68.948331 -14.322691) (xy 69.032356 -14.22324) (xy 69.122288 -14.129097)
			(xy 69.217792 -14.040612) (xy 69.318512 -13.958113) (xy 69.424074 -13.881908) (xy 69.534086 -13.812281)
			(xy 69.648138 -13.74949) (xy 69.765806 -13.693768) (xy 69.886652 -13.645324) (xy 70.010227 -13.604337)
			(xy 70.13607 -13.57096) (xy 70.263715 -13.545317) (xy 70.392685 -13.527503) (xy 70.522501 -13.517585)
			(xy 70.65268 -13.5156) (xy 70.782739 -13.521554) (xy 70.912192 -13.535427) (xy 71.040559 -13.557165)
			(xy 71.167362 -13.586689) (xy 71.292129 -13.623888) (xy 71.414396 -13.668624) (xy 71.533709 -13.720732)
			(xy 71.649622 -13.780015) (xy 71.761707 -13.846256) (xy 71.869544 -13.919206) (xy 71.972733 -13.998594)
			(xy 72.070891 -14.084126) (xy 72.087316 -14.100302) (xy 77.242922 -14.100302) (xy 77.246993 -14.04468)
			(xy 77.259119 -13.990243) (xy 77.279042 -13.938152) (xy 77.306338 -13.889517) (xy 77.340424 -13.845374)
			(xy 77.380573 -13.806665) (xy 77.425931 -13.774214) (xy 77.475531 -13.748713) (xy 77.528315 -13.730706)
			(xy 77.583158 -13.720576) (xy 77.638892 -13.718539) (xy 77.694329 -13.724639) (xy 77.748286 -13.738745)
			(xy 77.799615 -13.760557) (xy 77.847221 -13.789611) (xy 77.890089 -13.825286) (xy 77.927306 -13.866823)
			(xy 77.958079 -13.913336) (xy 77.981751 -13.963833) (xy 77.997819 -14.01724) (xy 78.005939 -14.072416)
			(xy 78.006448 -14.100302) (xy 78.005939 -14.128188) (xy 77.997819 -14.183364) (xy 77.981751 -14.236771)
			(xy 77.958079 -14.287268) (xy 77.927306 -14.333781) (xy 77.890089 -14.375318) (xy 77.847221 -14.410993)
			(xy 77.799615 -14.440047) (xy 77.748286 -14.461859) (xy 77.694329 -14.475965) (xy 77.638892 -14.482065)
			(xy 77.583158 -14.480028) (xy 77.528315 -14.469898) (xy 77.475531 -14.451891) (xy 77.425931 -14.42639)
			(xy 77.380573 -14.393939) (xy 77.340424 -14.35523) (xy 77.306338 -14.311087) (xy 77.279042 -14.262452)
			(xy 77.259119 -14.210361) (xy 77.246993 -14.155924) (xy 77.242922 -14.100302) (xy 72.087316 -14.100302)
			(xy 72.163652 -14.175483) (xy 72.250671 -14.272325) (xy 72.331624 -14.374292) (xy 72.40621 -14.481004)
			(xy 72.474151 -14.592065) (xy 72.535196 -14.707061) (xy 72.589117 -14.825565) (xy 72.635712 -14.947136)
			(xy 72.67481 -15.071321) (xy 72.706264 -15.197659) (xy 72.729958 -15.32568) (xy 72.739273 -15.401652)
			(xy 77.829644 -15.401652) (xy 77.829644 -15.347148) (xy 77.8374 -15.293199) (xy 77.852755 -15.240902)
			(xy 77.875395 -15.191323) (xy 77.904861 -15.14547) (xy 77.940552 -15.104277) (xy 77.981741 -15.068582)
			(xy 78.027591 -15.039113) (xy 78.077168 -15.016467) (xy 78.129463 -15.001108) (xy 78.183412 -14.993346)
			(xy 78.210664 -14.992858) (xy 78.236798 -14.993271) (xy 78.288576 -15.00042) (xy 78.338895 -15.014563)
			(xy 78.386816 -15.035434) (xy 78.431443 -15.062645) (xy 78.471943 -15.095687) (xy 78.490064 -15.114524)
			(xy 78.497684 -15.122906) (xy 78.518258 -15.131288) (xy 78.618588 -15.126462) (xy 78.638146 -15.116302)
			(xy 78.645004 -15.107412) (xy 78.663187 -15.084652) (xy 78.705279 -15.044382) (xy 78.753006 -15.010982)
			(xy 78.805256 -14.985228) (xy 78.860816 -14.96772) (xy 78.918392 -14.958864) (xy 78.947518 -14.958314)
			(xy 78.97477 -14.958757) (xy 79.028719 -14.966516) (xy 79.081014 -14.981874) (xy 79.130592 -15.004517)
			(xy 79.176443 -15.033986) (xy 79.217634 -15.069679) (xy 79.253325 -15.110871) (xy 79.282791 -15.156724)
			(xy 79.305433 -15.206302) (xy 79.320788 -15.258599) (xy 79.328544 -15.312548) (xy 79.328544 -15.367052)
			(xy 79.320788 -15.421001) (xy 79.305433 -15.473298) (xy 79.282791 -15.522876) (xy 79.253325 -15.568729)
			(xy 79.217634 -15.609921) (xy 79.176443 -15.645614) (xy 79.169687 -15.649956) (xy 94.485472 -15.649956)
			(xy 94.489442 -15.519822) (xy 94.501338 -15.390172) (xy 94.521117 -15.261489) (xy 94.548703 -15.13425)
			(xy 94.583996 -15.008931) (xy 94.626862 -14.885995) (xy 94.677144 -14.765902) (xy 94.734653 -14.649098)
			(xy 94.799177 -14.536016) (xy 94.870474 -14.427079) (xy 94.948279 -14.322691) (xy 95.032304 -14.22324)
			(xy 95.122236 -14.129097) (xy 95.21774 -14.040612) (xy 95.31846 -13.958113) (xy 95.424022 -13.881908)
			(xy 95.534034 -13.812281) (xy 95.648086 -13.74949) (xy 95.765754 -13.693768) (xy 95.8866 -13.645324)
			(xy 96.010175 -13.604337) (xy 96.136018 -13.57096) (xy 96.263663 -13.545317) (xy 96.392633 -13.527503)
			(xy 96.522449 -13.517585) (xy 96.652628 -13.5156) (xy 96.782687 -13.521554) (xy 96.91214 -13.535427)
			(xy 97.040507 -13.557165) (xy 97.16731 -13.586689) (xy 97.292077 -13.623888) (xy 97.414344 -13.668624)
			(xy 97.533657 -13.720732) (xy 97.64957 -13.780015) (xy 97.761655 -13.846256) (xy 97.869492 -13.919206)
			(xy 97.972681 -13.998594) (xy 98.070839 -14.084126) (xy 98.1636 -14.175483) (xy 98.250619 -14.272325)
			(xy 98.331572 -14.374292) (xy 98.406158 -14.481004) (xy 98.474099 -14.592065) (xy 98.535144 -14.707061)
			(xy 98.589065 -14.825565) (xy 98.63566 -14.947136) (xy 98.674758 -15.071321) (xy 98.706212 -15.197659)
			(xy 98.729906 -15.32568) (xy 98.74575 -15.454906) (xy 98.753688 -15.584859) (xy 98.754184 -15.649956)
			(xy 132.585472 -15.649956) (xy 132.589442 -15.519822) (xy 132.601338 -15.390172) (xy 132.621117 -15.261489)
			(xy 132.648703 -15.13425) (xy 132.683996 -15.008931) (xy 132.726862 -14.885995) (xy 132.777144 -14.765902)
			(xy 132.834653 -14.649098) (xy 132.899177 -14.536016) (xy 132.970474 -14.427079) (xy 133.048279 -14.322691)
			(xy 133.132304 -14.22324) (xy 133.222236 -14.129097) (xy 133.31774 -14.040612) (xy 133.41846 -13.958113)
			(xy 133.524022 -13.881908) (xy 133.634034 -13.812281) (xy 133.748086 -13.74949) (xy 133.865754 -13.693768)
			(xy 133.9866 -13.645324) (xy 134.110175 -13.604337) (xy 134.236018 -13.57096) (xy 134.363663 -13.545317)
			(xy 134.492633 -13.527503) (xy 134.622449 -13.517585) (xy 134.752628 -13.5156) (xy 134.882687 -13.521554)
			(xy 135.01214 -13.535427) (xy 135.140507 -13.557165) (xy 135.26731 -13.586689) (xy 135.392077 -13.623888)
			(xy 135.514344 -13.668624) (xy 135.633657 -13.720732) (xy 135.74957 -13.780015) (xy 135.861655 -13.846256)
			(xy 135.969492 -13.919206) (xy 136.072681 -13.998594) (xy 136.170839 -14.084126) (xy 136.187264 -14.100302)
			(xy 141.343124 -14.100302) (xy 141.347195 -14.04468) (xy 141.359321 -13.990243) (xy 141.379244 -13.938152)
			(xy 141.40654 -13.889517) (xy 141.440626 -13.845374) (xy 141.480775 -13.806665) (xy 141.526133 -13.774214)
			(xy 141.575733 -13.748713) (xy 141.628517 -13.730706) (xy 141.68336 -13.720576) (xy 141.739094 -13.718539)
			(xy 141.794531 -13.724639) (xy 141.848488 -13.738745) (xy 141.899817 -13.760557) (xy 141.947423 -13.789611)
			(xy 141.990291 -13.825286) (xy 142.027508 -13.866823) (xy 142.058281 -13.913336) (xy 142.081953 -13.963833)
			(xy 142.098021 -14.01724) (xy 142.106141 -14.072416) (xy 142.10665 -14.100302) (xy 142.106141 -14.128188)
			(xy 142.098021 -14.183364) (xy 142.081953 -14.236771) (xy 142.058281 -14.287268) (xy 142.027508 -14.333781)
			(xy 141.990291 -14.375318) (xy 141.947423 -14.410993) (xy 141.899817 -14.440047) (xy 141.848488 -14.461859)
			(xy 141.794531 -14.475965) (xy 141.739094 -14.482065) (xy 141.68336 -14.480028) (xy 141.628517 -14.469898)
			(xy 141.575733 -14.451891) (xy 141.526133 -14.42639) (xy 141.480775 -14.393939) (xy 141.440626 -14.35523)
			(xy 141.40654 -14.311087) (xy 141.379244 -14.262452) (xy 141.359321 -14.210361) (xy 141.347195 -14.155924)
			(xy 141.343124 -14.100302) (xy 136.187264 -14.100302) (xy 136.2636 -14.175483) (xy 136.350619 -14.272325)
			(xy 136.431572 -14.374292) (xy 136.506158 -14.481004) (xy 136.574099 -14.592065) (xy 136.635144 -14.707061)
			(xy 136.689065 -14.825565) (xy 136.73566 -14.947136) (xy 136.774758 -15.071321) (xy 136.806212 -15.197659)
			(xy 136.829906 -15.32568) (xy 136.838718 -15.397555) (xy 142.004457 -15.397555) (xy 142.004457 -15.343045)
			(xy 142.012215 -15.289091) (xy 142.027574 -15.23679) (xy 142.050219 -15.187207) (xy 142.079691 -15.141353)
			(xy 142.115389 -15.100159) (xy 142.156586 -15.064466) (xy 142.202444 -15.034999) (xy 142.25203 -15.012359)
			(xy 142.304332 -14.997007) (xy 142.358287 -14.989254) (xy 142.385542 -14.988794) (xy 142.411779 -14.989226)
			(xy 142.463756 -14.996426) (xy 142.514254 -15.010686) (xy 142.562321 -15.031736) (xy 142.607047 -15.059178)
			(xy 142.647588 -15.092493) (xy 142.665704 -15.111476) (xy 142.665958 -15.11173) (xy 142.673691 -15.119112)
			(xy 142.693374 -15.127386) (xy 142.704058 -15.127732) (xy 142.791942 -15.125446) (xy 142.8115 -15.116048)
			(xy 142.818612 -15.107412) (xy 142.83679 -15.086232) (xy 142.878337 -15.048959) (xy 142.924874 -15.018141)
			(xy 142.975405 -14.994435) (xy 143.028853 -14.978349) (xy 143.084074 -14.970225) (xy 143.111982 -14.969744)
			(xy 143.139232 -14.970302) (xy 143.193178 -14.978056) (xy 143.245472 -14.993408) (xy 143.295048 -15.016047)
			(xy 143.340898 -15.045511) (xy 143.382087 -15.0812) (xy 143.417778 -15.122388) (xy 143.447244 -15.168236)
			(xy 143.469885 -15.217811) (xy 143.48524 -15.270104) (xy 143.492997 -15.32405) (xy 143.492997 -15.37855)
			(xy 143.48524 -15.432496) (xy 143.469885 -15.484789) (xy 143.447244 -15.534364) (xy 143.417778 -15.580212)
			(xy 143.382087 -15.6214) (xy 143.34913 -15.649956) (xy 158.58542 -15.649956) (xy 158.58939 -15.519822)
			(xy 158.601286 -15.390172) (xy 158.621065 -15.261489) (xy 158.648651 -15.13425) (xy 158.683944 -15.008931)
			(xy 158.72681 -14.885995) (xy 158.777092 -14.765902) (xy 158.834601 -14.649098) (xy 158.899125 -14.536016)
			(xy 158.970422 -14.427079) (xy 159.048227 -14.322691) (xy 159.132252 -14.22324) (xy 159.222184 -14.129097)
			(xy 159.317688 -14.040612) (xy 159.418408 -13.958113) (xy 159.52397 -13.881908) (xy 159.633982 -13.812281)
			(xy 159.748034 -13.74949) (xy 159.865702 -13.693768) (xy 159.986548 -13.645324) (xy 160.110123 -13.604337)
			(xy 160.235966 -13.57096) (xy 160.363611 -13.545317) (xy 160.492581 -13.527503) (xy 160.622397 -13.517585)
			(xy 160.752576 -13.5156) (xy 160.882635 -13.521554) (xy 161.012088 -13.535427) (xy 161.140455 -13.557165)
			(xy 161.267258 -13.586689) (xy 161.392025 -13.623888) (xy 161.514292 -13.668624) (xy 161.633605 -13.720732)
			(xy 161.749518 -13.780015) (xy 161.861603 -13.846256) (xy 161.96944 -13.919206) (xy 162.072629 -13.998594)
			(xy 162.170787 -14.084126) (xy 162.263548 -14.175483) (xy 162.350567 -14.272325) (xy 162.43152 -14.374292)
			(xy 162.506106 -14.481004) (xy 162.574047 -14.592065) (xy 162.635092 -14.707061) (xy 162.647942 -14.735302)
			(xy 166.62476 -14.735302) (xy 166.628831 -14.67968) (xy 166.640957 -14.625243) (xy 166.66088 -14.573152)
			(xy 166.688176 -14.524517) (xy 166.722262 -14.480374) (xy 166.762411 -14.441665) (xy 166.807769 -14.409214)
			(xy 166.857369 -14.383713) (xy 166.910153 -14.365706) (xy 166.964996 -14.355576) (xy 167.02073 -14.353539)
			(xy 167.076167 -14.359639) (xy 167.130124 -14.373745) (xy 167.181453 -14.395557) (xy 167.229059 -14.424611)
			(xy 167.271927 -14.460286) (xy 167.309144 -14.501823) (xy 167.339917 -14.548336) (xy 167.363589 -14.598833)
			(xy 167.379657 -14.65224) (xy 167.387777 -14.707416) (xy 167.388286 -14.735302) (xy 167.387777 -14.763188)
			(xy 167.379657 -14.818364) (xy 167.363589 -14.871771) (xy 167.339917 -14.922268) (xy 167.309144 -14.968781)
			(xy 167.271927 -15.010318) (xy 167.229059 -15.045993) (xy 167.181453 -15.075047) (xy 167.130124 -15.096859)
			(xy 167.076167 -15.110965) (xy 167.02073 -15.117065) (xy 166.964996 -15.115028) (xy 166.910153 -15.104898)
			(xy 166.857369 -15.086891) (xy 166.807769 -15.06139) (xy 166.762411 -15.028939) (xy 166.722262 -14.99023)
			(xy 166.688176 -14.946087) (xy 166.66088 -14.897452) (xy 166.640957 -14.845361) (xy 166.628831 -14.790924)
			(xy 166.62476 -14.735302) (xy 162.647942 -14.735302) (xy 162.689013 -14.825565) (xy 162.735608 -14.947136)
			(xy 162.774706 -15.071321) (xy 162.80616 -15.197659) (xy 162.829854 -15.32568) (xy 162.838666 -15.397551)
			(xy 168.00448 -15.397551) (xy 168.00448 -15.343049) (xy 168.012236 -15.289103) (xy 168.02759 -15.236809)
			(xy 168.050231 -15.187233) (xy 168.079696 -15.141383) (xy 168.115386 -15.100193) (xy 168.156575 -15.064502)
			(xy 168.202424 -15.035036) (xy 168.252 -15.012394) (xy 168.304293 -14.997038) (xy 168.358239 -14.98928)
			(xy 168.38549 -14.988794) (xy 168.411726 -14.98926) (xy 168.463701 -14.996454) (xy 168.514199 -15.010707)
			(xy 168.562266 -15.03175) (xy 168.606993 -15.059186) (xy 168.647535 -15.092495) (xy 168.665652 -15.111476)
			(xy 168.665906 -15.11173) (xy 168.673621 -15.119134) (xy 168.693318 -15.127396) (xy 168.704006 -15.127732)
			(xy 168.79189 -15.125446) (xy 168.811448 -15.116048) (xy 168.81856 -15.107412) (xy 168.836766 -15.086257)
			(xy 168.878307 -15.048983) (xy 168.924838 -15.018161) (xy 168.975364 -14.994451) (xy 169.028806 -14.978359)
			(xy 169.084024 -14.970228) (xy 169.11193 -14.969744) (xy 169.139176 -14.970328) (xy 169.193114 -14.978087)
			(xy 169.245399 -14.993443) (xy 169.294966 -15.016083) (xy 169.340807 -15.045546) (xy 169.381988 -15.081233)
			(xy 169.417672 -15.122418) (xy 169.447131 -15.168261) (xy 169.469768 -15.21783) (xy 169.485119 -15.270115)
			(xy 169.492874 -15.324054) (xy 169.492874 -15.378546) (xy 169.485119 -15.432485) (xy 169.469768 -15.48477)
			(xy 169.447131 -15.534339) (xy 169.417672 -15.580182) (xy 169.381988 -15.621367) (xy 169.348998 -15.649956)
			(xy 184.585368 -15.649956) (xy 184.589338 -15.519822) (xy 184.601234 -15.390172) (xy 184.621013 -15.261489)
			(xy 184.648599 -15.13425) (xy 184.683892 -15.008931) (xy 184.726758 -14.885995) (xy 184.77704 -14.765902)
			(xy 184.834549 -14.649098) (xy 184.899073 -14.536016) (xy 184.97037 -14.427079) (xy 185.048175 -14.322691)
			(xy 185.1322 -14.22324) (xy 185.222132 -14.129097) (xy 185.317636 -14.040612) (xy 185.418356 -13.958113)
			(xy 185.523918 -13.881908) (xy 185.63393 -13.812281) (xy 185.747982 -13.74949) (xy 185.86565 -13.693768)
			(xy 185.986496 -13.645324) (xy 186.110071 -13.604337) (xy 186.235914 -13.57096) (xy 186.363559 -13.545317)
			(xy 186.492529 -13.527503) (xy 186.622345 -13.517585) (xy 186.752524 -13.5156) (xy 186.882583 -13.521554)
			(xy 187.012036 -13.535427) (xy 187.140403 -13.557165) (xy 187.267206 -13.586689) (xy 187.391973 -13.623888)
			(xy 187.51424 -13.668624) (xy 187.633553 -13.720732) (xy 187.749466 -13.780015) (xy 187.861551 -13.846256)
			(xy 187.969388 -13.919206) (xy 188.072577 -13.998594) (xy 188.170735 -14.084126) (xy 188.18716 -14.100302)
			(xy 193.34302 -14.100302) (xy 193.347091 -14.04468) (xy 193.359217 -13.990243) (xy 193.37914 -13.938152)
			(xy 193.406436 -13.889517) (xy 193.440522 -13.845374) (xy 193.480671 -13.806665) (xy 193.526029 -13.774214)
			(xy 193.575629 -13.748713) (xy 193.628413 -13.730706) (xy 193.683256 -13.720576) (xy 193.73899 -13.718539)
			(xy 193.794427 -13.724639) (xy 193.848384 -13.738745) (xy 193.899713 -13.760557) (xy 193.947319 -13.789611)
			(xy 193.990187 -13.825286) (xy 194.027404 -13.866823) (xy 194.058177 -13.913336) (xy 194.081849 -13.963833)
			(xy 194.097917 -14.01724) (xy 194.106037 -14.072416) (xy 194.106546 -14.100302) (xy 194.106037 -14.128188)
			(xy 194.097917 -14.183364) (xy 194.081849 -14.236771) (xy 194.058177 -14.287268) (xy 194.027404 -14.333781)
			(xy 193.990187 -14.375318) (xy 193.947319 -14.410993) (xy 193.899713 -14.440047) (xy 193.848384 -14.461859)
			(xy 193.794427 -14.475965) (xy 193.73899 -14.482065) (xy 193.683256 -14.480028) (xy 193.628413 -14.469898)
			(xy 193.575629 -14.451891) (xy 193.526029 -14.42639) (xy 193.480671 -14.393939) (xy 193.440522 -14.35523)
			(xy 193.406436 -14.311087) (xy 193.37914 -14.262452) (xy 193.359217 -14.210361) (xy 193.347091 -14.155924)
			(xy 193.34302 -14.100302) (xy 188.18716 -14.100302) (xy 188.263496 -14.175483) (xy 188.350515 -14.272325)
			(xy 188.431468 -14.374292) (xy 188.506054 -14.481004) (xy 188.573995 -14.592065) (xy 188.63504 -14.707061)
			(xy 188.688961 -14.825565) (xy 188.735556 -14.947136) (xy 188.774654 -15.071321) (xy 188.806108 -15.197659)
			(xy 188.829802 -15.32568) (xy 188.838614 -15.397554) (xy 194.004357 -15.397554) (xy 194.004357 -15.343046)
			(xy 194.012115 -15.289092) (xy 194.027473 -15.236791) (xy 194.050118 -15.187209) (xy 194.07959 -15.141354)
			(xy 194.115287 -15.10016) (xy 194.156484 -15.064467) (xy 194.202342 -15.035) (xy 194.251927 -15.01236)
			(xy 194.304229 -14.997007) (xy 194.358184 -14.989255) (xy 194.385438 -14.988794) (xy 194.411675 -14.989228)
			(xy 194.463652 -14.996429) (xy 194.51415 -15.010688) (xy 194.562217 -15.031737) (xy 194.606943 -15.059178)
			(xy 194.647484 -15.092493) (xy 194.6656 -15.111476) (xy 194.665854 -15.11173) (xy 194.673588 -15.11911)
			(xy 194.69327 -15.127385) (xy 194.703954 -15.127732) (xy 194.791838 -15.125446) (xy 194.811396 -15.116048)
			(xy 194.818508 -15.107412) (xy 194.836689 -15.086234) (xy 194.878235 -15.048961) (xy 194.924771 -15.018143)
			(xy 194.975302 -14.994437) (xy 195.028749 -14.97835) (xy 195.08397 -14.970225) (xy 195.111878 -14.969744)
			(xy 195.139128 -14.970302) (xy 195.193075 -14.978055) (xy 195.245369 -14.993407) (xy 195.294946 -15.016046)
			(xy 195.340796 -15.045509) (xy 195.381986 -15.081199) (xy 195.417677 -15.122387) (xy 195.447144 -15.168235)
			(xy 195.469785 -15.21781) (xy 195.48514 -15.270104) (xy 195.492897 -15.32405) (xy 195.492897 -15.37855)
			(xy 195.48514 -15.432497) (xy 195.469785 -15.48479) (xy 195.447144 -15.534365) (xy 195.417677 -15.580213)
			(xy 195.381986 -15.621401) (xy 195.349031 -15.649956) (xy 210.585316 -15.649956) (xy 210.589286 -15.519822)
			(xy 210.601182 -15.390172) (xy 210.620961 -15.261489) (xy 210.648547 -15.13425) (xy 210.68384 -15.008931)
			(xy 210.726706 -14.885995) (xy 210.776988 -14.765902) (xy 210.834497 -14.649098) (xy 210.899021 -14.536016)
			(xy 210.970318 -14.427079) (xy 211.048123 -14.322691) (xy 211.132148 -14.22324) (xy 211.22208 -14.129097)
			(xy 211.317584 -14.040612) (xy 211.418304 -13.958113) (xy 211.523866 -13.881908) (xy 211.633878 -13.812281)
			(xy 211.74793 -13.74949) (xy 211.865598 -13.693768) (xy 211.986444 -13.645324) (xy 212.110019 -13.604337)
			(xy 212.235862 -13.57096) (xy 212.363507 -13.545317) (xy 212.492477 -13.527503) (xy 212.622293 -13.517585)
			(xy 212.752472 -13.5156) (xy 212.882531 -13.521554) (xy 213.011984 -13.535427) (xy 213.140351 -13.557165)
			(xy 213.267154 -13.586689) (xy 213.391921 -13.623888) (xy 213.514188 -13.668624) (xy 213.633501 -13.720732)
			(xy 213.749414 -13.780015) (xy 213.861499 -13.846256) (xy 213.969336 -13.919206) (xy 214.072525 -13.998594)
			(xy 214.170683 -14.084126) (xy 214.187108 -14.100302) (xy 219.342968 -14.100302) (xy 219.347039 -14.04468)
			(xy 219.359165 -13.990243) (xy 219.379088 -13.938152) (xy 219.406384 -13.889517) (xy 219.44047 -13.845374)
			(xy 219.480619 -13.806665) (xy 219.525977 -13.774214) (xy 219.575577 -13.748713) (xy 219.628361 -13.730706)
			(xy 219.683204 -13.720576) (xy 219.738938 -13.718539) (xy 219.794375 -13.724639) (xy 219.848332 -13.738745)
			(xy 219.899661 -13.760557) (xy 219.947267 -13.789611) (xy 219.990135 -13.825286) (xy 220.027352 -13.866823)
			(xy 220.058125 -13.913336) (xy 220.081797 -13.963833) (xy 220.097865 -14.01724) (xy 220.105985 -14.072416)
			(xy 220.106494 -14.100302) (xy 220.105985 -14.128188) (xy 220.097865 -14.183364) (xy 220.081797 -14.236771)
			(xy 220.058125 -14.287268) (xy 220.027352 -14.333781) (xy 219.990135 -14.375318) (xy 219.947267 -14.410993)
			(xy 219.899661 -14.440047) (xy 219.848332 -14.461859) (xy 219.794375 -14.475965) (xy 219.738938 -14.482065)
			(xy 219.683204 -14.480028) (xy 219.628361 -14.469898) (xy 219.575577 -14.451891) (xy 219.525977 -14.42639)
			(xy 219.480619 -14.393939) (xy 219.44047 -14.35523) (xy 219.406384 -14.311087) (xy 219.379088 -14.262452)
			(xy 219.359165 -14.210361) (xy 219.347039 -14.155924) (xy 219.342968 -14.100302) (xy 214.187108 -14.100302)
			(xy 214.263444 -14.175483) (xy 214.350463 -14.272325) (xy 214.431416 -14.374292) (xy 214.506002 -14.481004)
			(xy 214.573943 -14.592065) (xy 214.634988 -14.707061) (xy 214.688909 -14.825565) (xy 214.735504 -14.947136)
			(xy 214.774602 -15.071321) (xy 214.806056 -15.197659) (xy 214.82975 -15.32568) (xy 214.838562 -15.39755)
			(xy 220.00438 -15.39755) (xy 220.00438 -15.34305) (xy 220.012136 -15.289103) (xy 220.02749 -15.23681)
			(xy 220.05013 -15.187234) (xy 220.079595 -15.141384) (xy 220.115285 -15.100195) (xy 220.156473 -15.064503)
			(xy 220.202322 -15.035037) (xy 220.251897 -15.012395) (xy 220.30419 -14.997039) (xy 220.358136 -14.989281)
			(xy 220.385386 -14.988794) (xy 220.411621 -14.989263) (xy 220.463597 -14.996456) (xy 220.514095 -15.010709)
			(xy 220.562161 -15.031751) (xy 220.606889 -15.059186) (xy 220.647431 -15.092496) (xy 220.665548 -15.111476)
			(xy 220.665802 -15.11173) (xy 220.673518 -15.119132) (xy 220.693214 -15.127395) (xy 220.703902 -15.127732)
			(xy 220.791786 -15.125446) (xy 220.811344 -15.116048) (xy 220.818456 -15.107412) (xy 220.836664 -15.086259)
			(xy 220.878205 -15.048984) (xy 220.924735 -15.018163) (xy 220.975261 -14.994453) (xy 221.028703 -14.97836)
			(xy 221.08392 -14.970229) (xy 221.111826 -14.969744) (xy 221.139073 -14.970328) (xy 221.193011 -14.978086)
			(xy 221.245296 -14.993442) (xy 221.294863 -15.016082) (xy 221.340705 -15.045545) (xy 221.381887 -15.081232)
			(xy 221.417571 -15.122416) (xy 221.447031 -15.16826) (xy 221.469667 -15.217829) (xy 221.485019 -15.270115)
			(xy 221.492774 -15.324053) (xy 221.492774 -15.378547) (xy 221.485019 -15.432485) (xy 221.469667 -15.484771)
			(xy 221.447031 -15.53434) (xy 221.417571 -15.580184) (xy 221.381887 -15.621368) (xy 221.348897 -15.649956)
			(xy 248.685316 -15.649956) (xy 248.689286 -15.519822) (xy 248.701182 -15.390172) (xy 248.720961 -15.261489)
			(xy 248.748547 -15.13425) (xy 248.78384 -15.008931) (xy 248.826706 -14.885995) (xy 248.876988 -14.765902)
			(xy 248.934497 -14.649098) (xy 248.999021 -14.536016) (xy 249.070318 -14.427079) (xy 249.148123 -14.322691)
			(xy 249.232148 -14.22324) (xy 249.32208 -14.129097) (xy 249.417584 -14.040612) (xy 249.518304 -13.958113)
			(xy 249.623866 -13.881908) (xy 249.733878 -13.812281) (xy 249.84793 -13.74949) (xy 249.965598 -13.693768)
			(xy 250.086444 -13.645324) (xy 250.210019 -13.604337) (xy 250.335862 -13.57096) (xy 250.463507 -13.545317)
			(xy 250.592477 -13.527503) (xy 250.722293 -13.517585) (xy 250.852472 -13.5156) (xy 250.982531 -13.521554)
			(xy 251.111984 -13.535427) (xy 251.240351 -13.557165) (xy 251.367154 -13.586689) (xy 251.491921 -13.623888)
			(xy 251.614188 -13.668624) (xy 251.733501 -13.720732) (xy 251.849414 -13.780015) (xy 251.961499 -13.846256)
			(xy 252.069336 -13.919206) (xy 252.172525 -13.998594) (xy 252.270683 -14.084126) (xy 252.287108 -14.100302)
			(xy 257.442968 -14.100302) (xy 257.447039 -14.04468) (xy 257.459165 -13.990243) (xy 257.479088 -13.938152)
			(xy 257.506384 -13.889517) (xy 257.54047 -13.845374) (xy 257.580619 -13.806665) (xy 257.625977 -13.774214)
			(xy 257.675577 -13.748713) (xy 257.728361 -13.730706) (xy 257.783204 -13.720576) (xy 257.838938 -13.718539)
			(xy 257.894375 -13.724639) (xy 257.948332 -13.738745) (xy 257.999661 -13.760557) (xy 258.047267 -13.789611)
			(xy 258.090135 -13.825286) (xy 258.127352 -13.866823) (xy 258.158125 -13.913336) (xy 258.181797 -13.963833)
			(xy 258.197865 -14.01724) (xy 258.205985 -14.072416) (xy 258.206494 -14.100302) (xy 258.205985 -14.128188)
			(xy 258.197865 -14.183364) (xy 258.181797 -14.236771) (xy 258.158125 -14.287268) (xy 258.127352 -14.333781)
			(xy 258.090135 -14.375318) (xy 258.047267 -14.410993) (xy 257.999661 -14.440047) (xy 257.948332 -14.461859)
			(xy 257.894375 -14.475965) (xy 257.838938 -14.482065) (xy 257.783204 -14.480028) (xy 257.728361 -14.469898)
			(xy 257.675577 -14.451891) (xy 257.625977 -14.42639) (xy 257.580619 -14.393939) (xy 257.54047 -14.35523)
			(xy 257.506384 -14.311087) (xy 257.479088 -14.262452) (xy 257.459165 -14.210361) (xy 257.447039 -14.155924)
			(xy 257.442968 -14.100302) (xy 252.287108 -14.100302) (xy 252.363444 -14.175483) (xy 252.450463 -14.272325)
			(xy 252.531416 -14.374292) (xy 252.606002 -14.481004) (xy 252.673943 -14.592065) (xy 252.734988 -14.707061)
			(xy 252.788909 -14.825565) (xy 252.835504 -14.947136) (xy 252.874602 -15.071321) (xy 252.906056 -15.197659)
			(xy 252.92975 -15.32568) (xy 252.938562 -15.39755) (xy 258.10438 -15.39755) (xy 258.10438 -15.34305)
			(xy 258.112136 -15.289103) (xy 258.12749 -15.23681) (xy 258.15013 -15.187234) (xy 258.179595 -15.141384)
			(xy 258.215285 -15.100195) (xy 258.256473 -15.064503) (xy 258.302322 -15.035037) (xy 258.351897 -15.012395)
			(xy 258.40419 -14.997039) (xy 258.458136 -14.989281) (xy 258.485386 -14.988794) (xy 258.511621 -14.989263)
			(xy 258.563597 -14.996456) (xy 258.614095 -15.010709) (xy 258.662161 -15.031751) (xy 258.706889 -15.059186)
			(xy 258.747431 -15.092496) (xy 258.765548 -15.111476) (xy 258.765802 -15.11173) (xy 258.773518 -15.119132)
			(xy 258.793214 -15.127395) (xy 258.803902 -15.127732) (xy 258.891786 -15.125446) (xy 258.911344 -15.116048)
			(xy 258.918456 -15.107412) (xy 258.936664 -15.086259) (xy 258.978205 -15.048984) (xy 259.024735 -15.018163)
			(xy 259.075261 -14.994453) (xy 259.128703 -14.97836) (xy 259.18392 -14.970229) (xy 259.211826 -14.969744)
			(xy 259.239073 -14.970328) (xy 259.293011 -14.978086) (xy 259.345296 -14.993442) (xy 259.394863 -15.016082)
			(xy 259.440705 -15.045545) (xy 259.481887 -15.081232) (xy 259.517571 -15.122416) (xy 259.547031 -15.16826)
			(xy 259.569667 -15.217829) (xy 259.585019 -15.270115) (xy 259.592774 -15.324053) (xy 259.592774 -15.378547)
			(xy 259.585019 -15.432485) (xy 259.569667 -15.484771) (xy 259.547031 -15.53434) (xy 259.517571 -15.580184)
			(xy 259.481887 -15.621368) (xy 259.448897 -15.649956) (xy 274.685518 -15.649956) (xy 274.689488 -15.519822)
			(xy 274.701384 -15.390172) (xy 274.721163 -15.261489) (xy 274.748749 -15.13425) (xy 274.784042 -15.008931)
			(xy 274.826908 -14.885995) (xy 274.87719 -14.765902) (xy 274.934699 -14.649098) (xy 274.999223 -14.536016)
			(xy 275.07052 -14.427079) (xy 275.148325 -14.322691) (xy 275.23235 -14.22324) (xy 275.322282 -14.129097)
			(xy 275.417786 -14.040612) (xy 275.518506 -13.958113) (xy 275.624068 -13.881908) (xy 275.73408 -13.812281)
			(xy 275.848132 -13.74949) (xy 275.9658 -13.693768) (xy 276.086646 -13.645324) (xy 276.210221 -13.604337)
			(xy 276.336064 -13.57096) (xy 276.463709 -13.545317) (xy 276.592679 -13.527503) (xy 276.722495 -13.517585)
			(xy 276.852674 -13.5156) (xy 276.982733 -13.521554) (xy 277.112186 -13.535427) (xy 277.240553 -13.557165)
			(xy 277.367356 -13.586689) (xy 277.492123 -13.623888) (xy 277.61439 -13.668624) (xy 277.733703 -13.720732)
			(xy 277.849616 -13.780015) (xy 277.961701 -13.846256) (xy 278.069538 -13.919206) (xy 278.172727 -13.998594)
			(xy 278.270885 -14.084126) (xy 278.363646 -14.175483) (xy 278.450665 -14.272325) (xy 278.531618 -14.374292)
			(xy 278.606204 -14.481004) (xy 278.674145 -14.592065) (xy 278.73519 -14.707061) (xy 278.74804 -14.735302)
			(xy 282.772356 -14.735302) (xy 282.776427 -14.67968) (xy 282.788553 -14.625243) (xy 282.808476 -14.573152)
			(xy 282.835772 -14.524517) (xy 282.869858 -14.480374) (xy 282.910007 -14.441665) (xy 282.955365 -14.409214)
			(xy 283.004965 -14.383713) (xy 283.057749 -14.365706) (xy 283.112592 -14.355576) (xy 283.168326 -14.353539)
			(xy 283.223763 -14.359639) (xy 283.27772 -14.373745) (xy 283.329049 -14.395557) (xy 283.376655 -14.424611)
			(xy 283.419523 -14.460286) (xy 283.45674 -14.501823) (xy 283.487513 -14.548336) (xy 283.511185 -14.598833)
			(xy 283.527253 -14.65224) (xy 283.535373 -14.707416) (xy 283.535882 -14.735302) (xy 283.535373 -14.763188)
			(xy 283.527253 -14.818364) (xy 283.511185 -14.871771) (xy 283.487513 -14.922268) (xy 283.45674 -14.968781)
			(xy 283.419523 -15.010318) (xy 283.376655 -15.045993) (xy 283.329049 -15.075047) (xy 283.27772 -15.096859)
			(xy 283.223763 -15.110965) (xy 283.168326 -15.117065) (xy 283.112592 -15.115028) (xy 283.057749 -15.104898)
			(xy 283.004965 -15.086891) (xy 282.955365 -15.06139) (xy 282.910007 -15.028939) (xy 282.869858 -14.99023)
			(xy 282.835772 -14.946087) (xy 282.808476 -14.897452) (xy 282.788553 -14.845361) (xy 282.776427 -14.790924)
			(xy 282.772356 -14.735302) (xy 278.74804 -14.735302) (xy 278.789111 -14.825565) (xy 278.835706 -14.947136)
			(xy 278.874804 -15.071321) (xy 278.906258 -15.197659) (xy 278.929952 -15.32568) (xy 278.938764 -15.397554)
			(xy 284.104257 -15.397554) (xy 284.104257 -15.343046) (xy 284.112015 -15.289092) (xy 284.127373 -15.236792)
			(xy 284.150018 -15.18721) (xy 284.179489 -15.141355) (xy 284.215186 -15.100162) (xy 284.256382 -15.064468)
			(xy 284.30224 -15.035001) (xy 284.351824 -15.012361) (xy 284.404125 -14.997008) (xy 284.45808 -14.989255)
			(xy 284.485334 -14.988794) (xy 284.511571 -14.989231) (xy 284.563547 -14.996431) (xy 284.614046 -15.01069)
			(xy 284.662112 -15.031738) (xy 284.706839 -15.059179) (xy 284.74738 -15.092493) (xy 284.765496 -15.111476)
			(xy 284.76575 -15.11173) (xy 284.773486 -15.119108) (xy 284.793167 -15.127385) (xy 284.80385 -15.127732)
			(xy 284.891734 -15.125446) (xy 284.911292 -15.116048) (xy 284.918404 -15.107412) (xy 284.936587 -15.086236)
			(xy 284.978133 -15.048963) (xy 285.024668 -15.018144) (xy 285.075199 -14.994438) (xy 285.128646 -14.97835)
			(xy 285.183866 -14.970225) (xy 285.211774 -14.969744) (xy 285.239025 -14.970301) (xy 285.292972 -14.978054)
			(xy 285.345266 -14.993406) (xy 285.394843 -15.016044) (xy 285.440694 -15.045508) (xy 285.481884 -15.081197)
			(xy 285.517576 -15.122385) (xy 285.547043 -15.168234) (xy 285.569685 -15.21781) (xy 285.58504 -15.270103)
			(xy 285.592797 -15.324049) (xy 285.592797 -15.378551) (xy 285.58504 -15.432497) (xy 285.569685 -15.48479)
			(xy 285.547043 -15.534366) (xy 285.517576 -15.580215) (xy 285.481884 -15.621403) (xy 285.44893 -15.649956)
			(xy 300.685466 -15.649956) (xy 300.689436 -15.519822) (xy 300.701332 -15.390172) (xy 300.721111 -15.261489)
			(xy 300.748697 -15.13425) (xy 300.78399 -15.008931) (xy 300.826856 -14.885995) (xy 300.877138 -14.765902)
			(xy 300.934647 -14.649098) (xy 300.999171 -14.536016) (xy 301.070468 -14.427079) (xy 301.148273 -14.322691)
			(xy 301.232298 -14.22324) (xy 301.32223 -14.129097) (xy 301.417734 -14.040612) (xy 301.518454 -13.958113)
			(xy 301.624016 -13.881908) (xy 301.734028 -13.812281) (xy 301.84808 -13.74949) (xy 301.965748 -13.693768)
			(xy 302.086594 -13.645324) (xy 302.210169 -13.604337) (xy 302.336012 -13.57096) (xy 302.463657 -13.545317)
			(xy 302.592627 -13.527503) (xy 302.722443 -13.517585) (xy 302.852622 -13.5156) (xy 302.982681 -13.521554)
			(xy 303.112134 -13.535427) (xy 303.240501 -13.557165) (xy 303.367304 -13.586689) (xy 303.492071 -13.623888)
			(xy 303.614338 -13.668624) (xy 303.733651 -13.720732) (xy 303.849564 -13.780015) (xy 303.961649 -13.846256)
			(xy 304.069486 -13.919206) (xy 304.172675 -13.998594) (xy 304.270833 -14.084126) (xy 304.287258 -14.100302)
			(xy 309.442864 -14.100302) (xy 309.446935 -14.04468) (xy 309.459061 -13.990243) (xy 309.478984 -13.938152)
			(xy 309.50628 -13.889517) (xy 309.540366 -13.845374) (xy 309.580515 -13.806665) (xy 309.625873 -13.774214)
			(xy 309.675473 -13.748713) (xy 309.728257 -13.730706) (xy 309.7831 -13.720576) (xy 309.838834 -13.718539)
			(xy 309.894271 -13.724639) (xy 309.948228 -13.738745) (xy 309.999557 -13.760557) (xy 310.047163 -13.789611)
			(xy 310.090031 -13.825286) (xy 310.127248 -13.866823) (xy 310.158021 -13.913336) (xy 310.181693 -13.963833)
			(xy 310.197761 -14.01724) (xy 310.205881 -14.072416) (xy 310.20639 -14.100302) (xy 310.205881 -14.128188)
			(xy 310.197761 -14.183364) (xy 310.181693 -14.236771) (xy 310.158021 -14.287268) (xy 310.127248 -14.333781)
			(xy 310.090031 -14.375318) (xy 310.047163 -14.410993) (xy 309.999557 -14.440047) (xy 309.948228 -14.461859)
			(xy 309.894271 -14.475965) (xy 309.838834 -14.482065) (xy 309.7831 -14.480028) (xy 309.728257 -14.469898)
			(xy 309.675473 -14.451891) (xy 309.625873 -14.42639) (xy 309.580515 -14.393939) (xy 309.540366 -14.35523)
			(xy 309.50628 -14.311087) (xy 309.478984 -14.262452) (xy 309.459061 -14.210361) (xy 309.446935 -14.155924)
			(xy 309.442864 -14.100302) (xy 304.287258 -14.100302) (xy 304.363594 -14.175483) (xy 304.450613 -14.272325)
			(xy 304.531566 -14.374292) (xy 304.606152 -14.481004) (xy 304.674093 -14.592065) (xy 304.735138 -14.707061)
			(xy 304.789059 -14.825565) (xy 304.835654 -14.947136) (xy 304.874752 -15.071321) (xy 304.906206 -15.197659)
			(xy 304.9299 -15.32568) (xy 304.938712 -15.39755) (xy 310.10428 -15.39755) (xy 310.10428 -15.34305)
			(xy 310.112036 -15.289104) (xy 310.12739 -15.236811) (xy 310.15003 -15.187235) (xy 310.179494 -15.141386)
			(xy 310.215183 -15.100196) (xy 310.256371 -15.064505) (xy 310.302219 -15.035038) (xy 310.351794 -15.012396)
			(xy 310.404086 -14.99704) (xy 310.458032 -14.989281) (xy 310.485282 -14.988794) (xy 310.511517 -14.989266)
			(xy 310.563493 -14.996458) (xy 310.613991 -15.01071) (xy 310.662057 -15.031752) (xy 310.706784 -15.059187)
			(xy 310.747327 -15.092496) (xy 310.765444 -15.111476) (xy 310.765698 -15.11173) (xy 310.773416 -15.11913)
			(xy 310.79311 -15.127394) (xy 310.803798 -15.127732) (xy 310.891682 -15.125446) (xy 310.91124 -15.116048)
			(xy 310.918352 -15.107412) (xy 310.936563 -15.086261) (xy 310.978103 -15.048986) (xy 311.024632 -15.018164)
			(xy 311.075158 -14.994454) (xy 311.128599 -14.978361) (xy 311.183816 -14.970229) (xy 311.211722 -14.969744)
			(xy 311.238969 -14.970328) (xy 311.292907 -14.978086) (xy 311.345193 -14.993441) (xy 311.394761 -15.01608)
			(xy 311.440603 -15.045543) (xy 311.481785 -15.08123) (xy 311.51747 -15.122415) (xy 311.54693 -15.168258)
			(xy 311.569567 -15.217828) (xy 311.584919 -15.270114) (xy 311.592674 -15.324053) (xy 311.592674 -15.378547)
			(xy 311.584919 -15.432486) (xy 311.569567 -15.484772) (xy 311.54693 -15.534342) (xy 311.51747 -15.580185)
			(xy 311.481785 -15.62137) (xy 311.448797 -15.649956) (xy 326.685414 -15.649956) (xy 326.689384 -15.519822)
			(xy 326.70128 -15.390172) (xy 326.721059 -15.261489) (xy 326.748645 -15.13425) (xy 326.783938 -15.008931)
			(xy 326.826804 -14.885995) (xy 326.877086 -14.765902) (xy 326.934595 -14.649098) (xy 326.999119 -14.536016)
			(xy 327.070416 -14.427079) (xy 327.148221 -14.322691) (xy 327.232246 -14.22324) (xy 327.322178 -14.129097)
			(xy 327.417682 -14.040612) (xy 327.518402 -13.958113) (xy 327.623964 -13.881908) (xy 327.733976 -13.812281)
			(xy 327.848028 -13.74949) (xy 327.965696 -13.693768) (xy 328.086542 -13.645324) (xy 328.210117 -13.604337)
			(xy 328.33596 -13.57096) (xy 328.463605 -13.545317) (xy 328.592575 -13.527503) (xy 328.722391 -13.517585)
			(xy 328.85257 -13.5156) (xy 328.982629 -13.521554) (xy 329.112082 -13.535427) (xy 329.240449 -13.557165)
			(xy 329.367252 -13.586689) (xy 329.492019 -13.623888) (xy 329.614286 -13.668624) (xy 329.733599 -13.720732)
			(xy 329.849512 -13.780015) (xy 329.961597 -13.846256) (xy 330.069434 -13.919206) (xy 330.172623 -13.998594)
			(xy 330.270781 -14.084126) (xy 330.363542 -14.175483) (xy 330.450561 -14.272325) (xy 330.531514 -14.374292)
			(xy 330.6061 -14.481004) (xy 330.674041 -14.592065) (xy 330.735086 -14.707061) (xy 330.789007 -14.825565)
			(xy 330.835602 -14.947136) (xy 330.8747 -15.071321) (xy 330.906154 -15.197659) (xy 330.929848 -15.32568)
			(xy 330.945692 -15.454906) (xy 330.95363 -15.584859) (xy 330.954126 -15.649956) (xy 364.785414 -15.649956)
			(xy 364.789384 -15.519822) (xy 364.80128 -15.390172) (xy 364.821059 -15.261489) (xy 364.848645 -15.13425)
			(xy 364.883938 -15.008931) (xy 364.926804 -14.885995) (xy 364.977086 -14.765902) (xy 365.034595 -14.649098)
			(xy 365.099119 -14.536016) (xy 365.170416 -14.427079) (xy 365.248221 -14.322691) (xy 365.332246 -14.22324)
			(xy 365.422178 -14.129097) (xy 365.517682 -14.040612) (xy 365.618402 -13.958113) (xy 365.723964 -13.881908)
			(xy 365.833976 -13.812281) (xy 365.948028 -13.74949) (xy 366.065696 -13.693768) (xy 366.186542 -13.645324)
			(xy 366.310117 -13.604337) (xy 366.43596 -13.57096) (xy 366.563605 -13.545317) (xy 366.692575 -13.527503)
			(xy 366.822391 -13.517585) (xy 366.95257 -13.5156) (xy 367.082629 -13.521554) (xy 367.212082 -13.535427)
			(xy 367.340449 -13.557165) (xy 367.467252 -13.586689) (xy 367.592019 -13.623888) (xy 367.714286 -13.668624)
			(xy 367.833599 -13.720732) (xy 367.949512 -13.780015) (xy 368.061597 -13.846256) (xy 368.169434 -13.919206)
			(xy 368.272623 -13.998594) (xy 368.370781 -14.084126) (xy 368.387206 -14.100302) (xy 373.543066 -14.100302)
			(xy 373.547137 -14.04468) (xy 373.559263 -13.990243) (xy 373.579186 -13.938152) (xy 373.606482 -13.889517)
			(xy 373.640568 -13.845374) (xy 373.680717 -13.806665) (xy 373.726075 -13.774214) (xy 373.775675 -13.748713)
			(xy 373.828459 -13.730706) (xy 373.883302 -13.720576) (xy 373.939036 -13.718539) (xy 373.994473 -13.724639)
			(xy 374.04843 -13.738745) (xy 374.099759 -13.760557) (xy 374.147365 -13.789611) (xy 374.190233 -13.825286)
			(xy 374.22745 -13.866823) (xy 374.258223 -13.913336) (xy 374.281895 -13.963833) (xy 374.297963 -14.01724)
			(xy 374.306083 -14.072416) (xy 374.306592 -14.100302) (xy 374.306083 -14.128188) (xy 374.297963 -14.183364)
			(xy 374.281895 -14.236771) (xy 374.258223 -14.287268) (xy 374.22745 -14.333781) (xy 374.190233 -14.375318)
			(xy 374.147365 -14.410993) (xy 374.099759 -14.440047) (xy 374.04843 -14.461859) (xy 373.994473 -14.475965)
			(xy 373.939036 -14.482065) (xy 373.883302 -14.480028) (xy 373.828459 -14.469898) (xy 373.775675 -14.451891)
			(xy 373.726075 -14.42639) (xy 373.680717 -14.393939) (xy 373.640568 -14.35523) (xy 373.606482 -14.311087)
			(xy 373.579186 -14.262452) (xy 373.559263 -14.210361) (xy 373.547137 -14.155924) (xy 373.543066 -14.100302)
			(xy 368.387206 -14.100302) (xy 368.463542 -14.175483) (xy 368.550561 -14.272325) (xy 368.631514 -14.374292)
			(xy 368.7061 -14.481004) (xy 368.774041 -14.592065) (xy 368.835086 -14.707061) (xy 368.889007 -14.825565)
			(xy 368.935602 -14.947136) (xy 368.9747 -15.071321) (xy 369.006154 -15.197659) (xy 369.029848 -15.32568)
			(xy 369.03866 -15.39755) (xy 374.20448 -15.39755) (xy 374.20448 -15.34305) (xy 374.212236 -15.289104)
			(xy 374.22759 -15.23681) (xy 374.25023 -15.187234) (xy 374.279695 -15.141385) (xy 374.315384 -15.100195)
			(xy 374.356572 -15.064504) (xy 374.40242 -15.035038) (xy 374.451995 -15.012396) (xy 374.504288 -14.997039)
			(xy 374.558234 -14.989281) (xy 374.585484 -14.988794) (xy 374.611719 -14.989264) (xy 374.663695 -14.996457)
			(xy 374.714193 -15.01071) (xy 374.762259 -15.031752) (xy 374.806986 -15.059187) (xy 374.847529 -15.092496)
			(xy 374.865646 -15.111476) (xy 374.8659 -15.11173) (xy 374.873617 -15.119131) (xy 374.893312 -15.127394)
			(xy 374.904 -15.127732) (xy 374.991884 -15.125446) (xy 375.011442 -15.116048) (xy 375.018554 -15.107412)
			(xy 375.036763 -15.08626) (xy 375.078304 -15.048985) (xy 375.124834 -15.018164) (xy 375.175359 -14.994453)
			(xy 375.228801 -14.97836) (xy 375.284018 -14.970229) (xy 375.311924 -14.969744) (xy 375.339171 -14.970328)
			(xy 375.393109 -14.978086) (xy 375.445394 -14.993441) (xy 375.494962 -15.016081) (xy 375.540804 -15.045544)
			(xy 375.581986 -15.081231) (xy 375.61767 -15.122416) (xy 375.647131 -15.168259) (xy 375.669767 -15.217828)
			(xy 375.685119 -15.270115) (xy 375.692874 -15.324053) (xy 375.692874 -15.378547) (xy 375.685119 -15.432485)
			(xy 375.669767 -15.484772) (xy 375.647131 -15.534341) (xy 375.61767 -15.580184) (xy 375.581986 -15.621369)
			(xy 375.548997 -15.649956) (xy 390.785362 -15.649956) (xy 390.789332 -15.519822) (xy 390.801228 -15.390172)
			(xy 390.821007 -15.261489) (xy 390.848593 -15.13425) (xy 390.883886 -15.008931) (xy 390.926752 -14.885995)
			(xy 390.977034 -14.765902) (xy 391.034543 -14.649098) (xy 391.099067 -14.536016) (xy 391.170364 -14.427079)
			(xy 391.248169 -14.322691) (xy 391.332194 -14.22324) (xy 391.422126 -14.129097) (xy 391.51763 -14.040612)
			(xy 391.61835 -13.958113) (xy 391.723912 -13.881908) (xy 391.833924 -13.812281) (xy 391.947976 -13.74949)
			(xy 392.065644 -13.693768) (xy 392.18649 -13.645324) (xy 392.310065 -13.604337) (xy 392.435908 -13.57096)
			(xy 392.563553 -13.545317) (xy 392.692523 -13.527503) (xy 392.822339 -13.517585) (xy 392.952518 -13.5156)
			(xy 393.082577 -13.521554) (xy 393.21203 -13.535427) (xy 393.340397 -13.557165) (xy 393.4672 -13.586689)
			(xy 393.591967 -13.623888) (xy 393.714234 -13.668624) (xy 393.833547 -13.720732) (xy 393.94946 -13.780015)
			(xy 394.061545 -13.846256) (xy 394.169382 -13.919206) (xy 394.272571 -13.998594) (xy 394.370729 -14.084126)
			(xy 394.46349 -14.175483) (xy 394.550509 -14.272325) (xy 394.631462 -14.374292) (xy 394.706048 -14.481004)
			(xy 394.773989 -14.592065) (xy 394.835034 -14.707061) (xy 394.847884 -14.735302) (xy 398.879312 -14.735302)
			(xy 398.883383 -14.67968) (xy 398.895509 -14.625243) (xy 398.915432 -14.573152) (xy 398.942728 -14.524517)
			(xy 398.976814 -14.480374) (xy 399.016963 -14.441665) (xy 399.062321 -14.409214) (xy 399.111921 -14.383713)
			(xy 399.164705 -14.365706) (xy 399.219548 -14.355576) (xy 399.275282 -14.353539) (xy 399.330719 -14.359639)
			(xy 399.384676 -14.373745) (xy 399.436005 -14.395557) (xy 399.483611 -14.424611) (xy 399.526479 -14.460286)
			(xy 399.563696 -14.501823) (xy 399.594469 -14.548336) (xy 399.618141 -14.598833) (xy 399.634209 -14.65224)
			(xy 399.642329 -14.707416) (xy 399.642838 -14.735302) (xy 399.642329 -14.763188) (xy 399.634209 -14.818364)
			(xy 399.618141 -14.871771) (xy 399.594469 -14.922268) (xy 399.563696 -14.968781) (xy 399.526479 -15.010318)
			(xy 399.483611 -15.045993) (xy 399.436005 -15.075047) (xy 399.384676 -15.096859) (xy 399.330719 -15.110965)
			(xy 399.275282 -15.117065) (xy 399.219548 -15.115028) (xy 399.164705 -15.104898) (xy 399.111921 -15.086891)
			(xy 399.062321 -15.06139) (xy 399.016963 -15.028939) (xy 398.976814 -14.99023) (xy 398.942728 -14.946087)
			(xy 398.915432 -14.897452) (xy 398.895509 -14.845361) (xy 398.883383 -14.790924) (xy 398.879312 -14.735302)
			(xy 394.847884 -14.735302) (xy 394.888955 -14.825565) (xy 394.93555 -14.947136) (xy 394.974648 -15.071321)
			(xy 395.006102 -15.197659) (xy 395.029796 -15.32568) (xy 395.038608 -15.397554) (xy 400.204357 -15.397554)
			(xy 400.204357 -15.343046) (xy 400.212115 -15.289092) (xy 400.227473 -15.236792) (xy 400.250117 -15.18721)
			(xy 400.279588 -15.141356) (xy 400.315285 -15.100163) (xy 400.356482 -15.064469) (xy 400.402338 -15.035002)
			(xy 400.451922 -15.012362) (xy 400.504224 -14.997008) (xy 400.558178 -14.989255) (xy 400.585432 -14.988794)
			(xy 400.611668 -14.989232) (xy 400.663645 -14.996432) (xy 400.714144 -15.01069) (xy 400.76221 -15.031739)
			(xy 400.806937 -15.059179) (xy 400.847478 -15.092493) (xy 400.865594 -15.111476) (xy 400.865848 -15.11173)
			(xy 400.873584 -15.119107) (xy 400.893265 -15.127384) (xy 400.903948 -15.127732) (xy 400.991832 -15.125446)
			(xy 401.01139 -15.116048) (xy 401.018502 -15.107412) (xy 401.036686 -15.086237) (xy 401.078232 -15.048964)
			(xy 401.124767 -15.018145) (xy 401.175297 -14.994439) (xy 401.228744 -14.978351) (xy 401.283964 -14.970225)
			(xy 401.311872 -14.969744) (xy 401.339123 -14.970301) (xy 401.39307 -14.978054) (xy 401.445365 -14.993406)
			(xy 401.494942 -15.016044) (xy 401.540793 -15.045507) (xy 401.581984 -15.081197) (xy 401.617676 -15.122385)
			(xy 401.647143 -15.168233) (xy 401.669784 -15.217809) (xy 401.68514 -15.270103) (xy 401.692897 -15.324049)
			(xy 401.692897 -15.378551) (xy 401.68514 -15.432497) (xy 401.669784 -15.484791) (xy 401.647143 -15.534367)
			(xy 401.617676 -15.580215) (xy 401.581984 -15.621403) (xy 401.54903 -15.649956) (xy 416.78531 -15.649956)
			(xy 416.78928 -15.519822) (xy 416.801176 -15.390172) (xy 416.820955 -15.261489) (xy 416.848541 -15.13425)
			(xy 416.883834 -15.008931) (xy 416.9267 -14.885995) (xy 416.976982 -14.765902) (xy 417.034491 -14.649098)
			(xy 417.099015 -14.536016) (xy 417.170312 -14.427079) (xy 417.248117 -14.322691) (xy 417.332142 -14.22324)
			(xy 417.422074 -14.129097) (xy 417.517578 -14.040612) (xy 417.618298 -13.958113) (xy 417.72386 -13.881908)
			(xy 417.833872 -13.812281) (xy 417.947924 -13.74949) (xy 418.065592 -13.693768) (xy 418.186438 -13.645324)
			(xy 418.310013 -13.604337) (xy 418.435856 -13.57096) (xy 418.563501 -13.545317) (xy 418.692471 -13.527503)
			(xy 418.822287 -13.517585) (xy 418.952466 -13.5156) (xy 419.082525 -13.521554) (xy 419.211978 -13.535427)
			(xy 419.340345 -13.557165) (xy 419.467148 -13.586689) (xy 419.591915 -13.623888) (xy 419.714182 -13.668624)
			(xy 419.833495 -13.720732) (xy 419.949408 -13.780015) (xy 420.061493 -13.846256) (xy 420.16933 -13.919206)
			(xy 420.272519 -13.998594) (xy 420.370677 -14.084126) (xy 420.387102 -14.100302) (xy 425.542962 -14.100302)
			(xy 425.547033 -14.04468) (xy 425.559159 -13.990243) (xy 425.579082 -13.938152) (xy 425.606378 -13.889517)
			(xy 425.640464 -13.845374) (xy 425.680613 -13.806665) (xy 425.725971 -13.774214) (xy 425.775571 -13.748713)
			(xy 425.828355 -13.730706) (xy 425.883198 -13.720576) (xy 425.938932 -13.718539) (xy 425.994369 -13.724639)
			(xy 426.048326 -13.738745) (xy 426.099655 -13.760557) (xy 426.147261 -13.789611) (xy 426.190129 -13.825286)
			(xy 426.227346 -13.866823) (xy 426.258119 -13.913336) (xy 426.281791 -13.963833) (xy 426.297859 -14.01724)
			(xy 426.305979 -14.072416) (xy 426.306488 -14.100302) (xy 426.305979 -14.128188) (xy 426.297859 -14.183364)
			(xy 426.281791 -14.236771) (xy 426.258119 -14.287268) (xy 426.227346 -14.333781) (xy 426.190129 -14.375318)
			(xy 426.147261 -14.410993) (xy 426.099655 -14.440047) (xy 426.048326 -14.461859) (xy 425.994369 -14.475965)
			(xy 425.938932 -14.482065) (xy 425.883198 -14.480028) (xy 425.828355 -14.469898) (xy 425.775571 -14.451891)
			(xy 425.725971 -14.42639) (xy 425.680613 -14.393939) (xy 425.640464 -14.35523) (xy 425.606378 -14.311087)
			(xy 425.579082 -14.262452) (xy 425.559159 -14.210361) (xy 425.547033 -14.155924) (xy 425.542962 -14.100302)
			(xy 420.387102 -14.100302) (xy 420.463438 -14.175483) (xy 420.550457 -14.272325) (xy 420.63141 -14.374292)
			(xy 420.705996 -14.481004) (xy 420.773937 -14.592065) (xy 420.834982 -14.707061) (xy 420.888903 -14.825565)
			(xy 420.935498 -14.947136) (xy 420.974596 -15.071321) (xy 421.00605 -15.197659) (xy 421.029744 -15.32568)
			(xy 421.038556 -15.39755) (xy 426.20438 -15.39755) (xy 426.20438 -15.34305) (xy 426.212136 -15.289104)
			(xy 426.22749 -15.236811) (xy 426.250129 -15.187236) (xy 426.279594 -15.141386) (xy 426.315283 -15.100197)
			(xy 426.35647 -15.064506) (xy 426.402318 -15.035039) (xy 426.451892 -15.012397) (xy 426.504185 -14.99704)
			(xy 426.55813 -14.989281) (xy 426.58538 -14.988794) (xy 426.611615 -14.989267) (xy 426.663591 -14.996459)
			(xy 426.714089 -15.010711) (xy 426.762155 -15.031753) (xy 426.806882 -15.059187) (xy 426.847425 -15.092496)
			(xy 426.865542 -15.111476) (xy 426.865796 -15.11173) (xy 426.873514 -15.119129) (xy 426.893208 -15.127394)
			(xy 426.903896 -15.127732) (xy 426.99178 -15.125446) (xy 427.011338 -15.116048) (xy 427.01845 -15.107412)
			(xy 427.036662 -15.086262) (xy 427.078202 -15.048987) (xy 427.124731 -15.018165) (xy 427.175256 -14.994454)
			(xy 427.228698 -14.978361) (xy 427.283914 -14.970229) (xy 427.31182 -14.969744) (xy 427.339067 -14.970328)
			(xy 427.393006 -14.978085) (xy 427.445291 -14.99344) (xy 427.49486 -15.01608) (xy 427.540702 -15.045543)
			(xy 427.581884 -15.08123) (xy 427.617569 -15.122414) (xy 427.64703 -15.168258) (xy 427.669667 -15.217827)
			(xy 427.685019 -15.270114) (xy 427.692774 -15.324053) (xy 427.692774 -15.378547) (xy 427.685019 -15.432486)
			(xy 427.669667 -15.484773) (xy 427.64703 -15.534342) (xy 427.617569 -15.580186) (xy 427.581884 -15.62137)
			(xy 427.548896 -15.649956) (xy 442.785512 -15.649956) (xy 442.789482 -15.519822) (xy 442.801378 -15.390172)
			(xy 442.821157 -15.261489) (xy 442.848743 -15.13425) (xy 442.884036 -15.008931) (xy 442.926902 -14.885995)
			(xy 442.977184 -14.765902) (xy 443.034693 -14.649098) (xy 443.099217 -14.536016) (xy 443.170514 -14.427079)
			(xy 443.248319 -14.322691) (xy 443.332344 -14.22324) (xy 443.422276 -14.129097) (xy 443.51778 -14.040612)
			(xy 443.6185 -13.958113) (xy 443.724062 -13.881908) (xy 443.834074 -13.812281) (xy 443.948126 -13.74949)
			(xy 444.065794 -13.693768) (xy 444.18664 -13.645324) (xy 444.310215 -13.604337) (xy 444.436058 -13.57096)
			(xy 444.563703 -13.545317) (xy 444.692673 -13.527503) (xy 444.822489 -13.517585) (xy 444.952668 -13.5156)
			(xy 445.082727 -13.521554) (xy 445.21218 -13.535427) (xy 445.340547 -13.557165) (xy 445.46735 -13.586689)
			(xy 445.592117 -13.623888) (xy 445.714384 -13.668624) (xy 445.833697 -13.720732) (xy 445.94961 -13.780015)
			(xy 446.061695 -13.846256) (xy 446.169532 -13.919206) (xy 446.272721 -13.998594) (xy 446.370879 -14.084126)
			(xy 446.387304 -14.100302) (xy 451.54291 -14.100302) (xy 451.546981 -14.04468) (xy 451.559107 -13.990243)
			(xy 451.57903 -13.938152) (xy 451.606326 -13.889517) (xy 451.640412 -13.845374) (xy 451.680561 -13.806665)
			(xy 451.725919 -13.774214) (xy 451.775519 -13.748713) (xy 451.828303 -13.730706) (xy 451.883146 -13.720576)
			(xy 451.93888 -13.718539) (xy 451.994317 -13.724639) (xy 452.048274 -13.738745) (xy 452.099603 -13.760557)
			(xy 452.147209 -13.789611) (xy 452.190077 -13.825286) (xy 452.227294 -13.866823) (xy 452.258067 -13.913336)
			(xy 452.281739 -13.963833) (xy 452.297807 -14.01724) (xy 452.305927 -14.072416) (xy 452.306436 -14.100302)
			(xy 452.305927 -14.128188) (xy 452.297807 -14.183364) (xy 452.281739 -14.236771) (xy 452.258067 -14.287268)
			(xy 452.227294 -14.333781) (xy 452.190077 -14.375318) (xy 452.147209 -14.410993) (xy 452.099603 -14.440047)
			(xy 452.048274 -14.461859) (xy 451.994317 -14.475965) (xy 451.93888 -14.482065) (xy 451.883146 -14.480028)
			(xy 451.828303 -14.469898) (xy 451.775519 -14.451891) (xy 451.725919 -14.42639) (xy 451.680561 -14.393939)
			(xy 451.640412 -14.35523) (xy 451.606326 -14.311087) (xy 451.57903 -14.262452) (xy 451.559107 -14.210361)
			(xy 451.546981 -14.155924) (xy 451.54291 -14.100302) (xy 446.387304 -14.100302) (xy 446.46364 -14.175483)
			(xy 446.550659 -14.272325) (xy 446.631612 -14.374292) (xy 446.706198 -14.481004) (xy 446.774139 -14.592065)
			(xy 446.835184 -14.707061) (xy 446.889105 -14.825565) (xy 446.9357 -14.947136) (xy 446.974798 -15.071321)
			(xy 447.006252 -15.197659) (xy 447.029946 -15.32568) (xy 447.035417 -15.370302) (xy 452.20331 -15.370302)
			(xy 452.207381 -15.31468) (xy 452.219507 -15.260243) (xy 452.23943 -15.208152) (xy 452.266726 -15.159517)
			(xy 452.300812 -15.115374) (xy 452.340961 -15.076665) (xy 452.386319 -15.044214) (xy 452.435919 -15.018713)
			(xy 452.488703 -15.000706) (xy 452.543546 -14.990576) (xy 452.59928 -14.988539) (xy 452.654717 -14.994639)
			(xy 452.708674 -15.008745) (xy 452.760003 -15.030557) (xy 452.807609 -15.059611) (xy 452.850477 -15.095286)
			(xy 452.887694 -15.136823) (xy 452.918467 -15.183336) (xy 452.942139 -15.233833) (xy 452.958207 -15.28724)
			(xy 452.966327 -15.342416) (xy 452.966836 -15.370302) (xy 452.966327 -15.398188) (xy 452.964936 -15.40764)
			(xy 453.070466 -15.40764) (xy 453.074537 -15.352018) (xy 453.086663 -15.297581) (xy 453.106586 -15.24549)
			(xy 453.133882 -15.196855) (xy 453.167968 -15.152712) (xy 453.208117 -15.114003) (xy 453.253475 -15.081552)
			(xy 453.303075 -15.056051) (xy 453.355859 -15.038044) (xy 453.410702 -15.027914) (xy 453.466436 -15.025877)
			(xy 453.521873 -15.031977) (xy 453.57583 -15.046083) (xy 453.627159 -15.067895) (xy 453.674765 -15.096949)
			(xy 453.717633 -15.132624) (xy 453.75485 -15.174161) (xy 453.772026 -15.200122) (xy 459.541372 -15.200122)
			(xy 459.541372 -13.599922) (xy 459.54188 -13.535242) (xy 459.550003 -13.406136) (xy 459.566216 -13.277796)
			(xy 459.590456 -13.150726) (xy 459.622626 -13.02543) (xy 459.662601 -12.9024) (xy 459.710222 -12.782124)
			(xy 459.765301 -12.665075) (xy 459.827621 -12.551715) (xy 459.896936 -12.442492) (xy 459.972972 -12.337837)
			(xy 460.05543 -12.238163) (xy 460.143983 -12.143863) (xy 460.238283 -12.05531) (xy 460.337957 -11.972852)
			(xy 460.442612 -11.896816) (xy 460.551835 -11.827501) (xy 460.665195 -11.765181) (xy 460.782244 -11.710102)
			(xy 460.90252 -11.662481) (xy 461.02555 -11.622506) (xy 461.150846 -11.590336) (xy 461.277916 -11.566096)
			(xy 461.406256 -11.549883) (xy 461.535362 -11.54176) (xy 461.664722 -11.54176) (xy 461.793828 -11.549883)
			(xy 461.922168 -11.566096) (xy 462.049238 -11.590336) (xy 462.174534 -11.622506) (xy 462.297564 -11.662481)
			(xy 462.41784 -11.710102) (xy 462.534889 -11.765181) (xy 462.648249 -11.827501) (xy 462.757472 -11.896816)
			(xy 462.862127 -11.972852) (xy 462.961801 -12.05531) (xy 463.056101 -12.143863) (xy 463.144654 -12.238163)
			(xy 463.227112 -12.337837) (xy 463.303148 -12.442492) (xy 463.372463 -12.551715) (xy 463.434783 -12.665075)
			(xy 463.489862 -12.782124) (xy 463.537483 -12.9024) (xy 463.577458 -13.02543) (xy 463.609628 -13.150726)
			(xy 463.633868 -13.277796) (xy 463.650081 -13.406136) (xy 463.658204 -13.535242) (xy 463.658712 -13.599922)
			(xy 463.658712 -15.200122) (xy 463.658204 -15.264802) (xy 463.650081 -15.393908) (xy 463.633868 -15.522248)
			(xy 463.609628 -15.649318) (xy 463.577458 -15.774614) (xy 463.537483 -15.897644) (xy 463.489862 -16.01792)
			(xy 463.434783 -16.134969) (xy 463.372463 -16.248329) (xy 463.303148 -16.357552) (xy 463.227112 -16.462207)
			(xy 463.144654 -16.561881) (xy 463.056101 -16.656181) (xy 462.961801 -16.744734) (xy 462.862127 -16.827192)
			(xy 462.757472 -16.903228) (xy 462.648249 -16.972543) (xy 462.534889 -17.034863) (xy 462.41784 -17.089942)
			(xy 462.297564 -17.137563) (xy 462.174534 -17.177538) (xy 462.049238 -17.209708) (xy 461.922168 -17.233948)
			(xy 461.793828 -17.250161) (xy 461.664722 -17.258284) (xy 461.535362 -17.258284) (xy 461.406256 -17.250161)
			(xy 461.277916 -17.233948) (xy 461.150846 -17.209708) (xy 461.02555 -17.177538) (xy 460.90252 -17.137563)
			(xy 460.782244 -17.089942) (xy 460.665195 -17.034863) (xy 460.551835 -16.972543) (xy 460.442612 -16.903228)
			(xy 460.337957 -16.827192) (xy 460.238283 -16.744734) (xy 460.143983 -16.656181) (xy 460.05543 -16.561881)
			(xy 459.972972 -16.462207) (xy 459.896936 -16.357552) (xy 459.827621 -16.248329) (xy 459.765301 -16.134969)
			(xy 459.710222 -16.01792) (xy 459.662601 -15.897644) (xy 459.622626 -15.774614) (xy 459.590456 -15.649318)
			(xy 459.566216 -15.522248) (xy 459.550003 -15.393908) (xy 459.54188 -15.264802) (xy 459.541372 -15.200122)
			(xy 453.772026 -15.200122) (xy 453.785623 -15.220674) (xy 453.809295 -15.271171) (xy 453.825363 -15.324578)
			(xy 453.833483 -15.379754) (xy 453.833992 -15.40764) (xy 453.833483 -15.435526) (xy 453.825363 -15.490702)
			(xy 453.809295 -15.544109) (xy 453.785623 -15.594606) (xy 453.75485 -15.641119) (xy 453.717633 -15.682656)
			(xy 453.674765 -15.718331) (xy 453.627159 -15.747385) (xy 453.57583 -15.769197) (xy 453.521873 -15.783303)
			(xy 453.466436 -15.789403) (xy 453.410702 -15.787366) (xy 453.355859 -15.777236) (xy 453.303075 -15.759229)
			(xy 453.253475 -15.733728) (xy 453.208117 -15.701277) (xy 453.167968 -15.662568) (xy 453.133882 -15.618425)
			(xy 453.106586 -15.56979) (xy 453.086663 -15.517699) (xy 453.074537 -15.463262) (xy 453.070466 -15.40764)
			(xy 452.964936 -15.40764) (xy 452.958207 -15.453364) (xy 452.942139 -15.506771) (xy 452.918467 -15.557268)
			(xy 452.887694 -15.603781) (xy 452.850477 -15.645318) (xy 452.807609 -15.680993) (xy 452.760003 -15.710047)
			(xy 452.708674 -15.731859) (xy 452.654717 -15.745965) (xy 452.59928 -15.752065) (xy 452.543546 -15.750028)
			(xy 452.488703 -15.739898) (xy 452.435919 -15.721891) (xy 452.386319 -15.69639) (xy 452.340961 -15.663939)
			(xy 452.300812 -15.62523) (xy 452.266726 -15.581087) (xy 452.23943 -15.532452) (xy 452.219507 -15.480361)
			(xy 452.207381 -15.425924) (xy 452.20331 -15.370302) (xy 447.035417 -15.370302) (xy 447.04579 -15.454906)
			(xy 447.053728 -15.584859) (xy 447.054224 -15.649956) (xy 447.053728 -15.715053) (xy 447.04579 -15.845006)
			(xy 447.029946 -15.974232) (xy 447.006252 -16.102253) (xy 446.974798 -16.228591) (xy 446.9357 -16.352776)
			(xy 446.889105 -16.474347) (xy 446.835184 -16.592851) (xy 446.774139 -16.707847) (xy 446.706198 -16.818908)
			(xy 446.631612 -16.92562) (xy 446.550659 -17.027587) (xy 446.46364 -17.124429) (xy 446.370879 -17.215786)
			(xy 446.272721 -17.301318) (xy 446.169532 -17.380706) (xy 446.112076 -17.419574) (xy 450.58406 -17.419574)
			(xy 450.588131 -17.363952) (xy 450.600257 -17.309515) (xy 450.62018 -17.257424) (xy 450.647476 -17.208789)
			(xy 450.681562 -17.164646) (xy 450.721711 -17.125937) (xy 450.767069 -17.093486) (xy 450.816669 -17.067985)
			(xy 450.869453 -17.049978) (xy 450.924296 -17.039848) (xy 450.98003 -17.037811) (xy 451.035467 -17.043911)
			(xy 451.089424 -17.058017) (xy 451.140753 -17.079829) (xy 451.188359 -17.108883) (xy 451.231227 -17.144558)
			(xy 451.268444 -17.186095) (xy 451.299217 -17.232608) (xy 451.322889 -17.283105) (xy 451.338957 -17.336512)
			(xy 451.347077 -17.391688) (xy 451.347586 -17.419574) (xy 451.347077 -17.44746) (xy 451.338957 -17.502636)
			(xy 451.322889 -17.556043) (xy 451.299217 -17.60654) (xy 451.268444 -17.653053) (xy 451.231227 -17.69459)
			(xy 451.188359 -17.730265) (xy 451.140753 -17.759319) (xy 451.089424 -17.781131) (xy 451.035467 -17.795237)
			(xy 450.98003 -17.801337) (xy 450.924296 -17.7993) (xy 450.869453 -17.78917) (xy 450.816669 -17.771163)
			(xy 450.767069 -17.745662) (xy 450.721711 -17.713211) (xy 450.681562 -17.674502) (xy 450.647476 -17.630359)
			(xy 450.62018 -17.581724) (xy 450.600257 -17.529633) (xy 450.588131 -17.475196) (xy 450.58406 -17.419574)
			(xy 446.112076 -17.419574) (xy 446.061695 -17.453656) (xy 445.94961 -17.519897) (xy 445.833697 -17.57918)
			(xy 445.714384 -17.631288) (xy 445.592117 -17.676024) (xy 445.46735 -17.713223) (xy 445.340547 -17.742747)
			(xy 445.21218 -17.764485) (xy 445.082727 -17.778358) (xy 444.952668 -17.784312) (xy 444.822489 -17.782327)
			(xy 444.692673 -17.772409) (xy 444.563703 -17.754595) (xy 444.436058 -17.728952) (xy 444.310215 -17.695575)
			(xy 444.18664 -17.654588) (xy 444.065794 -17.606144) (xy 443.948126 -17.550422) (xy 443.834074 -17.487631)
			(xy 443.724062 -17.418004) (xy 443.6185 -17.341799) (xy 443.51778 -17.2593) (xy 443.422276 -17.170815)
			(xy 443.332344 -17.076672) (xy 443.248319 -16.977221) (xy 443.170514 -16.872833) (xy 443.099217 -16.763896)
			(xy 443.034693 -16.650814) (xy 442.977184 -16.53401) (xy 442.926902 -16.413917) (xy 442.884036 -16.290981)
			(xy 442.848743 -16.165662) (xy 442.821157 -16.038423) (xy 442.801378 -15.90974) (xy 442.789482 -15.78009)
			(xy 442.785512 -15.649956) (xy 427.548896 -15.649956) (xy 427.540702 -15.657057) (xy 427.49486 -15.68652)
			(xy 427.445291 -15.70916) (xy 427.393006 -15.724515) (xy 427.339067 -15.732272) (xy 427.31182 -15.73276)
			(xy 427.285584 -15.732302) (xy 427.233608 -15.725108) (xy 427.183109 -15.710855) (xy 427.135042 -15.68981)
			(xy 427.090315 -15.662373) (xy 427.049774 -15.62906) (xy 427.031658 -15.610078) (xy 427.031404 -15.609824)
			(xy 427.023691 -15.602418) (xy 427.003993 -15.594159) (xy 426.993304 -15.593822) (xy 426.90542 -15.596108)
			(xy 426.885862 -15.605506) (xy 426.87875 -15.614142) (xy 426.860528 -15.635283) (xy 426.818991 -15.67256)
			(xy 426.772464 -15.703385) (xy 426.721941 -15.727097) (xy 426.668501 -15.743192) (xy 426.613286 -15.751325)
			(xy 426.58538 -15.75181) (xy 426.55813 -15.751319) (xy 426.504185 -15.74356) (xy 426.451892 -15.728203)
			(xy 426.402318 -15.705561) (xy 426.35647 -15.676094) (xy 426.315283 -15.640403) (xy 426.279594 -15.599214)
			(xy 426.250129 -15.553364) (xy 426.22749 -15.503789) (xy 426.212136 -15.451496) (xy 426.20438 -15.39755)
			(xy 421.038556 -15.39755) (xy 421.045588 -15.454906) (xy 421.053526 -15.584859) (xy 421.054022 -15.649956)
			(xy 421.053526 -15.715053) (xy 421.045588 -15.845006) (xy 421.029744 -15.974232) (xy 421.00605 -16.102253)
			(xy 420.974596 -16.228591) (xy 420.935498 -16.352776) (xy 420.888903 -16.474347) (xy 420.834982 -16.592851)
			(xy 420.773937 -16.707847) (xy 420.705996 -16.818908) (xy 420.63141 -16.92562) (xy 420.596181 -16.969994)
			(xy 440.048149 -16.969994) (xy 440.052154 -16.882086) (xy 440.064137 -16.794906) (xy 440.083997 -16.709177)
			(xy 440.111572 -16.625609) (xy 440.146631 -16.544895) (xy 440.188884 -16.467703) (xy 440.237982 -16.394674)
			(xy 440.293518 -16.326412) (xy 440.35503 -16.263482) (xy 440.422011 -16.206408) (xy 440.493904 -16.15566)
			(xy 440.570113 -16.11166) (xy 440.650008 -16.074773) (xy 440.732927 -16.045304) (xy 440.818182 -16.023497)
			(xy 440.905066 -16.009533) (xy 440.99286 -16.003527) (xy 441.080837 -16.005531) (xy 441.168267 -16.015526)
			(xy 441.254426 -16.03343) (xy 441.3386 -16.059094) (xy 441.420091 -16.092307) (xy 441.498225 -16.132793)
			(xy 441.572353 -16.180215) (xy 441.641861 -16.234182) (xy 441.706175 -16.294247) (xy 441.764759 -16.359911)
			(xy 441.81713 -16.43063) (xy 441.862853 -16.505818) (xy 441.90155 -16.584853) (xy 441.932899 -16.667079)
			(xy 441.956641 -16.751815) (xy 441.972579 -16.838359) (xy 441.980581 -16.925994) (xy 441.981082 -16.969994)
			(xy 441.980581 -17.013994) (xy 441.972579 -17.101629) (xy 441.956641 -17.188173) (xy 441.932899 -17.272909)
			(xy 441.90155 -17.355135) (xy 441.862853 -17.43417) (xy 441.81713 -17.509358) (xy 441.764759 -17.580077)
			(xy 441.706175 -17.645741) (xy 441.641861 -17.705806) (xy 441.572353 -17.759773) (xy 441.498225 -17.807195)
			(xy 441.420091 -17.847681) (xy 441.3386 -17.880894) (xy 441.254426 -17.906558) (xy 441.168267 -17.924462)
			(xy 441.080837 -17.934457) (xy 440.99286 -17.936461) (xy 440.905066 -17.930455) (xy 440.818182 -17.916491)
			(xy 440.732927 -17.894684) (xy 440.650008 -17.865215) (xy 440.570113 -17.828328) (xy 440.493904 -17.784328)
			(xy 440.422011 -17.73358) (xy 440.35503 -17.676506) (xy 440.293518 -17.613576) (xy 440.237982 -17.545314)
			(xy 440.188884 -17.472285) (xy 440.146631 -17.395093) (xy 440.111572 -17.314379) (xy 440.083997 -17.230811)
			(xy 440.064137 -17.145082) (xy 440.052154 -17.057902) (xy 440.048149 -16.969994) (xy 420.596181 -16.969994)
			(xy 420.550457 -17.027587) (xy 420.463438 -17.124429) (xy 420.370677 -17.215786) (xy 420.272519 -17.301318)
			(xy 420.16933 -17.380706) (xy 420.111874 -17.419574) (xy 424.584112 -17.419574) (xy 424.588183 -17.363952)
			(xy 424.600309 -17.309515) (xy 424.620232 -17.257424) (xy 424.647528 -17.208789) (xy 424.681614 -17.164646)
			(xy 424.721763 -17.125937) (xy 424.767121 -17.093486) (xy 424.816721 -17.067985) (xy 424.869505 -17.049978)
			(xy 424.924348 -17.039848) (xy 424.980082 -17.037811) (xy 425.035519 -17.043911) (xy 425.089476 -17.058017)
			(xy 425.140805 -17.079829) (xy 425.188411 -17.108883) (xy 425.231279 -17.144558) (xy 425.268496 -17.186095)
			(xy 425.299269 -17.232608) (xy 425.322941 -17.283105) (xy 425.339009 -17.336512) (xy 425.347129 -17.391688)
			(xy 425.347638 -17.419574) (xy 425.347129 -17.44746) (xy 425.339009 -17.502636) (xy 425.322941 -17.556043)
			(xy 425.299269 -17.60654) (xy 425.268496 -17.653053) (xy 425.231279 -17.69459) (xy 425.188411 -17.730265)
			(xy 425.140805 -17.759319) (xy 425.089476 -17.781131) (xy 425.035519 -17.795237) (xy 424.980082 -17.801337)
			(xy 424.924348 -17.7993) (xy 424.869505 -17.78917) (xy 424.816721 -17.771163) (xy 424.767121 -17.745662)
			(xy 424.721763 -17.713211) (xy 424.681614 -17.674502) (xy 424.647528 -17.630359) (xy 424.620232 -17.581724)
			(xy 424.600309 -17.529633) (xy 424.588183 -17.475196) (xy 424.584112 -17.419574) (xy 420.111874 -17.419574)
			(xy 420.061493 -17.453656) (xy 419.949408 -17.519897) (xy 419.833495 -17.57918) (xy 419.714182 -17.631288)
			(xy 419.591915 -17.676024) (xy 419.467148 -17.713223) (xy 419.340345 -17.742747) (xy 419.211978 -17.764485)
			(xy 419.082525 -17.778358) (xy 418.952466 -17.784312) (xy 418.822287 -17.782327) (xy 418.692471 -17.772409)
			(xy 418.563501 -17.754595) (xy 418.435856 -17.728952) (xy 418.310013 -17.695575) (xy 418.186438 -17.654588)
			(xy 418.065592 -17.606144) (xy 417.947924 -17.550422) (xy 417.833872 -17.487631) (xy 417.72386 -17.418004)
			(xy 417.618298 -17.341799) (xy 417.517578 -17.2593) (xy 417.422074 -17.170815) (xy 417.332142 -17.076672)
			(xy 417.248117 -16.977221) (xy 417.170312 -16.872833) (xy 417.099015 -16.763896) (xy 417.034491 -16.650814)
			(xy 416.976982 -16.53401) (xy 416.9267 -16.413917) (xy 416.883834 -16.290981) (xy 416.848541 -16.165662)
			(xy 416.820955 -16.038423) (xy 416.801176 -15.90974) (xy 416.78928 -15.78009) (xy 416.78531 -15.649956)
			(xy 401.54903 -15.649956) (xy 401.540793 -15.657093) (xy 401.494942 -15.686556) (xy 401.445365 -15.709194)
			(xy 401.39307 -15.724546) (xy 401.339123 -15.732299) (xy 401.311872 -15.73276) (xy 401.285635 -15.732334)
			(xy 401.233657 -15.725134) (xy 401.183158 -15.710874) (xy 401.135091 -15.689823) (xy 401.090365 -15.66238)
			(xy 401.049825 -15.629063) (xy 401.03171 -15.610078) (xy 401.031456 -15.609824) (xy 401.023724 -15.602442)
			(xy 401.00404 -15.594169) (xy 400.993356 -15.593822) (xy 400.905472 -15.596108) (xy 400.885914 -15.605506)
			(xy 400.878802 -15.614142) (xy 400.860605 -15.635306) (xy 400.819064 -15.672582) (xy 400.772531 -15.703403)
			(xy 400.722003 -15.727112) (xy 400.668558 -15.743202) (xy 400.613339 -15.751328) (xy 400.585432 -15.75181)
			(xy 400.558178 -15.751345) (xy 400.504224 -15.743592) (xy 400.451922 -15.728238) (xy 400.402338 -15.705598)
			(xy 400.356481 -15.676131) (xy 400.315285 -15.640437) (xy 400.279588 -15.599244) (xy 400.250117 -15.55339)
			(xy 400.227473 -15.503808) (xy 400.212115 -15.451508) (xy 400.204357 -15.397554) (xy 395.038608 -15.397554)
			(xy 395.04564 -15.454906) (xy 395.053578 -15.584859) (xy 395.054074 -15.649956) (xy 395.053578 -15.715053)
			(xy 395.04564 -15.845006) (xy 395.029796 -15.974232) (xy 395.006102 -16.102253) (xy 394.974648 -16.228591)
			(xy 394.93555 -16.352776) (xy 394.888955 -16.474347) (xy 394.835034 -16.592851) (xy 394.773989 -16.707847)
			(xy 394.706048 -16.818908) (xy 394.631462 -16.92562) (xy 394.596233 -16.969994) (xy 414.048201 -16.969994)
			(xy 414.052206 -16.882086) (xy 414.064189 -16.794906) (xy 414.084049 -16.709177) (xy 414.111624 -16.625609)
			(xy 414.146683 -16.544895) (xy 414.188936 -16.467703) (xy 414.238034 -16.394674) (xy 414.29357 -16.326412)
			(xy 414.355082 -16.263482) (xy 414.422063 -16.206408) (xy 414.493956 -16.15566) (xy 414.570165 -16.11166)
			(xy 414.65006 -16.074773) (xy 414.732979 -16.045304) (xy 414.818234 -16.023497) (xy 414.905118 -16.009533)
			(xy 414.992912 -16.003527) (xy 415.080889 -16.005531) (xy 415.168319 -16.015526) (xy 415.254478 -16.03343)
			(xy 415.338652 -16.059094) (xy 415.420143 -16.092307) (xy 415.498277 -16.132793) (xy 415.572405 -16.180215)
			(xy 415.641913 -16.234182) (xy 415.706227 -16.294247) (xy 415.764811 -16.359911) (xy 415.817182 -16.43063)
			(xy 415.862905 -16.505818) (xy 415.901602 -16.584853) (xy 415.932951 -16.667079) (xy 415.956693 -16.751815)
			(xy 415.972631 -16.838359) (xy 415.980633 -16.925994) (xy 415.981134 -16.969994) (xy 415.980633 -17.013994)
			(xy 415.972631 -17.101629) (xy 415.956693 -17.188173) (xy 415.932951 -17.272909) (xy 415.901602 -17.355135)
			(xy 415.862905 -17.43417) (xy 415.817182 -17.509358) (xy 415.764811 -17.580077) (xy 415.706227 -17.645741)
			(xy 415.641913 -17.705806) (xy 415.572405 -17.759773) (xy 415.498277 -17.807195) (xy 415.420143 -17.847681)
			(xy 415.338652 -17.880894) (xy 415.254478 -17.906558) (xy 415.168319 -17.924462) (xy 415.080889 -17.934457)
			(xy 414.992912 -17.936461) (xy 414.905118 -17.930455) (xy 414.818234 -17.916491) (xy 414.732979 -17.894684)
			(xy 414.65006 -17.865215) (xy 414.570165 -17.828328) (xy 414.493956 -17.784328) (xy 414.422063 -17.73358)
			(xy 414.355082 -17.676506) (xy 414.29357 -17.613576) (xy 414.238034 -17.545314) (xy 414.188936 -17.472285)
			(xy 414.146683 -17.395093) (xy 414.111624 -17.314379) (xy 414.084049 -17.230811) (xy 414.064189 -17.145082)
			(xy 414.052206 -17.057902) (xy 414.048201 -16.969994) (xy 394.596233 -16.969994) (xy 394.550509 -17.027587)
			(xy 394.46349 -17.124429) (xy 394.370729 -17.215786) (xy 394.272571 -17.301318) (xy 394.169382 -17.380706)
			(xy 394.111926 -17.419574) (xy 398.584164 -17.419574) (xy 398.588235 -17.363952) (xy 398.600361 -17.309515)
			(xy 398.620284 -17.257424) (xy 398.64758 -17.208789) (xy 398.681666 -17.164646) (xy 398.721815 -17.125937)
			(xy 398.767173 -17.093486) (xy 398.816773 -17.067985) (xy 398.869557 -17.049978) (xy 398.9244 -17.039848)
			(xy 398.980134 -17.037811) (xy 399.035571 -17.043911) (xy 399.089528 -17.058017) (xy 399.140857 -17.079829)
			(xy 399.188463 -17.108883) (xy 399.231331 -17.144558) (xy 399.268548 -17.186095) (xy 399.299321 -17.232608)
			(xy 399.322993 -17.283105) (xy 399.339061 -17.336512) (xy 399.347181 -17.391688) (xy 399.34769 -17.419574)
			(xy 399.347181 -17.44746) (xy 399.339061 -17.502636) (xy 399.322993 -17.556043) (xy 399.299321 -17.60654)
			(xy 399.268548 -17.653053) (xy 399.231331 -17.69459) (xy 399.188463 -17.730265) (xy 399.140857 -17.759319)
			(xy 399.089528 -17.781131) (xy 399.035571 -17.795237) (xy 398.980134 -17.801337) (xy 398.9244 -17.7993)
			(xy 398.869557 -17.78917) (xy 398.816773 -17.771163) (xy 398.767173 -17.745662) (xy 398.721815 -17.713211)
			(xy 398.681666 -17.674502) (xy 398.64758 -17.630359) (xy 398.620284 -17.581724) (xy 398.600361 -17.529633)
			(xy 398.588235 -17.475196) (xy 398.584164 -17.419574) (xy 394.111926 -17.419574) (xy 394.061545 -17.453656)
			(xy 393.94946 -17.519897) (xy 393.833547 -17.57918) (xy 393.714234 -17.631288) (xy 393.591967 -17.676024)
			(xy 393.4672 -17.713223) (xy 393.340397 -17.742747) (xy 393.21203 -17.764485) (xy 393.082577 -17.778358)
			(xy 392.952518 -17.784312) (xy 392.822339 -17.782327) (xy 392.692523 -17.772409) (xy 392.563553 -17.754595)
			(xy 392.435908 -17.728952) (xy 392.310065 -17.695575) (xy 392.18649 -17.654588) (xy 392.065644 -17.606144)
			(xy 391.947976 -17.550422) (xy 391.833924 -17.487631) (xy 391.723912 -17.418004) (xy 391.61835 -17.341799)
			(xy 391.51763 -17.2593) (xy 391.422126 -17.170815) (xy 391.332194 -17.076672) (xy 391.248169 -16.977221)
			(xy 391.170364 -16.872833) (xy 391.099067 -16.763896) (xy 391.034543 -16.650814) (xy 390.977034 -16.53401)
			(xy 390.926752 -16.413917) (xy 390.883886 -16.290981) (xy 390.848593 -16.165662) (xy 390.821007 -16.038423)
			(xy 390.801228 -15.90974) (xy 390.789332 -15.78009) (xy 390.785362 -15.649956) (xy 375.548997 -15.649956)
			(xy 375.540804 -15.657056) (xy 375.494962 -15.686519) (xy 375.445394 -15.709159) (xy 375.393109 -15.724514)
			(xy 375.339171 -15.732272) (xy 375.311924 -15.73276) (xy 375.285688 -15.732299) (xy 375.233712 -15.725106)
			(xy 375.183213 -15.710853) (xy 375.135146 -15.689809) (xy 375.090419 -15.662372) (xy 375.049878 -15.62906)
			(xy 375.031762 -15.610078) (xy 375.031508 -15.609824) (xy 375.023794 -15.60242) (xy 375.004096 -15.59416)
			(xy 374.993408 -15.593822) (xy 374.905524 -15.596108) (xy 374.885966 -15.605506) (xy 374.878854 -15.614142)
			(xy 374.86063 -15.635281) (xy 374.819094 -15.672558) (xy 374.772567 -15.703383) (xy 374.722044 -15.727096)
			(xy 374.668605 -15.743191) (xy 374.613389 -15.751325) (xy 374.585484 -15.75181) (xy 374.558234 -15.751319)
			(xy 374.504288 -15.743561) (xy 374.451995 -15.728204) (xy 374.40242 -15.705562) (xy 374.356572 -15.676096)
			(xy 374.315384 -15.640405) (xy 374.279695 -15.599215) (xy 374.25023 -15.553366) (xy 374.22759 -15.50379)
			(xy 374.212236 -15.451496) (xy 374.20448 -15.39755) (xy 369.03866 -15.39755) (xy 369.045692 -15.454906)
			(xy 369.05363 -15.584859) (xy 369.054126 -15.649956) (xy 369.05363 -15.715053) (xy 369.045692 -15.845006)
			(xy 369.029848 -15.974232) (xy 369.006154 -16.102253) (xy 368.9747 -16.228591) (xy 368.935602 -16.352776)
			(xy 368.889007 -16.474347) (xy 368.835086 -16.592851) (xy 368.774041 -16.707847) (xy 368.7061 -16.818908)
			(xy 368.631514 -16.92562) (xy 368.596285 -16.969994) (xy 388.048253 -16.969994) (xy 388.052258 -16.882086)
			(xy 388.064241 -16.794906) (xy 388.084101 -16.709177) (xy 388.111676 -16.625609) (xy 388.146735 -16.544895)
			(xy 388.188988 -16.467703) (xy 388.238086 -16.394674) (xy 388.293622 -16.326412) (xy 388.355134 -16.263482)
			(xy 388.422115 -16.206408) (xy 388.494008 -16.15566) (xy 388.570217 -16.11166) (xy 388.650112 -16.074773)
			(xy 388.733031 -16.045304) (xy 388.818286 -16.023497) (xy 388.90517 -16.009533) (xy 388.992964 -16.003527)
			(xy 389.080941 -16.005531) (xy 389.168371 -16.015526) (xy 389.25453 -16.03343) (xy 389.338704 -16.059094)
			(xy 389.420195 -16.092307) (xy 389.498329 -16.132793) (xy 389.572457 -16.180215) (xy 389.641965 -16.234182)
			(xy 389.706279 -16.294247) (xy 389.764863 -16.359911) (xy 389.817234 -16.43063) (xy 389.862957 -16.505818)
			(xy 389.901654 -16.584853) (xy 389.933003 -16.667079) (xy 389.956745 -16.751815) (xy 389.972683 -16.838359)
			(xy 389.980685 -16.925994) (xy 389.981186 -16.969994) (xy 389.980685 -17.013994) (xy 389.972683 -17.101629)
			(xy 389.956745 -17.188173) (xy 389.933003 -17.272909) (xy 389.901654 -17.355135) (xy 389.862957 -17.43417)
			(xy 389.817234 -17.509358) (xy 389.764863 -17.580077) (xy 389.706279 -17.645741) (xy 389.641965 -17.705806)
			(xy 389.572457 -17.759773) (xy 389.498329 -17.807195) (xy 389.420195 -17.847681) (xy 389.338704 -17.880894)
			(xy 389.25453 -17.906558) (xy 389.168371 -17.924462) (xy 389.080941 -17.934457) (xy 388.992964 -17.936461)
			(xy 388.90517 -17.930455) (xy 388.818286 -17.916491) (xy 388.733031 -17.894684) (xy 388.650112 -17.865215)
			(xy 388.570217 -17.828328) (xy 388.494008 -17.784328) (xy 388.422115 -17.73358) (xy 388.355134 -17.676506)
			(xy 388.293622 -17.613576) (xy 388.238086 -17.545314) (xy 388.188988 -17.472285) (xy 388.146735 -17.395093)
			(xy 388.111676 -17.314379) (xy 388.084101 -17.230811) (xy 388.064241 -17.145082) (xy 388.052258 -17.057902)
			(xy 388.048253 -16.969994) (xy 368.596285 -16.969994) (xy 368.550561 -17.027587) (xy 368.463542 -17.124429)
			(xy 368.370781 -17.215786) (xy 368.272623 -17.301318) (xy 368.169434 -17.380706) (xy 368.111978 -17.419574)
			(xy 372.584216 -17.419574) (xy 372.588287 -17.363952) (xy 372.600413 -17.309515) (xy 372.620336 -17.257424)
			(xy 372.647632 -17.208789) (xy 372.681718 -17.164646) (xy 372.721867 -17.125937) (xy 372.767225 -17.093486)
			(xy 372.816825 -17.067985) (xy 372.869609 -17.049978) (xy 372.924452 -17.039848) (xy 372.980186 -17.037811)
			(xy 373.035623 -17.043911) (xy 373.08958 -17.058017) (xy 373.140909 -17.079829) (xy 373.188515 -17.108883)
			(xy 373.231383 -17.144558) (xy 373.2686 -17.186095) (xy 373.299373 -17.232608) (xy 373.323045 -17.283105)
			(xy 373.339113 -17.336512) (xy 373.347233 -17.391688) (xy 373.347742 -17.419574) (xy 373.347233 -17.44746)
			(xy 373.339113 -17.502636) (xy 373.323045 -17.556043) (xy 373.299373 -17.60654) (xy 373.2686 -17.653053)
			(xy 373.231383 -17.69459) (xy 373.188515 -17.730265) (xy 373.140909 -17.759319) (xy 373.08958 -17.781131)
			(xy 373.035623 -17.795237) (xy 372.980186 -17.801337) (xy 372.924452 -17.7993) (xy 372.869609 -17.78917)
			(xy 372.816825 -17.771163) (xy 372.767225 -17.745662) (xy 372.721867 -17.713211) (xy 372.681718 -17.674502)
			(xy 372.647632 -17.630359) (xy 372.620336 -17.581724) (xy 372.600413 -17.529633) (xy 372.588287 -17.475196)
			(xy 372.584216 -17.419574) (xy 368.111978 -17.419574) (xy 368.061597 -17.453656) (xy 367.949512 -17.519897)
			(xy 367.833599 -17.57918) (xy 367.714286 -17.631288) (xy 367.592019 -17.676024) (xy 367.467252 -17.713223)
			(xy 367.340449 -17.742747) (xy 367.212082 -17.764485) (xy 367.082629 -17.778358) (xy 366.95257 -17.784312)
			(xy 366.822391 -17.782327) (xy 366.692575 -17.772409) (xy 366.563605 -17.754595) (xy 366.43596 -17.728952)
			(xy 366.310117 -17.695575) (xy 366.186542 -17.654588) (xy 366.065696 -17.606144) (xy 365.948028 -17.550422)
			(xy 365.833976 -17.487631) (xy 365.723964 -17.418004) (xy 365.618402 -17.341799) (xy 365.517682 -17.2593)
			(xy 365.422178 -17.170815) (xy 365.332246 -17.076672) (xy 365.248221 -16.977221) (xy 365.170416 -16.872833)
			(xy 365.099119 -16.763896) (xy 365.034595 -16.650814) (xy 364.977086 -16.53401) (xy 364.926804 -16.413917)
			(xy 364.883938 -16.290981) (xy 364.848645 -16.165662) (xy 364.821059 -16.038423) (xy 364.80128 -15.90974)
			(xy 364.789384 -15.78009) (xy 364.785414 -15.649956) (xy 330.954126 -15.649956) (xy 330.95363 -15.715053)
			(xy 330.945692 -15.845006) (xy 330.929848 -15.974232) (xy 330.906154 -16.102253) (xy 330.8747 -16.228591)
			(xy 330.835602 -16.352776) (xy 330.789007 -16.474347) (xy 330.735086 -16.592851) (xy 330.674041 -16.707847)
			(xy 330.6061 -16.818908) (xy 330.531514 -16.92562) (xy 330.496285 -16.969994) (xy 362.048305 -16.969994)
			(xy 362.05231 -16.882086) (xy 362.064293 -16.794906) (xy 362.084153 -16.709177) (xy 362.111728 -16.625609)
			(xy 362.146787 -16.544895) (xy 362.18904 -16.467703) (xy 362.238138 -16.394674) (xy 362.293674 -16.326412)
			(xy 362.355186 -16.263482) (xy 362.422167 -16.206408) (xy 362.49406 -16.15566) (xy 362.570269 -16.11166)
			(xy 362.650164 -16.074773) (xy 362.733083 -16.045304) (xy 362.818338 -16.023497) (xy 362.905222 -16.009533)
			(xy 362.993016 -16.003527) (xy 363.080993 -16.005531) (xy 363.168423 -16.015526) (xy 363.254582 -16.03343)
			(xy 363.338756 -16.059094) (xy 363.420247 -16.092307) (xy 363.498381 -16.132793) (xy 363.572509 -16.180215)
			(xy 363.642017 -16.234182) (xy 363.706331 -16.294247) (xy 363.764915 -16.359911) (xy 363.817286 -16.43063)
			(xy 363.863009 -16.505818) (xy 363.901706 -16.584853) (xy 363.933055 -16.667079) (xy 363.956797 -16.751815)
			(xy 363.972735 -16.838359) (xy 363.980737 -16.925994) (xy 363.981238 -16.969994) (xy 363.980737 -17.013994)
			(xy 363.972735 -17.101629) (xy 363.956797 -17.188173) (xy 363.933055 -17.272909) (xy 363.901706 -17.355135)
			(xy 363.863009 -17.43417) (xy 363.817286 -17.509358) (xy 363.764915 -17.580077) (xy 363.706331 -17.645741)
			(xy 363.642017 -17.705806) (xy 363.572509 -17.759773) (xy 363.498381 -17.807195) (xy 363.420247 -17.847681)
			(xy 363.338756 -17.880894) (xy 363.254582 -17.906558) (xy 363.168423 -17.924462) (xy 363.080993 -17.934457)
			(xy 362.993016 -17.936461) (xy 362.905222 -17.930455) (xy 362.818338 -17.916491) (xy 362.733083 -17.894684)
			(xy 362.650164 -17.865215) (xy 362.570269 -17.828328) (xy 362.49406 -17.784328) (xy 362.422167 -17.73358)
			(xy 362.355186 -17.676506) (xy 362.293674 -17.613576) (xy 362.238138 -17.545314) (xy 362.18904 -17.472285)
			(xy 362.146787 -17.395093) (xy 362.111728 -17.314379) (xy 362.084153 -17.230811) (xy 362.064293 -17.145082)
			(xy 362.05231 -17.057902) (xy 362.048305 -16.969994) (xy 330.496285 -16.969994) (xy 330.450561 -17.027587)
			(xy 330.363542 -17.124429) (xy 330.270781 -17.215786) (xy 330.172623 -17.301318) (xy 330.069434 -17.380706)
			(xy 329.961597 -17.453656) (xy 329.849512 -17.519897) (xy 329.733599 -17.57918) (xy 329.614286 -17.631288)
			(xy 329.492019 -17.676024) (xy 329.367252 -17.713223) (xy 329.240449 -17.742747) (xy 329.112082 -17.764485)
			(xy 328.982629 -17.778358) (xy 328.85257 -17.784312) (xy 328.722391 -17.782327) (xy 328.592575 -17.772409)
			(xy 328.463605 -17.754595) (xy 328.33596 -17.728952) (xy 328.210117 -17.695575) (xy 328.086542 -17.654588)
			(xy 327.965696 -17.606144) (xy 327.848028 -17.550422) (xy 327.733976 -17.487631) (xy 327.623964 -17.418004)
			(xy 327.518402 -17.341799) (xy 327.417682 -17.2593) (xy 327.322178 -17.170815) (xy 327.232246 -17.076672)
			(xy 327.148221 -16.977221) (xy 327.070416 -16.872833) (xy 326.999119 -16.763896) (xy 326.934595 -16.650814)
			(xy 326.877086 -16.53401) (xy 326.826804 -16.413917) (xy 326.783938 -16.290981) (xy 326.748645 -16.165662)
			(xy 326.721059 -16.038423) (xy 326.70128 -15.90974) (xy 326.689384 -15.78009) (xy 326.685414 -15.649956)
			(xy 311.448797 -15.649956) (xy 311.440603 -15.657057) (xy 311.394761 -15.68652) (xy 311.345193 -15.709159)
			(xy 311.292907 -15.724514) (xy 311.238969 -15.732272) (xy 311.211722 -15.73276) (xy 311.185486 -15.7323)
			(xy 311.13351 -15.725107) (xy 311.083011 -15.710854) (xy 311.034944 -15.68981) (xy 310.990217 -15.662372)
			(xy 310.949676 -15.62906) (xy 310.93156 -15.610078) (xy 310.931306 -15.609824) (xy 310.923593 -15.602419)
			(xy 310.903894 -15.59416) (xy 310.893206 -15.593822) (xy 310.805322 -15.596108) (xy 310.785764 -15.605506)
			(xy 310.778652 -15.614142) (xy 310.760429 -15.635282) (xy 310.718892 -15.672559) (xy 310.672366 -15.703384)
			(xy 310.621843 -15.727097) (xy 310.568403 -15.743192) (xy 310.513188 -15.751325) (xy 310.485282 -15.75181)
			(xy 310.458032 -15.751319) (xy 310.404086 -15.74356) (xy 310.351794 -15.728204) (xy 310.302219 -15.705562)
			(xy 310.256371 -15.676095) (xy 310.215183 -15.640404) (xy 310.179494 -15.599214) (xy 310.15003 -15.553365)
			(xy 310.12739 -15.503789) (xy 310.112036 -15.451496) (xy 310.10428 -15.39755) (xy 304.938712 -15.39755)
			(xy 304.945744 -15.454906) (xy 304.953682 -15.584859) (xy 304.954178 -15.649956) (xy 304.953682 -15.715053)
			(xy 304.945744 -15.845006) (xy 304.9299 -15.974232) (xy 304.906206 -16.102253) (xy 304.874752 -16.228591)
			(xy 304.835654 -16.352776) (xy 304.789059 -16.474347) (xy 304.735138 -16.592851) (xy 304.674093 -16.707847)
			(xy 304.606152 -16.818908) (xy 304.531566 -16.92562) (xy 304.496337 -16.969994) (xy 323.948051 -16.969994)
			(xy 323.952056 -16.882086) (xy 323.964039 -16.794906) (xy 323.983899 -16.709177) (xy 324.011474 -16.625609)
			(xy 324.046533 -16.544895) (xy 324.088786 -16.467703) (xy 324.137884 -16.394674) (xy 324.19342 -16.326412)
			(xy 324.254932 -16.263482) (xy 324.321913 -16.206408) (xy 324.393806 -16.15566) (xy 324.470015 -16.11166)
			(xy 324.54991 -16.074773) (xy 324.632829 -16.045304) (xy 324.718084 -16.023497) (xy 324.804968 -16.009533)
			(xy 324.892762 -16.003527) (xy 324.980739 -16.005531) (xy 325.068169 -16.015526) (xy 325.154328 -16.03343)
			(xy 325.238502 -16.059094) (xy 325.319993 -16.092307) (xy 325.398127 -16.132793) (xy 325.472255 -16.180215)
			(xy 325.541763 -16.234182) (xy 325.606077 -16.294247) (xy 325.664661 -16.359911) (xy 325.717032 -16.43063)
			(xy 325.762755 -16.505818) (xy 325.801452 -16.584853) (xy 325.832801 -16.667079) (xy 325.856543 -16.751815)
			(xy 325.872481 -16.838359) (xy 325.880483 -16.925994) (xy 325.880984 -16.969994) (xy 325.880483 -17.013994)
			(xy 325.872481 -17.101629) (xy 325.856543 -17.188173) (xy 325.832801 -17.272909) (xy 325.801452 -17.355135)
			(xy 325.762755 -17.43417) (xy 325.717032 -17.509358) (xy 325.664661 -17.580077) (xy 325.606077 -17.645741)
			(xy 325.541763 -17.705806) (xy 325.472255 -17.759773) (xy 325.398127 -17.807195) (xy 325.319993 -17.847681)
			(xy 325.238502 -17.880894) (xy 325.154328 -17.906558) (xy 325.068169 -17.924462) (xy 324.980739 -17.934457)
			(xy 324.892762 -17.936461) (xy 324.804968 -17.930455) (xy 324.718084 -17.916491) (xy 324.632829 -17.894684)
			(xy 324.54991 -17.865215) (xy 324.470015 -17.828328) (xy 324.393806 -17.784328) (xy 324.321913 -17.73358)
			(xy 324.254932 -17.676506) (xy 324.19342 -17.613576) (xy 324.137884 -17.545314) (xy 324.088786 -17.472285)
			(xy 324.046533 -17.395093) (xy 324.011474 -17.314379) (xy 323.983899 -17.230811) (xy 323.964039 -17.145082)
			(xy 323.952056 -17.057902) (xy 323.948051 -16.969994) (xy 304.496337 -16.969994) (xy 304.450613 -17.027587)
			(xy 304.363594 -17.124429) (xy 304.270833 -17.215786) (xy 304.172675 -17.301318) (xy 304.069486 -17.380706)
			(xy 304.01203 -17.419574) (xy 308.484014 -17.419574) (xy 308.488085 -17.363952) (xy 308.500211 -17.309515)
			(xy 308.520134 -17.257424) (xy 308.54743 -17.208789) (xy 308.581516 -17.164646) (xy 308.621665 -17.125937)
			(xy 308.667023 -17.093486) (xy 308.716623 -17.067985) (xy 308.769407 -17.049978) (xy 308.82425 -17.039848)
			(xy 308.879984 -17.037811) (xy 308.935421 -17.043911) (xy 308.989378 -17.058017) (xy 309.040707 -17.079829)
			(xy 309.088313 -17.108883) (xy 309.131181 -17.144558) (xy 309.168398 -17.186095) (xy 309.199171 -17.232608)
			(xy 309.222843 -17.283105) (xy 309.238911 -17.336512) (xy 309.247031 -17.391688) (xy 309.24754 -17.419574)
			(xy 309.247031 -17.44746) (xy 309.238911 -17.502636) (xy 309.222843 -17.556043) (xy 309.199171 -17.60654)
			(xy 309.168398 -17.653053) (xy 309.131181 -17.69459) (xy 309.088313 -17.730265) (xy 309.040707 -17.759319)
			(xy 308.989378 -17.781131) (xy 308.935421 -17.795237) (xy 308.879984 -17.801337) (xy 308.82425 -17.7993)
			(xy 308.769407 -17.78917) (xy 308.716623 -17.771163) (xy 308.667023 -17.745662) (xy 308.621665 -17.713211)
			(xy 308.581516 -17.674502) (xy 308.54743 -17.630359) (xy 308.520134 -17.581724) (xy 308.500211 -17.529633)
			(xy 308.488085 -17.475196) (xy 308.484014 -17.419574) (xy 304.01203 -17.419574) (xy 303.961649 -17.453656)
			(xy 303.849564 -17.519897) (xy 303.733651 -17.57918) (xy 303.614338 -17.631288) (xy 303.492071 -17.676024)
			(xy 303.367304 -17.713223) (xy 303.240501 -17.742747) (xy 303.112134 -17.764485) (xy 302.982681 -17.778358)
			(xy 302.852622 -17.784312) (xy 302.722443 -17.782327) (xy 302.592627 -17.772409) (xy 302.463657 -17.754595)
			(xy 302.336012 -17.728952) (xy 302.210169 -17.695575) (xy 302.086594 -17.654588) (xy 301.965748 -17.606144)
			(xy 301.84808 -17.550422) (xy 301.734028 -17.487631) (xy 301.624016 -17.418004) (xy 301.518454 -17.341799)
			(xy 301.417734 -17.2593) (xy 301.32223 -17.170815) (xy 301.232298 -17.076672) (xy 301.148273 -16.977221)
			(xy 301.070468 -16.872833) (xy 300.999171 -16.763896) (xy 300.934647 -16.650814) (xy 300.877138 -16.53401)
			(xy 300.826856 -16.413917) (xy 300.78399 -16.290981) (xy 300.748697 -16.165662) (xy 300.721111 -16.038423)
			(xy 300.701332 -15.90974) (xy 300.689436 -15.78009) (xy 300.685466 -15.649956) (xy 285.44893 -15.649956)
			(xy 285.440694 -15.657092) (xy 285.394843 -15.686556) (xy 285.345266 -15.709194) (xy 285.292972 -15.724546)
			(xy 285.239025 -15.732299) (xy 285.211774 -15.73276) (xy 285.185537 -15.732332) (xy 285.133559 -15.725133)
			(xy 285.08306 -15.710873) (xy 285.034993 -15.689823) (xy 284.990267 -15.66238) (xy 284.949727 -15.629063)
			(xy 284.931612 -15.610078) (xy 284.931358 -15.609824) (xy 284.923625 -15.602443) (xy 284.903942 -15.59417)
			(xy 284.893258 -15.593822) (xy 284.805374 -15.596108) (xy 284.785816 -15.605506) (xy 284.778704 -15.614142)
			(xy 284.760506 -15.635305) (xy 284.718965 -15.672581) (xy 284.672433 -15.703402) (xy 284.621905 -15.727111)
			(xy 284.56846 -15.743201) (xy 284.513241 -15.751328) (xy 284.485334 -15.75181) (xy 284.45808 -15.751345)
			(xy 284.404125 -15.743592) (xy 284.351824 -15.728239) (xy 284.30224 -15.705599) (xy 284.256382 -15.676132)
			(xy 284.215186 -15.640438) (xy 284.179489 -15.599245) (xy 284.150018 -15.55339) (xy 284.127373 -15.503808)
			(xy 284.112015 -15.451508) (xy 284.104257 -15.397554) (xy 278.938764 -15.397554) (xy 278.945796 -15.454906)
			(xy 278.953734 -15.584859) (xy 278.95423 -15.649956) (xy 278.953734 -15.715053) (xy 278.945796 -15.845006)
			(xy 278.929952 -15.974232) (xy 278.906258 -16.102253) (xy 278.874804 -16.228591) (xy 278.835706 -16.352776)
			(xy 278.789111 -16.474347) (xy 278.73519 -16.592851) (xy 278.674145 -16.707847) (xy 278.606204 -16.818908)
			(xy 278.531618 -16.92562) (xy 278.496389 -16.969994) (xy 297.948103 -16.969994) (xy 297.952108 -16.882086)
			(xy 297.964091 -16.794906) (xy 297.983951 -16.709177) (xy 298.011526 -16.625609) (xy 298.046585 -16.544895)
			(xy 298.088838 -16.467703) (xy 298.137936 -16.394674) (xy 298.193472 -16.326412) (xy 298.254984 -16.263482)
			(xy 298.321965 -16.206408) (xy 298.393858 -16.15566) (xy 298.470067 -16.11166) (xy 298.549962 -16.074773)
			(xy 298.632881 -16.045304) (xy 298.718136 -16.023497) (xy 298.80502 -16.009533) (xy 298.892814 -16.003527)
			(xy 298.980791 -16.005531) (xy 299.068221 -16.015526) (xy 299.15438 -16.03343) (xy 299.238554 -16.059094)
			(xy 299.320045 -16.092307) (xy 299.398179 -16.132793) (xy 299.472307 -16.180215) (xy 299.541815 -16.234182)
			(xy 299.606129 -16.294247) (xy 299.664713 -16.359911) (xy 299.717084 -16.43063) (xy 299.762807 -16.505818)
			(xy 299.801504 -16.584853) (xy 299.832853 -16.667079) (xy 299.856595 -16.751815) (xy 299.872533 -16.838359)
			(xy 299.880535 -16.925994) (xy 299.881036 -16.969994) (xy 299.880535 -17.013994) (xy 299.872533 -17.101629)
			(xy 299.856595 -17.188173) (xy 299.832853 -17.272909) (xy 299.801504 -17.355135) (xy 299.762807 -17.43417)
			(xy 299.717084 -17.509358) (xy 299.664713 -17.580077) (xy 299.606129 -17.645741) (xy 299.541815 -17.705806)
			(xy 299.472307 -17.759773) (xy 299.398179 -17.807195) (xy 299.320045 -17.847681) (xy 299.238554 -17.880894)
			(xy 299.15438 -17.906558) (xy 299.068221 -17.924462) (xy 298.980791 -17.934457) (xy 298.892814 -17.936461)
			(xy 298.80502 -17.930455) (xy 298.718136 -17.916491) (xy 298.632881 -17.894684) (xy 298.549962 -17.865215)
			(xy 298.470067 -17.828328) (xy 298.393858 -17.784328) (xy 298.321965 -17.73358) (xy 298.254984 -17.676506)
			(xy 298.193472 -17.613576) (xy 298.137936 -17.545314) (xy 298.088838 -17.472285) (xy 298.046585 -17.395093)
			(xy 298.011526 -17.314379) (xy 297.983951 -17.230811) (xy 297.964091 -17.145082) (xy 297.952108 -17.057902)
			(xy 297.948103 -16.969994) (xy 278.496389 -16.969994) (xy 278.450665 -17.027587) (xy 278.363646 -17.124429)
			(xy 278.270885 -17.215786) (xy 278.172727 -17.301318) (xy 278.069538 -17.380706) (xy 278.012082 -17.419574)
			(xy 282.484066 -17.419574) (xy 282.488137 -17.363952) (xy 282.500263 -17.309515) (xy 282.520186 -17.257424)
			(xy 282.547482 -17.208789) (xy 282.581568 -17.164646) (xy 282.621717 -17.125937) (xy 282.667075 -17.093486)
			(xy 282.716675 -17.067985) (xy 282.769459 -17.049978) (xy 282.824302 -17.039848) (xy 282.880036 -17.037811)
			(xy 282.935473 -17.043911) (xy 282.98943 -17.058017) (xy 283.040759 -17.079829) (xy 283.088365 -17.108883)
			(xy 283.131233 -17.144558) (xy 283.16845 -17.186095) (xy 283.199223 -17.232608) (xy 283.222895 -17.283105)
			(xy 283.238963 -17.336512) (xy 283.247083 -17.391688) (xy 283.247592 -17.419574) (xy 283.247083 -17.44746)
			(xy 283.238963 -17.502636) (xy 283.222895 -17.556043) (xy 283.199223 -17.60654) (xy 283.16845 -17.653053)
			(xy 283.131233 -17.69459) (xy 283.088365 -17.730265) (xy 283.040759 -17.759319) (xy 282.98943 -17.781131)
			(xy 282.935473 -17.795237) (xy 282.880036 -17.801337) (xy 282.824302 -17.7993) (xy 282.769459 -17.78917)
			(xy 282.716675 -17.771163) (xy 282.667075 -17.745662) (xy 282.621717 -17.713211) (xy 282.581568 -17.674502)
			(xy 282.547482 -17.630359) (xy 282.520186 -17.581724) (xy 282.500263 -17.529633) (xy 282.488137 -17.475196)
			(xy 282.484066 -17.419574) (xy 278.012082 -17.419574) (xy 277.961701 -17.453656) (xy 277.849616 -17.519897)
			(xy 277.733703 -17.57918) (xy 277.61439 -17.631288) (xy 277.492123 -17.676024) (xy 277.367356 -17.713223)
			(xy 277.240553 -17.742747) (xy 277.112186 -17.764485) (xy 276.982733 -17.778358) (xy 276.852674 -17.784312)
			(xy 276.722495 -17.782327) (xy 276.592679 -17.772409) (xy 276.463709 -17.754595) (xy 276.336064 -17.728952)
			(xy 276.210221 -17.695575) (xy 276.086646 -17.654588) (xy 275.9658 -17.606144) (xy 275.848132 -17.550422)
			(xy 275.73408 -17.487631) (xy 275.624068 -17.418004) (xy 275.518506 -17.341799) (xy 275.417786 -17.2593)
			(xy 275.322282 -17.170815) (xy 275.23235 -17.076672) (xy 275.148325 -16.977221) (xy 275.07052 -16.872833)
			(xy 274.999223 -16.763896) (xy 274.934699 -16.650814) (xy 274.87719 -16.53401) (xy 274.826908 -16.413917)
			(xy 274.784042 -16.290981) (xy 274.748749 -16.165662) (xy 274.721163 -16.038423) (xy 274.701384 -15.90974)
			(xy 274.689488 -15.78009) (xy 274.685518 -15.649956) (xy 259.448897 -15.649956) (xy 259.440705 -15.657055)
			(xy 259.394863 -15.686518) (xy 259.345296 -15.709158) (xy 259.293011 -15.724514) (xy 259.239073 -15.732272)
			(xy 259.211826 -15.73276) (xy 259.18559 -15.732298) (xy 259.133614 -15.725105) (xy 259.083115 -15.710852)
			(xy 259.035048 -15.689809) (xy 258.990321 -15.662372) (xy 258.94978 -15.62906) (xy 258.931664 -15.610078)
			(xy 258.93141 -15.609824) (xy 258.923695 -15.602421) (xy 258.903998 -15.59416) (xy 258.89331 -15.593822)
			(xy 258.805426 -15.596108) (xy 258.785868 -15.605506) (xy 258.778756 -15.614142) (xy 258.760531 -15.63528)
			(xy 258.718995 -15.672558) (xy 258.672469 -15.703382) (xy 258.621946 -15.727096) (xy 258.568506 -15.743191)
			(xy 258.513291 -15.751324) (xy 258.485386 -15.75181) (xy 258.458136 -15.751319) (xy 258.40419 -15.743561)
			(xy 258.351897 -15.728205) (xy 258.302322 -15.705563) (xy 258.256473 -15.676097) (xy 258.215285 -15.640405)
			(xy 258.179595 -15.599216) (xy 258.15013 -15.553366) (xy 258.12749 -15.50379) (xy 258.112136 -15.451497)
			(xy 258.10438 -15.39755) (xy 252.938562 -15.39755) (xy 252.945594 -15.454906) (xy 252.953532 -15.584859)
			(xy 252.954028 -15.649956) (xy 252.953532 -15.715053) (xy 252.945594 -15.845006) (xy 252.92975 -15.974232)
			(xy 252.906056 -16.102253) (xy 252.874602 -16.228591) (xy 252.835504 -16.352776) (xy 252.788909 -16.474347)
			(xy 252.734988 -16.592851) (xy 252.673943 -16.707847) (xy 252.606002 -16.818908) (xy 252.531416 -16.92562)
			(xy 252.496187 -16.969994) (xy 271.948155 -16.969994) (xy 271.95216 -16.882086) (xy 271.964143 -16.794906)
			(xy 271.984003 -16.709177) (xy 272.011578 -16.625609) (xy 272.046637 -16.544895) (xy 272.08889 -16.467703)
			(xy 272.137988 -16.394674) (xy 272.193524 -16.326412) (xy 272.255036 -16.263482) (xy 272.322017 -16.206408)
			(xy 272.39391 -16.15566) (xy 272.470119 -16.11166) (xy 272.550014 -16.074773) (xy 272.632933 -16.045304)
			(xy 272.718188 -16.023497) (xy 272.805072 -16.009533) (xy 272.892866 -16.003527) (xy 272.980843 -16.005531)
			(xy 273.068273 -16.015526) (xy 273.154432 -16.03343) (xy 273.238606 -16.059094) (xy 273.320097 -16.092307)
			(xy 273.398231 -16.132793) (xy 273.472359 -16.180215) (xy 273.541867 -16.234182) (xy 273.606181 -16.294247)
			(xy 273.664765 -16.359911) (xy 273.717136 -16.43063) (xy 273.762859 -16.505818) (xy 273.801556 -16.584853)
			(xy 273.832905 -16.667079) (xy 273.856647 -16.751815) (xy 273.872585 -16.838359) (xy 273.880587 -16.925994)
			(xy 273.881088 -16.969994) (xy 273.880587 -17.013994) (xy 273.872585 -17.101629) (xy 273.856647 -17.188173)
			(xy 273.832905 -17.272909) (xy 273.801556 -17.355135) (xy 273.762859 -17.43417) (xy 273.717136 -17.509358)
			(xy 273.664765 -17.580077) (xy 273.606181 -17.645741) (xy 273.541867 -17.705806) (xy 273.472359 -17.759773)
			(xy 273.398231 -17.807195) (xy 273.320097 -17.847681) (xy 273.238606 -17.880894) (xy 273.154432 -17.906558)
			(xy 273.068273 -17.924462) (xy 272.980843 -17.934457) (xy 272.892866 -17.936461) (xy 272.805072 -17.930455)
			(xy 272.718188 -17.916491) (xy 272.632933 -17.894684) (xy 272.550014 -17.865215) (xy 272.470119 -17.828328)
			(xy 272.39391 -17.784328) (xy 272.322017 -17.73358) (xy 272.255036 -17.676506) (xy 272.193524 -17.613576)
			(xy 272.137988 -17.545314) (xy 272.08889 -17.472285) (xy 272.046637 -17.395093) (xy 272.011578 -17.314379)
			(xy 271.984003 -17.230811) (xy 271.964143 -17.145082) (xy 271.95216 -17.057902) (xy 271.948155 -16.969994)
			(xy 252.496187 -16.969994) (xy 252.450463 -17.027587) (xy 252.363444 -17.124429) (xy 252.270683 -17.215786)
			(xy 252.172525 -17.301318) (xy 252.069336 -17.380706) (xy 252.01188 -17.419574) (xy 256.484118 -17.419574)
			(xy 256.488189 -17.363952) (xy 256.500315 -17.309515) (xy 256.520238 -17.257424) (xy 256.547534 -17.208789)
			(xy 256.58162 -17.164646) (xy 256.621769 -17.125937) (xy 256.667127 -17.093486) (xy 256.716727 -17.067985)
			(xy 256.769511 -17.049978) (xy 256.824354 -17.039848) (xy 256.880088 -17.037811) (xy 256.935525 -17.043911)
			(xy 256.989482 -17.058017) (xy 257.040811 -17.079829) (xy 257.088417 -17.108883) (xy 257.131285 -17.144558)
			(xy 257.168502 -17.186095) (xy 257.199275 -17.232608) (xy 257.222947 -17.283105) (xy 257.239015 -17.336512)
			(xy 257.247135 -17.391688) (xy 257.247644 -17.419574) (xy 257.247135 -17.44746) (xy 257.239015 -17.502636)
			(xy 257.222947 -17.556043) (xy 257.199275 -17.60654) (xy 257.168502 -17.653053) (xy 257.131285 -17.69459)
			(xy 257.088417 -17.730265) (xy 257.040811 -17.759319) (xy 256.989482 -17.781131) (xy 256.935525 -17.795237)
			(xy 256.880088 -17.801337) (xy 256.824354 -17.7993) (xy 256.769511 -17.78917) (xy 256.716727 -17.771163)
			(xy 256.667127 -17.745662) (xy 256.621769 -17.713211) (xy 256.58162 -17.674502) (xy 256.547534 -17.630359)
			(xy 256.520238 -17.581724) (xy 256.500315 -17.529633) (xy 256.488189 -17.475196) (xy 256.484118 -17.419574)
			(xy 252.01188 -17.419574) (xy 251.961499 -17.453656) (xy 251.849414 -17.519897) (xy 251.733501 -17.57918)
			(xy 251.614188 -17.631288) (xy 251.491921 -17.676024) (xy 251.367154 -17.713223) (xy 251.240351 -17.742747)
			(xy 251.111984 -17.764485) (xy 250.982531 -17.778358) (xy 250.852472 -17.784312) (xy 250.722293 -17.782327)
			(xy 250.592477 -17.772409) (xy 250.463507 -17.754595) (xy 250.335862 -17.728952) (xy 250.210019 -17.695575)
			(xy 250.086444 -17.654588) (xy 249.965598 -17.606144) (xy 249.84793 -17.550422) (xy 249.733878 -17.487631)
			(xy 249.623866 -17.418004) (xy 249.518304 -17.341799) (xy 249.417584 -17.2593) (xy 249.32208 -17.170815)
			(xy 249.232148 -17.076672) (xy 249.148123 -16.977221) (xy 249.070318 -16.872833) (xy 248.999021 -16.763896)
			(xy 248.934497 -16.650814) (xy 248.876988 -16.53401) (xy 248.826706 -16.413917) (xy 248.78384 -16.290981)
			(xy 248.748547 -16.165662) (xy 248.720961 -16.038423) (xy 248.701182 -15.90974) (xy 248.689286 -15.78009)
			(xy 248.685316 -15.649956) (xy 221.348897 -15.649956) (xy 221.340705 -15.657055) (xy 221.294863 -15.686518)
			(xy 221.245296 -15.709158) (xy 221.193011 -15.724514) (xy 221.139073 -15.732272) (xy 221.111826 -15.73276)
			(xy 221.08559 -15.732298) (xy 221.033614 -15.725105) (xy 220.983115 -15.710852) (xy 220.935048 -15.689809)
			(xy 220.890321 -15.662372) (xy 220.84978 -15.62906) (xy 220.831664 -15.610078) (xy 220.83141 -15.609824)
			(xy 220.823695 -15.602421) (xy 220.803998 -15.59416) (xy 220.79331 -15.593822) (xy 220.705426 -15.596108)
			(xy 220.685868 -15.605506) (xy 220.678756 -15.614142) (xy 220.660531 -15.63528) (xy 220.618995 -15.672558)
			(xy 220.572469 -15.703382) (xy 220.521946 -15.727096) (xy 220.468506 -15.743191) (xy 220.413291 -15.751324)
			(xy 220.385386 -15.75181) (xy 220.358136 -15.751319) (xy 220.30419 -15.743561) (xy 220.251897 -15.728205)
			(xy 220.202322 -15.705563) (xy 220.156473 -15.676097) (xy 220.115285 -15.640405) (xy 220.079595 -15.599216)
			(xy 220.05013 -15.553366) (xy 220.02749 -15.50379) (xy 220.012136 -15.451497) (xy 220.00438 -15.39755)
			(xy 214.838562 -15.39755) (xy 214.845594 -15.454906) (xy 214.853532 -15.584859) (xy 214.854028 -15.649956)
			(xy 214.853532 -15.715053) (xy 214.845594 -15.845006) (xy 214.82975 -15.974232) (xy 214.806056 -16.102253)
			(xy 214.774602 -16.228591) (xy 214.735504 -16.352776) (xy 214.688909 -16.474347) (xy 214.634988 -16.592851)
			(xy 214.573943 -16.707847) (xy 214.506002 -16.818908) (xy 214.431416 -16.92562) (xy 214.396187 -16.969994)
			(xy 245.948207 -16.969994) (xy 245.952212 -16.882086) (xy 245.964195 -16.794906) (xy 245.984055 -16.709177)
			(xy 246.01163 -16.625609) (xy 246.046689 -16.544895) (xy 246.088942 -16.467703) (xy 246.13804 -16.394674)
			(xy 246.193576 -16.326412) (xy 246.255088 -16.263482) (xy 246.322069 -16.206408) (xy 246.393962 -16.15566)
			(xy 246.470171 -16.11166) (xy 246.550066 -16.074773) (xy 246.632985 -16.045304) (xy 246.71824 -16.023497)
			(xy 246.805124 -16.009533) (xy 246.892918 -16.003527) (xy 246.980895 -16.005531) (xy 247.068325 -16.015526)
			(xy 247.154484 -16.03343) (xy 247.238658 -16.059094) (xy 247.320149 -16.092307) (xy 247.398283 -16.132793)
			(xy 247.472411 -16.180215) (xy 247.541919 -16.234182) (xy 247.606233 -16.294247) (xy 247.664817 -16.359911)
			(xy 247.717188 -16.43063) (xy 247.762911 -16.505818) (xy 247.801608 -16.584853) (xy 247.832957 -16.667079)
			(xy 247.856699 -16.751815) (xy 247.872637 -16.838359) (xy 247.880639 -16.925994) (xy 247.88114 -16.969994)
			(xy 247.880639 -17.013994) (xy 247.872637 -17.101629) (xy 247.856699 -17.188173) (xy 247.832957 -17.272909)
			(xy 247.801608 -17.355135) (xy 247.762911 -17.43417) (xy 247.717188 -17.509358) (xy 247.664817 -17.580077)
			(xy 247.606233 -17.645741) (xy 247.541919 -17.705806) (xy 247.472411 -17.759773) (xy 247.398283 -17.807195)
			(xy 247.320149 -17.847681) (xy 247.238658 -17.880894) (xy 247.154484 -17.906558) (xy 247.068325 -17.924462)
			(xy 246.980895 -17.934457) (xy 246.892918 -17.936461) (xy 246.805124 -17.930455) (xy 246.71824 -17.916491)
			(xy 246.632985 -17.894684) (xy 246.550066 -17.865215) (xy 246.470171 -17.828328) (xy 246.393962 -17.784328)
			(xy 246.322069 -17.73358) (xy 246.255088 -17.676506) (xy 246.193576 -17.613576) (xy 246.13804 -17.545314)
			(xy 246.088942 -17.472285) (xy 246.046689 -17.395093) (xy 246.01163 -17.314379) (xy 245.984055 -17.230811)
			(xy 245.964195 -17.145082) (xy 245.952212 -17.057902) (xy 245.948207 -16.969994) (xy 214.396187 -16.969994)
			(xy 214.350463 -17.027587) (xy 214.263444 -17.124429) (xy 214.170683 -17.215786) (xy 214.072525 -17.301318)
			(xy 213.969336 -17.380706) (xy 213.91188 -17.419574) (xy 218.384118 -17.419574) (xy 218.388189 -17.363952)
			(xy 218.400315 -17.309515) (xy 218.420238 -17.257424) (xy 218.447534 -17.208789) (xy 218.48162 -17.164646)
			(xy 218.521769 -17.125937) (xy 218.567127 -17.093486) (xy 218.616727 -17.067985) (xy 218.669511 -17.049978)
			(xy 218.724354 -17.039848) (xy 218.780088 -17.037811) (xy 218.835525 -17.043911) (xy 218.889482 -17.058017)
			(xy 218.940811 -17.079829) (xy 218.988417 -17.108883) (xy 219.031285 -17.144558) (xy 219.068502 -17.186095)
			(xy 219.099275 -17.232608) (xy 219.122947 -17.283105) (xy 219.139015 -17.336512) (xy 219.147135 -17.391688)
			(xy 219.147644 -17.419574) (xy 219.147135 -17.44746) (xy 219.139015 -17.502636) (xy 219.122947 -17.556043)
			(xy 219.099275 -17.60654) (xy 219.068502 -17.653053) (xy 219.031285 -17.69459) (xy 218.988417 -17.730265)
			(xy 218.940811 -17.759319) (xy 218.889482 -17.781131) (xy 218.835525 -17.795237) (xy 218.780088 -17.801337)
			(xy 218.724354 -17.7993) (xy 218.669511 -17.78917) (xy 218.616727 -17.771163) (xy 218.567127 -17.745662)
			(xy 218.521769 -17.713211) (xy 218.48162 -17.674502) (xy 218.447534 -17.630359) (xy 218.420238 -17.581724)
			(xy 218.400315 -17.529633) (xy 218.388189 -17.475196) (xy 218.384118 -17.419574) (xy 213.91188 -17.419574)
			(xy 213.861499 -17.453656) (xy 213.749414 -17.519897) (xy 213.633501 -17.57918) (xy 213.514188 -17.631288)
			(xy 213.391921 -17.676024) (xy 213.267154 -17.713223) (xy 213.140351 -17.742747) (xy 213.011984 -17.764485)
			(xy 212.882531 -17.778358) (xy 212.752472 -17.784312) (xy 212.622293 -17.782327) (xy 212.492477 -17.772409)
			(xy 212.363507 -17.754595) (xy 212.235862 -17.728952) (xy 212.110019 -17.695575) (xy 211.986444 -17.654588)
			(xy 211.865598 -17.606144) (xy 211.74793 -17.550422) (xy 211.633878 -17.487631) (xy 211.523866 -17.418004)
			(xy 211.418304 -17.341799) (xy 211.317584 -17.2593) (xy 211.22208 -17.170815) (xy 211.132148 -17.076672)
			(xy 211.048123 -16.977221) (xy 210.970318 -16.872833) (xy 210.899021 -16.763896) (xy 210.834497 -16.650814)
			(xy 210.776988 -16.53401) (xy 210.726706 -16.413917) (xy 210.68384 -16.290981) (xy 210.648547 -16.165662)
			(xy 210.620961 -16.038423) (xy 210.601182 -15.90974) (xy 210.589286 -15.78009) (xy 210.585316 -15.649956)
			(xy 195.349031 -15.649956) (xy 195.340796 -15.657091) (xy 195.294946 -15.686554) (xy 195.245369 -15.709193)
			(xy 195.193075 -15.724545) (xy 195.139128 -15.732298) (xy 195.111878 -15.73276) (xy 195.085641 -15.73233)
			(xy 195.033663 -15.725131) (xy 194.983164 -15.710872) (xy 194.935097 -15.689822) (xy 194.890371 -15.662379)
			(xy 194.849831 -15.629062) (xy 194.831716 -15.610078) (xy 194.831462 -15.609824) (xy 194.823728 -15.602445)
			(xy 194.804046 -15.594171) (xy 194.793362 -15.593822) (xy 194.705478 -15.596108) (xy 194.68592 -15.605506)
			(xy 194.678808 -15.614142) (xy 194.660608 -15.635303) (xy 194.619067 -15.672579) (xy 194.572535 -15.703401)
			(xy 194.522008 -15.72711) (xy 194.468564 -15.7432) (xy 194.413345 -15.751328) (xy 194.385438 -15.75181)
			(xy 194.358184 -15.751345) (xy 194.304229 -15.743593) (xy 194.251927 -15.72824) (xy 194.202342 -15.7056)
			(xy 194.156484 -15.676133) (xy 194.115287 -15.64044) (xy 194.07959 -15.599246) (xy 194.050118 -15.553391)
			(xy 194.027473 -15.503809) (xy 194.012115 -15.451508) (xy 194.004357 -15.397554) (xy 188.838614 -15.397554)
			(xy 188.845646 -15.454906) (xy 188.853584 -15.584859) (xy 188.85408 -15.649956) (xy 188.853584 -15.715053)
			(xy 188.845646 -15.845006) (xy 188.829802 -15.974232) (xy 188.806108 -16.102253) (xy 188.774654 -16.228591)
			(xy 188.735556 -16.352776) (xy 188.688961 -16.474347) (xy 188.63504 -16.592851) (xy 188.573995 -16.707847)
			(xy 188.506054 -16.818908) (xy 188.431468 -16.92562) (xy 188.396239 -16.969994) (xy 207.848207 -16.969994)
			(xy 207.852212 -16.882086) (xy 207.864195 -16.794906) (xy 207.884055 -16.709177) (xy 207.91163 -16.625609)
			(xy 207.946689 -16.544895) (xy 207.988942 -16.467703) (xy 208.03804 -16.394674) (xy 208.093576 -16.326412)
			(xy 208.155088 -16.263482) (xy 208.222069 -16.206408) (xy 208.293962 -16.15566) (xy 208.370171 -16.11166)
			(xy 208.450066 -16.074773) (xy 208.532985 -16.045304) (xy 208.61824 -16.023497) (xy 208.705124 -16.009533)
			(xy 208.792918 -16.003527) (xy 208.880895 -16.005531) (xy 208.968325 -16.015526) (xy 209.054484 -16.03343)
			(xy 209.138658 -16.059094) (xy 209.220149 -16.092307) (xy 209.298283 -16.132793) (xy 209.372411 -16.180215)
			(xy 209.441919 -16.234182) (xy 209.506233 -16.294247) (xy 209.564817 -16.359911) (xy 209.617188 -16.43063)
			(xy 209.662911 -16.505818) (xy 209.701608 -16.584853) (xy 209.732957 -16.667079) (xy 209.756699 -16.751815)
			(xy 209.772637 -16.838359) (xy 209.780639 -16.925994) (xy 209.78114 -16.969994) (xy 209.780639 -17.013994)
			(xy 209.772637 -17.101629) (xy 209.756699 -17.188173) (xy 209.732957 -17.272909) (xy 209.701608 -17.355135)
			(xy 209.662911 -17.43417) (xy 209.617188 -17.509358) (xy 209.564817 -17.580077) (xy 209.506233 -17.645741)
			(xy 209.441919 -17.705806) (xy 209.372411 -17.759773) (xy 209.298283 -17.807195) (xy 209.220149 -17.847681)
			(xy 209.138658 -17.880894) (xy 209.054484 -17.906558) (xy 208.968325 -17.924462) (xy 208.880895 -17.934457)
			(xy 208.792918 -17.936461) (xy 208.705124 -17.930455) (xy 208.61824 -17.916491) (xy 208.532985 -17.894684)
			(xy 208.450066 -17.865215) (xy 208.370171 -17.828328) (xy 208.293962 -17.784328) (xy 208.222069 -17.73358)
			(xy 208.155088 -17.676506) (xy 208.093576 -17.613576) (xy 208.03804 -17.545314) (xy 207.988942 -17.472285)
			(xy 207.946689 -17.395093) (xy 207.91163 -17.314379) (xy 207.884055 -17.230811) (xy 207.864195 -17.145082)
			(xy 207.852212 -17.057902) (xy 207.848207 -16.969994) (xy 188.396239 -16.969994) (xy 188.350515 -17.027587)
			(xy 188.263496 -17.124429) (xy 188.170735 -17.215786) (xy 188.072577 -17.301318) (xy 187.969388 -17.380706)
			(xy 187.911932 -17.419574) (xy 192.38417 -17.419574) (xy 192.388241 -17.363952) (xy 192.400367 -17.309515)
			(xy 192.42029 -17.257424) (xy 192.447586 -17.208789) (xy 192.481672 -17.164646) (xy 192.521821 -17.125937)
			(xy 192.567179 -17.093486) (xy 192.616779 -17.067985) (xy 192.669563 -17.049978) (xy 192.724406 -17.039848)
			(xy 192.78014 -17.037811) (xy 192.835577 -17.043911) (xy 192.889534 -17.058017) (xy 192.940863 -17.079829)
			(xy 192.988469 -17.108883) (xy 193.031337 -17.144558) (xy 193.068554 -17.186095) (xy 193.099327 -17.232608)
			(xy 193.122999 -17.283105) (xy 193.139067 -17.336512) (xy 193.147187 -17.391688) (xy 193.147696 -17.419574)
			(xy 193.147187 -17.44746) (xy 193.139067 -17.502636) (xy 193.122999 -17.556043) (xy 193.099327 -17.60654)
			(xy 193.068554 -17.653053) (xy 193.031337 -17.69459) (xy 192.988469 -17.730265) (xy 192.940863 -17.759319)
			(xy 192.889534 -17.781131) (xy 192.835577 -17.795237) (xy 192.78014 -17.801337) (xy 192.724406 -17.7993)
			(xy 192.669563 -17.78917) (xy 192.616779 -17.771163) (xy 192.567179 -17.745662) (xy 192.521821 -17.713211)
			(xy 192.481672 -17.674502) (xy 192.447586 -17.630359) (xy 192.42029 -17.581724) (xy 192.400367 -17.529633)
			(xy 192.388241 -17.475196) (xy 192.38417 -17.419574) (xy 187.911932 -17.419574) (xy 187.861551 -17.453656)
			(xy 187.749466 -17.519897) (xy 187.633553 -17.57918) (xy 187.51424 -17.631288) (xy 187.391973 -17.676024)
			(xy 187.267206 -17.713223) (xy 187.140403 -17.742747) (xy 187.012036 -17.764485) (xy 186.882583 -17.778358)
			(xy 186.752524 -17.784312) (xy 186.622345 -17.782327) (xy 186.492529 -17.772409) (xy 186.363559 -17.754595)
			(xy 186.235914 -17.728952) (xy 186.110071 -17.695575) (xy 185.986496 -17.654588) (xy 185.86565 -17.606144)
			(xy 185.747982 -17.550422) (xy 185.63393 -17.487631) (xy 185.523918 -17.418004) (xy 185.418356 -17.341799)
			(xy 185.317636 -17.2593) (xy 185.222132 -17.170815) (xy 185.1322 -17.076672) (xy 185.048175 -16.977221)
			(xy 184.97037 -16.872833) (xy 184.899073 -16.763896) (xy 184.834549 -16.650814) (xy 184.77704 -16.53401)
			(xy 184.726758 -16.413917) (xy 184.683892 -16.290981) (xy 184.648599 -16.165662) (xy 184.621013 -16.038423)
			(xy 184.601234 -15.90974) (xy 184.589338 -15.78009) (xy 184.585368 -15.649956) (xy 169.348998 -15.649956)
			(xy 169.340807 -15.657054) (xy 169.294966 -15.686517) (xy 169.245399 -15.709157) (xy 169.193114 -15.724513)
			(xy 169.139176 -15.732272) (xy 169.11193 -15.73276) (xy 169.085692 -15.732362) (xy 169.033713 -15.725156)
			(xy 168.983213 -15.710891) (xy 168.935146 -15.689835) (xy 168.890421 -15.662387) (xy 168.849882 -15.629065)
			(xy 168.831768 -15.610078) (xy 168.831514 -15.609824) (xy 168.823798 -15.602423) (xy 168.804102 -15.594161)
			(xy 168.793414 -15.593822) (xy 168.70553 -15.596108) (xy 168.685972 -15.605506) (xy 168.67886 -15.614142)
			(xy 168.660632 -15.635278) (xy 168.619097 -15.672556) (xy 168.572571 -15.703381) (xy 168.522049 -15.727094)
			(xy 168.46861 -15.74319) (xy 168.413395 -15.751324) (xy 168.38549 -15.75181) (xy 168.358239 -15.75132)
			(xy 168.304293 -15.743562) (xy 168.252 -15.728206) (xy 168.202424 -15.705564) (xy 168.156575 -15.676098)
			(xy 168.115386 -15.640407) (xy 168.079696 -15.599217) (xy 168.050231 -15.553367) (xy 168.02759 -15.503791)
			(xy 168.012236 -15.451497) (xy 168.00448 -15.397551) (xy 162.838666 -15.397551) (xy 162.845698 -15.454906)
			(xy 162.853636 -15.584859) (xy 162.854132 -15.649956) (xy 162.853636 -15.715053) (xy 162.845698 -15.845006)
			(xy 162.829854 -15.974232) (xy 162.80616 -16.102253) (xy 162.774706 -16.228591) (xy 162.735608 -16.352776)
			(xy 162.689013 -16.474347) (xy 162.635092 -16.592851) (xy 162.574047 -16.707847) (xy 162.506106 -16.818908)
			(xy 162.43152 -16.92562) (xy 162.396291 -16.969994) (xy 181.848259 -16.969994) (xy 181.852264 -16.882086)
			(xy 181.864247 -16.794906) (xy 181.884107 -16.709177) (xy 181.911682 -16.625609) (xy 181.946741 -16.544895)
			(xy 181.988994 -16.467703) (xy 182.038092 -16.394674) (xy 182.093628 -16.326412) (xy 182.15514 -16.263482)
			(xy 182.222121 -16.206408) (xy 182.294014 -16.15566) (xy 182.370223 -16.11166) (xy 182.450118 -16.074773)
			(xy 182.533037 -16.045304) (xy 182.618292 -16.023497) (xy 182.705176 -16.009533) (xy 182.79297 -16.003527)
			(xy 182.880947 -16.005531) (xy 182.968377 -16.015526) (xy 183.054536 -16.03343) (xy 183.13871 -16.059094)
			(xy 183.220201 -16.092307) (xy 183.298335 -16.132793) (xy 183.372463 -16.180215) (xy 183.441971 -16.234182)
			(xy 183.506285 -16.294247) (xy 183.564869 -16.359911) (xy 183.61724 -16.43063) (xy 183.662963 -16.505818)
			(xy 183.70166 -16.584853) (xy 183.733009 -16.667079) (xy 183.756751 -16.751815) (xy 183.772689 -16.838359)
			(xy 183.780691 -16.925994) (xy 183.781192 -16.969994) (xy 183.780691 -17.013994) (xy 183.772689 -17.101629)
			(xy 183.756751 -17.188173) (xy 183.733009 -17.272909) (xy 183.70166 -17.355135) (xy 183.662963 -17.43417)
			(xy 183.61724 -17.509358) (xy 183.564869 -17.580077) (xy 183.506285 -17.645741) (xy 183.441971 -17.705806)
			(xy 183.372463 -17.759773) (xy 183.298335 -17.807195) (xy 183.220201 -17.847681) (xy 183.13871 -17.880894)
			(xy 183.054536 -17.906558) (xy 182.968377 -17.924462) (xy 182.880947 -17.934457) (xy 182.79297 -17.936461)
			(xy 182.705176 -17.930455) (xy 182.618292 -17.916491) (xy 182.533037 -17.894684) (xy 182.450118 -17.865215)
			(xy 182.370223 -17.828328) (xy 182.294014 -17.784328) (xy 182.222121 -17.73358) (xy 182.15514 -17.676506)
			(xy 182.093628 -17.613576) (xy 182.038092 -17.545314) (xy 181.988994 -17.472285) (xy 181.946741 -17.395093)
			(xy 181.911682 -17.314379) (xy 181.884107 -17.230811) (xy 181.864247 -17.145082) (xy 181.852264 -17.057902)
			(xy 181.848259 -16.969994) (xy 162.396291 -16.969994) (xy 162.350567 -17.027587) (xy 162.263548 -17.124429)
			(xy 162.170787 -17.215786) (xy 162.072629 -17.301318) (xy 161.96944 -17.380706) (xy 161.911984 -17.419574)
			(xy 166.384222 -17.419574) (xy 166.388293 -17.363952) (xy 166.400419 -17.309515) (xy 166.420342 -17.257424)
			(xy 166.447638 -17.208789) (xy 166.481724 -17.164646) (xy 166.521873 -17.125937) (xy 166.567231 -17.093486)
			(xy 166.616831 -17.067985) (xy 166.669615 -17.049978) (xy 166.724458 -17.039848) (xy 166.780192 -17.037811)
			(xy 166.835629 -17.043911) (xy 166.889586 -17.058017) (xy 166.940915 -17.079829) (xy 166.988521 -17.108883)
			(xy 167.031389 -17.144558) (xy 167.068606 -17.186095) (xy 167.099379 -17.232608) (xy 167.123051 -17.283105)
			(xy 167.139119 -17.336512) (xy 167.147239 -17.391688) (xy 167.147748 -17.419574) (xy 167.147239 -17.44746)
			(xy 167.139119 -17.502636) (xy 167.123051 -17.556043) (xy 167.099379 -17.60654) (xy 167.068606 -17.653053)
			(xy 167.031389 -17.69459) (xy 166.988521 -17.730265) (xy 166.940915 -17.759319) (xy 166.889586 -17.781131)
			(xy 166.835629 -17.795237) (xy 166.780192 -17.801337) (xy 166.724458 -17.7993) (xy 166.669615 -17.78917)
			(xy 166.616831 -17.771163) (xy 166.567231 -17.745662) (xy 166.521873 -17.713211) (xy 166.481724 -17.674502)
			(xy 166.447638 -17.630359) (xy 166.420342 -17.581724) (xy 166.400419 -17.529633) (xy 166.388293 -17.475196)
			(xy 166.384222 -17.419574) (xy 161.911984 -17.419574) (xy 161.861603 -17.453656) (xy 161.749518 -17.519897)
			(xy 161.633605 -17.57918) (xy 161.514292 -17.631288) (xy 161.392025 -17.676024) (xy 161.267258 -17.713223)
			(xy 161.140455 -17.742747) (xy 161.012088 -17.764485) (xy 160.882635 -17.778358) (xy 160.752576 -17.784312)
			(xy 160.622397 -17.782327) (xy 160.492581 -17.772409) (xy 160.363611 -17.754595) (xy 160.235966 -17.728952)
			(xy 160.110123 -17.695575) (xy 159.986548 -17.654588) (xy 159.865702 -17.606144) (xy 159.748034 -17.550422)
			(xy 159.633982 -17.487631) (xy 159.52397 -17.418004) (xy 159.418408 -17.341799) (xy 159.317688 -17.2593)
			(xy 159.222184 -17.170815) (xy 159.132252 -17.076672) (xy 159.048227 -16.977221) (xy 158.970422 -16.872833)
			(xy 158.899125 -16.763896) (xy 158.834601 -16.650814) (xy 158.777092 -16.53401) (xy 158.72681 -16.413917)
			(xy 158.683944 -16.290981) (xy 158.648651 -16.165662) (xy 158.621065 -16.038423) (xy 158.601286 -15.90974)
			(xy 158.58939 -15.78009) (xy 158.58542 -15.649956) (xy 143.34913 -15.649956) (xy 143.340898 -15.657089)
			(xy 143.295048 -15.686553) (xy 143.245472 -15.709192) (xy 143.193178 -15.724544) (xy 143.139232 -15.732298)
			(xy 143.111982 -15.73276) (xy 143.085745 -15.732327) (xy 143.033768 -15.725129) (xy 142.983268 -15.71087)
			(xy 142.935202 -15.689821) (xy 142.890475 -15.662379) (xy 142.849935 -15.629062) (xy 142.83182 -15.610078)
			(xy 142.831566 -15.609824) (xy 142.82383 -15.602446) (xy 142.804149 -15.594171) (xy 142.793466 -15.593822)
			(xy 142.705582 -15.596108) (xy 142.686024 -15.605506) (xy 142.678912 -15.614142) (xy 142.66071 -15.635301)
			(xy 142.619169 -15.672577) (xy 142.572638 -15.703399) (xy 142.522111 -15.727109) (xy 142.468667 -15.7432)
			(xy 142.413449 -15.751328) (xy 142.385542 -15.75181) (xy 142.358287 -15.751346) (xy 142.304332 -15.743593)
			(xy 142.25203 -15.728241) (xy 142.202444 -15.705601) (xy 142.156586 -15.676134) (xy 142.115389 -15.640441)
			(xy 142.079691 -15.599247) (xy 142.050219 -15.553393) (xy 142.027574 -15.50381) (xy 142.012215 -15.451509)
			(xy 142.004457 -15.397555) (xy 136.838718 -15.397555) (xy 136.84575 -15.454906) (xy 136.853688 -15.584859)
			(xy 136.854184 -15.649956) (xy 136.853688 -15.715053) (xy 136.84575 -15.845006) (xy 136.829906 -15.974232)
			(xy 136.806212 -16.102253) (xy 136.774758 -16.228591) (xy 136.73566 -16.352776) (xy 136.689065 -16.474347)
			(xy 136.635144 -16.592851) (xy 136.574099 -16.707847) (xy 136.506158 -16.818908) (xy 136.431572 -16.92562)
			(xy 136.396343 -16.969994) (xy 155.848311 -16.969994) (xy 155.852316 -16.882086) (xy 155.864299 -16.794906)
			(xy 155.884159 -16.709177) (xy 155.911734 -16.625609) (xy 155.946793 -16.544895) (xy 155.989046 -16.467703)
			(xy 156.038144 -16.394674) (xy 156.09368 -16.326412) (xy 156.155192 -16.263482) (xy 156.222173 -16.206408)
			(xy 156.294066 -16.15566) (xy 156.370275 -16.11166) (xy 156.45017 -16.074773) (xy 156.533089 -16.045304)
			(xy 156.618344 -16.023497) (xy 156.705228 -16.009533) (xy 156.793022 -16.003527) (xy 156.880999 -16.005531)
			(xy 156.968429 -16.015526) (xy 157.054588 -16.03343) (xy 157.138762 -16.059094) (xy 157.220253 -16.092307)
			(xy 157.298387 -16.132793) (xy 157.372515 -16.180215) (xy 157.442023 -16.234182) (xy 157.506337 -16.294247)
			(xy 157.564921 -16.359911) (xy 157.617292 -16.43063) (xy 157.663015 -16.505818) (xy 157.701712 -16.584853)
			(xy 157.733061 -16.667079) (xy 157.756803 -16.751815) (xy 157.772741 -16.838359) (xy 157.780743 -16.925994)
			(xy 157.781244 -16.969994) (xy 157.780743 -17.013994) (xy 157.772741 -17.101629) (xy 157.756803 -17.188173)
			(xy 157.733061 -17.272909) (xy 157.701712 -17.355135) (xy 157.663015 -17.43417) (xy 157.617292 -17.509358)
			(xy 157.564921 -17.580077) (xy 157.506337 -17.645741) (xy 157.442023 -17.705806) (xy 157.372515 -17.759773)
			(xy 157.298387 -17.807195) (xy 157.220253 -17.847681) (xy 157.138762 -17.880894) (xy 157.054588 -17.906558)
			(xy 156.968429 -17.924462) (xy 156.880999 -17.934457) (xy 156.793022 -17.936461) (xy 156.705228 -17.930455)
			(xy 156.618344 -17.916491) (xy 156.533089 -17.894684) (xy 156.45017 -17.865215) (xy 156.370275 -17.828328)
			(xy 156.294066 -17.784328) (xy 156.222173 -17.73358) (xy 156.155192 -17.676506) (xy 156.09368 -17.613576)
			(xy 156.038144 -17.545314) (xy 155.989046 -17.472285) (xy 155.946793 -17.395093) (xy 155.911734 -17.314379)
			(xy 155.884159 -17.230811) (xy 155.864299 -17.145082) (xy 155.852316 -17.057902) (xy 155.848311 -16.969994)
			(xy 136.396343 -16.969994) (xy 136.350619 -17.027587) (xy 136.2636 -17.124429) (xy 136.170839 -17.215786)
			(xy 136.072681 -17.301318) (xy 135.969492 -17.380706) (xy 135.912036 -17.419574) (xy 140.384274 -17.419574)
			(xy 140.388345 -17.363952) (xy 140.400471 -17.309515) (xy 140.420394 -17.257424) (xy 140.44769 -17.208789)
			(xy 140.481776 -17.164646) (xy 140.521925 -17.125937) (xy 140.567283 -17.093486) (xy 140.616883 -17.067985)
			(xy 140.669667 -17.049978) (xy 140.72451 -17.039848) (xy 140.780244 -17.037811) (xy 140.835681 -17.043911)
			(xy 140.889638 -17.058017) (xy 140.940967 -17.079829) (xy 140.988573 -17.108883) (xy 141.031441 -17.144558)
			(xy 141.068658 -17.186095) (xy 141.099431 -17.232608) (xy 141.123103 -17.283105) (xy 141.139171 -17.336512)
			(xy 141.147291 -17.391688) (xy 141.1478 -17.419574) (xy 141.147291 -17.44746) (xy 141.139171 -17.502636)
			(xy 141.123103 -17.556043) (xy 141.099431 -17.60654) (xy 141.068658 -17.653053) (xy 141.031441 -17.69459)
			(xy 140.988573 -17.730265) (xy 140.940967 -17.759319) (xy 140.889638 -17.781131) (xy 140.835681 -17.795237)
			(xy 140.780244 -17.801337) (xy 140.72451 -17.7993) (xy 140.669667 -17.78917) (xy 140.616883 -17.771163)
			(xy 140.567283 -17.745662) (xy 140.521925 -17.713211) (xy 140.481776 -17.674502) (xy 140.44769 -17.630359)
			(xy 140.420394 -17.581724) (xy 140.400471 -17.529633) (xy 140.388345 -17.475196) (xy 140.384274 -17.419574)
			(xy 135.912036 -17.419574) (xy 135.861655 -17.453656) (xy 135.74957 -17.519897) (xy 135.633657 -17.57918)
			(xy 135.514344 -17.631288) (xy 135.392077 -17.676024) (xy 135.26731 -17.713223) (xy 135.140507 -17.742747)
			(xy 135.01214 -17.764485) (xy 134.882687 -17.778358) (xy 134.752628 -17.784312) (xy 134.622449 -17.782327)
			(xy 134.492633 -17.772409) (xy 134.363663 -17.754595) (xy 134.236018 -17.728952) (xy 134.110175 -17.695575)
			(xy 133.9866 -17.654588) (xy 133.865754 -17.606144) (xy 133.748086 -17.550422) (xy 133.634034 -17.487631)
			(xy 133.524022 -17.418004) (xy 133.41846 -17.341799) (xy 133.31774 -17.2593) (xy 133.222236 -17.170815)
			(xy 133.132304 -17.076672) (xy 133.048279 -16.977221) (xy 132.970474 -16.872833) (xy 132.899177 -16.763896)
			(xy 132.834653 -16.650814) (xy 132.777144 -16.53401) (xy 132.726862 -16.413917) (xy 132.683996 -16.290981)
			(xy 132.648703 -16.165662) (xy 132.621117 -16.038423) (xy 132.601338 -15.90974) (xy 132.589442 -15.78009)
			(xy 132.585472 -15.649956) (xy 98.754184 -15.649956) (xy 98.753688 -15.715053) (xy 98.74575 -15.845006)
			(xy 98.729906 -15.974232) (xy 98.706212 -16.102253) (xy 98.674758 -16.228591) (xy 98.63566 -16.352776)
			(xy 98.589065 -16.474347) (xy 98.535144 -16.592851) (xy 98.474099 -16.707847) (xy 98.406158 -16.818908)
			(xy 98.331572 -16.92562) (xy 98.296343 -16.969994) (xy 129.848363 -16.969994) (xy 129.852368 -16.882086)
			(xy 129.864351 -16.794906) (xy 129.884211 -16.709177) (xy 129.911786 -16.625609) (xy 129.946845 -16.544895)
			(xy 129.989098 -16.467703) (xy 130.038196 -16.394674) (xy 130.093732 -16.326412) (xy 130.155244 -16.263482)
			(xy 130.222225 -16.206408) (xy 130.294118 -16.15566) (xy 130.370327 -16.11166) (xy 130.450222 -16.074773)
			(xy 130.533141 -16.045304) (xy 130.618396 -16.023497) (xy 130.70528 -16.009533) (xy 130.793074 -16.003527)
			(xy 130.881051 -16.005531) (xy 130.968481 -16.015526) (xy 131.05464 -16.03343) (xy 131.138814 -16.059094)
			(xy 131.220305 -16.092307) (xy 131.298439 -16.132793) (xy 131.372567 -16.180215) (xy 131.442075 -16.234182)
			(xy 131.506389 -16.294247) (xy 131.564973 -16.359911) (xy 131.617344 -16.43063) (xy 131.663067 -16.505818)
			(xy 131.701764 -16.584853) (xy 131.733113 -16.667079) (xy 131.756855 -16.751815) (xy 131.772793 -16.838359)
			(xy 131.780795 -16.925994) (xy 131.781296 -16.969994) (xy 131.780795 -17.013994) (xy 131.772793 -17.101629)
			(xy 131.756855 -17.188173) (xy 131.733113 -17.272909) (xy 131.701764 -17.355135) (xy 131.663067 -17.43417)
			(xy 131.617344 -17.509358) (xy 131.564973 -17.580077) (xy 131.506389 -17.645741) (xy 131.442075 -17.705806)
			(xy 131.372567 -17.759773) (xy 131.298439 -17.807195) (xy 131.220305 -17.847681) (xy 131.138814 -17.880894)
			(xy 131.05464 -17.906558) (xy 130.968481 -17.924462) (xy 130.881051 -17.934457) (xy 130.793074 -17.936461)
			(xy 130.70528 -17.930455) (xy 130.618396 -17.916491) (xy 130.533141 -17.894684) (xy 130.450222 -17.865215)
			(xy 130.370327 -17.828328) (xy 130.294118 -17.784328) (xy 130.222225 -17.73358) (xy 130.155244 -17.676506)
			(xy 130.093732 -17.613576) (xy 130.038196 -17.545314) (xy 129.989098 -17.472285) (xy 129.946845 -17.395093)
			(xy 129.911786 -17.314379) (xy 129.884211 -17.230811) (xy 129.864351 -17.145082) (xy 129.852368 -17.057902)
			(xy 129.848363 -16.969994) (xy 98.296343 -16.969994) (xy 98.250619 -17.027587) (xy 98.1636 -17.124429)
			(xy 98.070839 -17.215786) (xy 97.972681 -17.301318) (xy 97.869492 -17.380706) (xy 97.761655 -17.453656)
			(xy 97.64957 -17.519897) (xy 97.533657 -17.57918) (xy 97.414344 -17.631288) (xy 97.292077 -17.676024)
			(xy 97.16731 -17.713223) (xy 97.040507 -17.742747) (xy 96.91214 -17.764485) (xy 96.782687 -17.778358)
			(xy 96.652628 -17.784312) (xy 96.522449 -17.782327) (xy 96.392633 -17.772409) (xy 96.263663 -17.754595)
			(xy 96.136018 -17.728952) (xy 96.010175 -17.695575) (xy 95.8866 -17.654588) (xy 95.765754 -17.606144)
			(xy 95.648086 -17.550422) (xy 95.534034 -17.487631) (xy 95.424022 -17.418004) (xy 95.31846 -17.341799)
			(xy 95.21774 -17.2593) (xy 95.122236 -17.170815) (xy 95.032304 -17.076672) (xy 94.948279 -16.977221)
			(xy 94.870474 -16.872833) (xy 94.799177 -16.763896) (xy 94.734653 -16.650814) (xy 94.677144 -16.53401)
			(xy 94.626862 -16.413917) (xy 94.583996 -16.290981) (xy 94.548703 -16.165662) (xy 94.521117 -16.038423)
			(xy 94.501338 -15.90974) (xy 94.489442 -15.78009) (xy 94.485472 -15.649956) (xy 79.169687 -15.649956)
			(xy 79.130592 -15.675083) (xy 79.081014 -15.697726) (xy 79.028719 -15.713084) (xy 78.97477 -15.720843)
			(xy 78.947518 -15.72133) (xy 78.921385 -15.720867) (xy 78.86961 -15.713728) (xy 78.819292 -15.699596)
			(xy 78.771371 -15.678734) (xy 78.726742 -15.651531) (xy 78.68624 -15.618497) (xy 78.668118 -15.599664)
			(xy 78.660498 -15.591282) (xy 78.639924 -15.5829) (xy 78.539594 -15.587726) (xy 78.520036 -15.597886)
			(xy 78.513178 -15.606776) (xy 78.495002 -15.629542) (xy 78.452909 -15.669812) (xy 78.405181 -15.703212)
			(xy 78.352929 -15.728965) (xy 78.297368 -15.746472) (xy 78.239791 -15.755326) (xy 78.210664 -15.755874)
			(xy 78.183412 -15.755454) (xy 78.129463 -15.747692) (xy 78.077168 -15.732333) (xy 78.027591 -15.709687)
			(xy 77.981741 -15.680218) (xy 77.940552 -15.644523) (xy 77.904861 -15.60333) (xy 77.875395 -15.557477)
			(xy 77.852755 -15.507898) (xy 77.8374 -15.455601) (xy 77.829644 -15.401652) (xy 72.739273 -15.401652)
			(xy 72.745802 -15.454906) (xy 72.75374 -15.584859) (xy 72.754236 -15.649956) (xy 72.75374 -15.715053)
			(xy 72.745802 -15.845006) (xy 72.729958 -15.974232) (xy 72.706264 -16.102253) (xy 72.67481 -16.228591)
			(xy 72.635712 -16.352776) (xy 72.589117 -16.474347) (xy 72.535196 -16.592851) (xy 72.474151 -16.707847)
			(xy 72.40621 -16.818908) (xy 72.331624 -16.92562) (xy 72.296395 -16.969994) (xy 91.748109 -16.969994)
			(xy 91.752114 -16.882086) (xy 91.764097 -16.794906) (xy 91.783957 -16.709177) (xy 91.811532 -16.625609)
			(xy 91.846591 -16.544895) (xy 91.888844 -16.467703) (xy 91.937942 -16.394674) (xy 91.993478 -16.326412)
			(xy 92.05499 -16.263482) (xy 92.121971 -16.206408) (xy 92.193864 -16.15566) (xy 92.270073 -16.11166)
			(xy 92.349968 -16.074773) (xy 92.432887 -16.045304) (xy 92.518142 -16.023497) (xy 92.605026 -16.009533)
			(xy 92.69282 -16.003527) (xy 92.780797 -16.005531) (xy 92.868227 -16.015526) (xy 92.954386 -16.03343)
			(xy 93.03856 -16.059094) (xy 93.120051 -16.092307) (xy 93.198185 -16.132793) (xy 93.272313 -16.180215)
			(xy 93.341821 -16.234182) (xy 93.406135 -16.294247) (xy 93.464719 -16.359911) (xy 93.51709 -16.43063)
			(xy 93.562813 -16.505818) (xy 93.60151 -16.584853) (xy 93.632859 -16.667079) (xy 93.656601 -16.751815)
			(xy 93.672539 -16.838359) (xy 93.680541 -16.925994) (xy 93.681042 -16.969994) (xy 93.680541 -17.013994)
			(xy 93.672539 -17.101629) (xy 93.656601 -17.188173) (xy 93.632859 -17.272909) (xy 93.60151 -17.355135)
			(xy 93.562813 -17.43417) (xy 93.51709 -17.509358) (xy 93.464719 -17.580077) (xy 93.406135 -17.645741)
			(xy 93.341821 -17.705806) (xy 93.272313 -17.759773) (xy 93.198185 -17.807195) (xy 93.120051 -17.847681)
			(xy 93.03856 -17.880894) (xy 92.954386 -17.906558) (xy 92.868227 -17.924462) (xy 92.780797 -17.934457)
			(xy 92.69282 -17.936461) (xy 92.605026 -17.930455) (xy 92.518142 -17.916491) (xy 92.432887 -17.894684)
			(xy 92.349968 -17.865215) (xy 92.270073 -17.828328) (xy 92.193864 -17.784328) (xy 92.121971 -17.73358)
			(xy 92.05499 -17.676506) (xy 91.993478 -17.613576) (xy 91.937942 -17.545314) (xy 91.888844 -17.472285)
			(xy 91.846591 -17.395093) (xy 91.811532 -17.314379) (xy 91.783957 -17.230811) (xy 91.764097 -17.145082)
			(xy 91.752114 -17.057902) (xy 91.748109 -16.969994) (xy 72.296395 -16.969994) (xy 72.250671 -17.027587)
			(xy 72.163652 -17.124429) (xy 72.070891 -17.215786) (xy 71.972733 -17.301318) (xy 71.869544 -17.380706)
			(xy 71.812088 -17.419574) (xy 76.284072 -17.419574) (xy 76.288143 -17.363952) (xy 76.300269 -17.309515)
			(xy 76.320192 -17.257424) (xy 76.347488 -17.208789) (xy 76.381574 -17.164646) (xy 76.421723 -17.125937)
			(xy 76.467081 -17.093486) (xy 76.516681 -17.067985) (xy 76.569465 -17.049978) (xy 76.624308 -17.039848)
			(xy 76.680042 -17.037811) (xy 76.735479 -17.043911) (xy 76.789436 -17.058017) (xy 76.840765 -17.079829)
			(xy 76.888371 -17.108883) (xy 76.931239 -17.144558) (xy 76.968456 -17.186095) (xy 76.999229 -17.232608)
			(xy 77.022901 -17.283105) (xy 77.038969 -17.336512) (xy 77.047089 -17.391688) (xy 77.047598 -17.419574)
			(xy 77.047089 -17.44746) (xy 77.038969 -17.502636) (xy 77.022901 -17.556043) (xy 76.999229 -17.60654)
			(xy 76.968456 -17.653053) (xy 76.931239 -17.69459) (xy 76.888371 -17.730265) (xy 76.840765 -17.759319)
			(xy 76.789436 -17.781131) (xy 76.735479 -17.795237) (xy 76.680042 -17.801337) (xy 76.624308 -17.7993)
			(xy 76.569465 -17.78917) (xy 76.516681 -17.771163) (xy 76.467081 -17.745662) (xy 76.421723 -17.713211)
			(xy 76.381574 -17.674502) (xy 76.347488 -17.630359) (xy 76.320192 -17.581724) (xy 76.300269 -17.529633)
			(xy 76.288143 -17.475196) (xy 76.284072 -17.419574) (xy 71.812088 -17.419574) (xy 71.761707 -17.453656)
			(xy 71.649622 -17.519897) (xy 71.533709 -17.57918) (xy 71.414396 -17.631288) (xy 71.292129 -17.676024)
			(xy 71.167362 -17.713223) (xy 71.040559 -17.742747) (xy 70.912192 -17.764485) (xy 70.782739 -17.778358)
			(xy 70.65268 -17.784312) (xy 70.522501 -17.782327) (xy 70.392685 -17.772409) (xy 70.263715 -17.754595)
			(xy 70.13607 -17.728952) (xy 70.010227 -17.695575) (xy 69.886652 -17.654588) (xy 69.765806 -17.606144)
			(xy 69.648138 -17.550422) (xy 69.534086 -17.487631) (xy 69.424074 -17.418004) (xy 69.318512 -17.341799)
			(xy 69.217792 -17.2593) (xy 69.122288 -17.170815) (xy 69.032356 -17.076672) (xy 68.948331 -16.977221)
			(xy 68.870526 -16.872833) (xy 68.799229 -16.763896) (xy 68.734705 -16.650814) (xy 68.677196 -16.53401)
			(xy 68.626914 -16.413917) (xy 68.584048 -16.290981) (xy 68.548755 -16.165662) (xy 68.521169 -16.038423)
			(xy 68.50139 -15.90974) (xy 68.489494 -15.78009) (xy 68.485524 -15.649956) (xy 53.208503 -15.649956)
			(xy 53.178901 -15.668982) (xy 53.129325 -15.691627) (xy 53.07703 -15.706986) (xy 53.023082 -15.714746)
			(xy 52.99583 -15.715234) (xy 52.966209 -15.714701) (xy 52.90768 -15.705534) (xy 52.851272 -15.687431)
			(xy 52.798339 -15.660828) (xy 52.750154 -15.626363) (xy 52.728622 -15.606014) (xy 52.720697 -15.598964)
			(xy 52.700875 -15.591485) (xy 52.690268 -15.591536) (xy 52.604924 -15.596108) (xy 52.586128 -15.605506)
			(xy 52.57927 -15.613634) (xy 52.561081 -15.634885) (xy 52.519485 -15.672284) (xy 52.472876 -15.703212)
			(xy 52.422253 -15.727007) (xy 52.368699 -15.743158) (xy 52.31336 -15.751321) (xy 52.285392 -15.75181)
			(xy 52.258141 -15.75132) (xy 52.204195 -15.743562) (xy 52.151901 -15.728207) (xy 52.102325 -15.705565)
			(xy 52.056476 -15.676099) (xy 52.015287 -15.640407) (xy 51.979596 -15.599218) (xy 51.950131 -15.553368)
			(xy 51.927491 -15.503791) (xy 51.912136 -15.451497) (xy 51.90438 -15.397551) (xy 46.738568 -15.397551)
			(xy 46.7456 -15.454906) (xy 46.753538 -15.584859) (xy 46.754034 -15.649956) (xy 46.753538 -15.715053)
			(xy 46.7456 -15.845006) (xy 46.729756 -15.974232) (xy 46.706062 -16.102253) (xy 46.674608 -16.228591)
			(xy 46.63551 -16.352776) (xy 46.588915 -16.474347) (xy 46.534994 -16.592851) (xy 46.473949 -16.707847)
			(xy 46.406008 -16.818908) (xy 46.331422 -16.92562) (xy 46.296193 -16.969994) (xy 65.748161 -16.969994)
			(xy 65.752166 -16.882086) (xy 65.764149 -16.794906) (xy 65.784009 -16.709177) (xy 65.811584 -16.625609)
			(xy 65.846643 -16.544895) (xy 65.888896 -16.467703) (xy 65.937994 -16.394674) (xy 65.99353 -16.326412)
			(xy 66.055042 -16.263482) (xy 66.122023 -16.206408) (xy 66.193916 -16.15566) (xy 66.270125 -16.11166)
			(xy 66.35002 -16.074773) (xy 66.432939 -16.045304) (xy 66.518194 -16.023497) (xy 66.605078 -16.009533)
			(xy 66.692872 -16.003527) (xy 66.780849 -16.005531) (xy 66.868279 -16.015526) (xy 66.954438 -16.03343)
			(xy 67.038612 -16.059094) (xy 67.120103 -16.092307) (xy 67.198237 -16.132793) (xy 67.272365 -16.180215)
			(xy 67.341873 -16.234182) (xy 67.406187 -16.294247) (xy 67.464771 -16.359911) (xy 67.517142 -16.43063)
			(xy 67.562865 -16.505818) (xy 67.601562 -16.584853) (xy 67.632911 -16.667079) (xy 67.656653 -16.751815)
			(xy 67.672591 -16.838359) (xy 67.680593 -16.925994) (xy 67.681094 -16.969994) (xy 67.680593 -17.013994)
			(xy 67.672591 -17.101629) (xy 67.656653 -17.188173) (xy 67.632911 -17.272909) (xy 67.601562 -17.355135)
			(xy 67.562865 -17.43417) (xy 67.517142 -17.509358) (xy 67.464771 -17.580077) (xy 67.406187 -17.645741)
			(xy 67.341873 -17.705806) (xy 67.272365 -17.759773) (xy 67.198237 -17.807195) (xy 67.120103 -17.847681)
			(xy 67.038612 -17.880894) (xy 66.954438 -17.906558) (xy 66.868279 -17.924462) (xy 66.780849 -17.934457)
			(xy 66.692872 -17.936461) (xy 66.605078 -17.930455) (xy 66.518194 -17.916491) (xy 66.432939 -17.894684)
			(xy 66.35002 -17.865215) (xy 66.270125 -17.828328) (xy 66.193916 -17.784328) (xy 66.122023 -17.73358)
			(xy 66.055042 -17.676506) (xy 65.99353 -17.613576) (xy 65.937994 -17.545314) (xy 65.888896 -17.472285)
			(xy 65.846643 -17.395093) (xy 65.811584 -17.314379) (xy 65.784009 -17.230811) (xy 65.764149 -17.145082)
			(xy 65.752166 -17.057902) (xy 65.748161 -16.969994) (xy 46.296193 -16.969994) (xy 46.250469 -17.027587)
			(xy 46.16345 -17.124429) (xy 46.070689 -17.215786) (xy 45.972531 -17.301318) (xy 45.869342 -17.380706)
			(xy 45.811886 -17.419574) (xy 50.284124 -17.419574) (xy 50.288195 -17.363952) (xy 50.300321 -17.309515)
			(xy 50.320244 -17.257424) (xy 50.34754 -17.208789) (xy 50.381626 -17.164646) (xy 50.421775 -17.125937)
			(xy 50.467133 -17.093486) (xy 50.516733 -17.067985) (xy 50.569517 -17.049978) (xy 50.62436 -17.039848)
			(xy 50.680094 -17.037811) (xy 50.735531 -17.043911) (xy 50.789488 -17.058017) (xy 50.840817 -17.079829)
			(xy 50.888423 -17.108883) (xy 50.931291 -17.144558) (xy 50.968508 -17.186095) (xy 50.999281 -17.232608)
			(xy 51.022953 -17.283105) (xy 51.039021 -17.336512) (xy 51.047141 -17.391688) (xy 51.04765 -17.419574)
			(xy 51.047141 -17.44746) (xy 51.039021 -17.502636) (xy 51.022953 -17.556043) (xy 50.999281 -17.60654)
			(xy 50.968508 -17.653053) (xy 50.931291 -17.69459) (xy 50.888423 -17.730265) (xy 50.840817 -17.759319)
			(xy 50.789488 -17.781131) (xy 50.735531 -17.795237) (xy 50.680094 -17.801337) (xy 50.62436 -17.7993)
			(xy 50.569517 -17.78917) (xy 50.516733 -17.771163) (xy 50.467133 -17.745662) (xy 50.421775 -17.713211)
			(xy 50.381626 -17.674502) (xy 50.34754 -17.630359) (xy 50.320244 -17.581724) (xy 50.300321 -17.529633)
			(xy 50.288195 -17.475196) (xy 50.284124 -17.419574) (xy 45.811886 -17.419574) (xy 45.761505 -17.453656)
			(xy 45.64942 -17.519897) (xy 45.533507 -17.57918) (xy 45.414194 -17.631288) (xy 45.291927 -17.676024)
			(xy 45.16716 -17.713223) (xy 45.040357 -17.742747) (xy 44.91199 -17.764485) (xy 44.782537 -17.778358)
			(xy 44.652478 -17.784312) (xy 44.522299 -17.782327) (xy 44.392483 -17.772409) (xy 44.263513 -17.754595)
			(xy 44.135868 -17.728952) (xy 44.010025 -17.695575) (xy 43.88645 -17.654588) (xy 43.765604 -17.606144)
			(xy 43.647936 -17.550422) (xy 43.533884 -17.487631) (xy 43.423872 -17.418004) (xy 43.31831 -17.341799)
			(xy 43.21759 -17.2593) (xy 43.122086 -17.170815) (xy 43.032154 -17.076672) (xy 42.948129 -16.977221)
			(xy 42.870324 -16.872833) (xy 42.799027 -16.763896) (xy 42.734503 -16.650814) (xy 42.676994 -16.53401)
			(xy 42.626712 -16.413917) (xy 42.583846 -16.290981) (xy 42.548553 -16.165662) (xy 42.520967 -16.038423)
			(xy 42.501188 -15.90974) (xy 42.489292 -15.78009) (xy 42.485322 -15.649956) (xy 20.754086 -15.649956)
			(xy 20.75359 -15.715053) (xy 20.745652 -15.845006) (xy 20.729808 -15.974232) (xy 20.706114 -16.102253)
			(xy 20.67466 -16.228591) (xy 20.635562 -16.352776) (xy 20.588967 -16.474347) (xy 20.535046 -16.592851)
			(xy 20.474001 -16.707847) (xy 20.40606 -16.818908) (xy 20.331474 -16.92562) (xy 20.296245 -16.969994)
			(xy 39.748213 -16.969994) (xy 39.752218 -16.882086) (xy 39.764201 -16.794906) (xy 39.784061 -16.709177)
			(xy 39.811636 -16.625609) (xy 39.846695 -16.544895) (xy 39.888948 -16.467703) (xy 39.938046 -16.394674)
			(xy 39.993582 -16.326412) (xy 40.055094 -16.263482) (xy 40.122075 -16.206408) (xy 40.193968 -16.15566)
			(xy 40.270177 -16.11166) (xy 40.350072 -16.074773) (xy 40.432991 -16.045304) (xy 40.518246 -16.023497)
			(xy 40.60513 -16.009533) (xy 40.692924 -16.003527) (xy 40.780901 -16.005531) (xy 40.868331 -16.015526)
			(xy 40.95449 -16.03343) (xy 41.038664 -16.059094) (xy 41.120155 -16.092307) (xy 41.198289 -16.132793)
			(xy 41.272417 -16.180215) (xy 41.341925 -16.234182) (xy 41.406239 -16.294247) (xy 41.464823 -16.359911)
			(xy 41.517194 -16.43063) (xy 41.562917 -16.505818) (xy 41.601614 -16.584853) (xy 41.632963 -16.667079)
			(xy 41.656705 -16.751815) (xy 41.672643 -16.838359) (xy 41.680645 -16.925994) (xy 41.681146 -16.969994)
			(xy 41.680645 -17.013994) (xy 41.672643 -17.101629) (xy 41.656705 -17.188173) (xy 41.632963 -17.272909)
			(xy 41.601614 -17.355135) (xy 41.562917 -17.43417) (xy 41.517194 -17.509358) (xy 41.464823 -17.580077)
			(xy 41.406239 -17.645741) (xy 41.341925 -17.705806) (xy 41.272417 -17.759773) (xy 41.198289 -17.807195)
			(xy 41.120155 -17.847681) (xy 41.038664 -17.880894) (xy 40.95449 -17.906558) (xy 40.868331 -17.924462)
			(xy 40.780901 -17.934457) (xy 40.692924 -17.936461) (xy 40.60513 -17.930455) (xy 40.518246 -17.916491)
			(xy 40.432991 -17.894684) (xy 40.350072 -17.865215) (xy 40.270177 -17.828328) (xy 40.193968 -17.784328)
			(xy 40.122075 -17.73358) (xy 40.055094 -17.676506) (xy 39.993582 -17.613576) (xy 39.938046 -17.545314)
			(xy 39.888948 -17.472285) (xy 39.846695 -17.395093) (xy 39.811636 -17.314379) (xy 39.784061 -17.230811)
			(xy 39.764201 -17.145082) (xy 39.752218 -17.057902) (xy 39.748213 -16.969994) (xy 20.296245 -16.969994)
			(xy 20.250521 -17.027587) (xy 20.163502 -17.124429) (xy 20.070741 -17.215786) (xy 19.972583 -17.301318)
			(xy 19.869394 -17.380706) (xy 19.761557 -17.453656) (xy 19.649472 -17.519897) (xy 19.533559 -17.57918)
			(xy 19.414246 -17.631288) (xy 19.291979 -17.676024) (xy 19.167212 -17.713223) (xy 19.040409 -17.742747)
			(xy 18.912042 -17.764485) (xy 18.782589 -17.778358) (xy 18.65253 -17.784312) (xy 18.522351 -17.782327)
			(xy 18.392535 -17.772409) (xy 18.263565 -17.754595) (xy 18.13592 -17.728952) (xy 18.010077 -17.695575)
			(xy 17.886502 -17.654588) (xy 17.765656 -17.606144) (xy 17.647988 -17.550422) (xy 17.533936 -17.487631)
			(xy 17.423924 -17.418004) (xy 17.318362 -17.341799) (xy 17.217642 -17.2593) (xy 17.122138 -17.170815)
			(xy 17.032206 -17.076672) (xy 16.948181 -16.977221) (xy 16.870376 -16.872833) (xy 16.799079 -16.763896)
			(xy 16.734555 -16.650814) (xy 16.677046 -16.53401) (xy 16.626764 -16.413917) (xy 16.583898 -16.290981)
			(xy 16.548605 -16.165662) (xy 16.521019 -16.038423) (xy 16.50124 -15.90974) (xy 16.489344 -15.78009)
			(xy 16.485374 -15.649956) (xy 0.715772 -15.649956) (xy 0.715772 -16.144748) (xy 7.834882 -16.144748)
			(xy 7.838953 -16.089126) (xy 7.851079 -16.034689) (xy 7.871002 -15.982598) (xy 7.898298 -15.933963)
			(xy 7.932384 -15.88982) (xy 7.972533 -15.851111) (xy 8.017891 -15.81866) (xy 8.067491 -15.793159)
			(xy 8.120275 -15.775152) (xy 8.175118 -15.765022) (xy 8.230852 -15.762985) (xy 8.286289 -15.769085)
			(xy 8.340246 -15.783191) (xy 8.391575 -15.805003) (xy 8.439181 -15.834057) (xy 8.482049 -15.869732)
			(xy 8.519266 -15.911269) (xy 8.550039 -15.957782) (xy 8.573711 -16.008279) (xy 8.589779 -16.061686)
			(xy 8.597899 -16.116862) (xy 8.598408 -16.144748) (xy 8.597899 -16.172634) (xy 8.589779 -16.22781)
			(xy 8.573711 -16.281217) (xy 8.550039 -16.331714) (xy 8.519266 -16.378227) (xy 8.482049 -16.419764)
			(xy 8.439181 -16.455439) (xy 8.391575 -16.484493) (xy 8.340246 -16.506305) (xy 8.286289 -16.520411)
			(xy 8.230852 -16.526511) (xy 8.175118 -16.524474) (xy 8.120275 -16.514344) (xy 8.067491 -16.496337)
			(xy 8.017891 -16.470836) (xy 7.972533 -16.438385) (xy 7.932384 -16.399676) (xy 7.898298 -16.355533)
			(xy 7.871002 -16.306898) (xy 7.851079 -16.254807) (xy 7.838953 -16.20037) (xy 7.834882 -16.144748)
			(xy 0.715772 -16.144748) (xy 0.715772 -17.160748) (xy 7.834882 -17.160748) (xy 7.838953 -17.105126)
			(xy 7.851079 -17.050689) (xy 7.871002 -16.998598) (xy 7.898298 -16.949963) (xy 7.932384 -16.90582)
			(xy 7.972533 -16.867111) (xy 8.017891 -16.83466) (xy 8.067491 -16.809159) (xy 8.120275 -16.791152)
			(xy 8.175118 -16.781022) (xy 8.230852 -16.778985) (xy 8.286289 -16.785085) (xy 8.340246 -16.799191)
			(xy 8.391575 -16.821003) (xy 8.439181 -16.850057) (xy 8.482049 -16.885732) (xy 8.519266 -16.927269)
			(xy 8.547533 -16.969994) (xy 13.748265 -16.969994) (xy 13.75227 -16.882086) (xy 13.764253 -16.794906)
			(xy 13.784113 -16.709177) (xy 13.811688 -16.625609) (xy 13.846747 -16.544895) (xy 13.889 -16.467703)
			(xy 13.938098 -16.394674) (xy 13.993634 -16.326412) (xy 14.055146 -16.263482) (xy 14.122127 -16.206408)
			(xy 14.19402 -16.15566) (xy 14.270229 -16.11166) (xy 14.350124 -16.074773) (xy 14.433043 -16.045304)
			(xy 14.518298 -16.023497) (xy 14.605182 -16.009533) (xy 14.692976 -16.003527) (xy 14.780953 -16.005531)
			(xy 14.868383 -16.015526) (xy 14.954542 -16.03343) (xy 15.038716 -16.059094) (xy 15.120207 -16.092307)
			(xy 15.198341 -16.132793) (xy 15.272469 -16.180215) (xy 15.341977 -16.234182) (xy 15.406291 -16.294247)
			(xy 15.464875 -16.359911) (xy 15.517246 -16.43063) (xy 15.562969 -16.505818) (xy 15.601666 -16.584853)
			(xy 15.633015 -16.667079) (xy 15.656757 -16.751815) (xy 15.672695 -16.838359) (xy 15.680697 -16.925994)
			(xy 15.681198 -16.969994) (xy 15.680697 -17.013994) (xy 15.672695 -17.101629) (xy 15.656757 -17.188173)
			(xy 15.633015 -17.272909) (xy 15.601666 -17.355135) (xy 15.562969 -17.43417) (xy 15.517246 -17.509358)
			(xy 15.464875 -17.580077) (xy 15.406291 -17.645741) (xy 15.341977 -17.705806) (xy 15.272469 -17.759773)
			(xy 15.198341 -17.807195) (xy 15.120207 -17.847681) (xy 15.038716 -17.880894) (xy 14.954542 -17.906558)
			(xy 14.868383 -17.924462) (xy 14.780953 -17.934457) (xy 14.692976 -17.936461) (xy 14.605182 -17.930455)
			(xy 14.518298 -17.916491) (xy 14.433043 -17.894684) (xy 14.350124 -17.865215) (xy 14.270229 -17.828328)
			(xy 14.19402 -17.784328) (xy 14.122127 -17.73358) (xy 14.055146 -17.676506) (xy 13.993634 -17.613576)
			(xy 13.938098 -17.545314) (xy 13.889 -17.472285) (xy 13.846747 -17.395093) (xy 13.811688 -17.314379)
			(xy 13.784113 -17.230811) (xy 13.764253 -17.145082) (xy 13.75227 -17.057902) (xy 13.748265 -16.969994)
			(xy 8.547533 -16.969994) (xy 8.550039 -16.973782) (xy 8.573711 -17.024279) (xy 8.589779 -17.077686)
			(xy 8.597899 -17.132862) (xy 8.598408 -17.160748) (xy 8.597899 -17.188634) (xy 8.589779 -17.24381)
			(xy 8.573711 -17.297217) (xy 8.550039 -17.347714) (xy 8.519266 -17.394227) (xy 8.482049 -17.435764)
			(xy 8.439181 -17.471439) (xy 8.391575 -17.500493) (xy 8.340246 -17.522305) (xy 8.286289 -17.536411)
			(xy 8.230852 -17.542511) (xy 8.175118 -17.540474) (xy 8.120275 -17.530344) (xy 8.067491 -17.512337)
			(xy 8.017891 -17.486836) (xy 7.972533 -17.454385) (xy 7.932384 -17.415676) (xy 7.898298 -17.371533)
			(xy 7.871002 -17.322898) (xy 7.851079 -17.270807) (xy 7.838953 -17.21637) (xy 7.834882 -17.160748)
			(xy 0.715772 -17.160748) (xy 0.715772 -18.029174) (xy 1.464816 -18.029174) (xy 1.468887 -17.973552)
			(xy 1.481013 -17.919115) (xy 1.500936 -17.867024) (xy 1.528232 -17.818389) (xy 1.562318 -17.774246)
			(xy 1.602467 -17.735537) (xy 1.647825 -17.703086) (xy 1.697425 -17.677585) (xy 1.750209 -17.659578)
			(xy 1.805052 -17.649448) (xy 1.860786 -17.647411) (xy 1.916223 -17.653511) (xy 1.97018 -17.667617)
			(xy 2.021509 -17.689429) (xy 2.069115 -17.718483) (xy 2.111983 -17.754158) (xy 2.1492 -17.795695)
			(xy 2.179973 -17.842208) (xy 2.203645 -17.892705) (xy 2.219713 -17.946112) (xy 2.227833 -18.001288)
			(xy 2.228342 -18.029174) (xy 2.227833 -18.05706) (xy 2.219713 -18.112236) (xy 2.203645 -18.165643)
			(xy 2.179973 -18.21614) (xy 2.1492 -18.262653) (xy 2.111983 -18.30419) (xy 2.069115 -18.339865) (xy 2.021509 -18.368919)
			(xy 1.97018 -18.390731) (xy 1.916223 -18.404837) (xy 1.860786 -18.410937) (xy 1.805052 -18.4089)
			(xy 1.750209 -18.39877) (xy 1.697425 -18.380763) (xy 1.647825 -18.355262) (xy 1.602467 -18.322811)
			(xy 1.562318 -18.284102) (xy 1.528232 -18.239959) (xy 1.500936 -18.191324) (xy 1.481013 -18.139233)
			(xy 1.468887 -18.084796) (xy 1.464816 -18.029174) (xy 0.715772 -18.029174) (xy 0.715772 -18.44421)
			(xy 48.276254 -18.44421) (xy 48.280325 -18.388588) (xy 48.292451 -18.334151) (xy 48.312374 -18.28206)
			(xy 48.33967 -18.233425) (xy 48.373756 -18.189282) (xy 48.413905 -18.150573) (xy 48.459263 -18.118122)
			(xy 48.508863 -18.092621) (xy 48.561647 -18.074614) (xy 48.61649 -18.064484) (xy 48.672224 -18.062447)
			(xy 48.727661 -18.068547) (xy 48.781618 -18.082653) (xy 48.832947 -18.104465) (xy 48.880553 -18.133519)
			(xy 48.923421 -18.169194) (xy 48.960638 -18.210731) (xy 48.991411 -18.257244) (xy 49.015083 -18.307741)
			(xy 49.031151 -18.361148) (xy 49.039271 -18.416324) (xy 49.03978 -18.44421) (xy 74.276202 -18.44421)
			(xy 74.280273 -18.388588) (xy 74.292399 -18.334151) (xy 74.312322 -18.28206) (xy 74.339618 -18.233425)
			(xy 74.373704 -18.189282) (xy 74.413853 -18.150573) (xy 74.459211 -18.118122) (xy 74.508811 -18.092621)
			(xy 74.561595 -18.074614) (xy 74.616438 -18.064484) (xy 74.672172 -18.062447) (xy 74.727609 -18.068547)
			(xy 74.781566 -18.082653) (xy 74.832895 -18.104465) (xy 74.880501 -18.133519) (xy 74.923369 -18.169194)
			(xy 74.960586 -18.210731) (xy 74.991359 -18.257244) (xy 75.015031 -18.307741) (xy 75.031099 -18.361148)
			(xy 75.039219 -18.416324) (xy 75.039728 -18.44421) (xy 138.376404 -18.44421) (xy 138.380475 -18.388588)
			(xy 138.392601 -18.334151) (xy 138.412524 -18.28206) (xy 138.43982 -18.233425) (xy 138.473906 -18.189282)
			(xy 138.514055 -18.150573) (xy 138.559413 -18.118122) (xy 138.609013 -18.092621) (xy 138.661797 -18.074614)
			(xy 138.71664 -18.064484) (xy 138.772374 -18.062447) (xy 138.827811 -18.068547) (xy 138.881768 -18.082653)
			(xy 138.933097 -18.104465) (xy 138.980703 -18.133519) (xy 139.023571 -18.169194) (xy 139.060788 -18.210731)
			(xy 139.091561 -18.257244) (xy 139.115233 -18.307741) (xy 139.131301 -18.361148) (xy 139.139421 -18.416324)
			(xy 139.13993 -18.44421) (xy 164.376352 -18.44421) (xy 164.380423 -18.388588) (xy 164.392549 -18.334151)
			(xy 164.412472 -18.28206) (xy 164.439768 -18.233425) (xy 164.473854 -18.189282) (xy 164.514003 -18.150573)
			(xy 164.559361 -18.118122) (xy 164.608961 -18.092621) (xy 164.661745 -18.074614) (xy 164.716588 -18.064484)
			(xy 164.772322 -18.062447) (xy 164.827759 -18.068547) (xy 164.881716 -18.082653) (xy 164.933045 -18.104465)
			(xy 164.980651 -18.133519) (xy 165.023519 -18.169194) (xy 165.060736 -18.210731) (xy 165.091509 -18.257244)
			(xy 165.115181 -18.307741) (xy 165.131249 -18.361148) (xy 165.139369 -18.416324) (xy 165.139878 -18.44421)
			(xy 190.3763 -18.44421) (xy 190.380371 -18.388588) (xy 190.392497 -18.334151) (xy 190.41242 -18.28206)
			(xy 190.439716 -18.233425) (xy 190.473802 -18.189282) (xy 190.513951 -18.150573) (xy 190.559309 -18.118122)
			(xy 190.608909 -18.092621) (xy 190.661693 -18.074614) (xy 190.716536 -18.064484) (xy 190.77227 -18.062447)
			(xy 190.827707 -18.068547) (xy 190.881664 -18.082653) (xy 190.932993 -18.104465) (xy 190.980599 -18.133519)
			(xy 191.023467 -18.169194) (xy 191.060684 -18.210731) (xy 191.091457 -18.257244) (xy 191.115129 -18.307741)
			(xy 191.131197 -18.361148) (xy 191.139317 -18.416324) (xy 191.139826 -18.44421) (xy 216.376248 -18.44421)
			(xy 216.380319 -18.388588) (xy 216.392445 -18.334151) (xy 216.412368 -18.28206) (xy 216.439664 -18.233425)
			(xy 216.47375 -18.189282) (xy 216.513899 -18.150573) (xy 216.559257 -18.118122) (xy 216.608857 -18.092621)
			(xy 216.661641 -18.074614) (xy 216.716484 -18.064484) (xy 216.772218 -18.062447) (xy 216.827655 -18.068547)
			(xy 216.881612 -18.082653) (xy 216.932941 -18.104465) (xy 216.980547 -18.133519) (xy 217.023415 -18.169194)
			(xy 217.060632 -18.210731) (xy 217.091405 -18.257244) (xy 217.115077 -18.307741) (xy 217.131145 -18.361148)
			(xy 217.139265 -18.416324) (xy 217.139774 -18.44421) (xy 254.476248 -18.44421) (xy 254.480319 -18.388588)
			(xy 254.492445 -18.334151) (xy 254.512368 -18.28206) (xy 254.539664 -18.233425) (xy 254.57375 -18.189282)
			(xy 254.613899 -18.150573) (xy 254.659257 -18.118122) (xy 254.708857 -18.092621) (xy 254.761641 -18.074614)
			(xy 254.816484 -18.064484) (xy 254.872218 -18.062447) (xy 254.927655 -18.068547) (xy 254.981612 -18.082653)
			(xy 255.032941 -18.104465) (xy 255.080547 -18.133519) (xy 255.123415 -18.169194) (xy 255.160632 -18.210731)
			(xy 255.191405 -18.257244) (xy 255.215077 -18.307741) (xy 255.231145 -18.361148) (xy 255.239265 -18.416324)
			(xy 255.239774 -18.44421) (xy 280.476196 -18.44421) (xy 280.480267 -18.388588) (xy 280.492393 -18.334151)
			(xy 280.512316 -18.28206) (xy 280.539612 -18.233425) (xy 280.573698 -18.189282) (xy 280.613847 -18.150573)
			(xy 280.659205 -18.118122) (xy 280.708805 -18.092621) (xy 280.761589 -18.074614) (xy 280.816432 -18.064484)
			(xy 280.872166 -18.062447) (xy 280.927603 -18.068547) (xy 280.98156 -18.082653) (xy 281.032889 -18.104465)
			(xy 281.080495 -18.133519) (xy 281.123363 -18.169194) (xy 281.16058 -18.210731) (xy 281.191353 -18.257244)
			(xy 281.215025 -18.307741) (xy 281.231093 -18.361148) (xy 281.239213 -18.416324) (xy 281.239722 -18.44421)
			(xy 306.476144 -18.44421) (xy 306.480215 -18.388588) (xy 306.492341 -18.334151) (xy 306.512264 -18.28206)
			(xy 306.53956 -18.233425) (xy 306.573646 -18.189282) (xy 306.613795 -18.150573) (xy 306.659153 -18.118122)
			(xy 306.708753 -18.092621) (xy 306.761537 -18.074614) (xy 306.81638 -18.064484) (xy 306.872114 -18.062447)
			(xy 306.927551 -18.068547) (xy 306.981508 -18.082653) (xy 307.032837 -18.104465) (xy 307.080443 -18.133519)
			(xy 307.123311 -18.169194) (xy 307.160528 -18.210731) (xy 307.191301 -18.257244) (xy 307.214973 -18.307741)
			(xy 307.231041 -18.361148) (xy 307.239161 -18.416324) (xy 307.23967 -18.44421) (xy 370.576346 -18.44421)
			(xy 370.580417 -18.388588) (xy 370.592543 -18.334151) (xy 370.612466 -18.28206) (xy 370.639762 -18.233425)
			(xy 370.673848 -18.189282) (xy 370.713997 -18.150573) (xy 370.759355 -18.118122) (xy 370.808955 -18.092621)
			(xy 370.861739 -18.074614) (xy 370.916582 -18.064484) (xy 370.972316 -18.062447) (xy 371.027753 -18.068547)
			(xy 371.08171 -18.082653) (xy 371.133039 -18.104465) (xy 371.180645 -18.133519) (xy 371.223513 -18.169194)
			(xy 371.26073 -18.210731) (xy 371.291503 -18.257244) (xy 371.315175 -18.307741) (xy 371.331243 -18.361148)
			(xy 371.339363 -18.416324) (xy 371.339872 -18.44421) (xy 396.576294 -18.44421) (xy 396.580365 -18.388588)
			(xy 396.592491 -18.334151) (xy 396.612414 -18.28206) (xy 396.63971 -18.233425) (xy 396.673796 -18.189282)
			(xy 396.713945 -18.150573) (xy 396.759303 -18.118122) (xy 396.808903 -18.092621) (xy 396.861687 -18.074614)
			(xy 396.91653 -18.064484) (xy 396.972264 -18.062447) (xy 397.027701 -18.068547) (xy 397.081658 -18.082653)
			(xy 397.132987 -18.104465) (xy 397.180593 -18.133519) (xy 397.223461 -18.169194) (xy 397.260678 -18.210731)
			(xy 397.291451 -18.257244) (xy 397.315123 -18.307741) (xy 397.331191 -18.361148) (xy 397.339311 -18.416324)
			(xy 397.33982 -18.44421) (xy 422.576242 -18.44421) (xy 422.580313 -18.388588) (xy 422.592439 -18.334151)
			(xy 422.612362 -18.28206) (xy 422.639658 -18.233425) (xy 422.673744 -18.189282) (xy 422.713893 -18.150573)
			(xy 422.759251 -18.118122) (xy 422.808851 -18.092621) (xy 422.861635 -18.074614) (xy 422.916478 -18.064484)
			(xy 422.972212 -18.062447) (xy 423.027649 -18.068547) (xy 423.081606 -18.082653) (xy 423.132935 -18.104465)
			(xy 423.180541 -18.133519) (xy 423.223409 -18.169194) (xy 423.260626 -18.210731) (xy 423.291399 -18.257244)
			(xy 423.315071 -18.307741) (xy 423.331139 -18.361148) (xy 423.339259 -18.416324) (xy 423.339768 -18.44421)
			(xy 448.57619 -18.44421) (xy 448.580261 -18.388588) (xy 448.592387 -18.334151) (xy 448.61231 -18.28206)
			(xy 448.639606 -18.233425) (xy 448.673692 -18.189282) (xy 448.713841 -18.150573) (xy 448.759199 -18.118122)
			(xy 448.808799 -18.092621) (xy 448.861583 -18.074614) (xy 448.916426 -18.064484) (xy 448.97216 -18.062447)
			(xy 449.027597 -18.068547) (xy 449.081554 -18.082653) (xy 449.132883 -18.104465) (xy 449.180489 -18.133519)
			(xy 449.223357 -18.169194) (xy 449.260574 -18.210731) (xy 449.291347 -18.257244) (xy 449.315019 -18.307741)
			(xy 449.331087 -18.361148) (xy 449.339207 -18.416324) (xy 449.339716 -18.44421) (xy 449.339207 -18.472096)
			(xy 449.331087 -18.527272) (xy 449.315019 -18.580679) (xy 449.291347 -18.631176) (xy 449.260574 -18.677689)
			(xy 449.223357 -18.719226) (xy 449.180489 -18.754901) (xy 449.132883 -18.783955) (xy 449.081554 -18.805767)
			(xy 449.027597 -18.819873) (xy 448.97216 -18.825973) (xy 448.916426 -18.823936) (xy 448.861583 -18.813806)
			(xy 448.808799 -18.795799) (xy 448.759199 -18.770298) (xy 448.713841 -18.737847) (xy 448.673692 -18.699138)
			(xy 448.639606 -18.654995) (xy 448.61231 -18.60636) (xy 448.592387 -18.554269) (xy 448.580261 -18.499832)
			(xy 448.57619 -18.44421) (xy 423.339768 -18.44421) (xy 423.339259 -18.472096) (xy 423.331139 -18.527272)
			(xy 423.315071 -18.580679) (xy 423.291399 -18.631176) (xy 423.260626 -18.677689) (xy 423.223409 -18.719226)
			(xy 423.180541 -18.754901) (xy 423.132935 -18.783955) (xy 423.081606 -18.805767) (xy 423.027649 -18.819873)
			(xy 422.972212 -18.825973) (xy 422.916478 -18.823936) (xy 422.861635 -18.813806) (xy 422.808851 -18.795799)
			(xy 422.759251 -18.770298) (xy 422.713893 -18.737847) (xy 422.673744 -18.699138) (xy 422.639658 -18.654995)
			(xy 422.612362 -18.60636) (xy 422.592439 -18.554269) (xy 422.580313 -18.499832) (xy 422.576242 -18.44421)
			(xy 397.33982 -18.44421) (xy 397.339311 -18.472096) (xy 397.331191 -18.527272) (xy 397.315123 -18.580679)
			(xy 397.291451 -18.631176) (xy 397.260678 -18.677689) (xy 397.223461 -18.719226) (xy 397.180593 -18.754901)
			(xy 397.132987 -18.783955) (xy 397.081658 -18.805767) (xy 397.027701 -18.819873) (xy 396.972264 -18.825973)
			(xy 396.91653 -18.823936) (xy 396.861687 -18.813806) (xy 396.808903 -18.795799) (xy 396.759303 -18.770298)
			(xy 396.713945 -18.737847) (xy 396.673796 -18.699138) (xy 396.63971 -18.654995) (xy 396.612414 -18.60636)
			(xy 396.592491 -18.554269) (xy 396.580365 -18.499832) (xy 396.576294 -18.44421) (xy 371.339872 -18.44421)
			(xy 371.339363 -18.472096) (xy 371.331243 -18.527272) (xy 371.315175 -18.580679) (xy 371.291503 -18.631176)
			(xy 371.26073 -18.677689) (xy 371.223513 -18.719226) (xy 371.180645 -18.754901) (xy 371.133039 -18.783955)
			(xy 371.08171 -18.805767) (xy 371.027753 -18.819873) (xy 370.972316 -18.825973) (xy 370.916582 -18.823936)
			(xy 370.861739 -18.813806) (xy 370.808955 -18.795799) (xy 370.759355 -18.770298) (xy 370.713997 -18.737847)
			(xy 370.673848 -18.699138) (xy 370.639762 -18.654995) (xy 370.612466 -18.60636) (xy 370.592543 -18.554269)
			(xy 370.580417 -18.499832) (xy 370.576346 -18.44421) (xy 307.23967 -18.44421) (xy 307.239161 -18.472096)
			(xy 307.231041 -18.527272) (xy 307.214973 -18.580679) (xy 307.191301 -18.631176) (xy 307.160528 -18.677689)
			(xy 307.123311 -18.719226) (xy 307.080443 -18.754901) (xy 307.032837 -18.783955) (xy 306.981508 -18.805767)
			(xy 306.927551 -18.819873) (xy 306.872114 -18.825973) (xy 306.81638 -18.823936) (xy 306.761537 -18.813806)
			(xy 306.708753 -18.795799) (xy 306.659153 -18.770298) (xy 306.613795 -18.737847) (xy 306.573646 -18.699138)
			(xy 306.53956 -18.654995) (xy 306.512264 -18.60636) (xy 306.492341 -18.554269) (xy 306.480215 -18.499832)
			(xy 306.476144 -18.44421) (xy 281.239722 -18.44421) (xy 281.239213 -18.472096) (xy 281.231093 -18.527272)
			(xy 281.215025 -18.580679) (xy 281.191353 -18.631176) (xy 281.16058 -18.677689) (xy 281.123363 -18.719226)
			(xy 281.080495 -18.754901) (xy 281.032889 -18.783955) (xy 280.98156 -18.805767) (xy 280.927603 -18.819873)
			(xy 280.872166 -18.825973) (xy 280.816432 -18.823936) (xy 280.761589 -18.813806) (xy 280.708805 -18.795799)
			(xy 280.659205 -18.770298) (xy 280.613847 -18.737847) (xy 280.573698 -18.699138) (xy 280.539612 -18.654995)
			(xy 280.512316 -18.60636) (xy 280.492393 -18.554269) (xy 280.480267 -18.499832) (xy 280.476196 -18.44421)
			(xy 255.239774 -18.44421) (xy 255.239265 -18.472096) (xy 255.231145 -18.527272) (xy 255.215077 -18.580679)
			(xy 255.191405 -18.631176) (xy 255.160632 -18.677689) (xy 255.123415 -18.719226) (xy 255.080547 -18.754901)
			(xy 255.032941 -18.783955) (xy 254.981612 -18.805767) (xy 254.927655 -18.819873) (xy 254.872218 -18.825973)
			(xy 254.816484 -18.823936) (xy 254.761641 -18.813806) (xy 254.708857 -18.795799) (xy 254.659257 -18.770298)
			(xy 254.613899 -18.737847) (xy 254.57375 -18.699138) (xy 254.539664 -18.654995) (xy 254.512368 -18.60636)
			(xy 254.492445 -18.554269) (xy 254.480319 -18.499832) (xy 254.476248 -18.44421) (xy 217.139774 -18.44421)
			(xy 217.139265 -18.472096) (xy 217.131145 -18.527272) (xy 217.115077 -18.580679) (xy 217.091405 -18.631176)
			(xy 217.060632 -18.677689) (xy 217.023415 -18.719226) (xy 216.980547 -18.754901) (xy 216.932941 -18.783955)
			(xy 216.881612 -18.805767) (xy 216.827655 -18.819873) (xy 216.772218 -18.825973) (xy 216.716484 -18.823936)
			(xy 216.661641 -18.813806) (xy 216.608857 -18.795799) (xy 216.559257 -18.770298) (xy 216.513899 -18.737847)
			(xy 216.47375 -18.699138) (xy 216.439664 -18.654995) (xy 216.412368 -18.60636) (xy 216.392445 -18.554269)
			(xy 216.380319 -18.499832) (xy 216.376248 -18.44421) (xy 191.139826 -18.44421) (xy 191.139317 -18.472096)
			(xy 191.131197 -18.527272) (xy 191.115129 -18.580679) (xy 191.091457 -18.631176) (xy 191.060684 -18.677689)
			(xy 191.023467 -18.719226) (xy 190.980599 -18.754901) (xy 190.932993 -18.783955) (xy 190.881664 -18.805767)
			(xy 190.827707 -18.819873) (xy 190.77227 -18.825973) (xy 190.716536 -18.823936) (xy 190.661693 -18.813806)
			(xy 190.608909 -18.795799) (xy 190.559309 -18.770298) (xy 190.513951 -18.737847) (xy 190.473802 -18.699138)
			(xy 190.439716 -18.654995) (xy 190.41242 -18.60636) (xy 190.392497 -18.554269) (xy 190.380371 -18.499832)
			(xy 190.3763 -18.44421) (xy 165.139878 -18.44421) (xy 165.139369 -18.472096) (xy 165.131249 -18.527272)
			(xy 165.115181 -18.580679) (xy 165.091509 -18.631176) (xy 165.060736 -18.677689) (xy 165.023519 -18.719226)
			(xy 164.980651 -18.754901) (xy 164.933045 -18.783955) (xy 164.881716 -18.805767) (xy 164.827759 -18.819873)
			(xy 164.772322 -18.825973) (xy 164.716588 -18.823936) (xy 164.661745 -18.813806) (xy 164.608961 -18.795799)
			(xy 164.559361 -18.770298) (xy 164.514003 -18.737847) (xy 164.473854 -18.699138) (xy 164.439768 -18.654995)
			(xy 164.412472 -18.60636) (xy 164.392549 -18.554269) (xy 164.380423 -18.499832) (xy 164.376352 -18.44421)
			(xy 139.13993 -18.44421) (xy 139.139421 -18.472096) (xy 139.131301 -18.527272) (xy 139.115233 -18.580679)
			(xy 139.091561 -18.631176) (xy 139.060788 -18.677689) (xy 139.023571 -18.719226) (xy 138.980703 -18.754901)
			(xy 138.933097 -18.783955) (xy 138.881768 -18.805767) (xy 138.827811 -18.819873) (xy 138.772374 -18.825973)
			(xy 138.71664 -18.823936) (xy 138.661797 -18.813806) (xy 138.609013 -18.795799) (xy 138.559413 -18.770298)
			(xy 138.514055 -18.737847) (xy 138.473906 -18.699138) (xy 138.43982 -18.654995) (xy 138.412524 -18.60636)
			(xy 138.392601 -18.554269) (xy 138.380475 -18.499832) (xy 138.376404 -18.44421) (xy 75.039728 -18.44421)
			(xy 75.039219 -18.472096) (xy 75.031099 -18.527272) (xy 75.015031 -18.580679) (xy 74.991359 -18.631176)
			(xy 74.960586 -18.677689) (xy 74.923369 -18.719226) (xy 74.880501 -18.754901) (xy 74.832895 -18.783955)
			(xy 74.781566 -18.805767) (xy 74.727609 -18.819873) (xy 74.672172 -18.825973) (xy 74.616438 -18.823936)
			(xy 74.561595 -18.813806) (xy 74.508811 -18.795799) (xy 74.459211 -18.770298) (xy 74.413853 -18.737847)
			(xy 74.373704 -18.699138) (xy 74.339618 -18.654995) (xy 74.312322 -18.60636) (xy 74.292399 -18.554269)
			(xy 74.280273 -18.499832) (xy 74.276202 -18.44421) (xy 49.03978 -18.44421) (xy 49.039271 -18.472096)
			(xy 49.031151 -18.527272) (xy 49.015083 -18.580679) (xy 48.991411 -18.631176) (xy 48.960638 -18.677689)
			(xy 48.923421 -18.719226) (xy 48.880553 -18.754901) (xy 48.832947 -18.783955) (xy 48.781618 -18.805767)
			(xy 48.727661 -18.819873) (xy 48.672224 -18.825973) (xy 48.61649 -18.823936) (xy 48.561647 -18.813806)
			(xy 48.508863 -18.795799) (xy 48.459263 -18.770298) (xy 48.413905 -18.737847) (xy 48.373756 -18.699138)
			(xy 48.33967 -18.654995) (xy 48.312374 -18.60636) (xy 48.292451 -18.554269) (xy 48.280325 -18.499832)
			(xy 48.276254 -18.44421) (xy 0.715772 -18.44421) (xy 0.715772 -20.24888) (xy 2.414776 -20.24888)
			(xy 2.418847 -20.193258) (xy 2.430973 -20.138821) (xy 2.450896 -20.08673) (xy 2.478192 -20.038095)
			(xy 2.512278 -19.993952) (xy 2.552427 -19.955243) (xy 2.597785 -19.922792) (xy 2.647385 -19.897291)
			(xy 2.700169 -19.879284) (xy 2.755012 -19.869154) (xy 2.810746 -19.867117) (xy 2.866183 -19.873217)
			(xy 2.92014 -19.887323) (xy 2.971469 -19.909135) (xy 3.019075 -19.938189) (xy 3.061943 -19.973864)
			(xy 3.09916 -20.015401) (xy 3.129933 -20.061914) (xy 3.153605 -20.112411) (xy 3.169673 -20.165818)
			(xy 3.177793 -20.220994) (xy 3.178302 -20.24888) (xy 3.177793 -20.276766) (xy 3.169673 -20.331942)
			(xy 3.153605 -20.385349) (xy 3.129933 -20.435846) (xy 3.09916 -20.482359) (xy 3.061943 -20.523896)
			(xy 3.019075 -20.559571) (xy 2.971469 -20.588625) (xy 2.92014 -20.610437) (xy 2.866183 -20.624543)
			(xy 2.810746 -20.630643) (xy 2.755012 -20.628606) (xy 2.700169 -20.618476) (xy 2.647385 -20.600469)
			(xy 2.597785 -20.574968) (xy 2.552427 -20.542517) (xy 2.512278 -20.503808) (xy 2.478192 -20.459665)
			(xy 2.450896 -20.41103) (xy 2.430973 -20.358939) (xy 2.418847 -20.304502) (xy 2.414776 -20.24888)
			(xy 0.715772 -20.24888) (xy 0.715772 -20.72005) (xy 5.185422 -20.72005) (xy 5.189392 -20.589916)
			(xy 5.201288 -20.460266) (xy 5.221067 -20.331583) (xy 5.248653 -20.204344) (xy 5.283946 -20.079025)
			(xy 5.326812 -19.956089) (xy 5.377094 -19.835996) (xy 5.434603 -19.719192) (xy 5.499127 -19.60611)
			(xy 5.570424 -19.497173) (xy 5.648229 -19.392785) (xy 5.732254 -19.293334) (xy 5.822186 -19.199191)
			(xy 5.91769 -19.110706) (xy 6.01841 -19.028207) (xy 6.123972 -18.952002) (xy 6.233984 -18.882375)
			(xy 6.348036 -18.819584) (xy 6.465704 -18.763862) (xy 6.58655 -18.715418) (xy 6.710125 -18.674431)
			(xy 6.835968 -18.641054) (xy 6.963613 -18.615411) (xy 7.092583 -18.597597) (xy 7.222399 -18.587679)
			(xy 7.352578 -18.585694) (xy 7.482637 -18.591648) (xy 7.61209 -18.605521) (xy 7.740457 -18.627259)
			(xy 7.86726 -18.656783) (xy 7.992027 -18.693982) (xy 8.114294 -18.738718) (xy 8.233607 -18.790826)
			(xy 8.34952 -18.850109) (xy 8.461605 -18.91635) (xy 8.569442 -18.9893) (xy 8.672631 -19.068688) (xy 8.770789 -19.15422)
			(xy 8.86355 -19.245577) (xy 8.950569 -19.342419) (xy 9.031522 -19.444386) (xy 9.106108 -19.551098)
			(xy 9.174049 -19.662159) (xy 9.235094 -19.777155) (xy 9.289015 -19.895659) (xy 9.33561 -20.01723)
			(xy 9.374708 -20.141415) (xy 9.406162 -20.267753) (xy 9.429856 -20.395774) (xy 9.4457 -20.525) (xy 9.453638 -20.654953)
			(xy 9.454134 -20.72005) (xy 9.453638 -20.785147) (xy 9.4457 -20.9151) (xy 9.429856 -21.044326) (xy 9.406162 -21.172347)
			(xy 9.374708 -21.298685) (xy 9.33561 -21.42287) (xy 9.289015 -21.544441) (xy 9.245979 -21.639022)
			(xy 16.073882 -21.639022) (xy 16.074424 -21.610284) (xy 16.083043 -21.553458) (xy 16.100089 -21.498567)
			(xy 16.125176 -21.446855) (xy 16.157737 -21.399492) (xy 16.177006 -21.378164) (xy 16.18361 -21.371306)
			(xy 16.190722 -21.353272) (xy 16.190722 -21.264372) (xy 16.18361 -21.246338) (xy 16.177006 -21.23948)
			(xy 16.157758 -21.218134) (xy 16.125193 -21.170774) (xy 16.100102 -21.119065) (xy 16.083051 -21.064178)
			(xy 16.074427 -21.007354) (xy 16.074424 -20.949879) (xy 16.083044 -20.893053) (xy 16.10009 -20.838164)
			(xy 16.125177 -20.786454) (xy 16.157738 -20.739091) (xy 16.177006 -20.717764) (xy 16.18361 -20.710906)
			(xy 16.190722 -20.692872) (xy 16.190722 -20.603972) (xy 16.18361 -20.585938) (xy 16.177006 -20.57908)
			(xy 16.157758 -20.557734) (xy 16.125193 -20.510374) (xy 16.100102 -20.458665) (xy 16.083051 -20.403778)
			(xy 16.074427 -20.346954) (xy 16.074424 -20.289479) (xy 16.083044 -20.232653) (xy 16.10009 -20.177764)
			(xy 16.125177 -20.126054) (xy 16.157738 -20.078691) (xy 16.177006 -20.057364) (xy 16.18361 -20.050506)
			(xy 16.190722 -20.032472) (xy 16.190722 -19.943572) (xy 16.18361 -19.925538) (xy 16.177006 -19.91868)
			(xy 16.157758 -19.897334) (xy 16.125193 -19.849974) (xy 16.100102 -19.798265) (xy 16.083051 -19.743378)
			(xy 16.074427 -19.686554) (xy 16.074424 -19.629079) (xy 16.083044 -19.572253) (xy 16.10009 -19.517364)
			(xy 16.125177 -19.465654) (xy 16.157738 -19.418291) (xy 16.177006 -19.396964) (xy 16.18361 -19.390106)
			(xy 16.190722 -19.372072) (xy 16.190722 -19.283172) (xy 16.18361 -19.265138) (xy 16.177006 -19.25828)
			(xy 16.157757 -19.236934) (xy 16.125186 -19.189578) (xy 16.100088 -19.137872) (xy 16.083032 -19.082985)
			(xy 16.074405 -19.02616) (xy 16.073882 -18.997422) (xy 16.074368 -18.970171) (xy 16.082124 -18.916223)
			(xy 16.097479 -18.863928) (xy 16.120121 -18.814351) (xy 16.149587 -18.768501) (xy 16.185278 -18.72731)
			(xy 16.226469 -18.691619) (xy 16.272319 -18.662153) (xy 16.321896 -18.639511) (xy 16.374191 -18.624156)
			(xy 16.428139 -18.6164) (xy 16.482641 -18.6164) (xy 16.536589 -18.624156) (xy 16.588884 -18.639511)
			(xy 16.638461 -18.662153) (xy 16.684311 -18.691619) (xy 16.725502 -18.72731) (xy 16.761193 -18.768501)
			(xy 16.790659 -18.814351) (xy 16.813301 -18.863928) (xy 16.828656 -18.916223) (xy 16.836412 -18.970171)
			(xy 16.836898 -18.997422) (xy 16.836388 -19.026161) (xy 16.827762 -19.082989) (xy 16.810709 -19.13788)
			(xy 16.785614 -19.189592) (xy 16.753046 -19.236954) (xy 16.733774 -19.25828) (xy 16.72717 -19.265138)
			(xy 16.720058 -19.283172) (xy 16.720058 -19.372072) (xy 16.72717 -19.390106) (xy 16.733774 -19.396964)
			(xy 16.753067 -19.418272) (xy 16.785631 -19.465637) (xy 16.810722 -19.517352) (xy 16.82777 -19.572246)
			(xy 16.836391 -19.629076) (xy 16.836389 -19.686556) (xy 16.827763 -19.743385) (xy 16.81071 -19.798278)
			(xy 16.785615 -19.84999) (xy 16.753047 -19.897353) (xy 16.733774 -19.91868) (xy 16.72717 -19.925538)
			(xy 16.720058 -19.943572) (xy 16.720058 -20.032472) (xy 16.72717 -20.050506) (xy 16.733774 -20.057364)
			(xy 16.753067 -20.078672) (xy 16.785631 -20.126037) (xy 16.810722 -20.177752) (xy 16.82777 -20.232646)
			(xy 16.836391 -20.289476) (xy 16.836389 -20.346956) (xy 16.827763 -20.403785) (xy 16.81071 -20.458678)
			(xy 16.785615 -20.51039) (xy 16.753047 -20.557753) (xy 16.733774 -20.57908) (xy 16.72717 -20.585938)
			(xy 16.720058 -20.603972) (xy 16.720058 -20.692872) (xy 16.72717 -20.710906) (xy 16.733774 -20.717764)
			(xy 16.735844 -20.72005) (xy 31.18537 -20.72005) (xy 31.18934 -20.589916) (xy 31.201236 -20.460266)
			(xy 31.221015 -20.331583) (xy 31.248601 -20.204344) (xy 31.283894 -20.079025) (xy 31.32676 -19.956089)
			(xy 31.377042 -19.835996) (xy 31.434551 -19.719192) (xy 31.499075 -19.60611) (xy 31.570372 -19.497173)
			(xy 31.648177 -19.392785) (xy 31.732202 -19.293334) (xy 31.822134 -19.199191) (xy 31.917638 -19.110706)
			(xy 32.018358 -19.028207) (xy 32.12392 -18.952002) (xy 32.233932 -18.882375) (xy 32.347984 -18.819584)
			(xy 32.465652 -18.763862) (xy 32.586498 -18.715418) (xy 32.710073 -18.674431) (xy 32.835916 -18.641054)
			(xy 32.963561 -18.615411) (xy 33.092531 -18.597597) (xy 33.222347 -18.587679) (xy 33.352526 -18.585694)
			(xy 33.482585 -18.591648) (xy 33.612038 -18.605521) (xy 33.740405 -18.627259) (xy 33.867208 -18.656783)
			(xy 33.991975 -18.693982) (xy 34.114242 -18.738718) (xy 34.233555 -18.790826) (xy 34.349468 -18.850109)
			(xy 34.461553 -18.91635) (xy 34.56939 -18.9893) (xy 34.672579 -19.068688) (xy 34.770737 -19.15422)
			(xy 34.863498 -19.245577) (xy 34.950517 -19.342419) (xy 35.03147 -19.444386) (xy 35.106056 -19.551098)
			(xy 35.173997 -19.662159) (xy 35.235042 -19.777155) (xy 35.288963 -19.895659) (xy 35.335558 -20.01723)
			(xy 35.374656 -20.141415) (xy 35.40611 -20.267753) (xy 35.429804 -20.395774) (xy 35.445648 -20.525)
			(xy 35.453586 -20.654953) (xy 35.454082 -20.72005) (xy 35.453586 -20.785147) (xy 35.445648 -20.9151)
			(xy 35.429804 -21.044326) (xy 35.40611 -21.172347) (xy 35.374656 -21.298685) (xy 35.335558 -21.42287)
			(xy 35.288963 -21.544441) (xy 35.245927 -21.639022) (xy 42.07383 -21.639022) (xy 42.074386 -21.610285)
			(xy 42.083003 -21.553459) (xy 42.100047 -21.49857) (xy 42.125131 -21.446858) (xy 42.157688 -21.399493)
			(xy 42.176954 -21.378164) (xy 42.183558 -21.371306) (xy 42.19067 -21.353272) (xy 42.19067 -21.264372)
			(xy 42.183558 -21.246338) (xy 42.176954 -21.23948) (xy 42.157704 -21.218135) (xy 42.125135 -21.170777)
			(xy 42.10004 -21.119068) (xy 42.082987 -21.06418) (xy 42.074362 -21.007354) (xy 42.07436 -20.949878)
			(xy 42.08298 -20.893052) (xy 42.100029 -20.838162) (xy 42.125119 -20.786451) (xy 42.157683 -20.73909)
			(xy 42.176954 -20.717764) (xy 42.183558 -20.710906) (xy 42.19067 -20.692872) (xy 42.19067 -20.603972)
			(xy 42.183558 -20.585938) (xy 42.176954 -20.57908) (xy 42.157704 -20.557735) (xy 42.125135 -20.510377)
			(xy 42.10004 -20.458668) (xy 42.082987 -20.40378) (xy 42.074362 -20.346954) (xy 42.07436 -20.289478)
			(xy 42.08298 -20.232652) (xy 42.100029 -20.177762) (xy 42.125119 -20.126051) (xy 42.157683 -20.07869)
			(xy 42.176954 -20.057364) (xy 42.183558 -20.050506) (xy 42.19067 -20.032472) (xy 42.19067 -19.943572)
			(xy 42.183558 -19.925538) (xy 42.176954 -19.91868) (xy 42.157704 -19.897335) (xy 42.125135 -19.849977)
			(xy 42.10004 -19.798268) (xy 42.082987 -19.74338) (xy 42.074362 -19.686554) (xy 42.07436 -19.629078)
			(xy 42.08298 -19.572252) (xy 42.100029 -19.517362) (xy 42.125119 -19.465651) (xy 42.157683 -19.41829)
			(xy 42.176954 -19.396964) (xy 42.183558 -19.390106) (xy 42.19067 -19.372072) (xy 42.19067 -19.283172)
			(xy 42.183558 -19.265138) (xy 42.176954 -19.25828) (xy 42.157696 -19.236942) (xy 42.125128 -19.189583)
			(xy 42.100032 -19.137874) (xy 42.082979 -19.082986) (xy 42.074353 -19.02616) (xy 42.07383 -18.997422)
			(xy 42.074316 -18.970171) (xy 42.082072 -18.916223) (xy 42.097427 -18.863928) (xy 42.120069 -18.814351)
			(xy 42.149535 -18.768501) (xy 42.185226 -18.72731) (xy 42.226417 -18.691619) (xy 42.272267 -18.662153)
			(xy 42.321844 -18.639511) (xy 42.374139 -18.624156) (xy 42.428087 -18.6164) (xy 42.482589 -18.6164)
			(xy 42.536537 -18.624156) (xy 42.588832 -18.639511) (xy 42.638409 -18.662153) (xy 42.684259 -18.691619)
			(xy 42.72545 -18.72731) (xy 42.761141 -18.768501) (xy 42.790607 -18.814351) (xy 42.813249 -18.863928)
			(xy 42.828604 -18.916223) (xy 42.83636 -18.970171) (xy 42.836846 -18.997422) (xy 42.836323 -19.026161)
			(xy 42.827699 -19.082988) (xy 42.810648 -19.137878) (xy 42.785556 -19.18959) (xy 42.752992 -19.236953)
			(xy 42.733722 -19.25828) (xy 42.727118 -19.265138) (xy 42.720006 -19.283172) (xy 42.720006 -19.372072)
			(xy 42.727118 -19.390106) (xy 42.733722 -19.396964) (xy 42.753013 -19.418273) (xy 42.776952 -19.453098)
			(xy 48.276254 -19.453098) (xy 48.280325 -19.397476) (xy 48.292451 -19.343039) (xy 48.312374 -19.290948)
			(xy 48.33967 -19.242313) (xy 48.373756 -19.19817) (xy 48.413905 -19.159461) (xy 48.459263 -19.12701)
			(xy 48.508863 -19.101509) (xy 48.561647 -19.083502) (xy 48.61649 -19.073372) (xy 48.672224 -19.071335)
			(xy 48.727661 -19.077435) (xy 48.781618 -19.091541) (xy 48.832947 -19.113353) (xy 48.880553 -19.142407)
			(xy 48.923421 -19.178082) (xy 48.960638 -19.219619) (xy 48.991411 -19.266132) (xy 49.015083 -19.316629)
			(xy 49.031151 -19.370036) (xy 49.039271 -19.425212) (xy 49.03978 -19.453098) (xy 49.039271 -19.480984)
			(xy 49.031151 -19.53616) (xy 49.015083 -19.589567) (xy 48.991411 -19.640064) (xy 48.960638 -19.686577)
			(xy 48.923421 -19.728114) (xy 48.880553 -19.763789) (xy 48.832947 -19.792843) (xy 48.781618 -19.814655)
			(xy 48.727661 -19.828761) (xy 48.672224 -19.834861) (xy 48.61649 -19.832824) (xy 48.561647 -19.822694)
			(xy 48.508863 -19.804687) (xy 48.459263 -19.779186) (xy 48.413905 -19.746735) (xy 48.373756 -19.708026)
			(xy 48.33967 -19.663883) (xy 48.312374 -19.615248) (xy 48.292451 -19.563157) (xy 48.280325 -19.50872)
			(xy 48.276254 -19.453098) (xy 42.776952 -19.453098) (xy 42.785573 -19.46564) (xy 42.810661 -19.517355)
			(xy 42.827707 -19.572248) (xy 42.836326 -19.629077) (xy 42.836324 -19.686555) (xy 42.8277 -19.743384)
			(xy 42.810649 -19.798275) (xy 42.785557 -19.849988) (xy 42.752992 -19.897352) (xy 42.733722 -19.91868)
			(xy 42.727118 -19.925538) (xy 42.720006 -19.943572) (xy 42.720006 -20.032472) (xy 42.727118 -20.050506)
			(xy 42.733722 -20.057364) (xy 42.753013 -20.078673) (xy 42.785573 -20.12604) (xy 42.810661 -20.177755)
			(xy 42.827707 -20.232648) (xy 42.836326 -20.289477) (xy 42.836324 -20.346955) (xy 42.8277 -20.403784)
			(xy 42.810649 -20.458675) (xy 42.806331 -20.467574) (xy 50.287426 -20.467574) (xy 50.291497 -20.411952)
			(xy 50.303623 -20.357515) (xy 50.323546 -20.305424) (xy 50.350842 -20.256789) (xy 50.384928 -20.212646)
			(xy 50.425077 -20.173937) (xy 50.470435 -20.141486) (xy 50.520035 -20.115985) (xy 50.572819 -20.097978)
			(xy 50.627662 -20.087848) (xy 50.683396 -20.085811) (xy 50.738833 -20.091911) (xy 50.79279 -20.106017)
			(xy 50.844119 -20.127829) (xy 50.891725 -20.156883) (xy 50.934593 -20.192558) (xy 50.97181 -20.234095)
			(xy 51.002583 -20.280608) (xy 51.026255 -20.331105) (xy 51.042323 -20.384512) (xy 51.050443 -20.439688)
			(xy 51.050952 -20.467574) (xy 51.050443 -20.49546) (xy 51.042323 -20.550636) (xy 51.026255 -20.604043)
			(xy 51.002583 -20.65454) (xy 50.97181 -20.701053) (xy 50.954789 -20.72005) (xy 57.185318 -20.72005)
			(xy 57.189288 -20.589916) (xy 57.201184 -20.460266) (xy 57.220963 -20.331583) (xy 57.248549 -20.204344)
			(xy 57.283842 -20.079025) (xy 57.326708 -19.956089) (xy 57.37699 -19.835996) (xy 57.434499 -19.719192)
			(xy 57.499023 -19.60611) (xy 57.57032 -19.497173) (xy 57.648125 -19.392785) (xy 57.73215 -19.293334)
			(xy 57.822082 -19.199191) (xy 57.917586 -19.110706) (xy 58.018306 -19.028207) (xy 58.123868 -18.952002)
			(xy 58.23388 -18.882375) (xy 58.347932 -18.819584) (xy 58.4656 -18.763862) (xy 58.586446 -18.715418)
			(xy 58.710021 -18.674431) (xy 58.835864 -18.641054) (xy 58.963509 -18.615411) (xy 59.092479 -18.597597)
			(xy 59.222295 -18.587679) (xy 59.352474 -18.585694) (xy 59.482533 -18.591648) (xy 59.611986 -18.605521)
			(xy 59.740353 -18.627259) (xy 59.867156 -18.656783) (xy 59.991923 -18.693982) (xy 60.11419 -18.738718)
			(xy 60.233503 -18.790826) (xy 60.349416 -18.850109) (xy 60.461501 -18.91635) (xy 60.569338 -18.9893)
			(xy 60.672527 -19.068688) (xy 60.770685 -19.15422) (xy 60.863446 -19.245577) (xy 60.950465 -19.342419)
			(xy 61.031418 -19.444386) (xy 61.106004 -19.551098) (xy 61.173945 -19.662159) (xy 61.23499 -19.777155)
			(xy 61.288911 -19.895659) (xy 61.335506 -20.01723) (xy 61.374604 -20.141415) (xy 61.406058 -20.267753)
			(xy 61.429752 -20.395774) (xy 61.445596 -20.525) (xy 61.453534 -20.654953) (xy 61.45403 -20.72005)
			(xy 61.453534 -20.785147) (xy 61.445596 -20.9151) (xy 61.429752 -21.044326) (xy 61.406058 -21.172347)
			(xy 61.374604 -21.298685) (xy 61.335506 -21.42287) (xy 61.288911 -21.544441) (xy 61.245875 -21.639022)
			(xy 68.073778 -21.639022) (xy 68.074321 -21.610284) (xy 68.08294 -21.553458) (xy 68.099986 -21.498567)
			(xy 68.125073 -21.446855) (xy 68.157633 -21.399492) (xy 68.176902 -21.378164) (xy 68.183506 -21.371306)
			(xy 68.190618 -21.353272) (xy 68.190618 -21.264372) (xy 68.183506 -21.246338) (xy 68.176902 -21.23948)
			(xy 68.157654 -21.218134) (xy 68.12509 -21.170774) (xy 68.099999 -21.119065) (xy 68.082948 -21.064178)
			(xy 68.074324 -21.007354) (xy 68.074321 -20.949879) (xy 68.082941 -20.893054) (xy 68.099987 -20.838165)
			(xy 68.125074 -20.786454) (xy 68.157634 -20.739091) (xy 68.176902 -20.717764) (xy 68.183506 -20.710906)
			(xy 68.190618 -20.692872) (xy 68.190618 -20.603972) (xy 68.183506 -20.585938) (xy 68.176902 -20.57908)
			(xy 68.157654 -20.557734) (xy 68.12509 -20.510374) (xy 68.099999 -20.458665) (xy 68.082948 -20.403778)
			(xy 68.074324 -20.346954) (xy 68.074321 -20.289479) (xy 68.082941 -20.232654) (xy 68.099987 -20.177765)
			(xy 68.125074 -20.126054) (xy 68.157634 -20.078691) (xy 68.176902 -20.057364) (xy 68.183506 -20.050506)
			(xy 68.190618 -20.032472) (xy 68.190618 -19.943572) (xy 68.183506 -19.925538) (xy 68.176902 -19.91868)
			(xy 68.157654 -19.897334) (xy 68.12509 -19.849974) (xy 68.099999 -19.798265) (xy 68.082948 -19.743378)
			(xy 68.074324 -19.686554) (xy 68.074321 -19.629079) (xy 68.082941 -19.572254) (xy 68.099987 -19.517365)
			(xy 68.125074 -19.465654) (xy 68.157634 -19.418291) (xy 68.176902 -19.396964) (xy 68.183506 -19.390106)
			(xy 68.190618 -19.372072) (xy 68.190618 -19.283172) (xy 68.183506 -19.265138) (xy 68.176902 -19.25828)
			(xy 68.157653 -19.236934) (xy 68.125081 -19.189578) (xy 68.099984 -19.137872) (xy 68.082928 -19.082985)
			(xy 68.074301 -19.02616) (xy 68.073778 -18.997422) (xy 68.074264 -18.970171) (xy 68.08202 -18.916223)
			(xy 68.097375 -18.863928) (xy 68.120017 -18.814351) (xy 68.149483 -18.768501) (xy 68.185174 -18.72731)
			(xy 68.226365 -18.691619) (xy 68.272215 -18.662153) (xy 68.321792 -18.639511) (xy 68.374087 -18.624156)
			(xy 68.428035 -18.6164) (xy 68.482537 -18.6164) (xy 68.536485 -18.624156) (xy 68.58878 -18.639511)
			(xy 68.638357 -18.662153) (xy 68.684207 -18.691619) (xy 68.725398 -18.72731) (xy 68.761089 -18.768501)
			(xy 68.790555 -18.814351) (xy 68.813197 -18.863928) (xy 68.828552 -18.916223) (xy 68.836308 -18.970171)
			(xy 68.836794 -18.997422) (xy 68.836285 -19.026161) (xy 68.827659 -19.08299) (xy 68.810606 -19.137881)
			(xy 68.785511 -19.189592) (xy 68.752942 -19.236954) (xy 68.73367 -19.25828) (xy 68.727066 -19.265138)
			(xy 68.719954 -19.283172) (xy 68.719954 -19.372072) (xy 68.727066 -19.390106) (xy 68.73367 -19.396964)
			(xy 68.752963 -19.418272) (xy 68.776907 -19.453098) (xy 74.276202 -19.453098) (xy 74.280273 -19.397476)
			(xy 74.292399 -19.343039) (xy 74.312322 -19.290948) (xy 74.339618 -19.242313) (xy 74.373704 -19.19817)
			(xy 74.413853 -19.159461) (xy 74.459211 -19.12701) (xy 74.508811 -19.101509) (xy 74.561595 -19.083502)
			(xy 74.616438 -19.073372) (xy 74.672172 -19.071335) (xy 74.727609 -19.077435) (xy 74.781566 -19.091541)
			(xy 74.832895 -19.113353) (xy 74.880501 -19.142407) (xy 74.923369 -19.178082) (xy 74.960586 -19.219619)
			(xy 74.991359 -19.266132) (xy 75.015031 -19.316629) (xy 75.031099 -19.370036) (xy 75.039219 -19.425212)
			(xy 75.039728 -19.453098) (xy 75.039219 -19.480984) (xy 75.031099 -19.53616) (xy 75.015031 -19.589567)
			(xy 74.991359 -19.640064) (xy 74.960586 -19.686577) (xy 74.923369 -19.728114) (xy 74.880501 -19.763789)
			(xy 74.832895 -19.792843) (xy 74.781566 -19.814655) (xy 74.727609 -19.828761) (xy 74.672172 -19.834861)
			(xy 74.616438 -19.832824) (xy 74.561595 -19.822694) (xy 74.508811 -19.804687) (xy 74.459211 -19.779186)
			(xy 74.413853 -19.746735) (xy 74.373704 -19.708026) (xy 74.339618 -19.663883) (xy 74.312322 -19.615248)
			(xy 74.292399 -19.563157) (xy 74.280273 -19.50872) (xy 74.276202 -19.453098) (xy 68.776907 -19.453098)
			(xy 68.785528 -19.465637) (xy 68.810619 -19.517352) (xy 68.827667 -19.572246) (xy 68.836288 -19.629076)
			(xy 68.836286 -19.686556) (xy 68.82766 -19.743386) (xy 68.810607 -19.798278) (xy 68.785512 -19.849991)
			(xy 68.752943 -19.897353) (xy 68.73367 -19.91868) (xy 68.727066 -19.925538) (xy 68.719954 -19.943572)
			(xy 68.719954 -20.032472) (xy 68.727066 -20.050506) (xy 68.73367 -20.057364) (xy 68.752963 -20.078672)
			(xy 68.785528 -20.126037) (xy 68.810619 -20.177752) (xy 68.827667 -20.232646) (xy 68.836288 -20.289476)
			(xy 68.836286 -20.346956) (xy 68.82766 -20.403786) (xy 68.810607 -20.458678) (xy 68.80629 -20.467574)
			(xy 76.287374 -20.467574) (xy 76.291445 -20.411952) (xy 76.303571 -20.357515) (xy 76.323494 -20.305424)
			(xy 76.35079 -20.256789) (xy 76.384876 -20.212646) (xy 76.425025 -20.173937) (xy 76.470383 -20.141486)
			(xy 76.519983 -20.115985) (xy 76.572767 -20.097978) (xy 76.62761 -20.087848) (xy 76.683344 -20.085811)
			(xy 76.738781 -20.091911) (xy 76.792738 -20.106017) (xy 76.844067 -20.127829) (xy 76.891673 -20.156883)
			(xy 76.934541 -20.192558) (xy 76.971758 -20.234095) (xy 77.002531 -20.280608) (xy 77.026203 -20.331105)
			(xy 77.042271 -20.384512) (xy 77.050391 -20.439688) (xy 77.0509 -20.467574) (xy 77.050391 -20.49546)
			(xy 77.042271 -20.550636) (xy 77.026203 -20.604043) (xy 77.002531 -20.65454) (xy 76.971758 -20.701053)
			(xy 76.954737 -20.72005) (xy 83.18552 -20.72005) (xy 83.18949 -20.589916) (xy 83.201386 -20.460266)
			(xy 83.221165 -20.331583) (xy 83.248751 -20.204344) (xy 83.284044 -20.079025) (xy 83.32691 -19.956089)
			(xy 83.377192 -19.835996) (xy 83.434701 -19.719192) (xy 83.499225 -19.60611) (xy 83.570522 -19.497173)
			(xy 83.648327 -19.392785) (xy 83.732352 -19.293334) (xy 83.822284 -19.199191) (xy 83.917788 -19.110706)
			(xy 84.018508 -19.028207) (xy 84.12407 -18.952002) (xy 84.234082 -18.882375) (xy 84.348134 -18.819584)
			(xy 84.465802 -18.763862) (xy 84.586648 -18.715418) (xy 84.710223 -18.674431) (xy 84.836066 -18.641054)
			(xy 84.963711 -18.615411) (xy 85.092681 -18.597597) (xy 85.222497 -18.587679) (xy 85.352676 -18.585694)
			(xy 85.482735 -18.591648) (xy 85.612188 -18.605521) (xy 85.740555 -18.627259) (xy 85.867358 -18.656783)
			(xy 85.992125 -18.693982) (xy 86.114392 -18.738718) (xy 86.233705 -18.790826) (xy 86.349618 -18.850109)
			(xy 86.461703 -18.91635) (xy 86.56954 -18.9893) (xy 86.672729 -19.068688) (xy 86.770887 -19.15422)
			(xy 86.863648 -19.245577) (xy 86.950667 -19.342419) (xy 87.03162 -19.444386) (xy 87.106206 -19.551098)
			(xy 87.174147 -19.662159) (xy 87.235192 -19.777155) (xy 87.289113 -19.895659) (xy 87.335708 -20.01723)
			(xy 87.374806 -20.141415) (xy 87.40626 -20.267753) (xy 87.429954 -20.395774) (xy 87.445798 -20.525)
			(xy 87.453736 -20.654953) (xy 87.454232 -20.72005) (xy 87.453736 -20.785147) (xy 87.445798 -20.9151)
			(xy 87.429954 -21.044326) (xy 87.40626 -21.172347) (xy 87.374806 -21.298685) (xy 87.335708 -21.42287)
			(xy 87.289113 -21.544441) (xy 87.246077 -21.639022) (xy 94.073726 -21.639022) (xy 94.074283 -21.610285)
			(xy 94.0829 -21.55346) (xy 94.099944 -21.49857) (xy 94.125027 -21.446858) (xy 94.157584 -21.399493)
			(xy 94.17685 -21.378164) (xy 94.183454 -21.371306) (xy 94.190566 -21.353272) (xy 94.190566 -21.264372)
			(xy 94.183454 -21.246338) (xy 94.17685 -21.23948) (xy 94.1576 -21.218135) (xy 94.125032 -21.170776)
			(xy 94.099937 -21.119068) (xy 94.082884 -21.064179) (xy 94.074259 -21.007354) (xy 94.074257 -20.949878)
			(xy 94.082877 -20.893052) (xy 94.099925 -20.838162) (xy 94.125016 -20.786451) (xy 94.15758 -20.73909)
			(xy 94.17685 -20.717764) (xy 94.183454 -20.710906) (xy 94.190566 -20.692872) (xy 94.190566 -20.603972)
			(xy 94.183454 -20.585938) (xy 94.17685 -20.57908) (xy 94.1576 -20.557735) (xy 94.125032 -20.510376)
			(xy 94.099937 -20.458668) (xy 94.082884 -20.403779) (xy 94.074259 -20.346954) (xy 94.074257 -20.289478)
			(xy 94.082877 -20.232652) (xy 94.099925 -20.177762) (xy 94.125016 -20.126051) (xy 94.15758 -20.07869)
			(xy 94.17685 -20.057364) (xy 94.183454 -20.050506) (xy 94.190566 -20.032472) (xy 94.190566 -19.943572)
			(xy 94.183454 -19.925538) (xy 94.17685 -19.91868) (xy 94.1576 -19.897335) (xy 94.125032 -19.849976)
			(xy 94.099937 -19.798268) (xy 94.082884 -19.743379) (xy 94.074259 -19.686554) (xy 94.074257 -19.629078)
			(xy 94.082877 -19.572252) (xy 94.099925 -19.517362) (xy 94.125016 -19.465651) (xy 94.15758 -19.41829)
			(xy 94.17685 -19.396964) (xy 94.183454 -19.390106) (xy 94.190566 -19.372072) (xy 94.190566 -19.283172)
			(xy 94.183454 -19.265138) (xy 94.17685 -19.25828) (xy 94.157592 -19.236942) (xy 94.125023 -19.189583)
			(xy 94.099928 -19.137874) (xy 94.082875 -19.082986) (xy 94.074249 -19.02616) (xy 94.073726 -18.997422)
			(xy 94.074212 -18.970171) (xy 94.081968 -18.916223) (xy 94.097323 -18.863928) (xy 94.119965 -18.814351)
			(xy 94.149431 -18.768501) (xy 94.185122 -18.72731) (xy 94.226313 -18.691619) (xy 94.272163 -18.662153)
			(xy 94.32174 -18.639511) (xy 94.374035 -18.624156) (xy 94.427983 -18.6164) (xy 94.482485 -18.6164)
			(xy 94.536433 -18.624156) (xy 94.588728 -18.639511) (xy 94.638305 -18.662153) (xy 94.684155 -18.691619)
			(xy 94.725346 -18.72731) (xy 94.761037 -18.768501) (xy 94.790503 -18.814351) (xy 94.813145 -18.863928)
			(xy 94.8285 -18.916223) (xy 94.836256 -18.970171) (xy 94.836742 -18.997422) (xy 94.83622 -19.026161)
			(xy 94.827596 -19.082988) (xy 94.810544 -19.137878) (xy 94.785453 -19.18959) (xy 94.752888 -19.236953)
			(xy 94.733618 -19.25828) (xy 94.727014 -19.265138) (xy 94.719902 -19.283172) (xy 94.719902 -19.372072)
			(xy 94.727014 -19.390106) (xy 94.733618 -19.396964) (xy 94.752909 -19.418273) (xy 94.78547 -19.46564)
			(xy 94.810557 -19.517355) (xy 94.827604 -19.572248) (xy 94.836223 -19.629077) (xy 94.836221 -19.686555)
			(xy 94.827597 -19.743384) (xy 94.810545 -19.798275) (xy 94.785454 -19.849988) (xy 94.752889 -19.897352)
			(xy 94.733618 -19.91868) (xy 94.727014 -19.925538) (xy 94.719902 -19.943572) (xy 94.719902 -20.032472)
			(xy 94.727014 -20.050506) (xy 94.733618 -20.057364) (xy 94.752909 -20.078673) (xy 94.78547 -20.12604)
			(xy 94.810557 -20.177755) (xy 94.827604 -20.232648) (xy 94.836223 -20.289477) (xy 94.836221 -20.346955)
			(xy 94.827597 -20.403784) (xy 94.810545 -20.458675) (xy 94.785454 -20.510388) (xy 94.752889 -20.557752)
			(xy 94.733618 -20.57908) (xy 94.727014 -20.585938) (xy 94.719902 -20.603972) (xy 94.719902 -20.692872)
			(xy 94.727014 -20.710906) (xy 94.733618 -20.717764) (xy 94.740286 -20.72513) (xy 121.28044 -20.72513)
			(xy 121.28441 -20.594996) (xy 121.296306 -20.465346) (xy 121.316085 -20.336663) (xy 121.343671 -20.209424)
			(xy 121.378964 -20.084105) (xy 121.42183 -19.961169) (xy 121.472112 -19.841076) (xy 121.529621 -19.724272)
			(xy 121.594145 -19.61119) (xy 121.665442 -19.502253) (xy 121.743247 -19.397865) (xy 121.827272 -19.298414)
			(xy 121.917204 -19.204271) (xy 122.012708 -19.115786) (xy 122.113428 -19.033287) (xy 122.21899 -18.957082)
			(xy 122.329002 -18.887455) (xy 122.443054 -18.824664) (xy 122.560722 -18.768942) (xy 122.681568 -18.720498)
			(xy 122.805143 -18.679511) (xy 122.930986 -18.646134) (xy 123.058631 -18.620491) (xy 123.187601 -18.602677)
			(xy 123.317417 -18.592759) (xy 123.447596 -18.590774) (xy 123.577655 -18.596728) (xy 123.707108 -18.610601)
			(xy 123.835475 -18.632339) (xy 123.962278 -18.661863) (xy 124.087045 -18.699062) (xy 124.209312 -18.743798)
			(xy 124.328625 -18.795906) (xy 124.444538 -18.855189) (xy 124.556623 -18.92143) (xy 124.66446 -18.99438)
			(xy 124.767649 -19.073768) (xy 124.865807 -19.1593) (xy 124.958568 -19.250657) (xy 125.045587 -19.347499)
			(xy 125.12654 -19.449466) (xy 125.201126 -19.556178) (xy 125.269067 -19.667239) (xy 125.330112 -19.782235)
			(xy 125.384033 -19.900739) (xy 125.430628 -20.02231) (xy 125.469726 -20.146495) (xy 125.50118 -20.272833)
			(xy 125.524874 -20.400854) (xy 125.540718 -20.53008) (xy 125.548656 -20.660033) (xy 125.549152 -20.72513)
			(xy 125.548656 -20.790227) (xy 125.540718 -20.92018) (xy 125.524874 -21.049406) (xy 125.50118 -21.177427)
			(xy 125.469726 -21.303765) (xy 125.430628 -21.42795) (xy 125.384033 -21.549521) (xy 125.343309 -21.639022)
			(xy 132.17398 -21.639022) (xy 132.174522 -21.610284) (xy 132.183141 -21.553458) (xy 132.200187 -21.498567)
			(xy 132.225275 -21.446855) (xy 132.257835 -21.399492) (xy 132.277104 -21.378164) (xy 132.283708 -21.371306)
			(xy 132.29082 -21.353272) (xy 132.29082 -21.264372) (xy 132.283708 -21.246338) (xy 132.277104 -21.23948)
			(xy 132.257856 -21.218134) (xy 132.225292 -21.170774) (xy 132.2002 -21.119065) (xy 132.183149 -21.064178)
			(xy 132.174525 -21.007354) (xy 132.174523 -20.949879) (xy 132.183142 -20.893054) (xy 132.200188 -20.838165)
			(xy 132.225275 -20.786454) (xy 132.257836 -20.739091) (xy 132.277104 -20.717764) (xy 132.283708 -20.710906)
			(xy 132.29082 -20.692872) (xy 132.29082 -20.603972) (xy 132.283708 -20.585938) (xy 132.277104 -20.57908)
			(xy 132.257856 -20.557734) (xy 132.225292 -20.510374) (xy 132.2002 -20.458665) (xy 132.183149 -20.403778)
			(xy 132.174525 -20.346954) (xy 132.174523 -20.289479) (xy 132.183142 -20.232654) (xy 132.200188 -20.177765)
			(xy 132.225275 -20.126054) (xy 132.257836 -20.078691) (xy 132.277104 -20.057364) (xy 132.283708 -20.050506)
			(xy 132.29082 -20.032472) (xy 132.29082 -19.943572) (xy 132.283708 -19.925538) (xy 132.277104 -19.91868)
			(xy 132.257856 -19.897334) (xy 132.225292 -19.849974) (xy 132.2002 -19.798265) (xy 132.183149 -19.743378)
			(xy 132.174525 -19.686554) (xy 132.174523 -19.629079) (xy 132.183142 -19.572254) (xy 132.200188 -19.517365)
			(xy 132.225275 -19.465654) (xy 132.257836 -19.418291) (xy 132.277104 -19.396964) (xy 132.283708 -19.390106)
			(xy 132.29082 -19.372072) (xy 132.29082 -19.283172) (xy 132.283708 -19.265138) (xy 132.277104 -19.25828)
			(xy 132.257855 -19.236934) (xy 132.225283 -19.189578) (xy 132.200186 -19.137872) (xy 132.18313 -19.082985)
			(xy 132.174503 -19.02616) (xy 132.17398 -18.997422) (xy 132.174466 -18.970171) (xy 132.182222 -18.916223)
			(xy 132.197577 -18.863928) (xy 132.220219 -18.814351) (xy 132.249685 -18.768501) (xy 132.285376 -18.72731)
			(xy 132.326567 -18.691619) (xy 132.372417 -18.662153) (xy 132.421994 -18.639511) (xy 132.474289 -18.624156)
			(xy 132.528237 -18.6164) (xy 132.582739 -18.6164) (xy 132.636687 -18.624156) (xy 132.688982 -18.639511)
			(xy 132.738559 -18.662153) (xy 132.784409 -18.691619) (xy 132.8256 -18.72731) (xy 132.861291 -18.768501)
			(xy 132.890757 -18.814351) (xy 132.913399 -18.863928) (xy 132.928754 -18.916223) (xy 132.93651 -18.970171)
			(xy 132.936996 -18.997422) (xy 132.936487 -19.026161) (xy 132.927861 -19.082989) (xy 132.910807 -19.13788)
			(xy 132.885713 -19.189592) (xy 132.853144 -19.236954) (xy 132.833872 -19.25828) (xy 132.827268 -19.265138)
			(xy 132.820156 -19.283172) (xy 132.820156 -19.372072) (xy 132.827268 -19.390106) (xy 132.833872 -19.396964)
			(xy 132.853165 -19.418272) (xy 132.877109 -19.453098) (xy 138.376404 -19.453098) (xy 138.380475 -19.397476)
			(xy 138.392601 -19.343039) (xy 138.412524 -19.290948) (xy 138.43982 -19.242313) (xy 138.473906 -19.19817)
			(xy 138.514055 -19.159461) (xy 138.559413 -19.12701) (xy 138.609013 -19.101509) (xy 138.661797 -19.083502)
			(xy 138.71664 -19.073372) (xy 138.772374 -19.071335) (xy 138.827811 -19.077435) (xy 138.881768 -19.091541)
			(xy 138.933097 -19.113353) (xy 138.980703 -19.142407) (xy 139.023571 -19.178082) (xy 139.060788 -19.219619)
			(xy 139.091561 -19.266132) (xy 139.115233 -19.316629) (xy 139.131301 -19.370036) (xy 139.139421 -19.425212)
			(xy 139.13993 -19.453098) (xy 139.139421 -19.480984) (xy 139.131301 -19.53616) (xy 139.115233 -19.589567)
			(xy 139.091561 -19.640064) (xy 139.060788 -19.686577) (xy 139.023571 -19.728114) (xy 138.980703 -19.763789)
			(xy 138.933097 -19.792843) (xy 138.881768 -19.814655) (xy 138.827811 -19.828761) (xy 138.772374 -19.834861)
			(xy 138.71664 -19.832824) (xy 138.661797 -19.822694) (xy 138.609013 -19.804687) (xy 138.559413 -19.779186)
			(xy 138.514055 -19.746735) (xy 138.473906 -19.708026) (xy 138.43982 -19.663883) (xy 138.412524 -19.615248)
			(xy 138.392601 -19.563157) (xy 138.380475 -19.50872) (xy 138.376404 -19.453098) (xy 132.877109 -19.453098)
			(xy 132.88573 -19.465637) (xy 132.91082 -19.517352) (xy 132.927869 -19.572246) (xy 132.93649 -19.629076)
			(xy 132.936487 -19.686556) (xy 132.927862 -19.743385) (xy 132.910808 -19.798278) (xy 132.885713 -19.84999)
			(xy 132.853145 -19.897353) (xy 132.833872 -19.91868) (xy 132.827268 -19.925538) (xy 132.820156 -19.943572)
			(xy 132.820156 -20.032472) (xy 132.827268 -20.050506) (xy 132.833872 -20.057364) (xy 132.853165 -20.078672)
			(xy 132.88573 -20.126037) (xy 132.91082 -20.177752) (xy 132.927869 -20.232646) (xy 132.93649 -20.289476)
			(xy 132.936487 -20.346956) (xy 132.927862 -20.403785) (xy 132.910808 -20.458678) (xy 132.906491 -20.467574)
			(xy 140.387576 -20.467574) (xy 140.391647 -20.411952) (xy 140.403773 -20.357515) (xy 140.423696 -20.305424)
			(xy 140.450992 -20.256789) (xy 140.485078 -20.212646) (xy 140.525227 -20.173937) (xy 140.570585 -20.141486)
			(xy 140.620185 -20.115985) (xy 140.672969 -20.097978) (xy 140.727812 -20.087848) (xy 140.783546 -20.085811)
			(xy 140.838983 -20.091911) (xy 140.89294 -20.106017) (xy 140.944269 -20.127829) (xy 140.991875 -20.156883)
			(xy 141.034743 -20.192558) (xy 141.07196 -20.234095) (xy 141.102733 -20.280608) (xy 141.126405 -20.331105)
			(xy 141.142473 -20.384512) (xy 141.150593 -20.439688) (xy 141.151102 -20.467574) (xy 141.150593 -20.49546)
			(xy 141.142473 -20.550636) (xy 141.126405 -20.604043) (xy 141.102733 -20.65454) (xy 141.07196 -20.701053)
			(xy 141.050615 -20.724876) (xy 147.280388 -20.724876) (xy 147.284358 -20.594742) (xy 147.296254 -20.465092)
			(xy 147.316033 -20.336409) (xy 147.343619 -20.20917) (xy 147.378912 -20.083851) (xy 147.421778 -19.960915)
			(xy 147.47206 -19.840822) (xy 147.529569 -19.724018) (xy 147.594093 -19.610936) (xy 147.66539 -19.501999)
			(xy 147.743195 -19.397611) (xy 147.82722 -19.29816) (xy 147.917152 -19.204017) (xy 148.012656 -19.115532)
			(xy 148.113376 -19.033033) (xy 148.218938 -18.956828) (xy 148.32895 -18.887201) (xy 148.443002 -18.82441)
			(xy 148.56067 -18.768688) (xy 148.681516 -18.720244) (xy 148.805091 -18.679257) (xy 148.930934 -18.64588)
			(xy 149.058579 -18.620237) (xy 149.187549 -18.602423) (xy 149.317365 -18.592505) (xy 149.447544 -18.59052)
			(xy 149.577603 -18.596474) (xy 149.707056 -18.610347) (xy 149.835423 -18.632085) (xy 149.962226 -18.661609)
			(xy 150.086993 -18.698808) (xy 150.20926 -18.743544) (xy 150.328573 -18.795652) (xy 150.444486 -18.854935)
			(xy 150.556571 -18.921176) (xy 150.664408 -18.994126) (xy 150.767597 -19.073514) (xy 150.865755 -19.159046)
			(xy 150.958516 -19.250403) (xy 151.045535 -19.347245) (xy 151.126488 -19.449212) (xy 151.201074 -19.555924)
			(xy 151.269015 -19.666985) (xy 151.33006 -19.781981) (xy 151.383981 -19.900485) (xy 151.430576 -20.022056)
			(xy 151.469674 -20.146241) (xy 151.501128 -20.272579) (xy 151.524822 -20.4006) (xy 151.540666 -20.529826)
			(xy 151.548604 -20.659779) (xy 151.5491 -20.724876) (xy 151.548604 -20.789973) (xy 151.540666 -20.919926)
			(xy 151.524822 -21.049152) (xy 151.501128 -21.177173) (xy 151.469674 -21.303511) (xy 151.430576 -21.427696)
			(xy 151.383981 -21.549267) (xy 151.343141 -21.639022) (xy 158.173928 -21.639022) (xy 158.174484 -21.610285)
			(xy 158.183102 -21.55346) (xy 158.200145 -21.49857) (xy 158.225229 -21.446858) (xy 158.257786 -21.399493)
			(xy 158.277052 -21.378164) (xy 158.283656 -21.371306) (xy 158.290768 -21.353272) (xy 158.290768 -21.264372)
			(xy 158.283656 -21.246338) (xy 158.277052 -21.23948) (xy 158.257802 -21.218135) (xy 158.225233 -21.170776)
			(xy 158.200139 -21.119068) (xy 158.183086 -21.06418) (xy 158.17446 -21.007354) (xy 158.174458 -20.949878)
			(xy 158.183079 -20.893052) (xy 158.200127 -20.838162) (xy 158.225217 -20.786451) (xy 158.257782 -20.73909)
			(xy 158.277052 -20.717764) (xy 158.283656 -20.710906) (xy 158.290768 -20.692872) (xy 158.290768 -20.603972)
			(xy 158.283656 -20.585938) (xy 158.277052 -20.57908) (xy 158.257802 -20.557735) (xy 158.225233 -20.510376)
			(xy 158.200139 -20.458668) (xy 158.183086 -20.40378) (xy 158.17446 -20.346954) (xy 158.174458 -20.289478)
			(xy 158.183079 -20.232652) (xy 158.200127 -20.177762) (xy 158.225217 -20.126051) (xy 158.257782 -20.07869)
			(xy 158.277052 -20.057364) (xy 158.283656 -20.050506) (xy 158.290768 -20.032472) (xy 158.290768 -19.943572)
			(xy 158.283656 -19.925538) (xy 158.277052 -19.91868) (xy 158.257802 -19.897335) (xy 158.225233 -19.849976)
			(xy 158.200139 -19.798268) (xy 158.183086 -19.74338) (xy 158.17446 -19.686554) (xy 158.174458 -19.629078)
			(xy 158.183079 -19.572252) (xy 158.200127 -19.517362) (xy 158.225217 -19.465651) (xy 158.257782 -19.41829)
			(xy 158.277052 -19.396964) (xy 158.283656 -19.390106) (xy 158.290768 -19.372072) (xy 158.290768 -19.283172)
			(xy 158.283656 -19.265138) (xy 158.277052 -19.25828) (xy 158.257794 -19.236942) (xy 158.225225 -19.189583)
			(xy 158.20013 -19.137874) (xy 158.183077 -19.082986) (xy 158.174451 -19.02616) (xy 158.173928 -18.997422)
			(xy 158.174414 -18.970171) (xy 158.18217 -18.916223) (xy 158.197525 -18.863928) (xy 158.220167 -18.814351)
			(xy 158.249633 -18.768501) (xy 158.285324 -18.72731) (xy 158.326515 -18.691619) (xy 158.372365 -18.662153)
			(xy 158.421942 -18.639511) (xy 158.474237 -18.624156) (xy 158.528185 -18.6164) (xy 158.582687 -18.6164)
			(xy 158.636635 -18.624156) (xy 158.68893 -18.639511) (xy 158.738507 -18.662153) (xy 158.784357 -18.691619)
			(xy 158.825548 -18.72731) (xy 158.861239 -18.768501) (xy 158.890705 -18.814351) (xy 158.913347 -18.863928)
			(xy 158.928702 -18.916223) (xy 158.936458 -18.970171) (xy 158.936944 -18.997422) (xy 158.936422 -19.026161)
			(xy 158.927797 -19.082988) (xy 158.910746 -19.137878) (xy 158.885654 -19.18959) (xy 158.85309 -19.236953)
			(xy 158.83382 -19.25828) (xy 158.827216 -19.265138) (xy 158.820104 -19.283172) (xy 158.820104 -19.372072)
			(xy 158.827216 -19.390106) (xy 158.83382 -19.396964) (xy 158.853111 -19.418273) (xy 158.87705 -19.453098)
			(xy 164.376352 -19.453098) (xy 164.380423 -19.397476) (xy 164.392549 -19.343039) (xy 164.412472 -19.290948)
			(xy 164.439768 -19.242313) (xy 164.473854 -19.19817) (xy 164.514003 -19.159461) (xy 164.559361 -19.12701)
			(xy 164.608961 -19.101509) (xy 164.661745 -19.083502) (xy 164.716588 -19.073372) (xy 164.772322 -19.071335)
			(xy 164.827759 -19.077435) (xy 164.881716 -19.091541) (xy 164.933045 -19.113353) (xy 164.980651 -19.142407)
			(xy 165.023519 -19.178082) (xy 165.060736 -19.219619) (xy 165.091509 -19.266132) (xy 165.115181 -19.316629)
			(xy 165.131249 -19.370036) (xy 165.139369 -19.425212) (xy 165.139878 -19.453098) (xy 165.139369 -19.480984)
			(xy 165.131249 -19.53616) (xy 165.115181 -19.589567) (xy 165.091509 -19.640064) (xy 165.060736 -19.686577)
			(xy 165.023519 -19.728114) (xy 164.980651 -19.763789) (xy 164.933045 -19.792843) (xy 164.881716 -19.814655)
			(xy 164.827759 -19.828761) (xy 164.772322 -19.834861) (xy 164.716588 -19.832824) (xy 164.661745 -19.822694)
			(xy 164.608961 -19.804687) (xy 164.559361 -19.779186) (xy 164.514003 -19.746735) (xy 164.473854 -19.708026)
			(xy 164.439768 -19.663883) (xy 164.412472 -19.615248) (xy 164.392549 -19.563157) (xy 164.380423 -19.50872)
			(xy 164.376352 -19.453098) (xy 158.87705 -19.453098) (xy 158.885671 -19.46564) (xy 158.910759 -19.517355)
			(xy 158.927805 -19.572248) (xy 158.936425 -19.629077) (xy 158.936422 -19.686555) (xy 158.927798 -19.743384)
			(xy 158.910747 -19.798275) (xy 158.885655 -19.849988) (xy 158.85309 -19.897352) (xy 158.83382 -19.91868)
			(xy 158.827216 -19.925538) (xy 158.820104 -19.943572) (xy 158.820104 -20.032472) (xy 158.827216 -20.050506)
			(xy 158.83382 -20.057364) (xy 158.853111 -20.078673) (xy 158.885671 -20.12604) (xy 158.910759 -20.177755)
			(xy 158.927805 -20.232648) (xy 158.936425 -20.289477) (xy 158.936422 -20.346955) (xy 158.927798 -20.403784)
			(xy 158.910747 -20.458675) (xy 158.906429 -20.467574) (xy 166.387524 -20.467574) (xy 166.391595 -20.411952)
			(xy 166.403721 -20.357515) (xy 166.423644 -20.305424) (xy 166.45094 -20.256789) (xy 166.485026 -20.212646)
			(xy 166.525175 -20.173937) (xy 166.570533 -20.141486) (xy 166.620133 -20.115985) (xy 166.672917 -20.097978)
			(xy 166.72776 -20.087848) (xy 166.783494 -20.085811) (xy 166.838931 -20.091911) (xy 166.892888 -20.106017)
			(xy 166.944217 -20.127829) (xy 166.991823 -20.156883) (xy 167.034691 -20.192558) (xy 167.071908 -20.234095)
			(xy 167.102681 -20.280608) (xy 167.126353 -20.331105) (xy 167.142421 -20.384512) (xy 167.150541 -20.439688)
			(xy 167.15105 -20.467574) (xy 167.150541 -20.49546) (xy 167.142421 -20.550636) (xy 167.126353 -20.604043)
			(xy 167.102681 -20.65454) (xy 167.071908 -20.701053) (xy 167.050335 -20.72513) (xy 173.28059 -20.72513)
			(xy 173.28456 -20.594996) (xy 173.296456 -20.465346) (xy 173.316235 -20.336663) (xy 173.343821 -20.209424)
			(xy 173.379114 -20.084105) (xy 173.42198 -19.961169) (xy 173.472262 -19.841076) (xy 173.529771 -19.724272)
			(xy 173.594295 -19.61119) (xy 173.665592 -19.502253) (xy 173.743397 -19.397865) (xy 173.827422 -19.298414)
			(xy 173.917354 -19.204271) (xy 174.012858 -19.115786) (xy 174.113578 -19.033287) (xy 174.21914 -18.957082)
			(xy 174.329152 -18.887455) (xy 174.443204 -18.824664) (xy 174.560872 -18.768942) (xy 174.681718 -18.720498)
			(xy 174.805293 -18.679511) (xy 174.931136 -18.646134) (xy 175.058781 -18.620491) (xy 175.187751 -18.602677)
			(xy 175.317567 -18.592759) (xy 175.447746 -18.590774) (xy 175.577805 -18.596728) (xy 175.707258 -18.610601)
			(xy 175.835625 -18.632339) (xy 175.962428 -18.661863) (xy 176.087195 -18.699062) (xy 176.209462 -18.743798)
			(xy 176.328775 -18.795906) (xy 176.444688 -18.855189) (xy 176.556773 -18.92143) (xy 176.66461 -18.99438)
			(xy 176.767799 -19.073768) (xy 176.865957 -19.1593) (xy 176.958718 -19.250657) (xy 177.045737 -19.347499)
			(xy 177.12669 -19.449466) (xy 177.201276 -19.556178) (xy 177.269217 -19.667239) (xy 177.330262 -19.782235)
			(xy 177.384183 -19.900739) (xy 177.430778 -20.02231) (xy 177.469876 -20.146495) (xy 177.50133 -20.272833)
			(xy 177.525024 -20.400854) (xy 177.540868 -20.53008) (xy 177.548806 -20.660033) (xy 177.549302 -20.72513)
			(xy 177.548806 -20.790227) (xy 177.540868 -20.92018) (xy 177.525024 -21.049406) (xy 177.50133 -21.177427)
			(xy 177.469876 -21.303765) (xy 177.430778 -21.42795) (xy 177.384183 -21.549521) (xy 177.343459 -21.639022)
			(xy 184.173876 -21.639022) (xy 184.17442 -21.610284) (xy 184.183038 -21.553458) (xy 184.200084 -21.498567)
			(xy 184.225171 -21.446855) (xy 184.257732 -21.399492) (xy 184.277 -21.378164) (xy 184.283604 -21.371306)
			(xy 184.290716 -21.353272) (xy 184.290716 -21.264372) (xy 184.283604 -21.246338) (xy 184.277 -21.23948)
			(xy 184.257752 -21.218134) (xy 184.225188 -21.170774) (xy 184.200097 -21.119065) (xy 184.183046 -21.064178)
			(xy 184.174422 -21.007353) (xy 184.17442 -20.949879) (xy 184.183039 -20.893054) (xy 184.200085 -20.838165)
			(xy 184.225172 -20.786454) (xy 184.257732 -20.739091) (xy 184.277 -20.717764) (xy 184.283604 -20.710906)
			(xy 184.290716 -20.692872) (xy 184.290716 -20.603972) (xy 184.283604 -20.585938) (xy 184.277 -20.57908)
			(xy 184.257752 -20.557734) (xy 184.225188 -20.510374) (xy 184.200097 -20.458665) (xy 184.183046 -20.403778)
			(xy 184.174422 -20.346953) (xy 184.17442 -20.289479) (xy 184.183039 -20.232654) (xy 184.200085 -20.177765)
			(xy 184.225172 -20.126054) (xy 184.257732 -20.078691) (xy 184.277 -20.057364) (xy 184.283604 -20.050506)
			(xy 184.290716 -20.032472) (xy 184.290716 -19.943572) (xy 184.283604 -19.925538) (xy 184.277 -19.91868)
			(xy 184.257752 -19.897334) (xy 184.225188 -19.849974) (xy 184.200097 -19.798265) (xy 184.183046 -19.743378)
			(xy 184.174422 -19.686553) (xy 184.17442 -19.629079) (xy 184.183039 -19.572254) (xy 184.200085 -19.517365)
			(xy 184.225172 -19.465654) (xy 184.257732 -19.418291) (xy 184.277 -19.396964) (xy 184.283604 -19.390106)
			(xy 184.290716 -19.372072) (xy 184.290716 -19.283172) (xy 184.283604 -19.265138) (xy 184.277 -19.25828)
			(xy 184.25775 -19.236935) (xy 184.225179 -19.189579) (xy 184.200081 -19.137872) (xy 184.183026 -19.082985)
			(xy 184.174399 -19.02616) (xy 184.173876 -18.997422) (xy 184.174362 -18.970171) (xy 184.182118 -18.916223)
			(xy 184.197473 -18.863928) (xy 184.220115 -18.814351) (xy 184.249581 -18.768501) (xy 184.285272 -18.72731)
			(xy 184.326463 -18.691619) (xy 184.372313 -18.662153) (xy 184.42189 -18.639511) (xy 184.474185 -18.624156)
			(xy 184.528133 -18.6164) (xy 184.582635 -18.6164) (xy 184.636583 -18.624156) (xy 184.688878 -18.639511)
			(xy 184.738455 -18.662153) (xy 184.784305 -18.691619) (xy 184.825496 -18.72731) (xy 184.861187 -18.768501)
			(xy 184.890653 -18.814351) (xy 184.913295 -18.863928) (xy 184.92865 -18.916223) (xy 184.936406 -18.970171)
			(xy 184.936892 -18.997422) (xy 184.936384 -19.026162) (xy 184.927758 -19.08299) (xy 184.910704 -19.137881)
			(xy 184.885609 -19.189592) (xy 184.85304 -19.236954) (xy 184.833768 -19.25828) (xy 184.827164 -19.265138)
			(xy 184.820052 -19.283172) (xy 184.820052 -19.372072) (xy 184.827164 -19.390106) (xy 184.833768 -19.396964)
			(xy 184.853061 -19.418272) (xy 184.877005 -19.453098) (xy 190.3763 -19.453098) (xy 190.380371 -19.397476)
			(xy 190.392497 -19.343039) (xy 190.41242 -19.290948) (xy 190.439716 -19.242313) (xy 190.473802 -19.19817)
			(xy 190.513951 -19.159461) (xy 190.559309 -19.12701) (xy 190.608909 -19.101509) (xy 190.661693 -19.083502)
			(xy 190.716536 -19.073372) (xy 190.77227 -19.071335) (xy 190.827707 -19.077435) (xy 190.881664 -19.091541)
			(xy 190.932993 -19.113353) (xy 190.980599 -19.142407) (xy 191.023467 -19.178082) (xy 191.060684 -19.219619)
			(xy 191.091457 -19.266132) (xy 191.115129 -19.316629) (xy 191.131197 -19.370036) (xy 191.139317 -19.425212)
			(xy 191.139826 -19.453098) (xy 191.139317 -19.480984) (xy 191.131197 -19.53616) (xy 191.115129 -19.589567)
			(xy 191.091457 -19.640064) (xy 191.060684 -19.686577) (xy 191.023467 -19.728114) (xy 190.980599 -19.763789)
			(xy 190.932993 -19.792843) (xy 190.881664 -19.814655) (xy 190.827707 -19.828761) (xy 190.77227 -19.834861)
			(xy 190.716536 -19.832824) (xy 190.661693 -19.822694) (xy 190.608909 -19.804687) (xy 190.559309 -19.779186)
			(xy 190.513951 -19.746735) (xy 190.473802 -19.708026) (xy 190.439716 -19.663883) (xy 190.41242 -19.615248)
			(xy 190.392497 -19.563157) (xy 190.380371 -19.50872) (xy 190.3763 -19.453098) (xy 184.877005 -19.453098)
			(xy 184.885626 -19.465637) (xy 184.910717 -19.517352) (xy 184.927766 -19.572246) (xy 184.936387 -19.629076)
			(xy 184.936384 -19.686556) (xy 184.927759 -19.743386) (xy 184.910705 -19.798278) (xy 184.88561 -19.849991)
			(xy 184.853041 -19.897353) (xy 184.833768 -19.91868) (xy 184.827164 -19.925538) (xy 184.820052 -19.943572)
			(xy 184.820052 -20.032472) (xy 184.827164 -20.050506) (xy 184.833768 -20.057364) (xy 184.853061 -20.078672)
			(xy 184.885626 -20.126037) (xy 184.910717 -20.177752) (xy 184.927766 -20.232646) (xy 184.936387 -20.289476)
			(xy 184.936384 -20.346956) (xy 184.927759 -20.403786) (xy 184.910705 -20.458678) (xy 184.906388 -20.467574)
			(xy 192.387472 -20.467574) (xy 192.391543 -20.411952) (xy 192.403669 -20.357515) (xy 192.423592 -20.305424)
			(xy 192.450888 -20.256789) (xy 192.484974 -20.212646) (xy 192.525123 -20.173937) (xy 192.570481 -20.141486)
			(xy 192.620081 -20.115985) (xy 192.672865 -20.097978) (xy 192.727708 -20.087848) (xy 192.783442 -20.085811)
			(xy 192.838879 -20.091911) (xy 192.892836 -20.106017) (xy 192.944165 -20.127829) (xy 192.991771 -20.156883)
			(xy 193.034639 -20.192558) (xy 193.071856 -20.234095) (xy 193.102629 -20.280608) (xy 193.126301 -20.331105)
			(xy 193.142369 -20.384512) (xy 193.150489 -20.439688) (xy 193.150998 -20.467574) (xy 193.150489 -20.49546)
			(xy 193.142369 -20.550636) (xy 193.126301 -20.604043) (xy 193.102629 -20.65454) (xy 193.071856 -20.701053)
			(xy 193.050283 -20.72513) (xy 199.280538 -20.72513) (xy 199.284508 -20.594996) (xy 199.296404 -20.465346)
			(xy 199.316183 -20.336663) (xy 199.343769 -20.209424) (xy 199.379062 -20.084105) (xy 199.421928 -19.961169)
			(xy 199.47221 -19.841076) (xy 199.529719 -19.724272) (xy 199.594243 -19.61119) (xy 199.66554 -19.502253)
			(xy 199.743345 -19.397865) (xy 199.82737 -19.298414) (xy 199.917302 -19.204271) (xy 200.012806 -19.115786)
			(xy 200.113526 -19.033287) (xy 200.219088 -18.957082) (xy 200.3291 -18.887455) (xy 200.443152 -18.824664)
			(xy 200.56082 -18.768942) (xy 200.681666 -18.720498) (xy 200.805241 -18.679511) (xy 200.931084 -18.646134)
			(xy 201.058729 -18.620491) (xy 201.187699 -18.602677) (xy 201.317515 -18.592759) (xy 201.447694 -18.590774)
			(xy 201.577753 -18.596728) (xy 201.707206 -18.610601) (xy 201.835573 -18.632339) (xy 201.962376 -18.661863)
			(xy 202.087143 -18.699062) (xy 202.20941 -18.743798) (xy 202.328723 -18.795906) (xy 202.444636 -18.855189)
			(xy 202.556721 -18.92143) (xy 202.664558 -18.99438) (xy 202.767747 -19.073768) (xy 202.865905 -19.1593)
			(xy 202.958666 -19.250657) (xy 203.045685 -19.347499) (xy 203.126638 -19.449466) (xy 203.201224 -19.556178)
			(xy 203.269165 -19.667239) (xy 203.33021 -19.782235) (xy 203.384131 -19.900739) (xy 203.430726 -20.02231)
			(xy 203.469824 -20.146495) (xy 203.501278 -20.272833) (xy 203.524972 -20.400854) (xy 203.540816 -20.53008)
			(xy 203.548754 -20.660033) (xy 203.54925 -20.72513) (xy 203.548754 -20.790227) (xy 203.540816 -20.92018)
			(xy 203.524972 -21.049406) (xy 203.501278 -21.177427) (xy 203.469824 -21.303765) (xy 203.430726 -21.42795)
			(xy 203.384131 -21.549521) (xy 203.343407 -21.639022) (xy 210.173824 -21.639022) (xy 210.174381 -21.610285)
			(xy 210.182999 -21.55346) (xy 210.200042 -21.49857) (xy 210.225126 -21.446858) (xy 210.257682 -21.399493)
			(xy 210.276948 -21.378164) (xy 210.283552 -21.371306) (xy 210.290664 -21.353272) (xy 210.290664 -21.264372)
			(xy 210.283552 -21.246338) (xy 210.276948 -21.23948) (xy 210.257698 -21.218135) (xy 210.22513 -21.170776)
			(xy 210.200036 -21.119068) (xy 210.182983 -21.064179) (xy 210.174358 -21.007354) (xy 210.174355 -20.949878)
			(xy 210.182976 -20.893052) (xy 210.200024 -20.838162) (xy 210.225114 -20.786452) (xy 210.257678 -20.73909)
			(xy 210.276948 -20.717764) (xy 210.283552 -20.710906) (xy 210.290664 -20.692872) (xy 210.290664 -20.603972)
			(xy 210.283552 -20.585938) (xy 210.276948 -20.57908) (xy 210.257698 -20.557735) (xy 210.22513 -20.510376)
			(xy 210.200036 -20.458668) (xy 210.182983 -20.403779) (xy 210.174358 -20.346954) (xy 210.174355 -20.289478)
			(xy 210.182976 -20.232652) (xy 210.200024 -20.177762) (xy 210.225114 -20.126052) (xy 210.257678 -20.07869)
			(xy 210.276948 -20.057364) (xy 210.283552 -20.050506) (xy 210.290664 -20.032472) (xy 210.290664 -19.943572)
			(xy 210.283552 -19.925538) (xy 210.276948 -19.91868) (xy 210.257698 -19.897335) (xy 210.22513 -19.849976)
			(xy 210.200036 -19.798268) (xy 210.182983 -19.743379) (xy 210.174358 -19.686554) (xy 210.174355 -19.629078)
			(xy 210.182976 -19.572252) (xy 210.200024 -19.517362) (xy 210.225114 -19.465652) (xy 210.257678 -19.41829)
			(xy 210.276948 -19.396964) (xy 210.283552 -19.390106) (xy 210.290664 -19.372072) (xy 210.290664 -19.283172)
			(xy 210.283552 -19.265138) (xy 210.276948 -19.25828) (xy 210.257689 -19.236942) (xy 210.225121 -19.189584)
			(xy 210.200026 -19.137875) (xy 210.182973 -19.082986) (xy 210.174347 -19.02616) (xy 210.173824 -18.997422)
			(xy 210.17431 -18.970171) (xy 210.182066 -18.916223) (xy 210.197421 -18.863928) (xy 210.220063 -18.814351)
			(xy 210.249529 -18.768501) (xy 210.28522 -18.72731) (xy 210.326411 -18.691619) (xy 210.372261 -18.662153)
			(xy 210.421838 -18.639511) (xy 210.474133 -18.624156) (xy 210.528081 -18.6164) (xy 210.582583 -18.6164)
			(xy 210.636531 -18.624156) (xy 210.688826 -18.639511) (xy 210.738403 -18.662153) (xy 210.784253 -18.691619)
			(xy 210.825444 -18.72731) (xy 210.861135 -18.768501) (xy 210.890601 -18.814351) (xy 210.913243 -18.863928)
			(xy 210.928598 -18.916223) (xy 210.936354 -18.970171) (xy 210.93684 -18.997422) (xy 210.936319 -19.026161)
			(xy 210.927694 -19.082988) (xy 210.910643 -19.137878) (xy 210.885551 -19.18959) (xy 210.852986 -19.236953)
			(xy 210.833716 -19.25828) (xy 210.827112 -19.265138) (xy 210.82 -19.283172) (xy 210.82 -19.372072)
			(xy 210.827112 -19.390106) (xy 210.833716 -19.396964) (xy 210.853007 -19.418273) (xy 210.876947 -19.453098)
			(xy 216.376248 -19.453098) (xy 216.380319 -19.397476) (xy 216.392445 -19.343039) (xy 216.412368 -19.290948)
			(xy 216.439664 -19.242313) (xy 216.47375 -19.19817) (xy 216.513899 -19.159461) (xy 216.559257 -19.12701)
			(xy 216.608857 -19.101509) (xy 216.661641 -19.083502) (xy 216.716484 -19.073372) (xy 216.772218 -19.071335)
			(xy 216.827655 -19.077435) (xy 216.881612 -19.091541) (xy 216.932941 -19.113353) (xy 216.980547 -19.142407)
			(xy 217.023415 -19.178082) (xy 217.060632 -19.219619) (xy 217.091405 -19.266132) (xy 217.115077 -19.316629)
			(xy 217.131145 -19.370036) (xy 217.139265 -19.425212) (xy 217.139774 -19.453098) (xy 217.139265 -19.480984)
			(xy 217.131145 -19.53616) (xy 217.115077 -19.589567) (xy 217.091405 -19.640064) (xy 217.060632 -19.686577)
			(xy 217.023415 -19.728114) (xy 216.980547 -19.763789) (xy 216.932941 -19.792843) (xy 216.881612 -19.814655)
			(xy 216.827655 -19.828761) (xy 216.772218 -19.834861) (xy 216.716484 -19.832824) (xy 216.661641 -19.822694)
			(xy 216.608857 -19.804687) (xy 216.559257 -19.779186) (xy 216.513899 -19.746735) (xy 216.47375 -19.708026)
			(xy 216.439664 -19.663883) (xy 216.412368 -19.615248) (xy 216.392445 -19.563157) (xy 216.380319 -19.50872)
			(xy 216.376248 -19.453098) (xy 210.876947 -19.453098) (xy 210.885568 -19.465639) (xy 210.910656 -19.517354)
			(xy 210.927702 -19.572248) (xy 210.936322 -19.629077) (xy 210.936319 -19.686556) (xy 210.927695 -19.743384)
			(xy 210.910644 -19.798275) (xy 210.885552 -19.849988) (xy 210.852987 -19.897352) (xy 210.833716 -19.91868)
			(xy 210.827112 -19.925538) (xy 210.82 -19.943572) (xy 210.82 -20.032472) (xy 210.827112 -20.050506)
			(xy 210.833716 -20.057364) (xy 210.853007 -20.078673) (xy 210.885568 -20.126039) (xy 210.910656 -20.177754)
			(xy 210.927702 -20.232648) (xy 210.936322 -20.289477) (xy 210.936319 -20.346956) (xy 210.927695 -20.403784)
			(xy 210.910644 -20.458675) (xy 210.906326 -20.467574) (xy 218.38742 -20.467574) (xy 218.391491 -20.411952)
			(xy 218.403617 -20.357515) (xy 218.42354 -20.305424) (xy 218.450836 -20.256789) (xy 218.484922 -20.212646)
			(xy 218.525071 -20.173937) (xy 218.570429 -20.141486) (xy 218.620029 -20.115985) (xy 218.672813 -20.097978)
			(xy 218.727656 -20.087848) (xy 218.78339 -20.085811) (xy 218.838827 -20.091911) (xy 218.892784 -20.106017)
			(xy 218.944113 -20.127829) (xy 218.991719 -20.156883) (xy 219.034587 -20.192558) (xy 219.071804 -20.234095)
			(xy 219.102577 -20.280608) (xy 219.126249 -20.331105) (xy 219.142317 -20.384512) (xy 219.150437 -20.439688)
			(xy 219.150946 -20.467574) (xy 219.150437 -20.49546) (xy 219.142317 -20.550636) (xy 219.126249 -20.604043)
			(xy 219.102577 -20.65454) (xy 219.071804 -20.701053) (xy 219.050231 -20.72513) (xy 237.380538 -20.72513)
			(xy 237.384508 -20.594996) (xy 237.396404 -20.465346) (xy 237.416183 -20.336663) (xy 237.443769 -20.209424)
			(xy 237.479062 -20.084105) (xy 237.521928 -19.961169) (xy 237.57221 -19.841076) (xy 237.629719 -19.724272)
			(xy 237.694243 -19.61119) (xy 237.76554 -19.502253) (xy 237.843345 -19.397865) (xy 237.92737 -19.298414)
			(xy 238.017302 -19.204271) (xy 238.112806 -19.115786) (xy 238.213526 -19.033287) (xy 238.319088 -18.957082)
			(xy 238.4291 -18.887455) (xy 238.543152 -18.824664) (xy 238.66082 -18.768942) (xy 238.781666 -18.720498)
			(xy 238.905241 -18.679511) (xy 239.031084 -18.646134) (xy 239.158729 -18.620491) (xy 239.287699 -18.602677)
			(xy 239.417515 -18.592759) (xy 239.547694 -18.590774) (xy 239.677753 -18.596728) (xy 239.807206 -18.610601)
			(xy 239.935573 -18.632339) (xy 240.062376 -18.661863) (xy 240.187143 -18.699062) (xy 240.30941 -18.743798)
			(xy 240.428723 -18.795906) (xy 240.544636 -18.855189) (xy 240.656721 -18.92143) (xy 240.764558 -18.99438)
			(xy 240.867747 -19.073768) (xy 240.965905 -19.1593) (xy 241.058666 -19.250657) (xy 241.145685 -19.347499)
			(xy 241.226638 -19.449466) (xy 241.301224 -19.556178) (xy 241.369165 -19.667239) (xy 241.43021 -19.782235)
			(xy 241.484131 -19.900739) (xy 241.530726 -20.02231) (xy 241.569824 -20.146495) (xy 241.601278 -20.272833)
			(xy 241.624972 -20.400854) (xy 241.640816 -20.53008) (xy 241.648754 -20.660033) (xy 241.64925 -20.72513)
			(xy 241.648754 -20.790227) (xy 241.640816 -20.92018) (xy 241.624972 -21.049406) (xy 241.601278 -21.177427)
			(xy 241.569824 -21.303765) (xy 241.530726 -21.42795) (xy 241.484131 -21.549521) (xy 241.443407 -21.639022)
			(xy 248.273824 -21.639022) (xy 248.274381 -21.610285) (xy 248.282999 -21.55346) (xy 248.300042 -21.49857)
			(xy 248.325126 -21.446858) (xy 248.357682 -21.399493) (xy 248.376948 -21.378164) (xy 248.383552 -21.371306)
			(xy 248.390664 -21.353272) (xy 248.390664 -21.264372) (xy 248.383552 -21.246338) (xy 248.376948 -21.23948)
			(xy 248.357698 -21.218135) (xy 248.32513 -21.170776) (xy 248.300036 -21.119068) (xy 248.282983 -21.064179)
			(xy 248.274358 -21.007354) (xy 248.274355 -20.949878) (xy 248.282976 -20.893052) (xy 248.300024 -20.838162)
			(xy 248.325114 -20.786452) (xy 248.357678 -20.73909) (xy 248.376948 -20.717764) (xy 248.383552 -20.710906)
			(xy 248.390664 -20.692872) (xy 248.390664 -20.603972) (xy 248.383552 -20.585938) (xy 248.376948 -20.57908)
			(xy 248.357698 -20.557735) (xy 248.32513 -20.510376) (xy 248.300036 -20.458668) (xy 248.282983 -20.403779)
			(xy 248.274358 -20.346954) (xy 248.274355 -20.289478) (xy 248.282976 -20.232652) (xy 248.300024 -20.177762)
			(xy 248.325114 -20.126052) (xy 248.357678 -20.07869) (xy 248.376948 -20.057364) (xy 248.383552 -20.050506)
			(xy 248.390664 -20.032472) (xy 248.390664 -19.943572) (xy 248.383552 -19.925538) (xy 248.376948 -19.91868)
			(xy 248.357698 -19.897335) (xy 248.32513 -19.849976) (xy 248.300036 -19.798268) (xy 248.282983 -19.743379)
			(xy 248.274358 -19.686554) (xy 248.274355 -19.629078) (xy 248.282976 -19.572252) (xy 248.300024 -19.517362)
			(xy 248.325114 -19.465652) (xy 248.357678 -19.41829) (xy 248.376948 -19.396964) (xy 248.383552 -19.390106)
			(xy 248.390664 -19.372072) (xy 248.390664 -19.283172) (xy 248.383552 -19.265138) (xy 248.376948 -19.25828)
			(xy 248.357689 -19.236942) (xy 248.325121 -19.189584) (xy 248.300026 -19.137875) (xy 248.282973 -19.082986)
			(xy 248.274347 -19.02616) (xy 248.273824 -18.997422) (xy 248.27431 -18.970171) (xy 248.282066 -18.916223)
			(xy 248.297421 -18.863928) (xy 248.320063 -18.814351) (xy 248.349529 -18.768501) (xy 248.38522 -18.72731)
			(xy 248.426411 -18.691619) (xy 248.472261 -18.662153) (xy 248.521838 -18.639511) (xy 248.574133 -18.624156)
			(xy 248.628081 -18.6164) (xy 248.682583 -18.6164) (xy 248.736531 -18.624156) (xy 248.788826 -18.639511)
			(xy 248.838403 -18.662153) (xy 248.884253 -18.691619) (xy 248.925444 -18.72731) (xy 248.961135 -18.768501)
			(xy 248.990601 -18.814351) (xy 249.013243 -18.863928) (xy 249.028598 -18.916223) (xy 249.036354 -18.970171)
			(xy 249.03684 -18.997422) (xy 249.036319 -19.026161) (xy 249.027694 -19.082988) (xy 249.010643 -19.137878)
			(xy 248.985551 -19.18959) (xy 248.952986 -19.236953) (xy 248.933716 -19.25828) (xy 248.927112 -19.265138)
			(xy 248.92 -19.283172) (xy 248.92 -19.372072) (xy 248.927112 -19.390106) (xy 248.933716 -19.396964)
			(xy 248.953007 -19.418273) (xy 248.976947 -19.453098) (xy 254.476248 -19.453098) (xy 254.480319 -19.397476)
			(xy 254.492445 -19.343039) (xy 254.512368 -19.290948) (xy 254.539664 -19.242313) (xy 254.57375 -19.19817)
			(xy 254.613899 -19.159461) (xy 254.659257 -19.12701) (xy 254.708857 -19.101509) (xy 254.761641 -19.083502)
			(xy 254.816484 -19.073372) (xy 254.872218 -19.071335) (xy 254.927655 -19.077435) (xy 254.981612 -19.091541)
			(xy 255.032941 -19.113353) (xy 255.080547 -19.142407) (xy 255.123415 -19.178082) (xy 255.160632 -19.219619)
			(xy 255.191405 -19.266132) (xy 255.215077 -19.316629) (xy 255.231145 -19.370036) (xy 255.239265 -19.425212)
			(xy 255.239774 -19.453098) (xy 255.239265 -19.480984) (xy 255.231145 -19.53616) (xy 255.215077 -19.589567)
			(xy 255.191405 -19.640064) (xy 255.160632 -19.686577) (xy 255.123415 -19.728114) (xy 255.080547 -19.763789)
			(xy 255.032941 -19.792843) (xy 254.981612 -19.814655) (xy 254.927655 -19.828761) (xy 254.872218 -19.834861)
			(xy 254.816484 -19.832824) (xy 254.761641 -19.822694) (xy 254.708857 -19.804687) (xy 254.659257 -19.779186)
			(xy 254.613899 -19.746735) (xy 254.57375 -19.708026) (xy 254.539664 -19.663883) (xy 254.512368 -19.615248)
			(xy 254.492445 -19.563157) (xy 254.480319 -19.50872) (xy 254.476248 -19.453098) (xy 248.976947 -19.453098)
			(xy 248.985568 -19.465639) (xy 249.010656 -19.517354) (xy 249.027702 -19.572248) (xy 249.036322 -19.629077)
			(xy 249.036319 -19.686556) (xy 249.027695 -19.743384) (xy 249.010644 -19.798275) (xy 248.985552 -19.849988)
			(xy 248.952987 -19.897352) (xy 248.933716 -19.91868) (xy 248.927112 -19.925538) (xy 248.92 -19.943572)
			(xy 248.92 -20.032472) (xy 248.927112 -20.050506) (xy 248.933716 -20.057364) (xy 248.953007 -20.078673)
			(xy 248.985568 -20.126039) (xy 249.010656 -20.177754) (xy 249.027702 -20.232648) (xy 249.036322 -20.289477)
			(xy 249.036319 -20.346956) (xy 249.027695 -20.403784) (xy 249.010644 -20.458675) (xy 249.006326 -20.467574)
			(xy 256.48742 -20.467574) (xy 256.491491 -20.411952) (xy 256.503617 -20.357515) (xy 256.52354 -20.305424)
			(xy 256.550836 -20.256789) (xy 256.584922 -20.212646) (xy 256.625071 -20.173937) (xy 256.670429 -20.141486)
			(xy 256.720029 -20.115985) (xy 256.772813 -20.097978) (xy 256.827656 -20.087848) (xy 256.88339 -20.085811)
			(xy 256.938827 -20.091911) (xy 256.992784 -20.106017) (xy 257.044113 -20.127829) (xy 257.091719 -20.156883)
			(xy 257.134587 -20.192558) (xy 257.171804 -20.234095) (xy 257.202577 -20.280608) (xy 257.226249 -20.331105)
			(xy 257.242317 -20.384512) (xy 257.250437 -20.439688) (xy 257.250946 -20.467574) (xy 257.250437 -20.49546)
			(xy 257.242317 -20.550636) (xy 257.226249 -20.604043) (xy 257.202577 -20.65454) (xy 257.171804 -20.701053)
			(xy 257.150231 -20.72513) (xy 263.380486 -20.72513) (xy 263.384456 -20.594996) (xy 263.396352 -20.465346)
			(xy 263.416131 -20.336663) (xy 263.443717 -20.209424) (xy 263.47901 -20.084105) (xy 263.521876 -19.961169)
			(xy 263.572158 -19.841076) (xy 263.629667 -19.724272) (xy 263.694191 -19.61119) (xy 263.765488 -19.502253)
			(xy 263.843293 -19.397865) (xy 263.927318 -19.298414) (xy 264.01725 -19.204271) (xy 264.112754 -19.115786)
			(xy 264.213474 -19.033287) (xy 264.319036 -18.957082) (xy 264.429048 -18.887455) (xy 264.5431 -18.824664)
			(xy 264.660768 -18.768942) (xy 264.781614 -18.720498) (xy 264.905189 -18.679511) (xy 265.031032 -18.646134)
			(xy 265.158677 -18.620491) (xy 265.287647 -18.602677) (xy 265.417463 -18.592759) (xy 265.547642 -18.590774)
			(xy 265.677701 -18.596728) (xy 265.807154 -18.610601) (xy 265.935521 -18.632339) (xy 266.062324 -18.661863)
			(xy 266.187091 -18.699062) (xy 266.309358 -18.743798) (xy 266.428671 -18.795906) (xy 266.544584 -18.855189)
			(xy 266.656669 -18.92143) (xy 266.764506 -18.99438) (xy 266.867695 -19.073768) (xy 266.965853 -19.1593)
			(xy 267.058614 -19.250657) (xy 267.145633 -19.347499) (xy 267.226586 -19.449466) (xy 267.301172 -19.556178)
			(xy 267.369113 -19.667239) (xy 267.430158 -19.782235) (xy 267.484079 -19.900739) (xy 267.530674 -20.02231)
			(xy 267.569772 -20.146495) (xy 267.601226 -20.272833) (xy 267.62492 -20.400854) (xy 267.640764 -20.53008)
			(xy 267.648702 -20.660033) (xy 267.649198 -20.72513) (xy 267.648702 -20.790227) (xy 267.640764 -20.92018)
			(xy 267.62492 -21.049406) (xy 267.601226 -21.177427) (xy 267.569772 -21.303765) (xy 267.530674 -21.42795)
			(xy 267.484079 -21.549521) (xy 267.443355 -21.639022) (xy 274.273772 -21.639022) (xy 274.274317 -21.610284)
			(xy 274.282935 -21.553458) (xy 274.299981 -21.498568) (xy 274.325068 -21.446856) (xy 274.357628 -21.399492)
			(xy 274.376896 -21.378164) (xy 274.3835 -21.371306) (xy 274.390612 -21.353272) (xy 274.390612 -21.264372)
			(xy 274.3835 -21.246338) (xy 274.376896 -21.23948) (xy 274.357648 -21.218134) (xy 274.325085 -21.170774)
			(xy 274.299994 -21.119065) (xy 274.282943 -21.064178) (xy 274.274319 -21.007353) (xy 274.274317 -20.949879)
			(xy 274.282936 -20.893054) (xy 274.299982 -20.838165) (xy 274.325068 -20.786454) (xy 274.357628 -20.739091)
			(xy 274.376896 -20.717764) (xy 274.3835 -20.710906) (xy 274.390612 -20.692872) (xy 274.390612 -20.603972)
			(xy 274.3835 -20.585938) (xy 274.376896 -20.57908) (xy 274.357648 -20.557734) (xy 274.325085 -20.510374)
			(xy 274.299994 -20.458665) (xy 274.282943 -20.403778) (xy 274.274319 -20.346953) (xy 274.274317 -20.289479)
			(xy 274.282936 -20.232654) (xy 274.299982 -20.177765) (xy 274.325068 -20.126054) (xy 274.357628 -20.078691)
			(xy 274.376896 -20.057364) (xy 274.3835 -20.050506) (xy 274.390612 -20.032472) (xy 274.390612 -19.943572)
			(xy 274.3835 -19.925538) (xy 274.376896 -19.91868) (xy 274.357648 -19.897334) (xy 274.325085 -19.849974)
			(xy 274.299994 -19.798265) (xy 274.282943 -19.743378) (xy 274.274319 -19.686553) (xy 274.274317 -19.629079)
			(xy 274.282936 -19.572254) (xy 274.299982 -19.517365) (xy 274.325068 -19.465654) (xy 274.357628 -19.418291)
			(xy 274.376896 -19.396964) (xy 274.3835 -19.390106) (xy 274.390612 -19.372072) (xy 274.390612 -19.283172)
			(xy 274.3835 -19.265138) (xy 274.376896 -19.25828) (xy 274.357646 -19.236935) (xy 274.325075 -19.189579)
			(xy 274.299977 -19.137872) (xy 274.282922 -19.082985) (xy 274.274295 -19.02616) (xy 274.273772 -18.997422)
			(xy 274.274258 -18.970171) (xy 274.282014 -18.916223) (xy 274.297369 -18.863928) (xy 274.320011 -18.814351)
			(xy 274.349477 -18.768501) (xy 274.385168 -18.72731) (xy 274.426359 -18.691619) (xy 274.472209 -18.662153)
			(xy 274.521786 -18.639511) (xy 274.574081 -18.624156) (xy 274.628029 -18.6164) (xy 274.682531 -18.6164)
			(xy 274.736479 -18.624156) (xy 274.788774 -18.639511) (xy 274.838351 -18.662153) (xy 274.884201 -18.691619)
			(xy 274.925392 -18.72731) (xy 274.961083 -18.768501) (xy 274.990549 -18.814351) (xy 275.013191 -18.863928)
			(xy 275.028546 -18.916223) (xy 275.036302 -18.970171) (xy 275.036788 -18.997422) (xy 275.036281 -19.026162)
			(xy 275.027655 -19.08299) (xy 275.010601 -19.137881) (xy 274.985506 -19.189592) (xy 274.952937 -19.236954)
			(xy 274.933664 -19.25828) (xy 274.92706 -19.265138) (xy 274.919948 -19.283172) (xy 274.919948 -19.372072)
			(xy 274.92706 -19.390106) (xy 274.933664 -19.396964) (xy 274.952957 -19.418272) (xy 274.976902 -19.453098)
			(xy 280.476196 -19.453098) (xy 280.480267 -19.397476) (xy 280.492393 -19.343039) (xy 280.512316 -19.290948)
			(xy 280.539612 -19.242313) (xy 280.573698 -19.19817) (xy 280.613847 -19.159461) (xy 280.659205 -19.12701)
			(xy 280.708805 -19.101509) (xy 280.761589 -19.083502) (xy 280.816432 -19.073372) (xy 280.872166 -19.071335)
			(xy 280.927603 -19.077435) (xy 280.98156 -19.091541) (xy 281.032889 -19.113353) (xy 281.080495 -19.142407)
			(xy 281.123363 -19.178082) (xy 281.16058 -19.219619) (xy 281.191353 -19.266132) (xy 281.215025 -19.316629)
			(xy 281.231093 -19.370036) (xy 281.239213 -19.425212) (xy 281.239722 -19.453098) (xy 281.239213 -19.480984)
			(xy 281.231093 -19.53616) (xy 281.215025 -19.589567) (xy 281.191353 -19.640064) (xy 281.16058 -19.686577)
			(xy 281.123363 -19.728114) (xy 281.080495 -19.763789) (xy 281.032889 -19.792843) (xy 280.98156 -19.814655)
			(xy 280.927603 -19.828761) (xy 280.872166 -19.834861) (xy 280.816432 -19.832824) (xy 280.761589 -19.822694)
			(xy 280.708805 -19.804687) (xy 280.659205 -19.779186) (xy 280.613847 -19.746735) (xy 280.573698 -19.708026)
			(xy 280.539612 -19.663883) (xy 280.512316 -19.615248) (xy 280.492393 -19.563157) (xy 280.480267 -19.50872)
			(xy 280.476196 -19.453098) (xy 274.976902 -19.453098) (xy 274.985523 -19.465637) (xy 275.010614 -19.517352)
			(xy 275.027663 -19.572246) (xy 275.036284 -19.629076) (xy 275.036281 -19.686556) (xy 275.027656 -19.743386)
			(xy 275.010602 -19.798278) (xy 274.985506 -19.849991) (xy 274.952937 -19.897353) (xy 274.933664 -19.91868)
			(xy 274.92706 -19.925538) (xy 274.919948 -19.943572) (xy 274.919948 -20.032472) (xy 274.92706 -20.050506)
			(xy 274.933664 -20.057364) (xy 274.952957 -20.078672) (xy 274.985523 -20.126037) (xy 275.010614 -20.177752)
			(xy 275.027663 -20.232646) (xy 275.036284 -20.289476) (xy 275.036281 -20.346956) (xy 275.027656 -20.403786)
			(xy 275.010602 -20.458678) (xy 275.006285 -20.467574) (xy 282.487368 -20.467574) (xy 282.491439 -20.411952)
			(xy 282.503565 -20.357515) (xy 282.523488 -20.305424) (xy 282.550784 -20.256789) (xy 282.58487 -20.212646)
			(xy 282.625019 -20.173937) (xy 282.670377 -20.141486) (xy 282.719977 -20.115985) (xy 282.772761 -20.097978)
			(xy 282.827604 -20.087848) (xy 282.883338 -20.085811) (xy 282.938775 -20.091911) (xy 282.992732 -20.106017)
			(xy 283.044061 -20.127829) (xy 283.091667 -20.156883) (xy 283.134535 -20.192558) (xy 283.171752 -20.234095)
			(xy 283.202525 -20.280608) (xy 283.226197 -20.331105) (xy 283.242265 -20.384512) (xy 283.250385 -20.439688)
			(xy 283.250894 -20.467574) (xy 283.250385 -20.49546) (xy 283.242265 -20.550636) (xy 283.226197 -20.604043)
			(xy 283.202525 -20.65454) (xy 283.171752 -20.701053) (xy 283.150179 -20.72513) (xy 289.380434 -20.72513)
			(xy 289.384404 -20.594996) (xy 289.3963 -20.465346) (xy 289.416079 -20.336663) (xy 289.443665 -20.209424)
			(xy 289.478958 -20.084105) (xy 289.521824 -19.961169) (xy 289.572106 -19.841076) (xy 289.629615 -19.724272)
			(xy 289.694139 -19.61119) (xy 289.765436 -19.502253) (xy 289.843241 -19.397865) (xy 289.927266 -19.298414)
			(xy 290.017198 -19.204271) (xy 290.112702 -19.115786) (xy 290.213422 -19.033287) (xy 290.318984 -18.957082)
			(xy 290.428996 -18.887455) (xy 290.543048 -18.824664) (xy 290.660716 -18.768942) (xy 290.781562 -18.720498)
			(xy 290.905137 -18.679511) (xy 291.03098 -18.646134) (xy 291.158625 -18.620491) (xy 291.287595 -18.602677)
			(xy 291.417411 -18.592759) (xy 291.54759 -18.590774) (xy 291.677649 -18.596728) (xy 291.807102 -18.610601)
			(xy 291.935469 -18.632339) (xy 292.062272 -18.661863) (xy 292.187039 -18.699062) (xy 292.309306 -18.743798)
			(xy 292.428619 -18.795906) (xy 292.544532 -18.855189) (xy 292.656617 -18.92143) (xy 292.764454 -18.99438)
			(xy 292.867643 -19.073768) (xy 292.965801 -19.1593) (xy 293.058562 -19.250657) (xy 293.145581 -19.347499)
			(xy 293.226534 -19.449466) (xy 293.30112 -19.556178) (xy 293.369061 -19.667239) (xy 293.430106 -19.782235)
			(xy 293.484027 -19.900739) (xy 293.530622 -20.02231) (xy 293.56972 -20.146495) (xy 293.601174 -20.272833)
			(xy 293.624868 -20.400854) (xy 293.640712 -20.53008) (xy 293.64865 -20.660033) (xy 293.649146 -20.72513)
			(xy 293.64865 -20.790227) (xy 293.640712 -20.92018) (xy 293.624868 -21.049406) (xy 293.601174 -21.177427)
			(xy 293.56972 -21.303765) (xy 293.530622 -21.42795) (xy 293.484027 -21.549521) (xy 293.443303 -21.639022)
			(xy 300.27372 -21.639022) (xy 300.274279 -21.610285) (xy 300.282896 -21.55346) (xy 300.299939 -21.49857)
			(xy 300.325022 -21.446858) (xy 300.357578 -21.399493) (xy 300.376844 -21.378164) (xy 300.383448 -21.371306)
			(xy 300.39056 -21.353272) (xy 300.39056 -21.264372) (xy 300.383448 -21.246338) (xy 300.376844 -21.23948)
			(xy 300.357594 -21.218135) (xy 300.325026 -21.170776) (xy 300.299932 -21.119067) (xy 300.28288 -21.064179)
			(xy 300.274255 -21.007354) (xy 300.274252 -20.949878) (xy 300.282873 -20.893052) (xy 300.299921 -20.838162)
			(xy 300.32501 -20.786452) (xy 300.357574 -20.73909) (xy 300.376844 -20.717764) (xy 300.383448 -20.710906)
			(xy 300.39056 -20.692872) (xy 300.39056 -20.603972) (xy 300.383448 -20.585938) (xy 300.376844 -20.57908)
			(xy 300.357594 -20.557735) (xy 300.325026 -20.510376) (xy 300.299932 -20.458667) (xy 300.28288 -20.403779)
			(xy 300.274255 -20.346954) (xy 300.274252 -20.289478) (xy 300.282873 -20.232652) (xy 300.299921 -20.177762)
			(xy 300.32501 -20.126052) (xy 300.357574 -20.07869) (xy 300.376844 -20.057364) (xy 300.383448 -20.050506)
			(xy 300.39056 -20.032472) (xy 300.39056 -19.943572) (xy 300.383448 -19.925538) (xy 300.376844 -19.91868)
			(xy 300.357594 -19.897335) (xy 300.325026 -19.849976) (xy 300.299932 -19.798267) (xy 300.28288 -19.743379)
			(xy 300.274255 -19.686554) (xy 300.274252 -19.629078) (xy 300.282873 -19.572252) (xy 300.299921 -19.517362)
			(xy 300.32501 -19.465652) (xy 300.357574 -19.41829) (xy 300.376844 -19.396964) (xy 300.383448 -19.390106)
			(xy 300.39056 -19.372072) (xy 300.39056 -19.283172) (xy 300.383448 -19.265138) (xy 300.376844 -19.25828)
			(xy 300.357585 -19.236943) (xy 300.325017 -19.189584) (xy 300.299922 -19.137875) (xy 300.282869 -19.082986)
			(xy 300.274243 -19.02616) (xy 300.27372 -18.997422) (xy 300.274206 -18.970171) (xy 300.281962 -18.916223)
			(xy 300.297317 -18.863928) (xy 300.319959 -18.814351) (xy 300.349425 -18.768501) (xy 300.385116 -18.72731)
			(xy 300.426307 -18.691619) (xy 300.472157 -18.662153) (xy 300.521734 -18.639511) (xy 300.574029 -18.624156)
			(xy 300.627977 -18.6164) (xy 300.682479 -18.6164) (xy 300.736427 -18.624156) (xy 300.788722 -18.639511)
			(xy 300.838299 -18.662153) (xy 300.884149 -18.691619) (xy 300.92534 -18.72731) (xy 300.961031 -18.768501)
			(xy 300.990497 -18.814351) (xy 301.013139 -18.863928) (xy 301.028494 -18.916223) (xy 301.03625 -18.970171)
			(xy 301.036736 -18.997422) (xy 301.036216 -19.026161) (xy 301.027591 -19.082988) (xy 301.01054 -19.137878)
			(xy 300.985447 -19.18959) (xy 300.952882 -19.236953) (xy 300.933612 -19.25828) (xy 300.927008 -19.265138)
			(xy 300.919896 -19.283172) (xy 300.919896 -19.372072) (xy 300.927008 -19.390106) (xy 300.933612 -19.396964)
			(xy 300.952903 -19.418273) (xy 300.976844 -19.453098) (xy 306.476144 -19.453098) (xy 306.480215 -19.397476)
			(xy 306.492341 -19.343039) (xy 306.512264 -19.290948) (xy 306.53956 -19.242313) (xy 306.573646 -19.19817)
			(xy 306.613795 -19.159461) (xy 306.659153 -19.12701) (xy 306.708753 -19.101509) (xy 306.761537 -19.083502)
			(xy 306.81638 -19.073372) (xy 306.872114 -19.071335) (xy 306.927551 -19.077435) (xy 306.981508 -19.091541)
			(xy 307.032837 -19.113353) (xy 307.080443 -19.142407) (xy 307.123311 -19.178082) (xy 307.160528 -19.219619)
			(xy 307.191301 -19.266132) (xy 307.214973 -19.316629) (xy 307.231041 -19.370036) (xy 307.239161 -19.425212)
			(xy 307.23967 -19.453098) (xy 307.239161 -19.480984) (xy 307.231041 -19.53616) (xy 307.214973 -19.589567)
			(xy 307.191301 -19.640064) (xy 307.160528 -19.686577) (xy 307.123311 -19.728114) (xy 307.080443 -19.763789)
			(xy 307.032837 -19.792843) (xy 306.981508 -19.814655) (xy 306.927551 -19.828761) (xy 306.872114 -19.834861)
			(xy 306.81638 -19.832824) (xy 306.761537 -19.822694) (xy 306.708753 -19.804687) (xy 306.659153 -19.779186)
			(xy 306.613795 -19.746735) (xy 306.573646 -19.708026) (xy 306.53956 -19.663883) (xy 306.512264 -19.615248)
			(xy 306.492341 -19.563157) (xy 306.480215 -19.50872) (xy 306.476144 -19.453098) (xy 300.976844 -19.453098)
			(xy 300.985465 -19.465639) (xy 301.010552 -19.517354) (xy 301.027599 -19.572247) (xy 301.036219 -19.629076)
			(xy 301.036216 -19.686556) (xy 301.027592 -19.743384) (xy 301.010541 -19.798276) (xy 300.985448 -19.849989)
			(xy 300.952883 -19.897352) (xy 300.933612 -19.91868) (xy 300.927008 -19.925538) (xy 300.919896 -19.943572)
			(xy 300.919896 -20.032472) (xy 300.927008 -20.050506) (xy 300.933612 -20.057364) (xy 300.952903 -20.078673)
			(xy 300.985465 -20.126039) (xy 301.010552 -20.177754) (xy 301.027599 -20.232647) (xy 301.036219 -20.289476)
			(xy 301.036216 -20.346956) (xy 301.027592 -20.403784) (xy 301.010541 -20.458676) (xy 301.006223 -20.467574)
			(xy 308.487316 -20.467574) (xy 308.491387 -20.411952) (xy 308.503513 -20.357515) (xy 308.523436 -20.305424)
			(xy 308.550732 -20.256789) (xy 308.584818 -20.212646) (xy 308.624967 -20.173937) (xy 308.670325 -20.141486)
			(xy 308.719925 -20.115985) (xy 308.772709 -20.097978) (xy 308.827552 -20.087848) (xy 308.883286 -20.085811)
			(xy 308.938723 -20.091911) (xy 308.99268 -20.106017) (xy 309.044009 -20.127829) (xy 309.091615 -20.156883)
			(xy 309.134483 -20.192558) (xy 309.1717 -20.234095) (xy 309.202473 -20.280608) (xy 309.226145 -20.331105)
			(xy 309.242213 -20.384512) (xy 309.250333 -20.439688) (xy 309.250842 -20.467574) (xy 309.250333 -20.49546)
			(xy 309.242213 -20.550636) (xy 309.226145 -20.604043) (xy 309.202473 -20.65454) (xy 309.1717 -20.701053)
			(xy 309.150127 -20.72513) (xy 315.380636 -20.72513) (xy 315.384606 -20.594996) (xy 315.396502 -20.465346)
			(xy 315.416281 -20.336663) (xy 315.443867 -20.209424) (xy 315.47916 -20.084105) (xy 315.522026 -19.961169)
			(xy 315.572308 -19.841076) (xy 315.629817 -19.724272) (xy 315.694341 -19.61119) (xy 315.765638 -19.502253)
			(xy 315.843443 -19.397865) (xy 315.927468 -19.298414) (xy 316.0174 -19.204271) (xy 316.112904 -19.115786)
			(xy 316.213624 -19.033287) (xy 316.319186 -18.957082) (xy 316.429198 -18.887455) (xy 316.54325 -18.824664)
			(xy 316.660918 -18.768942) (xy 316.781764 -18.720498) (xy 316.905339 -18.679511) (xy 317.031182 -18.646134)
			(xy 317.158827 -18.620491) (xy 317.287797 -18.602677) (xy 317.417613 -18.592759) (xy 317.547792 -18.590774)
			(xy 317.677851 -18.596728) (xy 317.807304 -18.610601) (xy 317.935671 -18.632339) (xy 318.062474 -18.661863)
			(xy 318.187241 -18.699062) (xy 318.309508 -18.743798) (xy 318.428821 -18.795906) (xy 318.544734 -18.855189)
			(xy 318.656819 -18.92143) (xy 318.764656 -18.99438) (xy 318.867845 -19.073768) (xy 318.966003 -19.1593)
			(xy 319.058764 -19.250657) (xy 319.145783 -19.347499) (xy 319.226736 -19.449466) (xy 319.301322 -19.556178)
			(xy 319.369263 -19.667239) (xy 319.430308 -19.782235) (xy 319.484229 -19.900739) (xy 319.530824 -20.02231)
			(xy 319.569922 -20.146495) (xy 319.601376 -20.272833) (xy 319.62507 -20.400854) (xy 319.640914 -20.53008)
			(xy 319.648852 -20.660033) (xy 319.649348 -20.72513) (xy 319.648852 -20.790227) (xy 319.640914 -20.92018)
			(xy 319.62507 -21.049406) (xy 319.601376 -21.177427) (xy 319.569922 -21.303765) (xy 319.530824 -21.42795)
			(xy 319.484229 -21.549521) (xy 319.430308 -21.668025) (xy 319.399051 -21.726906) (xy 326.273668 -21.726906)
			(xy 326.274204 -21.698168) (xy 326.282825 -21.641341) (xy 326.299873 -21.586451) (xy 326.324961 -21.534739)
			(xy 326.357523 -21.487376) (xy 326.376792 -21.466048) (xy 326.383396 -21.45919) (xy 326.390508 -21.441156)
			(xy 326.390508 -21.352256) (xy 326.383396 -21.334222) (xy 326.376792 -21.327364) (xy 326.357529 -21.306031)
			(xy 326.324966 -21.258669) (xy 326.299876 -21.206958) (xy 326.282827 -21.152068) (xy 326.274205 -21.095243)
			(xy 326.274204 -21.037766) (xy 326.282825 -20.98094) (xy 326.299873 -20.92605) (xy 326.324961 -20.874339)
			(xy 326.357523 -20.826975) (xy 326.376792 -20.805648) (xy 326.383396 -20.79879) (xy 326.390508 -20.780756)
			(xy 326.390508 -20.691856) (xy 326.383396 -20.673822) (xy 326.376792 -20.666964) (xy 326.357529 -20.645631)
			(xy 326.324966 -20.598269) (xy 326.299876 -20.546558) (xy 326.282827 -20.491668) (xy 326.274205 -20.434843)
			(xy 326.274204 -20.377366) (xy 326.282825 -20.32054) (xy 326.299873 -20.26565) (xy 326.324961 -20.213939)
			(xy 326.357523 -20.166575) (xy 326.376792 -20.145248) (xy 326.383396 -20.13839) (xy 326.390508 -20.120356)
			(xy 326.390508 -20.031456) (xy 326.383396 -20.013422) (xy 326.376792 -20.006564) (xy 326.357529 -19.985231)
			(xy 326.324966 -19.937869) (xy 326.299876 -19.886158) (xy 326.282827 -19.831268) (xy 326.274205 -19.774443)
			(xy 326.274204 -19.716966) (xy 326.282825 -19.66014) (xy 326.299873 -19.60525) (xy 326.324961 -19.553539)
			(xy 326.357523 -19.506175) (xy 326.376792 -19.484848) (xy 326.383396 -19.47799) (xy 326.390508 -19.459956)
			(xy 326.390508 -19.371056) (xy 326.383396 -19.353022) (xy 326.376792 -19.346164) (xy 326.357533 -19.324826)
			(xy 326.324964 -19.277468) (xy 326.299868 -19.225759) (xy 326.282815 -19.170871) (xy 326.27419 -19.114044)
			(xy 326.273668 -19.085306) (xy 326.274154 -19.058055) (xy 326.28191 -19.004107) (xy 326.297265 -18.951812)
			(xy 326.319907 -18.902235) (xy 326.349373 -18.856385) (xy 326.385064 -18.815194) (xy 326.426255 -18.779503)
			(xy 326.472105 -18.750037) (xy 326.521682 -18.727395) (xy 326.573977 -18.71204) (xy 326.627925 -18.704284)
			(xy 326.682427 -18.704284) (xy 326.736375 -18.71204) (xy 326.78867 -18.727395) (xy 326.838247 -18.750037)
			(xy 326.884097 -18.779503) (xy 326.925288 -18.815194) (xy 326.960979 -18.856385) (xy 326.990445 -18.902235)
			(xy 327.013087 -18.951812) (xy 327.028442 -19.004107) (xy 327.036198 -19.058055) (xy 327.036684 -19.085306)
			(xy 327.036141 -19.114044) (xy 327.02752 -19.170869) (xy 327.010473 -19.225759) (xy 326.985386 -19.277471)
			(xy 326.952827 -19.324835) (xy 326.93356 -19.346164) (xy 326.926956 -19.353022) (xy 326.919844 -19.371056)
			(xy 326.919844 -19.459956) (xy 326.926956 -19.47799) (xy 326.93356 -19.484848) (xy 326.952837 -19.506169)
			(xy 326.985404 -19.553532) (xy 327.010496 -19.605245) (xy 327.027547 -19.660137) (xy 327.036169 -19.716965)
			(xy 327.036168 -19.774444) (xy 327.027545 -19.831272) (xy 327.010493 -19.886163) (xy 326.985399 -19.937875)
			(xy 326.952832 -19.985238) (xy 326.93356 -20.006564) (xy 326.926956 -20.013422) (xy 326.919844 -20.031456)
			(xy 326.919844 -20.120356) (xy 326.926956 -20.13839) (xy 326.93356 -20.145248) (xy 326.952837 -20.166569)
			(xy 326.985404 -20.213932) (xy 327.010496 -20.265645) (xy 327.027547 -20.320537) (xy 327.036169 -20.377365)
			(xy 327.036168 -20.434844) (xy 327.027545 -20.491672) (xy 327.010493 -20.546563) (xy 326.985399 -20.598275)
			(xy 326.952832 -20.645638) (xy 326.93356 -20.666964) (xy 326.926956 -20.673822) (xy 326.919844 -20.691856)
			(xy 326.919844 -20.72513) (xy 353.480636 -20.72513) (xy 353.484606 -20.594996) (xy 353.496502 -20.465346)
			(xy 353.516281 -20.336663) (xy 353.543867 -20.209424) (xy 353.57916 -20.084105) (xy 353.622026 -19.961169)
			(xy 353.672308 -19.841076) (xy 353.729817 -19.724272) (xy 353.794341 -19.61119) (xy 353.865638 -19.502253)
			(xy 353.943443 -19.397865) (xy 354.027468 -19.298414) (xy 354.1174 -19.204271) (xy 354.212904 -19.115786)
			(xy 354.313624 -19.033287) (xy 354.419186 -18.957082) (xy 354.529198 -18.887455) (xy 354.64325 -18.824664)
			(xy 354.760918 -18.768942) (xy 354.881764 -18.720498) (xy 355.005339 -18.679511) (xy 355.131182 -18.646134)
			(xy 355.258827 -18.620491) (xy 355.387797 -18.602677) (xy 355.517613 -18.592759) (xy 355.647792 -18.590774)
			(xy 355.777851 -18.596728) (xy 355.907304 -18.610601) (xy 356.035671 -18.632339) (xy 356.162474 -18.661863)
			(xy 356.287241 -18.699062) (xy 356.409508 -18.743798) (xy 356.528821 -18.795906) (xy 356.644734 -18.855189)
			(xy 356.756819 -18.92143) (xy 356.864656 -18.99438) (xy 356.967845 -19.073768) (xy 357.066003 -19.1593)
			(xy 357.158764 -19.250657) (xy 357.245783 -19.347499) (xy 357.326736 -19.449466) (xy 357.401322 -19.556178)
			(xy 357.469263 -19.667239) (xy 357.530308 -19.782235) (xy 357.584229 -19.900739) (xy 357.630824 -20.02231)
			(xy 357.669922 -20.146495) (xy 357.701376 -20.272833) (xy 357.72507 -20.400854) (xy 357.740914 -20.53008)
			(xy 357.748852 -20.660033) (xy 357.749348 -20.72513) (xy 357.748852 -20.790227) (xy 357.740914 -20.92018)
			(xy 357.72507 -21.049406) (xy 357.701376 -21.177427) (xy 357.669922 -21.303765) (xy 357.630824 -21.42795)
			(xy 357.584229 -21.549521) (xy 357.543505 -21.639022) (xy 364.373922 -21.639022) (xy 364.37448 -21.610285)
			(xy 364.383097 -21.55346) (xy 364.400141 -21.49857) (xy 364.425224 -21.446858) (xy 364.45778 -21.399493)
			(xy 364.477046 -21.378164) (xy 364.48365 -21.371306) (xy 364.490762 -21.353272) (xy 364.490762 -21.264372)
			(xy 364.48365 -21.246338) (xy 364.477046 -21.23948) (xy 364.457796 -21.218135) (xy 364.425228 -21.170776)
			(xy 364.400134 -21.119068) (xy 364.383081 -21.064179) (xy 364.374456 -21.007354) (xy 364.374454 -20.949878)
			(xy 364.383074 -20.893052) (xy 364.400122 -20.838162) (xy 364.425212 -20.786452) (xy 364.457776 -20.73909)
			(xy 364.477046 -20.717764) (xy 364.48365 -20.710906) (xy 364.490762 -20.692872) (xy 364.490762 -20.603972)
			(xy 364.48365 -20.585938) (xy 364.477046 -20.57908) (xy 364.457796 -20.557735) (xy 364.425228 -20.510376)
			(xy 364.400134 -20.458668) (xy 364.383081 -20.403779) (xy 364.374456 -20.346954) (xy 364.374454 -20.289478)
			(xy 364.383074 -20.232652) (xy 364.400122 -20.177762) (xy 364.425212 -20.126052) (xy 364.457776 -20.07869)
			(xy 364.477046 -20.057364) (xy 364.48365 -20.050506) (xy 364.490762 -20.032472) (xy 364.490762 -19.943572)
			(xy 364.48365 -19.925538) (xy 364.477046 -19.91868) (xy 364.457796 -19.897335) (xy 364.425228 -19.849976)
			(xy 364.400134 -19.798268) (xy 364.383081 -19.743379) (xy 364.374456 -19.686554) (xy 364.374454 -19.629078)
			(xy 364.383074 -19.572252) (xy 364.400122 -19.517362) (xy 364.425212 -19.465652) (xy 364.457776 -19.41829)
			(xy 364.477046 -19.396964) (xy 364.48365 -19.390106) (xy 364.490762 -19.372072) (xy 364.490762 -19.283172)
			(xy 364.48365 -19.265138) (xy 364.477046 -19.25828) (xy 364.457787 -19.236943) (xy 364.425219 -19.189584)
			(xy 364.400124 -19.137875) (xy 364.383071 -19.082986) (xy 364.374445 -19.02616) (xy 364.373922 -18.997422)
			(xy 364.374408 -18.970171) (xy 364.382164 -18.916223) (xy 364.397519 -18.863928) (xy 364.420161 -18.814351)
			(xy 364.449627 -18.768501) (xy 364.485318 -18.72731) (xy 364.526509 -18.691619) (xy 364.572359 -18.662153)
			(xy 364.621936 -18.639511) (xy 364.674231 -18.624156) (xy 364.728179 -18.6164) (xy 364.782681 -18.6164)
			(xy 364.836629 -18.624156) (xy 364.888924 -18.639511) (xy 364.938501 -18.662153) (xy 364.984351 -18.691619)
			(xy 365.025542 -18.72731) (xy 365.061233 -18.768501) (xy 365.090699 -18.814351) (xy 365.113341 -18.863928)
			(xy 365.128696 -18.916223) (xy 365.136452 -18.970171) (xy 365.136938 -18.997422) (xy 365.136417 -19.026161)
			(xy 365.127793 -19.082988) (xy 365.110741 -19.137878) (xy 365.085649 -19.18959) (xy 365.053084 -19.236953)
			(xy 365.033814 -19.25828) (xy 365.02721 -19.265138) (xy 365.020098 -19.283172) (xy 365.020098 -19.372072)
			(xy 365.02721 -19.390106) (xy 365.033814 -19.396964) (xy 365.053105 -19.418273) (xy 365.077045 -19.453098)
			(xy 370.576346 -19.453098) (xy 370.580417 -19.397476) (xy 370.592543 -19.343039) (xy 370.612466 -19.290948)
			(xy 370.639762 -19.242313) (xy 370.673848 -19.19817) (xy 370.713997 -19.159461) (xy 370.759355 -19.12701)
			(xy 370.808955 -19.101509) (xy 370.861739 -19.083502) (xy 370.916582 -19.073372) (xy 370.972316 -19.071335)
			(xy 371.027753 -19.077435) (xy 371.08171 -19.091541) (xy 371.133039 -19.113353) (xy 371.180645 -19.142407)
			(xy 371.223513 -19.178082) (xy 371.26073 -19.219619) (xy 371.291503 -19.266132) (xy 371.315175 -19.316629)
			(xy 371.331243 -19.370036) (xy 371.339363 -19.425212) (xy 371.339872 -19.453098) (xy 371.339363 -19.480984)
			(xy 371.331243 -19.53616) (xy 371.315175 -19.589567) (xy 371.291503 -19.640064) (xy 371.26073 -19.686577)
			(xy 371.223513 -19.728114) (xy 371.180645 -19.763789) (xy 371.133039 -19.792843) (xy 371.08171 -19.814655)
			(xy 371.027753 -19.828761) (xy 370.972316 -19.834861) (xy 370.916582 -19.832824) (xy 370.861739 -19.822694)
			(xy 370.808955 -19.804687) (xy 370.759355 -19.779186) (xy 370.713997 -19.746735) (xy 370.673848 -19.708026)
			(xy 370.639762 -19.663883) (xy 370.612466 -19.615248) (xy 370.592543 -19.563157) (xy 370.580417 -19.50872)
			(xy 370.576346 -19.453098) (xy 365.077045 -19.453098) (xy 365.085666 -19.465639) (xy 365.110754 -19.517354)
			(xy 365.127801 -19.572247) (xy 365.13642 -19.629077) (xy 365.136418 -19.686556) (xy 365.127793 -19.743384)
			(xy 365.110742 -19.798276) (xy 365.08565 -19.849988) (xy 365.053085 -19.897352) (xy 365.033814 -19.91868)
			(xy 365.02721 -19.925538) (xy 365.020098 -19.943572) (xy 365.020098 -20.032472) (xy 365.02721 -20.050506)
			(xy 365.033814 -20.057364) (xy 365.053105 -20.078673) (xy 365.085666 -20.126039) (xy 365.110754 -20.177754)
			(xy 365.127801 -20.232647) (xy 365.13642 -20.289477) (xy 365.136418 -20.346956) (xy 365.127793 -20.403784)
			(xy 365.110742 -20.458676) (xy 365.106424 -20.467574) (xy 372.587518 -20.467574) (xy 372.591589 -20.411952)
			(xy 372.603715 -20.357515) (xy 372.623638 -20.305424) (xy 372.650934 -20.256789) (xy 372.68502 -20.212646)
			(xy 372.725169 -20.173937) (xy 372.770527 -20.141486) (xy 372.820127 -20.115985) (xy 372.872911 -20.097978)
			(xy 372.927754 -20.087848) (xy 372.983488 -20.085811) (xy 373.038925 -20.091911) (xy 373.092882 -20.106017)
			(xy 373.144211 -20.127829) (xy 373.191817 -20.156883) (xy 373.234685 -20.192558) (xy 373.271902 -20.234095)
			(xy 373.302675 -20.280608) (xy 373.326347 -20.331105) (xy 373.342415 -20.384512) (xy 373.350535 -20.439688)
			(xy 373.351044 -20.467574) (xy 373.350535 -20.49546) (xy 373.342415 -20.550636) (xy 373.326347 -20.604043)
			(xy 373.302675 -20.65454) (xy 373.271902 -20.701053) (xy 373.254881 -20.72005) (xy 379.48541 -20.72005)
			(xy 379.48938 -20.589916) (xy 379.501276 -20.460266) (xy 379.521055 -20.331583) (xy 379.548641 -20.204344)
			(xy 379.583934 -20.079025) (xy 379.6268 -19.956089) (xy 379.677082 -19.835996) (xy 379.734591 -19.719192)
			(xy 379.799115 -19.60611) (xy 379.870412 -19.497173) (xy 379.948217 -19.392785) (xy 380.032242 -19.293334)
			(xy 380.122174 -19.199191) (xy 380.217678 -19.110706) (xy 380.318398 -19.028207) (xy 380.42396 -18.952002)
			(xy 380.533972 -18.882375) (xy 380.648024 -18.819584) (xy 380.765692 -18.763862) (xy 380.886538 -18.715418)
			(xy 381.010113 -18.674431) (xy 381.135956 -18.641054) (xy 381.263601 -18.615411) (xy 381.392571 -18.597597)
			(xy 381.522387 -18.587679) (xy 381.652566 -18.585694) (xy 381.782625 -18.591648) (xy 381.912078 -18.605521)
			(xy 382.040445 -18.627259) (xy 382.167248 -18.656783) (xy 382.292015 -18.693982) (xy 382.414282 -18.738718)
			(xy 382.533595 -18.790826) (xy 382.649508 -18.850109) (xy 382.761593 -18.91635) (xy 382.86943 -18.9893)
			(xy 382.972619 -19.068688) (xy 383.070777 -19.15422) (xy 383.163538 -19.245577) (xy 383.250557 -19.342419)
			(xy 383.33151 -19.444386) (xy 383.406096 -19.551098) (xy 383.474037 -19.662159) (xy 383.535082 -19.777155)
			(xy 383.589003 -19.895659) (xy 383.635598 -20.01723) (xy 383.674696 -20.141415) (xy 383.70615 -20.267753)
			(xy 383.729844 -20.395774) (xy 383.745688 -20.525) (xy 383.753626 -20.654953) (xy 383.754122 -20.72005)
			(xy 383.753626 -20.785147) (xy 383.745688 -20.9151) (xy 383.729844 -21.044326) (xy 383.70615 -21.172347)
			(xy 383.674696 -21.298685) (xy 383.635598 -21.42287) (xy 383.589003 -21.544441) (xy 383.535082 -21.662945)
			(xy 383.501129 -21.726906) (xy 390.37387 -21.726906) (xy 390.374405 -21.698168) (xy 390.383026 -21.641341)
			(xy 390.400074 -21.586451) (xy 390.425163 -21.534739) (xy 390.457725 -21.487376) (xy 390.476994 -21.466048)
			(xy 390.483598 -21.45919) (xy 390.49071 -21.441156) (xy 390.49071 -21.352256) (xy 390.483598 -21.334222)
			(xy 390.476994 -21.327364) (xy 390.45773 -21.306031) (xy 390.425168 -21.258669) (xy 390.400078 -21.206958)
			(xy 390.383029 -21.152068) (xy 390.374406 -21.095243) (xy 390.374406 -21.037766) (xy 390.383027 -20.98094)
			(xy 390.400074 -20.92605) (xy 390.425163 -20.874339) (xy 390.457725 -20.826975) (xy 390.476994 -20.805648)
			(xy 390.483598 -20.79879) (xy 390.49071 -20.780756) (xy 390.49071 -20.691856) (xy 390.483598 -20.673822)
			(xy 390.476994 -20.666964) (xy 390.45773 -20.645631) (xy 390.425168 -20.598269) (xy 390.400078 -20.546558)
			(xy 390.383029 -20.491668) (xy 390.374406 -20.434843) (xy 390.374406 -20.377366) (xy 390.383027 -20.32054)
			(xy 390.400074 -20.26565) (xy 390.425163 -20.213939) (xy 390.457725 -20.166575) (xy 390.476994 -20.145248)
			(xy 390.483598 -20.13839) (xy 390.49071 -20.120356) (xy 390.49071 -20.031456) (xy 390.483598 -20.013422)
			(xy 390.476994 -20.006564) (xy 390.45773 -19.985231) (xy 390.425168 -19.937869) (xy 390.400078 -19.886158)
			(xy 390.383029 -19.831268) (xy 390.374406 -19.774443) (xy 390.374406 -19.716966) (xy 390.383027 -19.66014)
			(xy 390.400074 -19.60525) (xy 390.425163 -19.553539) (xy 390.457725 -19.506175) (xy 390.476994 -19.484848)
			(xy 390.483598 -19.47799) (xy 390.49071 -19.459956) (xy 390.49071 -19.371056) (xy 390.483598 -19.353022)
			(xy 390.476994 -19.346164) (xy 390.457736 -19.324826) (xy 390.425166 -19.277468) (xy 390.40007 -19.225759)
			(xy 390.383017 -19.17087) (xy 390.374392 -19.114044) (xy 390.37387 -19.085306) (xy 390.374356 -19.058055)
			(xy 390.382112 -19.004107) (xy 390.397467 -18.951812) (xy 390.420109 -18.902235) (xy 390.449575 -18.856385)
			(xy 390.485266 -18.815194) (xy 390.526457 -18.779503) (xy 390.572307 -18.750037) (xy 390.621884 -18.727395)
			(xy 390.674179 -18.71204) (xy 390.728127 -18.704284) (xy 390.782629 -18.704284) (xy 390.836577 -18.71204)
			(xy 390.888872 -18.727395) (xy 390.938449 -18.750037) (xy 390.984299 -18.779503) (xy 391.02549 -18.815194)
			(xy 391.061181 -18.856385) (xy 391.090647 -18.902235) (xy 391.113289 -18.951812) (xy 391.128644 -19.004107)
			(xy 391.1364 -19.058055) (xy 391.136886 -19.085306) (xy 391.136343 -19.114044) (xy 391.127722 -19.170869)
			(xy 391.110675 -19.225759) (xy 391.085588 -19.277471) (xy 391.053029 -19.324835) (xy 391.033762 -19.346164)
			(xy 391.027158 -19.353022) (xy 391.020046 -19.371056) (xy 391.020046 -19.453098) (xy 396.576294 -19.453098)
			(xy 396.580365 -19.397476) (xy 396.592491 -19.343039) (xy 396.612414 -19.290948) (xy 396.63971 -19.242313)
			(xy 396.673796 -19.19817) (xy 396.713945 -19.159461) (xy 396.759303 -19.12701) (xy 396.808903 -19.101509)
			(xy 396.861687 -19.083502) (xy 396.91653 -19.073372) (xy 396.972264 -19.071335) (xy 397.027701 -19.077435)
			(xy 397.081658 -19.091541) (xy 397.132987 -19.113353) (xy 397.180593 -19.142407) (xy 397.223461 -19.178082)
			(xy 397.260678 -19.219619) (xy 397.291451 -19.266132) (xy 397.315123 -19.316629) (xy 397.331191 -19.370036)
			(xy 397.339311 -19.425212) (xy 397.33982 -19.453098) (xy 397.339311 -19.480984) (xy 397.331191 -19.53616)
			(xy 397.315123 -19.589567) (xy 397.291451 -19.640064) (xy 397.260678 -19.686577) (xy 397.223461 -19.728114)
			(xy 397.180593 -19.763789) (xy 397.132987 -19.792843) (xy 397.081658 -19.814655) (xy 397.027701 -19.828761)
			(xy 396.972264 -19.834861) (xy 396.91653 -19.832824) (xy 396.861687 -19.822694) (xy 396.808903 -19.804687)
			(xy 396.759303 -19.779186) (xy 396.713945 -19.746735) (xy 396.673796 -19.708026) (xy 396.63971 -19.663883)
			(xy 396.612414 -19.615248) (xy 396.592491 -19.563157) (xy 396.580365 -19.50872) (xy 396.576294 -19.453098)
			(xy 391.020046 -19.453098) (xy 391.020046 -19.459956) (xy 391.027158 -19.47799) (xy 391.033762 -19.484848)
			(xy 391.053039 -19.506169) (xy 391.085606 -19.553532) (xy 391.110698 -19.605245) (xy 391.127748 -19.660137)
			(xy 391.13637 -19.716965) (xy 391.13637 -19.774444) (xy 391.127746 -19.831272) (xy 391.110695 -19.886163)
			(xy 391.085601 -19.937875) (xy 391.053034 -19.985238) (xy 391.033762 -20.006564) (xy 391.027158 -20.013422)
			(xy 391.020046 -20.031456) (xy 391.020046 -20.120356) (xy 391.027158 -20.13839) (xy 391.033762 -20.145248)
			(xy 391.053039 -20.166569) (xy 391.085606 -20.213932) (xy 391.110698 -20.265645) (xy 391.127748 -20.320537)
			(xy 391.13637 -20.377365) (xy 391.13637 -20.434844) (xy 391.131403 -20.467574) (xy 398.587466 -20.467574)
			(xy 398.591537 -20.411952) (xy 398.603663 -20.357515) (xy 398.623586 -20.305424) (xy 398.650882 -20.256789)
			(xy 398.684968 -20.212646) (xy 398.725117 -20.173937) (xy 398.770475 -20.141486) (xy 398.820075 -20.115985)
			(xy 398.872859 -20.097978) (xy 398.927702 -20.087848) (xy 398.983436 -20.085811) (xy 399.038873 -20.091911)
			(xy 399.09283 -20.106017) (xy 399.144159 -20.127829) (xy 399.191765 -20.156883) (xy 399.234633 -20.192558)
			(xy 399.27185 -20.234095) (xy 399.302623 -20.280608) (xy 399.326295 -20.331105) (xy 399.342363 -20.384512)
			(xy 399.350483 -20.439688) (xy 399.350992 -20.467574) (xy 399.350483 -20.49546) (xy 399.342363 -20.550636)
			(xy 399.326295 -20.604043) (xy 399.302623 -20.65454) (xy 399.27185 -20.701053) (xy 399.250277 -20.72513)
			(xy 405.480532 -20.72513) (xy 405.484502 -20.594996) (xy 405.496398 -20.465346) (xy 405.516177 -20.336663)
			(xy 405.543763 -20.209424) (xy 405.579056 -20.084105) (xy 405.621922 -19.961169) (xy 405.672204 -19.841076)
			(xy 405.729713 -19.724272) (xy 405.794237 -19.61119) (xy 405.865534 -19.502253) (xy 405.943339 -19.397865)
			(xy 406.027364 -19.298414) (xy 406.117296 -19.204271) (xy 406.2128 -19.115786) (xy 406.31352 -19.033287)
			(xy 406.419082 -18.957082) (xy 406.529094 -18.887455) (xy 406.643146 -18.824664) (xy 406.760814 -18.768942)
			(xy 406.88166 -18.720498) (xy 407.005235 -18.679511) (xy 407.131078 -18.646134) (xy 407.258723 -18.620491)
			(xy 407.387693 -18.602677) (xy 407.517509 -18.592759) (xy 407.647688 -18.590774) (xy 407.777747 -18.596728)
			(xy 407.9072 -18.610601) (xy 408.035567 -18.632339) (xy 408.16237 -18.661863) (xy 408.287137 -18.699062)
			(xy 408.409404 -18.743798) (xy 408.528717 -18.795906) (xy 408.64463 -18.855189) (xy 408.756715 -18.92143)
			(xy 408.864552 -18.99438) (xy 408.967741 -19.073768) (xy 409.065899 -19.1593) (xy 409.15866 -19.250657)
			(xy 409.245679 -19.347499) (xy 409.326632 -19.449466) (xy 409.401218 -19.556178) (xy 409.469159 -19.667239)
			(xy 409.530204 -19.782235) (xy 409.584125 -19.900739) (xy 409.63072 -20.02231) (xy 409.669818 -20.146495)
			(xy 409.701272 -20.272833) (xy 409.724966 -20.400854) (xy 409.74081 -20.53008) (xy 409.748748 -20.660033)
			(xy 409.749244 -20.72513) (xy 409.748748 -20.790227) (xy 409.74081 -20.92018) (xy 409.724966 -21.049406)
			(xy 409.701272 -21.177427) (xy 409.669818 -21.303765) (xy 409.63072 -21.42795) (xy 409.584125 -21.549521)
			(xy 409.530204 -21.668025) (xy 409.498947 -21.726906) (xy 416.373818 -21.726906) (xy 416.374367 -21.698168)
			(xy 416.382987 -21.641343) (xy 416.400032 -21.586453) (xy 416.425118 -21.534741) (xy 416.457675 -21.487377)
			(xy 416.476942 -21.466048) (xy 416.483546 -21.45919) (xy 416.490658 -21.441156) (xy 416.490658 -21.352256)
			(xy 416.483546 -21.334222) (xy 416.476942 -21.327364) (xy 416.457676 -21.306032) (xy 416.425109 -21.258671)
			(xy 416.400016 -21.20696) (xy 416.382965 -21.15207) (xy 416.374341 -21.095243) (xy 416.374341 -21.037766)
			(xy 416.382963 -20.980938) (xy 416.400013 -20.926048) (xy 416.425105 -20.874336) (xy 416.457671 -20.826974)
			(xy 416.476942 -20.805648) (xy 416.483546 -20.79879) (xy 416.490658 -20.780756) (xy 416.490658 -20.691856)
			(xy 416.483546 -20.673822) (xy 416.476942 -20.666964) (xy 416.457676 -20.645632) (xy 416.425109 -20.598271)
			(xy 416.400016 -20.54656) (xy 416.382965 -20.49167) (xy 416.374341 -20.434843) (xy 416.374341 -20.377366)
			(xy 416.382963 -20.320538) (xy 416.400013 -20.265648) (xy 416.425105 -20.213936) (xy 416.457671 -20.166574)
			(xy 416.476942 -20.145248) (xy 416.483546 -20.13839) (xy 416.490658 -20.120356) (xy 416.490658 -20.031456)
			(xy 416.483546 -20.013422) (xy 416.476942 -20.006564) (xy 416.457676 -19.985232) (xy 416.425109 -19.937871)
			(xy 416.400016 -19.88616) (xy 416.382965 -19.83127) (xy 416.374341 -19.774443) (xy 416.374341 -19.716966)
			(xy 416.382963 -19.660138) (xy 416.400013 -19.605248) (xy 416.425105 -19.553536) (xy 416.457671 -19.506174)
			(xy 416.476942 -19.484848) (xy 416.483546 -19.47799) (xy 416.490658 -19.459956) (xy 416.490658 -19.371056)
			(xy 416.483546 -19.353022) (xy 416.476942 -19.346164) (xy 416.457675 -19.324834) (xy 416.425108 -19.277473)
			(xy 416.400015 -19.225762) (xy 416.382963 -19.170872) (xy 416.374339 -19.114045) (xy 416.373818 -19.085306)
			(xy 416.374304 -19.058055) (xy 416.38206 -19.004107) (xy 416.397415 -18.951812) (xy 416.420057 -18.902235)
			(xy 416.449523 -18.856385) (xy 416.485214 -18.815194) (xy 416.526405 -18.779503) (xy 416.572255 -18.750037)
			(xy 416.621832 -18.727395) (xy 416.674127 -18.71204) (xy 416.728075 -18.704284) (xy 416.782577 -18.704284)
			(xy 416.836525 -18.71204) (xy 416.88882 -18.727395) (xy 416.938397 -18.750037) (xy 416.984247 -18.779503)
			(xy 417.025438 -18.815194) (xy 417.061129 -18.856385) (xy 417.090595 -18.902235) (xy 417.113237 -18.951812)
			(xy 417.128592 -19.004107) (xy 417.136348 -19.058055) (xy 417.136834 -19.085306) (xy 417.136305 -19.114045)
			(xy 417.127682 -19.170871) (xy 417.110633 -19.225762) (xy 417.085543 -19.277473) (xy 417.05298 -19.324837)
			(xy 417.03371 -19.346164) (xy 417.027106 -19.353022) (xy 417.019994 -19.371056) (xy 417.019994 -19.453098)
			(xy 422.576242 -19.453098) (xy 422.580313 -19.397476) (xy 422.592439 -19.343039) (xy 422.612362 -19.290948)
			(xy 422.639658 -19.242313) (xy 422.673744 -19.19817) (xy 422.713893 -19.159461) (xy 422.759251 -19.12701)
			(xy 422.808851 -19.101509) (xy 422.861635 -19.083502) (xy 422.916478 -19.073372) (xy 422.972212 -19.071335)
			(xy 423.027649 -19.077435) (xy 423.081606 -19.091541) (xy 423.132935 -19.113353) (xy 423.180541 -19.142407)
			(xy 423.223409 -19.178082) (xy 423.260626 -19.219619) (xy 423.291399 -19.266132) (xy 423.315071 -19.316629)
			(xy 423.331139 -19.370036) (xy 423.339259 -19.425212) (xy 423.339768 -19.453098) (xy 423.339259 -19.480984)
			(xy 423.331139 -19.53616) (xy 423.315071 -19.589567) (xy 423.291399 -19.640064) (xy 423.260626 -19.686577)
			(xy 423.223409 -19.728114) (xy 423.180541 -19.763789) (xy 423.132935 -19.792843) (xy 423.081606 -19.814655)
			(xy 423.027649 -19.828761) (xy 422.972212 -19.834861) (xy 422.916478 -19.832824) (xy 422.861635 -19.822694)
			(xy 422.808851 -19.804687) (xy 422.759251 -19.779186) (xy 422.713893 -19.746735) (xy 422.673744 -19.708026)
			(xy 422.639658 -19.663883) (xy 422.612362 -19.615248) (xy 422.592439 -19.563157) (xy 422.580313 -19.50872)
			(xy 422.576242 -19.453098) (xy 417.019994 -19.453098) (xy 417.019994 -19.459956) (xy 417.027106 -19.47799)
			(xy 417.03371 -19.484848) (xy 417.052985 -19.50617) (xy 417.085547 -19.553535) (xy 417.110636 -19.605247)
			(xy 417.127684 -19.660138) (xy 417.136306 -19.716966) (xy 417.136305 -19.774443) (xy 417.127682 -19.83127)
			(xy 417.110633 -19.886161) (xy 417.085543 -19.937873) (xy 417.05298 -19.985236) (xy 417.03371 -20.006564)
			(xy 417.027106 -20.013422) (xy 417.019994 -20.031456) (xy 417.019994 -20.120356) (xy 417.027106 -20.13839)
			(xy 417.03371 -20.145248) (xy 417.052985 -20.16657) (xy 417.085547 -20.213935) (xy 417.110636 -20.265647)
			(xy 417.127684 -20.320538) (xy 417.136306 -20.377366) (xy 417.136305 -20.434843) (xy 417.131338 -20.467574)
			(xy 424.587414 -20.467574) (xy 424.591485 -20.411952) (xy 424.603611 -20.357515) (xy 424.623534 -20.305424)
			(xy 424.65083 -20.256789) (xy 424.684916 -20.212646) (xy 424.725065 -20.173937) (xy 424.770423 -20.141486)
			(xy 424.820023 -20.115985) (xy 424.872807 -20.097978) (xy 424.92765 -20.087848) (xy 424.983384 -20.085811)
			(xy 425.038821 -20.091911) (xy 425.092778 -20.106017) (xy 425.144107 -20.127829) (xy 425.191713 -20.156883)
			(xy 425.234581 -20.192558) (xy 425.271798 -20.234095) (xy 425.302571 -20.280608) (xy 425.326243 -20.331105)
			(xy 425.342311 -20.384512) (xy 425.350431 -20.439688) (xy 425.35094 -20.467574) (xy 425.350431 -20.49546)
			(xy 425.342311 -20.550636) (xy 425.326243 -20.604043) (xy 425.302571 -20.65454) (xy 425.271798 -20.701053)
			(xy 425.250225 -20.72513) (xy 431.48048 -20.72513) (xy 431.48445 -20.594996) (xy 431.496346 -20.465346)
			(xy 431.516125 -20.336663) (xy 431.543711 -20.209424) (xy 431.579004 -20.084105) (xy 431.62187 -19.961169)
			(xy 431.672152 -19.841076) (xy 431.729661 -19.724272) (xy 431.794185 -19.61119) (xy 431.865482 -19.502253)
			(xy 431.943287 -19.397865) (xy 432.027312 -19.298414) (xy 432.117244 -19.204271) (xy 432.212748 -19.115786)
			(xy 432.313468 -19.033287) (xy 432.41903 -18.957082) (xy 432.529042 -18.887455) (xy 432.643094 -18.824664)
			(xy 432.760762 -18.768942) (xy 432.881608 -18.720498) (xy 433.005183 -18.679511) (xy 433.131026 -18.646134)
			(xy 433.258671 -18.620491) (xy 433.387641 -18.602677) (xy 433.517457 -18.592759) (xy 433.647636 -18.590774)
			(xy 433.777695 -18.596728) (xy 433.907148 -18.610601) (xy 434.035515 -18.632339) (xy 434.162318 -18.661863)
			(xy 434.287085 -18.699062) (xy 434.409352 -18.743798) (xy 434.528665 -18.795906) (xy 434.644578 -18.855189)
			(xy 434.756663 -18.92143) (xy 434.8645 -18.99438) (xy 434.967689 -19.073768) (xy 435.065847 -19.1593)
			(xy 435.158608 -19.250657) (xy 435.245627 -19.347499) (xy 435.32658 -19.449466) (xy 435.401166 -19.556178)
			(xy 435.469107 -19.667239) (xy 435.530152 -19.782235) (xy 435.584073 -19.900739) (xy 435.630668 -20.02231)
			(xy 435.669766 -20.146495) (xy 435.70122 -20.272833) (xy 435.724914 -20.400854) (xy 435.740758 -20.53008)
			(xy 435.748696 -20.660033) (xy 435.749192 -20.72513) (xy 435.748696 -20.790227) (xy 435.740758 -20.92018)
			(xy 435.724914 -21.049406) (xy 435.70122 -21.177427) (xy 435.669766 -21.303765) (xy 435.630668 -21.42795)
			(xy 435.584073 -21.549521) (xy 435.530152 -21.668025) (xy 435.498895 -21.726906) (xy 442.373766 -21.726906)
			(xy 442.374302 -21.698168) (xy 442.382923 -21.641341) (xy 442.399971 -21.586451) (xy 442.425059 -21.534739)
			(xy 442.457621 -21.487376) (xy 442.47689 -21.466048) (xy 442.483494 -21.45919) (xy 442.490606 -21.441156)
			(xy 442.490606 -21.352256) (xy 442.483494 -21.334222) (xy 442.47689 -21.327364) (xy 442.457627 -21.306031)
			(xy 442.425064 -21.258669) (xy 442.399974 -21.206958) (xy 442.382926 -21.152068) (xy 442.374303 -21.095243)
			(xy 442.374303 -21.037766) (xy 442.382924 -20.98094) (xy 442.399971 -20.92605) (xy 442.42506 -20.874339)
			(xy 442.457621 -20.826976) (xy 442.47689 -20.805648) (xy 442.483494 -20.79879) (xy 442.490606 -20.780756)
			(xy 442.490606 -20.691856) (xy 442.483494 -20.673822) (xy 442.47689 -20.666964) (xy 442.457627 -20.645631)
			(xy 442.425064 -20.598269) (xy 442.399974 -20.546558) (xy 442.382926 -20.491668) (xy 442.374303 -20.434843)
			(xy 442.374303 -20.377366) (xy 442.382924 -20.32054) (xy 442.399971 -20.26565) (xy 442.42506 -20.213939)
			(xy 442.457621 -20.166576) (xy 442.47689 -20.145248) (xy 442.483494 -20.13839) (xy 442.490606 -20.120356)
			(xy 442.490606 -20.031456) (xy 442.483494 -20.013422) (xy 442.47689 -20.006564) (xy 442.457627 -19.985231)
			(xy 442.425064 -19.937869) (xy 442.399974 -19.886158) (xy 442.382926 -19.831268) (xy 442.374303 -19.774443)
			(xy 442.374303 -19.716966) (xy 442.382924 -19.66014) (xy 442.399971 -19.60525) (xy 442.42506 -19.553539)
			(xy 442.457621 -19.506176) (xy 442.47689 -19.484848) (xy 442.483494 -19.47799) (xy 442.490606 -19.459956)
			(xy 442.490606 -19.371056) (xy 442.483494 -19.353022) (xy 442.47689 -19.346164) (xy 442.457631 -19.324827)
			(xy 442.425061 -19.277468) (xy 442.399966 -19.225759) (xy 442.382913 -19.170871) (xy 442.374288 -19.114044)
			(xy 442.373766 -19.085306) (xy 442.374252 -19.058055) (xy 442.382008 -19.004107) (xy 442.397363 -18.951812)
			(xy 442.420005 -18.902235) (xy 442.449471 -18.856385) (xy 442.485162 -18.815194) (xy 442.526353 -18.779503)
			(xy 442.572203 -18.750037) (xy 442.62178 -18.727395) (xy 442.674075 -18.71204) (xy 442.728023 -18.704284)
			(xy 442.782525 -18.704284) (xy 442.836473 -18.71204) (xy 442.888768 -18.727395) (xy 442.938345 -18.750037)
			(xy 442.984195 -18.779503) (xy 443.025386 -18.815194) (xy 443.061077 -18.856385) (xy 443.090543 -18.902235)
			(xy 443.113185 -18.951812) (xy 443.12854 -19.004107) (xy 443.136296 -19.058055) (xy 443.136782 -19.085306)
			(xy 443.13624 -19.114044) (xy 443.127619 -19.17087) (xy 443.110572 -19.225759) (xy 443.085485 -19.277471)
			(xy 443.052925 -19.324835) (xy 443.033658 -19.346164) (xy 443.027054 -19.353022) (xy 443.019942 -19.371056)
			(xy 443.019942 -19.453098) (xy 448.57619 -19.453098) (xy 448.580261 -19.397476) (xy 448.592387 -19.343039)
			(xy 448.61231 -19.290948) (xy 448.639606 -19.242313) (xy 448.673692 -19.19817) (xy 448.713841 -19.159461)
			(xy 448.759199 -19.12701) (xy 448.808799 -19.101509) (xy 448.861583 -19.083502) (xy 448.916426 -19.073372)
			(xy 448.97216 -19.071335) (xy 449.027597 -19.077435) (xy 449.081554 -19.091541) (xy 449.132883 -19.113353)
			(xy 449.180489 -19.142407) (xy 449.223357 -19.178082) (xy 449.260574 -19.219619) (xy 449.291347 -19.266132)
			(xy 449.315019 -19.316629) (xy 449.331087 -19.370036) (xy 449.339207 -19.425212) (xy 449.339716 -19.453098)
			(xy 449.339207 -19.480984) (xy 449.331087 -19.53616) (xy 449.315019 -19.589567) (xy 449.291347 -19.640064)
			(xy 449.260574 -19.686577) (xy 449.223357 -19.728114) (xy 449.180489 -19.763789) (xy 449.132883 -19.792843)
			(xy 449.081554 -19.814655) (xy 449.027597 -19.828761) (xy 448.97216 -19.834861) (xy 448.916426 -19.832824)
			(xy 448.861583 -19.822694) (xy 448.808799 -19.804687) (xy 448.759199 -19.779186) (xy 448.713841 -19.746735)
			(xy 448.673692 -19.708026) (xy 448.639606 -19.663883) (xy 448.61231 -19.615248) (xy 448.592387 -19.563157)
			(xy 448.580261 -19.50872) (xy 448.57619 -19.453098) (xy 443.019942 -19.453098) (xy 443.019942 -19.459956)
			(xy 443.027054 -19.47799) (xy 443.033658 -19.484848) (xy 443.052936 -19.506169) (xy 443.085502 -19.553532)
			(xy 443.110595 -19.605245) (xy 443.127645 -19.660136) (xy 443.136267 -19.716965) (xy 443.136267 -19.774444)
			(xy 443.127643 -19.831272) (xy 443.110591 -19.886163) (xy 443.085498 -19.937875) (xy 443.05293 -19.985238)
			(xy 443.033658 -20.006564) (xy 443.027054 -20.013422) (xy 443.019942 -20.031456) (xy 443.019942 -20.120356)
			(xy 443.027054 -20.13839) (xy 443.033658 -20.145248) (xy 443.052936 -20.166569) (xy 443.085502 -20.213932)
			(xy 443.110595 -20.265645) (xy 443.127645 -20.320536) (xy 443.136267 -20.377365) (xy 443.136267 -20.434844)
			(xy 443.1313 -20.467574) (xy 450.587362 -20.467574) (xy 450.591433 -20.411952) (xy 450.603559 -20.357515)
			(xy 450.623482 -20.305424) (xy 450.650778 -20.256789) (xy 450.684864 -20.212646) (xy 450.725013 -20.173937)
			(xy 450.770371 -20.141486) (xy 450.819971 -20.115985) (xy 450.872755 -20.097978) (xy 450.927598 -20.087848)
			(xy 450.983332 -20.085811) (xy 451.038769 -20.091911) (xy 451.092726 -20.106017) (xy 451.144055 -20.127829)
			(xy 451.191661 -20.156883) (xy 451.234529 -20.192558) (xy 451.271746 -20.234095) (xy 451.302519 -20.280608)
			(xy 451.326191 -20.331105) (xy 451.342259 -20.384512) (xy 451.350379 -20.439688) (xy 451.350888 -20.467574)
			(xy 451.350379 -20.49546) (xy 451.342259 -20.550636) (xy 451.326191 -20.604043) (xy 451.302519 -20.65454)
			(xy 451.271746 -20.701053) (xy 451.234529 -20.74259) (xy 451.191661 -20.778265) (xy 451.144055 -20.807319)
			(xy 451.092726 -20.829131) (xy 451.038769 -20.843237) (xy 450.983332 -20.849337) (xy 450.927598 -20.8473)
			(xy 450.872755 -20.83717) (xy 450.819971 -20.819163) (xy 450.770371 -20.793662) (xy 450.725013 -20.761211)
			(xy 450.684864 -20.722502) (xy 450.650778 -20.678359) (xy 450.623482 -20.629724) (xy 450.603559 -20.577633)
			(xy 450.591433 -20.523196) (xy 450.587362 -20.467574) (xy 443.1313 -20.467574) (xy 443.127643 -20.491672)
			(xy 443.110591 -20.546563) (xy 443.085498 -20.598275) (xy 443.05293 -20.645638) (xy 443.033658 -20.666964)
			(xy 443.027054 -20.673822) (xy 443.019942 -20.691856) (xy 443.019942 -20.780756) (xy 443.027054 -20.79879)
			(xy 443.033658 -20.805648) (xy 443.052936 -20.826969) (xy 443.085502 -20.874332) (xy 443.110595 -20.926045)
			(xy 443.127645 -20.980936) (xy 443.136267 -21.037765) (xy 443.136267 -21.095244) (xy 443.127643 -21.152072)
			(xy 443.110591 -21.206963) (xy 443.085498 -21.258675) (xy 443.05293 -21.306038) (xy 443.033658 -21.327364)
			(xy 443.027054 -21.334222) (xy 443.019942 -21.352256) (xy 443.019942 -21.441156) (xy 443.027054 -21.45919)
			(xy 443.033658 -21.466048) (xy 443.052931 -21.487373) (xy 443.085497 -21.534736) (xy 443.110589 -21.586448)
			(xy 443.127639 -21.641339) (xy 443.136261 -21.698167) (xy 443.136782 -21.726906) (xy 443.136296 -21.754157)
			(xy 443.133203 -21.775674) (xy 452.235822 -21.775674) (xy 452.239893 -21.720052) (xy 452.252019 -21.665615)
			(xy 452.271942 -21.613524) (xy 452.299238 -21.564889) (xy 452.333324 -21.520746) (xy 452.373473 -21.482037)
			(xy 452.418831 -21.449586) (xy 452.468431 -21.424085) (xy 452.521215 -21.406078) (xy 452.576058 -21.395948)
			(xy 452.631792 -21.393911) (xy 452.687229 -21.400011) (xy 452.741186 -21.414117) (xy 452.792515 -21.435929)
			(xy 452.840121 -21.464983) (xy 452.882989 -21.500658) (xy 452.920206 -21.542195) (xy 452.950979 -21.588708)
			(xy 452.974651 -21.639205) (xy 452.990719 -21.692612) (xy 452.998839 -21.747788) (xy 452.999348 -21.775674)
			(xy 452.998839 -21.80356) (xy 452.990719 -21.858736) (xy 452.974651 -21.912143) (xy 452.950979 -21.96264)
			(xy 452.920206 -22.009153) (xy 452.882989 -22.05069) (xy 452.840121 -22.086365) (xy 452.792515 -22.115419)
			(xy 452.741186 -22.137231) (xy 452.687229 -22.151337) (xy 452.631792 -22.157437) (xy 452.576058 -22.1554)
			(xy 452.521215 -22.14527) (xy 452.468431 -22.127263) (xy 452.418831 -22.101762) (xy 452.373473 -22.069311)
			(xy 452.333324 -22.030602) (xy 452.299238 -21.986459) (xy 452.271942 -21.937824) (xy 452.252019 -21.885733)
			(xy 452.239893 -21.831296) (xy 452.235822 -21.775674) (xy 443.133203 -21.775674) (xy 443.12854 -21.808105)
			(xy 443.113185 -21.8604) (xy 443.090543 -21.909977) (xy 443.061077 -21.955827) (xy 443.025386 -21.997018)
			(xy 442.984195 -22.032709) (xy 442.938345 -22.062175) (xy 442.888768 -22.084817) (xy 442.836473 -22.100172)
			(xy 442.782525 -22.107928) (xy 442.728023 -22.107928) (xy 442.674075 -22.100172) (xy 442.62178 -22.084817)
			(xy 442.572203 -22.062175) (xy 442.526353 -22.032709) (xy 442.485162 -21.997018) (xy 442.449471 -21.955827)
			(xy 442.420005 -21.909977) (xy 442.397363 -21.8604) (xy 442.382008 -21.808105) (xy 442.374252 -21.754157)
			(xy 442.373766 -21.726906) (xy 435.498895 -21.726906) (xy 435.469107 -21.783021) (xy 435.401166 -21.894082)
			(xy 435.32658 -22.000794) (xy 435.245627 -22.102761) (xy 435.158608 -22.199603) (xy 435.065847 -22.29096)
			(xy 434.967689 -22.376492) (xy 434.8645 -22.45588) (xy 434.756663 -22.52883) (xy 434.711613 -22.555454)
			(xy 451.636382 -22.555454) (xy 451.640453 -22.499832) (xy 451.652579 -22.445395) (xy 451.672502 -22.393304)
			(xy 451.699798 -22.344669) (xy 451.733884 -22.300526) (xy 451.774033 -22.261817) (xy 451.819391 -22.229366)
			(xy 451.868991 -22.203865) (xy 451.921775 -22.185858) (xy 451.976618 -22.175728) (xy 452.032352 -22.173691)
			(xy 452.087789 -22.179791) (xy 452.141746 -22.193897) (xy 452.193075 -22.215709) (xy 452.240681 -22.244763)
			(xy 452.283549 -22.280438) (xy 452.320766 -22.321975) (xy 452.351539 -22.368488) (xy 452.375211 -22.418985)
			(xy 452.391279 -22.472392) (xy 452.399399 -22.527568) (xy 452.399908 -22.555454) (xy 452.399399 -22.58334)
			(xy 452.391279 -22.638516) (xy 452.375211 -22.691923) (xy 452.351539 -22.74242) (xy 452.320766 -22.788933)
			(xy 452.283549 -22.83047) (xy 452.240681 -22.866145) (xy 452.193075 -22.895199) (xy 452.141746 -22.917011)
			(xy 452.087789 -22.931117) (xy 452.032352 -22.937217) (xy 451.976618 -22.93518) (xy 451.921775 -22.92505)
			(xy 451.868991 -22.907043) (xy 451.819391 -22.881542) (xy 451.774033 -22.849091) (xy 451.733884 -22.810382)
			(xy 451.699798 -22.766239) (xy 451.672502 -22.717604) (xy 451.652579 -22.665513) (xy 451.640453 -22.611076)
			(xy 451.636382 -22.555454) (xy 434.711613 -22.555454) (xy 434.644578 -22.595071) (xy 434.528665 -22.654354)
			(xy 434.409352 -22.706462) (xy 434.287085 -22.751198) (xy 434.162318 -22.788397) (xy 434.035515 -22.817921)
			(xy 433.907148 -22.839659) (xy 433.777695 -22.853532) (xy 433.647636 -22.859486) (xy 433.517457 -22.857501)
			(xy 433.387641 -22.847583) (xy 433.258671 -22.829769) (xy 433.131026 -22.804126) (xy 433.005183 -22.770749)
			(xy 432.881608 -22.729762) (xy 432.760762 -22.681318) (xy 432.643094 -22.625596) (xy 432.529042 -22.562805)
			(xy 432.41903 -22.493178) (xy 432.313468 -22.416973) (xy 432.212748 -22.334474) (xy 432.117244 -22.245989)
			(xy 432.027312 -22.151846) (xy 431.943287 -22.052395) (xy 431.865482 -21.948007) (xy 431.794185 -21.83907)
			(xy 431.729661 -21.725988) (xy 431.672152 -21.609184) (xy 431.62187 -21.489091) (xy 431.579004 -21.366155)
			(xy 431.543711 -21.240836) (xy 431.516125 -21.113597) (xy 431.496346 -20.984914) (xy 431.48445 -20.855264)
			(xy 431.48048 -20.72513) (xy 425.250225 -20.72513) (xy 425.234581 -20.74259) (xy 425.191713 -20.778265)
			(xy 425.144107 -20.807319) (xy 425.092778 -20.829131) (xy 425.038821 -20.843237) (xy 424.983384 -20.849337)
			(xy 424.92765 -20.8473) (xy 424.872807 -20.83717) (xy 424.820023 -20.819163) (xy 424.770423 -20.793662)
			(xy 424.725065 -20.761211) (xy 424.684916 -20.722502) (xy 424.65083 -20.678359) (xy 424.623534 -20.629724)
			(xy 424.603611 -20.577633) (xy 424.591485 -20.523196) (xy 424.587414 -20.467574) (xy 417.131338 -20.467574)
			(xy 417.127682 -20.49167) (xy 417.110633 -20.546561) (xy 417.085543 -20.598273) (xy 417.05298 -20.645636)
			(xy 417.03371 -20.666964) (xy 417.027106 -20.673822) (xy 417.019994 -20.691856) (xy 417.019994 -20.780756)
			(xy 417.027106 -20.79879) (xy 417.03371 -20.805648) (xy 417.052985 -20.82697) (xy 417.085547 -20.874335)
			(xy 417.110636 -20.926047) (xy 417.127684 -20.980938) (xy 417.136306 -21.037766) (xy 417.136305 -21.095243)
			(xy 417.127682 -21.15207) (xy 417.110633 -21.206961) (xy 417.085543 -21.258673) (xy 417.05298 -21.306036)
			(xy 417.03371 -21.327364) (xy 417.027106 -21.334222) (xy 417.019994 -21.352256) (xy 417.019994 -21.441156)
			(xy 417.027106 -21.45919) (xy 417.03371 -21.466048) (xy 417.052975 -21.487381) (xy 417.085544 -21.53474)
			(xy 417.110638 -21.58645) (xy 417.12769 -21.64134) (xy 417.136313 -21.698167) (xy 417.136834 -21.726906)
			(xy 417.136348 -21.754157) (xy 417.133255 -21.775674) (xy 426.235874 -21.775674) (xy 426.239945 -21.720052)
			(xy 426.252071 -21.665615) (xy 426.271994 -21.613524) (xy 426.29929 -21.564889) (xy 426.333376 -21.520746)
			(xy 426.373525 -21.482037) (xy 426.418883 -21.449586) (xy 426.468483 -21.424085) (xy 426.521267 -21.406078)
			(xy 426.57611 -21.395948) (xy 426.631844 -21.393911) (xy 426.687281 -21.400011) (xy 426.741238 -21.414117)
			(xy 426.792567 -21.435929) (xy 426.840173 -21.464983) (xy 426.883041 -21.500658) (xy 426.920258 -21.542195)
			(xy 426.951031 -21.588708) (xy 426.974703 -21.639205) (xy 426.990771 -21.692612) (xy 426.998891 -21.747788)
			(xy 426.9994 -21.775674) (xy 426.998891 -21.80356) (xy 426.99122 -21.855684) (xy 427.13859 -21.855684)
			(xy 427.142661 -21.800062) (xy 427.154787 -21.745625) (xy 427.17471 -21.693534) (xy 427.202006 -21.644899)
			(xy 427.236092 -21.600756) (xy 427.276241 -21.562047) (xy 427.321599 -21.529596) (xy 427.371199 -21.504095)
			(xy 427.423983 -21.486088) (xy 427.478826 -21.475958) (xy 427.53456 -21.473921) (xy 427.589997 -21.480021)
			(xy 427.643954 -21.494127) (xy 427.695283 -21.515939) (xy 427.742889 -21.544993) (xy 427.785757 -21.580668)
			(xy 427.822974 -21.622205) (xy 427.853747 -21.668718) (xy 427.877419 -21.719215) (xy 427.893487 -21.772622)
			(xy 427.901607 -21.827798) (xy 427.901958 -21.847048) (xy 428.372776 -21.847048) (xy 428.376847 -21.791426)
			(xy 428.388973 -21.736989) (xy 428.408896 -21.684898) (xy 428.436192 -21.636263) (xy 428.470278 -21.59212)
			(xy 428.510427 -21.553411) (xy 428.555785 -21.52096) (xy 428.605385 -21.495459) (xy 428.658169 -21.477452)
			(xy 428.713012 -21.467322) (xy 428.768746 -21.465285) (xy 428.824183 -21.471385) (xy 428.87814 -21.485491)
			(xy 428.929469 -21.507303) (xy 428.977075 -21.536357) (xy 429.019943 -21.572032) (xy 429.05716 -21.613569)
			(xy 429.087933 -21.660082) (xy 429.111605 -21.710579) (xy 429.127673 -21.763986) (xy 429.135793 -21.819162)
			(xy 429.136302 -21.847048) (xy 429.135793 -21.874934) (xy 429.127673 -21.93011) (xy 429.111605 -21.983517)
			(xy 429.087933 -22.034014) (xy 429.05716 -22.080527) (xy 429.019943 -22.122064) (xy 428.977075 -22.157739)
			(xy 428.929469 -22.186793) (xy 428.87814 -22.208605) (xy 428.824183 -22.222711) (xy 428.768746 -22.228811)
			(xy 428.713012 -22.226774) (xy 428.658169 -22.216644) (xy 428.605385 -22.198637) (xy 428.555785 -22.173136)
			(xy 428.510427 -22.140685) (xy 428.470278 -22.101976) (xy 428.436192 -22.057833) (xy 428.408896 -22.009198)
			(xy 428.388973 -21.957107) (xy 428.376847 -21.90267) (xy 428.372776 -21.847048) (xy 427.901958 -21.847048)
			(xy 427.902116 -21.855684) (xy 427.901607 -21.88357) (xy 427.893487 -21.938746) (xy 427.877419 -21.992153)
			(xy 427.853747 -22.04265) (xy 427.822974 -22.089163) (xy 427.785757 -22.1307) (xy 427.742889 -22.166375)
			(xy 427.695283 -22.195429) (xy 427.643954 -22.217241) (xy 427.589997 -22.231347) (xy 427.53456 -22.237447)
			(xy 427.478826 -22.23541) (xy 427.423983 -22.22528) (xy 427.371199 -22.207273) (xy 427.321599 -22.181772)
			(xy 427.276241 -22.149321) (xy 427.236092 -22.110612) (xy 427.202006 -22.066469) (xy 427.17471 -22.017834)
			(xy 427.154787 -21.965743) (xy 427.142661 -21.911306) (xy 427.13859 -21.855684) (xy 426.99122 -21.855684)
			(xy 426.990771 -21.858736) (xy 426.974703 -21.912143) (xy 426.951031 -21.96264) (xy 426.920258 -22.009153)
			(xy 426.883041 -22.05069) (xy 426.840173 -22.086365) (xy 426.792567 -22.115419) (xy 426.741238 -22.137231)
			(xy 426.687281 -22.151337) (xy 426.631844 -22.157437) (xy 426.57611 -22.1554) (xy 426.521267 -22.14527)
			(xy 426.468483 -22.127263) (xy 426.418883 -22.101762) (xy 426.373525 -22.069311) (xy 426.333376 -22.030602)
			(xy 426.29929 -21.986459) (xy 426.271994 -21.937824) (xy 426.252071 -21.885733) (xy 426.239945 -21.831296)
			(xy 426.235874 -21.775674) (xy 417.133255 -21.775674) (xy 417.128592 -21.808105) (xy 417.113237 -21.8604)
			(xy 417.090595 -21.909977) (xy 417.061129 -21.955827) (xy 417.025438 -21.997018) (xy 416.984247 -22.032709)
			(xy 416.938397 -22.062175) (xy 416.88882 -22.084817) (xy 416.836525 -22.100172) (xy 416.782577 -22.107928)
			(xy 416.728075 -22.107928) (xy 416.674127 -22.100172) (xy 416.621832 -22.084817) (xy 416.572255 -22.062175)
			(xy 416.526405 -22.032709) (xy 416.485214 -21.997018) (xy 416.449523 -21.955827) (xy 416.420057 -21.909977)
			(xy 416.397415 -21.8604) (xy 416.38206 -21.808105) (xy 416.374304 -21.754157) (xy 416.373818 -21.726906)
			(xy 409.498947 -21.726906) (xy 409.469159 -21.783021) (xy 409.401218 -21.894082) (xy 409.326632 -22.000794)
			(xy 409.245679 -22.102761) (xy 409.15866 -22.199603) (xy 409.065899 -22.29096) (xy 408.967741 -22.376492)
			(xy 408.864552 -22.45588) (xy 408.756715 -22.52883) (xy 408.711665 -22.555454) (xy 425.636434 -22.555454)
			(xy 425.640505 -22.499832) (xy 425.652631 -22.445395) (xy 425.672554 -22.393304) (xy 425.69985 -22.344669)
			(xy 425.733936 -22.300526) (xy 425.774085 -22.261817) (xy 425.819443 -22.229366) (xy 425.869043 -22.203865)
			(xy 425.921827 -22.185858) (xy 425.97667 -22.175728) (xy 426.032404 -22.173691) (xy 426.087841 -22.179791)
			(xy 426.141798 -22.193897) (xy 426.193127 -22.215709) (xy 426.240733 -22.244763) (xy 426.283601 -22.280438)
			(xy 426.320818 -22.321975) (xy 426.351591 -22.368488) (xy 426.375263 -22.418985) (xy 426.391331 -22.472392)
			(xy 426.399451 -22.527568) (xy 426.39996 -22.555454) (xy 426.399451 -22.58334) (xy 426.391331 -22.638516)
			(xy 426.375263 -22.691923) (xy 426.351591 -22.74242) (xy 426.320818 -22.788933) (xy 426.283601 -22.83047)
			(xy 426.240733 -22.866145) (xy 426.193127 -22.895199) (xy 426.141798 -22.917011) (xy 426.087841 -22.931117)
			(xy 426.032404 -22.937217) (xy 425.97667 -22.93518) (xy 425.921827 -22.92505) (xy 425.869043 -22.907043)
			(xy 425.819443 -22.881542) (xy 425.774085 -22.849091) (xy 425.733936 -22.810382) (xy 425.69985 -22.766239)
			(xy 425.672554 -22.717604) (xy 425.652631 -22.665513) (xy 425.640505 -22.611076) (xy 425.636434 -22.555454)
			(xy 408.711665 -22.555454) (xy 408.64463 -22.595071) (xy 408.528717 -22.654354) (xy 408.409404 -22.706462)
			(xy 408.287137 -22.751198) (xy 408.16237 -22.788397) (xy 408.035567 -22.817921) (xy 407.9072 -22.839659)
			(xy 407.777747 -22.853532) (xy 407.647688 -22.859486) (xy 407.517509 -22.857501) (xy 407.387693 -22.847583)
			(xy 407.258723 -22.829769) (xy 407.131078 -22.804126) (xy 407.005235 -22.770749) (xy 406.88166 -22.729762)
			(xy 406.760814 -22.681318) (xy 406.643146 -22.625596) (xy 406.529094 -22.562805) (xy 406.419082 -22.493178)
			(xy 406.31352 -22.416973) (xy 406.2128 -22.334474) (xy 406.117296 -22.245989) (xy 406.027364 -22.151846)
			(xy 405.943339 -22.052395) (xy 405.865534 -21.948007) (xy 405.794237 -21.83907) (xy 405.729713 -21.725988)
			(xy 405.672204 -21.609184) (xy 405.621922 -21.489091) (xy 405.579056 -21.366155) (xy 405.543763 -21.240836)
			(xy 405.516177 -21.113597) (xy 405.496398 -20.984914) (xy 405.484502 -20.855264) (xy 405.480532 -20.72513)
			(xy 399.250277 -20.72513) (xy 399.234633 -20.74259) (xy 399.191765 -20.778265) (xy 399.144159 -20.807319)
			(xy 399.09283 -20.829131) (xy 399.038873 -20.843237) (xy 398.983436 -20.849337) (xy 398.927702 -20.8473)
			(xy 398.872859 -20.83717) (xy 398.820075 -20.819163) (xy 398.770475 -20.793662) (xy 398.725117 -20.761211)
			(xy 398.684968 -20.722502) (xy 398.650882 -20.678359) (xy 398.623586 -20.629724) (xy 398.603663 -20.577633)
			(xy 398.591537 -20.523196) (xy 398.587466 -20.467574) (xy 391.131403 -20.467574) (xy 391.127746 -20.491672)
			(xy 391.110695 -20.546563) (xy 391.085601 -20.598275) (xy 391.053034 -20.645638) (xy 391.033762 -20.666964)
			(xy 391.027158 -20.673822) (xy 391.020046 -20.691856) (xy 391.020046 -20.780756) (xy 391.027158 -20.79879)
			(xy 391.033762 -20.805648) (xy 391.053039 -20.826969) (xy 391.085606 -20.874332) (xy 391.110698 -20.926045)
			(xy 391.127748 -20.980937) (xy 391.13637 -21.037765) (xy 391.13637 -21.095244) (xy 391.127746 -21.152072)
			(xy 391.110695 -21.206963) (xy 391.085601 -21.258675) (xy 391.053034 -21.306038) (xy 391.033762 -21.327364)
			(xy 391.027158 -21.334222) (xy 391.020046 -21.352256) (xy 391.020046 -21.441156) (xy 391.027158 -21.45919)
			(xy 391.033762 -21.466048) (xy 391.053036 -21.487373) (xy 391.085601 -21.534735) (xy 391.110693 -21.586448)
			(xy 391.127743 -21.641339) (xy 391.136365 -21.698167) (xy 391.136886 -21.726906) (xy 391.1364 -21.754157)
			(xy 391.133307 -21.775674) (xy 400.235926 -21.775674) (xy 400.239997 -21.720052) (xy 400.252123 -21.665615)
			(xy 400.272046 -21.613524) (xy 400.299342 -21.564889) (xy 400.333428 -21.520746) (xy 400.373577 -21.482037)
			(xy 400.418935 -21.449586) (xy 400.468535 -21.424085) (xy 400.521319 -21.406078) (xy 400.576162 -21.395948)
			(xy 400.631896 -21.393911) (xy 400.687333 -21.400011) (xy 400.74129 -21.414117) (xy 400.792619 -21.435929)
			(xy 400.840225 -21.464983) (xy 400.883093 -21.500658) (xy 400.92031 -21.542195) (xy 400.951083 -21.588708)
			(xy 400.974755 -21.639205) (xy 400.990823 -21.692612) (xy 400.998943 -21.747788) (xy 400.999452 -21.775674)
			(xy 400.998943 -21.80356) (xy 400.991272 -21.855684) (xy 401.138642 -21.855684) (xy 401.142713 -21.800062)
			(xy 401.154839 -21.745625) (xy 401.174762 -21.693534) (xy 401.202058 -21.644899) (xy 401.236144 -21.600756)
			(xy 401.276293 -21.562047) (xy 401.321651 -21.529596) (xy 401.371251 -21.504095) (xy 401.424035 -21.486088)
			(xy 401.478878 -21.475958) (xy 401.534612 -21.473921) (xy 401.590049 -21.480021) (xy 401.644006 -21.494127)
			(xy 401.695335 -21.515939) (xy 401.742941 -21.544993) (xy 401.785809 -21.580668) (xy 401.823026 -21.622205)
			(xy 401.853799 -21.668718) (xy 401.877471 -21.719215) (xy 401.893539 -21.772622) (xy 401.901659 -21.827798)
			(xy 401.90201 -21.847048) (xy 402.372828 -21.847048) (xy 402.376899 -21.791426) (xy 402.389025 -21.736989)
			(xy 402.408948 -21.684898) (xy 402.436244 -21.636263) (xy 402.47033 -21.59212) (xy 402.510479 -21.553411)
			(xy 402.555837 -21.52096) (xy 402.605437 -21.495459) (xy 402.658221 -21.477452) (xy 402.713064 -21.467322)
			(xy 402.768798 -21.465285) (xy 402.824235 -21.471385) (xy 402.878192 -21.485491) (xy 402.929521 -21.507303)
			(xy 402.977127 -21.536357) (xy 403.019995 -21.572032) (xy 403.057212 -21.613569) (xy 403.087985 -21.660082)
			(xy 403.111657 -21.710579) (xy 403.127725 -21.763986) (xy 403.135845 -21.819162) (xy 403.136354 -21.847048)
			(xy 403.135845 -21.874934) (xy 403.127725 -21.93011) (xy 403.111657 -21.983517) (xy 403.087985 -22.034014)
			(xy 403.057212 -22.080527) (xy 403.019995 -22.122064) (xy 402.977127 -22.157739) (xy 402.929521 -22.186793)
			(xy 402.878192 -22.208605) (xy 402.824235 -22.222711) (xy 402.768798 -22.228811) (xy 402.713064 -22.226774)
			(xy 402.658221 -22.216644) (xy 402.605437 -22.198637) (xy 402.555837 -22.173136) (xy 402.510479 -22.140685)
			(xy 402.47033 -22.101976) (xy 402.436244 -22.057833) (xy 402.408948 -22.009198) (xy 402.389025 -21.957107)
			(xy 402.376899 -21.90267) (xy 402.372828 -21.847048) (xy 401.90201 -21.847048) (xy 401.902168 -21.855684)
			(xy 401.901659 -21.88357) (xy 401.893539 -21.938746) (xy 401.877471 -21.992153) (xy 401.853799 -22.04265)
			(xy 401.823026 -22.089163) (xy 401.785809 -22.1307) (xy 401.742941 -22.166375) (xy 401.695335 -22.195429)
			(xy 401.644006 -22.217241) (xy 401.590049 -22.231347) (xy 401.534612 -22.237447) (xy 401.478878 -22.23541)
			(xy 401.424035 -22.22528) (xy 401.371251 -22.207273) (xy 401.321651 -22.181772) (xy 401.276293 -22.149321)
			(xy 401.236144 -22.110612) (xy 401.202058 -22.066469) (xy 401.174762 -22.017834) (xy 401.154839 -21.965743)
			(xy 401.142713 -21.911306) (xy 401.138642 -21.855684) (xy 400.991272 -21.855684) (xy 400.990823 -21.858736)
			(xy 400.974755 -21.912143) (xy 400.951083 -21.96264) (xy 400.92031 -22.009153) (xy 400.883093 -22.05069)
			(xy 400.840225 -22.086365) (xy 400.792619 -22.115419) (xy 400.74129 -22.137231) (xy 400.687333 -22.151337)
			(xy 400.631896 -22.157437) (xy 400.576162 -22.1554) (xy 400.521319 -22.14527) (xy 400.468535 -22.127263)
			(xy 400.418935 -22.101762) (xy 400.373577 -22.069311) (xy 400.333428 -22.030602) (xy 400.299342 -21.986459)
			(xy 400.272046 -21.937824) (xy 400.252123 -21.885733) (xy 400.239997 -21.831296) (xy 400.235926 -21.775674)
			(xy 391.133307 -21.775674) (xy 391.128644 -21.808105) (xy 391.113289 -21.8604) (xy 391.090647 -21.909977)
			(xy 391.061181 -21.955827) (xy 391.02549 -21.997018) (xy 390.984299 -22.032709) (xy 390.938449 -22.062175)
			(xy 390.888872 -22.084817) (xy 390.836577 -22.100172) (xy 390.782629 -22.107928) (xy 390.728127 -22.107928)
			(xy 390.674179 -22.100172) (xy 390.621884 -22.084817) (xy 390.572307 -22.062175) (xy 390.526457 -22.032709)
			(xy 390.485266 -21.997018) (xy 390.449575 -21.955827) (xy 390.420109 -21.909977) (xy 390.397467 -21.8604)
			(xy 390.382112 -21.808105) (xy 390.374356 -21.754157) (xy 390.37387 -21.726906) (xy 383.501129 -21.726906)
			(xy 383.474037 -21.777941) (xy 383.406096 -21.889002) (xy 383.33151 -21.995714) (xy 383.250557 -22.097681)
			(xy 383.163538 -22.194523) (xy 383.070777 -22.28588) (xy 382.972619 -22.371412) (xy 382.86943 -22.4508)
			(xy 382.761593 -22.52375) (xy 382.707947 -22.555454) (xy 399.636486 -22.555454) (xy 399.640557 -22.499832)
			(xy 399.652683 -22.445395) (xy 399.672606 -22.393304) (xy 399.699902 -22.344669) (xy 399.733988 -22.300526)
			(xy 399.774137 -22.261817) (xy 399.819495 -22.229366) (xy 399.869095 -22.203865) (xy 399.921879 -22.185858)
			(xy 399.976722 -22.175728) (xy 400.032456 -22.173691) (xy 400.087893 -22.179791) (xy 400.14185 -22.193897)
			(xy 400.193179 -22.215709) (xy 400.240785 -22.244763) (xy 400.283653 -22.280438) (xy 400.32087 -22.321975)
			(xy 400.351643 -22.368488) (xy 400.375315 -22.418985) (xy 400.391383 -22.472392) (xy 400.399503 -22.527568)
			(xy 400.400012 -22.555454) (xy 400.399503 -22.58334) (xy 400.391383 -22.638516) (xy 400.375315 -22.691923)
			(xy 400.351643 -22.74242) (xy 400.32087 -22.788933) (xy 400.283653 -22.83047) (xy 400.240785 -22.866145)
			(xy 400.193179 -22.895199) (xy 400.14185 -22.917011) (xy 400.087893 -22.931117) (xy 400.032456 -22.937217)
			(xy 399.976722 -22.93518) (xy 399.921879 -22.92505) (xy 399.869095 -22.907043) (xy 399.819495 -22.881542)
			(xy 399.774137 -22.849091) (xy 399.733988 -22.810382) (xy 399.699902 -22.766239) (xy 399.672606 -22.717604)
			(xy 399.652683 -22.665513) (xy 399.640557 -22.611076) (xy 399.636486 -22.555454) (xy 382.707947 -22.555454)
			(xy 382.649508 -22.589991) (xy 382.533595 -22.649274) (xy 382.414282 -22.701382) (xy 382.292015 -22.746118)
			(xy 382.167248 -22.783317) (xy 382.040445 -22.812841) (xy 381.912078 -22.834579) (xy 381.782625 -22.848452)
			(xy 381.652566 -22.854406) (xy 381.522387 -22.852421) (xy 381.392571 -22.842503) (xy 381.263601 -22.824689)
			(xy 381.135956 -22.799046) (xy 381.010113 -22.765669) (xy 380.886538 -22.724682) (xy 380.765692 -22.676238)
			(xy 380.648024 -22.620516) (xy 380.533972 -22.557725) (xy 380.42396 -22.488098) (xy 380.318398 -22.411893)
			(xy 380.217678 -22.329394) (xy 380.122174 -22.240909) (xy 380.032242 -22.146766) (xy 379.948217 -22.047315)
			(xy 379.870412 -21.942927) (xy 379.799115 -21.83399) (xy 379.734591 -21.720908) (xy 379.677082 -21.604104)
			(xy 379.6268 -21.484011) (xy 379.583934 -21.361075) (xy 379.548641 -21.235756) (xy 379.521055 -21.108517)
			(xy 379.501276 -20.979834) (xy 379.48938 -20.850184) (xy 379.48541 -20.72005) (xy 373.254881 -20.72005)
			(xy 373.234685 -20.74259) (xy 373.191817 -20.778265) (xy 373.144211 -20.807319) (xy 373.092882 -20.829131)
			(xy 373.038925 -20.843237) (xy 372.983488 -20.849337) (xy 372.927754 -20.8473) (xy 372.872911 -20.83717)
			(xy 372.820127 -20.819163) (xy 372.770527 -20.793662) (xy 372.725169 -20.761211) (xy 372.68502 -20.722502)
			(xy 372.650934 -20.678359) (xy 372.623638 -20.629724) (xy 372.603715 -20.577633) (xy 372.591589 -20.523196)
			(xy 372.587518 -20.467574) (xy 365.106424 -20.467574) (xy 365.08565 -20.510388) (xy 365.053085 -20.557752)
			(xy 365.033814 -20.57908) (xy 365.02721 -20.585938) (xy 365.020098 -20.603972) (xy 365.020098 -20.692872)
			(xy 365.02721 -20.710906) (xy 365.033814 -20.717764) (xy 365.053105 -20.739073) (xy 365.085666 -20.786439)
			(xy 365.110754 -20.838154) (xy 365.127801 -20.893047) (xy 365.13642 -20.949877) (xy 365.136418 -21.007356)
			(xy 365.127793 -21.064184) (xy 365.110742 -21.119076) (xy 365.08565 -21.170788) (xy 365.053085 -21.218152)
			(xy 365.033814 -21.23948) (xy 365.02721 -21.246338) (xy 365.020098 -21.264372) (xy 365.020098 -21.353272)
			(xy 365.02721 -21.371306) (xy 365.033814 -21.378164) (xy 365.053087 -21.399489) (xy 365.085655 -21.446851)
			(xy 365.110748 -21.498563) (xy 365.127798 -21.553454) (xy 365.136419 -21.610283) (xy 365.136938 -21.639022)
			(xy 365.136452 -21.666273) (xy 365.128696 -21.720221) (xy 365.113341 -21.772516) (xy 365.111899 -21.775674)
			(xy 374.235978 -21.775674) (xy 374.240049 -21.720052) (xy 374.252175 -21.665615) (xy 374.272098 -21.613524)
			(xy 374.299394 -21.564889) (xy 374.33348 -21.520746) (xy 374.373629 -21.482037) (xy 374.418987 -21.449586)
			(xy 374.468587 -21.424085) (xy 374.521371 -21.406078) (xy 374.576214 -21.395948) (xy 374.631948 -21.393911)
			(xy 374.687385 -21.400011) (xy 374.741342 -21.414117) (xy 374.792671 -21.435929) (xy 374.840277 -21.464983)
			(xy 374.883145 -21.500658) (xy 374.920362 -21.542195) (xy 374.951135 -21.588708) (xy 374.974807 -21.639205)
			(xy 374.990875 -21.692612) (xy 374.998995 -21.747788) (xy 374.999504 -21.775674) (xy 374.998995 -21.80356)
			(xy 374.991324 -21.855684) (xy 375.138694 -21.855684) (xy 375.142765 -21.800062) (xy 375.154891 -21.745625)
			(xy 375.174814 -21.693534) (xy 375.20211 -21.644899) (xy 375.236196 -21.600756) (xy 375.276345 -21.562047)
			(xy 375.321703 -21.529596) (xy 375.371303 -21.504095) (xy 375.424087 -21.486088) (xy 375.47893 -21.475958)
			(xy 375.534664 -21.473921) (xy 375.590101 -21.480021) (xy 375.644058 -21.494127) (xy 375.695387 -21.515939)
			(xy 375.742993 -21.544993) (xy 375.785861 -21.580668) (xy 375.823078 -21.622205) (xy 375.853851 -21.668718)
			(xy 375.877523 -21.719215) (xy 375.893591 -21.772622) (xy 375.901711 -21.827798) (xy 375.902062 -21.847048)
			(xy 376.37288 -21.847048) (xy 376.376951 -21.791426) (xy 376.389077 -21.736989) (xy 376.409 -21.684898)
			(xy 376.436296 -21.636263) (xy 376.470382 -21.59212) (xy 376.510531 -21.553411) (xy 376.555889 -21.52096)
			(xy 376.605489 -21.495459) (xy 376.658273 -21.477452) (xy 376.713116 -21.467322) (xy 376.76885 -21.465285)
			(xy 376.824287 -21.471385) (xy 376.878244 -21.485491) (xy 376.929573 -21.507303) (xy 376.977179 -21.536357)
			(xy 377.020047 -21.572032) (xy 377.057264 -21.613569) (xy 377.088037 -21.660082) (xy 377.111709 -21.710579)
			(xy 377.127777 -21.763986) (xy 377.135897 -21.819162) (xy 377.136406 -21.847048) (xy 377.135897 -21.874934)
			(xy 377.127777 -21.93011) (xy 377.111709 -21.983517) (xy 377.088037 -22.034014) (xy 377.057264 -22.080527)
			(xy 377.020047 -22.122064) (xy 376.977179 -22.157739) (xy 376.929573 -22.186793) (xy 376.878244 -22.208605)
			(xy 376.824287 -22.222711) (xy 376.76885 -22.228811) (xy 376.713116 -22.226774) (xy 376.658273 -22.216644)
			(xy 376.605489 -22.198637) (xy 376.555889 -22.173136) (xy 376.510531 -22.140685) (xy 376.470382 -22.101976)
			(xy 376.436296 -22.057833) (xy 376.409 -22.009198) (xy 376.389077 -21.957107) (xy 376.376951 -21.90267)
			(xy 376.37288 -21.847048) (xy 375.902062 -21.847048) (xy 375.90222 -21.855684) (xy 375.901711 -21.88357)
			(xy 375.893591 -21.938746) (xy 375.877523 -21.992153) (xy 375.853851 -22.04265) (xy 375.823078 -22.089163)
			(xy 375.785861 -22.1307) (xy 375.742993 -22.166375) (xy 375.695387 -22.195429) (xy 375.644058 -22.217241)
			(xy 375.590101 -22.231347) (xy 375.534664 -22.237447) (xy 375.47893 -22.23541) (xy 375.424087 -22.22528)
			(xy 375.371303 -22.207273) (xy 375.321703 -22.181772) (xy 375.276345 -22.149321) (xy 375.236196 -22.110612)
			(xy 375.20211 -22.066469) (xy 375.174814 -22.017834) (xy 375.154891 -21.965743) (xy 375.142765 -21.911306)
			(xy 375.138694 -21.855684) (xy 374.991324 -21.855684) (xy 374.990875 -21.858736) (xy 374.974807 -21.912143)
			(xy 374.951135 -21.96264) (xy 374.920362 -22.009153) (xy 374.883145 -22.05069) (xy 374.840277 -22.086365)
			(xy 374.792671 -22.115419) (xy 374.741342 -22.137231) (xy 374.687385 -22.151337) (xy 374.631948 -22.157437)
			(xy 374.576214 -22.1554) (xy 374.521371 -22.14527) (xy 374.468587 -22.127263) (xy 374.418987 -22.101762)
			(xy 374.373629 -22.069311) (xy 374.33348 -22.030602) (xy 374.299394 -21.986459) (xy 374.272098 -21.937824)
			(xy 374.252175 -21.885733) (xy 374.240049 -21.831296) (xy 374.235978 -21.775674) (xy 365.111899 -21.775674)
			(xy 365.090699 -21.822093) (xy 365.061233 -21.867943) (xy 365.025542 -21.909134) (xy 364.984351 -21.944825)
			(xy 364.938501 -21.974291) (xy 364.888924 -21.996933) (xy 364.836629 -22.012288) (xy 364.782681 -22.020044)
			(xy 364.728179 -22.020044) (xy 364.674231 -22.012288) (xy 364.621936 -21.996933) (xy 364.572359 -21.974291)
			(xy 364.526509 -21.944825) (xy 364.485318 -21.909134) (xy 364.449627 -21.867943) (xy 364.420161 -21.822093)
			(xy 364.397519 -21.772516) (xy 364.382164 -21.720221) (xy 364.374408 -21.666273) (xy 364.373922 -21.639022)
			(xy 357.543505 -21.639022) (xy 357.530308 -21.668025) (xy 357.469263 -21.783021) (xy 357.401322 -21.894082)
			(xy 357.326736 -22.000794) (xy 357.245783 -22.102761) (xy 357.158764 -22.199603) (xy 357.066003 -22.29096)
			(xy 356.967845 -22.376492) (xy 356.864656 -22.45588) (xy 356.756819 -22.52883) (xy 356.711769 -22.555454)
			(xy 373.636538 -22.555454) (xy 373.640609 -22.499832) (xy 373.652735 -22.445395) (xy 373.672658 -22.393304)
			(xy 373.699954 -22.344669) (xy 373.73404 -22.300526) (xy 373.774189 -22.261817) (xy 373.819547 -22.229366)
			(xy 373.869147 -22.203865) (xy 373.921931 -22.185858) (xy 373.976774 -22.175728) (xy 374.032508 -22.173691)
			(xy 374.087945 -22.179791) (xy 374.141902 -22.193897) (xy 374.193231 -22.215709) (xy 374.240837 -22.244763)
			(xy 374.283705 -22.280438) (xy 374.320922 -22.321975) (xy 374.351695 -22.368488) (xy 374.375367 -22.418985)
			(xy 374.391435 -22.472392) (xy 374.399555 -22.527568) (xy 374.400064 -22.555454) (xy 374.399555 -22.58334)
			(xy 374.391435 -22.638516) (xy 374.375367 -22.691923) (xy 374.351695 -22.74242) (xy 374.320922 -22.788933)
			(xy 374.283705 -22.83047) (xy 374.240837 -22.866145) (xy 374.193231 -22.895199) (xy 374.141902 -22.917011)
			(xy 374.087945 -22.931117) (xy 374.032508 -22.937217) (xy 373.976774 -22.93518) (xy 373.921931 -22.92505)
			(xy 373.869147 -22.907043) (xy 373.819547 -22.881542) (xy 373.774189 -22.849091) (xy 373.73404 -22.810382)
			(xy 373.699954 -22.766239) (xy 373.672658 -22.717604) (xy 373.652735 -22.665513) (xy 373.640609 -22.611076)
			(xy 373.636538 -22.555454) (xy 356.711769 -22.555454) (xy 356.644734 -22.595071) (xy 356.528821 -22.654354)
			(xy 356.409508 -22.706462) (xy 356.287241 -22.751198) (xy 356.162474 -22.788397) (xy 356.035671 -22.817921)
			(xy 355.907304 -22.839659) (xy 355.777851 -22.853532) (xy 355.647792 -22.859486) (xy 355.517613 -22.857501)
			(xy 355.387797 -22.847583) (xy 355.258827 -22.829769) (xy 355.131182 -22.804126) (xy 355.005339 -22.770749)
			(xy 354.881764 -22.729762) (xy 354.760918 -22.681318) (xy 354.64325 -22.625596) (xy 354.529198 -22.562805)
			(xy 354.419186 -22.493178) (xy 354.313624 -22.416973) (xy 354.212904 -22.334474) (xy 354.1174 -22.245989)
			(xy 354.027468 -22.151846) (xy 353.943443 -22.052395) (xy 353.865638 -21.948007) (xy 353.794341 -21.83907)
			(xy 353.729817 -21.725988) (xy 353.672308 -21.609184) (xy 353.622026 -21.489091) (xy 353.57916 -21.366155)
			(xy 353.543867 -21.240836) (xy 353.516281 -21.113597) (xy 353.496502 -20.984914) (xy 353.484606 -20.855264)
			(xy 353.480636 -20.72513) (xy 326.919844 -20.72513) (xy 326.919844 -20.780756) (xy 326.926956 -20.79879)
			(xy 326.93356 -20.805648) (xy 326.952837 -20.826969) (xy 326.985404 -20.874332) (xy 327.010496 -20.926045)
			(xy 327.027547 -20.980937) (xy 327.036169 -21.037765) (xy 327.036168 -21.095244) (xy 327.027545 -21.152072)
			(xy 327.010493 -21.206963) (xy 326.985399 -21.258675) (xy 326.952832 -21.306038) (xy 326.93356 -21.327364)
			(xy 326.926956 -21.334222) (xy 326.919844 -21.352256) (xy 326.919844 -21.441156) (xy 326.926956 -21.45919)
			(xy 326.93356 -21.466048) (xy 326.952833 -21.487373) (xy 326.985399 -21.534735) (xy 327.010491 -21.586448)
			(xy 327.027541 -21.641339) (xy 327.036163 -21.698167) (xy 327.036684 -21.726906) (xy 327.036198 -21.754157)
			(xy 327.028442 -21.808105) (xy 327.013087 -21.8604) (xy 326.990445 -21.909977) (xy 326.960979 -21.955827)
			(xy 326.925288 -21.997018) (xy 326.884097 -22.032709) (xy 326.838247 -22.062175) (xy 326.78867 -22.084817)
			(xy 326.736375 -22.100172) (xy 326.682427 -22.107928) (xy 326.627925 -22.107928) (xy 326.573977 -22.100172)
			(xy 326.521682 -22.084817) (xy 326.472105 -22.062175) (xy 326.426255 -22.032709) (xy 326.385064 -21.997018)
			(xy 326.349373 -21.955827) (xy 326.319907 -21.909977) (xy 326.297265 -21.8604) (xy 326.28191 -21.808105)
			(xy 326.274154 -21.754157) (xy 326.273668 -21.726906) (xy 319.399051 -21.726906) (xy 319.369263 -21.783021)
			(xy 319.301322 -21.894082) (xy 319.226736 -22.000794) (xy 319.145783 -22.102761) (xy 319.058764 -22.199603)
			(xy 318.966003 -22.29096) (xy 318.867845 -22.376492) (xy 318.764656 -22.45588) (xy 318.656819 -22.52883)
			(xy 318.544734 -22.595071) (xy 318.428821 -22.654354) (xy 318.309508 -22.706462) (xy 318.187241 -22.751198)
			(xy 318.062474 -22.788397) (xy 317.935671 -22.817921) (xy 317.807304 -22.839659) (xy 317.677851 -22.853532)
			(xy 317.547792 -22.859486) (xy 317.417613 -22.857501) (xy 317.287797 -22.847583) (xy 317.158827 -22.829769)
			(xy 317.031182 -22.804126) (xy 316.905339 -22.770749) (xy 316.781764 -22.729762) (xy 316.660918 -22.681318)
			(xy 316.54325 -22.625596) (xy 316.429198 -22.562805) (xy 316.319186 -22.493178) (xy 316.213624 -22.416973)
			(xy 316.112904 -22.334474) (xy 316.0174 -22.245989) (xy 315.927468 -22.151846) (xy 315.843443 -22.052395)
			(xy 315.765638 -21.948007) (xy 315.694341 -21.83907) (xy 315.629817 -21.725988) (xy 315.572308 -21.609184)
			(xy 315.522026 -21.489091) (xy 315.47916 -21.366155) (xy 315.443867 -21.240836) (xy 315.416281 -21.113597)
			(xy 315.396502 -20.984914) (xy 315.384606 -20.855264) (xy 315.380636 -20.72513) (xy 309.150127 -20.72513)
			(xy 309.134483 -20.74259) (xy 309.091615 -20.778265) (xy 309.044009 -20.807319) (xy 308.99268 -20.829131)
			(xy 308.938723 -20.843237) (xy 308.883286 -20.849337) (xy 308.827552 -20.8473) (xy 308.772709 -20.83717)
			(xy 308.719925 -20.819163) (xy 308.670325 -20.793662) (xy 308.624967 -20.761211) (xy 308.584818 -20.722502)
			(xy 308.550732 -20.678359) (xy 308.523436 -20.629724) (xy 308.503513 -20.577633) (xy 308.491387 -20.523196)
			(xy 308.487316 -20.467574) (xy 301.006223 -20.467574) (xy 300.985448 -20.510389) (xy 300.952883 -20.557752)
			(xy 300.933612 -20.57908) (xy 300.927008 -20.585938) (xy 300.919896 -20.603972) (xy 300.919896 -20.692872)
			(xy 300.927008 -20.710906) (xy 300.933612 -20.717764) (xy 300.952903 -20.739073) (xy 300.985465 -20.786439)
			(xy 301.010552 -20.838154) (xy 301.027599 -20.893047) (xy 301.036219 -20.949876) (xy 301.036216 -21.007356)
			(xy 301.027592 -21.064184) (xy 301.010541 -21.119076) (xy 300.985448 -21.170789) (xy 300.952883 -21.218152)
			(xy 300.933612 -21.23948) (xy 300.927008 -21.246338) (xy 300.919896 -21.264372) (xy 300.919896 -21.353272)
			(xy 300.927008 -21.371306) (xy 300.933612 -21.378164) (xy 300.952885 -21.399489) (xy 300.985453 -21.446851)
			(xy 301.010546 -21.498563) (xy 301.027596 -21.553454) (xy 301.036217 -21.610283) (xy 301.036736 -21.639022)
			(xy 301.03625 -21.666273) (xy 301.028494 -21.720221) (xy 301.013139 -21.772516) (xy 301.011697 -21.775674)
			(xy 310.135776 -21.775674) (xy 310.139847 -21.720052) (xy 310.151973 -21.665615) (xy 310.171896 -21.613524)
			(xy 310.199192 -21.564889) (xy 310.233278 -21.520746) (xy 310.273427 -21.482037) (xy 310.318785 -21.449586)
			(xy 310.368385 -21.424085) (xy 310.421169 -21.406078) (xy 310.476012 -21.395948) (xy 310.531746 -21.393911)
			(xy 310.587183 -21.400011) (xy 310.64114 -21.414117) (xy 310.692469 -21.435929) (xy 310.740075 -21.464983)
			(xy 310.782943 -21.500658) (xy 310.82016 -21.542195) (xy 310.850933 -21.588708) (xy 310.874605 -21.639205)
			(xy 310.890673 -21.692612) (xy 310.898793 -21.747788) (xy 310.899302 -21.775674) (xy 310.898793 -21.80356)
			(xy 310.891122 -21.855684) (xy 311.038492 -21.855684) (xy 311.042563 -21.800062) (xy 311.054689 -21.745625)
			(xy 311.074612 -21.693534) (xy 311.101908 -21.644899) (xy 311.135994 -21.600756) (xy 311.176143 -21.562047)
			(xy 311.221501 -21.529596) (xy 311.271101 -21.504095) (xy 311.323885 -21.486088) (xy 311.378728 -21.475958)
			(xy 311.434462 -21.473921) (xy 311.489899 -21.480021) (xy 311.543856 -21.494127) (xy 311.595185 -21.515939)
			(xy 311.642791 -21.544993) (xy 311.685659 -21.580668) (xy 311.722876 -21.622205) (xy 311.753649 -21.668718)
			(xy 311.777321 -21.719215) (xy 311.793389 -21.772622) (xy 311.801509 -21.827798) (xy 311.80186 -21.847048)
			(xy 312.272678 -21.847048) (xy 312.276749 -21.791426) (xy 312.288875 -21.736989) (xy 312.308798 -21.684898)
			(xy 312.336094 -21.636263) (xy 312.37018 -21.59212) (xy 312.410329 -21.553411) (xy 312.455687 -21.52096)
			(xy 312.505287 -21.495459) (xy 312.558071 -21.477452) (xy 312.612914 -21.467322) (xy 312.668648 -21.465285)
			(xy 312.724085 -21.471385) (xy 312.778042 -21.485491) (xy 312.829371 -21.507303) (xy 312.876977 -21.536357)
			(xy 312.919845 -21.572032) (xy 312.957062 -21.613569) (xy 312.987835 -21.660082) (xy 313.011507 -21.710579)
			(xy 313.027575 -21.763986) (xy 313.035695 -21.819162) (xy 313.036204 -21.847048) (xy 313.035695 -21.874934)
			(xy 313.027575 -21.93011) (xy 313.011507 -21.983517) (xy 312.987835 -22.034014) (xy 312.957062 -22.080527)
			(xy 312.919845 -22.122064) (xy 312.876977 -22.157739) (xy 312.829371 -22.186793) (xy 312.778042 -22.208605)
			(xy 312.724085 -22.222711) (xy 312.668648 -22.228811) (xy 312.612914 -22.226774) (xy 312.558071 -22.216644)
			(xy 312.505287 -22.198637) (xy 312.455687 -22.173136) (xy 312.410329 -22.140685) (xy 312.37018 -22.101976)
			(xy 312.336094 -22.057833) (xy 312.308798 -22.009198) (xy 312.288875 -21.957107) (xy 312.276749 -21.90267)
			(xy 312.272678 -21.847048) (xy 311.80186 -21.847048) (xy 311.802018 -21.855684) (xy 311.801509 -21.88357)
			(xy 311.793389 -21.938746) (xy 311.777321 -21.992153) (xy 311.753649 -22.04265) (xy 311.722876 -22.089163)
			(xy 311.685659 -22.1307) (xy 311.642791 -22.166375) (xy 311.595185 -22.195429) (xy 311.543856 -22.217241)
			(xy 311.489899 -22.231347) (xy 311.434462 -22.237447) (xy 311.378728 -22.23541) (xy 311.323885 -22.22528)
			(xy 311.271101 -22.207273) (xy 311.221501 -22.181772) (xy 311.176143 -22.149321) (xy 311.135994 -22.110612)
			(xy 311.101908 -22.066469) (xy 311.074612 -22.017834) (xy 311.054689 -21.965743) (xy 311.042563 -21.911306)
			(xy 311.038492 -21.855684) (xy 310.891122 -21.855684) (xy 310.890673 -21.858736) (xy 310.874605 -21.912143)
			(xy 310.850933 -21.96264) (xy 310.82016 -22.009153) (xy 310.782943 -22.05069) (xy 310.740075 -22.086365)
			(xy 310.692469 -22.115419) (xy 310.64114 -22.137231) (xy 310.587183 -22.151337) (xy 310.531746 -22.157437)
			(xy 310.476012 -22.1554) (xy 310.421169 -22.14527) (xy 310.368385 -22.127263) (xy 310.318785 -22.101762)
			(xy 310.273427 -22.069311) (xy 310.233278 -22.030602) (xy 310.199192 -21.986459) (xy 310.171896 -21.937824)
			(xy 310.151973 -21.885733) (xy 310.139847 -21.831296) (xy 310.135776 -21.775674) (xy 301.011697 -21.775674)
			(xy 300.990497 -21.822093) (xy 300.961031 -21.867943) (xy 300.92534 -21.909134) (xy 300.884149 -21.944825)
			(xy 300.838299 -21.974291) (xy 300.788722 -21.996933) (xy 300.736427 -22.012288) (xy 300.682479 -22.020044)
			(xy 300.627977 -22.020044) (xy 300.574029 -22.012288) (xy 300.521734 -21.996933) (xy 300.472157 -21.974291)
			(xy 300.426307 -21.944825) (xy 300.385116 -21.909134) (xy 300.349425 -21.867943) (xy 300.319959 -21.822093)
			(xy 300.297317 -21.772516) (xy 300.281962 -21.720221) (xy 300.274206 -21.666273) (xy 300.27372 -21.639022)
			(xy 293.443303 -21.639022) (xy 293.430106 -21.668025) (xy 293.369061 -21.783021) (xy 293.30112 -21.894082)
			(xy 293.226534 -22.000794) (xy 293.145581 -22.102761) (xy 293.058562 -22.199603) (xy 292.965801 -22.29096)
			(xy 292.867643 -22.376492) (xy 292.764454 -22.45588) (xy 292.656617 -22.52883) (xy 292.611567 -22.555454)
			(xy 309.536336 -22.555454) (xy 309.540407 -22.499832) (xy 309.552533 -22.445395) (xy 309.572456 -22.393304)
			(xy 309.599752 -22.344669) (xy 309.633838 -22.300526) (xy 309.673987 -22.261817) (xy 309.719345 -22.229366)
			(xy 309.768945 -22.203865) (xy 309.821729 -22.185858) (xy 309.876572 -22.175728) (xy 309.932306 -22.173691)
			(xy 309.987743 -22.179791) (xy 310.0417 -22.193897) (xy 310.093029 -22.215709) (xy 310.140635 -22.244763)
			(xy 310.183503 -22.280438) (xy 310.22072 -22.321975) (xy 310.251493 -22.368488) (xy 310.275165 -22.418985)
			(xy 310.291233 -22.472392) (xy 310.299353 -22.527568) (xy 310.299862 -22.555454) (xy 310.299353 -22.58334)
			(xy 310.291233 -22.638516) (xy 310.275165 -22.691923) (xy 310.251493 -22.74242) (xy 310.22072 -22.788933)
			(xy 310.183503 -22.83047) (xy 310.140635 -22.866145) (xy 310.093029 -22.895199) (xy 310.0417 -22.917011)
			(xy 309.987743 -22.931117) (xy 309.932306 -22.937217) (xy 309.876572 -22.93518) (xy 309.821729 -22.92505)
			(xy 309.768945 -22.907043) (xy 309.719345 -22.881542) (xy 309.673987 -22.849091) (xy 309.633838 -22.810382)
			(xy 309.599752 -22.766239) (xy 309.572456 -22.717604) (xy 309.552533 -22.665513) (xy 309.540407 -22.611076)
			(xy 309.536336 -22.555454) (xy 292.611567 -22.555454) (xy 292.544532 -22.595071) (xy 292.428619 -22.654354)
			(xy 292.309306 -22.706462) (xy 292.187039 -22.751198) (xy 292.062272 -22.788397) (xy 291.935469 -22.817921)
			(xy 291.807102 -22.839659) (xy 291.677649 -22.853532) (xy 291.54759 -22.859486) (xy 291.417411 -22.857501)
			(xy 291.287595 -22.847583) (xy 291.158625 -22.829769) (xy 291.03098 -22.804126) (xy 290.905137 -22.770749)
			(xy 290.781562 -22.729762) (xy 290.660716 -22.681318) (xy 290.543048 -22.625596) (xy 290.428996 -22.562805)
			(xy 290.318984 -22.493178) (xy 290.213422 -22.416973) (xy 290.112702 -22.334474) (xy 290.017198 -22.245989)
			(xy 289.927266 -22.151846) (xy 289.843241 -22.052395) (xy 289.765436 -21.948007) (xy 289.694139 -21.83907)
			(xy 289.629615 -21.725988) (xy 289.572106 -21.609184) (xy 289.521824 -21.489091) (xy 289.478958 -21.366155)
			(xy 289.443665 -21.240836) (xy 289.416079 -21.113597) (xy 289.3963 -20.984914) (xy 289.384404 -20.855264)
			(xy 289.380434 -20.72513) (xy 283.150179 -20.72513) (xy 283.134535 -20.74259) (xy 283.091667 -20.778265)
			(xy 283.044061 -20.807319) (xy 282.992732 -20.829131) (xy 282.938775 -20.843237) (xy 282.883338 -20.849337)
			(xy 282.827604 -20.8473) (xy 282.772761 -20.83717) (xy 282.719977 -20.819163) (xy 282.670377 -20.793662)
			(xy 282.625019 -20.761211) (xy 282.58487 -20.722502) (xy 282.550784 -20.678359) (xy 282.523488 -20.629724)
			(xy 282.503565 -20.577633) (xy 282.491439 -20.523196) (xy 282.487368 -20.467574) (xy 275.006285 -20.467574)
			(xy 274.985506 -20.510391) (xy 274.952937 -20.557753) (xy 274.933664 -20.57908) (xy 274.92706 -20.585938)
			(xy 274.919948 -20.603972) (xy 274.919948 -20.692872) (xy 274.92706 -20.710906) (xy 274.933664 -20.717764)
			(xy 274.952957 -20.739072) (xy 274.985523 -20.786437) (xy 275.010614 -20.838152) (xy 275.027663 -20.893046)
			(xy 275.036284 -20.949876) (xy 275.036281 -21.007356) (xy 275.027656 -21.064186) (xy 275.010602 -21.119078)
			(xy 274.985506 -21.170791) (xy 274.952937 -21.218153) (xy 274.933664 -21.23948) (xy 274.92706 -21.246338)
			(xy 274.919948 -21.264372) (xy 274.919948 -21.353272) (xy 274.92706 -21.371306) (xy 274.933664 -21.378164)
			(xy 274.952945 -21.399482) (xy 274.98551 -21.446846) (xy 275.010601 -21.49856) (xy 275.027649 -21.553453)
			(xy 275.036269 -21.610282) (xy 275.036788 -21.639022) (xy 275.036302 -21.666273) (xy 275.028546 -21.720221)
			(xy 275.013191 -21.772516) (xy 275.011749 -21.775674) (xy 284.135828 -21.775674) (xy 284.139899 -21.720052)
			(xy 284.152025 -21.665615) (xy 284.171948 -21.613524) (xy 284.199244 -21.564889) (xy 284.23333 -21.520746)
			(xy 284.273479 -21.482037) (xy 284.318837 -21.449586) (xy 284.368437 -21.424085) (xy 284.421221 -21.406078)
			(xy 284.476064 -21.395948) (xy 284.531798 -21.393911) (xy 284.587235 -21.400011) (xy 284.641192 -21.414117)
			(xy 284.692521 -21.435929) (xy 284.740127 -21.464983) (xy 284.782995 -21.500658) (xy 284.820212 -21.542195)
			(xy 284.850985 -21.588708) (xy 284.874657 -21.639205) (xy 284.890725 -21.692612) (xy 284.898845 -21.747788)
			(xy 284.899354 -21.775674) (xy 284.898845 -21.80356) (xy 284.891174 -21.855684) (xy 285.038544 -21.855684)
			(xy 285.042615 -21.800062) (xy 285.054741 -21.745625) (xy 285.074664 -21.693534) (xy 285.10196 -21.644899)
			(xy 285.136046 -21.600756) (xy 285.176195 -21.562047) (xy 285.221553 -21.529596) (xy 285.271153 -21.504095)
			(xy 285.323937 -21.486088) (xy 285.37878 -21.475958) (xy 285.434514 -21.473921) (xy 285.489951 -21.480021)
			(xy 285.543908 -21.494127) (xy 285.595237 -21.515939) (xy 285.642843 -21.544993) (xy 285.685711 -21.580668)
			(xy 285.722928 -21.622205) (xy 285.753701 -21.668718) (xy 285.777373 -21.719215) (xy 285.793441 -21.772622)
			(xy 285.801561 -21.827798) (xy 285.801912 -21.847048) (xy 286.27273 -21.847048) (xy 286.276801 -21.791426)
			(xy 286.288927 -21.736989) (xy 286.30885 -21.684898) (xy 286.336146 -21.636263) (xy 286.370232 -21.59212)
			(xy 286.410381 -21.553411) (xy 286.455739 -21.52096) (xy 286.505339 -21.495459) (xy 286.558123 -21.477452)
			(xy 286.612966 -21.467322) (xy 286.6687 -21.465285) (xy 286.724137 -21.471385) (xy 286.778094 -21.485491)
			(xy 286.829423 -21.507303) (xy 286.877029 -21.536357) (xy 286.919897 -21.572032) (xy 286.957114 -21.613569)
			(xy 286.987887 -21.660082) (xy 287.011559 -21.710579) (xy 287.027627 -21.763986) (xy 287.035747 -21.819162)
			(xy 287.036256 -21.847048) (xy 287.035747 -21.874934) (xy 287.027627 -21.93011) (xy 287.011559 -21.983517)
			(xy 286.987887 -22.034014) (xy 286.957114 -22.080527) (xy 286.919897 -22.122064) (xy 286.877029 -22.157739)
			(xy 286.829423 -22.186793) (xy 286.778094 -22.208605) (xy 286.724137 -22.222711) (xy 286.6687 -22.228811)
			(xy 286.612966 -22.226774) (xy 286.558123 -22.216644) (xy 286.505339 -22.198637) (xy 286.455739 -22.173136)
			(xy 286.410381 -22.140685) (xy 286.370232 -22.101976) (xy 286.336146 -22.057833) (xy 286.30885 -22.009198)
			(xy 286.288927 -21.957107) (xy 286.276801 -21.90267) (xy 286.27273 -21.847048) (xy 285.801912 -21.847048)
			(xy 285.80207 -21.855684) (xy 285.801561 -21.88357) (xy 285.793441 -21.938746) (xy 285.777373 -21.992153)
			(xy 285.753701 -22.04265) (xy 285.722928 -22.089163) (xy 285.685711 -22.1307) (xy 285.642843 -22.166375)
			(xy 285.595237 -22.195429) (xy 285.543908 -22.217241) (xy 285.489951 -22.231347) (xy 285.434514 -22.237447)
			(xy 285.37878 -22.23541) (xy 285.323937 -22.22528) (xy 285.271153 -22.207273) (xy 285.221553 -22.181772)
			(xy 285.176195 -22.149321) (xy 285.136046 -22.110612) (xy 285.10196 -22.066469) (xy 285.074664 -22.017834)
			(xy 285.054741 -21.965743) (xy 285.042615 -21.911306) (xy 285.038544 -21.855684) (xy 284.891174 -21.855684)
			(xy 284.890725 -21.858736) (xy 284.874657 -21.912143) (xy 284.850985 -21.96264) (xy 284.820212 -22.009153)
			(xy 284.782995 -22.05069) (xy 284.740127 -22.086365) (xy 284.692521 -22.115419) (xy 284.641192 -22.137231)
			(xy 284.587235 -22.151337) (xy 284.531798 -22.157437) (xy 284.476064 -22.1554) (xy 284.421221 -22.14527)
			(xy 284.368437 -22.127263) (xy 284.318837 -22.101762) (xy 284.273479 -22.069311) (xy 284.23333 -22.030602)
			(xy 284.199244 -21.986459) (xy 284.171948 -21.937824) (xy 284.152025 -21.885733) (xy 284.139899 -21.831296)
			(xy 284.135828 -21.775674) (xy 275.011749 -21.775674) (xy 274.990549 -21.822093) (xy 274.961083 -21.867943)
			(xy 274.925392 -21.909134) (xy 274.884201 -21.944825) (xy 274.838351 -21.974291) (xy 274.788774 -21.996933)
			(xy 274.736479 -22.012288) (xy 274.682531 -22.020044) (xy 274.628029 -22.020044) (xy 274.574081 -22.012288)
			(xy 274.521786 -21.996933) (xy 274.472209 -21.974291) (xy 274.426359 -21.944825) (xy 274.385168 -21.909134)
			(xy 274.349477 -21.867943) (xy 274.320011 -21.822093) (xy 274.297369 -21.772516) (xy 274.282014 -21.720221)
			(xy 274.274258 -21.666273) (xy 274.273772 -21.639022) (xy 267.443355 -21.639022) (xy 267.430158 -21.668025)
			(xy 267.369113 -21.783021) (xy 267.301172 -21.894082) (xy 267.226586 -22.000794) (xy 267.145633 -22.102761)
			(xy 267.058614 -22.199603) (xy 266.965853 -22.29096) (xy 266.867695 -22.376492) (xy 266.764506 -22.45588)
			(xy 266.656669 -22.52883) (xy 266.611619 -22.555454) (xy 283.536388 -22.555454) (xy 283.540459 -22.499832)
			(xy 283.552585 -22.445395) (xy 283.572508 -22.393304) (xy 283.599804 -22.344669) (xy 283.63389 -22.300526)
			(xy 283.674039 -22.261817) (xy 283.719397 -22.229366) (xy 283.768997 -22.203865) (xy 283.821781 -22.185858)
			(xy 283.876624 -22.175728) (xy 283.932358 -22.173691) (xy 283.987795 -22.179791) (xy 284.041752 -22.193897)
			(xy 284.093081 -22.215709) (xy 284.140687 -22.244763) (xy 284.183555 -22.280438) (xy 284.220772 -22.321975)
			(xy 284.251545 -22.368488) (xy 284.275217 -22.418985) (xy 284.291285 -22.472392) (xy 284.299405 -22.527568)
			(xy 284.299914 -22.555454) (xy 284.299405 -22.58334) (xy 284.291285 -22.638516) (xy 284.275217 -22.691923)
			(xy 284.251545 -22.74242) (xy 284.220772 -22.788933) (xy 284.183555 -22.83047) (xy 284.140687 -22.866145)
			(xy 284.093081 -22.895199) (xy 284.041752 -22.917011) (xy 283.987795 -22.931117) (xy 283.932358 -22.937217)
			(xy 283.876624 -22.93518) (xy 283.821781 -22.92505) (xy 283.768997 -22.907043) (xy 283.719397 -22.881542)
			(xy 283.674039 -22.849091) (xy 283.63389 -22.810382) (xy 283.599804 -22.766239) (xy 283.572508 -22.717604)
			(xy 283.552585 -22.665513) (xy 283.540459 -22.611076) (xy 283.536388 -22.555454) (xy 266.611619 -22.555454)
			(xy 266.544584 -22.595071) (xy 266.428671 -22.654354) (xy 266.309358 -22.706462) (xy 266.187091 -22.751198)
			(xy 266.062324 -22.788397) (xy 265.935521 -22.817921) (xy 265.807154 -22.839659) (xy 265.677701 -22.853532)
			(xy 265.547642 -22.859486) (xy 265.417463 -22.857501) (xy 265.287647 -22.847583) (xy 265.158677 -22.829769)
			(xy 265.031032 -22.804126) (xy 264.905189 -22.770749) (xy 264.781614 -22.729762) (xy 264.660768 -22.681318)
			(xy 264.5431 -22.625596) (xy 264.429048 -22.562805) (xy 264.319036 -22.493178) (xy 264.213474 -22.416973)
			(xy 264.112754 -22.334474) (xy 264.01725 -22.245989) (xy 263.927318 -22.151846) (xy 263.843293 -22.052395)
			(xy 263.765488 -21.948007) (xy 263.694191 -21.83907) (xy 263.629667 -21.725988) (xy 263.572158 -21.609184)
			(xy 263.521876 -21.489091) (xy 263.47901 -21.366155) (xy 263.443717 -21.240836) (xy 263.416131 -21.113597)
			(xy 263.396352 -20.984914) (xy 263.384456 -20.855264) (xy 263.380486 -20.72513) (xy 257.150231 -20.72513)
			(xy 257.134587 -20.74259) (xy 257.091719 -20.778265) (xy 257.044113 -20.807319) (xy 256.992784 -20.829131)
			(xy 256.938827 -20.843237) (xy 256.88339 -20.849337) (xy 256.827656 -20.8473) (xy 256.772813 -20.83717)
			(xy 256.720029 -20.819163) (xy 256.670429 -20.793662) (xy 256.625071 -20.761211) (xy 256.584922 -20.722502)
			(xy 256.550836 -20.678359) (xy 256.52354 -20.629724) (xy 256.503617 -20.577633) (xy 256.491491 -20.523196)
			(xy 256.48742 -20.467574) (xy 249.006326 -20.467574) (xy 248.985552 -20.510388) (xy 248.952987 -20.557752)
			(xy 248.933716 -20.57908) (xy 248.927112 -20.585938) (xy 248.92 -20.603972) (xy 248.92 -20.692872)
			(xy 248.927112 -20.710906) (xy 248.933716 -20.717764) (xy 248.953007 -20.739073) (xy 248.985568 -20.786439)
			(xy 249.010656 -20.838154) (xy 249.027702 -20.893048) (xy 249.036322 -20.949877) (xy 249.036319 -21.007356)
			(xy 249.027695 -21.064184) (xy 249.010644 -21.119075) (xy 248.985552 -21.170788) (xy 248.952987 -21.218152)
			(xy 248.933716 -21.23948) (xy 248.927112 -21.246338) (xy 248.92 -21.264372) (xy 248.92 -21.353272)
			(xy 248.927112 -21.371306) (xy 248.933716 -21.378164) (xy 248.95299 -21.399489) (xy 248.985557 -21.446851)
			(xy 249.01065 -21.498563) (xy 249.0277 -21.553454) (xy 249.036321 -21.610283) (xy 249.03684 -21.639022)
			(xy 249.036354 -21.666273) (xy 249.028598 -21.720221) (xy 249.013243 -21.772516) (xy 249.011801 -21.775674)
			(xy 258.13588 -21.775674) (xy 258.139951 -21.720052) (xy 258.152077 -21.665615) (xy 258.172 -21.613524)
			(xy 258.199296 -21.564889) (xy 258.233382 -21.520746) (xy 258.273531 -21.482037) (xy 258.318889 -21.449586)
			(xy 258.368489 -21.424085) (xy 258.421273 -21.406078) (xy 258.476116 -21.395948) (xy 258.53185 -21.393911)
			(xy 258.587287 -21.400011) (xy 258.641244 -21.414117) (xy 258.692573 -21.435929) (xy 258.740179 -21.464983)
			(xy 258.783047 -21.500658) (xy 258.820264 -21.542195) (xy 258.851037 -21.588708) (xy 258.874709 -21.639205)
			(xy 258.890777 -21.692612) (xy 258.898897 -21.747788) (xy 258.899406 -21.775674) (xy 258.898897 -21.80356)
			(xy 258.891226 -21.855684) (xy 259.038596 -21.855684) (xy 259.042667 -21.800062) (xy 259.054793 -21.745625)
			(xy 259.074716 -21.693534) (xy 259.102012 -21.644899) (xy 259.136098 -21.600756) (xy 259.176247 -21.562047)
			(xy 259.221605 -21.529596) (xy 259.271205 -21.504095) (xy 259.323989 -21.486088) (xy 259.378832 -21.475958)
			(xy 259.434566 -21.473921) (xy 259.490003 -21.480021) (xy 259.54396 -21.494127) (xy 259.595289 -21.515939)
			(xy 259.642895 -21.544993) (xy 259.685763 -21.580668) (xy 259.72298 -21.622205) (xy 259.753753 -21.668718)
			(xy 259.777425 -21.719215) (xy 259.793493 -21.772622) (xy 259.801613 -21.827798) (xy 259.801964 -21.847048)
			(xy 260.272782 -21.847048) (xy 260.276853 -21.791426) (xy 260.288979 -21.736989) (xy 260.308902 -21.684898)
			(xy 260.336198 -21.636263) (xy 260.370284 -21.59212) (xy 260.410433 -21.553411) (xy 260.455791 -21.52096)
			(xy 260.505391 -21.495459) (xy 260.558175 -21.477452) (xy 260.613018 -21.467322) (xy 260.668752 -21.465285)
			(xy 260.724189 -21.471385) (xy 260.778146 -21.485491) (xy 260.829475 -21.507303) (xy 260.877081 -21.536357)
			(xy 260.919949 -21.572032) (xy 260.957166 -21.613569) (xy 260.987939 -21.660082) (xy 261.011611 -21.710579)
			(xy 261.027679 -21.763986) (xy 261.035799 -21.819162) (xy 261.036308 -21.847048) (xy 261.035799 -21.874934)
			(xy 261.027679 -21.93011) (xy 261.011611 -21.983517) (xy 260.987939 -22.034014) (xy 260.957166 -22.080527)
			(xy 260.919949 -22.122064) (xy 260.877081 -22.157739) (xy 260.829475 -22.186793) (xy 260.778146 -22.208605)
			(xy 260.724189 -22.222711) (xy 260.668752 -22.228811) (xy 260.613018 -22.226774) (xy 260.558175 -22.216644)
			(xy 260.505391 -22.198637) (xy 260.455791 -22.173136) (xy 260.410433 -22.140685) (xy 260.370284 -22.101976)
			(xy 260.336198 -22.057833) (xy 260.308902 -22.009198) (xy 260.288979 -21.957107) (xy 260.276853 -21.90267)
			(xy 260.272782 -21.847048) (xy 259.801964 -21.847048) (xy 259.802122 -21.855684) (xy 259.801613 -21.88357)
			(xy 259.793493 -21.938746) (xy 259.777425 -21.992153) (xy 259.753753 -22.04265) (xy 259.72298 -22.089163)
			(xy 259.685763 -22.1307) (xy 259.642895 -22.166375) (xy 259.595289 -22.195429) (xy 259.54396 -22.217241)
			(xy 259.490003 -22.231347) (xy 259.434566 -22.237447) (xy 259.378832 -22.23541) (xy 259.323989 -22.22528)
			(xy 259.271205 -22.207273) (xy 259.221605 -22.181772) (xy 259.176247 -22.149321) (xy 259.136098 -22.110612)
			(xy 259.102012 -22.066469) (xy 259.074716 -22.017834) (xy 259.054793 -21.965743) (xy 259.042667 -21.911306)
			(xy 259.038596 -21.855684) (xy 258.891226 -21.855684) (xy 258.890777 -21.858736) (xy 258.874709 -21.912143)
			(xy 258.851037 -21.96264) (xy 258.820264 -22.009153) (xy 258.783047 -22.05069) (xy 258.740179 -22.086365)
			(xy 258.692573 -22.115419) (xy 258.641244 -22.137231) (xy 258.587287 -22.151337) (xy 258.53185 -22.157437)
			(xy 258.476116 -22.1554) (xy 258.421273 -22.14527) (xy 258.368489 -22.127263) (xy 258.318889 -22.101762)
			(xy 258.273531 -22.069311) (xy 258.233382 -22.030602) (xy 258.199296 -21.986459) (xy 258.172 -21.937824)
			(xy 258.152077 -21.885733) (xy 258.139951 -21.831296) (xy 258.13588 -21.775674) (xy 249.011801 -21.775674)
			(xy 248.990601 -21.822093) (xy 248.961135 -21.867943) (xy 248.925444 -21.909134) (xy 248.884253 -21.944825)
			(xy 248.838403 -21.974291) (xy 248.788826 -21.996933) (xy 248.736531 -22.012288) (xy 248.682583 -22.020044)
			(xy 248.628081 -22.020044) (xy 248.574133 -22.012288) (xy 248.521838 -21.996933) (xy 248.472261 -21.974291)
			(xy 248.426411 -21.944825) (xy 248.38522 -21.909134) (xy 248.349529 -21.867943) (xy 248.320063 -21.822093)
			(xy 248.297421 -21.772516) (xy 248.282066 -21.720221) (xy 248.27431 -21.666273) (xy 248.273824 -21.639022)
			(xy 241.443407 -21.639022) (xy 241.43021 -21.668025) (xy 241.369165 -21.783021) (xy 241.301224 -21.894082)
			(xy 241.226638 -22.000794) (xy 241.145685 -22.102761) (xy 241.058666 -22.199603) (xy 240.965905 -22.29096)
			(xy 240.867747 -22.376492) (xy 240.764558 -22.45588) (xy 240.656721 -22.52883) (xy 240.611671 -22.555454)
			(xy 257.53644 -22.555454) (xy 257.540511 -22.499832) (xy 257.552637 -22.445395) (xy 257.57256 -22.393304)
			(xy 257.599856 -22.344669) (xy 257.633942 -22.300526) (xy 257.674091 -22.261817) (xy 257.719449 -22.229366)
			(xy 257.769049 -22.203865) (xy 257.821833 -22.185858) (xy 257.876676 -22.175728) (xy 257.93241 -22.173691)
			(xy 257.987847 -22.179791) (xy 258.041804 -22.193897) (xy 258.093133 -22.215709) (xy 258.140739 -22.244763)
			(xy 258.183607 -22.280438) (xy 258.220824 -22.321975) (xy 258.251597 -22.368488) (xy 258.275269 -22.418985)
			(xy 258.291337 -22.472392) (xy 258.299457 -22.527568) (xy 258.299966 -22.555454) (xy 258.299457 -22.58334)
			(xy 258.291337 -22.638516) (xy 258.275269 -22.691923) (xy 258.251597 -22.74242) (xy 258.220824 -22.788933)
			(xy 258.183607 -22.83047) (xy 258.140739 -22.866145) (xy 258.093133 -22.895199) (xy 258.041804 -22.917011)
			(xy 257.987847 -22.931117) (xy 257.93241 -22.937217) (xy 257.876676 -22.93518) (xy 257.821833 -22.92505)
			(xy 257.769049 -22.907043) (xy 257.719449 -22.881542) (xy 257.674091 -22.849091) (xy 257.633942 -22.810382)
			(xy 257.599856 -22.766239) (xy 257.57256 -22.717604) (xy 257.552637 -22.665513) (xy 257.540511 -22.611076)
			(xy 257.53644 -22.555454) (xy 240.611671 -22.555454) (xy 240.544636 -22.595071) (xy 240.428723 -22.654354)
			(xy 240.30941 -22.706462) (xy 240.187143 -22.751198) (xy 240.062376 -22.788397) (xy 239.935573 -22.817921)
			(xy 239.807206 -22.839659) (xy 239.677753 -22.853532) (xy 239.547694 -22.859486) (xy 239.417515 -22.857501)
			(xy 239.287699 -22.847583) (xy 239.158729 -22.829769) (xy 239.031084 -22.804126) (xy 238.905241 -22.770749)
			(xy 238.781666 -22.729762) (xy 238.66082 -22.681318) (xy 238.543152 -22.625596) (xy 238.4291 -22.562805)
			(xy 238.319088 -22.493178) (xy 238.213526 -22.416973) (xy 238.112806 -22.334474) (xy 238.017302 -22.245989)
			(xy 237.92737 -22.151846) (xy 237.843345 -22.052395) (xy 237.76554 -21.948007) (xy 237.694243 -21.83907)
			(xy 237.629719 -21.725988) (xy 237.57221 -21.609184) (xy 237.521928 -21.489091) (xy 237.479062 -21.366155)
			(xy 237.443769 -21.240836) (xy 237.416183 -21.113597) (xy 237.396404 -20.984914) (xy 237.384508 -20.855264)
			(xy 237.380538 -20.72513) (xy 219.050231 -20.72513) (xy 219.034587 -20.74259) (xy 218.991719 -20.778265)
			(xy 218.944113 -20.807319) (xy 218.892784 -20.829131) (xy 218.838827 -20.843237) (xy 218.78339 -20.849337)
			(xy 218.727656 -20.8473) (xy 218.672813 -20.83717) (xy 218.620029 -20.819163) (xy 218.570429 -20.793662)
			(xy 218.525071 -20.761211) (xy 218.484922 -20.722502) (xy 218.450836 -20.678359) (xy 218.42354 -20.629724)
			(xy 218.403617 -20.577633) (xy 218.391491 -20.523196) (xy 218.38742 -20.467574) (xy 210.906326 -20.467574)
			(xy 210.885552 -20.510388) (xy 210.852987 -20.557752) (xy 210.833716 -20.57908) (xy 210.827112 -20.585938)
			(xy 210.82 -20.603972) (xy 210.82 -20.692872) (xy 210.827112 -20.710906) (xy 210.833716 -20.717764)
			(xy 210.853007 -20.739073) (xy 210.885568 -20.786439) (xy 210.910656 -20.838154) (xy 210.927702 -20.893048)
			(xy 210.936322 -20.949877) (xy 210.936319 -21.007356) (xy 210.927695 -21.064184) (xy 210.910644 -21.119075)
			(xy 210.885552 -21.170788) (xy 210.852987 -21.218152) (xy 210.833716 -21.23948) (xy 210.827112 -21.246338)
			(xy 210.82 -21.264372) (xy 210.82 -21.353272) (xy 210.827112 -21.371306) (xy 210.833716 -21.378164)
			(xy 210.85299 -21.399489) (xy 210.885557 -21.446851) (xy 210.91065 -21.498563) (xy 210.9277 -21.553454)
			(xy 210.936321 -21.610283) (xy 210.93684 -21.639022) (xy 210.936354 -21.666273) (xy 210.928598 -21.720221)
			(xy 210.913243 -21.772516) (xy 210.911801 -21.775674) (xy 220.03588 -21.775674) (xy 220.039951 -21.720052)
			(xy 220.052077 -21.665615) (xy 220.072 -21.613524) (xy 220.099296 -21.564889) (xy 220.133382 -21.520746)
			(xy 220.173531 -21.482037) (xy 220.218889 -21.449586) (xy 220.268489 -21.424085) (xy 220.321273 -21.406078)
			(xy 220.376116 -21.395948) (xy 220.43185 -21.393911) (xy 220.487287 -21.400011) (xy 220.541244 -21.414117)
			(xy 220.592573 -21.435929) (xy 220.640179 -21.464983) (xy 220.683047 -21.500658) (xy 220.720264 -21.542195)
			(xy 220.751037 -21.588708) (xy 220.774709 -21.639205) (xy 220.790777 -21.692612) (xy 220.798897 -21.747788)
			(xy 220.799406 -21.775674) (xy 220.798897 -21.80356) (xy 220.791226 -21.855684) (xy 220.938596 -21.855684)
			(xy 220.942667 -21.800062) (xy 220.954793 -21.745625) (xy 220.974716 -21.693534) (xy 221.002012 -21.644899)
			(xy 221.036098 -21.600756) (xy 221.076247 -21.562047) (xy 221.121605 -21.529596) (xy 221.171205 -21.504095)
			(xy 221.223989 -21.486088) (xy 221.278832 -21.475958) (xy 221.334566 -21.473921) (xy 221.390003 -21.480021)
			(xy 221.44396 -21.494127) (xy 221.495289 -21.515939) (xy 221.542895 -21.544993) (xy 221.585763 -21.580668)
			(xy 221.62298 -21.622205) (xy 221.653753 -21.668718) (xy 221.677425 -21.719215) (xy 221.693493 -21.772622)
			(xy 221.701613 -21.827798) (xy 221.701964 -21.847048) (xy 222.172782 -21.847048) (xy 222.176853 -21.791426)
			(xy 222.188979 -21.736989) (xy 222.208902 -21.684898) (xy 222.236198 -21.636263) (xy 222.270284 -21.59212)
			(xy 222.310433 -21.553411) (xy 222.355791 -21.52096) (xy 222.405391 -21.495459) (xy 222.458175 -21.477452)
			(xy 222.513018 -21.467322) (xy 222.568752 -21.465285) (xy 222.624189 -21.471385) (xy 222.678146 -21.485491)
			(xy 222.729475 -21.507303) (xy 222.777081 -21.536357) (xy 222.819949 -21.572032) (xy 222.857166 -21.613569)
			(xy 222.887939 -21.660082) (xy 222.911611 -21.710579) (xy 222.927679 -21.763986) (xy 222.935799 -21.819162)
			(xy 222.936308 -21.847048) (xy 222.935799 -21.874934) (xy 222.927679 -21.93011) (xy 222.911611 -21.983517)
			(xy 222.887939 -22.034014) (xy 222.857166 -22.080527) (xy 222.819949 -22.122064) (xy 222.777081 -22.157739)
			(xy 222.729475 -22.186793) (xy 222.678146 -22.208605) (xy 222.624189 -22.222711) (xy 222.568752 -22.228811)
			(xy 222.513018 -22.226774) (xy 222.458175 -22.216644) (xy 222.405391 -22.198637) (xy 222.355791 -22.173136)
			(xy 222.310433 -22.140685) (xy 222.270284 -22.101976) (xy 222.236198 -22.057833) (xy 222.208902 -22.009198)
			(xy 222.188979 -21.957107) (xy 222.176853 -21.90267) (xy 222.172782 -21.847048) (xy 221.701964 -21.847048)
			(xy 221.702122 -21.855684) (xy 221.701613 -21.88357) (xy 221.693493 -21.938746) (xy 221.677425 -21.992153)
			(xy 221.653753 -22.04265) (xy 221.62298 -22.089163) (xy 221.585763 -22.1307) (xy 221.542895 -22.166375)
			(xy 221.495289 -22.195429) (xy 221.44396 -22.217241) (xy 221.390003 -22.231347) (xy 221.334566 -22.237447)
			(xy 221.278832 -22.23541) (xy 221.223989 -22.22528) (xy 221.171205 -22.207273) (xy 221.121605 -22.181772)
			(xy 221.076247 -22.149321) (xy 221.036098 -22.110612) (xy 221.002012 -22.066469) (xy 220.974716 -22.017834)
			(xy 220.954793 -21.965743) (xy 220.942667 -21.911306) (xy 220.938596 -21.855684) (xy 220.791226 -21.855684)
			(xy 220.790777 -21.858736) (xy 220.774709 -21.912143) (xy 220.751037 -21.96264) (xy 220.720264 -22.009153)
			(xy 220.683047 -22.05069) (xy 220.640179 -22.086365) (xy 220.592573 -22.115419) (xy 220.541244 -22.137231)
			(xy 220.487287 -22.151337) (xy 220.43185 -22.157437) (xy 220.376116 -22.1554) (xy 220.321273 -22.14527)
			(xy 220.268489 -22.127263) (xy 220.218889 -22.101762) (xy 220.173531 -22.069311) (xy 220.133382 -22.030602)
			(xy 220.099296 -21.986459) (xy 220.072 -21.937824) (xy 220.052077 -21.885733) (xy 220.039951 -21.831296)
			(xy 220.03588 -21.775674) (xy 210.911801 -21.775674) (xy 210.890601 -21.822093) (xy 210.861135 -21.867943)
			(xy 210.825444 -21.909134) (xy 210.784253 -21.944825) (xy 210.738403 -21.974291) (xy 210.688826 -21.996933)
			(xy 210.636531 -22.012288) (xy 210.582583 -22.020044) (xy 210.528081 -22.020044) (xy 210.474133 -22.012288)
			(xy 210.421838 -21.996933) (xy 210.372261 -21.974291) (xy 210.326411 -21.944825) (xy 210.28522 -21.909134)
			(xy 210.249529 -21.867943) (xy 210.220063 -21.822093) (xy 210.197421 -21.772516) (xy 210.182066 -21.720221)
			(xy 210.17431 -21.666273) (xy 210.173824 -21.639022) (xy 203.343407 -21.639022) (xy 203.33021 -21.668025)
			(xy 203.269165 -21.783021) (xy 203.201224 -21.894082) (xy 203.126638 -22.000794) (xy 203.045685 -22.102761)
			(xy 202.958666 -22.199603) (xy 202.865905 -22.29096) (xy 202.767747 -22.376492) (xy 202.664558 -22.45588)
			(xy 202.556721 -22.52883) (xy 202.511671 -22.555454) (xy 219.43644 -22.555454) (xy 219.440511 -22.499832)
			(xy 219.452637 -22.445395) (xy 219.47256 -22.393304) (xy 219.499856 -22.344669) (xy 219.533942 -22.300526)
			(xy 219.574091 -22.261817) (xy 219.619449 -22.229366) (xy 219.669049 -22.203865) (xy 219.721833 -22.185858)
			(xy 219.776676 -22.175728) (xy 219.83241 -22.173691) (xy 219.887847 -22.179791) (xy 219.941804 -22.193897)
			(xy 219.993133 -22.215709) (xy 220.040739 -22.244763) (xy 220.083607 -22.280438) (xy 220.120824 -22.321975)
			(xy 220.151597 -22.368488) (xy 220.175269 -22.418985) (xy 220.191337 -22.472392) (xy 220.199457 -22.527568)
			(xy 220.199966 -22.555454) (xy 220.199457 -22.58334) (xy 220.191337 -22.638516) (xy 220.175269 -22.691923)
			(xy 220.151597 -22.74242) (xy 220.120824 -22.788933) (xy 220.083607 -22.83047) (xy 220.040739 -22.866145)
			(xy 219.993133 -22.895199) (xy 219.941804 -22.917011) (xy 219.887847 -22.931117) (xy 219.83241 -22.937217)
			(xy 219.776676 -22.93518) (xy 219.721833 -22.92505) (xy 219.669049 -22.907043) (xy 219.619449 -22.881542)
			(xy 219.574091 -22.849091) (xy 219.533942 -22.810382) (xy 219.499856 -22.766239) (xy 219.47256 -22.717604)
			(xy 219.452637 -22.665513) (xy 219.440511 -22.611076) (xy 219.43644 -22.555454) (xy 202.511671 -22.555454)
			(xy 202.444636 -22.595071) (xy 202.328723 -22.654354) (xy 202.20941 -22.706462) (xy 202.087143 -22.751198)
			(xy 201.962376 -22.788397) (xy 201.835573 -22.817921) (xy 201.707206 -22.839659) (xy 201.577753 -22.853532)
			(xy 201.447694 -22.859486) (xy 201.317515 -22.857501) (xy 201.187699 -22.847583) (xy 201.058729 -22.829769)
			(xy 200.931084 -22.804126) (xy 200.805241 -22.770749) (xy 200.681666 -22.729762) (xy 200.56082 -22.681318)
			(xy 200.443152 -22.625596) (xy 200.3291 -22.562805) (xy 200.219088 -22.493178) (xy 200.113526 -22.416973)
			(xy 200.012806 -22.334474) (xy 199.917302 -22.245989) (xy 199.82737 -22.151846) (xy 199.743345 -22.052395)
			(xy 199.66554 -21.948007) (xy 199.594243 -21.83907) (xy 199.529719 -21.725988) (xy 199.47221 -21.609184)
			(xy 199.421928 -21.489091) (xy 199.379062 -21.366155) (xy 199.343769 -21.240836) (xy 199.316183 -21.113597)
			(xy 199.296404 -20.984914) (xy 199.284508 -20.855264) (xy 199.280538 -20.72513) (xy 193.050283 -20.72513)
			(xy 193.034639 -20.74259) (xy 192.991771 -20.778265) (xy 192.944165 -20.807319) (xy 192.892836 -20.829131)
			(xy 192.838879 -20.843237) (xy 192.783442 -20.849337) (xy 192.727708 -20.8473) (xy 192.672865 -20.83717)
			(xy 192.620081 -20.819163) (xy 192.570481 -20.793662) (xy 192.525123 -20.761211) (xy 192.484974 -20.722502)
			(xy 192.450888 -20.678359) (xy 192.423592 -20.629724) (xy 192.403669 -20.577633) (xy 192.391543 -20.523196)
			(xy 192.387472 -20.467574) (xy 184.906388 -20.467574) (xy 184.88561 -20.510391) (xy 184.853041 -20.557753)
			(xy 184.833768 -20.57908) (xy 184.827164 -20.585938) (xy 184.820052 -20.603972) (xy 184.820052 -20.692872)
			(xy 184.827164 -20.710906) (xy 184.833768 -20.717764) (xy 184.853061 -20.739072) (xy 184.885626 -20.786437)
			(xy 184.910717 -20.838152) (xy 184.927766 -20.893046) (xy 184.936387 -20.949876) (xy 184.936384 -21.007356)
			(xy 184.927759 -21.064186) (xy 184.910705 -21.119078) (xy 184.88561 -21.170791) (xy 184.853041 -21.218153)
			(xy 184.833768 -21.23948) (xy 184.827164 -21.246338) (xy 184.820052 -21.264372) (xy 184.820052 -21.353272)
			(xy 184.827164 -21.371306) (xy 184.833768 -21.378164) (xy 184.85305 -21.399481) (xy 184.885615 -21.446846)
			(xy 184.910705 -21.49856) (xy 184.927753 -21.553453) (xy 184.936373 -21.610282) (xy 184.936892 -21.639022)
			(xy 184.936406 -21.666273) (xy 184.92865 -21.720221) (xy 184.913295 -21.772516) (xy 184.911853 -21.775674)
			(xy 194.035932 -21.775674) (xy 194.040003 -21.720052) (xy 194.052129 -21.665615) (xy 194.072052 -21.613524)
			(xy 194.099348 -21.564889) (xy 194.133434 -21.520746) (xy 194.173583 -21.482037) (xy 194.218941 -21.449586)
			(xy 194.268541 -21.424085) (xy 194.321325 -21.406078) (xy 194.376168 -21.395948) (xy 194.431902 -21.393911)
			(xy 194.487339 -21.400011) (xy 194.541296 -21.414117) (xy 194.592625 -21.435929) (xy 194.640231 -21.464983)
			(xy 194.683099 -21.500658) (xy 194.720316 -21.542195) (xy 194.751089 -21.588708) (xy 194.774761 -21.639205)
			(xy 194.790829 -21.692612) (xy 194.798949 -21.747788) (xy 194.799458 -21.775674) (xy 194.798949 -21.80356)
			(xy 194.791278 -21.855684) (xy 194.938648 -21.855684) (xy 194.942719 -21.800062) (xy 194.954845 -21.745625)
			(xy 194.974768 -21.693534) (xy 195.002064 -21.644899) (xy 195.03615 -21.600756) (xy 195.076299 -21.562047)
			(xy 195.121657 -21.529596) (xy 195.171257 -21.504095) (xy 195.224041 -21.486088) (xy 195.278884 -21.475958)
			(xy 195.334618 -21.473921) (xy 195.390055 -21.480021) (xy 195.444012 -21.494127) (xy 195.495341 -21.515939)
			(xy 195.542947 -21.544993) (xy 195.585815 -21.580668) (xy 195.623032 -21.622205) (xy 195.653805 -21.668718)
			(xy 195.677477 -21.719215) (xy 195.693545 -21.772622) (xy 195.701665 -21.827798) (xy 195.702016 -21.847048)
			(xy 196.172834 -21.847048) (xy 196.176905 -21.791426) (xy 196.189031 -21.736989) (xy 196.208954 -21.684898)
			(xy 196.23625 -21.636263) (xy 196.270336 -21.59212) (xy 196.310485 -21.553411) (xy 196.355843 -21.52096)
			(xy 196.405443 -21.495459) (xy 196.458227 -21.477452) (xy 196.51307 -21.467322) (xy 196.568804 -21.465285)
			(xy 196.624241 -21.471385) (xy 196.678198 -21.485491) (xy 196.729527 -21.507303) (xy 196.777133 -21.536357)
			(xy 196.820001 -21.572032) (xy 196.857218 -21.613569) (xy 196.887991 -21.660082) (xy 196.911663 -21.710579)
			(xy 196.927731 -21.763986) (xy 196.935851 -21.819162) (xy 196.93636 -21.847048) (xy 196.935851 -21.874934)
			(xy 196.927731 -21.93011) (xy 196.911663 -21.983517) (xy 196.887991 -22.034014) (xy 196.857218 -22.080527)
			(xy 196.820001 -22.122064) (xy 196.777133 -22.157739) (xy 196.729527 -22.186793) (xy 196.678198 -22.208605)
			(xy 196.624241 -22.222711) (xy 196.568804 -22.228811) (xy 196.51307 -22.226774) (xy 196.458227 -22.216644)
			(xy 196.405443 -22.198637) (xy 196.355843 -22.173136) (xy 196.310485 -22.140685) (xy 196.270336 -22.101976)
			(xy 196.23625 -22.057833) (xy 196.208954 -22.009198) (xy 196.189031 -21.957107) (xy 196.176905 -21.90267)
			(xy 196.172834 -21.847048) (xy 195.702016 -21.847048) (xy 195.702174 -21.855684) (xy 195.701665 -21.88357)
			(xy 195.693545 -21.938746) (xy 195.677477 -21.992153) (xy 195.653805 -22.04265) (xy 195.623032 -22.089163)
			(xy 195.585815 -22.1307) (xy 195.542947 -22.166375) (xy 195.495341 -22.195429) (xy 195.444012 -22.217241)
			(xy 195.390055 -22.231347) (xy 195.334618 -22.237447) (xy 195.278884 -22.23541) (xy 195.224041 -22.22528)
			(xy 195.171257 -22.207273) (xy 195.121657 -22.181772) (xy 195.076299 -22.149321) (xy 195.03615 -22.110612)
			(xy 195.002064 -22.066469) (xy 194.974768 -22.017834) (xy 194.954845 -21.965743) (xy 194.942719 -21.911306)
			(xy 194.938648 -21.855684) (xy 194.791278 -21.855684) (xy 194.790829 -21.858736) (xy 194.774761 -21.912143)
			(xy 194.751089 -21.96264) (xy 194.720316 -22.009153) (xy 194.683099 -22.05069) (xy 194.640231 -22.086365)
			(xy 194.592625 -22.115419) (xy 194.541296 -22.137231) (xy 194.487339 -22.151337) (xy 194.431902 -22.157437)
			(xy 194.376168 -22.1554) (xy 194.321325 -22.14527) (xy 194.268541 -22.127263) (xy 194.218941 -22.101762)
			(xy 194.173583 -22.069311) (xy 194.133434 -22.030602) (xy 194.099348 -21.986459) (xy 194.072052 -21.937824)
			(xy 194.052129 -21.885733) (xy 194.040003 -21.831296) (xy 194.035932 -21.775674) (xy 184.911853 -21.775674)
			(xy 184.890653 -21.822093) (xy 184.861187 -21.867943) (xy 184.825496 -21.909134) (xy 184.784305 -21.944825)
			(xy 184.738455 -21.974291) (xy 184.688878 -21.996933) (xy 184.636583 -22.012288) (xy 184.582635 -22.020044)
			(xy 184.528133 -22.020044) (xy 184.474185 -22.012288) (xy 184.42189 -21.996933) (xy 184.372313 -21.974291)
			(xy 184.326463 -21.944825) (xy 184.285272 -21.909134) (xy 184.249581 -21.867943) (xy 184.220115 -21.822093)
			(xy 184.197473 -21.772516) (xy 184.182118 -21.720221) (xy 184.174362 -21.666273) (xy 184.173876 -21.639022)
			(xy 177.343459 -21.639022) (xy 177.330262 -21.668025) (xy 177.269217 -21.783021) (xy 177.201276 -21.894082)
			(xy 177.12669 -22.000794) (xy 177.045737 -22.102761) (xy 176.958718 -22.199603) (xy 176.865957 -22.29096)
			(xy 176.767799 -22.376492) (xy 176.66461 -22.45588) (xy 176.556773 -22.52883) (xy 176.511723 -22.555454)
			(xy 193.436492 -22.555454) (xy 193.440563 -22.499832) (xy 193.452689 -22.445395) (xy 193.472612 -22.393304)
			(xy 193.499908 -22.344669) (xy 193.533994 -22.300526) (xy 193.574143 -22.261817) (xy 193.619501 -22.229366)
			(xy 193.669101 -22.203865) (xy 193.721885 -22.185858) (xy 193.776728 -22.175728) (xy 193.832462 -22.173691)
			(xy 193.887899 -22.179791) (xy 193.941856 -22.193897) (xy 193.993185 -22.215709) (xy 194.040791 -22.244763)
			(xy 194.083659 -22.280438) (xy 194.120876 -22.321975) (xy 194.151649 -22.368488) (xy 194.175321 -22.418985)
			(xy 194.191389 -22.472392) (xy 194.199509 -22.527568) (xy 194.200018 -22.555454) (xy 194.199509 -22.58334)
			(xy 194.191389 -22.638516) (xy 194.175321 -22.691923) (xy 194.151649 -22.74242) (xy 194.120876 -22.788933)
			(xy 194.083659 -22.83047) (xy 194.040791 -22.866145) (xy 193.993185 -22.895199) (xy 193.941856 -22.917011)
			(xy 193.887899 -22.931117) (xy 193.832462 -22.937217) (xy 193.776728 -22.93518) (xy 193.721885 -22.92505)
			(xy 193.669101 -22.907043) (xy 193.619501 -22.881542) (xy 193.574143 -22.849091) (xy 193.533994 -22.810382)
			(xy 193.499908 -22.766239) (xy 193.472612 -22.717604) (xy 193.452689 -22.665513) (xy 193.440563 -22.611076)
			(xy 193.436492 -22.555454) (xy 176.511723 -22.555454) (xy 176.444688 -22.595071) (xy 176.328775 -22.654354)
			(xy 176.209462 -22.706462) (xy 176.087195 -22.751198) (xy 175.962428 -22.788397) (xy 175.835625 -22.817921)
			(xy 175.707258 -22.839659) (xy 175.577805 -22.853532) (xy 175.447746 -22.859486) (xy 175.317567 -22.857501)
			(xy 175.187751 -22.847583) (xy 175.058781 -22.829769) (xy 174.931136 -22.804126) (xy 174.805293 -22.770749)
			(xy 174.681718 -22.729762) (xy 174.560872 -22.681318) (xy 174.443204 -22.625596) (xy 174.329152 -22.562805)
			(xy 174.21914 -22.493178) (xy 174.113578 -22.416973) (xy 174.012858 -22.334474) (xy 173.917354 -22.245989)
			(xy 173.827422 -22.151846) (xy 173.743397 -22.052395) (xy 173.665592 -21.948007) (xy 173.594295 -21.83907)
			(xy 173.529771 -21.725988) (xy 173.472262 -21.609184) (xy 173.42198 -21.489091) (xy 173.379114 -21.366155)
			(xy 173.343821 -21.240836) (xy 173.316235 -21.113597) (xy 173.296456 -20.984914) (xy 173.28456 -20.855264)
			(xy 173.28059 -20.72513) (xy 167.050335 -20.72513) (xy 167.034691 -20.74259) (xy 166.991823 -20.778265)
			(xy 166.944217 -20.807319) (xy 166.892888 -20.829131) (xy 166.838931 -20.843237) (xy 166.783494 -20.849337)
			(xy 166.72776 -20.8473) (xy 166.672917 -20.83717) (xy 166.620133 -20.819163) (xy 166.570533 -20.793662)
			(xy 166.525175 -20.761211) (xy 166.485026 -20.722502) (xy 166.45094 -20.678359) (xy 166.423644 -20.629724)
			(xy 166.403721 -20.577633) (xy 166.391595 -20.523196) (xy 166.387524 -20.467574) (xy 158.906429 -20.467574)
			(xy 158.885655 -20.510388) (xy 158.85309 -20.557752) (xy 158.83382 -20.57908) (xy 158.827216 -20.585938)
			(xy 158.820104 -20.603972) (xy 158.820104 -20.692872) (xy 158.827216 -20.710906) (xy 158.83382 -20.717764)
			(xy 158.853111 -20.739073) (xy 158.885671 -20.78644) (xy 158.910759 -20.838155) (xy 158.927805 -20.893048)
			(xy 158.936425 -20.949877) (xy 158.936422 -21.007355) (xy 158.927798 -21.064184) (xy 158.910747 -21.119075)
			(xy 158.885655 -21.170788) (xy 158.85309 -21.218152) (xy 158.83382 -21.23948) (xy 158.827216 -21.246338)
			(xy 158.820104 -21.264372) (xy 158.820104 -21.353272) (xy 158.827216 -21.371306) (xy 158.83382 -21.378164)
			(xy 158.853094 -21.399488) (xy 158.885662 -21.44685) (xy 158.910754 -21.498562) (xy 158.927804 -21.553454)
			(xy 158.936425 -21.610283) (xy 158.936944 -21.639022) (xy 158.936458 -21.666273) (xy 158.928702 -21.720221)
			(xy 158.913347 -21.772516) (xy 158.911905 -21.775674) (xy 168.035984 -21.775674) (xy 168.040055 -21.720052)
			(xy 168.052181 -21.665615) (xy 168.072104 -21.613524) (xy 168.0994 -21.564889) (xy 168.133486 -21.520746)
			(xy 168.173635 -21.482037) (xy 168.218993 -21.449586) (xy 168.268593 -21.424085) (xy 168.321377 -21.406078)
			(xy 168.37622 -21.395948) (xy 168.431954 -21.393911) (xy 168.487391 -21.400011) (xy 168.541348 -21.414117)
			(xy 168.592677 -21.435929) (xy 168.640283 -21.464983) (xy 168.683151 -21.500658) (xy 168.720368 -21.542195)
			(xy 168.751141 -21.588708) (xy 168.774813 -21.639205) (xy 168.790881 -21.692612) (xy 168.799001 -21.747788)
			(xy 168.79951 -21.775674) (xy 168.799001 -21.80356) (xy 168.79133 -21.855684) (xy 168.9387 -21.855684)
			(xy 168.942771 -21.800062) (xy 168.954897 -21.745625) (xy 168.97482 -21.693534) (xy 169.002116 -21.644899)
			(xy 169.036202 -21.600756) (xy 169.076351 -21.562047) (xy 169.121709 -21.529596) (xy 169.171309 -21.504095)
			(xy 169.224093 -21.486088) (xy 169.278936 -21.475958) (xy 169.33467 -21.473921) (xy 169.390107 -21.480021)
			(xy 169.444064 -21.494127) (xy 169.495393 -21.515939) (xy 169.542999 -21.544993) (xy 169.585867 -21.580668)
			(xy 169.623084 -21.622205) (xy 169.653857 -21.668718) (xy 169.677529 -21.719215) (xy 169.693597 -21.772622)
			(xy 169.701717 -21.827798) (xy 169.702068 -21.847048) (xy 170.172886 -21.847048) (xy 170.176957 -21.791426)
			(xy 170.189083 -21.736989) (xy 170.209006 -21.684898) (xy 170.236302 -21.636263) (xy 170.270388 -21.59212)
			(xy 170.310537 -21.553411) (xy 170.355895 -21.52096) (xy 170.405495 -21.495459) (xy 170.458279 -21.477452)
			(xy 170.513122 -21.467322) (xy 170.568856 -21.465285) (xy 170.624293 -21.471385) (xy 170.67825 -21.485491)
			(xy 170.729579 -21.507303) (xy 170.777185 -21.536357) (xy 170.820053 -21.572032) (xy 170.85727 -21.613569)
			(xy 170.888043 -21.660082) (xy 170.911715 -21.710579) (xy 170.927783 -21.763986) (xy 170.935903 -21.819162)
			(xy 170.936412 -21.847048) (xy 170.935903 -21.874934) (xy 170.927783 -21.93011) (xy 170.911715 -21.983517)
			(xy 170.888043 -22.034014) (xy 170.85727 -22.080527) (xy 170.820053 -22.122064) (xy 170.777185 -22.157739)
			(xy 170.729579 -22.186793) (xy 170.67825 -22.208605) (xy 170.624293 -22.222711) (xy 170.568856 -22.228811)
			(xy 170.513122 -22.226774) (xy 170.458279 -22.216644) (xy 170.405495 -22.198637) (xy 170.355895 -22.173136)
			(xy 170.310537 -22.140685) (xy 170.270388 -22.101976) (xy 170.236302 -22.057833) (xy 170.209006 -22.009198)
			(xy 170.189083 -21.957107) (xy 170.176957 -21.90267) (xy 170.172886 -21.847048) (xy 169.702068 -21.847048)
			(xy 169.702226 -21.855684) (xy 169.701717 -21.88357) (xy 169.693597 -21.938746) (xy 169.677529 -21.992153)
			(xy 169.653857 -22.04265) (xy 169.623084 -22.089163) (xy 169.585867 -22.1307) (xy 169.542999 -22.166375)
			(xy 169.495393 -22.195429) (xy 169.444064 -22.217241) (xy 169.390107 -22.231347) (xy 169.33467 -22.237447)
			(xy 169.278936 -22.23541) (xy 169.224093 -22.22528) (xy 169.171309 -22.207273) (xy 169.121709 -22.181772)
			(xy 169.076351 -22.149321) (xy 169.036202 -22.110612) (xy 169.002116 -22.066469) (xy 168.97482 -22.017834)
			(xy 168.954897 -21.965743) (xy 168.942771 -21.911306) (xy 168.9387 -21.855684) (xy 168.79133 -21.855684)
			(xy 168.790881 -21.858736) (xy 168.774813 -21.912143) (xy 168.751141 -21.96264) (xy 168.720368 -22.009153)
			(xy 168.683151 -22.05069) (xy 168.640283 -22.086365) (xy 168.592677 -22.115419) (xy 168.541348 -22.137231)
			(xy 168.487391 -22.151337) (xy 168.431954 -22.157437) (xy 168.37622 -22.1554) (xy 168.321377 -22.14527)
			(xy 168.268593 -22.127263) (xy 168.218993 -22.101762) (xy 168.173635 -22.069311) (xy 168.133486 -22.030602)
			(xy 168.0994 -21.986459) (xy 168.072104 -21.937824) (xy 168.052181 -21.885733) (xy 168.040055 -21.831296)
			(xy 168.035984 -21.775674) (xy 158.911905 -21.775674) (xy 158.890705 -21.822093) (xy 158.861239 -21.867943)
			(xy 158.825548 -21.909134) (xy 158.784357 -21.944825) (xy 158.738507 -21.974291) (xy 158.68893 -21.996933)
			(xy 158.636635 -22.012288) (xy 158.582687 -22.020044) (xy 158.528185 -22.020044) (xy 158.474237 -22.012288)
			(xy 158.421942 -21.996933) (xy 158.372365 -21.974291) (xy 158.326515 -21.944825) (xy 158.285324 -21.909134)
			(xy 158.249633 -21.867943) (xy 158.220167 -21.822093) (xy 158.197525 -21.772516) (xy 158.18217 -21.720221)
			(xy 158.174414 -21.666273) (xy 158.173928 -21.639022) (xy 151.343141 -21.639022) (xy 151.33006 -21.667771)
			(xy 151.269015 -21.782767) (xy 151.201074 -21.893828) (xy 151.126488 -22.00054) (xy 151.045535 -22.102507)
			(xy 150.958516 -22.199349) (xy 150.865755 -22.290706) (xy 150.767597 -22.376238) (xy 150.664408 -22.455626)
			(xy 150.556571 -22.528576) (xy 150.511091 -22.555454) (xy 167.436544 -22.555454) (xy 167.440615 -22.499832)
			(xy 167.452741 -22.445395) (xy 167.472664 -22.393304) (xy 167.49996 -22.344669) (xy 167.534046 -22.300526)
			(xy 167.574195 -22.261817) (xy 167.619553 -22.229366) (xy 167.669153 -22.203865) (xy 167.721937 -22.185858)
			(xy 167.77678 -22.175728) (xy 167.832514 -22.173691) (xy 167.887951 -22.179791) (xy 167.941908 -22.193897)
			(xy 167.993237 -22.215709) (xy 168.040843 -22.244763) (xy 168.083711 -22.280438) (xy 168.120928 -22.321975)
			(xy 168.151701 -22.368488) (xy 168.175373 -22.418985) (xy 168.191441 -22.472392) (xy 168.199561 -22.527568)
			(xy 168.20007 -22.555454) (xy 168.199561 -22.58334) (xy 168.191441 -22.638516) (xy 168.175373 -22.691923)
			(xy 168.151701 -22.74242) (xy 168.120928 -22.788933) (xy 168.083711 -22.83047) (xy 168.040843 -22.866145)
			(xy 167.993237 -22.895199) (xy 167.941908 -22.917011) (xy 167.887951 -22.931117) (xy 167.832514 -22.937217)
			(xy 167.77678 -22.93518) (xy 167.721937 -22.92505) (xy 167.669153 -22.907043) (xy 167.619553 -22.881542)
			(xy 167.574195 -22.849091) (xy 167.534046 -22.810382) (xy 167.49996 -22.766239) (xy 167.472664 -22.717604)
			(xy 167.452741 -22.665513) (xy 167.440615 -22.611076) (xy 167.436544 -22.555454) (xy 150.511091 -22.555454)
			(xy 150.444486 -22.594817) (xy 150.328573 -22.6541) (xy 150.20926 -22.706208) (xy 150.086993 -22.750944)
			(xy 149.962226 -22.788143) (xy 149.835423 -22.817667) (xy 149.707056 -22.839405) (xy 149.577603 -22.853278)
			(xy 149.447544 -22.859232) (xy 149.317365 -22.857247) (xy 149.187549 -22.847329) (xy 149.058579 -22.829515)
			(xy 148.930934 -22.803872) (xy 148.805091 -22.770495) (xy 148.681516 -22.729508) (xy 148.56067 -22.681064)
			(xy 148.443002 -22.625342) (xy 148.32895 -22.562551) (xy 148.218938 -22.492924) (xy 148.113376 -22.416719)
			(xy 148.012656 -22.33422) (xy 147.917152 -22.245735) (xy 147.82722 -22.151592) (xy 147.743195 -22.052141)
			(xy 147.66539 -21.947753) (xy 147.594093 -21.838816) (xy 147.529569 -21.725734) (xy 147.47206 -21.60893)
			(xy 147.421778 -21.488837) (xy 147.378912 -21.365901) (xy 147.343619 -21.240582) (xy 147.316033 -21.113343)
			(xy 147.296254 -20.98466) (xy 147.284358 -20.85501) (xy 147.280388 -20.724876) (xy 141.050615 -20.724876)
			(xy 141.034743 -20.74259) (xy 140.991875 -20.778265) (xy 140.944269 -20.807319) (xy 140.89294 -20.829131)
			(xy 140.838983 -20.843237) (xy 140.783546 -20.849337) (xy 140.727812 -20.8473) (xy 140.672969 -20.83717)
			(xy 140.620185 -20.819163) (xy 140.570585 -20.793662) (xy 140.525227 -20.761211) (xy 140.485078 -20.722502)
			(xy 140.450992 -20.678359) (xy 140.423696 -20.629724) (xy 140.403773 -20.577633) (xy 140.391647 -20.523196)
			(xy 140.387576 -20.467574) (xy 132.906491 -20.467574) (xy 132.885713 -20.51039) (xy 132.853145 -20.557753)
			(xy 132.833872 -20.57908) (xy 132.827268 -20.585938) (xy 132.820156 -20.603972) (xy 132.820156 -20.692872)
			(xy 132.827268 -20.710906) (xy 132.833872 -20.717764) (xy 132.853165 -20.739072) (xy 132.88573 -20.786437)
			(xy 132.91082 -20.838152) (xy 132.927869 -20.893046) (xy 132.93649 -20.949876) (xy 132.936487 -21.007356)
			(xy 132.927862 -21.064185) (xy 132.910808 -21.119078) (xy 132.885713 -21.17079) (xy 132.853145 -21.218153)
			(xy 132.833872 -21.23948) (xy 132.827268 -21.246338) (xy 132.820156 -21.264372) (xy 132.820156 -21.353272)
			(xy 132.827268 -21.371306) (xy 132.833872 -21.378164) (xy 132.853155 -21.399481) (xy 132.885719 -21.446846)
			(xy 132.910809 -21.49856) (xy 132.927857 -21.553453) (xy 132.936477 -21.610282) (xy 132.936996 -21.639022)
			(xy 132.93651 -21.666273) (xy 132.928754 -21.720221) (xy 132.913399 -21.772516) (xy 132.911957 -21.775674)
			(xy 142.036036 -21.775674) (xy 142.040107 -21.720052) (xy 142.052233 -21.665615) (xy 142.072156 -21.613524)
			(xy 142.099452 -21.564889) (xy 142.133538 -21.520746) (xy 142.173687 -21.482037) (xy 142.219045 -21.449586)
			(xy 142.268645 -21.424085) (xy 142.321429 -21.406078) (xy 142.376272 -21.395948) (xy 142.432006 -21.393911)
			(xy 142.487443 -21.400011) (xy 142.5414 -21.414117) (xy 142.592729 -21.435929) (xy 142.640335 -21.464983)
			(xy 142.683203 -21.500658) (xy 142.72042 -21.542195) (xy 142.751193 -21.588708) (xy 142.774865 -21.639205)
			(xy 142.790933 -21.692612) (xy 142.799053 -21.747788) (xy 142.799562 -21.775674) (xy 142.799053 -21.80356)
			(xy 142.791382 -21.855684) (xy 142.938752 -21.855684) (xy 142.942823 -21.800062) (xy 142.954949 -21.745625)
			(xy 142.974872 -21.693534) (xy 143.002168 -21.644899) (xy 143.036254 -21.600756) (xy 143.076403 -21.562047)
			(xy 143.121761 -21.529596) (xy 143.171361 -21.504095) (xy 143.224145 -21.486088) (xy 143.278988 -21.475958)
			(xy 143.334722 -21.473921) (xy 143.390159 -21.480021) (xy 143.444116 -21.494127) (xy 143.495445 -21.515939)
			(xy 143.543051 -21.544993) (xy 143.585919 -21.580668) (xy 143.623136 -21.622205) (xy 143.653909 -21.668718)
			(xy 143.677581 -21.719215) (xy 143.693649 -21.772622) (xy 143.701769 -21.827798) (xy 143.70212 -21.847048)
			(xy 144.172938 -21.847048) (xy 144.177009 -21.791426) (xy 144.189135 -21.736989) (xy 144.209058 -21.684898)
			(xy 144.236354 -21.636263) (xy 144.27044 -21.59212) (xy 144.310589 -21.553411) (xy 144.355947 -21.52096)
			(xy 144.405547 -21.495459) (xy 144.458331 -21.477452) (xy 144.513174 -21.467322) (xy 144.568908 -21.465285)
			(xy 144.624345 -21.471385) (xy 144.678302 -21.485491) (xy 144.729631 -21.507303) (xy 144.777237 -21.536357)
			(xy 144.820105 -21.572032) (xy 144.857322 -21.613569) (xy 144.888095 -21.660082) (xy 144.911767 -21.710579)
			(xy 144.927835 -21.763986) (xy 144.935955 -21.819162) (xy 144.936464 -21.847048) (xy 144.935955 -21.874934)
			(xy 144.927835 -21.93011) (xy 144.911767 -21.983517) (xy 144.888095 -22.034014) (xy 144.857322 -22.080527)
			(xy 144.820105 -22.122064) (xy 144.777237 -22.157739) (xy 144.729631 -22.186793) (xy 144.678302 -22.208605)
			(xy 144.624345 -22.222711) (xy 144.568908 -22.228811) (xy 144.513174 -22.226774) (xy 144.458331 -22.216644)
			(xy 144.405547 -22.198637) (xy 144.355947 -22.173136) (xy 144.310589 -22.140685) (xy 144.27044 -22.101976)
			(xy 144.236354 -22.057833) (xy 144.209058 -22.009198) (xy 144.189135 -21.957107) (xy 144.177009 -21.90267)
			(xy 144.172938 -21.847048) (xy 143.70212 -21.847048) (xy 143.702278 -21.855684) (xy 143.701769 -21.88357)
			(xy 143.693649 -21.938746) (xy 143.677581 -21.992153) (xy 143.653909 -22.04265) (xy 143.623136 -22.089163)
			(xy 143.585919 -22.1307) (xy 143.543051 -22.166375) (xy 143.495445 -22.195429) (xy 143.444116 -22.217241)
			(xy 143.390159 -22.231347) (xy 143.334722 -22.237447) (xy 143.278988 -22.23541) (xy 143.224145 -22.22528)
			(xy 143.171361 -22.207273) (xy 143.121761 -22.181772) (xy 143.076403 -22.149321) (xy 143.036254 -22.110612)
			(xy 143.002168 -22.066469) (xy 142.974872 -22.017834) (xy 142.954949 -21.965743) (xy 142.942823 -21.911306)
			(xy 142.938752 -21.855684) (xy 142.791382 -21.855684) (xy 142.790933 -21.858736) (xy 142.774865 -21.912143)
			(xy 142.751193 -21.96264) (xy 142.72042 -22.009153) (xy 142.683203 -22.05069) (xy 142.640335 -22.086365)
			(xy 142.592729 -22.115419) (xy 142.5414 -22.137231) (xy 142.487443 -22.151337) (xy 142.432006 -22.157437)
			(xy 142.376272 -22.1554) (xy 142.321429 -22.14527) (xy 142.268645 -22.127263) (xy 142.219045 -22.101762)
			(xy 142.173687 -22.069311) (xy 142.133538 -22.030602) (xy 142.099452 -21.986459) (xy 142.072156 -21.937824)
			(xy 142.052233 -21.885733) (xy 142.040107 -21.831296) (xy 142.036036 -21.775674) (xy 132.911957 -21.775674)
			(xy 132.890757 -21.822093) (xy 132.861291 -21.867943) (xy 132.8256 -21.909134) (xy 132.784409 -21.944825)
			(xy 132.738559 -21.974291) (xy 132.688982 -21.996933) (xy 132.636687 -22.012288) (xy 132.582739 -22.020044)
			(xy 132.528237 -22.020044) (xy 132.474289 -22.012288) (xy 132.421994 -21.996933) (xy 132.372417 -21.974291)
			(xy 132.326567 -21.944825) (xy 132.285376 -21.909134) (xy 132.249685 -21.867943) (xy 132.220219 -21.822093)
			(xy 132.197577 -21.772516) (xy 132.182222 -21.720221) (xy 132.174466 -21.666273) (xy 132.17398 -21.639022)
			(xy 125.343309 -21.639022) (xy 125.330112 -21.668025) (xy 125.269067 -21.783021) (xy 125.201126 -21.894082)
			(xy 125.12654 -22.000794) (xy 125.045587 -22.102761) (xy 124.958568 -22.199603) (xy 124.865807 -22.29096)
			(xy 124.767649 -22.376492) (xy 124.66446 -22.45588) (xy 124.556623 -22.52883) (xy 124.511573 -22.555454)
			(xy 141.436596 -22.555454) (xy 141.440667 -22.499832) (xy 141.452793 -22.445395) (xy 141.472716 -22.393304)
			(xy 141.500012 -22.344669) (xy 141.534098 -22.300526) (xy 141.574247 -22.261817) (xy 141.619605 -22.229366)
			(xy 141.669205 -22.203865) (xy 141.721989 -22.185858) (xy 141.776832 -22.175728) (xy 141.832566 -22.173691)
			(xy 141.888003 -22.179791) (xy 141.94196 -22.193897) (xy 141.993289 -22.215709) (xy 142.040895 -22.244763)
			(xy 142.083763 -22.280438) (xy 142.12098 -22.321975) (xy 142.151753 -22.368488) (xy 142.175425 -22.418985)
			(xy 142.191493 -22.472392) (xy 142.199613 -22.527568) (xy 142.200122 -22.555454) (xy 142.199613 -22.58334)
			(xy 142.191493 -22.638516) (xy 142.175425 -22.691923) (xy 142.151753 -22.74242) (xy 142.12098 -22.788933)
			(xy 142.083763 -22.83047) (xy 142.040895 -22.866145) (xy 141.993289 -22.895199) (xy 141.94196 -22.917011)
			(xy 141.888003 -22.931117) (xy 141.832566 -22.937217) (xy 141.776832 -22.93518) (xy 141.721989 -22.92505)
			(xy 141.669205 -22.907043) (xy 141.619605 -22.881542) (xy 141.574247 -22.849091) (xy 141.534098 -22.810382)
			(xy 141.500012 -22.766239) (xy 141.472716 -22.717604) (xy 141.452793 -22.665513) (xy 141.440667 -22.611076)
			(xy 141.436596 -22.555454) (xy 124.511573 -22.555454) (xy 124.444538 -22.595071) (xy 124.328625 -22.654354)
			(xy 124.209312 -22.706462) (xy 124.087045 -22.751198) (xy 123.962278 -22.788397) (xy 123.835475 -22.817921)
			(xy 123.707108 -22.839659) (xy 123.577655 -22.853532) (xy 123.447596 -22.859486) (xy 123.317417 -22.857501)
			(xy 123.187601 -22.847583) (xy 123.058631 -22.829769) (xy 122.930986 -22.804126) (xy 122.805143 -22.770749)
			(xy 122.681568 -22.729762) (xy 122.560722 -22.681318) (xy 122.443054 -22.625596) (xy 122.329002 -22.562805)
			(xy 122.21899 -22.493178) (xy 122.113428 -22.416973) (xy 122.012708 -22.334474) (xy 121.917204 -22.245989)
			(xy 121.827272 -22.151846) (xy 121.743247 -22.052395) (xy 121.665442 -21.948007) (xy 121.594145 -21.83907)
			(xy 121.529621 -21.725988) (xy 121.472112 -21.609184) (xy 121.42183 -21.489091) (xy 121.378964 -21.366155)
			(xy 121.343671 -21.240836) (xy 121.316085 -21.113597) (xy 121.296306 -20.984914) (xy 121.28441 -20.855264)
			(xy 121.28044 -20.72513) (xy 94.740286 -20.72513) (xy 94.752909 -20.739073) (xy 94.78547 -20.78644)
			(xy 94.810557 -20.838155) (xy 94.827604 -20.893048) (xy 94.836223 -20.949877) (xy 94.836221 -21.007355)
			(xy 94.827597 -21.064184) (xy 94.810545 -21.119075) (xy 94.785454 -21.170788) (xy 94.752889 -21.218152)
			(xy 94.733618 -21.23948) (xy 94.727014 -21.246338) (xy 94.719902 -21.264372) (xy 94.719902 -21.353272)
			(xy 94.727014 -21.371306) (xy 94.733618 -21.378164) (xy 94.752892 -21.399489) (xy 94.785459 -21.44685)
			(xy 94.810552 -21.498563) (xy 94.827602 -21.553454) (xy 94.836223 -21.610283) (xy 94.836742 -21.639022)
			(xy 94.836256 -21.666273) (xy 94.8285 -21.720221) (xy 94.813145 -21.772516) (xy 94.790503 -21.822093)
			(xy 94.761037 -21.867943) (xy 94.725346 -21.909134) (xy 94.684155 -21.944825) (xy 94.638305 -21.974291)
			(xy 94.588728 -21.996933) (xy 94.536433 -22.012288) (xy 94.482485 -22.020044) (xy 94.427983 -22.020044)
			(xy 94.374035 -22.012288) (xy 94.32174 -21.996933) (xy 94.272163 -21.974291) (xy 94.226313 -21.944825)
			(xy 94.185122 -21.909134) (xy 94.149431 -21.867943) (xy 94.119965 -21.822093) (xy 94.097323 -21.772516)
			(xy 94.081968 -21.720221) (xy 94.074212 -21.666273) (xy 94.073726 -21.639022) (xy 87.246077 -21.639022)
			(xy 87.235192 -21.662945) (xy 87.174147 -21.777941) (xy 87.106206 -21.889002) (xy 87.03162 -21.995714)
			(xy 86.950667 -22.097681) (xy 86.863648 -22.194523) (xy 86.770887 -22.28588) (xy 86.672729 -22.371412)
			(xy 86.56954 -22.4508) (xy 86.461703 -22.52375) (xy 86.349618 -22.589991) (xy 86.233705 -22.649274)
			(xy 86.114392 -22.701382) (xy 85.992125 -22.746118) (xy 85.867358 -22.783317) (xy 85.740555 -22.812841)
			(xy 85.612188 -22.834579) (xy 85.482735 -22.848452) (xy 85.352676 -22.854406) (xy 85.222497 -22.852421)
			(xy 85.092681 -22.842503) (xy 84.963711 -22.824689) (xy 84.836066 -22.799046) (xy 84.710223 -22.765669)
			(xy 84.586648 -22.724682) (xy 84.465802 -22.676238) (xy 84.348134 -22.620516) (xy 84.234082 -22.557725)
			(xy 84.12407 -22.488098) (xy 84.018508 -22.411893) (xy 83.917788 -22.329394) (xy 83.822284 -22.240909)
			(xy 83.732352 -22.146766) (xy 83.648327 -22.047315) (xy 83.570522 -21.942927) (xy 83.499225 -21.83399)
			(xy 83.434701 -21.720908) (xy 83.377192 -21.604104) (xy 83.32691 -21.484011) (xy 83.284044 -21.361075)
			(xy 83.248751 -21.235756) (xy 83.221165 -21.108517) (xy 83.201386 -20.979834) (xy 83.18949 -20.850184)
			(xy 83.18552 -20.72005) (xy 76.954737 -20.72005) (xy 76.934541 -20.74259) (xy 76.891673 -20.778265)
			(xy 76.844067 -20.807319) (xy 76.792738 -20.829131) (xy 76.738781 -20.843237) (xy 76.683344 -20.849337)
			(xy 76.62761 -20.8473) (xy 76.572767 -20.83717) (xy 76.519983 -20.819163) (xy 76.470383 -20.793662)
			(xy 76.425025 -20.761211) (xy 76.384876 -20.722502) (xy 76.35079 -20.678359) (xy 76.323494 -20.629724)
			(xy 76.303571 -20.577633) (xy 76.291445 -20.523196) (xy 76.287374 -20.467574) (xy 68.80629 -20.467574)
			(xy 68.785512 -20.510391) (xy 68.752943 -20.557753) (xy 68.73367 -20.57908) (xy 68.727066 -20.585938)
			(xy 68.719954 -20.603972) (xy 68.719954 -20.692872) (xy 68.727066 -20.710906) (xy 68.73367 -20.717764)
			(xy 68.752963 -20.739072) (xy 68.785528 -20.786437) (xy 68.810619 -20.838152) (xy 68.827667 -20.893046)
			(xy 68.836288 -20.949876) (xy 68.836286 -21.007356) (xy 68.82766 -21.064186) (xy 68.810607 -21.119078)
			(xy 68.785512 -21.170791) (xy 68.752943 -21.218153) (xy 68.73367 -21.23948) (xy 68.727066 -21.246338)
			(xy 68.719954 -21.264372) (xy 68.719954 -21.353272) (xy 68.727066 -21.371306) (xy 68.73367 -21.378164)
			(xy 68.752952 -21.399481) (xy 68.785517 -21.446846) (xy 68.810607 -21.49856) (xy 68.827655 -21.553453)
			(xy 68.836275 -21.610282) (xy 68.836794 -21.639022) (xy 68.836308 -21.666273) (xy 68.828552 -21.720221)
			(xy 68.813197 -21.772516) (xy 68.811755 -21.775674) (xy 77.935834 -21.775674) (xy 77.939905 -21.720052)
			(xy 77.952031 -21.665615) (xy 77.971954 -21.613524) (xy 77.99925 -21.564889) (xy 78.033336 -21.520746)
			(xy 78.073485 -21.482037) (xy 78.118843 -21.449586) (xy 78.168443 -21.424085) (xy 78.221227 -21.406078)
			(xy 78.27607 -21.395948) (xy 78.331804 -21.393911) (xy 78.387241 -21.400011) (xy 78.441198 -21.414117)
			(xy 78.492527 -21.435929) (xy 78.540133 -21.464983) (xy 78.583001 -21.500658) (xy 78.620218 -21.542195)
			(xy 78.650991 -21.588708) (xy 78.674663 -21.639205) (xy 78.690731 -21.692612) (xy 78.698851 -21.747788)
			(xy 78.69936 -21.775674) (xy 78.698851 -21.80356) (xy 78.69118 -21.855684) (xy 78.83855 -21.855684)
			(xy 78.842621 -21.800062) (xy 78.854747 -21.745625) (xy 78.87467 -21.693534) (xy 78.901966 -21.644899)
			(xy 78.936052 -21.600756) (xy 78.976201 -21.562047) (xy 79.021559 -21.529596) (xy 79.071159 -21.504095)
			(xy 79.123943 -21.486088) (xy 79.178786 -21.475958) (xy 79.23452 -21.473921) (xy 79.289957 -21.480021)
			(xy 79.343914 -21.494127) (xy 79.395243 -21.515939) (xy 79.442849 -21.544993) (xy 79.485717 -21.580668)
			(xy 79.522934 -21.622205) (xy 79.553707 -21.668718) (xy 79.577379 -21.719215) (xy 79.593447 -21.772622)
			(xy 79.601567 -21.827798) (xy 79.601918 -21.847048) (xy 80.072736 -21.847048) (xy 80.076807 -21.791426)
			(xy 80.088933 -21.736989) (xy 80.108856 -21.684898) (xy 80.136152 -21.636263) (xy 80.170238 -21.59212)
			(xy 80.210387 -21.553411) (xy 80.255745 -21.52096) (xy 80.305345 -21.495459) (xy 80.358129 -21.477452)
			(xy 80.412972 -21.467322) (xy 80.468706 -21.465285) (xy 80.524143 -21.471385) (xy 80.5781 -21.485491)
			(xy 80.629429 -21.507303) (xy 80.677035 -21.536357) (xy 80.719903 -21.572032) (xy 80.75712 -21.613569)
			(xy 80.787893 -21.660082) (xy 80.811565 -21.710579) (xy 80.827633 -21.763986) (xy 80.835753 -21.819162)
			(xy 80.836262 -21.847048) (xy 80.835753 -21.874934) (xy 80.827633 -21.93011) (xy 80.811565 -21.983517)
			(xy 80.787893 -22.034014) (xy 80.75712 -22.080527) (xy 80.719903 -22.122064) (xy 80.677035 -22.157739)
			(xy 80.629429 -22.186793) (xy 80.5781 -22.208605) (xy 80.524143 -22.222711) (xy 80.468706 -22.228811)
			(xy 80.412972 -22.226774) (xy 80.358129 -22.216644) (xy 80.305345 -22.198637) (xy 80.255745 -22.173136)
			(xy 80.210387 -22.140685) (xy 80.170238 -22.101976) (xy 80.136152 -22.057833) (xy 80.108856 -22.009198)
			(xy 80.088933 -21.957107) (xy 80.076807 -21.90267) (xy 80.072736 -21.847048) (xy 79.601918 -21.847048)
			(xy 79.602076 -21.855684) (xy 79.601567 -21.88357) (xy 79.593447 -21.938746) (xy 79.577379 -21.992153)
			(xy 79.553707 -22.04265) (xy 79.522934 -22.089163) (xy 79.485717 -22.1307) (xy 79.442849 -22.166375)
			(xy 79.395243 -22.195429) (xy 79.343914 -22.217241) (xy 79.289957 -22.231347) (xy 79.23452 -22.237447)
			(xy 79.178786 -22.23541) (xy 79.123943 -22.22528) (xy 79.071159 -22.207273) (xy 79.021559 -22.181772)
			(xy 78.976201 -22.149321) (xy 78.936052 -22.110612) (xy 78.901966 -22.066469) (xy 78.87467 -22.017834)
			(xy 78.854747 -21.965743) (xy 78.842621 -21.911306) (xy 78.83855 -21.855684) (xy 78.69118 -21.855684)
			(xy 78.690731 -21.858736) (xy 78.674663 -21.912143) (xy 78.650991 -21.96264) (xy 78.620218 -22.009153)
			(xy 78.583001 -22.05069) (xy 78.540133 -22.086365) (xy 78.492527 -22.115419) (xy 78.441198 -22.137231)
			(xy 78.387241 -22.151337) (xy 78.331804 -22.157437) (xy 78.27607 -22.1554) (xy 78.221227 -22.14527)
			(xy 78.168443 -22.127263) (xy 78.118843 -22.101762) (xy 78.073485 -22.069311) (xy 78.033336 -22.030602)
			(xy 77.99925 -21.986459) (xy 77.971954 -21.937824) (xy 77.952031 -21.885733) (xy 77.939905 -21.831296)
			(xy 77.935834 -21.775674) (xy 68.811755 -21.775674) (xy 68.790555 -21.822093) (xy 68.761089 -21.867943)
			(xy 68.725398 -21.909134) (xy 68.684207 -21.944825) (xy 68.638357 -21.974291) (xy 68.58878 -21.996933)
			(xy 68.536485 -22.012288) (xy 68.482537 -22.020044) (xy 68.428035 -22.020044) (xy 68.374087 -22.012288)
			(xy 68.321792 -21.996933) (xy 68.272215 -21.974291) (xy 68.226365 -21.944825) (xy 68.185174 -21.909134)
			(xy 68.149483 -21.867943) (xy 68.120017 -21.822093) (xy 68.097375 -21.772516) (xy 68.08202 -21.720221)
			(xy 68.074264 -21.666273) (xy 68.073778 -21.639022) (xy 61.245875 -21.639022) (xy 61.23499 -21.662945)
			(xy 61.173945 -21.777941) (xy 61.106004 -21.889002) (xy 61.031418 -21.995714) (xy 60.950465 -22.097681)
			(xy 60.863446 -22.194523) (xy 60.770685 -22.28588) (xy 60.672527 -22.371412) (xy 60.569338 -22.4508)
			(xy 60.461501 -22.52375) (xy 60.407855 -22.555454) (xy 77.336394 -22.555454) (xy 77.340465 -22.499832)
			(xy 77.352591 -22.445395) (xy 77.372514 -22.393304) (xy 77.39981 -22.344669) (xy 77.433896 -22.300526)
			(xy 77.474045 -22.261817) (xy 77.519403 -22.229366) (xy 77.569003 -22.203865) (xy 77.621787 -22.185858)
			(xy 77.67663 -22.175728) (xy 77.732364 -22.173691) (xy 77.787801 -22.179791) (xy 77.841758 -22.193897)
			(xy 77.893087 -22.215709) (xy 77.940693 -22.244763) (xy 77.983561 -22.280438) (xy 78.020778 -22.321975)
			(xy 78.051551 -22.368488) (xy 78.075223 -22.418985) (xy 78.091291 -22.472392) (xy 78.099411 -22.527568)
			(xy 78.09992 -22.555454) (xy 78.099411 -22.58334) (xy 78.091291 -22.638516) (xy 78.075223 -22.691923)
			(xy 78.051551 -22.74242) (xy 78.020778 -22.788933) (xy 77.983561 -22.83047) (xy 77.940693 -22.866145)
			(xy 77.893087 -22.895199) (xy 77.841758 -22.917011) (xy 77.787801 -22.931117) (xy 77.732364 -22.937217)
			(xy 77.67663 -22.93518) (xy 77.621787 -22.92505) (xy 77.569003 -22.907043) (xy 77.519403 -22.881542)
			(xy 77.474045 -22.849091) (xy 77.433896 -22.810382) (xy 77.39981 -22.766239) (xy 77.372514 -22.717604)
			(xy 77.352591 -22.665513) (xy 77.340465 -22.611076) (xy 77.336394 -22.555454) (xy 60.407855 -22.555454)
			(xy 60.349416 -22.589991) (xy 60.233503 -22.649274) (xy 60.11419 -22.701382) (xy 59.991923 -22.746118)
			(xy 59.867156 -22.783317) (xy 59.740353 -22.812841) (xy 59.611986 -22.834579) (xy 59.482533 -22.848452)
			(xy 59.352474 -22.854406) (xy 59.222295 -22.852421) (xy 59.092479 -22.842503) (xy 58.963509 -22.824689)
			(xy 58.835864 -22.799046) (xy 58.710021 -22.765669) (xy 58.586446 -22.724682) (xy 58.4656 -22.676238)
			(xy 58.347932 -22.620516) (xy 58.23388 -22.557725) (xy 58.123868 -22.488098) (xy 58.018306 -22.411893)
			(xy 57.917586 -22.329394) (xy 57.822082 -22.240909) (xy 57.73215 -22.146766) (xy 57.648125 -22.047315)
			(xy 57.57032 -21.942927) (xy 57.499023 -21.83399) (xy 57.434499 -21.720908) (xy 57.37699 -21.604104)
			(xy 57.326708 -21.484011) (xy 57.283842 -21.361075) (xy 57.248549 -21.235756) (xy 57.220963 -21.108517)
			(xy 57.201184 -20.979834) (xy 57.189288 -20.850184) (xy 57.185318 -20.72005) (xy 50.954789 -20.72005)
			(xy 50.934593 -20.74259) (xy 50.891725 -20.778265) (xy 50.844119 -20.807319) (xy 50.79279 -20.829131)
			(xy 50.738833 -20.843237) (xy 50.683396 -20.849337) (xy 50.627662 -20.8473) (xy 50.572819 -20.83717)
			(xy 50.520035 -20.819163) (xy 50.470435 -20.793662) (xy 50.425077 -20.761211) (xy 50.384928 -20.722502)
			(xy 50.350842 -20.678359) (xy 50.323546 -20.629724) (xy 50.303623 -20.577633) (xy 50.291497 -20.523196)
			(xy 50.287426 -20.467574) (xy 42.806331 -20.467574) (xy 42.785557 -20.510388) (xy 42.752992 -20.557752)
			(xy 42.733722 -20.57908) (xy 42.727118 -20.585938) (xy 42.720006 -20.603972) (xy 42.720006 -20.692872)
			(xy 42.727118 -20.710906) (xy 42.733722 -20.717764) (xy 42.753013 -20.739073) (xy 42.785573 -20.78644)
			(xy 42.810661 -20.838155) (xy 42.827707 -20.893048) (xy 42.836326 -20.949877) (xy 42.836324 -21.007355)
			(xy 42.8277 -21.064184) (xy 42.810649 -21.119075) (xy 42.785557 -21.170788) (xy 42.752992 -21.218152)
			(xy 42.733722 -21.23948) (xy 42.727118 -21.246338) (xy 42.720006 -21.264372) (xy 42.720006 -21.353272)
			(xy 42.727118 -21.371306) (xy 42.733722 -21.378164) (xy 42.752997 -21.399488) (xy 42.785564 -21.44685)
			(xy 42.810656 -21.498562) (xy 42.827706 -21.553454) (xy 42.836327 -21.610283) (xy 42.836846 -21.639022)
			(xy 42.83636 -21.666273) (xy 42.828604 -21.720221) (xy 42.813249 -21.772516) (xy 42.811807 -21.775674)
			(xy 51.935886 -21.775674) (xy 51.939957 -21.720052) (xy 51.952083 -21.665615) (xy 51.972006 -21.613524)
			(xy 51.999302 -21.564889) (xy 52.033388 -21.520746) (xy 52.073537 -21.482037) (xy 52.118895 -21.449586)
			(xy 52.168495 -21.424085) (xy 52.221279 -21.406078) (xy 52.276122 -21.395948) (xy 52.331856 -21.393911)
			(xy 52.387293 -21.400011) (xy 52.44125 -21.414117) (xy 52.492579 -21.435929) (xy 52.540185 -21.464983)
			(xy 52.583053 -21.500658) (xy 52.62027 -21.542195) (xy 52.651043 -21.588708) (xy 52.674715 -21.639205)
			(xy 52.690783 -21.692612) (xy 52.698903 -21.747788) (xy 52.699412 -21.775674) (xy 52.698903 -21.80356)
			(xy 52.691232 -21.855684) (xy 52.838602 -21.855684) (xy 52.842673 -21.800062) (xy 52.854799 -21.745625)
			(xy 52.874722 -21.693534) (xy 52.902018 -21.644899) (xy 52.936104 -21.600756) (xy 52.976253 -21.562047)
			(xy 53.021611 -21.529596) (xy 53.071211 -21.504095) (xy 53.123995 -21.486088) (xy 53.178838 -21.475958)
			(xy 53.234572 -21.473921) (xy 53.290009 -21.480021) (xy 53.343966 -21.494127) (xy 53.395295 -21.515939)
			(xy 53.442901 -21.544993) (xy 53.485769 -21.580668) (xy 53.522986 -21.622205) (xy 53.553759 -21.668718)
			(xy 53.577431 -21.719215) (xy 53.593499 -21.772622) (xy 53.601619 -21.827798) (xy 53.60197 -21.847048)
			(xy 54.072788 -21.847048) (xy 54.076859 -21.791426) (xy 54.088985 -21.736989) (xy 54.108908 -21.684898)
			(xy 54.136204 -21.636263) (xy 54.17029 -21.59212) (xy 54.210439 -21.553411) (xy 54.255797 -21.52096)
			(xy 54.305397 -21.495459) (xy 54.358181 -21.477452) (xy 54.413024 -21.467322) (xy 54.468758 -21.465285)
			(xy 54.524195 -21.471385) (xy 54.578152 -21.485491) (xy 54.629481 -21.507303) (xy 54.677087 -21.536357)
			(xy 54.719955 -21.572032) (xy 54.757172 -21.613569) (xy 54.787945 -21.660082) (xy 54.811617 -21.710579)
			(xy 54.827685 -21.763986) (xy 54.835805 -21.819162) (xy 54.836314 -21.847048) (xy 54.835805 -21.874934)
			(xy 54.827685 -21.93011) (xy 54.811617 -21.983517) (xy 54.787945 -22.034014) (xy 54.757172 -22.080527)
			(xy 54.719955 -22.122064) (xy 54.677087 -22.157739) (xy 54.629481 -22.186793) (xy 54.578152 -22.208605)
			(xy 54.524195 -22.222711) (xy 54.468758 -22.228811) (xy 54.413024 -22.226774) (xy 54.358181 -22.216644)
			(xy 54.305397 -22.198637) (xy 54.255797 -22.173136) (xy 54.210439 -22.140685) (xy 54.17029 -22.101976)
			(xy 54.136204 -22.057833) (xy 54.108908 -22.009198) (xy 54.088985 -21.957107) (xy 54.076859 -21.90267)
			(xy 54.072788 -21.847048) (xy 53.60197 -21.847048) (xy 53.602128 -21.855684) (xy 53.601619 -21.88357)
			(xy 53.593499 -21.938746) (xy 53.577431 -21.992153) (xy 53.553759 -22.04265) (xy 53.522986 -22.089163)
			(xy 53.485769 -22.1307) (xy 53.442901 -22.166375) (xy 53.395295 -22.195429) (xy 53.343966 -22.217241)
			(xy 53.290009 -22.231347) (xy 53.234572 -22.237447) (xy 53.178838 -22.23541) (xy 53.123995 -22.22528)
			(xy 53.071211 -22.207273) (xy 53.021611 -22.181772) (xy 52.976253 -22.149321) (xy 52.936104 -22.110612)
			(xy 52.902018 -22.066469) (xy 52.874722 -22.017834) (xy 52.854799 -21.965743) (xy 52.842673 -21.911306)
			(xy 52.838602 -21.855684) (xy 52.691232 -21.855684) (xy 52.690783 -21.858736) (xy 52.674715 -21.912143)
			(xy 52.651043 -21.96264) (xy 52.62027 -22.009153) (xy 52.583053 -22.05069) (xy 52.540185 -22.086365)
			(xy 52.492579 -22.115419) (xy 52.44125 -22.137231) (xy 52.387293 -22.151337) (xy 52.331856 -22.157437)
			(xy 52.276122 -22.1554) (xy 52.221279 -22.14527) (xy 52.168495 -22.127263) (xy 52.118895 -22.101762)
			(xy 52.073537 -22.069311) (xy 52.033388 -22.030602) (xy 51.999302 -21.986459) (xy 51.972006 -21.937824)
			(xy 51.952083 -21.885733) (xy 51.939957 -21.831296) (xy 51.935886 -21.775674) (xy 42.811807 -21.775674)
			(xy 42.790607 -21.822093) (xy 42.761141 -21.867943) (xy 42.72545 -21.909134) (xy 42.684259 -21.944825)
			(xy 42.638409 -21.974291) (xy 42.588832 -21.996933) (xy 42.536537 -22.012288) (xy 42.482589 -22.020044)
			(xy 42.428087 -22.020044) (xy 42.374139 -22.012288) (xy 42.321844 -21.996933) (xy 42.272267 -21.974291)
			(xy 42.226417 -21.944825) (xy 42.185226 -21.909134) (xy 42.149535 -21.867943) (xy 42.120069 -21.822093)
			(xy 42.097427 -21.772516) (xy 42.082072 -21.720221) (xy 42.074316 -21.666273) (xy 42.07383 -21.639022)
			(xy 35.245927 -21.639022) (xy 35.235042 -21.662945) (xy 35.173997 -21.777941) (xy 35.106056 -21.889002)
			(xy 35.03147 -21.995714) (xy 34.950517 -22.097681) (xy 34.863498 -22.194523) (xy 34.770737 -22.28588)
			(xy 34.672579 -22.371412) (xy 34.56939 -22.4508) (xy 34.461553 -22.52375) (xy 34.407907 -22.555454)
			(xy 51.336446 -22.555454) (xy 51.340517 -22.499832) (xy 51.352643 -22.445395) (xy 51.372566 -22.393304)
			(xy 51.399862 -22.344669) (xy 51.433948 -22.300526) (xy 51.474097 -22.261817) (xy 51.519455 -22.229366)
			(xy 51.569055 -22.203865) (xy 51.621839 -22.185858) (xy 51.676682 -22.175728) (xy 51.732416 -22.173691)
			(xy 51.787853 -22.179791) (xy 51.84181 -22.193897) (xy 51.893139 -22.215709) (xy 51.940745 -22.244763)
			(xy 51.983613 -22.280438) (xy 52.02083 -22.321975) (xy 52.051603 -22.368488) (xy 52.075275 -22.418985)
			(xy 52.091343 -22.472392) (xy 52.099463 -22.527568) (xy 52.099972 -22.555454) (xy 52.099463 -22.58334)
			(xy 52.091343 -22.638516) (xy 52.075275 -22.691923) (xy 52.051603 -22.74242) (xy 52.02083 -22.788933)
			(xy 51.983613 -22.83047) (xy 51.940745 -22.866145) (xy 51.893139 -22.895199) (xy 51.84181 -22.917011)
			(xy 51.787853 -22.931117) (xy 51.732416 -22.937217) (xy 51.676682 -22.93518) (xy 51.621839 -22.92505)
			(xy 51.569055 -22.907043) (xy 51.519455 -22.881542) (xy 51.474097 -22.849091) (xy 51.433948 -22.810382)
			(xy 51.399862 -22.766239) (xy 51.372566 -22.717604) (xy 51.352643 -22.665513) (xy 51.340517 -22.611076)
			(xy 51.336446 -22.555454) (xy 34.407907 -22.555454) (xy 34.349468 -22.589991) (xy 34.233555 -22.649274)
			(xy 34.114242 -22.701382) (xy 33.991975 -22.746118) (xy 33.867208 -22.783317) (xy 33.740405 -22.812841)
			(xy 33.612038 -22.834579) (xy 33.482585 -22.848452) (xy 33.352526 -22.854406) (xy 33.222347 -22.852421)
			(xy 33.092531 -22.842503) (xy 32.963561 -22.824689) (xy 32.835916 -22.799046) (xy 32.710073 -22.765669)
			(xy 32.586498 -22.724682) (xy 32.465652 -22.676238) (xy 32.347984 -22.620516) (xy 32.233932 -22.557725)
			(xy 32.12392 -22.488098) (xy 32.018358 -22.411893) (xy 31.917638 -22.329394) (xy 31.822134 -22.240909)
			(xy 31.732202 -22.146766) (xy 31.648177 -22.047315) (xy 31.570372 -21.942927) (xy 31.499075 -21.83399)
			(xy 31.434551 -21.720908) (xy 31.377042 -21.604104) (xy 31.32676 -21.484011) (xy 31.283894 -21.361075)
			(xy 31.248601 -21.235756) (xy 31.221015 -21.108517) (xy 31.201236 -20.979834) (xy 31.18934 -20.850184)
			(xy 31.18537 -20.72005) (xy 16.735844 -20.72005) (xy 16.753067 -20.739072) (xy 16.785631 -20.786437)
			(xy 16.810722 -20.838152) (xy 16.82777 -20.893046) (xy 16.836391 -20.949876) (xy 16.836389 -21.007356)
			(xy 16.827763 -21.064185) (xy 16.81071 -21.119078) (xy 16.785615 -21.17079) (xy 16.753047 -21.218153)
			(xy 16.733774 -21.23948) (xy 16.72717 -21.246338) (xy 16.720058 -21.264372) (xy 16.720058 -21.353272)
			(xy 16.72717 -21.371306) (xy 16.733774 -21.378164) (xy 16.753057 -21.39948) (xy 16.785621 -21.446845)
			(xy 16.810711 -21.49856) (xy 16.827759 -21.553453) (xy 16.836379 -21.610282) (xy 16.836898 -21.639022)
			(xy 16.836412 -21.666273) (xy 16.828656 -21.720221) (xy 16.813301 -21.772516) (xy 16.790659 -21.822093)
			(xy 16.761193 -21.867943) (xy 16.725502 -21.909134) (xy 16.684311 -21.944825) (xy 16.638461 -21.974291)
			(xy 16.588884 -21.996933) (xy 16.536589 -22.012288) (xy 16.482641 -22.020044) (xy 16.428139 -22.020044)
			(xy 16.374191 -22.012288) (xy 16.321896 -21.996933) (xy 16.272319 -21.974291) (xy 16.226469 -21.944825)
			(xy 16.185278 -21.909134) (xy 16.149587 -21.867943) (xy 16.120121 -21.822093) (xy 16.097479 -21.772516)
			(xy 16.082124 -21.720221) (xy 16.074368 -21.666273) (xy 16.073882 -21.639022) (xy 9.245979 -21.639022)
			(xy 9.235094 -21.662945) (xy 9.174049 -21.777941) (xy 9.106108 -21.889002) (xy 9.031522 -21.995714)
			(xy 8.950569 -22.097681) (xy 8.86355 -22.194523) (xy 8.770789 -22.28588) (xy 8.672631 -22.371412)
			(xy 8.569442 -22.4508) (xy 8.461605 -22.52375) (xy 8.34952 -22.589991) (xy 8.233607 -22.649274) (xy 8.114294 -22.701382)
			(xy 7.992027 -22.746118) (xy 7.86726 -22.783317) (xy 7.740457 -22.812841) (xy 7.61209 -22.834579)
			(xy 7.482637 -22.848452) (xy 7.352578 -22.854406) (xy 7.222399 -22.852421) (xy 7.092583 -22.842503)
			(xy 6.963613 -22.824689) (xy 6.835968 -22.799046) (xy 6.710125 -22.765669) (xy 6.58655 -22.724682)
			(xy 6.465704 -22.676238) (xy 6.348036 -22.620516) (xy 6.233984 -22.557725) (xy 6.123972 -22.488098)
			(xy 6.01841 -22.411893) (xy 5.91769 -22.329394) (xy 5.822186 -22.240909) (xy 5.732254 -22.146766)
			(xy 5.648229 -22.047315) (xy 5.570424 -21.942927) (xy 5.499127 -21.83399) (xy 5.434603 -21.720908)
			(xy 5.377094 -21.604104) (xy 5.326812 -21.484011) (xy 5.283946 -21.361075) (xy 5.248653 -21.235756)
			(xy 5.221067 -21.108517) (xy 5.201288 -20.979834) (xy 5.189392 -20.850184) (xy 5.185422 -20.72005)
			(xy 0.715772 -20.72005) (xy 0.715772 -22.45995) (xy 1.849626 -22.45995) (xy 1.853697 -22.404328)
			(xy 1.865823 -22.349891) (xy 1.885746 -22.2978) (xy 1.913042 -22.249165) (xy 1.947128 -22.205022)
			(xy 1.987277 -22.166313) (xy 2.032635 -22.133862) (xy 2.082235 -22.108361) (xy 2.135019 -22.090354)
			(xy 2.189862 -22.080224) (xy 2.245596 -22.078187) (xy 2.301033 -22.084287) (xy 2.35499 -22.098393)
			(xy 2.406319 -22.120205) (xy 2.453925 -22.149259) (xy 2.496793 -22.184934) (xy 2.53401 -22.226471)
			(xy 2.564783 -22.272984) (xy 2.588455 -22.323481) (xy 2.589623 -22.327362) (xy 2.865626 -22.327362)
			(xy 2.869697 -22.27174) (xy 2.881823 -22.217303) (xy 2.901746 -22.165212) (xy 2.929042 -22.116577)
			(xy 2.963128 -22.072434) (xy 3.003277 -22.033725) (xy 3.048635 -22.001274) (xy 3.098235 -21.975773)
			(xy 3.151019 -21.957766) (xy 3.205862 -21.947636) (xy 3.261596 -21.945599) (xy 3.317033 -21.951699)
			(xy 3.37099 -21.965805) (xy 3.422319 -21.987617) (xy 3.469925 -22.016671) (xy 3.512793 -22.052346)
			(xy 3.55001 -22.093883) (xy 3.580783 -22.140396) (xy 3.604455 -22.190893) (xy 3.620523 -22.2443)
			(xy 3.628643 -22.299476) (xy 3.629152 -22.327362) (xy 3.628643 -22.355248) (xy 3.620523 -22.410424)
			(xy 3.604455 -22.463831) (xy 3.580783 -22.514328) (xy 3.55001 -22.560841) (xy 3.512793 -22.602378)
			(xy 3.469925 -22.638053) (xy 3.422319 -22.667107) (xy 3.37099 -22.688919) (xy 3.317033 -22.703025)
			(xy 3.261596 -22.709125) (xy 3.205862 -22.707088) (xy 3.151019 -22.696958) (xy 3.098235 -22.678951)
			(xy 3.048635 -22.65345) (xy 3.003277 -22.620999) (xy 2.963128 -22.58229) (xy 2.929042 -22.538147)
			(xy 2.901746 -22.489512) (xy 2.881823 -22.437421) (xy 2.869697 -22.382984) (xy 2.865626 -22.327362)
			(xy 2.589623 -22.327362) (xy 2.604523 -22.376888) (xy 2.612643 -22.432064) (xy 2.613152 -22.45995)
			(xy 2.612643 -22.487836) (xy 2.604523 -22.543012) (xy 2.588455 -22.596419) (xy 2.564783 -22.646916)
			(xy 2.53401 -22.693429) (xy 2.496793 -22.734966) (xy 2.453925 -22.770641) (xy 2.406319 -22.799695)
			(xy 2.35499 -22.821507) (xy 2.301033 -22.835613) (xy 2.245596 -22.841713) (xy 2.189862 -22.839676)
			(xy 2.135019 -22.829546) (xy 2.082235 -22.811539) (xy 2.032635 -22.786038) (xy 1.987277 -22.753587)
			(xy 1.947128 -22.714878) (xy 1.913042 -22.670735) (xy 1.885746 -22.6221) (xy 1.865823 -22.570009)
			(xy 1.853697 -22.515572) (xy 1.849626 -22.45995) (xy 0.715772 -22.45995) (xy 0.715772 -22.86) (xy 4.189982 -22.86)
			(xy 4.194053 -22.804378) (xy 4.206179 -22.749941) (xy 4.226102 -22.69785) (xy 4.253398 -22.649215)
			(xy 4.287484 -22.605072) (xy 4.327633 -22.566363) (xy 4.372991 -22.533912) (xy 4.422591 -22.508411)
			(xy 4.475375 -22.490404) (xy 4.530218 -22.480274) (xy 4.585952 -22.478237) (xy 4.641389 -22.484337)
			(xy 4.695346 -22.498443) (xy 4.746675 -22.520255) (xy 4.794281 -22.549309) (xy 4.837149 -22.584984)
			(xy 4.874366 -22.626521) (xy 4.905139 -22.673034) (xy 4.928811 -22.723531) (xy 4.944879 -22.776938)
			(xy 4.952999 -22.832114) (xy 4.953508 -22.86) (xy 4.952999 -22.887886) (xy 4.944879 -22.943062) (xy 4.930743 -22.990048)
			(xy 11.298934 -22.990048) (xy 11.303005 -22.934426) (xy 11.315131 -22.879989) (xy 11.335054 -22.827898)
			(xy 11.36235 -22.779263) (xy 11.396436 -22.73512) (xy 11.436585 -22.696411) (xy 11.481943 -22.66396)
			(xy 11.531543 -22.638459) (xy 11.584327 -22.620452) (xy 11.63917 -22.610322) (xy 11.694904 -22.608285)
			(xy 11.750341 -22.614385) (xy 11.804298 -22.628491) (xy 11.855627 -22.650303) (xy 11.903233 -22.679357)
			(xy 11.946101 -22.715032) (xy 11.983318 -22.756569) (xy 12.014091 -22.803082) (xy 12.037763 -22.853579)
			(xy 12.053831 -22.906986) (xy 12.061951 -22.962162) (xy 12.06246 -22.990048) (xy 12.061982 -23.01621)
			(xy 12.711682 -23.01621) (xy 12.715753 -22.960588) (xy 12.727879 -22.906151) (xy 12.747802 -22.85406)
			(xy 12.775098 -22.805425) (xy 12.809184 -22.761282) (xy 12.849333 -22.722573) (xy 12.894691 -22.690122)
			(xy 12.944291 -22.664621) (xy 12.997075 -22.646614) (xy 13.051918 -22.636484) (xy 13.107652 -22.634447)
			(xy 13.163089 -22.640547) (xy 13.217046 -22.654653) (xy 13.268375 -22.676465) (xy 13.315981 -22.705519)
			(xy 13.358849 -22.741194) (xy 13.396066 -22.782731) (xy 13.426839 -22.829244) (xy 13.450511 -22.879741)
			(xy 13.466579 -22.933148) (xy 13.474699 -22.988324) (xy 13.475208 -23.01621) (xy 13.475046 -23.0251)
			(xy 37.362382 -23.0251) (xy 37.366453 -22.969478) (xy 37.378579 -22.915041) (xy 37.398502 -22.86295)
			(xy 37.425798 -22.814315) (xy 37.459884 -22.770172) (xy 37.500033 -22.731463) (xy 37.545391 -22.699012)
			(xy 37.594991 -22.673511) (xy 37.647775 -22.655504) (xy 37.702618 -22.645374) (xy 37.758352 -22.643337)
			(xy 37.813789 -22.649437) (xy 37.867746 -22.663543) (xy 37.919075 -22.685355) (xy 37.966681 -22.714409)
			(xy 38.009549 -22.750084) (xy 38.046766 -22.791621) (xy 38.077539 -22.838134) (xy 38.101211 -22.888631)
			(xy 38.117279 -22.942038) (xy 38.125399 -22.997214) (xy 38.125746 -23.01621) (xy 38.71163 -23.01621)
			(xy 38.715701 -22.960588) (xy 38.727827 -22.906151) (xy 38.74775 -22.85406) (xy 38.775046 -22.805425)
			(xy 38.809132 -22.761282) (xy 38.849281 -22.722573) (xy 38.894639 -22.690122) (xy 38.944239 -22.664621)
			(xy 38.997023 -22.646614) (xy 39.051866 -22.636484) (xy 39.1076 -22.634447) (xy 39.163037 -22.640547)
			(xy 39.216994 -22.654653) (xy 39.268323 -22.676465) (xy 39.315929 -22.705519) (xy 39.358797 -22.741194)
			(xy 39.396014 -22.782731) (xy 39.426787 -22.829244) (xy 39.450459 -22.879741) (xy 39.466527 -22.933148)
			(xy 39.474647 -22.988324) (xy 39.475156 -23.01621) (xy 39.474994 -23.0251) (xy 63.36233 -23.0251)
			(xy 63.366401 -22.969478) (xy 63.378527 -22.915041) (xy 63.39845 -22.86295) (xy 63.425746 -22.814315)
			(xy 63.459832 -22.770172) (xy 63.499981 -22.731463) (xy 63.545339 -22.699012) (xy 63.594939 -22.673511)
			(xy 63.647723 -22.655504) (xy 63.702566 -22.645374) (xy 63.7583 -22.643337) (xy 63.813737 -22.649437)
			(xy 63.867694 -22.663543) (xy 63.919023 -22.685355) (xy 63.966629 -22.714409) (xy 64.009497 -22.750084)
			(xy 64.046714 -22.791621) (xy 64.077487 -22.838134) (xy 64.101159 -22.888631) (xy 64.117227 -22.942038)
			(xy 64.125347 -22.997214) (xy 64.125694 -23.01621) (xy 64.711578 -23.01621) (xy 64.715649 -22.960588)
			(xy 64.727775 -22.906151) (xy 64.747698 -22.85406) (xy 64.774994 -22.805425) (xy 64.80908 -22.761282)
			(xy 64.849229 -22.722573) (xy 64.894587 -22.690122) (xy 64.944187 -22.664621) (xy 64.996971 -22.646614)
			(xy 65.051814 -22.636484) (xy 65.107548 -22.634447) (xy 65.162985 -22.640547) (xy 65.216942 -22.654653)
			(xy 65.268271 -22.676465) (xy 65.315877 -22.705519) (xy 65.358745 -22.741194) (xy 65.395962 -22.782731)
			(xy 65.426735 -22.829244) (xy 65.450407 -22.879741) (xy 65.466475 -22.933148) (xy 65.474595 -22.988324)
			(xy 65.475104 -23.01621) (xy 65.474942 -23.0251) (xy 89.362278 -23.0251) (xy 89.366349 -22.969478)
			(xy 89.378475 -22.915041) (xy 89.398398 -22.86295) (xy 89.425694 -22.814315) (xy 89.45978 -22.770172)
			(xy 89.499929 -22.731463) (xy 89.545287 -22.699012) (xy 89.594887 -22.673511) (xy 89.647671 -22.655504)
			(xy 89.702514 -22.645374) (xy 89.758248 -22.643337) (xy 89.813685 -22.649437) (xy 89.867642 -22.663543)
			(xy 89.918971 -22.685355) (xy 89.966577 -22.714409) (xy 90.009445 -22.750084) (xy 90.046662 -22.791621)
			(xy 90.077435 -22.838134) (xy 90.101107 -22.888631) (xy 90.117175 -22.942038) (xy 90.125295 -22.997214)
			(xy 90.125642 -23.01621) (xy 90.711526 -23.01621) (xy 90.715597 -22.960588) (xy 90.727723 -22.906151)
			(xy 90.747646 -22.85406) (xy 90.774942 -22.805425) (xy 90.809028 -22.761282) (xy 90.849177 -22.722573)
			(xy 90.894535 -22.690122) (xy 90.944135 -22.664621) (xy 90.996919 -22.646614) (xy 91.051762 -22.636484)
			(xy 91.107496 -22.634447) (xy 91.162933 -22.640547) (xy 91.21689 -22.654653) (xy 91.268219 -22.676465)
			(xy 91.315825 -22.705519) (xy 91.358693 -22.741194) (xy 91.39591 -22.782731) (xy 91.426683 -22.829244)
			(xy 91.450355 -22.879741) (xy 91.466423 -22.933148) (xy 91.474543 -22.988324) (xy 91.475052 -23.01621)
			(xy 91.47489 -23.0251) (xy 127.462532 -23.0251) (xy 127.466603 -22.969478) (xy 127.478729 -22.915041)
			(xy 127.498652 -22.86295) (xy 127.525948 -22.814315) (xy 127.560034 -22.770172) (xy 127.600183 -22.731463)
			(xy 127.645541 -22.699012) (xy 127.695141 -22.673511) (xy 127.747925 -22.655504) (xy 127.802768 -22.645374)
			(xy 127.858502 -22.643337) (xy 127.913939 -22.649437) (xy 127.967896 -22.663543) (xy 128.019225 -22.685355)
			(xy 128.066831 -22.714409) (xy 128.109699 -22.750084) (xy 128.146916 -22.791621) (xy 128.177689 -22.838134)
			(xy 128.201361 -22.888631) (xy 128.217429 -22.942038) (xy 128.225549 -22.997214) (xy 128.225896 -23.01621)
			(xy 128.81178 -23.01621) (xy 128.815851 -22.960588) (xy 128.827977 -22.906151) (xy 128.8479 -22.85406)
			(xy 128.875196 -22.805425) (xy 128.909282 -22.761282) (xy 128.949431 -22.722573) (xy 128.994789 -22.690122)
			(xy 129.044389 -22.664621) (xy 129.097173 -22.646614) (xy 129.152016 -22.636484) (xy 129.20775 -22.634447)
			(xy 129.263187 -22.640547) (xy 129.317144 -22.654653) (xy 129.368473 -22.676465) (xy 129.416079 -22.705519)
			(xy 129.458947 -22.741194) (xy 129.496164 -22.782731) (xy 129.526937 -22.829244) (xy 129.550609 -22.879741)
			(xy 129.566677 -22.933148) (xy 129.574797 -22.988324) (xy 129.575306 -23.01621) (xy 129.575144 -23.0251)
			(xy 153.46248 -23.0251) (xy 153.466551 -22.969478) (xy 153.478677 -22.915041) (xy 153.4986 -22.86295)
			(xy 153.525896 -22.814315) (xy 153.559982 -22.770172) (xy 153.600131 -22.731463) (xy 153.645489 -22.699012)
			(xy 153.695089 -22.673511) (xy 153.747873 -22.655504) (xy 153.802716 -22.645374) (xy 153.85845 -22.643337)
			(xy 153.913887 -22.649437) (xy 153.967844 -22.663543) (xy 154.019173 -22.685355) (xy 154.066779 -22.714409)
			(xy 154.109647 -22.750084) (xy 154.146864 -22.791621) (xy 154.177637 -22.838134) (xy 154.201309 -22.888631)
			(xy 154.217377 -22.942038) (xy 154.225497 -22.997214) (xy 154.225844 -23.01621) (xy 154.811728 -23.01621)
			(xy 154.815799 -22.960588) (xy 154.827925 -22.906151) (xy 154.847848 -22.85406) (xy 154.875144 -22.805425)
			(xy 154.90923 -22.761282) (xy 154.949379 -22.722573) (xy 154.994737 -22.690122) (xy 155.044337 -22.664621)
			(xy 155.097121 -22.646614) (xy 155.151964 -22.636484) (xy 155.207698 -22.634447) (xy 155.263135 -22.640547)
			(xy 155.317092 -22.654653) (xy 155.368421 -22.676465) (xy 155.416027 -22.705519) (xy 155.458895 -22.741194)
			(xy 155.496112 -22.782731) (xy 155.526885 -22.829244) (xy 155.550557 -22.879741) (xy 155.566625 -22.933148)
			(xy 155.574745 -22.988324) (xy 155.575254 -23.01621) (xy 155.575092 -23.0251) (xy 179.462428 -23.0251)
			(xy 179.466499 -22.969478) (xy 179.478625 -22.915041) (xy 179.498548 -22.86295) (xy 179.525844 -22.814315)
			(xy 179.55993 -22.770172) (xy 179.600079 -22.731463) (xy 179.645437 -22.699012) (xy 179.695037 -22.673511)
			(xy 179.747821 -22.655504) (xy 179.802664 -22.645374) (xy 179.858398 -22.643337) (xy 179.913835 -22.649437)
			(xy 179.967792 -22.663543) (xy 180.019121 -22.685355) (xy 180.066727 -22.714409) (xy 180.109595 -22.750084)
			(xy 180.146812 -22.791621) (xy 180.177585 -22.838134) (xy 180.201257 -22.888631) (xy 180.217325 -22.942038)
			(xy 180.225445 -22.997214) (xy 180.225792 -23.01621) (xy 180.811676 -23.01621) (xy 180.815747 -22.960588)
			(xy 180.827873 -22.906151) (xy 180.847796 -22.85406) (xy 180.875092 -22.805425) (xy 180.909178 -22.761282)
			(xy 180.949327 -22.722573) (xy 180.994685 -22.690122) (xy 181.044285 -22.664621) (xy 181.097069 -22.646614)
			(xy 181.151912 -22.636484) (xy 181.207646 -22.634447) (xy 181.263083 -22.640547) (xy 181.31704 -22.654653)
			(xy 181.368369 -22.676465) (xy 181.415975 -22.705519) (xy 181.458843 -22.741194) (xy 181.49606 -22.782731)
			(xy 181.526833 -22.829244) (xy 181.550505 -22.879741) (xy 181.566573 -22.933148) (xy 181.574693 -22.988324)
			(xy 181.575202 -23.01621) (xy 181.57504 -23.0251) (xy 205.462376 -23.0251) (xy 205.466447 -22.969478)
			(xy 205.478573 -22.915041) (xy 205.498496 -22.86295) (xy 205.525792 -22.814315) (xy 205.559878 -22.770172)
			(xy 205.600027 -22.731463) (xy 205.645385 -22.699012) (xy 205.694985 -22.673511) (xy 205.747769 -22.655504)
			(xy 205.802612 -22.645374) (xy 205.858346 -22.643337) (xy 205.913783 -22.649437) (xy 205.96774 -22.663543)
			(xy 206.019069 -22.685355) (xy 206.066675 -22.714409) (xy 206.109543 -22.750084) (xy 206.14676 -22.791621)
			(xy 206.177533 -22.838134) (xy 206.201205 -22.888631) (xy 206.217273 -22.942038) (xy 206.225393 -22.997214)
			(xy 206.22574 -23.01621) (xy 206.811624 -23.01621) (xy 206.815695 -22.960588) (xy 206.827821 -22.906151)
			(xy 206.847744 -22.85406) (xy 206.87504 -22.805425) (xy 206.909126 -22.761282) (xy 206.949275 -22.722573)
			(xy 206.994633 -22.690122) (xy 207.044233 -22.664621) (xy 207.097017 -22.646614) (xy 207.15186 -22.636484)
			(xy 207.207594 -22.634447) (xy 207.263031 -22.640547) (xy 207.316988 -22.654653) (xy 207.368317 -22.676465)
			(xy 207.415923 -22.705519) (xy 207.458791 -22.741194) (xy 207.496008 -22.782731) (xy 207.526781 -22.829244)
			(xy 207.550453 -22.879741) (xy 207.566521 -22.933148) (xy 207.574641 -22.988324) (xy 207.57515 -23.01621)
			(xy 207.574988 -23.0251) (xy 243.562376 -23.0251) (xy 243.566447 -22.969478) (xy 243.578573 -22.915041)
			(xy 243.598496 -22.86295) (xy 243.625792 -22.814315) (xy 243.659878 -22.770172) (xy 243.700027 -22.731463)
			(xy 243.745385 -22.699012) (xy 243.794985 -22.673511) (xy 243.847769 -22.655504) (xy 243.902612 -22.645374)
			(xy 243.958346 -22.643337) (xy 244.013783 -22.649437) (xy 244.06774 -22.663543) (xy 244.119069 -22.685355)
			(xy 244.166675 -22.714409) (xy 244.209543 -22.750084) (xy 244.24676 -22.791621) (xy 244.277533 -22.838134)
			(xy 244.301205 -22.888631) (xy 244.317273 -22.942038) (xy 244.325393 -22.997214) (xy 244.32574 -23.01621)
			(xy 244.911624 -23.01621) (xy 244.915695 -22.960588) (xy 244.927821 -22.906151) (xy 244.947744 -22.85406)
			(xy 244.97504 -22.805425) (xy 245.009126 -22.761282) (xy 245.049275 -22.722573) (xy 245.094633 -22.690122)
			(xy 245.144233 -22.664621) (xy 245.197017 -22.646614) (xy 245.25186 -22.636484) (xy 245.307594 -22.634447)
			(xy 245.363031 -22.640547) (xy 245.416988 -22.654653) (xy 245.468317 -22.676465) (xy 245.515923 -22.705519)
			(xy 245.558791 -22.741194) (xy 245.596008 -22.782731) (xy 245.626781 -22.829244) (xy 245.650453 -22.879741)
			(xy 245.666521 -22.933148) (xy 245.674641 -22.988324) (xy 245.67515 -23.01621) (xy 245.674988 -23.0251)
			(xy 269.562324 -23.0251) (xy 269.566395 -22.969478) (xy 269.578521 -22.915041) (xy 269.598444 -22.86295)
			(xy 269.62574 -22.814315) (xy 269.659826 -22.770172) (xy 269.699975 -22.731463) (xy 269.745333 -22.699012)
			(xy 269.794933 -22.673511) (xy 269.847717 -22.655504) (xy 269.90256 -22.645374) (xy 269.958294 -22.643337)
			(xy 270.013731 -22.649437) (xy 270.067688 -22.663543) (xy 270.119017 -22.685355) (xy 270.166623 -22.714409)
			(xy 270.209491 -22.750084) (xy 270.246708 -22.791621) (xy 270.277481 -22.838134) (xy 270.301153 -22.888631)
			(xy 270.317221 -22.942038) (xy 270.325341 -22.997214) (xy 270.325688 -23.01621) (xy 270.911572 -23.01621)
			(xy 270.915643 -22.960588) (xy 270.927769 -22.906151) (xy 270.947692 -22.85406) (xy 270.974988 -22.805425)
			(xy 271.009074 -22.761282) (xy 271.049223 -22.722573) (xy 271.094581 -22.690122) (xy 271.144181 -22.664621)
			(xy 271.196965 -22.646614) (xy 271.251808 -22.636484) (xy 271.307542 -22.634447) (xy 271.362979 -22.640547)
			(xy 271.416936 -22.654653) (xy 271.468265 -22.676465) (xy 271.515871 -22.705519) (xy 271.558739 -22.741194)
			(xy 271.595956 -22.782731) (xy 271.626729 -22.829244) (xy 271.650401 -22.879741) (xy 271.666469 -22.933148)
			(xy 271.674589 -22.988324) (xy 271.675098 -23.01621) (xy 271.674936 -23.0251) (xy 295.562272 -23.0251)
			(xy 295.566343 -22.969478) (xy 295.578469 -22.915041) (xy 295.598392 -22.86295) (xy 295.625688 -22.814315)
			(xy 295.659774 -22.770172) (xy 295.699923 -22.731463) (xy 295.745281 -22.699012) (xy 295.794881 -22.673511)
			(xy 295.847665 -22.655504) (xy 295.902508 -22.645374) (xy 295.958242 -22.643337) (xy 296.013679 -22.649437)
			(xy 296.067636 -22.663543) (xy 296.118965 -22.685355) (xy 296.166571 -22.714409) (xy 296.209439 -22.750084)
			(xy 296.246656 -22.791621) (xy 296.277429 -22.838134) (xy 296.301101 -22.888631) (xy 296.317169 -22.942038)
			(xy 296.325289 -22.997214) (xy 296.325636 -23.01621) (xy 296.91152 -23.01621) (xy 296.915591 -22.960588)
			(xy 296.927717 -22.906151) (xy 296.94764 -22.85406) (xy 296.974936 -22.805425) (xy 297.009022 -22.761282)
			(xy 297.049171 -22.722573) (xy 297.094529 -22.690122) (xy 297.144129 -22.664621) (xy 297.196913 -22.646614)
			(xy 297.251756 -22.636484) (xy 297.30749 -22.634447) (xy 297.362927 -22.640547) (xy 297.416884 -22.654653)
			(xy 297.468213 -22.676465) (xy 297.515819 -22.705519) (xy 297.558687 -22.741194) (xy 297.595904 -22.782731)
			(xy 297.626677 -22.829244) (xy 297.650349 -22.879741) (xy 297.666417 -22.933148) (xy 297.674537 -22.988324)
			(xy 297.675046 -23.01621) (xy 297.674884 -23.0251) (xy 321.56222 -23.0251) (xy 321.566291 -22.969478)
			(xy 321.578417 -22.915041) (xy 321.59834 -22.86295) (xy 321.625636 -22.814315) (xy 321.659722 -22.770172)
			(xy 321.699871 -22.731463) (xy 321.745229 -22.699012) (xy 321.794829 -22.673511) (xy 321.847613 -22.655504)
			(xy 321.902456 -22.645374) (xy 321.95819 -22.643337) (xy 322.013627 -22.649437) (xy 322.067584 -22.663543)
			(xy 322.118913 -22.685355) (xy 322.166519 -22.714409) (xy 322.209387 -22.750084) (xy 322.246604 -22.791621)
			(xy 322.277377 -22.838134) (xy 322.301049 -22.888631) (xy 322.317117 -22.942038) (xy 322.325237 -22.997214)
			(xy 322.325584 -23.01621) (xy 322.911468 -23.01621) (xy 322.915539 -22.960588) (xy 322.927665 -22.906151)
			(xy 322.947588 -22.85406) (xy 322.974884 -22.805425) (xy 323.00897 -22.761282) (xy 323.049119 -22.722573)
			(xy 323.094477 -22.690122) (xy 323.144077 -22.664621) (xy 323.196861 -22.646614) (xy 323.251704 -22.636484)
			(xy 323.307438 -22.634447) (xy 323.362875 -22.640547) (xy 323.416832 -22.654653) (xy 323.468161 -22.676465)
			(xy 323.515767 -22.705519) (xy 323.558635 -22.741194) (xy 323.595852 -22.782731) (xy 323.626625 -22.829244)
			(xy 323.650297 -22.879741) (xy 323.666365 -22.933148) (xy 323.674485 -22.988324) (xy 323.674994 -23.01621)
			(xy 323.674832 -23.0251) (xy 359.662474 -23.0251) (xy 359.666545 -22.969478) (xy 359.678671 -22.915041)
			(xy 359.698594 -22.86295) (xy 359.72589 -22.814315) (xy 359.759976 -22.770172) (xy 359.800125 -22.731463)
			(xy 359.845483 -22.699012) (xy 359.895083 -22.673511) (xy 359.947867 -22.655504) (xy 360.00271 -22.645374)
			(xy 360.058444 -22.643337) (xy 360.113881 -22.649437) (xy 360.167838 -22.663543) (xy 360.219167 -22.685355)
			(xy 360.266773 -22.714409) (xy 360.309641 -22.750084) (xy 360.346858 -22.791621) (xy 360.377631 -22.838134)
			(xy 360.401303 -22.888631) (xy 360.417371 -22.942038) (xy 360.425491 -22.997214) (xy 360.425838 -23.01621)
			(xy 361.011722 -23.01621) (xy 361.015793 -22.960588) (xy 361.027919 -22.906151) (xy 361.047842 -22.85406)
			(xy 361.075138 -22.805425) (xy 361.109224 -22.761282) (xy 361.149373 -22.722573) (xy 361.194731 -22.690122)
			(xy 361.244331 -22.664621) (xy 361.297115 -22.646614) (xy 361.351958 -22.636484) (xy 361.407692 -22.634447)
			(xy 361.463129 -22.640547) (xy 361.517086 -22.654653) (xy 361.568415 -22.676465) (xy 361.616021 -22.705519)
			(xy 361.658889 -22.741194) (xy 361.696106 -22.782731) (xy 361.726879 -22.829244) (xy 361.750551 -22.879741)
			(xy 361.766619 -22.933148) (xy 361.774739 -22.988324) (xy 361.775248 -23.01621) (xy 361.775086 -23.0251)
			(xy 385.662422 -23.0251) (xy 385.666493 -22.969478) (xy 385.678619 -22.915041) (xy 385.698542 -22.86295)
			(xy 385.725838 -22.814315) (xy 385.759924 -22.770172) (xy 385.800073 -22.731463) (xy 385.845431 -22.699012)
			(xy 385.895031 -22.673511) (xy 385.947815 -22.655504) (xy 386.002658 -22.645374) (xy 386.058392 -22.643337)
			(xy 386.113829 -22.649437) (xy 386.167786 -22.663543) (xy 386.219115 -22.685355) (xy 386.266721 -22.714409)
			(xy 386.309589 -22.750084) (xy 386.346806 -22.791621) (xy 386.377579 -22.838134) (xy 386.401251 -22.888631)
			(xy 386.417319 -22.942038) (xy 386.425439 -22.997214) (xy 386.425786 -23.01621) (xy 387.01167 -23.01621)
			(xy 387.015741 -22.960588) (xy 387.027867 -22.906151) (xy 387.04779 -22.85406) (xy 387.075086 -22.805425)
			(xy 387.109172 -22.761282) (xy 387.149321 -22.722573) (xy 387.194679 -22.690122) (xy 387.244279 -22.664621)
			(xy 387.297063 -22.646614) (xy 387.351906 -22.636484) (xy 387.40764 -22.634447) (xy 387.463077 -22.640547)
			(xy 387.517034 -22.654653) (xy 387.568363 -22.676465) (xy 387.615969 -22.705519) (xy 387.658837 -22.741194)
			(xy 387.696054 -22.782731) (xy 387.726827 -22.829244) (xy 387.750499 -22.879741) (xy 387.766567 -22.933148)
			(xy 387.774687 -22.988324) (xy 387.775196 -23.01621) (xy 387.775034 -23.0251) (xy 411.66237 -23.0251)
			(xy 411.666441 -22.969478) (xy 411.678567 -22.915041) (xy 411.69849 -22.86295) (xy 411.725786 -22.814315)
			(xy 411.759872 -22.770172) (xy 411.800021 -22.731463) (xy 411.845379 -22.699012) (xy 411.894979 -22.673511)
			(xy 411.947763 -22.655504) (xy 412.002606 -22.645374) (xy 412.05834 -22.643337) (xy 412.113777 -22.649437)
			(xy 412.167734 -22.663543) (xy 412.219063 -22.685355) (xy 412.266669 -22.714409) (xy 412.309537 -22.750084)
			(xy 412.346754 -22.791621) (xy 412.377527 -22.838134) (xy 412.401199 -22.888631) (xy 412.417267 -22.942038)
			(xy 412.425387 -22.997214) (xy 412.425734 -23.01621) (xy 413.011618 -23.01621) (xy 413.015689 -22.960588)
			(xy 413.027815 -22.906151) (xy 413.047738 -22.85406) (xy 413.075034 -22.805425) (xy 413.10912 -22.761282)
			(xy 413.149269 -22.722573) (xy 413.194627 -22.690122) (xy 413.244227 -22.664621) (xy 413.297011 -22.646614)
			(xy 413.351854 -22.636484) (xy 413.407588 -22.634447) (xy 413.463025 -22.640547) (xy 413.516982 -22.654653)
			(xy 413.568311 -22.676465) (xy 413.615917 -22.705519) (xy 413.658785 -22.741194) (xy 413.696002 -22.782731)
			(xy 413.726775 -22.829244) (xy 413.750447 -22.879741) (xy 413.766515 -22.933148) (xy 413.774635 -22.988324)
			(xy 413.775144 -23.01621) (xy 413.774982 -23.0251) (xy 437.662318 -23.0251) (xy 437.666389 -22.969478)
			(xy 437.678515 -22.915041) (xy 437.698438 -22.86295) (xy 437.725734 -22.814315) (xy 437.75982 -22.770172)
			(xy 437.799969 -22.731463) (xy 437.845327 -22.699012) (xy 437.894927 -22.673511) (xy 437.947711 -22.655504)
			(xy 438.002554 -22.645374) (xy 438.058288 -22.643337) (xy 438.113725 -22.649437) (xy 438.167682 -22.663543)
			(xy 438.219011 -22.685355) (xy 438.266617 -22.714409) (xy 438.309485 -22.750084) (xy 438.346702 -22.791621)
			(xy 438.377475 -22.838134) (xy 438.401147 -22.888631) (xy 438.417215 -22.942038) (xy 438.425335 -22.997214)
			(xy 438.425682 -23.01621) (xy 439.011566 -23.01621) (xy 439.015637 -22.960588) (xy 439.027763 -22.906151)
			(xy 439.047686 -22.85406) (xy 439.074982 -22.805425) (xy 439.109068 -22.761282) (xy 439.149217 -22.722573)
			(xy 439.194575 -22.690122) (xy 439.244175 -22.664621) (xy 439.296959 -22.646614) (xy 439.351802 -22.636484)
			(xy 439.407536 -22.634447) (xy 439.462973 -22.640547) (xy 439.51693 -22.654653) (xy 439.568259 -22.676465)
			(xy 439.615865 -22.705519) (xy 439.658733 -22.741194) (xy 439.69595 -22.782731) (xy 439.726723 -22.829244)
			(xy 439.750395 -22.879741) (xy 439.766463 -22.933148) (xy 439.774583 -22.988324) (xy 439.775092 -23.01621)
			(xy 439.774583 -23.044096) (xy 439.766463 -23.099272) (xy 439.750395 -23.152679) (xy 439.726723 -23.203176)
			(xy 439.69595 -23.249689) (xy 439.658733 -23.291226) (xy 439.615865 -23.326901) (xy 439.568259 -23.355955)
			(xy 439.51693 -23.377767) (xy 439.462973 -23.391873) (xy 439.407536 -23.397973) (xy 439.351802 -23.395936)
			(xy 439.296959 -23.385806) (xy 439.244175 -23.367799) (xy 439.194575 -23.342298) (xy 439.149217 -23.309847)
			(xy 439.109068 -23.271138) (xy 439.074982 -23.226995) (xy 439.047686 -23.17836) (xy 439.027763 -23.126269)
			(xy 439.015637 -23.071832) (xy 439.011566 -23.01621) (xy 438.425682 -23.01621) (xy 438.425844 -23.0251)
			(xy 438.425335 -23.052986) (xy 438.417215 -23.108162) (xy 438.401147 -23.161569) (xy 438.377475 -23.212066)
			(xy 438.346702 -23.258579) (xy 438.309485 -23.300116) (xy 438.266617 -23.335791) (xy 438.219011 -23.364845)
			(xy 438.167682 -23.386657) (xy 438.113725 -23.400763) (xy 438.058288 -23.406863) (xy 438.002554 -23.404826)
			(xy 437.947711 -23.394696) (xy 437.894927 -23.376689) (xy 437.845327 -23.351188) (xy 437.799969 -23.318737)
			(xy 437.75982 -23.280028) (xy 437.725734 -23.235885) (xy 437.698438 -23.18725) (xy 437.678515 -23.135159)
			(xy 437.666389 -23.080722) (xy 437.662318 -23.0251) (xy 413.774982 -23.0251) (xy 413.774635 -23.044096)
			(xy 413.766515 -23.099272) (xy 413.750447 -23.152679) (xy 413.726775 -23.203176) (xy 413.696002 -23.249689)
			(xy 413.658785 -23.291226) (xy 413.615917 -23.326901) (xy 413.568311 -23.355955) (xy 413.516982 -23.377767)
			(xy 413.463025 -23.391873) (xy 413.407588 -23.397973) (xy 413.351854 -23.395936) (xy 413.297011 -23.385806)
			(xy 413.244227 -23.367799) (xy 413.194627 -23.342298) (xy 413.149269 -23.309847) (xy 413.10912 -23.271138)
			(xy 413.075034 -23.226995) (xy 413.047738 -23.17836) (xy 413.027815 -23.126269) (xy 413.015689 -23.071832)
			(xy 413.011618 -23.01621) (xy 412.425734 -23.01621) (xy 412.425896 -23.0251) (xy 412.425387 -23.052986)
			(xy 412.417267 -23.108162) (xy 412.401199 -23.161569) (xy 412.377527 -23.212066) (xy 412.346754 -23.258579)
			(xy 412.309537 -23.300116) (xy 412.266669 -23.335791) (xy 412.219063 -23.364845) (xy 412.167734 -23.386657)
			(xy 412.113777 -23.400763) (xy 412.05834 -23.406863) (xy 412.002606 -23.404826) (xy 411.947763 -23.394696)
			(xy 411.894979 -23.376689) (xy 411.845379 -23.351188) (xy 411.800021 -23.318737) (xy 411.759872 -23.280028)
			(xy 411.725786 -23.235885) (xy 411.69849 -23.18725) (xy 411.678567 -23.135159) (xy 411.666441 -23.080722)
			(xy 411.66237 -23.0251) (xy 387.775034 -23.0251) (xy 387.774687 -23.044096) (xy 387.766567 -23.099272)
			(xy 387.750499 -23.152679) (xy 387.726827 -23.203176) (xy 387.696054 -23.249689) (xy 387.658837 -23.291226)
			(xy 387.615969 -23.326901) (xy 387.568363 -23.355955) (xy 387.517034 -23.377767) (xy 387.463077 -23.391873)
			(xy 387.40764 -23.397973) (xy 387.351906 -23.395936) (xy 387.297063 -23.385806) (xy 387.244279 -23.367799)
			(xy 387.194679 -23.342298) (xy 387.149321 -23.309847) (xy 387.109172 -23.271138) (xy 387.075086 -23.226995)
			(xy 387.04779 -23.17836) (xy 387.027867 -23.126269) (xy 387.015741 -23.071832) (xy 387.01167 -23.01621)
			(xy 386.425786 -23.01621) (xy 386.425948 -23.0251) (xy 386.425439 -23.052986) (xy 386.417319 -23.108162)
			(xy 386.401251 -23.161569) (xy 386.377579 -23.212066) (xy 386.346806 -23.258579) (xy 386.309589 -23.300116)
			(xy 386.266721 -23.335791) (xy 386.219115 -23.364845) (xy 386.167786 -23.386657) (xy 386.113829 -23.400763)
			(xy 386.058392 -23.406863) (xy 386.002658 -23.404826) (xy 385.947815 -23.394696) (xy 385.895031 -23.376689)
			(xy 385.845431 -23.351188) (xy 385.800073 -23.318737) (xy 385.759924 -23.280028) (xy 385.725838 -23.235885)
			(xy 385.698542 -23.18725) (xy 385.678619 -23.135159) (xy 385.666493 -23.080722) (xy 385.662422 -23.0251)
			(xy 361.775086 -23.0251) (xy 361.774739 -23.044096) (xy 361.766619 -23.099272) (xy 361.750551 -23.152679)
			(xy 361.726879 -23.203176) (xy 361.696106 -23.249689) (xy 361.658889 -23.291226) (xy 361.616021 -23.326901)
			(xy 361.568415 -23.355955) (xy 361.517086 -23.377767) (xy 361.463129 -23.391873) (xy 361.407692 -23.397973)
			(xy 361.351958 -23.395936) (xy 361.297115 -23.385806) (xy 361.244331 -23.367799) (xy 361.194731 -23.342298)
			(xy 361.149373 -23.309847) (xy 361.109224 -23.271138) (xy 361.075138 -23.226995) (xy 361.047842 -23.17836)
			(xy 361.027919 -23.126269) (xy 361.015793 -23.071832) (xy 361.011722 -23.01621) (xy 360.425838 -23.01621)
			(xy 360.426 -23.0251) (xy 360.425491 -23.052986) (xy 360.417371 -23.108162) (xy 360.401303 -23.161569)
			(xy 360.377631 -23.212066) (xy 360.346858 -23.258579) (xy 360.309641 -23.300116) (xy 360.266773 -23.335791)
			(xy 360.219167 -23.364845) (xy 360.167838 -23.386657) (xy 360.113881 -23.400763) (xy 360.058444 -23.406863)
			(xy 360.00271 -23.404826) (xy 359.947867 -23.394696) (xy 359.895083 -23.376689) (xy 359.845483 -23.351188)
			(xy 359.800125 -23.318737) (xy 359.759976 -23.280028) (xy 359.72589 -23.235885) (xy 359.698594 -23.18725)
			(xy 359.678671 -23.135159) (xy 359.666545 -23.080722) (xy 359.662474 -23.0251) (xy 323.674832 -23.0251)
			(xy 323.674485 -23.044096) (xy 323.666365 -23.099272) (xy 323.650297 -23.152679) (xy 323.626625 -23.203176)
			(xy 323.595852 -23.249689) (xy 323.558635 -23.291226) (xy 323.515767 -23.326901) (xy 323.468161 -23.355955)
			(xy 323.416832 -23.377767) (xy 323.362875 -23.391873) (xy 323.307438 -23.397973) (xy 323.251704 -23.395936)
			(xy 323.196861 -23.385806) (xy 323.144077 -23.367799) (xy 323.094477 -23.342298) (xy 323.049119 -23.309847)
			(xy 323.00897 -23.271138) (xy 322.974884 -23.226995) (xy 322.947588 -23.17836) (xy 322.927665 -23.126269)
			(xy 322.915539 -23.071832) (xy 322.911468 -23.01621) (xy 322.325584 -23.01621) (xy 322.325746 -23.0251)
			(xy 322.325237 -23.052986) (xy 322.317117 -23.108162) (xy 322.301049 -23.161569) (xy 322.277377 -23.212066)
			(xy 322.246604 -23.258579) (xy 322.209387 -23.300116) (xy 322.166519 -23.335791) (xy 322.118913 -23.364845)
			(xy 322.067584 -23.386657) (xy 322.013627 -23.400763) (xy 321.95819 -23.406863) (xy 321.902456 -23.404826)
			(xy 321.847613 -23.394696) (xy 321.794829 -23.376689) (xy 321.745229 -23.351188) (xy 321.699871 -23.318737)
			(xy 321.659722 -23.280028) (xy 321.625636 -23.235885) (xy 321.59834 -23.18725) (xy 321.578417 -23.135159)
			(xy 321.566291 -23.080722) (xy 321.56222 -23.0251) (xy 297.674884 -23.0251) (xy 297.674537 -23.044096)
			(xy 297.666417 -23.099272) (xy 297.650349 -23.152679) (xy 297.626677 -23.203176) (xy 297.595904 -23.249689)
			(xy 297.558687 -23.291226) (xy 297.515819 -23.326901) (xy 297.468213 -23.355955) (xy 297.416884 -23.377767)
			(xy 297.362927 -23.391873) (xy 297.30749 -23.397973) (xy 297.251756 -23.395936) (xy 297.196913 -23.385806)
			(xy 297.144129 -23.367799) (xy 297.094529 -23.342298) (xy 297.049171 -23.309847) (xy 297.009022 -23.271138)
			(xy 296.974936 -23.226995) (xy 296.94764 -23.17836) (xy 296.927717 -23.126269) (xy 296.915591 -23.071832)
			(xy 296.91152 -23.01621) (xy 296.325636 -23.01621) (xy 296.325798 -23.0251) (xy 296.325289 -23.052986)
			(xy 296.317169 -23.108162) (xy 296.301101 -23.161569) (xy 296.277429 -23.212066) (xy 296.246656 -23.258579)
			(xy 296.209439 -23.300116) (xy 296.166571 -23.335791) (xy 296.118965 -23.364845) (xy 296.067636 -23.386657)
			(xy 296.013679 -23.400763) (xy 295.958242 -23.406863) (xy 295.902508 -23.404826) (xy 295.847665 -23.394696)
			(xy 295.794881 -23.376689) (xy 295.745281 -23.351188) (xy 295.699923 -23.318737) (xy 295.659774 -23.280028)
			(xy 295.625688 -23.235885) (xy 295.598392 -23.18725) (xy 295.578469 -23.135159) (xy 295.566343 -23.080722)
			(xy 295.562272 -23.0251) (xy 271.674936 -23.0251) (xy 271.674589 -23.044096) (xy 271.666469 -23.099272)
			(xy 271.650401 -23.152679) (xy 271.626729 -23.203176) (xy 271.595956 -23.249689) (xy 271.558739 -23.291226)
			(xy 271.515871 -23.326901) (xy 271.468265 -23.355955) (xy 271.416936 -23.377767) (xy 271.362979 -23.391873)
			(xy 271.307542 -23.397973) (xy 271.251808 -23.395936) (xy 271.196965 -23.385806) (xy 271.144181 -23.367799)
			(xy 271.094581 -23.342298) (xy 271.049223 -23.309847) (xy 271.009074 -23.271138) (xy 270.974988 -23.226995)
			(xy 270.947692 -23.17836) (xy 270.927769 -23.126269) (xy 270.915643 -23.071832) (xy 270.911572 -23.01621)
			(xy 270.325688 -23.01621) (xy 270.32585 -23.0251) (xy 270.325341 -23.052986) (xy 270.317221 -23.108162)
			(xy 270.301153 -23.161569) (xy 270.277481 -23.212066) (xy 270.246708 -23.258579) (xy 270.209491 -23.300116)
			(xy 270.166623 -23.335791) (xy 270.119017 -23.364845) (xy 270.067688 -23.386657) (xy 270.013731 -23.400763)
			(xy 269.958294 -23.406863) (xy 269.90256 -23.404826) (xy 269.847717 -23.394696) (xy 269.794933 -23.376689)
			(xy 269.745333 -23.351188) (xy 269.699975 -23.318737) (xy 269.659826 -23.280028) (xy 269.62574 -23.235885)
			(xy 269.598444 -23.18725) (xy 269.578521 -23.135159) (xy 269.566395 -23.080722) (xy 269.562324 -23.0251)
			(xy 245.674988 -23.0251) (xy 245.674641 -23.044096) (xy 245.666521 -23.099272) (xy 245.650453 -23.152679)
			(xy 245.626781 -23.203176) (xy 245.596008 -23.249689) (xy 245.558791 -23.291226) (xy 245.515923 -23.326901)
			(xy 245.468317 -23.355955) (xy 245.416988 -23.377767) (xy 245.363031 -23.391873) (xy 245.307594 -23.397973)
			(xy 245.25186 -23.395936) (xy 245.197017 -23.385806) (xy 245.144233 -23.367799) (xy 245.094633 -23.342298)
			(xy 245.049275 -23.309847) (xy 245.009126 -23.271138) (xy 244.97504 -23.226995) (xy 244.947744 -23.17836)
			(xy 244.927821 -23.126269) (xy 244.915695 -23.071832) (xy 244.911624 -23.01621) (xy 244.32574 -23.01621)
			(xy 244.325902 -23.0251) (xy 244.325393 -23.052986) (xy 244.317273 -23.108162) (xy 244.301205 -23.161569)
			(xy 244.277533 -23.212066) (xy 244.24676 -23.258579) (xy 244.209543 -23.300116) (xy 244.166675 -23.335791)
			(xy 244.119069 -23.364845) (xy 244.06774 -23.386657) (xy 244.013783 -23.400763) (xy 243.958346 -23.406863)
			(xy 243.902612 -23.404826) (xy 243.847769 -23.394696) (xy 243.794985 -23.376689) (xy 243.745385 -23.351188)
			(xy 243.700027 -23.318737) (xy 243.659878 -23.280028) (xy 243.625792 -23.235885) (xy 243.598496 -23.18725)
			(xy 243.578573 -23.135159) (xy 243.566447 -23.080722) (xy 243.562376 -23.0251) (xy 207.574988 -23.0251)
			(xy 207.574641 -23.044096) (xy 207.566521 -23.099272) (xy 207.550453 -23.152679) (xy 207.526781 -23.203176)
			(xy 207.496008 -23.249689) (xy 207.458791 -23.291226) (xy 207.415923 -23.326901) (xy 207.368317 -23.355955)
			(xy 207.316988 -23.377767) (xy 207.263031 -23.391873) (xy 207.207594 -23.397973) (xy 207.15186 -23.395936)
			(xy 207.097017 -23.385806) (xy 207.044233 -23.367799) (xy 206.994633 -23.342298) (xy 206.949275 -23.309847)
			(xy 206.909126 -23.271138) (xy 206.87504 -23.226995) (xy 206.847744 -23.17836) (xy 206.827821 -23.126269)
			(xy 206.815695 -23.071832) (xy 206.811624 -23.01621) (xy 206.22574 -23.01621) (xy 206.225902 -23.0251)
			(xy 206.225393 -23.052986) (xy 206.217273 -23.108162) (xy 206.201205 -23.161569) (xy 206.177533 -23.212066)
			(xy 206.14676 -23.258579) (xy 206.109543 -23.300116) (xy 206.066675 -23.335791) (xy 206.019069 -23.364845)
			(xy 205.96774 -23.386657) (xy 205.913783 -23.400763) (xy 205.858346 -23.406863) (xy 205.802612 -23.404826)
			(xy 205.747769 -23.394696) (xy 205.694985 -23.376689) (xy 205.645385 -23.351188) (xy 205.600027 -23.318737)
			(xy 205.559878 -23.280028) (xy 205.525792 -23.235885) (xy 205.498496 -23.18725) (xy 205.478573 -23.135159)
			(xy 205.466447 -23.080722) (xy 205.462376 -23.0251) (xy 181.57504 -23.0251) (xy 181.574693 -23.044096)
			(xy 181.566573 -23.099272) (xy 181.550505 -23.152679) (xy 181.526833 -23.203176) (xy 181.49606 -23.249689)
			(xy 181.458843 -23.291226) (xy 181.415975 -23.326901) (xy 181.368369 -23.355955) (xy 181.31704 -23.377767)
			(xy 181.263083 -23.391873) (xy 181.207646 -23.397973) (xy 181.151912 -23.395936) (xy 181.097069 -23.385806)
			(xy 181.044285 -23.367799) (xy 180.994685 -23.342298) (xy 180.949327 -23.309847) (xy 180.909178 -23.271138)
			(xy 180.875092 -23.226995) (xy 180.847796 -23.17836) (xy 180.827873 -23.126269) (xy 180.815747 -23.071832)
			(xy 180.811676 -23.01621) (xy 180.225792 -23.01621) (xy 180.225954 -23.0251) (xy 180.225445 -23.052986)
			(xy 180.217325 -23.108162) (xy 180.201257 -23.161569) (xy 180.177585 -23.212066) (xy 180.146812 -23.258579)
			(xy 180.109595 -23.300116) (xy 180.066727 -23.335791) (xy 180.019121 -23.364845) (xy 179.967792 -23.386657)
			(xy 179.913835 -23.400763) (xy 179.858398 -23.406863) (xy 179.802664 -23.404826) (xy 179.747821 -23.394696)
			(xy 179.695037 -23.376689) (xy 179.645437 -23.351188) (xy 179.600079 -23.318737) (xy 179.55993 -23.280028)
			(xy 179.525844 -23.235885) (xy 179.498548 -23.18725) (xy 179.478625 -23.135159) (xy 179.466499 -23.080722)
			(xy 179.462428 -23.0251) (xy 155.575092 -23.0251) (xy 155.574745 -23.044096) (xy 155.566625 -23.099272)
			(xy 155.550557 -23.152679) (xy 155.526885 -23.203176) (xy 155.496112 -23.249689) (xy 155.458895 -23.291226)
			(xy 155.416027 -23.326901) (xy 155.368421 -23.355955) (xy 155.317092 -23.377767) (xy 155.263135 -23.391873)
			(xy 155.207698 -23.397973) (xy 155.151964 -23.395936) (xy 155.097121 -23.385806) (xy 155.044337 -23.367799)
			(xy 154.994737 -23.342298) (xy 154.949379 -23.309847) (xy 154.90923 -23.271138) (xy 154.875144 -23.226995)
			(xy 154.847848 -23.17836) (xy 154.827925 -23.126269) (xy 154.815799 -23.071832) (xy 154.811728 -23.01621)
			(xy 154.225844 -23.01621) (xy 154.226006 -23.0251) (xy 154.225497 -23.052986) (xy 154.217377 -23.108162)
			(xy 154.201309 -23.161569) (xy 154.177637 -23.212066) (xy 154.146864 -23.258579) (xy 154.109647 -23.300116)
			(xy 154.066779 -23.335791) (xy 154.019173 -23.364845) (xy 153.967844 -23.386657) (xy 153.913887 -23.400763)
			(xy 153.85845 -23.406863) (xy 153.802716 -23.404826) (xy 153.747873 -23.394696) (xy 153.695089 -23.376689)
			(xy 153.645489 -23.351188) (xy 153.600131 -23.318737) (xy 153.559982 -23.280028) (xy 153.525896 -23.235885)
			(xy 153.4986 -23.18725) (xy 153.478677 -23.135159) (xy 153.466551 -23.080722) (xy 153.46248 -23.0251)
			(xy 129.575144 -23.0251) (xy 129.574797 -23.044096) (xy 129.566677 -23.099272) (xy 129.550609 -23.152679)
			(xy 129.526937 -23.203176) (xy 129.496164 -23.249689) (xy 129.458947 -23.291226) (xy 129.416079 -23.326901)
			(xy 129.368473 -23.355955) (xy 129.317144 -23.377767) (xy 129.263187 -23.391873) (xy 129.20775 -23.397973)
			(xy 129.152016 -23.395936) (xy 129.097173 -23.385806) (xy 129.044389 -23.367799) (xy 128.994789 -23.342298)
			(xy 128.949431 -23.309847) (xy 128.909282 -23.271138) (xy 128.875196 -23.226995) (xy 128.8479 -23.17836)
			(xy 128.827977 -23.126269) (xy 128.815851 -23.071832) (xy 128.81178 -23.01621) (xy 128.225896 -23.01621)
			(xy 128.226058 -23.0251) (xy 128.225549 -23.052986) (xy 128.217429 -23.108162) (xy 128.201361 -23.161569)
			(xy 128.177689 -23.212066) (xy 128.146916 -23.258579) (xy 128.109699 -23.300116) (xy 128.066831 -23.335791)
			(xy 128.019225 -23.364845) (xy 127.967896 -23.386657) (xy 127.913939 -23.400763) (xy 127.858502 -23.406863)
			(xy 127.802768 -23.404826) (xy 127.747925 -23.394696) (xy 127.695141 -23.376689) (xy 127.645541 -23.351188)
			(xy 127.600183 -23.318737) (xy 127.560034 -23.280028) (xy 127.525948 -23.235885) (xy 127.498652 -23.18725)
			(xy 127.478729 -23.135159) (xy 127.466603 -23.080722) (xy 127.462532 -23.0251) (xy 91.47489 -23.0251)
			(xy 91.474543 -23.044096) (xy 91.466423 -23.099272) (xy 91.450355 -23.152679) (xy 91.426683 -23.203176)
			(xy 91.39591 -23.249689) (xy 91.358693 -23.291226) (xy 91.315825 -23.326901) (xy 91.268219 -23.355955)
			(xy 91.21689 -23.377767) (xy 91.162933 -23.391873) (xy 91.107496 -23.397973) (xy 91.051762 -23.395936)
			(xy 90.996919 -23.385806) (xy 90.944135 -23.367799) (xy 90.894535 -23.342298) (xy 90.849177 -23.309847)
			(xy 90.809028 -23.271138) (xy 90.774942 -23.226995) (xy 90.747646 -23.17836) (xy 90.727723 -23.126269)
			(xy 90.715597 -23.071832) (xy 90.711526 -23.01621) (xy 90.125642 -23.01621) (xy 90.125804 -23.0251)
			(xy 90.125295 -23.052986) (xy 90.117175 -23.108162) (xy 90.101107 -23.161569) (xy 90.077435 -23.212066)
			(xy 90.046662 -23.258579) (xy 90.009445 -23.300116) (xy 89.966577 -23.335791) (xy 89.918971 -23.364845)
			(xy 89.867642 -23.386657) (xy 89.813685 -23.400763) (xy 89.758248 -23.406863) (xy 89.702514 -23.404826)
			(xy 89.647671 -23.394696) (xy 89.594887 -23.376689) (xy 89.545287 -23.351188) (xy 89.499929 -23.318737)
			(xy 89.45978 -23.280028) (xy 89.425694 -23.235885) (xy 89.398398 -23.18725) (xy 89.378475 -23.135159)
			(xy 89.366349 -23.080722) (xy 89.362278 -23.0251) (xy 65.474942 -23.0251) (xy 65.474595 -23.044096)
			(xy 65.466475 -23.099272) (xy 65.450407 -23.152679) (xy 65.426735 -23.203176) (xy 65.395962 -23.249689)
			(xy 65.358745 -23.291226) (xy 65.315877 -23.326901) (xy 65.268271 -23.355955) (xy 65.216942 -23.377767)
			(xy 65.162985 -23.391873) (xy 65.107548 -23.397973) (xy 65.051814 -23.395936) (xy 64.996971 -23.385806)
			(xy 64.944187 -23.367799) (xy 64.894587 -23.342298) (xy 64.849229 -23.309847) (xy 64.80908 -23.271138)
			(xy 64.774994 -23.226995) (xy 64.747698 -23.17836) (xy 64.727775 -23.126269) (xy 64.715649 -23.071832)
			(xy 64.711578 -23.01621) (xy 64.125694 -23.01621) (xy 64.125856 -23.0251) (xy 64.125347 -23.052986)
			(xy 64.117227 -23.108162) (xy 64.101159 -23.161569) (xy 64.077487 -23.212066) (xy 64.046714 -23.258579)
			(xy 64.009497 -23.300116) (xy 63.966629 -23.335791) (xy 63.919023 -23.364845) (xy 63.867694 -23.386657)
			(xy 63.813737 -23.400763) (xy 63.7583 -23.406863) (xy 63.702566 -23.404826) (xy 63.647723 -23.394696)
			(xy 63.594939 -23.376689) (xy 63.545339 -23.351188) (xy 63.499981 -23.318737) (xy 63.459832 -23.280028)
			(xy 63.425746 -23.235885) (xy 63.39845 -23.18725) (xy 63.378527 -23.135159) (xy 63.366401 -23.080722)
			(xy 63.36233 -23.0251) (xy 39.474994 -23.0251) (xy 39.474647 -23.044096) (xy 39.466527 -23.099272)
			(xy 39.450459 -23.152679) (xy 39.426787 -23.203176) (xy 39.396014 -23.249689) (xy 39.358797 -23.291226)
			(xy 39.315929 -23.326901) (xy 39.268323 -23.355955) (xy 39.216994 -23.377767) (xy 39.163037 -23.391873)
			(xy 39.1076 -23.397973) (xy 39.051866 -23.395936) (xy 38.997023 -23.385806) (xy 38.944239 -23.367799)
			(xy 38.894639 -23.342298) (xy 38.849281 -23.309847) (xy 38.809132 -23.271138) (xy 38.775046 -23.226995)
			(xy 38.74775 -23.17836) (xy 38.727827 -23.126269) (xy 38.715701 -23.071832) (xy 38.71163 -23.01621)
			(xy 38.125746 -23.01621) (xy 38.125908 -23.0251) (xy 38.125399 -23.052986) (xy 38.117279 -23.108162)
			(xy 38.101211 -23.161569) (xy 38.077539 -23.212066) (xy 38.046766 -23.258579) (xy 38.009549 -23.300116)
			(xy 37.966681 -23.335791) (xy 37.919075 -23.364845) (xy 37.867746 -23.386657) (xy 37.813789 -23.400763)
			(xy 37.758352 -23.406863) (xy 37.702618 -23.404826) (xy 37.647775 -23.394696) (xy 37.594991 -23.376689)
			(xy 37.545391 -23.351188) (xy 37.500033 -23.318737) (xy 37.459884 -23.280028) (xy 37.425798 -23.235885)
			(xy 37.398502 -23.18725) (xy 37.378579 -23.135159) (xy 37.366453 -23.080722) (xy 37.362382 -23.0251)
			(xy 13.475046 -23.0251) (xy 13.474699 -23.044096) (xy 13.466579 -23.099272) (xy 13.450511 -23.152679)
			(xy 13.426839 -23.203176) (xy 13.396066 -23.249689) (xy 13.358849 -23.291226) (xy 13.315981 -23.326901)
			(xy 13.268375 -23.355955) (xy 13.217046 -23.377767) (xy 13.163089 -23.391873) (xy 13.107652 -23.397973)
			(xy 13.051918 -23.395936) (xy 12.997075 -23.385806) (xy 12.944291 -23.367799) (xy 12.894691 -23.342298)
			(xy 12.849333 -23.309847) (xy 12.809184 -23.271138) (xy 12.775098 -23.226995) (xy 12.747802 -23.17836)
			(xy 12.727879 -23.126269) (xy 12.715753 -23.071832) (xy 12.711682 -23.01621) (xy 12.061982 -23.01621)
			(xy 12.061951 -23.017934) (xy 12.053831 -23.07311) (xy 12.037763 -23.126517) (xy 12.014091 -23.177014)
			(xy 11.983318 -23.223527) (xy 11.946101 -23.265064) (xy 11.903233 -23.300739) (xy 11.855627 -23.329793)
			(xy 11.804298 -23.351605) (xy 11.750341 -23.365711) (xy 11.694904 -23.371811) (xy 11.63917 -23.369774)
			(xy 11.584327 -23.359644) (xy 11.531543 -23.341637) (xy 11.481943 -23.316136) (xy 11.436585 -23.283685)
			(xy 11.396436 -23.244976) (xy 11.36235 -23.200833) (xy 11.335054 -23.152198) (xy 11.315131 -23.100107)
			(xy 11.303005 -23.04567) (xy 11.298934 -22.990048) (xy 4.930743 -22.990048) (xy 4.928811 -22.996469)
			(xy 4.905139 -23.046966) (xy 4.874366 -23.093479) (xy 4.837149 -23.135016) (xy 4.794281 -23.170691)
			(xy 4.746675 -23.199745) (xy 4.695346 -23.221557) (xy 4.641389 -23.235663) (xy 4.585952 -23.241763)
			(xy 4.530218 -23.239726) (xy 4.475375 -23.229596) (xy 4.422591 -23.211589) (xy 4.372991 -23.186088)
			(xy 4.327633 -23.153637) (xy 4.287484 -23.114928) (xy 4.253398 -23.070785) (xy 4.226102 -23.02215)
			(xy 4.206179 -22.970059) (xy 4.194053 -22.915622) (xy 4.189982 -22.86) (xy 0.715772 -22.86) (xy 0.715772 -23.935944)
			(xy 2.23215 -23.935944) (xy 2.236221 -23.880322) (xy 2.248347 -23.825885) (xy 2.26827 -23.773794)
			(xy 2.295566 -23.725159) (xy 2.329652 -23.681016) (xy 2.369801 -23.642307) (xy 2.415159 -23.609856)
			(xy 2.464759 -23.584355) (xy 2.517543 -23.566348) (xy 2.572386 -23.556218) (xy 2.62812 -23.554181)
			(xy 2.683557 -23.560281) (xy 2.737514 -23.574387) (xy 2.788843 -23.596199) (xy 2.836449 -23.625253)
			(xy 2.879317 -23.660928) (xy 2.916534 -23.702465) (xy 2.947307 -23.748978) (xy 2.970979 -23.799475)
			(xy 2.987047 -23.852882) (xy 2.995167 -23.908058) (xy 2.995676 -23.935944) (xy 3.241038 -23.935944)
			(xy 3.245109 -23.880322) (xy 3.257235 -23.825885) (xy 3.277158 -23.773794) (xy 3.304454 -23.725159)
			(xy 3.33854 -23.681016) (xy 3.378689 -23.642307) (xy 3.424047 -23.609856) (xy 3.473647 -23.584355)
			(xy 3.526431 -23.566348) (xy 3.581274 -23.556218) (xy 3.637008 -23.554181) (xy 3.692445 -23.560281)
			(xy 3.746402 -23.574387) (xy 3.783134 -23.589996) (xy 16.084548 -23.589996) (xy 16.088619 -23.534374)
			(xy 16.100745 -23.479937) (xy 16.120668 -23.427846) (xy 16.147964 -23.379211) (xy 16.18205 -23.335068)
			(xy 16.222199 -23.296359) (xy 16.267557 -23.263908) (xy 16.317157 -23.238407) (xy 16.369941 -23.2204)
			(xy 16.424784 -23.21027) (xy 16.480518 -23.208233) (xy 16.535955 -23.214333) (xy 16.589912 -23.228439)
			(xy 16.641241 -23.250251) (xy 16.688847 -23.279305) (xy 16.731715 -23.31498) (xy 16.768932 -23.356517)
			(xy 16.799705 -23.40303) (xy 16.823377 -23.453527) (xy 16.839445 -23.506934) (xy 16.847565 -23.56211)
			(xy 16.848074 -23.589996) (xy 42.084496 -23.589996) (xy 42.088567 -23.534374) (xy 42.100693 -23.479937)
			(xy 42.120616 -23.427846) (xy 42.147912 -23.379211) (xy 42.181998 -23.335068) (xy 42.222147 -23.296359)
			(xy 42.267505 -23.263908) (xy 42.317105 -23.238407) (xy 42.369889 -23.2204) (xy 42.424732 -23.21027)
			(xy 42.480466 -23.208233) (xy 42.535903 -23.214333) (xy 42.58986 -23.228439) (xy 42.641189 -23.250251)
			(xy 42.688795 -23.279305) (xy 42.731663 -23.31498) (xy 42.76888 -23.356517) (xy 42.799653 -23.40303)
			(xy 42.823325 -23.453527) (xy 42.839393 -23.506934) (xy 42.847513 -23.56211) (xy 42.848022 -23.589996)
			(xy 42.847513 -23.617882) (xy 42.839393 -23.673058) (xy 42.823325 -23.726465) (xy 42.799653 -23.776962)
			(xy 42.76888 -23.823475) (xy 42.731663 -23.865012) (xy 42.688795 -23.900687) (xy 42.641189 -23.929741)
			(xy 42.58986 -23.951553) (xy 42.537835 -23.965154) (xy 52.077364 -23.965154) (xy 52.081435 -23.909532)
			(xy 52.093561 -23.855095) (xy 52.113484 -23.803004) (xy 52.14078 -23.754369) (xy 52.174866 -23.710226)
			(xy 52.215015 -23.671517) (xy 52.260373 -23.639066) (xy 52.309973 -23.613565) (xy 52.362757 -23.595558)
			(xy 52.4176 -23.585428) (xy 52.473334 -23.583391) (xy 52.528771 -23.589491) (xy 52.582728 -23.603597)
			(xy 52.634057 -23.625409) (xy 52.681663 -23.654463) (xy 52.724531 -23.690138) (xy 52.761748 -23.731675)
			(xy 52.792521 -23.778188) (xy 52.816193 -23.828685) (xy 52.832261 -23.882092) (xy 52.840381 -23.937268)
			(xy 52.840556 -23.946866) (xy 53.08041 -23.946866) (xy 53.084481 -23.891244) (xy 53.096607 -23.836807)
			(xy 53.11653 -23.784716) (xy 53.143826 -23.736081) (xy 53.177912 -23.691938) (xy 53.218061 -23.653229)
			(xy 53.263419 -23.620778) (xy 53.313019 -23.595277) (xy 53.365803 -23.57727) (xy 53.420646 -23.56714)
			(xy 53.47638 -23.565103) (xy 53.531817 -23.571203) (xy 53.585774 -23.585309) (xy 53.637103 -23.607121)
			(xy 53.684709 -23.636175) (xy 53.727577 -23.67185) (xy 53.764794 -23.713387) (xy 53.795567 -23.7599)
			(xy 53.819239 -23.810397) (xy 53.835307 -23.863804) (xy 53.843427 -23.91898) (xy 53.843936 -23.946866)
			(xy 53.843496 -23.970996) (xy 54.072788 -23.970996) (xy 54.076859 -23.915374) (xy 54.088985 -23.860937)
			(xy 54.108908 -23.808846) (xy 54.136204 -23.760211) (xy 54.17029 -23.716068) (xy 54.210439 -23.677359)
			(xy 54.255797 -23.644908) (xy 54.305397 -23.619407) (xy 54.358181 -23.6014) (xy 54.413024 -23.59127)
			(xy 54.468758 -23.589233) (xy 54.475692 -23.589996) (xy 68.084444 -23.589996) (xy 68.088515 -23.534374)
			(xy 68.100641 -23.479937) (xy 68.120564 -23.427846) (xy 68.14786 -23.379211) (xy 68.181946 -23.335068)
			(xy 68.222095 -23.296359) (xy 68.267453 -23.263908) (xy 68.317053 -23.238407) (xy 68.369837 -23.2204)
			(xy 68.42468 -23.21027) (xy 68.480414 -23.208233) (xy 68.535851 -23.214333) (xy 68.589808 -23.228439)
			(xy 68.641137 -23.250251) (xy 68.688743 -23.279305) (xy 68.731611 -23.31498) (xy 68.768828 -23.356517)
			(xy 68.799601 -23.40303) (xy 68.823273 -23.453527) (xy 68.839341 -23.506934) (xy 68.847461 -23.56211)
			(xy 68.84797 -23.589996) (xy 68.847461 -23.617882) (xy 68.839341 -23.673058) (xy 68.823273 -23.726465)
			(xy 68.799601 -23.776962) (xy 68.768828 -23.823475) (xy 68.731611 -23.865012) (xy 68.688743 -23.900687)
			(xy 68.641137 -23.929741) (xy 68.589808 -23.951553) (xy 68.537783 -23.965154) (xy 78.077312 -23.965154)
			(xy 78.081383 -23.909532) (xy 78.093509 -23.855095) (xy 78.113432 -23.803004) (xy 78.140728 -23.754369)
			(xy 78.174814 -23.710226) (xy 78.214963 -23.671517) (xy 78.260321 -23.639066) (xy 78.309921 -23.613565)
			(xy 78.362705 -23.595558) (xy 78.417548 -23.585428) (xy 78.473282 -23.583391) (xy 78.528719 -23.589491)
			(xy 78.582676 -23.603597) (xy 78.634005 -23.625409) (xy 78.681611 -23.654463) (xy 78.724479 -23.690138)
			(xy 78.761696 -23.731675) (xy 78.792469 -23.778188) (xy 78.816141 -23.828685) (xy 78.832209 -23.882092)
			(xy 78.840329 -23.937268) (xy 78.840504 -23.946866) (xy 79.080358 -23.946866) (xy 79.084429 -23.891244)
			(xy 79.096555 -23.836807) (xy 79.116478 -23.784716) (xy 79.143774 -23.736081) (xy 79.17786 -23.691938)
			(xy 79.218009 -23.653229) (xy 79.263367 -23.620778) (xy 79.312967 -23.595277) (xy 79.365751 -23.57727)
			(xy 79.420594 -23.56714) (xy 79.476328 -23.565103) (xy 79.531765 -23.571203) (xy 79.585722 -23.585309)
			(xy 79.637051 -23.607121) (xy 79.684657 -23.636175) (xy 79.727525 -23.67185) (xy 79.764742 -23.713387)
			(xy 79.795515 -23.7599) (xy 79.819187 -23.810397) (xy 79.835255 -23.863804) (xy 79.843375 -23.91898)
			(xy 79.843884 -23.946866) (xy 79.843444 -23.970996) (xy 80.072736 -23.970996) (xy 80.076807 -23.915374)
			(xy 80.088933 -23.860937) (xy 80.108856 -23.808846) (xy 80.136152 -23.760211) (xy 80.170238 -23.716068)
			(xy 80.210387 -23.677359) (xy 80.255745 -23.644908) (xy 80.305345 -23.619407) (xy 80.358129 -23.6014)
			(xy 80.412972 -23.59127) (xy 80.468706 -23.589233) (xy 80.47564 -23.589996) (xy 94.084392 -23.589996)
			(xy 94.088463 -23.534374) (xy 94.100589 -23.479937) (xy 94.120512 -23.427846) (xy 94.147808 -23.379211)
			(xy 94.181894 -23.335068) (xy 94.222043 -23.296359) (xy 94.267401 -23.263908) (xy 94.317001 -23.238407)
			(xy 94.369785 -23.2204) (xy 94.424628 -23.21027) (xy 94.480362 -23.208233) (xy 94.535799 -23.214333)
			(xy 94.589756 -23.228439) (xy 94.641085 -23.250251) (xy 94.688691 -23.279305) (xy 94.731559 -23.31498)
			(xy 94.768776 -23.356517) (xy 94.799549 -23.40303) (xy 94.823221 -23.453527) (xy 94.839289 -23.506934)
			(xy 94.847409 -23.56211) (xy 94.847918 -23.589996) (xy 132.184646 -23.589996) (xy 132.188717 -23.534374)
			(xy 132.200843 -23.479937) (xy 132.220766 -23.427846) (xy 132.248062 -23.379211) (xy 132.282148 -23.335068)
			(xy 132.322297 -23.296359) (xy 132.367655 -23.263908) (xy 132.417255 -23.238407) (xy 132.470039 -23.2204)
			(xy 132.524882 -23.21027) (xy 132.580616 -23.208233) (xy 132.636053 -23.214333) (xy 132.69001 -23.228439)
			(xy 132.741339 -23.250251) (xy 132.788945 -23.279305) (xy 132.831813 -23.31498) (xy 132.86903 -23.356517)
			(xy 132.899803 -23.40303) (xy 132.923475 -23.453527) (xy 132.939543 -23.506934) (xy 132.947663 -23.56211)
			(xy 132.948172 -23.589996) (xy 132.947663 -23.617882) (xy 132.939543 -23.673058) (xy 132.923475 -23.726465)
			(xy 132.899803 -23.776962) (xy 132.86903 -23.823475) (xy 132.831813 -23.865012) (xy 132.788945 -23.900687)
			(xy 132.741339 -23.929741) (xy 132.69001 -23.951553) (xy 132.637985 -23.965154) (xy 142.177514 -23.965154)
			(xy 142.181585 -23.909532) (xy 142.193711 -23.855095) (xy 142.213634 -23.803004) (xy 142.24093 -23.754369)
			(xy 142.275016 -23.710226) (xy 142.315165 -23.671517) (xy 142.360523 -23.639066) (xy 142.410123 -23.613565)
			(xy 142.462907 -23.595558) (xy 142.51775 -23.585428) (xy 142.573484 -23.583391) (xy 142.628921 -23.589491)
			(xy 142.682878 -23.603597) (xy 142.734207 -23.625409) (xy 142.781813 -23.654463) (xy 142.824681 -23.690138)
			(xy 142.861898 -23.731675) (xy 142.892671 -23.778188) (xy 142.916343 -23.828685) (xy 142.932411 -23.882092)
			(xy 142.940531 -23.937268) (xy 142.940706 -23.946866) (xy 143.18056 -23.946866) (xy 143.184631 -23.891244)
			(xy 143.196757 -23.836807) (xy 143.21668 -23.784716) (xy 143.243976 -23.736081) (xy 143.278062 -23.691938)
			(xy 143.318211 -23.653229) (xy 143.363569 -23.620778) (xy 143.413169 -23.595277) (xy 143.465953 -23.57727)
			(xy 143.520796 -23.56714) (xy 143.57653 -23.565103) (xy 143.631967 -23.571203) (xy 143.685924 -23.585309)
			(xy 143.737253 -23.607121) (xy 143.784859 -23.636175) (xy 143.827727 -23.67185) (xy 143.864944 -23.713387)
			(xy 143.895717 -23.7599) (xy 143.919389 -23.810397) (xy 143.935457 -23.863804) (xy 143.943577 -23.91898)
			(xy 143.944086 -23.946866) (xy 143.943646 -23.970996) (xy 144.172938 -23.970996) (xy 144.177009 -23.915374)
			(xy 144.189135 -23.860937) (xy 144.209058 -23.808846) (xy 144.236354 -23.760211) (xy 144.27044 -23.716068)
			(xy 144.310589 -23.677359) (xy 144.355947 -23.644908) (xy 144.405547 -23.619407) (xy 144.458331 -23.6014)
			(xy 144.513174 -23.59127) (xy 144.568908 -23.589233) (xy 144.575842 -23.589996) (xy 158.184594 -23.589996)
			(xy 158.188665 -23.534374) (xy 158.200791 -23.479937) (xy 158.220714 -23.427846) (xy 158.24801 -23.379211)
			(xy 158.282096 -23.335068) (xy 158.322245 -23.296359) (xy 158.367603 -23.263908) (xy 158.417203 -23.238407)
			(xy 158.469987 -23.2204) (xy 158.52483 -23.21027) (xy 158.580564 -23.208233) (xy 158.636001 -23.214333)
			(xy 158.689958 -23.228439) (xy 158.741287 -23.250251) (xy 158.788893 -23.279305) (xy 158.831761 -23.31498)
			(xy 158.868978 -23.356517) (xy 158.899751 -23.40303) (xy 158.923423 -23.453527) (xy 158.939491 -23.506934)
			(xy 158.947611 -23.56211) (xy 158.94812 -23.589996) (xy 158.947611 -23.617882) (xy 158.939491 -23.673058)
			(xy 158.923423 -23.726465) (xy 158.899751 -23.776962) (xy 158.868978 -23.823475) (xy 158.831761 -23.865012)
			(xy 158.788893 -23.900687) (xy 158.741287 -23.929741) (xy 158.689958 -23.951553) (xy 158.637933 -23.965154)
			(xy 168.177462 -23.965154) (xy 168.181533 -23.909532) (xy 168.193659 -23.855095) (xy 168.213582 -23.803004)
			(xy 168.240878 -23.754369) (xy 168.274964 -23.710226) (xy 168.315113 -23.671517) (xy 168.360471 -23.639066)
			(xy 168.410071 -23.613565) (xy 168.462855 -23.595558) (xy 168.517698 -23.585428) (xy 168.573432 -23.583391)
			(xy 168.628869 -23.589491) (xy 168.682826 -23.603597) (xy 168.734155 -23.625409) (xy 168.781761 -23.654463)
			(xy 168.824629 -23.690138) (xy 168.861846 -23.731675) (xy 168.892619 -23.778188) (xy 168.916291 -23.828685)
			(xy 168.932359 -23.882092) (xy 168.940479 -23.937268) (xy 168.940654 -23.946866) (xy 169.180508 -23.946866)
			(xy 169.184579 -23.891244) (xy 169.196705 -23.836807) (xy 169.216628 -23.784716) (xy 169.243924 -23.736081)
			(xy 169.27801 -23.691938) (xy 169.318159 -23.653229) (xy 169.363517 -23.620778) (xy 169.413117 -23.595277)
			(xy 169.465901 -23.57727) (xy 169.520744 -23.56714) (xy 169.576478 -23.565103) (xy 169.631915 -23.571203)
			(xy 169.685872 -23.585309) (xy 169.737201 -23.607121) (xy 169.784807 -23.636175) (xy 169.827675 -23.67185)
			(xy 169.864892 -23.713387) (xy 169.895665 -23.7599) (xy 169.919337 -23.810397) (xy 169.935405 -23.863804)
			(xy 169.943525 -23.91898) (xy 169.944034 -23.946866) (xy 169.943594 -23.970996) (xy 170.172886 -23.970996)
			(xy 170.176957 -23.915374) (xy 170.189083 -23.860937) (xy 170.209006 -23.808846) (xy 170.236302 -23.760211)
			(xy 170.270388 -23.716068) (xy 170.310537 -23.677359) (xy 170.355895 -23.644908) (xy 170.405495 -23.619407)
			(xy 170.458279 -23.6014) (xy 170.513122 -23.59127) (xy 170.568856 -23.589233) (xy 170.57579 -23.589996)
			(xy 184.184542 -23.589996) (xy 184.188613 -23.534374) (xy 184.200739 -23.479937) (xy 184.220662 -23.427846)
			(xy 184.247958 -23.379211) (xy 184.282044 -23.335068) (xy 184.322193 -23.296359) (xy 184.367551 -23.263908)
			(xy 184.417151 -23.238407) (xy 184.469935 -23.2204) (xy 184.524778 -23.21027) (xy 184.580512 -23.208233)
			(xy 184.635949 -23.214333) (xy 184.689906 -23.228439) (xy 184.741235 -23.250251) (xy 184.788841 -23.279305)
			(xy 184.831709 -23.31498) (xy 184.868926 -23.356517) (xy 184.899699 -23.40303) (xy 184.923371 -23.453527)
			(xy 184.939439 -23.506934) (xy 184.947559 -23.56211) (xy 184.948068 -23.589996) (xy 184.947559 -23.617882)
			(xy 184.939439 -23.673058) (xy 184.923371 -23.726465) (xy 184.899699 -23.776962) (xy 184.868926 -23.823475)
			(xy 184.831709 -23.865012) (xy 184.788841 -23.900687) (xy 184.741235 -23.929741) (xy 184.689906 -23.951553)
			(xy 184.637881 -23.965154) (xy 194.17741 -23.965154) (xy 194.181481 -23.909532) (xy 194.193607 -23.855095)
			(xy 194.21353 -23.803004) (xy 194.240826 -23.754369) (xy 194.274912 -23.710226) (xy 194.315061 -23.671517)
			(xy 194.360419 -23.639066) (xy 194.410019 -23.613565) (xy 194.462803 -23.595558) (xy 194.517646 -23.585428)
			(xy 194.57338 -23.583391) (xy 194.628817 -23.589491) (xy 194.682774 -23.603597) (xy 194.734103 -23.625409)
			(xy 194.781709 -23.654463) (xy 194.824577 -23.690138) (xy 194.861794 -23.731675) (xy 194.892567 -23.778188)
			(xy 194.916239 -23.828685) (xy 194.932307 -23.882092) (xy 194.940427 -23.937268) (xy 194.940602 -23.946866)
			(xy 195.180456 -23.946866) (xy 195.184527 -23.891244) (xy 195.196653 -23.836807) (xy 195.216576 -23.784716)
			(xy 195.243872 -23.736081) (xy 195.277958 -23.691938) (xy 195.318107 -23.653229) (xy 195.363465 -23.620778)
			(xy 195.413065 -23.595277) (xy 195.465849 -23.57727) (xy 195.520692 -23.56714) (xy 195.576426 -23.565103)
			(xy 195.631863 -23.571203) (xy 195.68582 -23.585309) (xy 195.737149 -23.607121) (xy 195.784755 -23.636175)
			(xy 195.827623 -23.67185) (xy 195.86484 -23.713387) (xy 195.895613 -23.7599) (xy 195.919285 -23.810397)
			(xy 195.935353 -23.863804) (xy 195.943473 -23.91898) (xy 195.943982 -23.946866) (xy 195.943542 -23.970996)
			(xy 196.172834 -23.970996) (xy 196.176905 -23.915374) (xy 196.189031 -23.860937) (xy 196.208954 -23.808846)
			(xy 196.23625 -23.760211) (xy 196.270336 -23.716068) (xy 196.310485 -23.677359) (xy 196.355843 -23.644908)
			(xy 196.405443 -23.619407) (xy 196.458227 -23.6014) (xy 196.51307 -23.59127) (xy 196.568804 -23.589233)
			(xy 196.575738 -23.589996) (xy 210.18449 -23.589996) (xy 210.188561 -23.534374) (xy 210.200687 -23.479937)
			(xy 210.22061 -23.427846) (xy 210.247906 -23.379211) (xy 210.281992 -23.335068) (xy 210.322141 -23.296359)
			(xy 210.367499 -23.263908) (xy 210.417099 -23.238407) (xy 210.469883 -23.2204) (xy 210.524726 -23.21027)
			(xy 210.58046 -23.208233) (xy 210.635897 -23.214333) (xy 210.689854 -23.228439) (xy 210.741183 -23.250251)
			(xy 210.788789 -23.279305) (xy 210.831657 -23.31498) (xy 210.868874 -23.356517) (xy 210.899647 -23.40303)
			(xy 210.923319 -23.453527) (xy 210.939387 -23.506934) (xy 210.947507 -23.56211) (xy 210.948016 -23.589996)
			(xy 210.947507 -23.617882) (xy 210.939387 -23.673058) (xy 210.923319 -23.726465) (xy 210.899647 -23.776962)
			(xy 210.868874 -23.823475) (xy 210.831657 -23.865012) (xy 210.788789 -23.900687) (xy 210.741183 -23.929741)
			(xy 210.689854 -23.951553) (xy 210.637829 -23.965154) (xy 220.177358 -23.965154) (xy 220.181429 -23.909532)
			(xy 220.193555 -23.855095) (xy 220.213478 -23.803004) (xy 220.240774 -23.754369) (xy 220.27486 -23.710226)
			(xy 220.315009 -23.671517) (xy 220.360367 -23.639066) (xy 220.409967 -23.613565) (xy 220.462751 -23.595558)
			(xy 220.517594 -23.585428) (xy 220.573328 -23.583391) (xy 220.628765 -23.589491) (xy 220.682722 -23.603597)
			(xy 220.734051 -23.625409) (xy 220.781657 -23.654463) (xy 220.824525 -23.690138) (xy 220.861742 -23.731675)
			(xy 220.892515 -23.778188) (xy 220.916187 -23.828685) (xy 220.932255 -23.882092) (xy 220.940375 -23.937268)
			(xy 220.94055 -23.946866) (xy 221.180404 -23.946866) (xy 221.184475 -23.891244) (xy 221.196601 -23.836807)
			(xy 221.216524 -23.784716) (xy 221.24382 -23.736081) (xy 221.277906 -23.691938) (xy 221.318055 -23.653229)
			(xy 221.363413 -23.620778) (xy 221.413013 -23.595277) (xy 221.465797 -23.57727) (xy 221.52064 -23.56714)
			(xy 221.576374 -23.565103) (xy 221.631811 -23.571203) (xy 221.685768 -23.585309) (xy 221.737097 -23.607121)
			(xy 221.784703 -23.636175) (xy 221.827571 -23.67185) (xy 221.864788 -23.713387) (xy 221.895561 -23.7599)
			(xy 221.919233 -23.810397) (xy 221.935301 -23.863804) (xy 221.943421 -23.91898) (xy 221.94393 -23.946866)
			(xy 221.94349 -23.970996) (xy 222.172782 -23.970996) (xy 222.176853 -23.915374) (xy 222.188979 -23.860937)
			(xy 222.208902 -23.808846) (xy 222.236198 -23.760211) (xy 222.270284 -23.716068) (xy 222.310433 -23.677359)
			(xy 222.355791 -23.644908) (xy 222.405391 -23.619407) (xy 222.458175 -23.6014) (xy 222.513018 -23.59127)
			(xy 222.568752 -23.589233) (xy 222.575686 -23.589996) (xy 248.28449 -23.589996) (xy 248.288561 -23.534374)
			(xy 248.300687 -23.479937) (xy 248.32061 -23.427846) (xy 248.347906 -23.379211) (xy 248.381992 -23.335068)
			(xy 248.422141 -23.296359) (xy 248.467499 -23.263908) (xy 248.517099 -23.238407) (xy 248.569883 -23.2204)
			(xy 248.624726 -23.21027) (xy 248.68046 -23.208233) (xy 248.735897 -23.214333) (xy 248.789854 -23.228439)
			(xy 248.841183 -23.250251) (xy 248.888789 -23.279305) (xy 248.931657 -23.31498) (xy 248.968874 -23.356517)
			(xy 248.999647 -23.40303) (xy 249.023319 -23.453527) (xy 249.039387 -23.506934) (xy 249.047507 -23.56211)
			(xy 249.048016 -23.589996) (xy 249.047507 -23.617882) (xy 249.039387 -23.673058) (xy 249.023319 -23.726465)
			(xy 248.999647 -23.776962) (xy 248.968874 -23.823475) (xy 248.931657 -23.865012) (xy 248.888789 -23.900687)
			(xy 248.841183 -23.929741) (xy 248.789854 -23.951553) (xy 248.737829 -23.965154) (xy 258.277358 -23.965154)
			(xy 258.281429 -23.909532) (xy 258.293555 -23.855095) (xy 258.313478 -23.803004) (xy 258.340774 -23.754369)
			(xy 258.37486 -23.710226) (xy 258.415009 -23.671517) (xy 258.460367 -23.639066) (xy 258.509967 -23.613565)
			(xy 258.562751 -23.595558) (xy 258.617594 -23.585428) (xy 258.673328 -23.583391) (xy 258.728765 -23.589491)
			(xy 258.782722 -23.603597) (xy 258.834051 -23.625409) (xy 258.881657 -23.654463) (xy 258.924525 -23.690138)
			(xy 258.961742 -23.731675) (xy 258.992515 -23.778188) (xy 259.016187 -23.828685) (xy 259.032255 -23.882092)
			(xy 259.040375 -23.937268) (xy 259.04055 -23.946866) (xy 259.280404 -23.946866) (xy 259.284475 -23.891244)
			(xy 259.296601 -23.836807) (xy 259.316524 -23.784716) (xy 259.34382 -23.736081) (xy 259.377906 -23.691938)
			(xy 259.418055 -23.653229) (xy 259.463413 -23.620778) (xy 259.513013 -23.595277) (xy 259.565797 -23.57727)
			(xy 259.62064 -23.56714) (xy 259.676374 -23.565103) (xy 259.731811 -23.571203) (xy 259.785768 -23.585309)
			(xy 259.837097 -23.607121) (xy 259.884703 -23.636175) (xy 259.927571 -23.67185) (xy 259.964788 -23.713387)
			(xy 259.995561 -23.7599) (xy 260.019233 -23.810397) (xy 260.035301 -23.863804) (xy 260.043421 -23.91898)
			(xy 260.04393 -23.946866) (xy 260.04349 -23.970996) (xy 260.272782 -23.970996) (xy 260.276853 -23.915374)
			(xy 260.288979 -23.860937) (xy 260.308902 -23.808846) (xy 260.336198 -23.760211) (xy 260.370284 -23.716068)
			(xy 260.410433 -23.677359) (xy 260.455791 -23.644908) (xy 260.505391 -23.619407) (xy 260.558175 -23.6014)
			(xy 260.613018 -23.59127) (xy 260.668752 -23.589233) (xy 260.675686 -23.589996) (xy 274.284438 -23.589996)
			(xy 274.288509 -23.534374) (xy 274.300635 -23.479937) (xy 274.320558 -23.427846) (xy 274.347854 -23.379211)
			(xy 274.38194 -23.335068) (xy 274.422089 -23.296359) (xy 274.467447 -23.263908) (xy 274.517047 -23.238407)
			(xy 274.569831 -23.2204) (xy 274.624674 -23.21027) (xy 274.680408 -23.208233) (xy 274.735845 -23.214333)
			(xy 274.789802 -23.228439) (xy 274.841131 -23.250251) (xy 274.888737 -23.279305) (xy 274.931605 -23.31498)
			(xy 274.968822 -23.356517) (xy 274.999595 -23.40303) (xy 275.023267 -23.453527) (xy 275.039335 -23.506934)
			(xy 275.047455 -23.56211) (xy 275.047964 -23.589996) (xy 275.047455 -23.617882) (xy 275.039335 -23.673058)
			(xy 275.023267 -23.726465) (xy 274.999595 -23.776962) (xy 274.968822 -23.823475) (xy 274.931605 -23.865012)
			(xy 274.888737 -23.900687) (xy 274.841131 -23.929741) (xy 274.789802 -23.951553) (xy 274.737777 -23.965154)
			(xy 284.277306 -23.965154) (xy 284.281377 -23.909532) (xy 284.293503 -23.855095) (xy 284.313426 -23.803004)
			(xy 284.340722 -23.754369) (xy 284.374808 -23.710226) (xy 284.414957 -23.671517) (xy 284.460315 -23.639066)
			(xy 284.509915 -23.613565) (xy 284.562699 -23.595558) (xy 284.617542 -23.585428) (xy 284.673276 -23.583391)
			(xy 284.728713 -23.589491) (xy 284.78267 -23.603597) (xy 284.833999 -23.625409) (xy 284.881605 -23.654463)
			(xy 284.924473 -23.690138) (xy 284.96169 -23.731675) (xy 284.992463 -23.778188) (xy 285.016135 -23.828685)
			(xy 285.032203 -23.882092) (xy 285.040323 -23.937268) (xy 285.040498 -23.946866) (xy 285.280352 -23.946866)
			(xy 285.284423 -23.891244) (xy 285.296549 -23.836807) (xy 285.316472 -23.784716) (xy 285.343768 -23.736081)
			(xy 285.377854 -23.691938) (xy 285.418003 -23.653229) (xy 285.463361 -23.620778) (xy 285.512961 -23.595277)
			(xy 285.565745 -23.57727) (xy 285.620588 -23.56714) (xy 285.676322 -23.565103) (xy 285.731759 -23.571203)
			(xy 285.785716 -23.585309) (xy 285.837045 -23.607121) (xy 285.884651 -23.636175) (xy 285.927519 -23.67185)
			(xy 285.964736 -23.713387) (xy 285.995509 -23.7599) (xy 286.019181 -23.810397) (xy 286.035249 -23.863804)
			(xy 286.043369 -23.91898) (xy 286.043878 -23.946866) (xy 286.043438 -23.970996) (xy 286.27273 -23.970996)
			(xy 286.276801 -23.915374) (xy 286.288927 -23.860937) (xy 286.30885 -23.808846) (xy 286.336146 -23.760211)
			(xy 286.370232 -23.716068) (xy 286.410381 -23.677359) (xy 286.455739 -23.644908) (xy 286.505339 -23.619407)
			(xy 286.558123 -23.6014) (xy 286.612966 -23.59127) (xy 286.6687 -23.589233) (xy 286.675634 -23.589996)
			(xy 300.284386 -23.589996) (xy 300.288457 -23.534374) (xy 300.300583 -23.479937) (xy 300.320506 -23.427846)
			(xy 300.347802 -23.379211) (xy 300.381888 -23.335068) (xy 300.422037 -23.296359) (xy 300.467395 -23.263908)
			(xy 300.516995 -23.238407) (xy 300.569779 -23.2204) (xy 300.624622 -23.21027) (xy 300.680356 -23.208233)
			(xy 300.735793 -23.214333) (xy 300.78975 -23.228439) (xy 300.841079 -23.250251) (xy 300.888685 -23.279305)
			(xy 300.931553 -23.31498) (xy 300.96877 -23.356517) (xy 300.999543 -23.40303) (xy 301.023215 -23.453527)
			(xy 301.039283 -23.506934) (xy 301.047403 -23.56211) (xy 301.047912 -23.589996) (xy 301.047403 -23.617882)
			(xy 301.039283 -23.673058) (xy 301.023215 -23.726465) (xy 300.999543 -23.776962) (xy 300.96877 -23.823475)
			(xy 300.931553 -23.865012) (xy 300.888685 -23.900687) (xy 300.841079 -23.929741) (xy 300.78975 -23.951553)
			(xy 300.737725 -23.965154) (xy 310.277254 -23.965154) (xy 310.281325 -23.909532) (xy 310.293451 -23.855095)
			(xy 310.313374 -23.803004) (xy 310.34067 -23.754369) (xy 310.374756 -23.710226) (xy 310.414905 -23.671517)
			(xy 310.460263 -23.639066) (xy 310.509863 -23.613565) (xy 310.562647 -23.595558) (xy 310.61749 -23.585428)
			(xy 310.673224 -23.583391) (xy 310.728661 -23.589491) (xy 310.782618 -23.603597) (xy 310.833947 -23.625409)
			(xy 310.881553 -23.654463) (xy 310.924421 -23.690138) (xy 310.961638 -23.731675) (xy 310.992411 -23.778188)
			(xy 311.016083 -23.828685) (xy 311.032151 -23.882092) (xy 311.040271 -23.937268) (xy 311.040446 -23.946866)
			(xy 311.2803 -23.946866) (xy 311.284371 -23.891244) (xy 311.296497 -23.836807) (xy 311.31642 -23.784716)
			(xy 311.343716 -23.736081) (xy 311.377802 -23.691938) (xy 311.417951 -23.653229) (xy 311.463309 -23.620778)
			(xy 311.512909 -23.595277) (xy 311.565693 -23.57727) (xy 311.620536 -23.56714) (xy 311.67627 -23.565103)
			(xy 311.731707 -23.571203) (xy 311.785664 -23.585309) (xy 311.836993 -23.607121) (xy 311.884599 -23.636175)
			(xy 311.927467 -23.67185) (xy 311.964684 -23.713387) (xy 311.995457 -23.7599) (xy 312.019129 -23.810397)
			(xy 312.035197 -23.863804) (xy 312.043317 -23.91898) (xy 312.043826 -23.946866) (xy 312.043386 -23.970996)
			(xy 312.272678 -23.970996) (xy 312.276749 -23.915374) (xy 312.288875 -23.860937) (xy 312.308798 -23.808846)
			(xy 312.336094 -23.760211) (xy 312.37018 -23.716068) (xy 312.410329 -23.677359) (xy 312.455687 -23.644908)
			(xy 312.505287 -23.619407) (xy 312.558071 -23.6014) (xy 312.612914 -23.59127) (xy 312.668648 -23.589233)
			(xy 312.675582 -23.589996) (xy 326.284334 -23.589996) (xy 326.288405 -23.534374) (xy 326.300531 -23.479937)
			(xy 326.320454 -23.427846) (xy 326.34775 -23.379211) (xy 326.381836 -23.335068) (xy 326.421985 -23.296359)
			(xy 326.467343 -23.263908) (xy 326.516943 -23.238407) (xy 326.569727 -23.2204) (xy 326.62457 -23.21027)
			(xy 326.680304 -23.208233) (xy 326.735741 -23.214333) (xy 326.789698 -23.228439) (xy 326.841027 -23.250251)
			(xy 326.888633 -23.279305) (xy 326.931501 -23.31498) (xy 326.968718 -23.356517) (xy 326.999491 -23.40303)
			(xy 327.023163 -23.453527) (xy 327.039231 -23.506934) (xy 327.047351 -23.56211) (xy 327.04786 -23.589996)
			(xy 364.384588 -23.589996) (xy 364.388659 -23.534374) (xy 364.400785 -23.479937) (xy 364.420708 -23.427846)
			(xy 364.448004 -23.379211) (xy 364.48209 -23.335068) (xy 364.522239 -23.296359) (xy 364.567597 -23.263908)
			(xy 364.617197 -23.238407) (xy 364.669981 -23.2204) (xy 364.724824 -23.21027) (xy 364.780558 -23.208233)
			(xy 364.835995 -23.214333) (xy 364.889952 -23.228439) (xy 364.941281 -23.250251) (xy 364.988887 -23.279305)
			(xy 365.031755 -23.31498) (xy 365.068972 -23.356517) (xy 365.099745 -23.40303) (xy 365.123417 -23.453527)
			(xy 365.139485 -23.506934) (xy 365.147605 -23.56211) (xy 365.148114 -23.589996) (xy 365.147605 -23.617882)
			(xy 365.139485 -23.673058) (xy 365.123417 -23.726465) (xy 365.099745 -23.776962) (xy 365.068972 -23.823475)
			(xy 365.031755 -23.865012) (xy 364.988887 -23.900687) (xy 364.941281 -23.929741) (xy 364.889952 -23.951553)
			(xy 364.837927 -23.965154) (xy 374.377456 -23.965154) (xy 374.381527 -23.909532) (xy 374.393653 -23.855095)
			(xy 374.413576 -23.803004) (xy 374.440872 -23.754369) (xy 374.474958 -23.710226) (xy 374.515107 -23.671517)
			(xy 374.560465 -23.639066) (xy 374.610065 -23.613565) (xy 374.662849 -23.595558) (xy 374.717692 -23.585428)
			(xy 374.773426 -23.583391) (xy 374.828863 -23.589491) (xy 374.88282 -23.603597) (xy 374.934149 -23.625409)
			(xy 374.981755 -23.654463) (xy 375.024623 -23.690138) (xy 375.06184 -23.731675) (xy 375.092613 -23.778188)
			(xy 375.116285 -23.828685) (xy 375.132353 -23.882092) (xy 375.140473 -23.937268) (xy 375.140648 -23.946866)
			(xy 375.380502 -23.946866) (xy 375.384573 -23.891244) (xy 375.396699 -23.836807) (xy 375.416622 -23.784716)
			(xy 375.443918 -23.736081) (xy 375.478004 -23.691938) (xy 375.518153 -23.653229) (xy 375.563511 -23.620778)
			(xy 375.613111 -23.595277) (xy 375.665895 -23.57727) (xy 375.720738 -23.56714) (xy 375.776472 -23.565103)
			(xy 375.831909 -23.571203) (xy 375.885866 -23.585309) (xy 375.937195 -23.607121) (xy 375.984801 -23.636175)
			(xy 376.027669 -23.67185) (xy 376.064886 -23.713387) (xy 376.095659 -23.7599) (xy 376.119331 -23.810397)
			(xy 376.135399 -23.863804) (xy 376.143519 -23.91898) (xy 376.144028 -23.946866) (xy 376.143588 -23.970996)
			(xy 376.37288 -23.970996) (xy 376.376951 -23.915374) (xy 376.389077 -23.860937) (xy 376.409 -23.808846)
			(xy 376.436296 -23.760211) (xy 376.470382 -23.716068) (xy 376.510531 -23.677359) (xy 376.555889 -23.644908)
			(xy 376.605489 -23.619407) (xy 376.658273 -23.6014) (xy 376.713116 -23.59127) (xy 376.76885 -23.589233)
			(xy 376.775784 -23.589996) (xy 390.384536 -23.589996) (xy 390.388607 -23.534374) (xy 390.400733 -23.479937)
			(xy 390.420656 -23.427846) (xy 390.447952 -23.379211) (xy 390.482038 -23.335068) (xy 390.522187 -23.296359)
			(xy 390.567545 -23.263908) (xy 390.617145 -23.238407) (xy 390.669929 -23.2204) (xy 390.724772 -23.21027)
			(xy 390.780506 -23.208233) (xy 390.835943 -23.214333) (xy 390.8899 -23.228439) (xy 390.941229 -23.250251)
			(xy 390.988835 -23.279305) (xy 391.031703 -23.31498) (xy 391.06892 -23.356517) (xy 391.099693 -23.40303)
			(xy 391.123365 -23.453527) (xy 391.139433 -23.506934) (xy 391.147553 -23.56211) (xy 391.148062 -23.589996)
			(xy 391.147553 -23.617882) (xy 391.139433 -23.673058) (xy 391.123365 -23.726465) (xy 391.099693 -23.776962)
			(xy 391.06892 -23.823475) (xy 391.031703 -23.865012) (xy 390.988835 -23.900687) (xy 390.941229 -23.929741)
			(xy 390.8899 -23.951553) (xy 390.837875 -23.965154) (xy 400.377404 -23.965154) (xy 400.381475 -23.909532)
			(xy 400.393601 -23.855095) (xy 400.413524 -23.803004) (xy 400.44082 -23.754369) (xy 400.474906 -23.710226)
			(xy 400.515055 -23.671517) (xy 400.560413 -23.639066) (xy 400.610013 -23.613565) (xy 400.662797 -23.595558)
			(xy 400.71764 -23.585428) (xy 400.773374 -23.583391) (xy 400.828811 -23.589491) (xy 400.882768 -23.603597)
			(xy 400.934097 -23.625409) (xy 400.981703 -23.654463) (xy 401.024571 -23.690138) (xy 401.061788 -23.731675)
			(xy 401.092561 -23.778188) (xy 401.116233 -23.828685) (xy 401.132301 -23.882092) (xy 401.140421 -23.937268)
			(xy 401.140596 -23.946866) (xy 401.38045 -23.946866) (xy 401.384521 -23.891244) (xy 401.396647 -23.836807)
			(xy 401.41657 -23.784716) (xy 401.443866 -23.736081) (xy 401.477952 -23.691938) (xy 401.518101 -23.653229)
			(xy 401.563459 -23.620778) (xy 401.613059 -23.595277) (xy 401.665843 -23.57727) (xy 401.720686 -23.56714)
			(xy 401.77642 -23.565103) (xy 401.831857 -23.571203) (xy 401.885814 -23.585309) (xy 401.937143 -23.607121)
			(xy 401.984749 -23.636175) (xy 402.027617 -23.67185) (xy 402.064834 -23.713387) (xy 402.095607 -23.7599)
			(xy 402.119279 -23.810397) (xy 402.135347 -23.863804) (xy 402.143467 -23.91898) (xy 402.143976 -23.946866)
			(xy 402.143536 -23.970996) (xy 402.372828 -23.970996) (xy 402.376899 -23.915374) (xy 402.389025 -23.860937)
			(xy 402.408948 -23.808846) (xy 402.436244 -23.760211) (xy 402.47033 -23.716068) (xy 402.510479 -23.677359)
			(xy 402.555837 -23.644908) (xy 402.605437 -23.619407) (xy 402.658221 -23.6014) (xy 402.713064 -23.59127)
			(xy 402.768798 -23.589233) (xy 402.775732 -23.589996) (xy 416.384484 -23.589996) (xy 416.388555 -23.534374)
			(xy 416.400681 -23.479937) (xy 416.420604 -23.427846) (xy 416.4479 -23.379211) (xy 416.481986 -23.335068)
			(xy 416.522135 -23.296359) (xy 416.567493 -23.263908) (xy 416.617093 -23.238407) (xy 416.669877 -23.2204)
			(xy 416.72472 -23.21027) (xy 416.780454 -23.208233) (xy 416.835891 -23.214333) (xy 416.889848 -23.228439)
			(xy 416.941177 -23.250251) (xy 416.988783 -23.279305) (xy 417.031651 -23.31498) (xy 417.068868 -23.356517)
			(xy 417.099641 -23.40303) (xy 417.123313 -23.453527) (xy 417.139381 -23.506934) (xy 417.147501 -23.56211)
			(xy 417.14801 -23.589996) (xy 417.147501 -23.617882) (xy 417.139381 -23.673058) (xy 417.123313 -23.726465)
			(xy 417.099641 -23.776962) (xy 417.068868 -23.823475) (xy 417.031651 -23.865012) (xy 416.988783 -23.900687)
			(xy 416.941177 -23.929741) (xy 416.889848 -23.951553) (xy 416.837823 -23.965154) (xy 426.377352 -23.965154)
			(xy 426.381423 -23.909532) (xy 426.393549 -23.855095) (xy 426.413472 -23.803004) (xy 426.440768 -23.754369)
			(xy 426.474854 -23.710226) (xy 426.515003 -23.671517) (xy 426.560361 -23.639066) (xy 426.609961 -23.613565)
			(xy 426.662745 -23.595558) (xy 426.717588 -23.585428) (xy 426.773322 -23.583391) (xy 426.828759 -23.589491)
			(xy 426.882716 -23.603597) (xy 426.934045 -23.625409) (xy 426.981651 -23.654463) (xy 427.024519 -23.690138)
			(xy 427.061736 -23.731675) (xy 427.092509 -23.778188) (xy 427.116181 -23.828685) (xy 427.132249 -23.882092)
			(xy 427.140369 -23.937268) (xy 427.140544 -23.946866) (xy 427.380398 -23.946866) (xy 427.384469 -23.891244)
			(xy 427.396595 -23.836807) (xy 427.416518 -23.784716) (xy 427.443814 -23.736081) (xy 427.4779 -23.691938)
			(xy 427.518049 -23.653229) (xy 427.563407 -23.620778) (xy 427.613007 -23.595277) (xy 427.665791 -23.57727)
			(xy 427.720634 -23.56714) (xy 427.776368 -23.565103) (xy 427.831805 -23.571203) (xy 427.885762 -23.585309)
			(xy 427.937091 -23.607121) (xy 427.984697 -23.636175) (xy 428.027565 -23.67185) (xy 428.064782 -23.713387)
			(xy 428.095555 -23.7599) (xy 428.119227 -23.810397) (xy 428.135295 -23.863804) (xy 428.143415 -23.91898)
			(xy 428.143924 -23.946866) (xy 428.143484 -23.970996) (xy 428.372776 -23.970996) (xy 428.376847 -23.915374)
			(xy 428.388973 -23.860937) (xy 428.408896 -23.808846) (xy 428.436192 -23.760211) (xy 428.470278 -23.716068)
			(xy 428.510427 -23.677359) (xy 428.555785 -23.644908) (xy 428.605385 -23.619407) (xy 428.658169 -23.6014)
			(xy 428.713012 -23.59127) (xy 428.768746 -23.589233) (xy 428.77568 -23.589996) (xy 442.384432 -23.589996)
			(xy 442.388503 -23.534374) (xy 442.400629 -23.479937) (xy 442.420552 -23.427846) (xy 442.447848 -23.379211)
			(xy 442.481934 -23.335068) (xy 442.522083 -23.296359) (xy 442.567441 -23.263908) (xy 442.617041 -23.238407)
			(xy 442.669825 -23.2204) (xy 442.724668 -23.21027) (xy 442.780402 -23.208233) (xy 442.835839 -23.214333)
			(xy 442.889796 -23.228439) (xy 442.941125 -23.250251) (xy 442.988731 -23.279305) (xy 443.031599 -23.31498)
			(xy 443.068816 -23.356517) (xy 443.099589 -23.40303) (xy 443.123261 -23.453527) (xy 443.139329 -23.506934)
			(xy 443.147449 -23.56211) (xy 443.147958 -23.589996) (xy 443.147449 -23.617882) (xy 443.139329 -23.673058)
			(xy 443.123261 -23.726465) (xy 443.099589 -23.776962) (xy 443.068816 -23.823475) (xy 443.031599 -23.865012)
			(xy 442.988731 -23.900687) (xy 442.941125 -23.929741) (xy 442.889796 -23.951553) (xy 442.837771 -23.965154)
			(xy 452.3773 -23.965154) (xy 452.381371 -23.909532) (xy 452.393497 -23.855095) (xy 452.41342 -23.803004)
			(xy 452.440716 -23.754369) (xy 452.474802 -23.710226) (xy 452.514951 -23.671517) (xy 452.560309 -23.639066)
			(xy 452.609909 -23.613565) (xy 452.662693 -23.595558) (xy 452.717536 -23.585428) (xy 452.77327 -23.583391)
			(xy 452.828707 -23.589491) (xy 452.882664 -23.603597) (xy 452.933993 -23.625409) (xy 452.981599 -23.654463)
			(xy 453.024467 -23.690138) (xy 453.061684 -23.731675) (xy 453.092457 -23.778188) (xy 453.116129 -23.828685)
			(xy 453.132197 -23.882092) (xy 453.140317 -23.937268) (xy 453.140826 -23.965154) (xy 453.140317 -23.99304)
			(xy 453.132197 -24.048216) (xy 453.116129 -24.101623) (xy 453.092457 -24.15212) (xy 453.061684 -24.198633)
			(xy 453.024467 -24.24017) (xy 452.981599 -24.275845) (xy 452.933993 -24.304899) (xy 452.882664 -24.326711)
			(xy 452.828707 -24.340817) (xy 452.77327 -24.346917) (xy 452.717536 -24.34488) (xy 452.662693 -24.33475)
			(xy 452.609909 -24.316743) (xy 452.560309 -24.291242) (xy 452.514951 -24.258791) (xy 452.474802 -24.220082)
			(xy 452.440716 -24.175939) (xy 452.41342 -24.127304) (xy 452.393497 -24.075213) (xy 452.381371 -24.020776)
			(xy 452.3773 -23.965154) (xy 442.837771 -23.965154) (xy 442.835839 -23.965659) (xy 442.780402 -23.971759)
			(xy 442.724668 -23.969722) (xy 442.669825 -23.959592) (xy 442.617041 -23.941585) (xy 442.567441 -23.916084)
			(xy 442.522083 -23.883633) (xy 442.481934 -23.844924) (xy 442.447848 -23.800781) (xy 442.420552 -23.752146)
			(xy 442.400629 -23.700055) (xy 442.388503 -23.645618) (xy 442.384432 -23.589996) (xy 428.77568 -23.589996)
			(xy 428.824183 -23.595333) (xy 428.87814 -23.609439) (xy 428.929469 -23.631251) (xy 428.977075 -23.660305)
			(xy 429.019943 -23.69598) (xy 429.05716 -23.737517) (xy 429.087933 -23.78403) (xy 429.111605 -23.834527)
			(xy 429.127673 -23.887934) (xy 429.135793 -23.94311) (xy 429.136302 -23.970996) (xy 429.135793 -23.998882)
			(xy 429.127673 -24.054058) (xy 429.111605 -24.107465) (xy 429.087933 -24.157962) (xy 429.08778 -24.158194)
			(xy 433.750718 -24.158194) (xy 433.754789 -24.102572) (xy 433.766915 -24.048135) (xy 433.786838 -23.996044)
			(xy 433.814134 -23.947409) (xy 433.84822 -23.903266) (xy 433.888369 -23.864557) (xy 433.933727 -23.832106)
			(xy 433.983327 -23.806605) (xy 434.036111 -23.788598) (xy 434.090954 -23.778468) (xy 434.146688 -23.776431)
			(xy 434.202125 -23.782531) (xy 434.256082 -23.796637) (xy 434.307411 -23.818449) (xy 434.355017 -23.847503)
			(xy 434.397885 -23.883178) (xy 434.435102 -23.924715) (xy 434.465875 -23.971228) (xy 434.489547 -24.021725)
			(xy 434.505615 -24.075132) (xy 434.513735 -24.130308) (xy 434.514244 -24.158194) (xy 434.513735 -24.18608)
			(xy 434.513166 -24.189944) (xy 437.598818 -24.189944) (xy 437.602889 -24.134322) (xy 437.615015 -24.079885)
			(xy 437.634938 -24.027794) (xy 437.662234 -23.979159) (xy 437.69632 -23.935016) (xy 437.736469 -23.896307)
			(xy 437.781827 -23.863856) (xy 437.831427 -23.838355) (xy 437.884211 -23.820348) (xy 437.939054 -23.810218)
			(xy 437.994788 -23.808181) (xy 438.050225 -23.814281) (xy 438.104182 -23.828387) (xy 438.155511 -23.850199)
			(xy 438.203117 -23.879253) (xy 438.245985 -23.914928) (xy 438.283202 -23.956465) (xy 438.313975 -24.002978)
			(xy 438.337647 -24.053475) (xy 438.353715 -24.106882) (xy 438.361835 -24.162058) (xy 438.362344 -24.189944)
			(xy 440.1218 -24.189944) (xy 440.125871 -24.134322) (xy 440.137997 -24.079885) (xy 440.15792 -24.027794)
			(xy 440.185216 -23.979159) (xy 440.219302 -23.935016) (xy 440.259451 -23.896307) (xy 440.304809 -23.863856)
			(xy 440.354409 -23.838355) (xy 440.407193 -23.820348) (xy 440.462036 -23.810218) (xy 440.51777 -23.808181)
			(xy 440.573207 -23.814281) (xy 440.627164 -23.828387) (xy 440.678493 -23.850199) (xy 440.726099 -23.879253)
			(xy 440.768967 -23.914928) (xy 440.806184 -23.956465) (xy 440.836957 -24.002978) (xy 440.860629 -24.053475)
			(xy 440.876697 -24.106882) (xy 440.884817 -24.162058) (xy 440.885326 -24.189944) (xy 440.884817 -24.21783)
			(xy 440.876697 -24.273006) (xy 440.860629 -24.326413) (xy 440.836957 -24.37691) (xy 440.806184 -24.423423)
			(xy 440.768967 -24.46496) (xy 440.726099 -24.500635) (xy 440.678493 -24.529689) (xy 440.627164 -24.551501)
			(xy 440.573207 -24.565607) (xy 440.51777 -24.571707) (xy 440.462036 -24.56967) (xy 440.407193 -24.55954)
			(xy 440.354409 -24.541533) (xy 440.304809 -24.516032) (xy 440.259451 -24.483581) (xy 440.219302 -24.444872)
			(xy 440.185216 -24.400729) (xy 440.15792 -24.352094) (xy 440.137997 -24.300003) (xy 440.125871 -24.245566)
			(xy 440.1218 -24.189944) (xy 438.362344 -24.189944) (xy 438.361835 -24.21783) (xy 438.353715 -24.273006)
			(xy 438.337647 -24.326413) (xy 438.313975 -24.37691) (xy 438.283202 -24.423423) (xy 438.245985 -24.46496)
			(xy 438.203117 -24.500635) (xy 438.155511 -24.529689) (xy 438.104182 -24.551501) (xy 438.050225 -24.565607)
			(xy 437.994788 -24.571707) (xy 437.939054 -24.56967) (xy 437.884211 -24.55954) (xy 437.831427 -24.541533)
			(xy 437.781827 -24.516032) (xy 437.736469 -24.483581) (xy 437.69632 -24.444872) (xy 437.662234 -24.400729)
			(xy 437.634938 -24.352094) (xy 437.615015 -24.300003) (xy 437.602889 -24.245566) (xy 437.598818 -24.189944)
			(xy 434.513166 -24.189944) (xy 434.505615 -24.241256) (xy 434.489547 -24.294663) (xy 434.465875 -24.34516)
			(xy 434.435102 -24.391673) (xy 434.397885 -24.43321) (xy 434.355017 -24.468885) (xy 434.307411 -24.497939)
			(xy 434.256082 -24.519751) (xy 434.202125 -24.533857) (xy 434.146688 -24.539957) (xy 434.090954 -24.53792)
			(xy 434.036111 -24.52779) (xy 433.983327 -24.509783) (xy 433.933727 -24.484282) (xy 433.888369 -24.451831)
			(xy 433.84822 -24.413122) (xy 433.814134 -24.368979) (xy 433.786838 -24.320344) (xy 433.766915 -24.268253)
			(xy 433.754789 -24.213816) (xy 433.750718 -24.158194) (xy 429.08778 -24.158194) (xy 429.05716 -24.204475)
			(xy 429.019943 -24.246012) (xy 428.977075 -24.281687) (xy 428.929469 -24.310741) (xy 428.87814 -24.332553)
			(xy 428.824183 -24.346659) (xy 428.768746 -24.352759) (xy 428.713012 -24.350722) (xy 428.658169 -24.340592)
			(xy 428.605385 -24.322585) (xy 428.555785 -24.297084) (xy 428.510427 -24.264633) (xy 428.470278 -24.225924)
			(xy 428.436192 -24.181781) (xy 428.408896 -24.133146) (xy 428.388973 -24.081055) (xy 428.376847 -24.026618)
			(xy 428.372776 -23.970996) (xy 428.143484 -23.970996) (xy 428.143415 -23.974752) (xy 428.135295 -24.029928)
			(xy 428.119227 -24.083335) (xy 428.095555 -24.133832) (xy 428.064782 -24.180345) (xy 428.027565 -24.221882)
			(xy 427.984697 -24.257557) (xy 427.937091 -24.286611) (xy 427.885762 -24.308423) (xy 427.831805 -24.322529)
			(xy 427.776368 -24.328629) (xy 427.720634 -24.326592) (xy 427.665791 -24.316462) (xy 427.613007 -24.298455)
			(xy 427.563407 -24.272954) (xy 427.518049 -24.240503) (xy 427.4779 -24.201794) (xy 427.443814 -24.157651)
			(xy 427.416518 -24.109016) (xy 427.396595 -24.056925) (xy 427.384469 -24.002488) (xy 427.380398 -23.946866)
			(xy 427.140544 -23.946866) (xy 427.140878 -23.965154) (xy 427.140369 -23.99304) (xy 427.132249 -24.048216)
			(xy 427.116181 -24.101623) (xy 427.092509 -24.15212) (xy 427.061736 -24.198633) (xy 427.024519 -24.24017)
			(xy 426.981651 -24.275845) (xy 426.934045 -24.304899) (xy 426.882716 -24.326711) (xy 426.828759 -24.340817)
			(xy 426.773322 -24.346917) (xy 426.717588 -24.34488) (xy 426.662745 -24.33475) (xy 426.609961 -24.316743)
			(xy 426.560361 -24.291242) (xy 426.515003 -24.258791) (xy 426.474854 -24.220082) (xy 426.440768 -24.175939)
			(xy 426.413472 -24.127304) (xy 426.393549 -24.075213) (xy 426.381423 -24.020776) (xy 426.377352 -23.965154)
			(xy 416.837823 -23.965154) (xy 416.835891 -23.965659) (xy 416.780454 -23.971759) (xy 416.72472 -23.969722)
			(xy 416.669877 -23.959592) (xy 416.617093 -23.941585) (xy 416.567493 -23.916084) (xy 416.522135 -23.883633)
			(xy 416.481986 -23.844924) (xy 416.4479 -23.800781) (xy 416.420604 -23.752146) (xy 416.400681 -23.700055)
			(xy 416.388555 -23.645618) (xy 416.384484 -23.589996) (xy 402.775732 -23.589996) (xy 402.824235 -23.595333)
			(xy 402.878192 -23.609439) (xy 402.929521 -23.631251) (xy 402.977127 -23.660305) (xy 403.019995 -23.69598)
			(xy 403.057212 -23.737517) (xy 403.087985 -23.78403) (xy 403.111657 -23.834527) (xy 403.127725 -23.887934)
			(xy 403.135845 -23.94311) (xy 403.136354 -23.970996) (xy 403.135845 -23.998882) (xy 403.127725 -24.054058)
			(xy 403.111657 -24.107465) (xy 403.087985 -24.157962) (xy 403.087832 -24.158194) (xy 407.75077 -24.158194)
			(xy 407.754841 -24.102572) (xy 407.766967 -24.048135) (xy 407.78689 -23.996044) (xy 407.814186 -23.947409)
			(xy 407.848272 -23.903266) (xy 407.888421 -23.864557) (xy 407.933779 -23.832106) (xy 407.983379 -23.806605)
			(xy 408.036163 -23.788598) (xy 408.091006 -23.778468) (xy 408.14674 -23.776431) (xy 408.202177 -23.782531)
			(xy 408.256134 -23.796637) (xy 408.307463 -23.818449) (xy 408.355069 -23.847503) (xy 408.397937 -23.883178)
			(xy 408.435154 -23.924715) (xy 408.465927 -23.971228) (xy 408.489599 -24.021725) (xy 408.505667 -24.075132)
			(xy 408.513787 -24.130308) (xy 408.514296 -24.158194) (xy 408.513787 -24.18608) (xy 408.513218 -24.189944)
			(xy 411.59887 -24.189944) (xy 411.602941 -24.134322) (xy 411.615067 -24.079885) (xy 411.63499 -24.027794)
			(xy 411.662286 -23.979159) (xy 411.696372 -23.935016) (xy 411.736521 -23.896307) (xy 411.781879 -23.863856)
			(xy 411.831479 -23.838355) (xy 411.884263 -23.820348) (xy 411.939106 -23.810218) (xy 411.99484 -23.808181)
			(xy 412.050277 -23.814281) (xy 412.104234 -23.828387) (xy 412.155563 -23.850199) (xy 412.203169 -23.879253)
			(xy 412.246037 -23.914928) (xy 412.283254 -23.956465) (xy 412.314027 -24.002978) (xy 412.337699 -24.053475)
			(xy 412.353767 -24.106882) (xy 412.361887 -24.162058) (xy 412.362396 -24.189944) (xy 414.121852 -24.189944)
			(xy 414.125923 -24.134322) (xy 414.138049 -24.079885) (xy 414.157972 -24.027794) (xy 414.185268 -23.979159)
			(xy 414.219354 -23.935016) (xy 414.259503 -23.896307) (xy 414.304861 -23.863856) (xy 414.354461 -23.838355)
			(xy 414.407245 -23.820348) (xy 414.462088 -23.810218) (xy 414.517822 -23.808181) (xy 414.573259 -23.814281)
			(xy 414.627216 -23.828387) (xy 414.678545 -23.850199) (xy 414.726151 -23.879253) (xy 414.769019 -23.914928)
			(xy 414.806236 -23.956465) (xy 414.837009 -24.002978) (xy 414.860681 -24.053475) (xy 414.876749 -24.106882)
			(xy 414.884869 -24.162058) (xy 414.885378 -24.189944) (xy 414.884869 -24.21783) (xy 414.876749 -24.273006)
			(xy 414.860681 -24.326413) (xy 414.837009 -24.37691) (xy 414.806236 -24.423423) (xy 414.769019 -24.46496)
			(xy 414.726151 -24.500635) (xy 414.678545 -24.529689) (xy 414.627216 -24.551501) (xy 414.573259 -24.565607)
			(xy 414.517822 -24.571707) (xy 414.462088 -24.56967) (xy 414.407245 -24.55954) (xy 414.354461 -24.541533)
			(xy 414.304861 -24.516032) (xy 414.259503 -24.483581) (xy 414.219354 -24.444872) (xy 414.185268 -24.400729)
			(xy 414.157972 -24.352094) (xy 414.138049 -24.300003) (xy 414.125923 -24.245566) (xy 414.121852 -24.189944)
			(xy 412.362396 -24.189944) (xy 412.361887 -24.21783) (xy 412.353767 -24.273006) (xy 412.337699 -24.326413)
			(xy 412.314027 -24.37691) (xy 412.283254 -24.423423) (xy 412.246037 -24.46496) (xy 412.203169 -24.500635)
			(xy 412.155563 -24.529689) (xy 412.104234 -24.551501) (xy 412.050277 -24.565607) (xy 411.99484 -24.571707)
			(xy 411.939106 -24.56967) (xy 411.884263 -24.55954) (xy 411.831479 -24.541533) (xy 411.781879 -24.516032)
			(xy 411.736521 -24.483581) (xy 411.696372 -24.444872) (xy 411.662286 -24.400729) (xy 411.63499 -24.352094)
			(xy 411.615067 -24.300003) (xy 411.602941 -24.245566) (xy 411.59887 -24.189944) (xy 408.513218 -24.189944)
			(xy 408.505667 -24.241256) (xy 408.489599 -24.294663) (xy 408.465927 -24.34516) (xy 408.435154 -24.391673)
			(xy 408.397937 -24.43321) (xy 408.355069 -24.468885) (xy 408.307463 -24.497939) (xy 408.256134 -24.519751)
			(xy 408.202177 -24.533857) (xy 408.14674 -24.539957) (xy 408.091006 -24.53792) (xy 408.036163 -24.52779)
			(xy 407.983379 -24.509783) (xy 407.933779 -24.484282) (xy 407.888421 -24.451831) (xy 407.848272 -24.413122)
			(xy 407.814186 -24.368979) (xy 407.78689 -24.320344) (xy 407.766967 -24.268253) (xy 407.754841 -24.213816)
			(xy 407.75077 -24.158194) (xy 403.087832 -24.158194) (xy 403.057212 -24.204475) (xy 403.019995 -24.246012)
			(xy 402.977127 -24.281687) (xy 402.929521 -24.310741) (xy 402.878192 -24.332553) (xy 402.824235 -24.346659)
			(xy 402.768798 -24.352759) (xy 402.713064 -24.350722) (xy 402.658221 -24.340592) (xy 402.605437 -24.322585)
			(xy 402.555837 -24.297084) (xy 402.510479 -24.264633) (xy 402.47033 -24.225924) (xy 402.436244 -24.181781)
			(xy 402.408948 -24.133146) (xy 402.389025 -24.081055) (xy 402.376899 -24.026618) (xy 402.372828 -23.970996)
			(xy 402.143536 -23.970996) (xy 402.143467 -23.974752) (xy 402.135347 -24.029928) (xy 402.119279 -24.083335)
			(xy 402.095607 -24.133832) (xy 402.064834 -24.180345) (xy 402.027617 -24.221882) (xy 401.984749 -24.257557)
			(xy 401.937143 -24.286611) (xy 401.885814 -24.308423) (xy 401.831857 -24.322529) (xy 401.77642 -24.328629)
			(xy 401.720686 -24.326592) (xy 401.665843 -24.316462) (xy 401.613059 -24.298455) (xy 401.563459 -24.272954)
			(xy 401.518101 -24.240503) (xy 401.477952 -24.201794) (xy 401.443866 -24.157651) (xy 401.41657 -24.109016)
			(xy 401.396647 -24.056925) (xy 401.384521 -24.002488) (xy 401.38045 -23.946866) (xy 401.140596 -23.946866)
			(xy 401.14093 -23.965154) (xy 401.140421 -23.99304) (xy 401.132301 -24.048216) (xy 401.116233 -24.101623)
			(xy 401.092561 -24.15212) (xy 401.061788 -24.198633) (xy 401.024571 -24.24017) (xy 400.981703 -24.275845)
			(xy 400.934097 -24.304899) (xy 400.882768 -24.326711) (xy 400.828811 -24.340817) (xy 400.773374 -24.346917)
			(xy 400.71764 -24.34488) (xy 400.662797 -24.33475) (xy 400.610013 -24.316743) (xy 400.560413 -24.291242)
			(xy 400.515055 -24.258791) (xy 400.474906 -24.220082) (xy 400.44082 -24.175939) (xy 400.413524 -24.127304)
			(xy 400.393601 -24.075213) (xy 400.381475 -24.020776) (xy 400.377404 -23.965154) (xy 390.837875 -23.965154)
			(xy 390.835943 -23.965659) (xy 390.780506 -23.971759) (xy 390.724772 -23.969722) (xy 390.669929 -23.959592)
			(xy 390.617145 -23.941585) (xy 390.567545 -23.916084) (xy 390.522187 -23.883633) (xy 390.482038 -23.844924)
			(xy 390.447952 -23.800781) (xy 390.420656 -23.752146) (xy 390.400733 -23.700055) (xy 390.388607 -23.645618)
			(xy 390.384536 -23.589996) (xy 376.775784 -23.589996) (xy 376.824287 -23.595333) (xy 376.878244 -23.609439)
			(xy 376.929573 -23.631251) (xy 376.977179 -23.660305) (xy 377.020047 -23.69598) (xy 377.057264 -23.737517)
			(xy 377.088037 -23.78403) (xy 377.111709 -23.834527) (xy 377.127777 -23.887934) (xy 377.135897 -23.94311)
			(xy 377.136406 -23.970996) (xy 377.135897 -23.998882) (xy 377.127777 -24.054058) (xy 377.111709 -24.107465)
			(xy 377.088037 -24.157962) (xy 377.087884 -24.158194) (xy 381.750822 -24.158194) (xy 381.754893 -24.102572)
			(xy 381.767019 -24.048135) (xy 381.786942 -23.996044) (xy 381.814238 -23.947409) (xy 381.848324 -23.903266)
			(xy 381.888473 -23.864557) (xy 381.933831 -23.832106) (xy 381.983431 -23.806605) (xy 382.036215 -23.788598)
			(xy 382.091058 -23.778468) (xy 382.146792 -23.776431) (xy 382.202229 -23.782531) (xy 382.256186 -23.796637)
			(xy 382.307515 -23.818449) (xy 382.355121 -23.847503) (xy 382.397989 -23.883178) (xy 382.435206 -23.924715)
			(xy 382.465979 -23.971228) (xy 382.489651 -24.021725) (xy 382.505719 -24.075132) (xy 382.513839 -24.130308)
			(xy 382.514348 -24.158194) (xy 382.513839 -24.18608) (xy 382.51327 -24.189944) (xy 385.598922 -24.189944)
			(xy 385.602993 -24.134322) (xy 385.615119 -24.079885) (xy 385.635042 -24.027794) (xy 385.662338 -23.979159)
			(xy 385.696424 -23.935016) (xy 385.736573 -23.896307) (xy 385.781931 -23.863856) (xy 385.831531 -23.838355)
			(xy 385.884315 -23.820348) (xy 385.939158 -23.810218) (xy 385.994892 -23.808181) (xy 386.050329 -23.814281)
			(xy 386.104286 -23.828387) (xy 386.155615 -23.850199) (xy 386.203221 -23.879253) (xy 386.246089 -23.914928)
			(xy 386.283306 -23.956465) (xy 386.314079 -24.002978) (xy 386.337751 -24.053475) (xy 386.353819 -24.106882)
			(xy 386.361939 -24.162058) (xy 386.362448 -24.189944) (xy 388.121904 -24.189944) (xy 388.125975 -24.134322)
			(xy 388.138101 -24.079885) (xy 388.158024 -24.027794) (xy 388.18532 -23.979159) (xy 388.219406 -23.935016)
			(xy 388.259555 -23.896307) (xy 388.304913 -23.863856) (xy 388.354513 -23.838355) (xy 388.407297 -23.820348)
			(xy 388.46214 -23.810218) (xy 388.517874 -23.808181) (xy 388.573311 -23.814281) (xy 388.627268 -23.828387)
			(xy 388.678597 -23.850199) (xy 388.726203 -23.879253) (xy 388.769071 -23.914928) (xy 388.806288 -23.956465)
			(xy 388.837061 -24.002978) (xy 388.860733 -24.053475) (xy 388.876801 -24.106882) (xy 388.884921 -24.162058)
			(xy 388.88543 -24.189944) (xy 388.884921 -24.21783) (xy 388.876801 -24.273006) (xy 388.860733 -24.326413)
			(xy 388.837061 -24.37691) (xy 388.806288 -24.423423) (xy 388.769071 -24.46496) (xy 388.726203 -24.500635)
			(xy 388.678597 -24.529689) (xy 388.627268 -24.551501) (xy 388.573311 -24.565607) (xy 388.517874 -24.571707)
			(xy 388.46214 -24.56967) (xy 388.407297 -24.55954) (xy 388.354513 -24.541533) (xy 388.304913 -24.516032)
			(xy 388.259555 -24.483581) (xy 388.219406 -24.444872) (xy 388.18532 -24.400729) (xy 388.158024 -24.352094)
			(xy 388.138101 -24.300003) (xy 388.125975 -24.245566) (xy 388.121904 -24.189944) (xy 386.362448 -24.189944)
			(xy 386.361939 -24.21783) (xy 386.353819 -24.273006) (xy 386.337751 -24.326413) (xy 386.314079 -24.37691)
			(xy 386.283306 -24.423423) (xy 386.246089 -24.46496) (xy 386.203221 -24.500635) (xy 386.155615 -24.529689)
			(xy 386.104286 -24.551501) (xy 386.050329 -24.565607) (xy 385.994892 -24.571707) (xy 385.939158 -24.56967)
			(xy 385.884315 -24.55954) (xy 385.831531 -24.541533) (xy 385.781931 -24.516032) (xy 385.736573 -24.483581)
			(xy 385.696424 -24.444872) (xy 385.662338 -24.400729) (xy 385.635042 -24.352094) (xy 385.615119 -24.300003)
			(xy 385.602993 -24.245566) (xy 385.598922 -24.189944) (xy 382.51327 -24.189944) (xy 382.505719 -24.241256)
			(xy 382.489651 -24.294663) (xy 382.465979 -24.34516) (xy 382.435206 -24.391673) (xy 382.397989 -24.43321)
			(xy 382.355121 -24.468885) (xy 382.307515 -24.497939) (xy 382.256186 -24.519751) (xy 382.202229 -24.533857)
			(xy 382.146792 -24.539957) (xy 382.091058 -24.53792) (xy 382.036215 -24.52779) (xy 381.983431 -24.509783)
			(xy 381.933831 -24.484282) (xy 381.888473 -24.451831) (xy 381.848324 -24.413122) (xy 381.814238 -24.368979)
			(xy 381.786942 -24.320344) (xy 381.767019 -24.268253) (xy 381.754893 -24.213816) (xy 381.750822 -24.158194)
			(xy 377.087884 -24.158194) (xy 377.057264 -24.204475) (xy 377.020047 -24.246012) (xy 376.977179 -24.281687)
			(xy 376.929573 -24.310741) (xy 376.878244 -24.332553) (xy 376.824287 -24.346659) (xy 376.76885 -24.352759)
			(xy 376.713116 -24.350722) (xy 376.658273 -24.340592) (xy 376.605489 -24.322585) (xy 376.555889 -24.297084)
			(xy 376.510531 -24.264633) (xy 376.470382 -24.225924) (xy 376.436296 -24.181781) (xy 376.409 -24.133146)
			(xy 376.389077 -24.081055) (xy 376.376951 -24.026618) (xy 376.37288 -23.970996) (xy 376.143588 -23.970996)
			(xy 376.143519 -23.974752) (xy 376.135399 -24.029928) (xy 376.119331 -24.083335) (xy 376.095659 -24.133832)
			(xy 376.064886 -24.180345) (xy 376.027669 -24.221882) (xy 375.984801 -24.257557) (xy 375.937195 -24.286611)
			(xy 375.885866 -24.308423) (xy 375.831909 -24.322529) (xy 375.776472 -24.328629) (xy 375.720738 -24.326592)
			(xy 375.665895 -24.316462) (xy 375.613111 -24.298455) (xy 375.563511 -24.272954) (xy 375.518153 -24.240503)
			(xy 375.478004 -24.201794) (xy 375.443918 -24.157651) (xy 375.416622 -24.109016) (xy 375.396699 -24.056925)
			(xy 375.384573 -24.002488) (xy 375.380502 -23.946866) (xy 375.140648 -23.946866) (xy 375.140982 -23.965154)
			(xy 375.140473 -23.99304) (xy 375.132353 -24.048216) (xy 375.116285 -24.101623) (xy 375.092613 -24.15212)
			(xy 375.06184 -24.198633) (xy 375.024623 -24.24017) (xy 374.981755 -24.275845) (xy 374.934149 -24.304899)
			(xy 374.88282 -24.326711) (xy 374.828863 -24.340817) (xy 374.773426 -24.346917) (xy 374.717692 -24.34488)
			(xy 374.662849 -24.33475) (xy 374.610065 -24.316743) (xy 374.560465 -24.291242) (xy 374.515107 -24.258791)
			(xy 374.474958 -24.220082) (xy 374.440872 -24.175939) (xy 374.413576 -24.127304) (xy 374.393653 -24.075213)
			(xy 374.381527 -24.020776) (xy 374.377456 -23.965154) (xy 364.837927 -23.965154) (xy 364.835995 -23.965659)
			(xy 364.780558 -23.971759) (xy 364.724824 -23.969722) (xy 364.669981 -23.959592) (xy 364.617197 -23.941585)
			(xy 364.567597 -23.916084) (xy 364.522239 -23.883633) (xy 364.48209 -23.844924) (xy 364.448004 -23.800781)
			(xy 364.420708 -23.752146) (xy 364.400785 -23.700055) (xy 364.388659 -23.645618) (xy 364.384588 -23.589996)
			(xy 327.04786 -23.589996) (xy 327.047351 -23.617882) (xy 327.039231 -23.673058) (xy 327.023163 -23.726465)
			(xy 326.999491 -23.776962) (xy 326.968718 -23.823475) (xy 326.931501 -23.865012) (xy 326.888633 -23.900687)
			(xy 326.841027 -23.929741) (xy 326.789698 -23.951553) (xy 326.735741 -23.965659) (xy 326.680304 -23.971759)
			(xy 326.62457 -23.969722) (xy 326.569727 -23.959592) (xy 326.516943 -23.941585) (xy 326.467343 -23.916084)
			(xy 326.421985 -23.883633) (xy 326.381836 -23.844924) (xy 326.34775 -23.800781) (xy 326.320454 -23.752146)
			(xy 326.300531 -23.700055) (xy 326.288405 -23.645618) (xy 326.284334 -23.589996) (xy 312.675582 -23.589996)
			(xy 312.724085 -23.595333) (xy 312.778042 -23.609439) (xy 312.829371 -23.631251) (xy 312.876977 -23.660305)
			(xy 312.919845 -23.69598) (xy 312.957062 -23.737517) (xy 312.987835 -23.78403) (xy 313.011507 -23.834527)
			(xy 313.027575 -23.887934) (xy 313.035695 -23.94311) (xy 313.036204 -23.970996) (xy 313.035695 -23.998882)
			(xy 313.027575 -24.054058) (xy 313.011507 -24.107465) (xy 312.987835 -24.157962) (xy 312.987682 -24.158194)
			(xy 317.65062 -24.158194) (xy 317.654691 -24.102572) (xy 317.666817 -24.048135) (xy 317.68674 -23.996044)
			(xy 317.714036 -23.947409) (xy 317.748122 -23.903266) (xy 317.788271 -23.864557) (xy 317.833629 -23.832106)
			(xy 317.883229 -23.806605) (xy 317.936013 -23.788598) (xy 317.990856 -23.778468) (xy 318.04659 -23.776431)
			(xy 318.102027 -23.782531) (xy 318.155984 -23.796637) (xy 318.207313 -23.818449) (xy 318.254919 -23.847503)
			(xy 318.297787 -23.883178) (xy 318.335004 -23.924715) (xy 318.365777 -23.971228) (xy 318.389449 -24.021725)
			(xy 318.405517 -24.075132) (xy 318.413637 -24.130308) (xy 318.414146 -24.158194) (xy 318.413637 -24.18608)
			(xy 318.413068 -24.189944) (xy 321.49872 -24.189944) (xy 321.502791 -24.134322) (xy 321.514917 -24.079885)
			(xy 321.53484 -24.027794) (xy 321.562136 -23.979159) (xy 321.596222 -23.935016) (xy 321.636371 -23.896307)
			(xy 321.681729 -23.863856) (xy 321.731329 -23.838355) (xy 321.784113 -23.820348) (xy 321.838956 -23.810218)
			(xy 321.89469 -23.808181) (xy 321.950127 -23.814281) (xy 322.004084 -23.828387) (xy 322.055413 -23.850199)
			(xy 322.103019 -23.879253) (xy 322.145887 -23.914928) (xy 322.183104 -23.956465) (xy 322.213877 -24.002978)
			(xy 322.237549 -24.053475) (xy 322.253617 -24.106882) (xy 322.261737 -24.162058) (xy 322.262246 -24.189944)
			(xy 324.021702 -24.189944) (xy 324.025773 -24.134322) (xy 324.037899 -24.079885) (xy 324.057822 -24.027794)
			(xy 324.085118 -23.979159) (xy 324.119204 -23.935016) (xy 324.159353 -23.896307) (xy 324.204711 -23.863856)
			(xy 324.254311 -23.838355) (xy 324.307095 -23.820348) (xy 324.361938 -23.810218) (xy 324.417672 -23.808181)
			(xy 324.473109 -23.814281) (xy 324.527066 -23.828387) (xy 324.578395 -23.850199) (xy 324.626001 -23.879253)
			(xy 324.668869 -23.914928) (xy 324.706086 -23.956465) (xy 324.736859 -24.002978) (xy 324.760531 -24.053475)
			(xy 324.776599 -24.106882) (xy 324.78415 -24.158194) (xy 355.750874 -24.158194) (xy 355.754945 -24.102572)
			(xy 355.767071 -24.048135) (xy 355.786994 -23.996044) (xy 355.81429 -23.947409) (xy 355.848376 -23.903266)
			(xy 355.888525 -23.864557) (xy 355.933883 -23.832106) (xy 355.983483 -23.806605) (xy 356.036267 -23.788598)
			(xy 356.09111 -23.778468) (xy 356.146844 -23.776431) (xy 356.202281 -23.782531) (xy 356.256238 -23.796637)
			(xy 356.307567 -23.818449) (xy 356.355173 -23.847503) (xy 356.398041 -23.883178) (xy 356.435258 -23.924715)
			(xy 356.466031 -23.971228) (xy 356.489703 -24.021725) (xy 356.505771 -24.075132) (xy 356.513891 -24.130308)
			(xy 356.5144 -24.158194) (xy 356.513891 -24.18608) (xy 356.513322 -24.189944) (xy 359.598974 -24.189944)
			(xy 359.603045 -24.134322) (xy 359.615171 -24.079885) (xy 359.635094 -24.027794) (xy 359.66239 -23.979159)
			(xy 359.696476 -23.935016) (xy 359.736625 -23.896307) (xy 359.781983 -23.863856) (xy 359.831583 -23.838355)
			(xy 359.884367 -23.820348) (xy 359.93921 -23.810218) (xy 359.994944 -23.808181) (xy 360.050381 -23.814281)
			(xy 360.104338 -23.828387) (xy 360.155667 -23.850199) (xy 360.203273 -23.879253) (xy 360.246141 -23.914928)
			(xy 360.283358 -23.956465) (xy 360.314131 -24.002978) (xy 360.337803 -24.053475) (xy 360.353871 -24.106882)
			(xy 360.361991 -24.162058) (xy 360.3625 -24.189944) (xy 362.121956 -24.189944) (xy 362.126027 -24.134322)
			(xy 362.138153 -24.079885) (xy 362.158076 -24.027794) (xy 362.185372 -23.979159) (xy 362.219458 -23.935016)
			(xy 362.259607 -23.896307) (xy 362.304965 -23.863856) (xy 362.354565 -23.838355) (xy 362.407349 -23.820348)
			(xy 362.462192 -23.810218) (xy 362.517926 -23.808181) (xy 362.573363 -23.814281) (xy 362.62732 -23.828387)
			(xy 362.678649 -23.850199) (xy 362.726255 -23.879253) (xy 362.769123 -23.914928) (xy 362.80634 -23.956465)
			(xy 362.837113 -24.002978) (xy 362.860785 -24.053475) (xy 362.876853 -24.106882) (xy 362.884973 -24.162058)
			(xy 362.885482 -24.189944) (xy 362.884973 -24.21783) (xy 362.876853 -24.273006) (xy 362.860785 -24.326413)
			(xy 362.837113 -24.37691) (xy 362.80634 -24.423423) (xy 362.769123 -24.46496) (xy 362.726255 -24.500635)
			(xy 362.678649 -24.529689) (xy 362.62732 -24.551501) (xy 362.573363 -24.565607) (xy 362.517926 -24.571707)
			(xy 362.462192 -24.56967) (xy 362.407349 -24.55954) (xy 362.354565 -24.541533) (xy 362.304965 -24.516032)
			(xy 362.259607 -24.483581) (xy 362.219458 -24.444872) (xy 362.185372 -24.400729) (xy 362.158076 -24.352094)
			(xy 362.138153 -24.300003) (xy 362.126027 -24.245566) (xy 362.121956 -24.189944) (xy 360.3625 -24.189944)
			(xy 360.361991 -24.21783) (xy 360.353871 -24.273006) (xy 360.337803 -24.326413) (xy 360.314131 -24.37691)
			(xy 360.283358 -24.423423) (xy 360.246141 -24.46496) (xy 360.203273 -24.500635) (xy 360.155667 -24.529689)
			(xy 360.104338 -24.551501) (xy 360.050381 -24.565607) (xy 359.994944 -24.571707) (xy 359.93921 -24.56967)
			(xy 359.884367 -24.55954) (xy 359.831583 -24.541533) (xy 359.781983 -24.516032) (xy 359.736625 -24.483581)
			(xy 359.696476 -24.444872) (xy 359.66239 -24.400729) (xy 359.635094 -24.352094) (xy 359.615171 -24.300003)
			(xy 359.603045 -24.245566) (xy 359.598974 -24.189944) (xy 356.513322 -24.189944) (xy 356.505771 -24.241256)
			(xy 356.489703 -24.294663) (xy 356.466031 -24.34516) (xy 356.435258 -24.391673) (xy 356.398041 -24.43321)
			(xy 356.355173 -24.468885) (xy 356.307567 -24.497939) (xy 356.256238 -24.519751) (xy 356.202281 -24.533857)
			(xy 356.146844 -24.539957) (xy 356.09111 -24.53792) (xy 356.036267 -24.52779) (xy 355.983483 -24.509783)
			(xy 355.933883 -24.484282) (xy 355.888525 -24.451831) (xy 355.848376 -24.413122) (xy 355.81429 -24.368979)
			(xy 355.786994 -24.320344) (xy 355.767071 -24.268253) (xy 355.754945 -24.213816) (xy 355.750874 -24.158194)
			(xy 324.78415 -24.158194) (xy 324.784719 -24.162058) (xy 324.785228 -24.189944) (xy 324.784719 -24.21783)
			(xy 324.776599 -24.273006) (xy 324.760531 -24.326413) (xy 324.736859 -24.37691) (xy 324.706086 -24.423423)
			(xy 324.668869 -24.46496) (xy 324.626001 -24.500635) (xy 324.578395 -24.529689) (xy 324.527066 -24.551501)
			(xy 324.473109 -24.565607) (xy 324.417672 -24.571707) (xy 324.361938 -24.56967) (xy 324.307095 -24.55954)
			(xy 324.254311 -24.541533) (xy 324.204711 -24.516032) (xy 324.159353 -24.483581) (xy 324.119204 -24.444872)
			(xy 324.085118 -24.400729) (xy 324.057822 -24.352094) (xy 324.037899 -24.300003) (xy 324.025773 -24.245566)
			(xy 324.021702 -24.189944) (xy 322.262246 -24.189944) (xy 322.261737 -24.21783) (xy 322.253617 -24.273006)
			(xy 322.237549 -24.326413) (xy 322.213877 -24.37691) (xy 322.183104 -24.423423) (xy 322.145887 -24.46496)
			(xy 322.103019 -24.500635) (xy 322.055413 -24.529689) (xy 322.004084 -24.551501) (xy 321.950127 -24.565607)
			(xy 321.89469 -24.571707) (xy 321.838956 -24.56967) (xy 321.784113 -24.55954) (xy 321.731329 -24.541533)
			(xy 321.681729 -24.516032) (xy 321.636371 -24.483581) (xy 321.596222 -24.444872) (xy 321.562136 -24.400729)
			(xy 321.53484 -24.352094) (xy 321.514917 -24.300003) (xy 321.502791 -24.245566) (xy 321.49872 -24.189944)
			(xy 318.413068 -24.189944) (xy 318.405517 -24.241256) (xy 318.389449 -24.294663) (xy 318.365777 -24.34516)
			(xy 318.335004 -24.391673) (xy 318.297787 -24.43321) (xy 318.254919 -24.468885) (xy 318.207313 -24.497939)
			(xy 318.155984 -24.519751) (xy 318.102027 -24.533857) (xy 318.04659 -24.539957) (xy 317.990856 -24.53792)
			(xy 317.936013 -24.52779) (xy 317.883229 -24.509783) (xy 317.833629 -24.484282) (xy 317.788271 -24.451831)
			(xy 317.748122 -24.413122) (xy 317.714036 -24.368979) (xy 317.68674 -24.320344) (xy 317.666817 -24.268253)
			(xy 317.654691 -24.213816) (xy 317.65062 -24.158194) (xy 312.987682 -24.158194) (xy 312.957062 -24.204475)
			(xy 312.919845 -24.246012) (xy 312.876977 -24.281687) (xy 312.829371 -24.310741) (xy 312.778042 -24.332553)
			(xy 312.724085 -24.346659) (xy 312.668648 -24.352759) (xy 312.612914 -24.350722) (xy 312.558071 -24.340592)
			(xy 312.505287 -24.322585) (xy 312.455687 -24.297084) (xy 312.410329 -24.264633) (xy 312.37018 -24.225924)
			(xy 312.336094 -24.181781) (xy 312.308798 -24.133146) (xy 312.288875 -24.081055) (xy 312.276749 -24.026618)
			(xy 312.272678 -23.970996) (xy 312.043386 -23.970996) (xy 312.043317 -23.974752) (xy 312.035197 -24.029928)
			(xy 312.019129 -24.083335) (xy 311.995457 -24.133832) (xy 311.964684 -24.180345) (xy 311.927467 -24.221882)
			(xy 311.884599 -24.257557) (xy 311.836993 -24.286611) (xy 311.785664 -24.308423) (xy 311.731707 -24.322529)
			(xy 311.67627 -24.328629) (xy 311.620536 -24.326592) (xy 311.565693 -24.316462) (xy 311.512909 -24.298455)
			(xy 311.463309 -24.272954) (xy 311.417951 -24.240503) (xy 311.377802 -24.201794) (xy 311.343716 -24.157651)
			(xy 311.31642 -24.109016) (xy 311.296497 -24.056925) (xy 311.284371 -24.002488) (xy 311.2803 -23.946866)
			(xy 311.040446 -23.946866) (xy 311.04078 -23.965154) (xy 311.040271 -23.99304) (xy 311.032151 -24.048216)
			(xy 311.016083 -24.101623) (xy 310.992411 -24.15212) (xy 310.961638 -24.198633) (xy 310.924421 -24.24017)
			(xy 310.881553 -24.275845) (xy 310.833947 -24.304899) (xy 310.782618 -24.326711) (xy 310.728661 -24.340817)
			(xy 310.673224 -24.346917) (xy 310.61749 -24.34488) (xy 310.562647 -24.33475) (xy 310.509863 -24.316743)
			(xy 310.460263 -24.291242) (xy 310.414905 -24.258791) (xy 310.374756 -24.220082) (xy 310.34067 -24.175939)
			(xy 310.313374 -24.127304) (xy 310.293451 -24.075213) (xy 310.281325 -24.020776) (xy 310.277254 -23.965154)
			(xy 300.737725 -23.965154) (xy 300.735793 -23.965659) (xy 300.680356 -23.971759) (xy 300.624622 -23.969722)
			(xy 300.569779 -23.959592) (xy 300.516995 -23.941585) (xy 300.467395 -23.916084) (xy 300.422037 -23.883633)
			(xy 300.381888 -23.844924) (xy 300.347802 -23.800781) (xy 300.320506 -23.752146) (xy 300.300583 -23.700055)
			(xy 300.288457 -23.645618) (xy 300.284386 -23.589996) (xy 286.675634 -23.589996) (xy 286.724137 -23.595333)
			(xy 286.778094 -23.609439) (xy 286.829423 -23.631251) (xy 286.877029 -23.660305) (xy 286.919897 -23.69598)
			(xy 286.957114 -23.737517) (xy 286.987887 -23.78403) (xy 287.011559 -23.834527) (xy 287.027627 -23.887934)
			(xy 287.035747 -23.94311) (xy 287.036256 -23.970996) (xy 287.035747 -23.998882) (xy 287.027627 -24.054058)
			(xy 287.011559 -24.107465) (xy 286.987887 -24.157962) (xy 286.987734 -24.158194) (xy 291.650672 -24.158194)
			(xy 291.654743 -24.102572) (xy 291.666869 -24.048135) (xy 291.686792 -23.996044) (xy 291.714088 -23.947409)
			(xy 291.748174 -23.903266) (xy 291.788323 -23.864557) (xy 291.833681 -23.832106) (xy 291.883281 -23.806605)
			(xy 291.936065 -23.788598) (xy 291.990908 -23.778468) (xy 292.046642 -23.776431) (xy 292.102079 -23.782531)
			(xy 292.156036 -23.796637) (xy 292.207365 -23.818449) (xy 292.254971 -23.847503) (xy 292.297839 -23.883178)
			(xy 292.335056 -23.924715) (xy 292.365829 -23.971228) (xy 292.389501 -24.021725) (xy 292.405569 -24.075132)
			(xy 292.413689 -24.130308) (xy 292.414198 -24.158194) (xy 292.413689 -24.18608) (xy 292.41312 -24.189944)
			(xy 295.498772 -24.189944) (xy 295.502843 -24.134322) (xy 295.514969 -24.079885) (xy 295.534892 -24.027794)
			(xy 295.562188 -23.979159) (xy 295.596274 -23.935016) (xy 295.636423 -23.896307) (xy 295.681781 -23.863856)
			(xy 295.731381 -23.838355) (xy 295.784165 -23.820348) (xy 295.839008 -23.810218) (xy 295.894742 -23.808181)
			(xy 295.950179 -23.814281) (xy 296.004136 -23.828387) (xy 296.055465 -23.850199) (xy 296.103071 -23.879253)
			(xy 296.145939 -23.914928) (xy 296.183156 -23.956465) (xy 296.213929 -24.002978) (xy 296.237601 -24.053475)
			(xy 296.253669 -24.106882) (xy 296.261789 -24.162058) (xy 296.262298 -24.189944) (xy 298.021754 -24.189944)
			(xy 298.025825 -24.134322) (xy 298.037951 -24.079885) (xy 298.057874 -24.027794) (xy 298.08517 -23.979159)
			(xy 298.119256 -23.935016) (xy 298.159405 -23.896307) (xy 298.204763 -23.863856) (xy 298.254363 -23.838355)
			(xy 298.307147 -23.820348) (xy 298.36199 -23.810218) (xy 298.417724 -23.808181) (xy 298.473161 -23.814281)
			(xy 298.527118 -23.828387) (xy 298.578447 -23.850199) (xy 298.626053 -23.879253) (xy 298.668921 -23.914928)
			(xy 298.706138 -23.956465) (xy 298.736911 -24.002978) (xy 298.760583 -24.053475) (xy 298.776651 -24.106882)
			(xy 298.784771 -24.162058) (xy 298.78528 -24.189944) (xy 298.784771 -24.21783) (xy 298.776651 -24.273006)
			(xy 298.760583 -24.326413) (xy 298.736911 -24.37691) (xy 298.706138 -24.423423) (xy 298.668921 -24.46496)
			(xy 298.626053 -24.500635) (xy 298.578447 -24.529689) (xy 298.527118 -24.551501) (xy 298.473161 -24.565607)
			(xy 298.417724 -24.571707) (xy 298.36199 -24.56967) (xy 298.307147 -24.55954) (xy 298.254363 -24.541533)
			(xy 298.204763 -24.516032) (xy 298.159405 -24.483581) (xy 298.119256 -24.444872) (xy 298.08517 -24.400729)
			(xy 298.057874 -24.352094) (xy 298.037951 -24.300003) (xy 298.025825 -24.245566) (xy 298.021754 -24.189944)
			(xy 296.262298 -24.189944) (xy 296.261789 -24.21783) (xy 296.253669 -24.273006) (xy 296.237601 -24.326413)
			(xy 296.213929 -24.37691) (xy 296.183156 -24.423423) (xy 296.145939 -24.46496) (xy 296.103071 -24.500635)
			(xy 296.055465 -24.529689) (xy 296.004136 -24.551501) (xy 295.950179 -24.565607) (xy 295.894742 -24.571707)
			(xy 295.839008 -24.56967) (xy 295.784165 -24.55954) (xy 295.731381 -24.541533) (xy 295.681781 -24.516032)
			(xy 295.636423 -24.483581) (xy 295.596274 -24.444872) (xy 295.562188 -24.400729) (xy 295.534892 -24.352094)
			(xy 295.514969 -24.300003) (xy 295.502843 -24.245566) (xy 295.498772 -24.189944) (xy 292.41312 -24.189944)
			(xy 292.405569 -24.241256) (xy 292.389501 -24.294663) (xy 292.365829 -24.34516) (xy 292.335056 -24.391673)
			(xy 292.297839 -24.43321) (xy 292.254971 -24.468885) (xy 292.207365 -24.497939) (xy 292.156036 -24.519751)
			(xy 292.102079 -24.533857) (xy 292.046642 -24.539957) (xy 291.990908 -24.53792) (xy 291.936065 -24.52779)
			(xy 291.883281 -24.509783) (xy 291.833681 -24.484282) (xy 291.788323 -24.451831) (xy 291.748174 -24.413122)
			(xy 291.714088 -24.368979) (xy 291.686792 -24.320344) (xy 291.666869 -24.268253) (xy 291.654743 -24.213816)
			(xy 291.650672 -24.158194) (xy 286.987734 -24.158194) (xy 286.957114 -24.204475) (xy 286.919897 -24.246012)
			(xy 286.877029 -24.281687) (xy 286.829423 -24.310741) (xy 286.778094 -24.332553) (xy 286.724137 -24.346659)
			(xy 286.6687 -24.352759) (xy 286.612966 -24.350722) (xy 286.558123 -24.340592) (xy 286.505339 -24.322585)
			(xy 286.455739 -24.297084) (xy 286.410381 -24.264633) (xy 286.370232 -24.225924) (xy 286.336146 -24.181781)
			(xy 286.30885 -24.133146) (xy 286.288927 -24.081055) (xy 286.276801 -24.026618) (xy 286.27273 -23.970996)
			(xy 286.043438 -23.970996) (xy 286.043369 -23.974752) (xy 286.035249 -24.029928) (xy 286.019181 -24.083335)
			(xy 285.995509 -24.133832) (xy 285.964736 -24.180345) (xy 285.927519 -24.221882) (xy 285.884651 -24.257557)
			(xy 285.837045 -24.286611) (xy 285.785716 -24.308423) (xy 285.731759 -24.322529) (xy 285.676322 -24.328629)
			(xy 285.620588 -24.326592) (xy 285.565745 -24.316462) (xy 285.512961 -24.298455) (xy 285.463361 -24.272954)
			(xy 285.418003 -24.240503) (xy 285.377854 -24.201794) (xy 285.343768 -24.157651) (xy 285.316472 -24.109016)
			(xy 285.296549 -24.056925) (xy 285.284423 -24.002488) (xy 285.280352 -23.946866) (xy 285.040498 -23.946866)
			(xy 285.040832 -23.965154) (xy 285.040323 -23.99304) (xy 285.032203 -24.048216) (xy 285.016135 -24.101623)
			(xy 284.992463 -24.15212) (xy 284.96169 -24.198633) (xy 284.924473 -24.24017) (xy 284.881605 -24.275845)
			(xy 284.833999 -24.304899) (xy 284.78267 -24.326711) (xy 284.728713 -24.340817) (xy 284.673276 -24.346917)
			(xy 284.617542 -24.34488) (xy 284.562699 -24.33475) (xy 284.509915 -24.316743) (xy 284.460315 -24.291242)
			(xy 284.414957 -24.258791) (xy 284.374808 -24.220082) (xy 284.340722 -24.175939) (xy 284.313426 -24.127304)
			(xy 284.293503 -24.075213) (xy 284.281377 -24.020776) (xy 284.277306 -23.965154) (xy 274.737777 -23.965154)
			(xy 274.735845 -23.965659) (xy 274.680408 -23.971759) (xy 274.624674 -23.969722) (xy 274.569831 -23.959592)
			(xy 274.517047 -23.941585) (xy 274.467447 -23.916084) (xy 274.422089 -23.883633) (xy 274.38194 -23.844924)
			(xy 274.347854 -23.800781) (xy 274.320558 -23.752146) (xy 274.300635 -23.700055) (xy 274.288509 -23.645618)
			(xy 274.284438 -23.589996) (xy 260.675686 -23.589996) (xy 260.724189 -23.595333) (xy 260.778146 -23.609439)
			(xy 260.829475 -23.631251) (xy 260.877081 -23.660305) (xy 260.919949 -23.69598) (xy 260.957166 -23.737517)
			(xy 260.987939 -23.78403) (xy 261.011611 -23.834527) (xy 261.027679 -23.887934) (xy 261.035799 -23.94311)
			(xy 261.036308 -23.970996) (xy 261.035799 -23.998882) (xy 261.027679 -24.054058) (xy 261.011611 -24.107465)
			(xy 260.987939 -24.157962) (xy 260.987786 -24.158194) (xy 265.650724 -24.158194) (xy 265.654795 -24.102572)
			(xy 265.666921 -24.048135) (xy 265.686844 -23.996044) (xy 265.71414 -23.947409) (xy 265.748226 -23.903266)
			(xy 265.788375 -23.864557) (xy 265.833733 -23.832106) (xy 265.883333 -23.806605) (xy 265.936117 -23.788598)
			(xy 265.99096 -23.778468) (xy 266.046694 -23.776431) (xy 266.102131 -23.782531) (xy 266.156088 -23.796637)
			(xy 266.207417 -23.818449) (xy 266.255023 -23.847503) (xy 266.297891 -23.883178) (xy 266.335108 -23.924715)
			(xy 266.365881 -23.971228) (xy 266.389553 -24.021725) (xy 266.405621 -24.075132) (xy 266.413741 -24.130308)
			(xy 266.41425 -24.158194) (xy 266.413741 -24.18608) (xy 266.413172 -24.189944) (xy 269.498824 -24.189944)
			(xy 269.502895 -24.134322) (xy 269.515021 -24.079885) (xy 269.534944 -24.027794) (xy 269.56224 -23.979159)
			(xy 269.596326 -23.935016) (xy 269.636475 -23.896307) (xy 269.681833 -23.863856) (xy 269.731433 -23.838355)
			(xy 269.784217 -23.820348) (xy 269.83906 -23.810218) (xy 269.894794 -23.808181) (xy 269.950231 -23.814281)
			(xy 270.004188 -23.828387) (xy 270.055517 -23.850199) (xy 270.103123 -23.879253) (xy 270.145991 -23.914928)
			(xy 270.183208 -23.956465) (xy 270.213981 -24.002978) (xy 270.237653 -24.053475) (xy 270.253721 -24.106882)
			(xy 270.261841 -24.162058) (xy 270.26235 -24.189944) (xy 272.021806 -24.189944) (xy 272.025877 -24.134322)
			(xy 272.038003 -24.079885) (xy 272.057926 -24.027794) (xy 272.085222 -23.979159) (xy 272.119308 -23.935016)
			(xy 272.159457 -23.896307) (xy 272.204815 -23.863856) (xy 272.254415 -23.838355) (xy 272.307199 -23.820348)
			(xy 272.362042 -23.810218) (xy 272.417776 -23.808181) (xy 272.473213 -23.814281) (xy 272.52717 -23.828387)
			(xy 272.578499 -23.850199) (xy 272.626105 -23.879253) (xy 272.668973 -23.914928) (xy 272.70619 -23.956465)
			(xy 272.736963 -24.002978) (xy 272.760635 -24.053475) (xy 272.776703 -24.106882) (xy 272.784823 -24.162058)
			(xy 272.785332 -24.189944) (xy 272.784823 -24.21783) (xy 272.776703 -24.273006) (xy 272.760635 -24.326413)
			(xy 272.736963 -24.37691) (xy 272.70619 -24.423423) (xy 272.668973 -24.46496) (xy 272.626105 -24.500635)
			(xy 272.578499 -24.529689) (xy 272.52717 -24.551501) (xy 272.473213 -24.565607) (xy 272.417776 -24.571707)
			(xy 272.362042 -24.56967) (xy 272.307199 -24.55954) (xy 272.254415 -24.541533) (xy 272.204815 -24.516032)
			(xy 272.159457 -24.483581) (xy 272.119308 -24.444872) (xy 272.085222 -24.400729) (xy 272.057926 -24.352094)
			(xy 272.038003 -24.300003) (xy 272.025877 -24.245566) (xy 272.021806 -24.189944) (xy 270.26235 -24.189944)
			(xy 270.261841 -24.21783) (xy 270.253721 -24.273006) (xy 270.237653 -24.326413) (xy 270.213981 -24.37691)
			(xy 270.183208 -24.423423) (xy 270.145991 -24.46496) (xy 270.103123 -24.500635) (xy 270.055517 -24.529689)
			(xy 270.004188 -24.551501) (xy 269.950231 -24.565607) (xy 269.894794 -24.571707) (xy 269.83906 -24.56967)
			(xy 269.784217 -24.55954) (xy 269.731433 -24.541533) (xy 269.681833 -24.516032) (xy 269.636475 -24.483581)
			(xy 269.596326 -24.444872) (xy 269.56224 -24.400729) (xy 269.534944 -24.352094) (xy 269.515021 -24.300003)
			(xy 269.502895 -24.245566) (xy 269.498824 -24.189944) (xy 266.413172 -24.189944) (xy 266.405621 -24.241256)
			(xy 266.389553 -24.294663) (xy 266.365881 -24.34516) (xy 266.335108 -24.391673) (xy 266.297891 -24.43321)
			(xy 266.255023 -24.468885) (xy 266.207417 -24.497939) (xy 266.156088 -24.519751) (xy 266.102131 -24.533857)
			(xy 266.046694 -24.539957) (xy 265.99096 -24.53792) (xy 265.936117 -24.52779) (xy 265.883333 -24.509783)
			(xy 265.833733 -24.484282) (xy 265.788375 -24.451831) (xy 265.748226 -24.413122) (xy 265.71414 -24.368979)
			(xy 265.686844 -24.320344) (xy 265.666921 -24.268253) (xy 265.654795 -24.213816) (xy 265.650724 -24.158194)
			(xy 260.987786 -24.158194) (xy 260.957166 -24.204475) (xy 260.919949 -24.246012) (xy 260.877081 -24.281687)
			(xy 260.829475 -24.310741) (xy 260.778146 -24.332553) (xy 260.724189 -24.346659) (xy 260.668752 -24.352759)
			(xy 260.613018 -24.350722) (xy 260.558175 -24.340592) (xy 260.505391 -24.322585) (xy 260.455791 -24.297084)
			(xy 260.410433 -24.264633) (xy 260.370284 -24.225924) (xy 260.336198 -24.181781) (xy 260.308902 -24.133146)
			(xy 260.288979 -24.081055) (xy 260.276853 -24.026618) (xy 260.272782 -23.970996) (xy 260.04349 -23.970996)
			(xy 260.043421 -23.974752) (xy 260.035301 -24.029928) (xy 260.019233 -24.083335) (xy 259.995561 -24.133832)
			(xy 259.964788 -24.180345) (xy 259.927571 -24.221882) (xy 259.884703 -24.257557) (xy 259.837097 -24.286611)
			(xy 259.785768 -24.308423) (xy 259.731811 -24.322529) (xy 259.676374 -24.328629) (xy 259.62064 -24.326592)
			(xy 259.565797 -24.316462) (xy 259.513013 -24.298455) (xy 259.463413 -24.272954) (xy 259.418055 -24.240503)
			(xy 259.377906 -24.201794) (xy 259.34382 -24.157651) (xy 259.316524 -24.109016) (xy 259.296601 -24.056925)
			(xy 259.284475 -24.002488) (xy 259.280404 -23.946866) (xy 259.04055 -23.946866) (xy 259.040884 -23.965154)
			(xy 259.040375 -23.99304) (xy 259.032255 -24.048216) (xy 259.016187 -24.101623) (xy 258.992515 -24.15212)
			(xy 258.961742 -24.198633) (xy 258.924525 -24.24017) (xy 258.881657 -24.275845) (xy 258.834051 -24.304899)
			(xy 258.782722 -24.326711) (xy 258.728765 -24.340817) (xy 258.673328 -24.346917) (xy 258.617594 -24.34488)
			(xy 258.562751 -24.33475) (xy 258.509967 -24.316743) (xy 258.460367 -24.291242) (xy 258.415009 -24.258791)
			(xy 258.37486 -24.220082) (xy 258.340774 -24.175939) (xy 258.313478 -24.127304) (xy 258.293555 -24.075213)
			(xy 258.281429 -24.020776) (xy 258.277358 -23.965154) (xy 248.737829 -23.965154) (xy 248.735897 -23.965659)
			(xy 248.68046 -23.971759) (xy 248.624726 -23.969722) (xy 248.569883 -23.959592) (xy 248.517099 -23.941585)
			(xy 248.467499 -23.916084) (xy 248.422141 -23.883633) (xy 248.381992 -23.844924) (xy 248.347906 -23.800781)
			(xy 248.32061 -23.752146) (xy 248.300687 -23.700055) (xy 248.288561 -23.645618) (xy 248.28449 -23.589996)
			(xy 222.575686 -23.589996) (xy 222.624189 -23.595333) (xy 222.678146 -23.609439) (xy 222.729475 -23.631251)
			(xy 222.777081 -23.660305) (xy 222.819949 -23.69598) (xy 222.857166 -23.737517) (xy 222.887939 -23.78403)
			(xy 222.911611 -23.834527) (xy 222.927679 -23.887934) (xy 222.935799 -23.94311) (xy 222.936308 -23.970996)
			(xy 222.935799 -23.998882) (xy 222.927679 -24.054058) (xy 222.911611 -24.107465) (xy 222.887939 -24.157962)
			(xy 222.887786 -24.158194) (xy 239.650776 -24.158194) (xy 239.654847 -24.102572) (xy 239.666973 -24.048135)
			(xy 239.686896 -23.996044) (xy 239.714192 -23.947409) (xy 239.748278 -23.903266) (xy 239.788427 -23.864557)
			(xy 239.833785 -23.832106) (xy 239.883385 -23.806605) (xy 239.936169 -23.788598) (xy 239.991012 -23.778468)
			(xy 240.046746 -23.776431) (xy 240.102183 -23.782531) (xy 240.15614 -23.796637) (xy 240.207469 -23.818449)
			(xy 240.255075 -23.847503) (xy 240.297943 -23.883178) (xy 240.33516 -23.924715) (xy 240.365933 -23.971228)
			(xy 240.389605 -24.021725) (xy 240.405673 -24.075132) (xy 240.413793 -24.130308) (xy 240.414302 -24.158194)
			(xy 240.413793 -24.18608) (xy 240.413224 -24.189944) (xy 243.498876 -24.189944) (xy 243.502947 -24.134322)
			(xy 243.515073 -24.079885) (xy 243.534996 -24.027794) (xy 243.562292 -23.979159) (xy 243.596378 -23.935016)
			(xy 243.636527 -23.896307) (xy 243.681885 -23.863856) (xy 243.731485 -23.838355) (xy 243.784269 -23.820348)
			(xy 243.839112 -23.810218) (xy 243.894846 -23.808181) (xy 243.950283 -23.814281) (xy 244.00424 -23.828387)
			(xy 244.055569 -23.850199) (xy 244.103175 -23.879253) (xy 244.146043 -23.914928) (xy 244.18326 -23.956465)
			(xy 244.214033 -24.002978) (xy 244.237705 -24.053475) (xy 244.253773 -24.106882) (xy 244.261893 -24.162058)
			(xy 244.262402 -24.189944) (xy 246.021858 -24.189944) (xy 246.025929 -24.134322) (xy 246.038055 -24.079885)
			(xy 246.057978 -24.027794) (xy 246.085274 -23.979159) (xy 246.11936 -23.935016) (xy 246.159509 -23.896307)
			(xy 246.204867 -23.863856) (xy 246.254467 -23.838355) (xy 246.307251 -23.820348) (xy 246.362094 -23.810218)
			(xy 246.417828 -23.808181) (xy 246.473265 -23.814281) (xy 246.527222 -23.828387) (xy 246.578551 -23.850199)
			(xy 246.626157 -23.879253) (xy 246.669025 -23.914928) (xy 246.706242 -23.956465) (xy 246.737015 -24.002978)
			(xy 246.760687 -24.053475) (xy 246.776755 -24.106882) (xy 246.784875 -24.162058) (xy 246.785384 -24.189944)
			(xy 246.784875 -24.21783) (xy 246.776755 -24.273006) (xy 246.760687 -24.326413) (xy 246.737015 -24.37691)
			(xy 246.706242 -24.423423) (xy 246.669025 -24.46496) (xy 246.626157 -24.500635) (xy 246.578551 -24.529689)
			(xy 246.527222 -24.551501) (xy 246.473265 -24.565607) (xy 246.417828 -24.571707) (xy 246.362094 -24.56967)
			(xy 246.307251 -24.55954) (xy 246.254467 -24.541533) (xy 246.204867 -24.516032) (xy 246.159509 -24.483581)
			(xy 246.11936 -24.444872) (xy 246.085274 -24.400729) (xy 246.057978 -24.352094) (xy 246.038055 -24.300003)
			(xy 246.025929 -24.245566) (xy 246.021858 -24.189944) (xy 244.262402 -24.189944) (xy 244.261893 -24.21783)
			(xy 244.253773 -24.273006) (xy 244.237705 -24.326413) (xy 244.214033 -24.37691) (xy 244.18326 -24.423423)
			(xy 244.146043 -24.46496) (xy 244.103175 -24.500635) (xy 244.055569 -24.529689) (xy 244.00424 -24.551501)
			(xy 243.950283 -24.565607) (xy 243.894846 -24.571707) (xy 243.839112 -24.56967) (xy 243.784269 -24.55954)
			(xy 243.731485 -24.541533) (xy 243.681885 -24.516032) (xy 243.636527 -24.483581) (xy 243.596378 -24.444872)
			(xy 243.562292 -24.400729) (xy 243.534996 -24.352094) (xy 243.515073 -24.300003) (xy 243.502947 -24.245566)
			(xy 243.498876 -24.189944) (xy 240.413224 -24.189944) (xy 240.405673 -24.241256) (xy 240.389605 -24.294663)
			(xy 240.365933 -24.34516) (xy 240.33516 -24.391673) (xy 240.297943 -24.43321) (xy 240.255075 -24.468885)
			(xy 240.207469 -24.497939) (xy 240.15614 -24.519751) (xy 240.102183 -24.533857) (xy 240.046746 -24.539957)
			(xy 239.991012 -24.53792) (xy 239.936169 -24.52779) (xy 239.883385 -24.509783) (xy 239.833785 -24.484282)
			(xy 239.788427 -24.451831) (xy 239.748278 -24.413122) (xy 239.714192 -24.368979) (xy 239.686896 -24.320344)
			(xy 239.666973 -24.268253) (xy 239.654847 -24.213816) (xy 239.650776 -24.158194) (xy 222.887786 -24.158194)
			(xy 222.857166 -24.204475) (xy 222.819949 -24.246012) (xy 222.777081 -24.281687) (xy 222.729475 -24.310741)
			(xy 222.678146 -24.332553) (xy 222.624189 -24.346659) (xy 222.568752 -24.352759) (xy 222.513018 -24.350722)
			(xy 222.458175 -24.340592) (xy 222.405391 -24.322585) (xy 222.355791 -24.297084) (xy 222.310433 -24.264633)
			(xy 222.270284 -24.225924) (xy 222.236198 -24.181781) (xy 222.208902 -24.133146) (xy 222.188979 -24.081055)
			(xy 222.176853 -24.026618) (xy 222.172782 -23.970996) (xy 221.94349 -23.970996) (xy 221.943421 -23.974752)
			(xy 221.935301 -24.029928) (xy 221.919233 -24.083335) (xy 221.895561 -24.133832) (xy 221.864788 -24.180345)
			(xy 221.827571 -24.221882) (xy 221.784703 -24.257557) (xy 221.737097 -24.286611) (xy 221.685768 -24.308423)
			(xy 221.631811 -24.322529) (xy 221.576374 -24.328629) (xy 221.52064 -24.326592) (xy 221.465797 -24.316462)
			(xy 221.413013 -24.298455) (xy 221.363413 -24.272954) (xy 221.318055 -24.240503) (xy 221.277906 -24.201794)
			(xy 221.24382 -24.157651) (xy 221.216524 -24.109016) (xy 221.196601 -24.056925) (xy 221.184475 -24.002488)
			(xy 221.180404 -23.946866) (xy 220.94055 -23.946866) (xy 220.940884 -23.965154) (xy 220.940375 -23.99304)
			(xy 220.932255 -24.048216) (xy 220.916187 -24.101623) (xy 220.892515 -24.15212) (xy 220.861742 -24.198633)
			(xy 220.824525 -24.24017) (xy 220.781657 -24.275845) (xy 220.734051 -24.304899) (xy 220.682722 -24.326711)
			(xy 220.628765 -24.340817) (xy 220.573328 -24.346917) (xy 220.517594 -24.34488) (xy 220.462751 -24.33475)
			(xy 220.409967 -24.316743) (xy 220.360367 -24.291242) (xy 220.315009 -24.258791) (xy 220.27486 -24.220082)
			(xy 220.240774 -24.175939) (xy 220.213478 -24.127304) (xy 220.193555 -24.075213) (xy 220.181429 -24.020776)
			(xy 220.177358 -23.965154) (xy 210.637829 -23.965154) (xy 210.635897 -23.965659) (xy 210.58046 -23.971759)
			(xy 210.524726 -23.969722) (xy 210.469883 -23.959592) (xy 210.417099 -23.941585) (xy 210.367499 -23.916084)
			(xy 210.322141 -23.883633) (xy 210.281992 -23.844924) (xy 210.247906 -23.800781) (xy 210.22061 -23.752146)
			(xy 210.200687 -23.700055) (xy 210.188561 -23.645618) (xy 210.18449 -23.589996) (xy 196.575738 -23.589996)
			(xy 196.624241 -23.595333) (xy 196.678198 -23.609439) (xy 196.729527 -23.631251) (xy 196.777133 -23.660305)
			(xy 196.820001 -23.69598) (xy 196.857218 -23.737517) (xy 196.887991 -23.78403) (xy 196.911663 -23.834527)
			(xy 196.927731 -23.887934) (xy 196.935851 -23.94311) (xy 196.93636 -23.970996) (xy 196.935851 -23.998882)
			(xy 196.927731 -24.054058) (xy 196.911663 -24.107465) (xy 196.887991 -24.157962) (xy 196.887838 -24.158194)
			(xy 201.550776 -24.158194) (xy 201.554847 -24.102572) (xy 201.566973 -24.048135) (xy 201.586896 -23.996044)
			(xy 201.614192 -23.947409) (xy 201.648278 -23.903266) (xy 201.688427 -23.864557) (xy 201.733785 -23.832106)
			(xy 201.783385 -23.806605) (xy 201.836169 -23.788598) (xy 201.891012 -23.778468) (xy 201.946746 -23.776431)
			(xy 202.002183 -23.782531) (xy 202.05614 -23.796637) (xy 202.107469 -23.818449) (xy 202.155075 -23.847503)
			(xy 202.197943 -23.883178) (xy 202.23516 -23.924715) (xy 202.265933 -23.971228) (xy 202.289605 -24.021725)
			(xy 202.305673 -24.075132) (xy 202.313793 -24.130308) (xy 202.314302 -24.158194) (xy 202.313793 -24.18608)
			(xy 202.313224 -24.189944) (xy 205.398876 -24.189944) (xy 205.402947 -24.134322) (xy 205.415073 -24.079885)
			(xy 205.434996 -24.027794) (xy 205.462292 -23.979159) (xy 205.496378 -23.935016) (xy 205.536527 -23.896307)
			(xy 205.581885 -23.863856) (xy 205.631485 -23.838355) (xy 205.684269 -23.820348) (xy 205.739112 -23.810218)
			(xy 205.794846 -23.808181) (xy 205.850283 -23.814281) (xy 205.90424 -23.828387) (xy 205.955569 -23.850199)
			(xy 206.003175 -23.879253) (xy 206.046043 -23.914928) (xy 206.08326 -23.956465) (xy 206.114033 -24.002978)
			(xy 206.137705 -24.053475) (xy 206.153773 -24.106882) (xy 206.161893 -24.162058) (xy 206.162402 -24.189944)
			(xy 207.921858 -24.189944) (xy 207.925929 -24.134322) (xy 207.938055 -24.079885) (xy 207.957978 -24.027794)
			(xy 207.985274 -23.979159) (xy 208.01936 -23.935016) (xy 208.059509 -23.896307) (xy 208.104867 -23.863856)
			(xy 208.154467 -23.838355) (xy 208.207251 -23.820348) (xy 208.262094 -23.810218) (xy 208.317828 -23.808181)
			(xy 208.373265 -23.814281) (xy 208.427222 -23.828387) (xy 208.478551 -23.850199) (xy 208.526157 -23.879253)
			(xy 208.569025 -23.914928) (xy 208.606242 -23.956465) (xy 208.637015 -24.002978) (xy 208.660687 -24.053475)
			(xy 208.676755 -24.106882) (xy 208.684875 -24.162058) (xy 208.685384 -24.189944) (xy 208.684875 -24.21783)
			(xy 208.676755 -24.273006) (xy 208.660687 -24.326413) (xy 208.637015 -24.37691) (xy 208.606242 -24.423423)
			(xy 208.569025 -24.46496) (xy 208.526157 -24.500635) (xy 208.478551 -24.529689) (xy 208.427222 -24.551501)
			(xy 208.373265 -24.565607) (xy 208.317828 -24.571707) (xy 208.262094 -24.56967) (xy 208.207251 -24.55954)
			(xy 208.154467 -24.541533) (xy 208.104867 -24.516032) (xy 208.059509 -24.483581) (xy 208.01936 -24.444872)
			(xy 207.985274 -24.400729) (xy 207.957978 -24.352094) (xy 207.938055 -24.300003) (xy 207.925929 -24.245566)
			(xy 207.921858 -24.189944) (xy 206.162402 -24.189944) (xy 206.161893 -24.21783) (xy 206.153773 -24.273006)
			(xy 206.137705 -24.326413) (xy 206.114033 -24.37691) (xy 206.08326 -24.423423) (xy 206.046043 -24.46496)
			(xy 206.003175 -24.500635) (xy 205.955569 -24.529689) (xy 205.90424 -24.551501) (xy 205.850283 -24.565607)
			(xy 205.794846 -24.571707) (xy 205.739112 -24.56967) (xy 205.684269 -24.55954) (xy 205.631485 -24.541533)
			(xy 205.581885 -24.516032) (xy 205.536527 -24.483581) (xy 205.496378 -24.444872) (xy 205.462292 -24.400729)
			(xy 205.434996 -24.352094) (xy 205.415073 -24.300003) (xy 205.402947 -24.245566) (xy 205.398876 -24.189944)
			(xy 202.313224 -24.189944) (xy 202.305673 -24.241256) (xy 202.289605 -24.294663) (xy 202.265933 -24.34516)
			(xy 202.23516 -24.391673) (xy 202.197943 -24.43321) (xy 202.155075 -24.468885) (xy 202.107469 -24.497939)
			(xy 202.05614 -24.519751) (xy 202.002183 -24.533857) (xy 201.946746 -24.539957) (xy 201.891012 -24.53792)
			(xy 201.836169 -24.52779) (xy 201.783385 -24.509783) (xy 201.733785 -24.484282) (xy 201.688427 -24.451831)
			(xy 201.648278 -24.413122) (xy 201.614192 -24.368979) (xy 201.586896 -24.320344) (xy 201.566973 -24.268253)
			(xy 201.554847 -24.213816) (xy 201.550776 -24.158194) (xy 196.887838 -24.158194) (xy 196.857218 -24.204475)
			(xy 196.820001 -24.246012) (xy 196.777133 -24.281687) (xy 196.729527 -24.310741) (xy 196.678198 -24.332553)
			(xy 196.624241 -24.346659) (xy 196.568804 -24.352759) (xy 196.51307 -24.350722) (xy 196.458227 -24.340592)
			(xy 196.405443 -24.322585) (xy 196.355843 -24.297084) (xy 196.310485 -24.264633) (xy 196.270336 -24.225924)
			(xy 196.23625 -24.181781) (xy 196.208954 -24.133146) (xy 196.189031 -24.081055) (xy 196.176905 -24.026618)
			(xy 196.172834 -23.970996) (xy 195.943542 -23.970996) (xy 195.943473 -23.974752) (xy 195.935353 -24.029928)
			(xy 195.919285 -24.083335) (xy 195.895613 -24.133832) (xy 195.86484 -24.180345) (xy 195.827623 -24.221882)
			(xy 195.784755 -24.257557) (xy 195.737149 -24.286611) (xy 195.68582 -24.308423) (xy 195.631863 -24.322529)
			(xy 195.576426 -24.328629) (xy 195.520692 -24.326592) (xy 195.465849 -24.316462) (xy 195.413065 -24.298455)
			(xy 195.363465 -24.272954) (xy 195.318107 -24.240503) (xy 195.277958 -24.201794) (xy 195.243872 -24.157651)
			(xy 195.216576 -24.109016) (xy 195.196653 -24.056925) (xy 195.184527 -24.002488) (xy 195.180456 -23.946866)
			(xy 194.940602 -23.946866) (xy 194.940936 -23.965154) (xy 194.940427 -23.99304) (xy 194.932307 -24.048216)
			(xy 194.916239 -24.101623) (xy 194.892567 -24.15212) (xy 194.861794 -24.198633) (xy 194.824577 -24.24017)
			(xy 194.781709 -24.275845) (xy 194.734103 -24.304899) (xy 194.682774 -24.326711) (xy 194.628817 -24.340817)
			(xy 194.57338 -24.346917) (xy 194.517646 -24.34488) (xy 194.462803 -24.33475) (xy 194.410019 -24.316743)
			(xy 194.360419 -24.291242) (xy 194.315061 -24.258791) (xy 194.274912 -24.220082) (xy 194.240826 -24.175939)
			(xy 194.21353 -24.127304) (xy 194.193607 -24.075213) (xy 194.181481 -24.020776) (xy 194.17741 -23.965154)
			(xy 184.637881 -23.965154) (xy 184.635949 -23.965659) (xy 184.580512 -23.971759) (xy 184.524778 -23.969722)
			(xy 184.469935 -23.959592) (xy 184.417151 -23.941585) (xy 184.367551 -23.916084) (xy 184.322193 -23.883633)
			(xy 184.282044 -23.844924) (xy 184.247958 -23.800781) (xy 184.220662 -23.752146) (xy 184.200739 -23.700055)
			(xy 184.188613 -23.645618) (xy 184.184542 -23.589996) (xy 170.57579 -23.589996) (xy 170.624293 -23.595333)
			(xy 170.67825 -23.609439) (xy 170.729579 -23.631251) (xy 170.777185 -23.660305) (xy 170.820053 -23.69598)
			(xy 170.85727 -23.737517) (xy 170.888043 -23.78403) (xy 170.911715 -23.834527) (xy 170.927783 -23.887934)
			(xy 170.935903 -23.94311) (xy 170.936412 -23.970996) (xy 170.935903 -23.998882) (xy 170.927783 -24.054058)
			(xy 170.911715 -24.107465) (xy 170.888043 -24.157962) (xy 170.88789 -24.158194) (xy 175.550828 -24.158194)
			(xy 175.554899 -24.102572) (xy 175.567025 -24.048135) (xy 175.586948 -23.996044) (xy 175.614244 -23.947409)
			(xy 175.64833 -23.903266) (xy 175.688479 -23.864557) (xy 175.733837 -23.832106) (xy 175.783437 -23.806605)
			(xy 175.836221 -23.788598) (xy 175.891064 -23.778468) (xy 175.946798 -23.776431) (xy 176.002235 -23.782531)
			(xy 176.056192 -23.796637) (xy 176.107521 -23.818449) (xy 176.155127 -23.847503) (xy 176.197995 -23.883178)
			(xy 176.235212 -23.924715) (xy 176.265985 -23.971228) (xy 176.289657 -24.021725) (xy 176.305725 -24.075132)
			(xy 176.313845 -24.130308) (xy 176.314354 -24.158194) (xy 176.313845 -24.18608) (xy 176.313276 -24.189944)
			(xy 179.398928 -24.189944) (xy 179.402999 -24.134322) (xy 179.415125 -24.079885) (xy 179.435048 -24.027794)
			(xy 179.462344 -23.979159) (xy 179.49643 -23.935016) (xy 179.536579 -23.896307) (xy 179.581937 -23.863856)
			(xy 179.631537 -23.838355) (xy 179.684321 -23.820348) (xy 179.739164 -23.810218) (xy 179.794898 -23.808181)
			(xy 179.850335 -23.814281) (xy 179.904292 -23.828387) (xy 179.955621 -23.850199) (xy 180.003227 -23.879253)
			(xy 180.046095 -23.914928) (xy 180.083312 -23.956465) (xy 180.114085 -24.002978) (xy 180.137757 -24.053475)
			(xy 180.153825 -24.106882) (xy 180.161945 -24.162058) (xy 180.162454 -24.189944) (xy 181.92191 -24.189944)
			(xy 181.925981 -24.134322) (xy 181.938107 -24.079885) (xy 181.95803 -24.027794) (xy 181.985326 -23.979159)
			(xy 182.019412 -23.935016) (xy 182.059561 -23.896307) (xy 182.104919 -23.863856) (xy 182.154519 -23.838355)
			(xy 182.207303 -23.820348) (xy 182.262146 -23.810218) (xy 182.31788 -23.808181) (xy 182.373317 -23.814281)
			(xy 182.427274 -23.828387) (xy 182.478603 -23.850199) (xy 182.526209 -23.879253) (xy 182.569077 -23.914928)
			(xy 182.606294 -23.956465) (xy 182.637067 -24.002978) (xy 182.660739 -24.053475) (xy 182.676807 -24.106882)
			(xy 182.684927 -24.162058) (xy 182.685436 -24.189944) (xy 182.684927 -24.21783) (xy 182.676807 -24.273006)
			(xy 182.660739 -24.326413) (xy 182.637067 -24.37691) (xy 182.606294 -24.423423) (xy 182.569077 -24.46496)
			(xy 182.526209 -24.500635) (xy 182.478603 -24.529689) (xy 182.427274 -24.551501) (xy 182.373317 -24.565607)
			(xy 182.31788 -24.571707) (xy 182.262146 -24.56967) (xy 182.207303 -24.55954) (xy 182.154519 -24.541533)
			(xy 182.104919 -24.516032) (xy 182.059561 -24.483581) (xy 182.019412 -24.444872) (xy 181.985326 -24.400729)
			(xy 181.95803 -24.352094) (xy 181.938107 -24.300003) (xy 181.925981 -24.245566) (xy 181.92191 -24.189944)
			(xy 180.162454 -24.189944) (xy 180.161945 -24.21783) (xy 180.153825 -24.273006) (xy 180.137757 -24.326413)
			(xy 180.114085 -24.37691) (xy 180.083312 -24.423423) (xy 180.046095 -24.46496) (xy 180.003227 -24.500635)
			(xy 179.955621 -24.529689) (xy 179.904292 -24.551501) (xy 179.850335 -24.565607) (xy 179.794898 -24.571707)
			(xy 179.739164 -24.56967) (xy 179.684321 -24.55954) (xy 179.631537 -24.541533) (xy 179.581937 -24.516032)
			(xy 179.536579 -24.483581) (xy 179.49643 -24.444872) (xy 179.462344 -24.400729) (xy 179.435048 -24.352094)
			(xy 179.415125 -24.300003) (xy 179.402999 -24.245566) (xy 179.398928 -24.189944) (xy 176.313276 -24.189944)
			(xy 176.305725 -24.241256) (xy 176.289657 -24.294663) (xy 176.265985 -24.34516) (xy 176.235212 -24.391673)
			(xy 176.197995 -24.43321) (xy 176.155127 -24.468885) (xy 176.107521 -24.497939) (xy 176.056192 -24.519751)
			(xy 176.002235 -24.533857) (xy 175.946798 -24.539957) (xy 175.891064 -24.53792) (xy 175.836221 -24.52779)
			(xy 175.783437 -24.509783) (xy 175.733837 -24.484282) (xy 175.688479 -24.451831) (xy 175.64833 -24.413122)
			(xy 175.614244 -24.368979) (xy 175.586948 -24.320344) (xy 175.567025 -24.268253) (xy 175.554899 -24.213816)
			(xy 175.550828 -24.158194) (xy 170.88789 -24.158194) (xy 170.85727 -24.204475) (xy 170.820053 -24.246012)
			(xy 170.777185 -24.281687) (xy 170.729579 -24.310741) (xy 170.67825 -24.332553) (xy 170.624293 -24.346659)
			(xy 170.568856 -24.352759) (xy 170.513122 -24.350722) (xy 170.458279 -24.340592) (xy 170.405495 -24.322585)
			(xy 170.355895 -24.297084) (xy 170.310537 -24.264633) (xy 170.270388 -24.225924) (xy 170.236302 -24.181781)
			(xy 170.209006 -24.133146) (xy 170.189083 -24.081055) (xy 170.176957 -24.026618) (xy 170.172886 -23.970996)
			(xy 169.943594 -23.970996) (xy 169.943525 -23.974752) (xy 169.935405 -24.029928) (xy 169.919337 -24.083335)
			(xy 169.895665 -24.133832) (xy 169.864892 -24.180345) (xy 169.827675 -24.221882) (xy 169.784807 -24.257557)
			(xy 169.737201 -24.286611) (xy 169.685872 -24.308423) (xy 169.631915 -24.322529) (xy 169.576478 -24.328629)
			(xy 169.520744 -24.326592) (xy 169.465901 -24.316462) (xy 169.413117 -24.298455) (xy 169.363517 -24.272954)
			(xy 169.318159 -24.240503) (xy 169.27801 -24.201794) (xy 169.243924 -24.157651) (xy 169.216628 -24.109016)
			(xy 169.196705 -24.056925) (xy 169.184579 -24.002488) (xy 169.180508 -23.946866) (xy 168.940654 -23.946866)
			(xy 168.940988 -23.965154) (xy 168.940479 -23.99304) (xy 168.932359 -24.048216) (xy 168.916291 -24.101623)
			(xy 168.892619 -24.15212) (xy 168.861846 -24.198633) (xy 168.824629 -24.24017) (xy 168.781761 -24.275845)
			(xy 168.734155 -24.304899) (xy 168.682826 -24.326711) (xy 168.628869 -24.340817) (xy 168.573432 -24.346917)
			(xy 168.517698 -24.34488) (xy 168.462855 -24.33475) (xy 168.410071 -24.316743) (xy 168.360471 -24.291242)
			(xy 168.315113 -24.258791) (xy 168.274964 -24.220082) (xy 168.240878 -24.175939) (xy 168.213582 -24.127304)
			(xy 168.193659 -24.075213) (xy 168.181533 -24.020776) (xy 168.177462 -23.965154) (xy 158.637933 -23.965154)
			(xy 158.636001 -23.965659) (xy 158.580564 -23.971759) (xy 158.52483 -23.969722) (xy 158.469987 -23.959592)
			(xy 158.417203 -23.941585) (xy 158.367603 -23.916084) (xy 158.322245 -23.883633) (xy 158.282096 -23.844924)
			(xy 158.24801 -23.800781) (xy 158.220714 -23.752146) (xy 158.200791 -23.700055) (xy 158.188665 -23.645618)
			(xy 158.184594 -23.589996) (xy 144.575842 -23.589996) (xy 144.624345 -23.595333) (xy 144.678302 -23.609439)
			(xy 144.729631 -23.631251) (xy 144.777237 -23.660305) (xy 144.820105 -23.69598) (xy 144.857322 -23.737517)
			(xy 144.888095 -23.78403) (xy 144.911767 -23.834527) (xy 144.927835 -23.887934) (xy 144.935955 -23.94311)
			(xy 144.936464 -23.970996) (xy 144.935955 -23.998882) (xy 144.927835 -24.054058) (xy 144.911767 -24.107465)
			(xy 144.888095 -24.157962) (xy 144.887942 -24.158194) (xy 149.55088 -24.158194) (xy 149.554951 -24.102572)
			(xy 149.567077 -24.048135) (xy 149.587 -23.996044) (xy 149.614296 -23.947409) (xy 149.648382 -23.903266)
			(xy 149.688531 -23.864557) (xy 149.733889 -23.832106) (xy 149.783489 -23.806605) (xy 149.836273 -23.788598)
			(xy 149.891116 -23.778468) (xy 149.94685 -23.776431) (xy 150.002287 -23.782531) (xy 150.056244 -23.796637)
			(xy 150.107573 -23.818449) (xy 150.155179 -23.847503) (xy 150.198047 -23.883178) (xy 150.235264 -23.924715)
			(xy 150.266037 -23.971228) (xy 150.289709 -24.021725) (xy 150.305777 -24.075132) (xy 150.313897 -24.130308)
			(xy 150.314406 -24.158194) (xy 150.313897 -24.18608) (xy 150.313328 -24.189944) (xy 153.39898 -24.189944)
			(xy 153.403051 -24.134322) (xy 153.415177 -24.079885) (xy 153.4351 -24.027794) (xy 153.462396 -23.979159)
			(xy 153.496482 -23.935016) (xy 153.536631 -23.896307) (xy 153.581989 -23.863856) (xy 153.631589 -23.838355)
			(xy 153.684373 -23.820348) (xy 153.739216 -23.810218) (xy 153.79495 -23.808181) (xy 153.850387 -23.814281)
			(xy 153.904344 -23.828387) (xy 153.955673 -23.850199) (xy 154.003279 -23.879253) (xy 154.046147 -23.914928)
			(xy 154.083364 -23.956465) (xy 154.114137 -24.002978) (xy 154.137809 -24.053475) (xy 154.153877 -24.106882)
			(xy 154.161997 -24.162058) (xy 154.162506 -24.189944) (xy 155.921962 -24.189944) (xy 155.926033 -24.134322)
			(xy 155.938159 -24.079885) (xy 155.958082 -24.027794) (xy 155.985378 -23.979159) (xy 156.019464 -23.935016)
			(xy 156.059613 -23.896307) (xy 156.104971 -23.863856) (xy 156.154571 -23.838355) (xy 156.207355 -23.820348)
			(xy 156.262198 -23.810218) (xy 156.317932 -23.808181) (xy 156.373369 -23.814281) (xy 156.427326 -23.828387)
			(xy 156.478655 -23.850199) (xy 156.526261 -23.879253) (xy 156.569129 -23.914928) (xy 156.606346 -23.956465)
			(xy 156.637119 -24.002978) (xy 156.660791 -24.053475) (xy 156.676859 -24.106882) (xy 156.684979 -24.162058)
			(xy 156.685488 -24.189944) (xy 156.684979 -24.21783) (xy 156.676859 -24.273006) (xy 156.660791 -24.326413)
			(xy 156.637119 -24.37691) (xy 156.606346 -24.423423) (xy 156.569129 -24.46496) (xy 156.526261 -24.500635)
			(xy 156.478655 -24.529689) (xy 156.427326 -24.551501) (xy 156.373369 -24.565607) (xy 156.317932 -24.571707)
			(xy 156.262198 -24.56967) (xy 156.207355 -24.55954) (xy 156.154571 -24.541533) (xy 156.104971 -24.516032)
			(xy 156.059613 -24.483581) (xy 156.019464 -24.444872) (xy 155.985378 -24.400729) (xy 155.958082 -24.352094)
			(xy 155.938159 -24.300003) (xy 155.926033 -24.245566) (xy 155.921962 -24.189944) (xy 154.162506 -24.189944)
			(xy 154.161997 -24.21783) (xy 154.153877 -24.273006) (xy 154.137809 -24.326413) (xy 154.114137 -24.37691)
			(xy 154.083364 -24.423423) (xy 154.046147 -24.46496) (xy 154.003279 -24.500635) (xy 153.955673 -24.529689)
			(xy 153.904344 -24.551501) (xy 153.850387 -24.565607) (xy 153.79495 -24.571707) (xy 153.739216 -24.56967)
			(xy 153.684373 -24.55954) (xy 153.631589 -24.541533) (xy 153.581989 -24.516032) (xy 153.536631 -24.483581)
			(xy 153.496482 -24.444872) (xy 153.462396 -24.400729) (xy 153.4351 -24.352094) (xy 153.415177 -24.300003)
			(xy 153.403051 -24.245566) (xy 153.39898 -24.189944) (xy 150.313328 -24.189944) (xy 150.305777 -24.241256)
			(xy 150.289709 -24.294663) (xy 150.266037 -24.34516) (xy 150.235264 -24.391673) (xy 150.198047 -24.43321)
			(xy 150.155179 -24.468885) (xy 150.107573 -24.497939) (xy 150.056244 -24.519751) (xy 150.002287 -24.533857)
			(xy 149.94685 -24.539957) (xy 149.891116 -24.53792) (xy 149.836273 -24.52779) (xy 149.783489 -24.509783)
			(xy 149.733889 -24.484282) (xy 149.688531 -24.451831) (xy 149.648382 -24.413122) (xy 149.614296 -24.368979)
			(xy 149.587 -24.320344) (xy 149.567077 -24.268253) (xy 149.554951 -24.213816) (xy 149.55088 -24.158194)
			(xy 144.887942 -24.158194) (xy 144.857322 -24.204475) (xy 144.820105 -24.246012) (xy 144.777237 -24.281687)
			(xy 144.729631 -24.310741) (xy 144.678302 -24.332553) (xy 144.624345 -24.346659) (xy 144.568908 -24.352759)
			(xy 144.513174 -24.350722) (xy 144.458331 -24.340592) (xy 144.405547 -24.322585) (xy 144.355947 -24.297084)
			(xy 144.310589 -24.264633) (xy 144.27044 -24.225924) (xy 144.236354 -24.181781) (xy 144.209058 -24.133146)
			(xy 144.189135 -24.081055) (xy 144.177009 -24.026618) (xy 144.172938 -23.970996) (xy 143.943646 -23.970996)
			(xy 143.943577 -23.974752) (xy 143.935457 -24.029928) (xy 143.919389 -24.083335) (xy 143.895717 -24.133832)
			(xy 143.864944 -24.180345) (xy 143.827727 -24.221882) (xy 143.784859 -24.257557) (xy 143.737253 -24.286611)
			(xy 143.685924 -24.308423) (xy 143.631967 -24.322529) (xy 143.57653 -24.328629) (xy 143.520796 -24.326592)
			(xy 143.465953 -24.316462) (xy 143.413169 -24.298455) (xy 143.363569 -24.272954) (xy 143.318211 -24.240503)
			(xy 143.278062 -24.201794) (xy 143.243976 -24.157651) (xy 143.21668 -24.109016) (xy 143.196757 -24.056925)
			(xy 143.184631 -24.002488) (xy 143.18056 -23.946866) (xy 142.940706 -23.946866) (xy 142.94104 -23.965154)
			(xy 142.940531 -23.99304) (xy 142.932411 -24.048216) (xy 142.916343 -24.101623) (xy 142.892671 -24.15212)
			(xy 142.861898 -24.198633) (xy 142.824681 -24.24017) (xy 142.781813 -24.275845) (xy 142.734207 -24.304899)
			(xy 142.682878 -24.326711) (xy 142.628921 -24.340817) (xy 142.573484 -24.346917) (xy 142.51775 -24.34488)
			(xy 142.462907 -24.33475) (xy 142.410123 -24.316743) (xy 142.360523 -24.291242) (xy 142.315165 -24.258791)
			(xy 142.275016 -24.220082) (xy 142.24093 -24.175939) (xy 142.213634 -24.127304) (xy 142.193711 -24.075213)
			(xy 142.181585 -24.020776) (xy 142.177514 -23.965154) (xy 132.637985 -23.965154) (xy 132.636053 -23.965659)
			(xy 132.580616 -23.971759) (xy 132.524882 -23.969722) (xy 132.470039 -23.959592) (xy 132.417255 -23.941585)
			(xy 132.367655 -23.916084) (xy 132.322297 -23.883633) (xy 132.282148 -23.844924) (xy 132.248062 -23.800781)
			(xy 132.220766 -23.752146) (xy 132.200843 -23.700055) (xy 132.188717 -23.645618) (xy 132.184646 -23.589996)
			(xy 94.847918 -23.589996) (xy 94.847409 -23.617882) (xy 94.839289 -23.673058) (xy 94.823221 -23.726465)
			(xy 94.799549 -23.776962) (xy 94.768776 -23.823475) (xy 94.731559 -23.865012) (xy 94.688691 -23.900687)
			(xy 94.641085 -23.929741) (xy 94.589756 -23.951553) (xy 94.535799 -23.965659) (xy 94.480362 -23.971759)
			(xy 94.424628 -23.969722) (xy 94.369785 -23.959592) (xy 94.317001 -23.941585) (xy 94.267401 -23.916084)
			(xy 94.222043 -23.883633) (xy 94.181894 -23.844924) (xy 94.147808 -23.800781) (xy 94.120512 -23.752146)
			(xy 94.100589 -23.700055) (xy 94.088463 -23.645618) (xy 94.084392 -23.589996) (xy 80.47564 -23.589996)
			(xy 80.524143 -23.595333) (xy 80.5781 -23.609439) (xy 80.629429 -23.631251) (xy 80.677035 -23.660305)
			(xy 80.719903 -23.69598) (xy 80.75712 -23.737517) (xy 80.787893 -23.78403) (xy 80.811565 -23.834527)
			(xy 80.827633 -23.887934) (xy 80.835753 -23.94311) (xy 80.836262 -23.970996) (xy 80.835753 -23.998882)
			(xy 80.827633 -24.054058) (xy 80.811565 -24.107465) (xy 80.787893 -24.157962) (xy 80.78774 -24.158194)
			(xy 85.450678 -24.158194) (xy 85.454749 -24.102572) (xy 85.466875 -24.048135) (xy 85.486798 -23.996044)
			(xy 85.514094 -23.947409) (xy 85.54818 -23.903266) (xy 85.588329 -23.864557) (xy 85.633687 -23.832106)
			(xy 85.683287 -23.806605) (xy 85.736071 -23.788598) (xy 85.790914 -23.778468) (xy 85.846648 -23.776431)
			(xy 85.902085 -23.782531) (xy 85.956042 -23.796637) (xy 86.007371 -23.818449) (xy 86.054977 -23.847503)
			(xy 86.097845 -23.883178) (xy 86.135062 -23.924715) (xy 86.165835 -23.971228) (xy 86.189507 -24.021725)
			(xy 86.205575 -24.075132) (xy 86.213695 -24.130308) (xy 86.214204 -24.158194) (xy 86.213695 -24.18608)
			(xy 86.213126 -24.189944) (xy 89.298778 -24.189944) (xy 89.302849 -24.134322) (xy 89.314975 -24.079885)
			(xy 89.334898 -24.027794) (xy 89.362194 -23.979159) (xy 89.39628 -23.935016) (xy 89.436429 -23.896307)
			(xy 89.481787 -23.863856) (xy 89.531387 -23.838355) (xy 89.584171 -23.820348) (xy 89.639014 -23.810218)
			(xy 89.694748 -23.808181) (xy 89.750185 -23.814281) (xy 89.804142 -23.828387) (xy 89.855471 -23.850199)
			(xy 89.903077 -23.879253) (xy 89.945945 -23.914928) (xy 89.983162 -23.956465) (xy 90.013935 -24.002978)
			(xy 90.037607 -24.053475) (xy 90.053675 -24.106882) (xy 90.061795 -24.162058) (xy 90.062304 -24.189944)
			(xy 91.82176 -24.189944) (xy 91.825831 -24.134322) (xy 91.837957 -24.079885) (xy 91.85788 -24.027794)
			(xy 91.885176 -23.979159) (xy 91.919262 -23.935016) (xy 91.959411 -23.896307) (xy 92.004769 -23.863856)
			(xy 92.054369 -23.838355) (xy 92.107153 -23.820348) (xy 92.161996 -23.810218) (xy 92.21773 -23.808181)
			(xy 92.273167 -23.814281) (xy 92.327124 -23.828387) (xy 92.378453 -23.850199) (xy 92.426059 -23.879253)
			(xy 92.468927 -23.914928) (xy 92.506144 -23.956465) (xy 92.536917 -24.002978) (xy 92.560589 -24.053475)
			(xy 92.576657 -24.106882) (xy 92.584208 -24.158194) (xy 123.550932 -24.158194) (xy 123.555003 -24.102572)
			(xy 123.567129 -24.048135) (xy 123.587052 -23.996044) (xy 123.614348 -23.947409) (xy 123.648434 -23.903266)
			(xy 123.688583 -23.864557) (xy 123.733941 -23.832106) (xy 123.783541 -23.806605) (xy 123.836325 -23.788598)
			(xy 123.891168 -23.778468) (xy 123.946902 -23.776431) (xy 124.002339 -23.782531) (xy 124.056296 -23.796637)
			(xy 124.107625 -23.818449) (xy 124.155231 -23.847503) (xy 124.198099 -23.883178) (xy 124.235316 -23.924715)
			(xy 124.266089 -23.971228) (xy 124.289761 -24.021725) (xy 124.305829 -24.075132) (xy 124.313949 -24.130308)
			(xy 124.314458 -24.158194) (xy 124.313949 -24.18608) (xy 124.31338 -24.189944) (xy 127.399032 -24.189944)
			(xy 127.403103 -24.134322) (xy 127.415229 -24.079885) (xy 127.435152 -24.027794) (xy 127.462448 -23.979159)
			(xy 127.496534 -23.935016) (xy 127.536683 -23.896307) (xy 127.582041 -23.863856) (xy 127.631641 -23.838355)
			(xy 127.684425 -23.820348) (xy 127.739268 -23.810218) (xy 127.795002 -23.808181) (xy 127.850439 -23.814281)
			(xy 127.904396 -23.828387) (xy 127.955725 -23.850199) (xy 128.003331 -23.879253) (xy 128.046199 -23.914928)
			(xy 128.083416 -23.956465) (xy 128.114189 -24.002978) (xy 128.137861 -24.053475) (xy 128.153929 -24.106882)
			(xy 128.162049 -24.162058) (xy 128.162558 -24.189944) (xy 129.922014 -24.189944) (xy 129.926085 -24.134322)
			(xy 129.938211 -24.079885) (xy 129.958134 -24.027794) (xy 129.98543 -23.979159) (xy 130.019516 -23.935016)
			(xy 130.059665 -23.896307) (xy 130.105023 -23.863856) (xy 130.154623 -23.838355) (xy 130.207407 -23.820348)
			(xy 130.26225 -23.810218) (xy 130.317984 -23.808181) (xy 130.373421 -23.814281) (xy 130.427378 -23.828387)
			(xy 130.478707 -23.850199) (xy 130.526313 -23.879253) (xy 130.569181 -23.914928) (xy 130.606398 -23.956465)
			(xy 130.637171 -24.002978) (xy 130.660843 -24.053475) (xy 130.676911 -24.106882) (xy 130.685031 -24.162058)
			(xy 130.68554 -24.189944) (xy 130.685031 -24.21783) (xy 130.676911 -24.273006) (xy 130.660843 -24.326413)
			(xy 130.637171 -24.37691) (xy 130.606398 -24.423423) (xy 130.569181 -24.46496) (xy 130.526313 -24.500635)
			(xy 130.478707 -24.529689) (xy 130.427378 -24.551501) (xy 130.373421 -24.565607) (xy 130.317984 -24.571707)
			(xy 130.26225 -24.56967) (xy 130.207407 -24.55954) (xy 130.154623 -24.541533) (xy 130.105023 -24.516032)
			(xy 130.059665 -24.483581) (xy 130.019516 -24.444872) (xy 129.98543 -24.400729) (xy 129.958134 -24.352094)
			(xy 129.938211 -24.300003) (xy 129.926085 -24.245566) (xy 129.922014 -24.189944) (xy 128.162558 -24.189944)
			(xy 128.162049 -24.21783) (xy 128.153929 -24.273006) (xy 128.137861 -24.326413) (xy 128.114189 -24.37691)
			(xy 128.083416 -24.423423) (xy 128.046199 -24.46496) (xy 128.003331 -24.500635) (xy 127.955725 -24.529689)
			(xy 127.904396 -24.551501) (xy 127.850439 -24.565607) (xy 127.795002 -24.571707) (xy 127.739268 -24.56967)
			(xy 127.684425 -24.55954) (xy 127.631641 -24.541533) (xy 127.582041 -24.516032) (xy 127.536683 -24.483581)
			(xy 127.496534 -24.444872) (xy 127.462448 -24.400729) (xy 127.435152 -24.352094) (xy 127.415229 -24.300003)
			(xy 127.403103 -24.245566) (xy 127.399032 -24.189944) (xy 124.31338 -24.189944) (xy 124.305829 -24.241256)
			(xy 124.289761 -24.294663) (xy 124.266089 -24.34516) (xy 124.235316 -24.391673) (xy 124.198099 -24.43321)
			(xy 124.155231 -24.468885) (xy 124.107625 -24.497939) (xy 124.056296 -24.519751) (xy 124.002339 -24.533857)
			(xy 123.946902 -24.539957) (xy 123.891168 -24.53792) (xy 123.836325 -24.52779) (xy 123.783541 -24.509783)
			(xy 123.733941 -24.484282) (xy 123.688583 -24.451831) (xy 123.648434 -24.413122) (xy 123.614348 -24.368979)
			(xy 123.587052 -24.320344) (xy 123.567129 -24.268253) (xy 123.555003 -24.213816) (xy 123.550932 -24.158194)
			(xy 92.584208 -24.158194) (xy 92.584777 -24.162058) (xy 92.585286 -24.189944) (xy 92.584777 -24.21783)
			(xy 92.576657 -24.273006) (xy 92.560589 -24.326413) (xy 92.536917 -24.37691) (xy 92.506144 -24.423423)
			(xy 92.468927 -24.46496) (xy 92.426059 -24.500635) (xy 92.378453 -24.529689) (xy 92.327124 -24.551501)
			(xy 92.273167 -24.565607) (xy 92.21773 -24.571707) (xy 92.161996 -24.56967) (xy 92.107153 -24.55954)
			(xy 92.054369 -24.541533) (xy 92.004769 -24.516032) (xy 91.959411 -24.483581) (xy 91.919262 -24.444872)
			(xy 91.885176 -24.400729) (xy 91.85788 -24.352094) (xy 91.837957 -24.300003) (xy 91.825831 -24.245566)
			(xy 91.82176 -24.189944) (xy 90.062304 -24.189944) (xy 90.061795 -24.21783) (xy 90.053675 -24.273006)
			(xy 90.037607 -24.326413) (xy 90.013935 -24.37691) (xy 89.983162 -24.423423) (xy 89.945945 -24.46496)
			(xy 89.903077 -24.500635) (xy 89.855471 -24.529689) (xy 89.804142 -24.551501) (xy 89.750185 -24.565607)
			(xy 89.694748 -24.571707) (xy 89.639014 -24.56967) (xy 89.584171 -24.55954) (xy 89.531387 -24.541533)
			(xy 89.481787 -24.516032) (xy 89.436429 -24.483581) (xy 89.39628 -24.444872) (xy 89.362194 -24.400729)
			(xy 89.334898 -24.352094) (xy 89.314975 -24.300003) (xy 89.302849 -24.245566) (xy 89.298778 -24.189944)
			(xy 86.213126 -24.189944) (xy 86.205575 -24.241256) (xy 86.189507 -24.294663) (xy 86.165835 -24.34516)
			(xy 86.135062 -24.391673) (xy 86.097845 -24.43321) (xy 86.054977 -24.468885) (xy 86.007371 -24.497939)
			(xy 85.956042 -24.519751) (xy 85.902085 -24.533857) (xy 85.846648 -24.539957) (xy 85.790914 -24.53792)
			(xy 85.736071 -24.52779) (xy 85.683287 -24.509783) (xy 85.633687 -24.484282) (xy 85.588329 -24.451831)
			(xy 85.54818 -24.413122) (xy 85.514094 -24.368979) (xy 85.486798 -24.320344) (xy 85.466875 -24.268253)
			(xy 85.454749 -24.213816) (xy 85.450678 -24.158194) (xy 80.78774 -24.158194) (xy 80.75712 -24.204475)
			(xy 80.719903 -24.246012) (xy 80.677035 -24.281687) (xy 80.629429 -24.310741) (xy 80.5781 -24.332553)
			(xy 80.524143 -24.346659) (xy 80.468706 -24.352759) (xy 80.412972 -24.350722) (xy 80.358129 -24.340592)
			(xy 80.305345 -24.322585) (xy 80.255745 -24.297084) (xy 80.210387 -24.264633) (xy 80.170238 -24.225924)
			(xy 80.136152 -24.181781) (xy 80.108856 -24.133146) (xy 80.088933 -24.081055) (xy 80.076807 -24.026618)
			(xy 80.072736 -23.970996) (xy 79.843444 -23.970996) (xy 79.843375 -23.974752) (xy 79.835255 -24.029928)
			(xy 79.819187 -24.083335) (xy 79.795515 -24.133832) (xy 79.764742 -24.180345) (xy 79.727525 -24.221882)
			(xy 79.684657 -24.257557) (xy 79.637051 -24.286611) (xy 79.585722 -24.308423) (xy 79.531765 -24.322529)
			(xy 79.476328 -24.328629) (xy 79.420594 -24.326592) (xy 79.365751 -24.316462) (xy 79.312967 -24.298455)
			(xy 79.263367 -24.272954) (xy 79.218009 -24.240503) (xy 79.17786 -24.201794) (xy 79.143774 -24.157651)
			(xy 79.116478 -24.109016) (xy 79.096555 -24.056925) (xy 79.084429 -24.002488) (xy 79.080358 -23.946866)
			(xy 78.840504 -23.946866) (xy 78.840838 -23.965154) (xy 78.840329 -23.99304) (xy 78.832209 -24.048216)
			(xy 78.816141 -24.101623) (xy 78.792469 -24.15212) (xy 78.761696 -24.198633) (xy 78.724479 -24.24017)
			(xy 78.681611 -24.275845) (xy 78.634005 -24.304899) (xy 78.582676 -24.326711) (xy 78.528719 -24.340817)
			(xy 78.473282 -24.346917) (xy 78.417548 -24.34488) (xy 78.362705 -24.33475) (xy 78.309921 -24.316743)
			(xy 78.260321 -24.291242) (xy 78.214963 -24.258791) (xy 78.174814 -24.220082) (xy 78.140728 -24.175939)
			(xy 78.113432 -24.127304) (xy 78.093509 -24.075213) (xy 78.081383 -24.020776) (xy 78.077312 -23.965154)
			(xy 68.537783 -23.965154) (xy 68.535851 -23.965659) (xy 68.480414 -23.971759) (xy 68.42468 -23.969722)
			(xy 68.369837 -23.959592) (xy 68.317053 -23.941585) (xy 68.267453 -23.916084) (xy 68.222095 -23.883633)
			(xy 68.181946 -23.844924) (xy 68.14786 -23.800781) (xy 68.120564 -23.752146) (xy 68.100641 -23.700055)
			(xy 68.088515 -23.645618) (xy 68.084444 -23.589996) (xy 54.475692 -23.589996) (xy 54.524195 -23.595333)
			(xy 54.578152 -23.609439) (xy 54.629481 -23.631251) (xy 54.677087 -23.660305) (xy 54.719955 -23.69598)
			(xy 54.757172 -23.737517) (xy 54.787945 -23.78403) (xy 54.811617 -23.834527) (xy 54.827685 -23.887934)
			(xy 54.835805 -23.94311) (xy 54.836314 -23.970996) (xy 54.835805 -23.998882) (xy 54.827685 -24.054058)
			(xy 54.811617 -24.107465) (xy 54.787945 -24.157962) (xy 54.787792 -24.158194) (xy 59.45073 -24.158194)
			(xy 59.454801 -24.102572) (xy 59.466927 -24.048135) (xy 59.48685 -23.996044) (xy 59.514146 -23.947409)
			(xy 59.548232 -23.903266) (xy 59.588381 -23.864557) (xy 59.633739 -23.832106) (xy 59.683339 -23.806605)
			(xy 59.736123 -23.788598) (xy 59.790966 -23.778468) (xy 59.8467 -23.776431) (xy 59.902137 -23.782531)
			(xy 59.956094 -23.796637) (xy 60.007423 -23.818449) (xy 60.055029 -23.847503) (xy 60.097897 -23.883178)
			(xy 60.135114 -23.924715) (xy 60.165887 -23.971228) (xy 60.189559 -24.021725) (xy 60.205627 -24.075132)
			(xy 60.213747 -24.130308) (xy 60.214256 -24.158194) (xy 60.213747 -24.18608) (xy 60.213178 -24.189944)
			(xy 63.29883 -24.189944) (xy 63.302901 -24.134322) (xy 63.315027 -24.079885) (xy 63.33495 -24.027794)
			(xy 63.362246 -23.979159) (xy 63.396332 -23.935016) (xy 63.436481 -23.896307) (xy 63.481839 -23.863856)
			(xy 63.531439 -23.838355) (xy 63.584223 -23.820348) (xy 63.639066 -23.810218) (xy 63.6948 -23.808181)
			(xy 63.750237 -23.814281) (xy 63.804194 -23.828387) (xy 63.855523 -23.850199) (xy 63.903129 -23.879253)
			(xy 63.945997 -23.914928) (xy 63.983214 -23.956465) (xy 64.013987 -24.002978) (xy 64.037659 -24.053475)
			(xy 64.053727 -24.106882) (xy 64.061847 -24.162058) (xy 64.062356 -24.189944) (xy 65.821812 -24.189944)
			(xy 65.825883 -24.134322) (xy 65.838009 -24.079885) (xy 65.857932 -24.027794) (xy 65.885228 -23.979159)
			(xy 65.919314 -23.935016) (xy 65.959463 -23.896307) (xy 66.004821 -23.863856) (xy 66.054421 -23.838355)
			(xy 66.107205 -23.820348) (xy 66.162048 -23.810218) (xy 66.217782 -23.808181) (xy 66.273219 -23.814281)
			(xy 66.327176 -23.828387) (xy 66.378505 -23.850199) (xy 66.426111 -23.879253) (xy 66.468979 -23.914928)
			(xy 66.506196 -23.956465) (xy 66.536969 -24.002978) (xy 66.560641 -24.053475) (xy 66.576709 -24.106882)
			(xy 66.584829 -24.162058) (xy 66.585338 -24.189944) (xy 66.584829 -24.21783) (xy 66.576709 -24.273006)
			(xy 66.560641 -24.326413) (xy 66.536969 -24.37691) (xy 66.506196 -24.423423) (xy 66.468979 -24.46496)
			(xy 66.426111 -24.500635) (xy 66.378505 -24.529689) (xy 66.327176 -24.551501) (xy 66.273219 -24.565607)
			(xy 66.217782 -24.571707) (xy 66.162048 -24.56967) (xy 66.107205 -24.55954) (xy 66.054421 -24.541533)
			(xy 66.004821 -24.516032) (xy 65.959463 -24.483581) (xy 65.919314 -24.444872) (xy 65.885228 -24.400729)
			(xy 65.857932 -24.352094) (xy 65.838009 -24.300003) (xy 65.825883 -24.245566) (xy 65.821812 -24.189944)
			(xy 64.062356 -24.189944) (xy 64.061847 -24.21783) (xy 64.053727 -24.273006) (xy 64.037659 -24.326413)
			(xy 64.013987 -24.37691) (xy 63.983214 -24.423423) (xy 63.945997 -24.46496) (xy 63.903129 -24.500635)
			(xy 63.855523 -24.529689) (xy 63.804194 -24.551501) (xy 63.750237 -24.565607) (xy 63.6948 -24.571707)
			(xy 63.639066 -24.56967) (xy 63.584223 -24.55954) (xy 63.531439 -24.541533) (xy 63.481839 -24.516032)
			(xy 63.436481 -24.483581) (xy 63.396332 -24.444872) (xy 63.362246 -24.400729) (xy 63.33495 -24.352094)
			(xy 63.315027 -24.300003) (xy 63.302901 -24.245566) (xy 63.29883 -24.189944) (xy 60.213178 -24.189944)
			(xy 60.205627 -24.241256) (xy 60.189559 -24.294663) (xy 60.165887 -24.34516) (xy 60.135114 -24.391673)
			(xy 60.097897 -24.43321) (xy 60.055029 -24.468885) (xy 60.007423 -24.497939) (xy 59.956094 -24.519751)
			(xy 59.902137 -24.533857) (xy 59.8467 -24.539957) (xy 59.790966 -24.53792) (xy 59.736123 -24.52779)
			(xy 59.683339 -24.509783) (xy 59.633739 -24.484282) (xy 59.588381 -24.451831) (xy 59.548232 -24.413122)
			(xy 59.514146 -24.368979) (xy 59.48685 -24.320344) (xy 59.466927 -24.268253) (xy 59.454801 -24.213816)
			(xy 59.45073 -24.158194) (xy 54.787792 -24.158194) (xy 54.757172 -24.204475) (xy 54.719955 -24.246012)
			(xy 54.677087 -24.281687) (xy 54.629481 -24.310741) (xy 54.578152 -24.332553) (xy 54.524195 -24.346659)
			(xy 54.468758 -24.352759) (xy 54.413024 -24.350722) (xy 54.358181 -24.340592) (xy 54.305397 -24.322585)
			(xy 54.255797 -24.297084) (xy 54.210439 -24.264633) (xy 54.17029 -24.225924) (xy 54.136204 -24.181781)
			(xy 54.108908 -24.133146) (xy 54.088985 -24.081055) (xy 54.076859 -24.026618) (xy 54.072788 -23.970996)
			(xy 53.843496 -23.970996) (xy 53.843427 -23.974752) (xy 53.835307 -24.029928) (xy 53.819239 -24.083335)
			(xy 53.795567 -24.133832) (xy 53.764794 -24.180345) (xy 53.727577 -24.221882) (xy 53.684709 -24.257557)
			(xy 53.637103 -24.286611) (xy 53.585774 -24.308423) (xy 53.531817 -24.322529) (xy 53.47638 -24.328629)
			(xy 53.420646 -24.326592) (xy 53.365803 -24.316462) (xy 53.313019 -24.298455) (xy 53.263419 -24.272954)
			(xy 53.218061 -24.240503) (xy 53.177912 -24.201794) (xy 53.143826 -24.157651) (xy 53.11653 -24.109016)
			(xy 53.096607 -24.056925) (xy 53.084481 -24.002488) (xy 53.08041 -23.946866) (xy 52.840556 -23.946866)
			(xy 52.84089 -23.965154) (xy 52.840381 -23.99304) (xy 52.832261 -24.048216) (xy 52.816193 -24.101623)
			(xy 52.792521 -24.15212) (xy 52.761748 -24.198633) (xy 52.724531 -24.24017) (xy 52.681663 -24.275845)
			(xy 52.634057 -24.304899) (xy 52.582728 -24.326711) (xy 52.528771 -24.340817) (xy 52.473334 -24.346917)
			(xy 52.4176 -24.34488) (xy 52.362757 -24.33475) (xy 52.309973 -24.316743) (xy 52.260373 -24.291242)
			(xy 52.215015 -24.258791) (xy 52.174866 -24.220082) (xy 52.14078 -24.175939) (xy 52.113484 -24.127304)
			(xy 52.093561 -24.075213) (xy 52.081435 -24.020776) (xy 52.077364 -23.965154) (xy 42.537835 -23.965154)
			(xy 42.535903 -23.965659) (xy 42.480466 -23.971759) (xy 42.424732 -23.969722) (xy 42.369889 -23.959592)
			(xy 42.317105 -23.941585) (xy 42.267505 -23.916084) (xy 42.222147 -23.883633) (xy 42.181998 -23.844924)
			(xy 42.147912 -23.800781) (xy 42.120616 -23.752146) (xy 42.100693 -23.700055) (xy 42.088567 -23.645618)
			(xy 42.084496 -23.589996) (xy 16.848074 -23.589996) (xy 16.847565 -23.617882) (xy 16.839445 -23.673058)
			(xy 16.823377 -23.726465) (xy 16.799705 -23.776962) (xy 16.768932 -23.823475) (xy 16.731715 -23.865012)
			(xy 16.688847 -23.900687) (xy 16.641241 -23.929741) (xy 16.589912 -23.951553) (xy 16.535955 -23.965659)
			(xy 16.480518 -23.971759) (xy 16.424784 -23.969722) (xy 16.369941 -23.959592) (xy 16.317157 -23.941585)
			(xy 16.267557 -23.916084) (xy 16.222199 -23.883633) (xy 16.18205 -23.844924) (xy 16.147964 -23.800781)
			(xy 16.120668 -23.752146) (xy 16.100745 -23.700055) (xy 16.088619 -23.645618) (xy 16.084548 -23.589996)
			(xy 3.783134 -23.589996) (xy 3.797731 -23.596199) (xy 3.845337 -23.625253) (xy 3.888205 -23.660928)
			(xy 3.925422 -23.702465) (xy 3.956195 -23.748978) (xy 3.979867 -23.799475) (xy 3.995935 -23.852882)
			(xy 4.004055 -23.908058) (xy 4.004564 -23.935944) (xy 4.004055 -23.96383) (xy 3.995935 -24.019006)
			(xy 3.979867 -24.072413) (xy 3.956195 -24.12291) (xy 3.925422 -24.169423) (xy 3.907035 -24.189944)
			(xy 13.821916 -24.189944) (xy 13.825987 -24.134322) (xy 13.838113 -24.079885) (xy 13.858036 -24.027794)
			(xy 13.885332 -23.979159) (xy 13.919418 -23.935016) (xy 13.959567 -23.896307) (xy 14.004925 -23.863856)
			(xy 14.054525 -23.838355) (xy 14.107309 -23.820348) (xy 14.162152 -23.810218) (xy 14.217886 -23.808181)
			(xy 14.273323 -23.814281) (xy 14.32728 -23.828387) (xy 14.378609 -23.850199) (xy 14.426215 -23.879253)
			(xy 14.469083 -23.914928) (xy 14.5063 -23.956465) (xy 14.537073 -24.002978) (xy 14.560745 -24.053475)
			(xy 14.576813 -24.106882) (xy 14.584933 -24.162058) (xy 14.585442 -24.189944) (xy 14.584933 -24.21783)
			(xy 14.576813 -24.273006) (xy 14.560745 -24.326413) (xy 14.548157 -24.353266) (xy 19.380198 -24.353266)
			(xy 19.384269 -24.297644) (xy 19.396395 -24.243207) (xy 19.416318 -24.191116) (xy 19.443614 -24.142481)
			(xy 19.4777 -24.098338) (xy 19.517849 -24.059629) (xy 19.563207 -24.027178) (xy 19.612807 -24.001677)
			(xy 19.665591 -23.98367) (xy 19.720434 -23.97354) (xy 19.776168 -23.971503) (xy 19.831605 -23.977603)
			(xy 19.885562 -23.991709) (xy 19.936891 -24.013521) (xy 19.984497 -24.042575) (xy 20.027365 -24.07825)
			(xy 20.064582 -24.119787) (xy 20.089992 -24.158194) (xy 33.450782 -24.158194) (xy 33.454853 -24.102572)
			(xy 33.466979 -24.048135) (xy 33.486902 -23.996044) (xy 33.514198 -23.947409) (xy 33.548284 -23.903266)
			(xy 33.588433 -23.864557) (xy 33.633791 -23.832106) (xy 33.683391 -23.806605) (xy 33.736175 -23.788598)
			(xy 33.791018 -23.778468) (xy 33.846752 -23.776431) (xy 33.902189 -23.782531) (xy 33.956146 -23.796637)
			(xy 34.007475 -23.818449) (xy 34.055081 -23.847503) (xy 34.097949 -23.883178) (xy 34.135166 -23.924715)
			(xy 34.165939 -23.971228) (xy 34.189611 -24.021725) (xy 34.205679 -24.075132) (xy 34.213799 -24.130308)
			(xy 34.214308 -24.158194) (xy 34.213799 -24.18608) (xy 34.21323 -24.189944) (xy 37.298882 -24.189944)
			(xy 37.302953 -24.134322) (xy 37.315079 -24.079885) (xy 37.335002 -24.027794) (xy 37.362298 -23.979159)
			(xy 37.396384 -23.935016) (xy 37.436533 -23.896307) (xy 37.481891 -23.863856) (xy 37.531491 -23.838355)
			(xy 37.584275 -23.820348) (xy 37.639118 -23.810218) (xy 37.694852 -23.808181) (xy 37.750289 -23.814281)
			(xy 37.804246 -23.828387) (xy 37.855575 -23.850199) (xy 37.903181 -23.879253) (xy 37.946049 -23.914928)
			(xy 37.983266 -23.956465) (xy 38.014039 -24.002978) (xy 38.037711 -24.053475) (xy 38.053779 -24.106882)
			(xy 38.061899 -24.162058) (xy 38.062408 -24.189944) (xy 39.821864 -24.189944) (xy 39.825935 -24.134322)
			(xy 39.838061 -24.079885) (xy 39.857984 -24.027794) (xy 39.88528 -23.979159) (xy 39.919366 -23.935016)
			(xy 39.959515 -23.896307) (xy 40.004873 -23.863856) (xy 40.054473 -23.838355) (xy 40.107257 -23.820348)
			(xy 40.1621 -23.810218) (xy 40.217834 -23.808181) (xy 40.273271 -23.814281) (xy 40.327228 -23.828387)
			(xy 40.378557 -23.850199) (xy 40.426163 -23.879253) (xy 40.469031 -23.914928) (xy 40.506248 -23.956465)
			(xy 40.537021 -24.002978) (xy 40.560693 -24.053475) (xy 40.576761 -24.106882) (xy 40.584881 -24.162058)
			(xy 40.58539 -24.189944) (xy 40.584881 -24.21783) (xy 40.576761 -24.273006) (xy 40.560693 -24.326413)
			(xy 40.537021 -24.37691) (xy 40.506248 -24.423423) (xy 40.469031 -24.46496) (xy 40.426163 -24.500635)
			(xy 40.378557 -24.529689) (xy 40.327228 -24.551501) (xy 40.273271 -24.565607) (xy 40.217834 -24.571707)
			(xy 40.1621 -24.56967) (xy 40.107257 -24.55954) (xy 40.054473 -24.541533) (xy 40.004873 -24.516032)
			(xy 39.959515 -24.483581) (xy 39.919366 -24.444872) (xy 39.88528 -24.400729) (xy 39.857984 -24.352094)
			(xy 39.838061 -24.300003) (xy 39.825935 -24.245566) (xy 39.821864 -24.189944) (xy 38.062408 -24.189944)
			(xy 38.061899 -24.21783) (xy 38.053779 -24.273006) (xy 38.037711 -24.326413) (xy 38.014039 -24.37691)
			(xy 37.983266 -24.423423) (xy 37.946049 -24.46496) (xy 37.903181 -24.500635) (xy 37.855575 -24.529689)
			(xy 37.804246 -24.551501) (xy 37.750289 -24.565607) (xy 37.694852 -24.571707) (xy 37.639118 -24.56967)
			(xy 37.584275 -24.55954) (xy 37.531491 -24.541533) (xy 37.481891 -24.516032) (xy 37.436533 -24.483581)
			(xy 37.396384 -24.444872) (xy 37.362298 -24.400729) (xy 37.335002 -24.352094) (xy 37.315079 -24.300003)
			(xy 37.302953 -24.245566) (xy 37.298882 -24.189944) (xy 34.21323 -24.189944) (xy 34.205679 -24.241256)
			(xy 34.189611 -24.294663) (xy 34.165939 -24.34516) (xy 34.135166 -24.391673) (xy 34.097949 -24.43321)
			(xy 34.055081 -24.468885) (xy 34.007475 -24.497939) (xy 33.956146 -24.519751) (xy 33.902189 -24.533857)
			(xy 33.846752 -24.539957) (xy 33.791018 -24.53792) (xy 33.736175 -24.52779) (xy 33.683391 -24.509783)
			(xy 33.633791 -24.484282) (xy 33.588433 -24.451831) (xy 33.548284 -24.413122) (xy 33.514198 -24.368979)
			(xy 33.486902 -24.320344) (xy 33.466979 -24.268253) (xy 33.454853 -24.213816) (xy 33.450782 -24.158194)
			(xy 20.089992 -24.158194) (xy 20.095355 -24.1663) (xy 20.119027 -24.216797) (xy 20.135095 -24.270204)
			(xy 20.143215 -24.32538) (xy 20.143724 -24.353266) (xy 20.143215 -24.381152) (xy 20.135095 -24.436328)
			(xy 20.119027 -24.489735) (xy 20.095355 -24.540232) (xy 20.064582 -24.586745) (xy 20.027365 -24.628282)
			(xy 19.984497 -24.663957) (xy 19.936891 -24.693011) (xy 19.885562 -24.714823) (xy 19.831605 -24.728929)
			(xy 19.776168 -24.735029) (xy 19.720434 -24.732992) (xy 19.665591 -24.722862) (xy 19.612807 -24.704855)
			(xy 19.563207 -24.679354) (xy 19.517849 -24.646903) (xy 19.4777 -24.608194) (xy 19.443614 -24.564051)
			(xy 19.416318 -24.515416) (xy 19.396395 -24.463325) (xy 19.384269 -24.408888) (xy 19.380198 -24.353266)
			(xy 14.548157 -24.353266) (xy 14.537073 -24.37691) (xy 14.5063 -24.423423) (xy 14.469083 -24.46496)
			(xy 14.426215 -24.500635) (xy 14.378609 -24.529689) (xy 14.32728 -24.551501) (xy 14.273323 -24.565607)
			(xy 14.217886 -24.571707) (xy 14.162152 -24.56967) (xy 14.107309 -24.55954) (xy 14.054525 -24.541533)
			(xy 14.004925 -24.516032) (xy 13.959567 -24.483581) (xy 13.919418 -24.444872) (xy 13.885332 -24.400729)
			(xy 13.858036 -24.352094) (xy 13.838113 -24.300003) (xy 13.825987 -24.245566) (xy 13.821916 -24.189944)
			(xy 3.907035 -24.189944) (xy 3.888205 -24.21096) (xy 3.845337 -24.246635) (xy 3.797731 -24.275689)
			(xy 3.746402 -24.297501) (xy 3.692445 -24.311607) (xy 3.637008 -24.317707) (xy 3.581274 -24.31567)
			(xy 3.526431 -24.30554) (xy 3.473647 -24.287533) (xy 3.424047 -24.262032) (xy 3.378689 -24.229581)
			(xy 3.33854 -24.190872) (xy 3.304454 -24.146729) (xy 3.277158 -24.098094) (xy 3.257235 -24.046003)
			(xy 3.245109 -23.991566) (xy 3.241038 -23.935944) (xy 2.995676 -23.935944) (xy 2.995167 -23.96383)
			(xy 2.987047 -24.019006) (xy 2.970979 -24.072413) (xy 2.947307 -24.12291) (xy 2.916534 -24.169423)
			(xy 2.879317 -24.21096) (xy 2.836449 -24.246635) (xy 2.788843 -24.275689) (xy 2.737514 -24.297501)
			(xy 2.683557 -24.311607) (xy 2.62812 -24.317707) (xy 2.572386 -24.31567) (xy 2.517543 -24.30554)
			(xy 2.464759 -24.287533) (xy 2.415159 -24.262032) (xy 2.369801 -24.229581) (xy 2.329652 -24.190872)
			(xy 2.295566 -24.146729) (xy 2.26827 -24.098094) (xy 2.248347 -24.046003) (xy 2.236221 -23.991566)
			(xy 2.23215 -23.935944) (xy 0.715772 -23.935944) (xy 0.715772 -24.807418) (xy 6.371334 -24.807418)
			(xy 6.375405 -24.751796) (xy 6.387531 -24.697359) (xy 6.407454 -24.645268) (xy 6.43475 -24.596633)
			(xy 6.468836 -24.55249) (xy 6.508985 -24.513781) (xy 6.554343 -24.48133) (xy 6.603943 -24.455829)
			(xy 6.656727 -24.437822) (xy 6.71157 -24.427692) (xy 6.767304 -24.425655) (xy 6.822741 -24.431755)
			(xy 6.876698 -24.445861) (xy 6.928027 -24.467673) (xy 6.975633 -24.496727) (xy 7.018501 -24.532402)
			(xy 7.055718 -24.573939) (xy 7.086491 -24.620452) (xy 7.110163 -24.670949) (xy 7.126231 -24.724356)
			(xy 7.134351 -24.779532) (xy 7.13486 -24.807418) (xy 8.62025 -24.807418) (xy 8.624321 -24.751796)
			(xy 8.636447 -24.697359) (xy 8.65637 -24.645268) (xy 8.683666 -24.596633) (xy 8.717752 -24.55249)
			(xy 8.757901 -24.513781) (xy 8.803259 -24.48133) (xy 8.852859 -24.455829) (xy 8.905643 -24.437822)
			(xy 8.960486 -24.427692) (xy 9.01622 -24.425655) (xy 9.071657 -24.431755) (xy 9.125614 -24.445861)
			(xy 9.176943 -24.467673) (xy 9.224549 -24.496727) (xy 9.267417 -24.532402) (xy 9.304634 -24.573939)
			(xy 9.335407 -24.620452) (xy 9.359079 -24.670949) (xy 9.375147 -24.724356) (xy 9.383267 -24.779532)
			(xy 9.383776 -24.807418) (xy 9.383267 -24.835304) (xy 9.375147 -24.89048) (xy 9.359079 -24.943887)
			(xy 9.335407 -24.994384) (xy 9.304634 -25.040897) (xy 9.267417 -25.082434) (xy 9.224549 -25.118109)
			(xy 9.176943 -25.147163) (xy 9.125614 -25.168975) (xy 9.071657 -25.183081) (xy 9.01622 -25.189181)
			(xy 8.960486 -25.187144) (xy 8.905643 -25.177014) (xy 8.852859 -25.159007) (xy 8.803259 -25.133506)
			(xy 8.757901 -25.101055) (xy 8.717752 -25.062346) (xy 8.683666 -25.018203) (xy 8.65637 -24.969568)
			(xy 8.636447 -24.917477) (xy 8.624321 -24.86304) (xy 8.62025 -24.807418) (xy 7.13486 -24.807418)
			(xy 7.134351 -24.835304) (xy 7.126231 -24.89048) (xy 7.110163 -24.943887) (xy 7.086491 -24.994384)
			(xy 7.055718 -25.040897) (xy 7.018501 -25.082434) (xy 6.975633 -25.118109) (xy 6.928027 -25.147163)
			(xy 6.876698 -25.168975) (xy 6.822741 -25.183081) (xy 6.767304 -25.189181) (xy 6.71157 -25.187144)
			(xy 6.656727 -25.177014) (xy 6.603943 -25.159007) (xy 6.554343 -25.133506) (xy 6.508985 -25.101055)
			(xy 6.468836 -25.062346) (xy 6.43475 -25.018203) (xy 6.407454 -24.969568) (xy 6.387531 -24.917477)
			(xy 6.375405 -24.86304) (xy 6.371334 -24.807418) (xy 0.715772 -24.807418) (xy 0.715772 -25.390094)
			(xy 13.809216 -25.390094) (xy 13.813287 -25.334472) (xy 13.825413 -25.280035) (xy 13.845336 -25.227944)
			(xy 13.872632 -25.179309) (xy 13.906718 -25.135166) (xy 13.946867 -25.096457) (xy 13.992225 -25.064006)
			(xy 14.041825 -25.038505) (xy 14.094609 -25.020498) (xy 14.149452 -25.010368) (xy 14.205186 -25.008331)
			(xy 14.260623 -25.014431) (xy 14.31458 -25.028537) (xy 14.322621 -25.031954) (xy 18.187922 -25.031954)
			(xy 18.191993 -24.976332) (xy 18.204119 -24.921895) (xy 18.224042 -24.869804) (xy 18.251338 -24.821169)
			(xy 18.285424 -24.777026) (xy 18.325573 -24.738317) (xy 18.370931 -24.705866) (xy 18.420531 -24.680365)
			(xy 18.473315 -24.662358) (xy 18.528158 -24.652228) (xy 18.583892 -24.650191) (xy 18.639329 -24.656291)
			(xy 18.693286 -24.670397) (xy 18.744615 -24.692209) (xy 18.792221 -24.721263) (xy 18.835089 -24.756938)
			(xy 18.872306 -24.798475) (xy 18.878223 -24.807418) (xy 32.371282 -24.807418) (xy 32.375353 -24.751796)
			(xy 32.387479 -24.697359) (xy 32.407402 -24.645268) (xy 32.434698 -24.596633) (xy 32.468784 -24.55249)
			(xy 32.508933 -24.513781) (xy 32.554291 -24.48133) (xy 32.603891 -24.455829) (xy 32.656675 -24.437822)
			(xy 32.711518 -24.427692) (xy 32.767252 -24.425655) (xy 32.822689 -24.431755) (xy 32.876646 -24.445861)
			(xy 32.927975 -24.467673) (xy 32.975581 -24.496727) (xy 33.018449 -24.532402) (xy 33.055666 -24.573939)
			(xy 33.086439 -24.620452) (xy 33.110111 -24.670949) (xy 33.126179 -24.724356) (xy 33.134299 -24.779532)
			(xy 33.134808 -24.807418) (xy 34.620198 -24.807418) (xy 34.624269 -24.751796) (xy 34.636395 -24.697359)
			(xy 34.656318 -24.645268) (xy 34.683614 -24.596633) (xy 34.7177 -24.55249) (xy 34.757849 -24.513781)
			(xy 34.803207 -24.48133) (xy 34.852807 -24.455829) (xy 34.905591 -24.437822) (xy 34.960434 -24.427692)
			(xy 35.016168 -24.425655) (xy 35.071605 -24.431755) (xy 35.125562 -24.445861) (xy 35.176891 -24.467673)
			(xy 35.224497 -24.496727) (xy 35.267365 -24.532402) (xy 35.304582 -24.573939) (xy 35.335355 -24.620452)
			(xy 35.359027 -24.670949) (xy 35.375095 -24.724356) (xy 35.383215 -24.779532) (xy 35.383724 -24.807418)
			(xy 35.383215 -24.835304) (xy 35.375095 -24.89048) (xy 35.359027 -24.943887) (xy 35.335355 -24.994384)
			(xy 35.304582 -25.040897) (xy 35.267365 -25.082434) (xy 35.224497 -25.118109) (xy 35.176891 -25.147163)
			(xy 35.125562 -25.168975) (xy 35.071605 -25.183081) (xy 35.016168 -25.189181) (xy 34.960434 -25.187144)
			(xy 34.905591 -25.177014) (xy 34.852807 -25.159007) (xy 34.803207 -25.133506) (xy 34.757849 -25.101055)
			(xy 34.7177 -25.062346) (xy 34.683614 -25.018203) (xy 34.656318 -24.969568) (xy 34.636395 -24.917477)
			(xy 34.624269 -24.86304) (xy 34.620198 -24.807418) (xy 33.134808 -24.807418) (xy 33.134299 -24.835304)
			(xy 33.126179 -24.89048) (xy 33.110111 -24.943887) (xy 33.086439 -24.994384) (xy 33.055666 -25.040897)
			(xy 33.018449 -25.082434) (xy 32.975581 -25.118109) (xy 32.927975 -25.147163) (xy 32.876646 -25.168975)
			(xy 32.822689 -25.183081) (xy 32.767252 -25.189181) (xy 32.711518 -25.187144) (xy 32.656675 -25.177014)
			(xy 32.603891 -25.159007) (xy 32.554291 -25.133506) (xy 32.508933 -25.101055) (xy 32.468784 -25.062346)
			(xy 32.434698 -25.018203) (xy 32.407402 -24.969568) (xy 32.387479 -24.917477) (xy 32.375353 -24.86304)
			(xy 32.371282 -24.807418) (xy 18.878223 -24.807418) (xy 18.903079 -24.844988) (xy 18.926751 -24.895485)
			(xy 18.942819 -24.948892) (xy 18.950939 -25.004068) (xy 18.951448 -25.031954) (xy 18.950939 -25.05984)
			(xy 18.942819 -25.115016) (xy 18.926751 -25.168423) (xy 18.903079 -25.21892) (xy 18.872306 -25.265433)
			(xy 18.835089 -25.30697) (xy 18.792221 -25.342645) (xy 18.744615 -25.371699) (xy 18.701327 -25.390094)
			(xy 39.809164 -25.390094) (xy 39.813235 -25.334472) (xy 39.825361 -25.280035) (xy 39.845284 -25.227944)
			(xy 39.87258 -25.179309) (xy 39.906666 -25.135166) (xy 39.946815 -25.096457) (xy 39.992173 -25.064006)
			(xy 40.041773 -25.038505) (xy 40.094557 -25.020498) (xy 40.1494 -25.010368) (xy 40.205134 -25.008331)
			(xy 40.260571 -25.014431) (xy 40.314528 -25.028537) (xy 40.322569 -25.031954) (xy 44.18787 -25.031954)
			(xy 44.191941 -24.976332) (xy 44.204067 -24.921895) (xy 44.22399 -24.869804) (xy 44.251286 -24.821169)
			(xy 44.285372 -24.777026) (xy 44.325521 -24.738317) (xy 44.370879 -24.705866) (xy 44.420479 -24.680365)
			(xy 44.473263 -24.662358) (xy 44.528106 -24.652228) (xy 44.58384 -24.650191) (xy 44.639277 -24.656291)
			(xy 44.693234 -24.670397) (xy 44.744563 -24.692209) (xy 44.792169 -24.721263) (xy 44.835037 -24.756938)
			(xy 44.836571 -24.75865) (xy 46.868586 -24.75865) (xy 46.872657 -24.703028) (xy 46.884783 -24.648591)
			(xy 46.904706 -24.5965) (xy 46.932002 -24.547865) (xy 46.966088 -24.503722) (xy 47.006237 -24.465013)
			(xy 47.051595 -24.432562) (xy 47.101195 -24.407061) (xy 47.153979 -24.389054) (xy 47.208822 -24.378924)
			(xy 47.264556 -24.376887) (xy 47.319993 -24.382987) (xy 47.37395 -24.397093) (xy 47.425279 -24.418905)
			(xy 47.472885 -24.447959) (xy 47.515753 -24.483634) (xy 47.55297 -24.525171) (xy 47.583743 -24.571684)
			(xy 47.607415 -24.622181) (xy 47.623483 -24.675588) (xy 47.631603 -24.730764) (xy 47.632112 -24.75865)
			(xy 47.631603 -24.786536) (xy 47.62853 -24.807418) (xy 58.37123 -24.807418) (xy 58.375301 -24.751796)
			(xy 58.387427 -24.697359) (xy 58.40735 -24.645268) (xy 58.434646 -24.596633) (xy 58.468732 -24.55249)
			(xy 58.508881 -24.513781) (xy 58.554239 -24.48133) (xy 58.603839 -24.455829) (xy 58.656623 -24.437822)
			(xy 58.711466 -24.427692) (xy 58.7672 -24.425655) (xy 58.822637 -24.431755) (xy 58.876594 -24.445861)
			(xy 58.927923 -24.467673) (xy 58.975529 -24.496727) (xy 59.018397 -24.532402) (xy 59.055614 -24.573939)
			(xy 59.086387 -24.620452) (xy 59.110059 -24.670949) (xy 59.126127 -24.724356) (xy 59.134247 -24.779532)
			(xy 59.134756 -24.807418) (xy 60.620146 -24.807418) (xy 60.624217 -24.751796) (xy 60.636343 -24.697359)
			(xy 60.656266 -24.645268) (xy 60.683562 -24.596633) (xy 60.717648 -24.55249) (xy 60.757797 -24.513781)
			(xy 60.803155 -24.48133) (xy 60.852755 -24.455829) (xy 60.905539 -24.437822) (xy 60.960382 -24.427692)
			(xy 61.016116 -24.425655) (xy 61.071553 -24.431755) (xy 61.12551 -24.445861) (xy 61.176839 -24.467673)
			(xy 61.224445 -24.496727) (xy 61.267313 -24.532402) (xy 61.30453 -24.573939) (xy 61.335303 -24.620452)
			(xy 61.358975 -24.670949) (xy 61.375043 -24.724356) (xy 61.383163 -24.779532) (xy 61.383672 -24.807418)
			(xy 61.383163 -24.835304) (xy 61.375043 -24.89048) (xy 61.358975 -24.943887) (xy 61.335303 -24.994384)
			(xy 61.30453 -25.040897) (xy 61.267313 -25.082434) (xy 61.224445 -25.118109) (xy 61.176839 -25.147163)
			(xy 61.12551 -25.168975) (xy 61.071553 -25.183081) (xy 61.016116 -25.189181) (xy 60.960382 -25.187144)
			(xy 60.905539 -25.177014) (xy 60.852755 -25.159007) (xy 60.803155 -25.133506) (xy 60.757797 -25.101055)
			(xy 60.717648 -25.062346) (xy 60.683562 -25.018203) (xy 60.656266 -24.969568) (xy 60.636343 -24.917477)
			(xy 60.624217 -24.86304) (xy 60.620146 -24.807418) (xy 59.134756 -24.807418) (xy 59.134247 -24.835304)
			(xy 59.126127 -24.89048) (xy 59.110059 -24.943887) (xy 59.086387 -24.994384) (xy 59.055614 -25.040897)
			(xy 59.018397 -25.082434) (xy 58.975529 -25.118109) (xy 58.927923 -25.147163) (xy 58.876594 -25.168975)
			(xy 58.822637 -25.183081) (xy 58.7672 -25.189181) (xy 58.711466 -25.187144) (xy 58.656623 -25.177014)
			(xy 58.603839 -25.159007) (xy 58.554239 -25.133506) (xy 58.508881 -25.101055) (xy 58.468732 -25.062346)
			(xy 58.434646 -25.018203) (xy 58.40735 -24.969568) (xy 58.387427 -24.917477) (xy 58.375301 -24.86304)
			(xy 58.37123 -24.807418) (xy 47.62853 -24.807418) (xy 47.623483 -24.841712) (xy 47.607415 -24.895119)
			(xy 47.583743 -24.945616) (xy 47.55297 -24.992129) (xy 47.515753 -25.033666) (xy 47.472885 -25.069341)
			(xy 47.425279 -25.098395) (xy 47.37395 -25.120207) (xy 47.319993 -25.134313) (xy 47.264556 -25.140413)
			(xy 47.208822 -25.138376) (xy 47.153979 -25.128246) (xy 47.101195 -25.110239) (xy 47.051595 -25.084738)
			(xy 47.006237 -25.052287) (xy 46.966088 -25.013578) (xy 46.932002 -24.969435) (xy 46.904706 -24.9208)
			(xy 46.884783 -24.868709) (xy 46.872657 -24.814272) (xy 46.868586 -24.75865) (xy 44.836571 -24.75865)
			(xy 44.872254 -24.798475) (xy 44.903027 -24.844988) (xy 44.926699 -24.895485) (xy 44.942767 -24.948892)
			(xy 44.950887 -25.004068) (xy 44.951396 -25.031954) (xy 44.950887 -25.05984) (xy 44.942767 -25.115016)
			(xy 44.926699 -25.168423) (xy 44.903027 -25.21892) (xy 44.872254 -25.265433) (xy 44.835037 -25.30697)
			(xy 44.792169 -25.342645) (xy 44.744563 -25.371699) (xy 44.693234 -25.393511) (xy 44.639277 -25.407617)
			(xy 44.58384 -25.413717) (xy 44.528106 -25.41168) (xy 44.473263 -25.40155) (xy 44.420479 -25.383543)
			(xy 44.370879 -25.358042) (xy 44.325521 -25.325591) (xy 44.285372 -25.286882) (xy 44.251286 -25.242739)
			(xy 44.22399 -25.194104) (xy 44.204067 -25.142013) (xy 44.191941 -25.087576) (xy 44.18787 -25.031954)
			(xy 40.322569 -25.031954) (xy 40.365857 -25.050349) (xy 40.413463 -25.079403) (xy 40.456331 -25.115078)
			(xy 40.493548 -25.156615) (xy 40.524321 -25.203128) (xy 40.547993 -25.253625) (xy 40.564061 -25.307032)
			(xy 40.572181 -25.362208) (xy 40.57269 -25.390094) (xy 40.572181 -25.41798) (xy 40.564061 -25.473156)
			(xy 40.547993 -25.526563) (xy 40.532904 -25.55875) (xy 48.64176 -25.55875) (xy 48.645831 -25.503128)
			(xy 48.657957 -25.448691) (xy 48.67788 -25.3966) (xy 48.705176 -25.347965) (xy 48.739262 -25.303822)
			(xy 48.779411 -25.265113) (xy 48.824769 -25.232662) (xy 48.874369 -25.207161) (xy 48.927153 -25.189154)
			(xy 48.981996 -25.179024) (xy 49.03773 -25.176987) (xy 49.093167 -25.183087) (xy 49.147124 -25.197193)
			(xy 49.198453 -25.219005) (xy 49.246059 -25.248059) (xy 49.288927 -25.283734) (xy 49.326144 -25.325271)
			(xy 49.356917 -25.371784) (xy 49.3655 -25.390094) (xy 65.809112 -25.390094) (xy 65.813183 -25.334472)
			(xy 65.825309 -25.280035) (xy 65.845232 -25.227944) (xy 65.872528 -25.179309) (xy 65.906614 -25.135166)
			(xy 65.946763 -25.096457) (xy 65.992121 -25.064006) (xy 66.041721 -25.038505) (xy 66.094505 -25.020498)
			(xy 66.149348 -25.010368) (xy 66.205082 -25.008331) (xy 66.260519 -25.014431) (xy 66.314476 -25.028537)
			(xy 66.322517 -25.031954) (xy 70.187818 -25.031954) (xy 70.191889 -24.976332) (xy 70.204015 -24.921895)
			(xy 70.223938 -24.869804) (xy 70.251234 -24.821169) (xy 70.28532 -24.777026) (xy 70.325469 -24.738317)
			(xy 70.370827 -24.705866) (xy 70.420427 -24.680365) (xy 70.473211 -24.662358) (xy 70.528054 -24.652228)
			(xy 70.583788 -24.650191) (xy 70.639225 -24.656291) (xy 70.693182 -24.670397) (xy 70.744511 -24.692209)
			(xy 70.792117 -24.721263) (xy 70.834985 -24.756938) (xy 70.836519 -24.75865) (xy 72.868534 -24.75865)
			(xy 72.872605 -24.703028) (xy 72.884731 -24.648591) (xy 72.904654 -24.5965) (xy 72.93195 -24.547865)
			(xy 72.966036 -24.503722) (xy 73.006185 -24.465013) (xy 73.051543 -24.432562) (xy 73.101143 -24.407061)
			(xy 73.153927 -24.389054) (xy 73.20877 -24.378924) (xy 73.264504 -24.376887) (xy 73.319941 -24.382987)
			(xy 73.373898 -24.397093) (xy 73.425227 -24.418905) (xy 73.472833 -24.447959) (xy 73.515701 -24.483634)
			(xy 73.552918 -24.525171) (xy 73.583691 -24.571684) (xy 73.607363 -24.622181) (xy 73.623431 -24.675588)
			(xy 73.631551 -24.730764) (xy 73.63206 -24.75865) (xy 73.631551 -24.786536) (xy 73.628478 -24.807418)
			(xy 84.371178 -24.807418) (xy 84.375249 -24.751796) (xy 84.387375 -24.697359) (xy 84.407298 -24.645268)
			(xy 84.434594 -24.596633) (xy 84.46868 -24.55249) (xy 84.508829 -24.513781) (xy 84.554187 -24.48133)
			(xy 84.603787 -24.455829) (xy 84.656571 -24.437822) (xy 84.711414 -24.427692) (xy 84.767148 -24.425655)
			(xy 84.822585 -24.431755) (xy 84.876542 -24.445861) (xy 84.927871 -24.467673) (xy 84.975477 -24.496727)
			(xy 85.018345 -24.532402) (xy 85.055562 -24.573939) (xy 85.086335 -24.620452) (xy 85.110007 -24.670949)
			(xy 85.126075 -24.724356) (xy 85.134195 -24.779532) (xy 85.134704 -24.807418) (xy 86.620094 -24.807418)
			(xy 86.624165 -24.751796) (xy 86.636291 -24.697359) (xy 86.656214 -24.645268) (xy 86.68351 -24.596633)
			(xy 86.717596 -24.55249) (xy 86.757745 -24.513781) (xy 86.803103 -24.48133) (xy 86.852703 -24.455829)
			(xy 86.905487 -24.437822) (xy 86.96033 -24.427692) (xy 87.016064 -24.425655) (xy 87.071501 -24.431755)
			(xy 87.125458 -24.445861) (xy 87.176787 -24.467673) (xy 87.224393 -24.496727) (xy 87.267261 -24.532402)
			(xy 87.304478 -24.573939) (xy 87.335251 -24.620452) (xy 87.358923 -24.670949) (xy 87.374991 -24.724356)
			(xy 87.383111 -24.779532) (xy 87.38362 -24.807418) (xy 87.383111 -24.835304) (xy 87.374991 -24.89048)
			(xy 87.358923 -24.943887) (xy 87.335251 -24.994384) (xy 87.304478 -25.040897) (xy 87.267261 -25.082434)
			(xy 87.224393 -25.118109) (xy 87.176787 -25.147163) (xy 87.125458 -25.168975) (xy 87.071501 -25.183081)
			(xy 87.016064 -25.189181) (xy 86.96033 -25.187144) (xy 86.905487 -25.177014) (xy 86.852703 -25.159007)
			(xy 86.803103 -25.133506) (xy 86.757745 -25.101055) (xy 86.717596 -25.062346) (xy 86.68351 -25.018203)
			(xy 86.656214 -24.969568) (xy 86.636291 -24.917477) (xy 86.624165 -24.86304) (xy 86.620094 -24.807418)
			(xy 85.134704 -24.807418) (xy 85.134195 -24.835304) (xy 85.126075 -24.89048) (xy 85.110007 -24.943887)
			(xy 85.086335 -24.994384) (xy 85.055562 -25.040897) (xy 85.018345 -25.082434) (xy 84.975477 -25.118109)
			(xy 84.927871 -25.147163) (xy 84.876542 -25.168975) (xy 84.822585 -25.183081) (xy 84.767148 -25.189181)
			(xy 84.711414 -25.187144) (xy 84.656571 -25.177014) (xy 84.603787 -25.159007) (xy 84.554187 -25.133506)
			(xy 84.508829 -25.101055) (xy 84.46868 -25.062346) (xy 84.434594 -25.018203) (xy 84.407298 -24.969568)
			(xy 84.387375 -24.917477) (xy 84.375249 -24.86304) (xy 84.371178 -24.807418) (xy 73.628478 -24.807418)
			(xy 73.623431 -24.841712) (xy 73.607363 -24.895119) (xy 73.583691 -24.945616) (xy 73.552918 -24.992129)
			(xy 73.515701 -25.033666) (xy 73.472833 -25.069341) (xy 73.425227 -25.098395) (xy 73.373898 -25.120207)
			(xy 73.319941 -25.134313) (xy 73.264504 -25.140413) (xy 73.20877 -25.138376) (xy 73.153927 -25.128246)
			(xy 73.101143 -25.110239) (xy 73.051543 -25.084738) (xy 73.006185 -25.052287) (xy 72.966036 -25.013578)
			(xy 72.93195 -24.969435) (xy 72.904654 -24.9208) (xy 72.884731 -24.868709) (xy 72.872605 -24.814272)
			(xy 72.868534 -24.75865) (xy 70.836519 -24.75865) (xy 70.872202 -24.798475) (xy 70.902975 -24.844988)
			(xy 70.926647 -24.895485) (xy 70.942715 -24.948892) (xy 70.950835 -25.004068) (xy 70.951344 -25.031954)
			(xy 70.950835 -25.05984) (xy 70.942715 -25.115016) (xy 70.926647 -25.168423) (xy 70.902975 -25.21892)
			(xy 70.872202 -25.265433) (xy 70.834985 -25.30697) (xy 70.792117 -25.342645) (xy 70.744511 -25.371699)
			(xy 70.693182 -25.393511) (xy 70.639225 -25.407617) (xy 70.583788 -25.413717) (xy 70.528054 -25.41168)
			(xy 70.473211 -25.40155) (xy 70.420427 -25.383543) (xy 70.370827 -25.358042) (xy 70.325469 -25.325591)
			(xy 70.28532 -25.286882) (xy 70.251234 -25.242739) (xy 70.223938 -25.194104) (xy 70.204015 -25.142013)
			(xy 70.191889 -25.087576) (xy 70.187818 -25.031954) (xy 66.322517 -25.031954) (xy 66.365805 -25.050349)
			(xy 66.413411 -25.079403) (xy 66.456279 -25.115078) (xy 66.493496 -25.156615) (xy 66.524269 -25.203128)
			(xy 66.547941 -25.253625) (xy 66.564009 -25.307032) (xy 66.572129 -25.362208) (xy 66.572638 -25.390094)
			(xy 66.572129 -25.41798) (xy 66.564009 -25.473156) (xy 66.547941 -25.526563) (xy 66.532852 -25.55875)
			(xy 74.641708 -25.55875) (xy 74.645779 -25.503128) (xy 74.657905 -25.448691) (xy 74.677828 -25.3966)
			(xy 74.705124 -25.347965) (xy 74.73921 -25.303822) (xy 74.779359 -25.265113) (xy 74.824717 -25.232662)
			(xy 74.874317 -25.207161) (xy 74.927101 -25.189154) (xy 74.981944 -25.179024) (xy 75.037678 -25.176987)
			(xy 75.093115 -25.183087) (xy 75.147072 -25.197193) (xy 75.198401 -25.219005) (xy 75.246007 -25.248059)
			(xy 75.288875 -25.283734) (xy 75.326092 -25.325271) (xy 75.356865 -25.371784) (xy 75.365448 -25.390094)
			(xy 91.80906 -25.390094) (xy 91.813131 -25.334472) (xy 91.825257 -25.280035) (xy 91.84518 -25.227944)
			(xy 91.872476 -25.179309) (xy 91.906562 -25.135166) (xy 91.946711 -25.096457) (xy 91.992069 -25.064006)
			(xy 92.041669 -25.038505) (xy 92.094453 -25.020498) (xy 92.149296 -25.010368) (xy 92.20503 -25.008331)
			(xy 92.260467 -25.014431) (xy 92.314424 -25.028537) (xy 92.322465 -25.031954) (xy 96.187766 -25.031954)
			(xy 96.191837 -24.976332) (xy 96.203963 -24.921895) (xy 96.223886 -24.869804) (xy 96.251182 -24.821169)
			(xy 96.285268 -24.777026) (xy 96.325417 -24.738317) (xy 96.370775 -24.705866) (xy 96.420375 -24.680365)
			(xy 96.473159 -24.662358) (xy 96.528002 -24.652228) (xy 96.583736 -24.650191) (xy 96.639173 -24.656291)
			(xy 96.69313 -24.670397) (xy 96.744459 -24.692209) (xy 96.792065 -24.721263) (xy 96.834933 -24.756938)
			(xy 96.836467 -24.75865) (xy 98.868482 -24.75865) (xy 98.872553 -24.703028) (xy 98.884679 -24.648591)
			(xy 98.904602 -24.5965) (xy 98.931898 -24.547865) (xy 98.965984 -24.503722) (xy 99.006133 -24.465013)
			(xy 99.051491 -24.432562) (xy 99.101091 -24.407061) (xy 99.153875 -24.389054) (xy 99.208718 -24.378924)
			(xy 99.264452 -24.376887) (xy 99.319889 -24.382987) (xy 99.373846 -24.397093) (xy 99.425175 -24.418905)
			(xy 99.472781 -24.447959) (xy 99.515649 -24.483634) (xy 99.552866 -24.525171) (xy 99.583639 -24.571684)
			(xy 99.607311 -24.622181) (xy 99.623379 -24.675588) (xy 99.631499 -24.730764) (xy 99.632008 -24.75865)
			(xy 99.631499 -24.786536) (xy 99.628426 -24.807418) (xy 122.471432 -24.807418) (xy 122.475503 -24.751796)
			(xy 122.487629 -24.697359) (xy 122.507552 -24.645268) (xy 122.534848 -24.596633) (xy 122.568934 -24.55249)
			(xy 122.609083 -24.513781) (xy 122.654441 -24.48133) (xy 122.704041 -24.455829) (xy 122.756825 -24.437822)
			(xy 122.811668 -24.427692) (xy 122.867402 -24.425655) (xy 122.922839 -24.431755) (xy 122.976796 -24.445861)
			(xy 123.028125 -24.467673) (xy 123.075731 -24.496727) (xy 123.118599 -24.532402) (xy 123.155816 -24.573939)
			(xy 123.186589 -24.620452) (xy 123.210261 -24.670949) (xy 123.226329 -24.724356) (xy 123.234449 -24.779532)
			(xy 123.234958 -24.807418) (xy 124.720348 -24.807418) (xy 124.724419 -24.751796) (xy 124.736545 -24.697359)
			(xy 124.756468 -24.645268) (xy 124.783764 -24.596633) (xy 124.81785 -24.55249) (xy 124.857999 -24.513781)
			(xy 124.903357 -24.48133) (xy 124.952957 -24.455829) (xy 125.005741 -24.437822) (xy 125.060584 -24.427692)
			(xy 125.116318 -24.425655) (xy 125.171755 -24.431755) (xy 125.225712 -24.445861) (xy 125.277041 -24.467673)
			(xy 125.324647 -24.496727) (xy 125.367515 -24.532402) (xy 125.404732 -24.573939) (xy 125.435505 -24.620452)
			(xy 125.459177 -24.670949) (xy 125.475245 -24.724356) (xy 125.483365 -24.779532) (xy 125.483874 -24.807418)
			(xy 125.483365 -24.835304) (xy 125.475245 -24.89048) (xy 125.459177 -24.943887) (xy 125.435505 -24.994384)
			(xy 125.404732 -25.040897) (xy 125.367515 -25.082434) (xy 125.324647 -25.118109) (xy 125.277041 -25.147163)
			(xy 125.225712 -25.168975) (xy 125.171755 -25.183081) (xy 125.116318 -25.189181) (xy 125.060584 -25.187144)
			(xy 125.005741 -25.177014) (xy 124.952957 -25.159007) (xy 124.903357 -25.133506) (xy 124.857999 -25.101055)
			(xy 124.81785 -25.062346) (xy 124.783764 -25.018203) (xy 124.756468 -24.969568) (xy 124.736545 -24.917477)
			(xy 124.724419 -24.86304) (xy 124.720348 -24.807418) (xy 123.234958 -24.807418) (xy 123.234449 -24.835304)
			(xy 123.226329 -24.89048) (xy 123.210261 -24.943887) (xy 123.186589 -24.994384) (xy 123.155816 -25.040897)
			(xy 123.118599 -25.082434) (xy 123.075731 -25.118109) (xy 123.028125 -25.147163) (xy 122.976796 -25.168975)
			(xy 122.922839 -25.183081) (xy 122.867402 -25.189181) (xy 122.811668 -25.187144) (xy 122.756825 -25.177014)
			(xy 122.704041 -25.159007) (xy 122.654441 -25.133506) (xy 122.609083 -25.101055) (xy 122.568934 -25.062346)
			(xy 122.534848 -25.018203) (xy 122.507552 -24.969568) (xy 122.487629 -24.917477) (xy 122.475503 -24.86304)
			(xy 122.471432 -24.807418) (xy 99.628426 -24.807418) (xy 99.623379 -24.841712) (xy 99.607311 -24.895119)
			(xy 99.583639 -24.945616) (xy 99.552866 -24.992129) (xy 99.515649 -25.033666) (xy 99.472781 -25.069341)
			(xy 99.425175 -25.098395) (xy 99.373846 -25.120207) (xy 99.319889 -25.134313) (xy 99.264452 -25.140413)
			(xy 99.208718 -25.138376) (xy 99.153875 -25.128246) (xy 99.101091 -25.110239) (xy 99.051491 -25.084738)
			(xy 99.006133 -25.052287) (xy 98.965984 -25.013578) (xy 98.931898 -24.969435) (xy 98.904602 -24.9208)
			(xy 98.884679 -24.868709) (xy 98.872553 -24.814272) (xy 98.868482 -24.75865) (xy 96.836467 -24.75865)
			(xy 96.87215 -24.798475) (xy 96.902923 -24.844988) (xy 96.926595 -24.895485) (xy 96.942663 -24.948892)
			(xy 96.950783 -25.004068) (xy 96.951292 -25.031954) (xy 96.950783 -25.05984) (xy 96.942663 -25.115016)
			(xy 96.926595 -25.168423) (xy 96.902923 -25.21892) (xy 96.87215 -25.265433) (xy 96.834933 -25.30697)
			(xy 96.792065 -25.342645) (xy 96.744459 -25.371699) (xy 96.69313 -25.393511) (xy 96.639173 -25.407617)
			(xy 96.583736 -25.413717) (xy 96.528002 -25.41168) (xy 96.473159 -25.40155) (xy 96.420375 -25.383543)
			(xy 96.370775 -25.358042) (xy 96.325417 -25.325591) (xy 96.285268 -25.286882) (xy 96.251182 -25.242739)
			(xy 96.223886 -25.194104) (xy 96.203963 -25.142013) (xy 96.191837 -25.087576) (xy 96.187766 -25.031954)
			(xy 92.322465 -25.031954) (xy 92.365753 -25.050349) (xy 92.413359 -25.079403) (xy 92.456227 -25.115078)
			(xy 92.493444 -25.156615) (xy 92.524217 -25.203128) (xy 92.547889 -25.253625) (xy 92.563957 -25.307032)
			(xy 92.572077 -25.362208) (xy 92.572586 -25.390094) (xy 92.572077 -25.41798) (xy 92.563957 -25.473156)
			(xy 92.547889 -25.526563) (xy 92.5328 -25.55875) (xy 100.641656 -25.55875) (xy 100.645727 -25.503128)
			(xy 100.657853 -25.448691) (xy 100.677776 -25.3966) (xy 100.705072 -25.347965) (xy 100.739158 -25.303822)
			(xy 100.779307 -25.265113) (xy 100.824665 -25.232662) (xy 100.874265 -25.207161) (xy 100.927049 -25.189154)
			(xy 100.981892 -25.179024) (xy 101.037626 -25.176987) (xy 101.093063 -25.183087) (xy 101.14702 -25.197193)
			(xy 101.198349 -25.219005) (xy 101.245955 -25.248059) (xy 101.288823 -25.283734) (xy 101.32604 -25.325271)
			(xy 101.356813 -25.371784) (xy 101.365396 -25.390094) (xy 129.909314 -25.390094) (xy 129.913385 -25.334472)
			(xy 129.925511 -25.280035) (xy 129.945434 -25.227944) (xy 129.97273 -25.179309) (xy 130.006816 -25.135166)
			(xy 130.046965 -25.096457) (xy 130.092323 -25.064006) (xy 130.141923 -25.038505) (xy 130.194707 -25.020498)
			(xy 130.24955 -25.010368) (xy 130.305284 -25.008331) (xy 130.360721 -25.014431) (xy 130.414678 -25.028537)
			(xy 130.422719 -25.031954) (xy 134.28802 -25.031954) (xy 134.292091 -24.976332) (xy 134.304217 -24.921895)
			(xy 134.32414 -24.869804) (xy 134.351436 -24.821169) (xy 134.385522 -24.777026) (xy 134.425671 -24.738317)
			(xy 134.471029 -24.705866) (xy 134.520629 -24.680365) (xy 134.573413 -24.662358) (xy 134.628256 -24.652228)
			(xy 134.68399 -24.650191) (xy 134.739427 -24.656291) (xy 134.793384 -24.670397) (xy 134.844713 -24.692209)
			(xy 134.892319 -24.721263) (xy 134.935187 -24.756938) (xy 134.936721 -24.75865) (xy 136.968736 -24.75865)
			(xy 136.972807 -24.703028) (xy 136.984933 -24.648591) (xy 137.004856 -24.5965) (xy 137.032152 -24.547865)
			(xy 137.066238 -24.503722) (xy 137.106387 -24.465013) (xy 137.151745 -24.432562) (xy 137.201345 -24.407061)
			(xy 137.254129 -24.389054) (xy 137.308972 -24.378924) (xy 137.364706 -24.376887) (xy 137.420143 -24.382987)
			(xy 137.4741 -24.397093) (xy 137.525429 -24.418905) (xy 137.573035 -24.447959) (xy 137.615903 -24.483634)
			(xy 137.65312 -24.525171) (xy 137.683893 -24.571684) (xy 137.707565 -24.622181) (xy 137.723633 -24.675588)
			(xy 137.731753 -24.730764) (xy 137.732262 -24.75865) (xy 137.731753 -24.786536) (xy 137.72868 -24.807418)
			(xy 148.47138 -24.807418) (xy 148.475451 -24.751796) (xy 148.487577 -24.697359) (xy 148.5075 -24.645268)
			(xy 148.534796 -24.596633) (xy 148.568882 -24.55249) (xy 148.609031 -24.513781) (xy 148.654389 -24.48133)
			(xy 148.703989 -24.455829) (xy 148.756773 -24.437822) (xy 148.811616 -24.427692) (xy 148.86735 -24.425655)
			(xy 148.922787 -24.431755) (xy 148.976744 -24.445861) (xy 149.028073 -24.467673) (xy 149.075679 -24.496727)
			(xy 149.118547 -24.532402) (xy 149.155764 -24.573939) (xy 149.186537 -24.620452) (xy 149.210209 -24.670949)
			(xy 149.226277 -24.724356) (xy 149.234397 -24.779532) (xy 149.234906 -24.807418) (xy 150.720296 -24.807418)
			(xy 150.724367 -24.751796) (xy 150.736493 -24.697359) (xy 150.756416 -24.645268) (xy 150.783712 -24.596633)
			(xy 150.817798 -24.55249) (xy 150.857947 -24.513781) (xy 150.903305 -24.48133) (xy 150.952905 -24.455829)
			(xy 151.005689 -24.437822) (xy 151.060532 -24.427692) (xy 151.116266 -24.425655) (xy 151.171703 -24.431755)
			(xy 151.22566 -24.445861) (xy 151.276989 -24.467673) (xy 151.324595 -24.496727) (xy 151.367463 -24.532402)
			(xy 151.40468 -24.573939) (xy 151.435453 -24.620452) (xy 151.459125 -24.670949) (xy 151.475193 -24.724356)
			(xy 151.483313 -24.779532) (xy 151.483822 -24.807418) (xy 151.483313 -24.835304) (xy 151.475193 -24.89048)
			(xy 151.459125 -24.943887) (xy 151.435453 -24.994384) (xy 151.40468 -25.040897) (xy 151.367463 -25.082434)
			(xy 151.324595 -25.118109) (xy 151.276989 -25.147163) (xy 151.22566 -25.168975) (xy 151.171703 -25.183081)
			(xy 151.116266 -25.189181) (xy 151.060532 -25.187144) (xy 151.005689 -25.177014) (xy 150.952905 -25.159007)
			(xy 150.903305 -25.133506) (xy 150.857947 -25.101055) (xy 150.817798 -25.062346) (xy 150.783712 -25.018203)
			(xy 150.756416 -24.969568) (xy 150.736493 -24.917477) (xy 150.724367 -24.86304) (xy 150.720296 -24.807418)
			(xy 149.234906 -24.807418) (xy 149.234397 -24.835304) (xy 149.226277 -24.89048) (xy 149.210209 -24.943887)
			(xy 149.186537 -24.994384) (xy 149.155764 -25.040897) (xy 149.118547 -25.082434) (xy 149.075679 -25.118109)
			(xy 149.028073 -25.147163) (xy 148.976744 -25.168975) (xy 148.922787 -25.183081) (xy 148.86735 -25.189181)
			(xy 148.811616 -25.187144) (xy 148.756773 -25.177014) (xy 148.703989 -25.159007) (xy 148.654389 -25.133506)
			(xy 148.609031 -25.101055) (xy 148.568882 -25.062346) (xy 148.534796 -25.018203) (xy 148.5075 -24.969568)
			(xy 148.487577 -24.917477) (xy 148.475451 -24.86304) (xy 148.47138 -24.807418) (xy 137.72868 -24.807418)
			(xy 137.723633 -24.841712) (xy 137.707565 -24.895119) (xy 137.683893 -24.945616) (xy 137.65312 -24.992129)
			(xy 137.615903 -25.033666) (xy 137.573035 -25.069341) (xy 137.525429 -25.098395) (xy 137.4741 -25.120207)
			(xy 137.420143 -25.134313) (xy 137.364706 -25.140413) (xy 137.308972 -25.138376) (xy 137.254129 -25.128246)
			(xy 137.201345 -25.110239) (xy 137.151745 -25.084738) (xy 137.106387 -25.052287) (xy 137.066238 -25.013578)
			(xy 137.032152 -24.969435) (xy 137.004856 -24.9208) (xy 136.984933 -24.868709) (xy 136.972807 -24.814272)
			(xy 136.968736 -24.75865) (xy 134.936721 -24.75865) (xy 134.972404 -24.798475) (xy 135.003177 -24.844988)
			(xy 135.026849 -24.895485) (xy 135.042917 -24.948892) (xy 135.051037 -25.004068) (xy 135.051546 -25.031954)
			(xy 135.051037 -25.05984) (xy 135.042917 -25.115016) (xy 135.026849 -25.168423) (xy 135.003177 -25.21892)
			(xy 134.972404 -25.265433) (xy 134.935187 -25.30697) (xy 134.892319 -25.342645) (xy 134.844713 -25.371699)
			(xy 134.793384 -25.393511) (xy 134.739427 -25.407617) (xy 134.68399 -25.413717) (xy 134.628256 -25.41168)
			(xy 134.573413 -25.40155) (xy 134.520629 -25.383543) (xy 134.471029 -25.358042) (xy 134.425671 -25.325591)
			(xy 134.385522 -25.286882) (xy 134.351436 -25.242739) (xy 134.32414 -25.194104) (xy 134.304217 -25.142013)
			(xy 134.292091 -25.087576) (xy 134.28802 -25.031954) (xy 130.422719 -25.031954) (xy 130.466007 -25.050349)
			(xy 130.513613 -25.079403) (xy 130.556481 -25.115078) (xy 130.593698 -25.156615) (xy 130.624471 -25.203128)
			(xy 130.648143 -25.253625) (xy 130.664211 -25.307032) (xy 130.672331 -25.362208) (xy 130.67284 -25.390094)
			(xy 130.672331 -25.41798) (xy 130.664211 -25.473156) (xy 130.648143 -25.526563) (xy 130.633054 -25.55875)
			(xy 138.74191 -25.55875) (xy 138.745981 -25.503128) (xy 138.758107 -25.448691) (xy 138.77803 -25.3966)
			(xy 138.805326 -25.347965) (xy 138.839412 -25.303822) (xy 138.879561 -25.265113) (xy 138.924919 -25.232662)
			(xy 138.974519 -25.207161) (xy 139.027303 -25.189154) (xy 139.082146 -25.179024) (xy 139.13788 -25.176987)
			(xy 139.193317 -25.183087) (xy 139.247274 -25.197193) (xy 139.298603 -25.219005) (xy 139.346209 -25.248059)
			(xy 139.389077 -25.283734) (xy 139.426294 -25.325271) (xy 139.457067 -25.371784) (xy 139.46565 -25.390094)
			(xy 155.909262 -25.390094) (xy 155.913333 -25.334472) (xy 155.925459 -25.280035) (xy 155.945382 -25.227944)
			(xy 155.972678 -25.179309) (xy 156.006764 -25.135166) (xy 156.046913 -25.096457) (xy 156.092271 -25.064006)
			(xy 156.141871 -25.038505) (xy 156.194655 -25.020498) (xy 156.249498 -25.010368) (xy 156.305232 -25.008331)
			(xy 156.360669 -25.014431) (xy 156.414626 -25.028537) (xy 156.422667 -25.031954) (xy 160.287968 -25.031954)
			(xy 160.292039 -24.976332) (xy 160.304165 -24.921895) (xy 160.324088 -24.869804) (xy 160.351384 -24.821169)
			(xy 160.38547 -24.777026) (xy 160.425619 -24.738317) (xy 160.470977 -24.705866) (xy 160.520577 -24.680365)
			(xy 160.573361 -24.662358) (xy 160.628204 -24.652228) (xy 160.683938 -24.650191) (xy 160.739375 -24.656291)
			(xy 160.793332 -24.670397) (xy 160.844661 -24.692209) (xy 160.892267 -24.721263) (xy 160.935135 -24.756938)
			(xy 160.936669 -24.75865) (xy 162.968684 -24.75865) (xy 162.972755 -24.703028) (xy 162.984881 -24.648591)
			(xy 163.004804 -24.5965) (xy 163.0321 -24.547865) (xy 163.066186 -24.503722) (xy 163.106335 -24.465013)
			(xy 163.151693 -24.432562) (xy 163.201293 -24.407061) (xy 163.254077 -24.389054) (xy 163.30892 -24.378924)
			(xy 163.364654 -24.376887) (xy 163.420091 -24.382987) (xy 163.474048 -24.397093) (xy 163.525377 -24.418905)
			(xy 163.572983 -24.447959) (xy 163.615851 -24.483634) (xy 163.653068 -24.525171) (xy 163.683841 -24.571684)
			(xy 163.707513 -24.622181) (xy 163.723581 -24.675588) (xy 163.731701 -24.730764) (xy 163.73221 -24.75865)
			(xy 163.731701 -24.786536) (xy 163.728628 -24.807418) (xy 174.471328 -24.807418) (xy 174.475399 -24.751796)
			(xy 174.487525 -24.697359) (xy 174.507448 -24.645268) (xy 174.534744 -24.596633) (xy 174.56883 -24.55249)
			(xy 174.608979 -24.513781) (xy 174.654337 -24.48133) (xy 174.703937 -24.455829) (xy 174.756721 -24.437822)
			(xy 174.811564 -24.427692) (xy 174.867298 -24.425655) (xy 174.922735 -24.431755) (xy 174.976692 -24.445861)
			(xy 175.028021 -24.467673) (xy 175.075627 -24.496727) (xy 175.118495 -24.532402) (xy 175.155712 -24.573939)
			(xy 175.186485 -24.620452) (xy 175.210157 -24.670949) (xy 175.226225 -24.724356) (xy 175.234345 -24.779532)
			(xy 175.234854 -24.807418) (xy 176.720244 -24.807418) (xy 176.724315 -24.751796) (xy 176.736441 -24.697359)
			(xy 176.756364 -24.645268) (xy 176.78366 -24.596633) (xy 176.817746 -24.55249) (xy 176.857895 -24.513781)
			(xy 176.903253 -24.48133) (xy 176.952853 -24.455829) (xy 177.005637 -24.437822) (xy 177.06048 -24.427692)
			(xy 177.116214 -24.425655) (xy 177.171651 -24.431755) (xy 177.225608 -24.445861) (xy 177.276937 -24.467673)
			(xy 177.324543 -24.496727) (xy 177.367411 -24.532402) (xy 177.404628 -24.573939) (xy 177.435401 -24.620452)
			(xy 177.459073 -24.670949) (xy 177.475141 -24.724356) (xy 177.483261 -24.779532) (xy 177.48377 -24.807418)
			(xy 177.483261 -24.835304) (xy 177.475141 -24.89048) (xy 177.459073 -24.943887) (xy 177.435401 -24.994384)
			(xy 177.404628 -25.040897) (xy 177.367411 -25.082434) (xy 177.324543 -25.118109) (xy 177.276937 -25.147163)
			(xy 177.225608 -25.168975) (xy 177.171651 -25.183081) (xy 177.116214 -25.189181) (xy 177.06048 -25.187144)
			(xy 177.005637 -25.177014) (xy 176.952853 -25.159007) (xy 176.903253 -25.133506) (xy 176.857895 -25.101055)
			(xy 176.817746 -25.062346) (xy 176.78366 -25.018203) (xy 176.756364 -24.969568) (xy 176.736441 -24.917477)
			(xy 176.724315 -24.86304) (xy 176.720244 -24.807418) (xy 175.234854 -24.807418) (xy 175.234345 -24.835304)
			(xy 175.226225 -24.89048) (xy 175.210157 -24.943887) (xy 175.186485 -24.994384) (xy 175.155712 -25.040897)
			(xy 175.118495 -25.082434) (xy 175.075627 -25.118109) (xy 175.028021 -25.147163) (xy 174.976692 -25.168975)
			(xy 174.922735 -25.183081) (xy 174.867298 -25.189181) (xy 174.811564 -25.187144) (xy 174.756721 -25.177014)
			(xy 174.703937 -25.159007) (xy 174.654337 -25.133506) (xy 174.608979 -25.101055) (xy 174.56883 -25.062346)
			(xy 174.534744 -25.018203) (xy 174.507448 -24.969568) (xy 174.487525 -24.917477) (xy 174.475399 -24.86304)
			(xy 174.471328 -24.807418) (xy 163.728628 -24.807418) (xy 163.723581 -24.841712) (xy 163.707513 -24.895119)
			(xy 163.683841 -24.945616) (xy 163.653068 -24.992129) (xy 163.615851 -25.033666) (xy 163.572983 -25.069341)
			(xy 163.525377 -25.098395) (xy 163.474048 -25.120207) (xy 163.420091 -25.134313) (xy 163.364654 -25.140413)
			(xy 163.30892 -25.138376) (xy 163.254077 -25.128246) (xy 163.201293 -25.110239) (xy 163.151693 -25.084738)
			(xy 163.106335 -25.052287) (xy 163.066186 -25.013578) (xy 163.0321 -24.969435) (xy 163.004804 -24.9208)
			(xy 162.984881 -24.868709) (xy 162.972755 -24.814272) (xy 162.968684 -24.75865) (xy 160.936669 -24.75865)
			(xy 160.972352 -24.798475) (xy 161.003125 -24.844988) (xy 161.026797 -24.895485) (xy 161.042865 -24.948892)
			(xy 161.050985 -25.004068) (xy 161.051494 -25.031954) (xy 161.050985 -25.05984) (xy 161.042865 -25.115016)
			(xy 161.026797 -25.168423) (xy 161.003125 -25.21892) (xy 160.972352 -25.265433) (xy 160.935135 -25.30697)
			(xy 160.892267 -25.342645) (xy 160.844661 -25.371699) (xy 160.793332 -25.393511) (xy 160.739375 -25.407617)
			(xy 160.683938 -25.413717) (xy 160.628204 -25.41168) (xy 160.573361 -25.40155) (xy 160.520577 -25.383543)
			(xy 160.470977 -25.358042) (xy 160.425619 -25.325591) (xy 160.38547 -25.286882) (xy 160.351384 -25.242739)
			(xy 160.324088 -25.194104) (xy 160.304165 -25.142013) (xy 160.292039 -25.087576) (xy 160.287968 -25.031954)
			(xy 156.422667 -25.031954) (xy 156.465955 -25.050349) (xy 156.513561 -25.079403) (xy 156.556429 -25.115078)
			(xy 156.593646 -25.156615) (xy 156.624419 -25.203128) (xy 156.648091 -25.253625) (xy 156.664159 -25.307032)
			(xy 156.672279 -25.362208) (xy 156.672788 -25.390094) (xy 156.672279 -25.41798) (xy 156.664159 -25.473156)
			(xy 156.648091 -25.526563) (xy 156.633002 -25.55875) (xy 164.741858 -25.55875) (xy 164.745929 -25.503128)
			(xy 164.758055 -25.448691) (xy 164.777978 -25.3966) (xy 164.805274 -25.347965) (xy 164.83936 -25.303822)
			(xy 164.879509 -25.265113) (xy 164.924867 -25.232662) (xy 164.974467 -25.207161) (xy 165.027251 -25.189154)
			(xy 165.082094 -25.179024) (xy 165.137828 -25.176987) (xy 165.193265 -25.183087) (xy 165.247222 -25.197193)
			(xy 165.298551 -25.219005) (xy 165.346157 -25.248059) (xy 165.389025 -25.283734) (xy 165.426242 -25.325271)
			(xy 165.457015 -25.371784) (xy 165.465598 -25.390094) (xy 181.90921 -25.390094) (xy 181.913281 -25.334472)
			(xy 181.925407 -25.280035) (xy 181.94533 -25.227944) (xy 181.972626 -25.179309) (xy 182.006712 -25.135166)
			(xy 182.046861 -25.096457) (xy 182.092219 -25.064006) (xy 182.141819 -25.038505) (xy 182.194603 -25.020498)
			(xy 182.249446 -25.010368) (xy 182.30518 -25.008331) (xy 182.360617 -25.014431) (xy 182.414574 -25.028537)
			(xy 182.422615 -25.031954) (xy 186.287916 -25.031954) (xy 186.291987 -24.976332) (xy 186.304113 -24.921895)
			(xy 186.324036 -24.869804) (xy 186.351332 -24.821169) (xy 186.385418 -24.777026) (xy 186.425567 -24.738317)
			(xy 186.470925 -24.705866) (xy 186.520525 -24.680365) (xy 186.573309 -24.662358) (xy 186.628152 -24.652228)
			(xy 186.683886 -24.650191) (xy 186.739323 -24.656291) (xy 186.79328 -24.670397) (xy 186.844609 -24.692209)
			(xy 186.892215 -24.721263) (xy 186.935083 -24.756938) (xy 186.936617 -24.75865) (xy 188.968632 -24.75865)
			(xy 188.972703 -24.703028) (xy 188.984829 -24.648591) (xy 189.004752 -24.5965) (xy 189.032048 -24.547865)
			(xy 189.066134 -24.503722) (xy 189.106283 -24.465013) (xy 189.151641 -24.432562) (xy 189.201241 -24.407061)
			(xy 189.254025 -24.389054) (xy 189.308868 -24.378924) (xy 189.364602 -24.376887) (xy 189.420039 -24.382987)
			(xy 189.473996 -24.397093) (xy 189.525325 -24.418905) (xy 189.572931 -24.447959) (xy 189.615799 -24.483634)
			(xy 189.653016 -24.525171) (xy 189.683789 -24.571684) (xy 189.707461 -24.622181) (xy 189.723529 -24.675588)
			(xy 189.731649 -24.730764) (xy 189.732158 -24.75865) (xy 189.731649 -24.786536) (xy 189.728576 -24.807418)
			(xy 200.471276 -24.807418) (xy 200.475347 -24.751796) (xy 200.487473 -24.697359) (xy 200.507396 -24.645268)
			(xy 200.534692 -24.596633) (xy 200.568778 -24.55249) (xy 200.608927 -24.513781) (xy 200.654285 -24.48133)
			(xy 200.703885 -24.455829) (xy 200.756669 -24.437822) (xy 200.811512 -24.427692) (xy 200.867246 -24.425655)
			(xy 200.922683 -24.431755) (xy 200.97664 -24.445861) (xy 201.027969 -24.467673) (xy 201.075575 -24.496727)
			(xy 201.118443 -24.532402) (xy 201.15566 -24.573939) (xy 201.186433 -24.620452) (xy 201.210105 -24.670949)
			(xy 201.226173 -24.724356) (xy 201.234293 -24.779532) (xy 201.234802 -24.807418) (xy 202.720192 -24.807418)
			(xy 202.724263 -24.751796) (xy 202.736389 -24.697359) (xy 202.756312 -24.645268) (xy 202.783608 -24.596633)
			(xy 202.817694 -24.55249) (xy 202.857843 -24.513781) (xy 202.903201 -24.48133) (xy 202.952801 -24.455829)
			(xy 203.005585 -24.437822) (xy 203.060428 -24.427692) (xy 203.116162 -24.425655) (xy 203.171599 -24.431755)
			(xy 203.225556 -24.445861) (xy 203.276885 -24.467673) (xy 203.324491 -24.496727) (xy 203.367359 -24.532402)
			(xy 203.404576 -24.573939) (xy 203.435349 -24.620452) (xy 203.459021 -24.670949) (xy 203.475089 -24.724356)
			(xy 203.483209 -24.779532) (xy 203.483718 -24.807418) (xy 203.483209 -24.835304) (xy 203.475089 -24.89048)
			(xy 203.459021 -24.943887) (xy 203.435349 -24.994384) (xy 203.404576 -25.040897) (xy 203.367359 -25.082434)
			(xy 203.324491 -25.118109) (xy 203.276885 -25.147163) (xy 203.225556 -25.168975) (xy 203.171599 -25.183081)
			(xy 203.116162 -25.189181) (xy 203.060428 -25.187144) (xy 203.005585 -25.177014) (xy 202.952801 -25.159007)
			(xy 202.903201 -25.133506) (xy 202.857843 -25.101055) (xy 202.817694 -25.062346) (xy 202.783608 -25.018203)
			(xy 202.756312 -24.969568) (xy 202.736389 -24.917477) (xy 202.724263 -24.86304) (xy 202.720192 -24.807418)
			(xy 201.234802 -24.807418) (xy 201.234293 -24.835304) (xy 201.226173 -24.89048) (xy 201.210105 -24.943887)
			(xy 201.186433 -24.994384) (xy 201.15566 -25.040897) (xy 201.118443 -25.082434) (xy 201.075575 -25.118109)
			(xy 201.027969 -25.147163) (xy 200.97664 -25.168975) (xy 200.922683 -25.183081) (xy 200.867246 -25.189181)
			(xy 200.811512 -25.187144) (xy 200.756669 -25.177014) (xy 200.703885 -25.159007) (xy 200.654285 -25.133506)
			(xy 200.608927 -25.101055) (xy 200.568778 -25.062346) (xy 200.534692 -25.018203) (xy 200.507396 -24.969568)
			(xy 200.487473 -24.917477) (xy 200.475347 -24.86304) (xy 200.471276 -24.807418) (xy 189.728576 -24.807418)
			(xy 189.723529 -24.841712) (xy 189.707461 -24.895119) (xy 189.683789 -24.945616) (xy 189.653016 -24.992129)
			(xy 189.615799 -25.033666) (xy 189.572931 -25.069341) (xy 189.525325 -25.098395) (xy 189.473996 -25.120207)
			(xy 189.420039 -25.134313) (xy 189.364602 -25.140413) (xy 189.308868 -25.138376) (xy 189.254025 -25.128246)
			(xy 189.201241 -25.110239) (xy 189.151641 -25.084738) (xy 189.106283 -25.052287) (xy 189.066134 -25.013578)
			(xy 189.032048 -24.969435) (xy 189.004752 -24.9208) (xy 188.984829 -24.868709) (xy 188.972703 -24.814272)
			(xy 188.968632 -24.75865) (xy 186.936617 -24.75865) (xy 186.9723 -24.798475) (xy 187.003073 -24.844988)
			(xy 187.026745 -24.895485) (xy 187.042813 -24.948892) (xy 187.050933 -25.004068) (xy 187.051442 -25.031954)
			(xy 187.050933 -25.05984) (xy 187.042813 -25.115016) (xy 187.026745 -25.168423) (xy 187.003073 -25.21892)
			(xy 186.9723 -25.265433) (xy 186.935083 -25.30697) (xy 186.892215 -25.342645) (xy 186.844609 -25.371699)
			(xy 186.79328 -25.393511) (xy 186.739323 -25.407617) (xy 186.683886 -25.413717) (xy 186.628152 -25.41168)
			(xy 186.573309 -25.40155) (xy 186.520525 -25.383543) (xy 186.470925 -25.358042) (xy 186.425567 -25.325591)
			(xy 186.385418 -25.286882) (xy 186.351332 -25.242739) (xy 186.324036 -25.194104) (xy 186.304113 -25.142013)
			(xy 186.291987 -25.087576) (xy 186.287916 -25.031954) (xy 182.422615 -25.031954) (xy 182.465903 -25.050349)
			(xy 182.513509 -25.079403) (xy 182.556377 -25.115078) (xy 182.593594 -25.156615) (xy 182.624367 -25.203128)
			(xy 182.648039 -25.253625) (xy 182.664107 -25.307032) (xy 182.672227 -25.362208) (xy 182.672736 -25.390094)
			(xy 182.672227 -25.41798) (xy 182.664107 -25.473156) (xy 182.648039 -25.526563) (xy 182.63295 -25.55875)
			(xy 190.741806 -25.55875) (xy 190.745877 -25.503128) (xy 190.758003 -25.448691) (xy 190.777926 -25.3966)
			(xy 190.805222 -25.347965) (xy 190.839308 -25.303822) (xy 190.879457 -25.265113) (xy 190.924815 -25.232662)
			(xy 190.974415 -25.207161) (xy 191.027199 -25.189154) (xy 191.082042 -25.179024) (xy 191.137776 -25.176987)
			(xy 191.193213 -25.183087) (xy 191.24717 -25.197193) (xy 191.298499 -25.219005) (xy 191.346105 -25.248059)
			(xy 191.388973 -25.283734) (xy 191.42619 -25.325271) (xy 191.456963 -25.371784) (xy 191.465546 -25.390094)
			(xy 207.909158 -25.390094) (xy 207.913229 -25.334472) (xy 207.925355 -25.280035) (xy 207.945278 -25.227944)
			(xy 207.972574 -25.179309) (xy 208.00666 -25.135166) (xy 208.046809 -25.096457) (xy 208.092167 -25.064006)
			(xy 208.141767 -25.038505) (xy 208.194551 -25.020498) (xy 208.249394 -25.010368) (xy 208.305128 -25.008331)
			(xy 208.360565 -25.014431) (xy 208.414522 -25.028537) (xy 208.422563 -25.031954) (xy 212.287864 -25.031954)
			(xy 212.291935 -24.976332) (xy 212.304061 -24.921895) (xy 212.323984 -24.869804) (xy 212.35128 -24.821169)
			(xy 212.385366 -24.777026) (xy 212.425515 -24.738317) (xy 212.470873 -24.705866) (xy 212.520473 -24.680365)
			(xy 212.573257 -24.662358) (xy 212.6281 -24.652228) (xy 212.683834 -24.650191) (xy 212.739271 -24.656291)
			(xy 212.793228 -24.670397) (xy 212.844557 -24.692209) (xy 212.892163 -24.721263) (xy 212.935031 -24.756938)
			(xy 212.936565 -24.75865) (xy 214.96858 -24.75865) (xy 214.972651 -24.703028) (xy 214.984777 -24.648591)
			(xy 215.0047 -24.5965) (xy 215.031996 -24.547865) (xy 215.066082 -24.503722) (xy 215.106231 -24.465013)
			(xy 215.151589 -24.432562) (xy 215.201189 -24.407061) (xy 215.253973 -24.389054) (xy 215.308816 -24.378924)
			(xy 215.36455 -24.376887) (xy 215.419987 -24.382987) (xy 215.473944 -24.397093) (xy 215.525273 -24.418905)
			(xy 215.572879 -24.447959) (xy 215.615747 -24.483634) (xy 215.652964 -24.525171) (xy 215.683737 -24.571684)
			(xy 215.707409 -24.622181) (xy 215.723477 -24.675588) (xy 215.731597 -24.730764) (xy 215.732106 -24.75865)
			(xy 215.731597 -24.786536) (xy 215.728524 -24.807418) (xy 238.571276 -24.807418) (xy 238.575347 -24.751796)
			(xy 238.587473 -24.697359) (xy 238.607396 -24.645268) (xy 238.634692 -24.596633) (xy 238.668778 -24.55249)
			(xy 238.708927 -24.513781) (xy 238.754285 -24.48133) (xy 238.803885 -24.455829) (xy 238.856669 -24.437822)
			(xy 238.911512 -24.427692) (xy 238.967246 -24.425655) (xy 239.022683 -24.431755) (xy 239.07664 -24.445861)
			(xy 239.127969 -24.467673) (xy 239.175575 -24.496727) (xy 239.218443 -24.532402) (xy 239.25566 -24.573939)
			(xy 239.286433 -24.620452) (xy 239.310105 -24.670949) (xy 239.326173 -24.724356) (xy 239.334293 -24.779532)
			(xy 239.334802 -24.807418) (xy 240.820192 -24.807418) (xy 240.824263 -24.751796) (xy 240.836389 -24.697359)
			(xy 240.856312 -24.645268) (xy 240.883608 -24.596633) (xy 240.917694 -24.55249) (xy 240.957843 -24.513781)
			(xy 241.003201 -24.48133) (xy 241.052801 -24.455829) (xy 241.105585 -24.437822) (xy 241.160428 -24.427692)
			(xy 241.216162 -24.425655) (xy 241.271599 -24.431755) (xy 241.325556 -24.445861) (xy 241.376885 -24.467673)
			(xy 241.424491 -24.496727) (xy 241.467359 -24.532402) (xy 241.504576 -24.573939) (xy 241.535349 -24.620452)
			(xy 241.559021 -24.670949) (xy 241.575089 -24.724356) (xy 241.583209 -24.779532) (xy 241.583718 -24.807418)
			(xy 241.583209 -24.835304) (xy 241.575089 -24.89048) (xy 241.559021 -24.943887) (xy 241.535349 -24.994384)
			(xy 241.504576 -25.040897) (xy 241.467359 -25.082434) (xy 241.424491 -25.118109) (xy 241.376885 -25.147163)
			(xy 241.325556 -25.168975) (xy 241.271599 -25.183081) (xy 241.216162 -25.189181) (xy 241.160428 -25.187144)
			(xy 241.105585 -25.177014) (xy 241.052801 -25.159007) (xy 241.003201 -25.133506) (xy 240.957843 -25.101055)
			(xy 240.917694 -25.062346) (xy 240.883608 -25.018203) (xy 240.856312 -24.969568) (xy 240.836389 -24.917477)
			(xy 240.824263 -24.86304) (xy 240.820192 -24.807418) (xy 239.334802 -24.807418) (xy 239.334293 -24.835304)
			(xy 239.326173 -24.89048) (xy 239.310105 -24.943887) (xy 239.286433 -24.994384) (xy 239.25566 -25.040897)
			(xy 239.218443 -25.082434) (xy 239.175575 -25.118109) (xy 239.127969 -25.147163) (xy 239.07664 -25.168975)
			(xy 239.022683 -25.183081) (xy 238.967246 -25.189181) (xy 238.911512 -25.187144) (xy 238.856669 -25.177014)
			(xy 238.803885 -25.159007) (xy 238.754285 -25.133506) (xy 238.708927 -25.101055) (xy 238.668778 -25.062346)
			(xy 238.634692 -25.018203) (xy 238.607396 -24.969568) (xy 238.587473 -24.917477) (xy 238.575347 -24.86304)
			(xy 238.571276 -24.807418) (xy 215.728524 -24.807418) (xy 215.723477 -24.841712) (xy 215.707409 -24.895119)
			(xy 215.683737 -24.945616) (xy 215.652964 -24.992129) (xy 215.615747 -25.033666) (xy 215.572879 -25.069341)
			(xy 215.525273 -25.098395) (xy 215.473944 -25.120207) (xy 215.419987 -25.134313) (xy 215.36455 -25.140413)
			(xy 215.308816 -25.138376) (xy 215.253973 -25.128246) (xy 215.201189 -25.110239) (xy 215.151589 -25.084738)
			(xy 215.106231 -25.052287) (xy 215.066082 -25.013578) (xy 215.031996 -24.969435) (xy 215.0047 -24.9208)
			(xy 214.984777 -24.868709) (xy 214.972651 -24.814272) (xy 214.96858 -24.75865) (xy 212.936565 -24.75865)
			(xy 212.972248 -24.798475) (xy 213.003021 -24.844988) (xy 213.026693 -24.895485) (xy 213.042761 -24.948892)
			(xy 213.050881 -25.004068) (xy 213.05139 -25.031954) (xy 213.050881 -25.05984) (xy 213.042761 -25.115016)
			(xy 213.026693 -25.168423) (xy 213.003021 -25.21892) (xy 212.972248 -25.265433) (xy 212.935031 -25.30697)
			(xy 212.892163 -25.342645) (xy 212.844557 -25.371699) (xy 212.793228 -25.393511) (xy 212.739271 -25.407617)
			(xy 212.683834 -25.413717) (xy 212.6281 -25.41168) (xy 212.573257 -25.40155) (xy 212.520473 -25.383543)
			(xy 212.470873 -25.358042) (xy 212.425515 -25.325591) (xy 212.385366 -25.286882) (xy 212.35128 -25.242739)
			(xy 212.323984 -25.194104) (xy 212.304061 -25.142013) (xy 212.291935 -25.087576) (xy 212.287864 -25.031954)
			(xy 208.422563 -25.031954) (xy 208.465851 -25.050349) (xy 208.513457 -25.079403) (xy 208.556325 -25.115078)
			(xy 208.593542 -25.156615) (xy 208.624315 -25.203128) (xy 208.647987 -25.253625) (xy 208.664055 -25.307032)
			(xy 208.672175 -25.362208) (xy 208.672684 -25.390094) (xy 208.672175 -25.41798) (xy 208.664055 -25.473156)
			(xy 208.647987 -25.526563) (xy 208.632898 -25.55875) (xy 216.741754 -25.55875) (xy 216.745825 -25.503128)
			(xy 216.757951 -25.448691) (xy 216.777874 -25.3966) (xy 216.80517 -25.347965) (xy 216.839256 -25.303822)
			(xy 216.879405 -25.265113) (xy 216.924763 -25.232662) (xy 216.974363 -25.207161) (xy 217.027147 -25.189154)
			(xy 217.08199 -25.179024) (xy 217.137724 -25.176987) (xy 217.193161 -25.183087) (xy 217.247118 -25.197193)
			(xy 217.298447 -25.219005) (xy 217.346053 -25.248059) (xy 217.388921 -25.283734) (xy 217.426138 -25.325271)
			(xy 217.456911 -25.371784) (xy 217.465494 -25.390094) (xy 246.009158 -25.390094) (xy 246.013229 -25.334472)
			(xy 246.025355 -25.280035) (xy 246.045278 -25.227944) (xy 246.072574 -25.179309) (xy 246.10666 -25.135166)
			(xy 246.146809 -25.096457) (xy 246.192167 -25.064006) (xy 246.241767 -25.038505) (xy 246.294551 -25.020498)
			(xy 246.349394 -25.010368) (xy 246.405128 -25.008331) (xy 246.460565 -25.014431) (xy 246.514522 -25.028537)
			(xy 246.522563 -25.031954) (xy 250.387864 -25.031954) (xy 250.391935 -24.976332) (xy 250.404061 -24.921895)
			(xy 250.423984 -24.869804) (xy 250.45128 -24.821169) (xy 250.485366 -24.777026) (xy 250.525515 -24.738317)
			(xy 250.570873 -24.705866) (xy 250.620473 -24.680365) (xy 250.673257 -24.662358) (xy 250.7281 -24.652228)
			(xy 250.783834 -24.650191) (xy 250.839271 -24.656291) (xy 250.893228 -24.670397) (xy 250.944557 -24.692209)
			(xy 250.992163 -24.721263) (xy 251.035031 -24.756938) (xy 251.036565 -24.75865) (xy 253.06858 -24.75865)
			(xy 253.072651 -24.703028) (xy 253.084777 -24.648591) (xy 253.1047 -24.5965) (xy 253.131996 -24.547865)
			(xy 253.166082 -24.503722) (xy 253.206231 -24.465013) (xy 253.251589 -24.432562) (xy 253.301189 -24.407061)
			(xy 253.353973 -24.389054) (xy 253.408816 -24.378924) (xy 253.46455 -24.376887) (xy 253.519987 -24.382987)
			(xy 253.573944 -24.397093) (xy 253.625273 -24.418905) (xy 253.672879 -24.447959) (xy 253.715747 -24.483634)
			(xy 253.752964 -24.525171) (xy 253.783737 -24.571684) (xy 253.807409 -24.622181) (xy 253.823477 -24.675588)
			(xy 253.831597 -24.730764) (xy 253.832106 -24.75865) (xy 253.831597 -24.786536) (xy 253.828524 -24.807418)
			(xy 264.571224 -24.807418) (xy 264.575295 -24.751796) (xy 264.587421 -24.697359) (xy 264.607344 -24.645268)
			(xy 264.63464 -24.596633) (xy 264.668726 -24.55249) (xy 264.708875 -24.513781) (xy 264.754233 -24.48133)
			(xy 264.803833 -24.455829) (xy 264.856617 -24.437822) (xy 264.91146 -24.427692) (xy 264.967194 -24.425655)
			(xy 265.022631 -24.431755) (xy 265.076588 -24.445861) (xy 265.127917 -24.467673) (xy 265.175523 -24.496727)
			(xy 265.218391 -24.532402) (xy 265.255608 -24.573939) (xy 265.286381 -24.620452) (xy 265.310053 -24.670949)
			(xy 265.326121 -24.724356) (xy 265.334241 -24.779532) (xy 265.33475 -24.807418) (xy 266.82014 -24.807418)
			(xy 266.824211 -24.751796) (xy 266.836337 -24.697359) (xy 266.85626 -24.645268) (xy 266.883556 -24.596633)
			(xy 266.917642 -24.55249) (xy 266.957791 -24.513781) (xy 267.003149 -24.48133) (xy 267.052749 -24.455829)
			(xy 267.105533 -24.437822) (xy 267.160376 -24.427692) (xy 267.21611 -24.425655) (xy 267.271547 -24.431755)
			(xy 267.325504 -24.445861) (xy 267.376833 -24.467673) (xy 267.424439 -24.496727) (xy 267.467307 -24.532402)
			(xy 267.504524 -24.573939) (xy 267.535297 -24.620452) (xy 267.558969 -24.670949) (xy 267.575037 -24.724356)
			(xy 267.583157 -24.779532) (xy 267.583666 -24.807418) (xy 267.583157 -24.835304) (xy 267.575037 -24.89048)
			(xy 267.558969 -24.943887) (xy 267.535297 -24.994384) (xy 267.504524 -25.040897) (xy 267.467307 -25.082434)
			(xy 267.424439 -25.118109) (xy 267.376833 -25.147163) (xy 267.325504 -25.168975) (xy 267.271547 -25.183081)
			(xy 267.21611 -25.189181) (xy 267.160376 -25.187144) (xy 267.105533 -25.177014) (xy 267.052749 -25.159007)
			(xy 267.003149 -25.133506) (xy 266.957791 -25.101055) (xy 266.917642 -25.062346) (xy 266.883556 -25.018203)
			(xy 266.85626 -24.969568) (xy 266.836337 -24.917477) (xy 266.824211 -24.86304) (xy 266.82014 -24.807418)
			(xy 265.33475 -24.807418) (xy 265.334241 -24.835304) (xy 265.326121 -24.89048) (xy 265.310053 -24.943887)
			(xy 265.286381 -24.994384) (xy 265.255608 -25.040897) (xy 265.218391 -25.082434) (xy 265.175523 -25.118109)
			(xy 265.127917 -25.147163) (xy 265.076588 -25.168975) (xy 265.022631 -25.183081) (xy 264.967194 -25.189181)
			(xy 264.91146 -25.187144) (xy 264.856617 -25.177014) (xy 264.803833 -25.159007) (xy 264.754233 -25.133506)
			(xy 264.708875 -25.101055) (xy 264.668726 -25.062346) (xy 264.63464 -25.018203) (xy 264.607344 -24.969568)
			(xy 264.587421 -24.917477) (xy 264.575295 -24.86304) (xy 264.571224 -24.807418) (xy 253.828524 -24.807418)
			(xy 253.823477 -24.841712) (xy 253.807409 -24.895119) (xy 253.783737 -24.945616) (xy 253.752964 -24.992129)
			(xy 253.715747 -25.033666) (xy 253.672879 -25.069341) (xy 253.625273 -25.098395) (xy 253.573944 -25.120207)
			(xy 253.519987 -25.134313) (xy 253.46455 -25.140413) (xy 253.408816 -25.138376) (xy 253.353973 -25.128246)
			(xy 253.301189 -25.110239) (xy 253.251589 -25.084738) (xy 253.206231 -25.052287) (xy 253.166082 -25.013578)
			(xy 253.131996 -24.969435) (xy 253.1047 -24.9208) (xy 253.084777 -24.868709) (xy 253.072651 -24.814272)
			(xy 253.06858 -24.75865) (xy 251.036565 -24.75865) (xy 251.072248 -24.798475) (xy 251.103021 -24.844988)
			(xy 251.126693 -24.895485) (xy 251.142761 -24.948892) (xy 251.150881 -25.004068) (xy 251.15139 -25.031954)
			(xy 251.150881 -25.05984) (xy 251.142761 -25.115016) (xy 251.126693 -25.168423) (xy 251.103021 -25.21892)
			(xy 251.072248 -25.265433) (xy 251.035031 -25.30697) (xy 250.992163 -25.342645) (xy 250.944557 -25.371699)
			(xy 250.893228 -25.393511) (xy 250.839271 -25.407617) (xy 250.783834 -25.413717) (xy 250.7281 -25.41168)
			(xy 250.673257 -25.40155) (xy 250.620473 -25.383543) (xy 250.570873 -25.358042) (xy 250.525515 -25.325591)
			(xy 250.485366 -25.286882) (xy 250.45128 -25.242739) (xy 250.423984 -25.194104) (xy 250.404061 -25.142013)
			(xy 250.391935 -25.087576) (xy 250.387864 -25.031954) (xy 246.522563 -25.031954) (xy 246.565851 -25.050349)
			(xy 246.613457 -25.079403) (xy 246.656325 -25.115078) (xy 246.693542 -25.156615) (xy 246.724315 -25.203128)
			(xy 246.747987 -25.253625) (xy 246.764055 -25.307032) (xy 246.772175 -25.362208) (xy 246.772684 -25.390094)
			(xy 246.772175 -25.41798) (xy 246.764055 -25.473156) (xy 246.747987 -25.526563) (xy 246.732898 -25.55875)
			(xy 254.841754 -25.55875) (xy 254.845825 -25.503128) (xy 254.857951 -25.448691) (xy 254.877874 -25.3966)
			(xy 254.90517 -25.347965) (xy 254.939256 -25.303822) (xy 254.979405 -25.265113) (xy 255.024763 -25.232662)
			(xy 255.074363 -25.207161) (xy 255.127147 -25.189154) (xy 255.18199 -25.179024) (xy 255.237724 -25.176987)
			(xy 255.293161 -25.183087) (xy 255.347118 -25.197193) (xy 255.398447 -25.219005) (xy 255.446053 -25.248059)
			(xy 255.488921 -25.283734) (xy 255.526138 -25.325271) (xy 255.556911 -25.371784) (xy 255.565494 -25.390094)
			(xy 272.009106 -25.390094) (xy 272.013177 -25.334472) (xy 272.025303 -25.280035) (xy 272.045226 -25.227944)
			(xy 272.072522 -25.179309) (xy 272.106608 -25.135166) (xy 272.146757 -25.096457) (xy 272.192115 -25.064006)
			(xy 272.241715 -25.038505) (xy 272.294499 -25.020498) (xy 272.349342 -25.010368) (xy 272.405076 -25.008331)
			(xy 272.460513 -25.014431) (xy 272.51447 -25.028537) (xy 272.522511 -25.031954) (xy 276.387812 -25.031954)
			(xy 276.391883 -24.976332) (xy 276.404009 -24.921895) (xy 276.423932 -24.869804) (xy 276.451228 -24.821169)
			(xy 276.485314 -24.777026) (xy 276.525463 -24.738317) (xy 276.570821 -24.705866) (xy 276.620421 -24.680365)
			(xy 276.673205 -24.662358) (xy 276.728048 -24.652228) (xy 276.783782 -24.650191) (xy 276.839219 -24.656291)
			(xy 276.893176 -24.670397) (xy 276.944505 -24.692209) (xy 276.992111 -24.721263) (xy 277.034979 -24.756938)
			(xy 277.036513 -24.75865) (xy 279.068528 -24.75865) (xy 279.072599 -24.703028) (xy 279.084725 -24.648591)
			(xy 279.104648 -24.5965) (xy 279.131944 -24.547865) (xy 279.16603 -24.503722) (xy 279.206179 -24.465013)
			(xy 279.251537 -24.432562) (xy 279.301137 -24.407061) (xy 279.353921 -24.389054) (xy 279.408764 -24.378924)
			(xy 279.464498 -24.376887) (xy 279.519935 -24.382987) (xy 279.573892 -24.397093) (xy 279.625221 -24.418905)
			(xy 279.672827 -24.447959) (xy 279.715695 -24.483634) (xy 279.752912 -24.525171) (xy 279.783685 -24.571684)
			(xy 279.807357 -24.622181) (xy 279.823425 -24.675588) (xy 279.831545 -24.730764) (xy 279.832054 -24.75865)
			(xy 279.831545 -24.786536) (xy 279.828472 -24.807418) (xy 290.571172 -24.807418) (xy 290.575243 -24.751796)
			(xy 290.587369 -24.697359) (xy 290.607292 -24.645268) (xy 290.634588 -24.596633) (xy 290.668674 -24.55249)
			(xy 290.708823 -24.513781) (xy 290.754181 -24.48133) (xy 290.803781 -24.455829) (xy 290.856565 -24.437822)
			(xy 290.911408 -24.427692) (xy 290.967142 -24.425655) (xy 291.022579 -24.431755) (xy 291.076536 -24.445861)
			(xy 291.127865 -24.467673) (xy 291.175471 -24.496727) (xy 291.218339 -24.532402) (xy 291.255556 -24.573939)
			(xy 291.286329 -24.620452) (xy 291.310001 -24.670949) (xy 291.326069 -24.724356) (xy 291.334189 -24.779532)
			(xy 291.334698 -24.807418) (xy 292.820088 -24.807418) (xy 292.824159 -24.751796) (xy 292.836285 -24.697359)
			(xy 292.856208 -24.645268) (xy 292.883504 -24.596633) (xy 292.91759 -24.55249) (xy 292.957739 -24.513781)
			(xy 293.003097 -24.48133) (xy 293.052697 -24.455829) (xy 293.105481 -24.437822) (xy 293.160324 -24.427692)
			(xy 293.216058 -24.425655) (xy 293.271495 -24.431755) (xy 293.325452 -24.445861) (xy 293.376781 -24.467673)
			(xy 293.424387 -24.496727) (xy 293.467255 -24.532402) (xy 293.504472 -24.573939) (xy 293.535245 -24.620452)
			(xy 293.558917 -24.670949) (xy 293.574985 -24.724356) (xy 293.583105 -24.779532) (xy 293.583614 -24.807418)
			(xy 293.583105 -24.835304) (xy 293.574985 -24.89048) (xy 293.558917 -24.943887) (xy 293.535245 -24.994384)
			(xy 293.504472 -25.040897) (xy 293.467255 -25.082434) (xy 293.424387 -25.118109) (xy 293.376781 -25.147163)
			(xy 293.325452 -25.168975) (xy 293.271495 -25.183081) (xy 293.216058 -25.189181) (xy 293.160324 -25.187144)
			(xy 293.105481 -25.177014) (xy 293.052697 -25.159007) (xy 293.003097 -25.133506) (xy 292.957739 -25.101055)
			(xy 292.91759 -25.062346) (xy 292.883504 -25.018203) (xy 292.856208 -24.969568) (xy 292.836285 -24.917477)
			(xy 292.824159 -24.86304) (xy 292.820088 -24.807418) (xy 291.334698 -24.807418) (xy 291.334189 -24.835304)
			(xy 291.326069 -24.89048) (xy 291.310001 -24.943887) (xy 291.286329 -24.994384) (xy 291.255556 -25.040897)
			(xy 291.218339 -25.082434) (xy 291.175471 -25.118109) (xy 291.127865 -25.147163) (xy 291.076536 -25.168975)
			(xy 291.022579 -25.183081) (xy 290.967142 -25.189181) (xy 290.911408 -25.187144) (xy 290.856565 -25.177014)
			(xy 290.803781 -25.159007) (xy 290.754181 -25.133506) (xy 290.708823 -25.101055) (xy 290.668674 -25.062346)
			(xy 290.634588 -25.018203) (xy 290.607292 -24.969568) (xy 290.587369 -24.917477) (xy 290.575243 -24.86304)
			(xy 290.571172 -24.807418) (xy 279.828472 -24.807418) (xy 279.823425 -24.841712) (xy 279.807357 -24.895119)
			(xy 279.783685 -24.945616) (xy 279.752912 -24.992129) (xy 279.715695 -25.033666) (xy 279.672827 -25.069341)
			(xy 279.625221 -25.098395) (xy 279.573892 -25.120207) (xy 279.519935 -25.134313) (xy 279.464498 -25.140413)
			(xy 279.408764 -25.138376) (xy 279.353921 -25.128246) (xy 279.301137 -25.110239) (xy 279.251537 -25.084738)
			(xy 279.206179 -25.052287) (xy 279.16603 -25.013578) (xy 279.131944 -24.969435) (xy 279.104648 -24.9208)
			(xy 279.084725 -24.868709) (xy 279.072599 -24.814272) (xy 279.068528 -24.75865) (xy 277.036513 -24.75865)
			(xy 277.072196 -24.798475) (xy 277.102969 -24.844988) (xy 277.126641 -24.895485) (xy 277.142709 -24.948892)
			(xy 277.150829 -25.004068) (xy 277.151338 -25.031954) (xy 277.150829 -25.05984) (xy 277.142709 -25.115016)
			(xy 277.126641 -25.168423) (xy 277.102969 -25.21892) (xy 277.072196 -25.265433) (xy 277.034979 -25.30697)
			(xy 276.992111 -25.342645) (xy 276.944505 -25.371699) (xy 276.893176 -25.393511) (xy 276.839219 -25.407617)
			(xy 276.783782 -25.413717) (xy 276.728048 -25.41168) (xy 276.673205 -25.40155) (xy 276.620421 -25.383543)
			(xy 276.570821 -25.358042) (xy 276.525463 -25.325591) (xy 276.485314 -25.286882) (xy 276.451228 -25.242739)
			(xy 276.423932 -25.194104) (xy 276.404009 -25.142013) (xy 276.391883 -25.087576) (xy 276.387812 -25.031954)
			(xy 272.522511 -25.031954) (xy 272.565799 -25.050349) (xy 272.613405 -25.079403) (xy 272.656273 -25.115078)
			(xy 272.69349 -25.156615) (xy 272.724263 -25.203128) (xy 272.747935 -25.253625) (xy 272.764003 -25.307032)
			(xy 272.772123 -25.362208) (xy 272.772632 -25.390094) (xy 272.772123 -25.41798) (xy 272.764003 -25.473156)
			(xy 272.747935 -25.526563) (xy 272.732846 -25.55875) (xy 280.841702 -25.55875) (xy 280.845773 -25.503128)
			(xy 280.857899 -25.448691) (xy 280.877822 -25.3966) (xy 280.905118 -25.347965) (xy 280.939204 -25.303822)
			(xy 280.979353 -25.265113) (xy 281.024711 -25.232662) (xy 281.074311 -25.207161) (xy 281.127095 -25.189154)
			(xy 281.181938 -25.179024) (xy 281.237672 -25.176987) (xy 281.293109 -25.183087) (xy 281.347066 -25.197193)
			(xy 281.398395 -25.219005) (xy 281.446001 -25.248059) (xy 281.488869 -25.283734) (xy 281.526086 -25.325271)
			(xy 281.556859 -25.371784) (xy 281.565442 -25.390094) (xy 298.009054 -25.390094) (xy 298.013125 -25.334472)
			(xy 298.025251 -25.280035) (xy 298.045174 -25.227944) (xy 298.07247 -25.179309) (xy 298.106556 -25.135166)
			(xy 298.146705 -25.096457) (xy 298.192063 -25.064006) (xy 298.241663 -25.038505) (xy 298.294447 -25.020498)
			(xy 298.34929 -25.010368) (xy 298.405024 -25.008331) (xy 298.460461 -25.014431) (xy 298.514418 -25.028537)
			(xy 298.522459 -25.031954) (xy 302.38776 -25.031954) (xy 302.391831 -24.976332) (xy 302.403957 -24.921895)
			(xy 302.42388 -24.869804) (xy 302.451176 -24.821169) (xy 302.485262 -24.777026) (xy 302.525411 -24.738317)
			(xy 302.570769 -24.705866) (xy 302.620369 -24.680365) (xy 302.673153 -24.662358) (xy 302.727996 -24.652228)
			(xy 302.78373 -24.650191) (xy 302.839167 -24.656291) (xy 302.893124 -24.670397) (xy 302.944453 -24.692209)
			(xy 302.992059 -24.721263) (xy 303.034927 -24.756938) (xy 303.036461 -24.75865) (xy 305.068476 -24.75865)
			(xy 305.072547 -24.703028) (xy 305.084673 -24.648591) (xy 305.104596 -24.5965) (xy 305.131892 -24.547865)
			(xy 305.165978 -24.503722) (xy 305.206127 -24.465013) (xy 305.251485 -24.432562) (xy 305.301085 -24.407061)
			(xy 305.353869 -24.389054) (xy 305.408712 -24.378924) (xy 305.464446 -24.376887) (xy 305.519883 -24.382987)
			(xy 305.57384 -24.397093) (xy 305.625169 -24.418905) (xy 305.672775 -24.447959) (xy 305.715643 -24.483634)
			(xy 305.75286 -24.525171) (xy 305.783633 -24.571684) (xy 305.807305 -24.622181) (xy 305.823373 -24.675588)
			(xy 305.831493 -24.730764) (xy 305.832002 -24.75865) (xy 305.831493 -24.786536) (xy 305.82842 -24.807418)
			(xy 316.57112 -24.807418) (xy 316.575191 -24.751796) (xy 316.587317 -24.697359) (xy 316.60724 -24.645268)
			(xy 316.634536 -24.596633) (xy 316.668622 -24.55249) (xy 316.708771 -24.513781) (xy 316.754129 -24.48133)
			(xy 316.803729 -24.455829) (xy 316.856513 -24.437822) (xy 316.911356 -24.427692) (xy 316.96709 -24.425655)
			(xy 317.022527 -24.431755) (xy 317.076484 -24.445861) (xy 317.127813 -24.467673) (xy 317.175419 -24.496727)
			(xy 317.218287 -24.532402) (xy 317.255504 -24.573939) (xy 317.286277 -24.620452) (xy 317.309949 -24.670949)
			(xy 317.326017 -24.724356) (xy 317.334137 -24.779532) (xy 317.334646 -24.807418) (xy 318.820036 -24.807418)
			(xy 318.824107 -24.751796) (xy 318.836233 -24.697359) (xy 318.856156 -24.645268) (xy 318.883452 -24.596633)
			(xy 318.917538 -24.55249) (xy 318.957687 -24.513781) (xy 319.003045 -24.48133) (xy 319.052645 -24.455829)
			(xy 319.105429 -24.437822) (xy 319.160272 -24.427692) (xy 319.216006 -24.425655) (xy 319.271443 -24.431755)
			(xy 319.3254 -24.445861) (xy 319.376729 -24.467673) (xy 319.424335 -24.496727) (xy 319.467203 -24.532402)
			(xy 319.50442 -24.573939) (xy 319.535193 -24.620452) (xy 319.558865 -24.670949) (xy 319.574933 -24.724356)
			(xy 319.583053 -24.779532) (xy 319.583562 -24.807418) (xy 319.583053 -24.835304) (xy 319.574933 -24.89048)
			(xy 319.558865 -24.943887) (xy 319.535193 -24.994384) (xy 319.50442 -25.040897) (xy 319.467203 -25.082434)
			(xy 319.424335 -25.118109) (xy 319.376729 -25.147163) (xy 319.3254 -25.168975) (xy 319.271443 -25.183081)
			(xy 319.216006 -25.189181) (xy 319.160272 -25.187144) (xy 319.105429 -25.177014) (xy 319.052645 -25.159007)
			(xy 319.003045 -25.133506) (xy 318.957687 -25.101055) (xy 318.917538 -25.062346) (xy 318.883452 -25.018203)
			(xy 318.856156 -24.969568) (xy 318.836233 -24.917477) (xy 318.824107 -24.86304) (xy 318.820036 -24.807418)
			(xy 317.334646 -24.807418) (xy 317.334137 -24.835304) (xy 317.326017 -24.89048) (xy 317.309949 -24.943887)
			(xy 317.286277 -24.994384) (xy 317.255504 -25.040897) (xy 317.218287 -25.082434) (xy 317.175419 -25.118109)
			(xy 317.127813 -25.147163) (xy 317.076484 -25.168975) (xy 317.022527 -25.183081) (xy 316.96709 -25.189181)
			(xy 316.911356 -25.187144) (xy 316.856513 -25.177014) (xy 316.803729 -25.159007) (xy 316.754129 -25.133506)
			(xy 316.708771 -25.101055) (xy 316.668622 -25.062346) (xy 316.634536 -25.018203) (xy 316.60724 -24.969568)
			(xy 316.587317 -24.917477) (xy 316.575191 -24.86304) (xy 316.57112 -24.807418) (xy 305.82842 -24.807418)
			(xy 305.823373 -24.841712) (xy 305.807305 -24.895119) (xy 305.783633 -24.945616) (xy 305.75286 -24.992129)
			(xy 305.715643 -25.033666) (xy 305.672775 -25.069341) (xy 305.625169 -25.098395) (xy 305.57384 -25.120207)
			(xy 305.519883 -25.134313) (xy 305.464446 -25.140413) (xy 305.408712 -25.138376) (xy 305.353869 -25.128246)
			(xy 305.301085 -25.110239) (xy 305.251485 -25.084738) (xy 305.206127 -25.052287) (xy 305.165978 -25.013578)
			(xy 305.131892 -24.969435) (xy 305.104596 -24.9208) (xy 305.084673 -24.868709) (xy 305.072547 -24.814272)
			(xy 305.068476 -24.75865) (xy 303.036461 -24.75865) (xy 303.072144 -24.798475) (xy 303.102917 -24.844988)
			(xy 303.126589 -24.895485) (xy 303.142657 -24.948892) (xy 303.150777 -25.004068) (xy 303.151286 -25.031954)
			(xy 303.150777 -25.05984) (xy 303.142657 -25.115016) (xy 303.126589 -25.168423) (xy 303.102917 -25.21892)
			(xy 303.072144 -25.265433) (xy 303.034927 -25.30697) (xy 302.992059 -25.342645) (xy 302.944453 -25.371699)
			(xy 302.893124 -25.393511) (xy 302.839167 -25.407617) (xy 302.78373 -25.413717) (xy 302.727996 -25.41168)
			(xy 302.673153 -25.40155) (xy 302.620369 -25.383543) (xy 302.570769 -25.358042) (xy 302.525411 -25.325591)
			(xy 302.485262 -25.286882) (xy 302.451176 -25.242739) (xy 302.42388 -25.194104) (xy 302.403957 -25.142013)
			(xy 302.391831 -25.087576) (xy 302.38776 -25.031954) (xy 298.522459 -25.031954) (xy 298.565747 -25.050349)
			(xy 298.613353 -25.079403) (xy 298.656221 -25.115078) (xy 298.693438 -25.156615) (xy 298.724211 -25.203128)
			(xy 298.747883 -25.253625) (xy 298.763951 -25.307032) (xy 298.772071 -25.362208) (xy 298.77258 -25.390094)
			(xy 298.772071 -25.41798) (xy 298.763951 -25.473156) (xy 298.747883 -25.526563) (xy 298.732794 -25.55875)
			(xy 306.84165 -25.55875) (xy 306.845721 -25.503128) (xy 306.857847 -25.448691) (xy 306.87777 -25.3966)
			(xy 306.905066 -25.347965) (xy 306.939152 -25.303822) (xy 306.979301 -25.265113) (xy 307.024659 -25.232662)
			(xy 307.074259 -25.207161) (xy 307.127043 -25.189154) (xy 307.181886 -25.179024) (xy 307.23762 -25.176987)
			(xy 307.293057 -25.183087) (xy 307.347014 -25.197193) (xy 307.398343 -25.219005) (xy 307.445949 -25.248059)
			(xy 307.488817 -25.283734) (xy 307.526034 -25.325271) (xy 307.556807 -25.371784) (xy 307.56539 -25.390094)
			(xy 324.009002 -25.390094) (xy 324.013073 -25.334472) (xy 324.025199 -25.280035) (xy 324.045122 -25.227944)
			(xy 324.072418 -25.179309) (xy 324.106504 -25.135166) (xy 324.146653 -25.096457) (xy 324.192011 -25.064006)
			(xy 324.241611 -25.038505) (xy 324.294395 -25.020498) (xy 324.349238 -25.010368) (xy 324.404972 -25.008331)
			(xy 324.460409 -25.014431) (xy 324.514366 -25.028537) (xy 324.522407 -25.031954) (xy 328.387708 -25.031954)
			(xy 328.391779 -24.976332) (xy 328.403905 -24.921895) (xy 328.423828 -24.869804) (xy 328.451124 -24.821169)
			(xy 328.48521 -24.777026) (xy 328.525359 -24.738317) (xy 328.570717 -24.705866) (xy 328.620317 -24.680365)
			(xy 328.673101 -24.662358) (xy 328.727944 -24.652228) (xy 328.783678 -24.650191) (xy 328.839115 -24.656291)
			(xy 328.893072 -24.670397) (xy 328.944401 -24.692209) (xy 328.992007 -24.721263) (xy 329.034875 -24.756938)
			(xy 329.036409 -24.75865) (xy 331.068424 -24.75865) (xy 331.072495 -24.703028) (xy 331.084621 -24.648591)
			(xy 331.104544 -24.5965) (xy 331.13184 -24.547865) (xy 331.165926 -24.503722) (xy 331.206075 -24.465013)
			(xy 331.251433 -24.432562) (xy 331.301033 -24.407061) (xy 331.353817 -24.389054) (xy 331.40866 -24.378924)
			(xy 331.464394 -24.376887) (xy 331.519831 -24.382987) (xy 331.573788 -24.397093) (xy 331.625117 -24.418905)
			(xy 331.672723 -24.447959) (xy 331.715591 -24.483634) (xy 331.752808 -24.525171) (xy 331.783581 -24.571684)
			(xy 331.807253 -24.622181) (xy 331.823321 -24.675588) (xy 331.831441 -24.730764) (xy 331.83195 -24.75865)
			(xy 331.831441 -24.786536) (xy 331.828368 -24.807418) (xy 354.671374 -24.807418) (xy 354.675445 -24.751796)
			(xy 354.687571 -24.697359) (xy 354.707494 -24.645268) (xy 354.73479 -24.596633) (xy 354.768876 -24.55249)
			(xy 354.809025 -24.513781) (xy 354.854383 -24.48133) (xy 354.903983 -24.455829) (xy 354.956767 -24.437822)
			(xy 355.01161 -24.427692) (xy 355.067344 -24.425655) (xy 355.122781 -24.431755) (xy 355.176738 -24.445861)
			(xy 355.228067 -24.467673) (xy 355.275673 -24.496727) (xy 355.318541 -24.532402) (xy 355.355758 -24.573939)
			(xy 355.386531 -24.620452) (xy 355.410203 -24.670949) (xy 355.426271 -24.724356) (xy 355.434391 -24.779532)
			(xy 355.4349 -24.807418) (xy 356.92029 -24.807418) (xy 356.924361 -24.751796) (xy 356.936487 -24.697359)
			(xy 356.95641 -24.645268) (xy 356.983706 -24.596633) (xy 357.017792 -24.55249) (xy 357.057941 -24.513781)
			(xy 357.103299 -24.48133) (xy 357.152899 -24.455829) (xy 357.205683 -24.437822) (xy 357.260526 -24.427692)
			(xy 357.31626 -24.425655) (xy 357.371697 -24.431755) (xy 357.425654 -24.445861) (xy 357.476983 -24.467673)
			(xy 357.524589 -24.496727) (xy 357.567457 -24.532402) (xy 357.604674 -24.573939) (xy 357.635447 -24.620452)
			(xy 357.659119 -24.670949) (xy 357.675187 -24.724356) (xy 357.683307 -24.779532) (xy 357.683816 -24.807418)
			(xy 357.683307 -24.835304) (xy 357.675187 -24.89048) (xy 357.659119 -24.943887) (xy 357.635447 -24.994384)
			(xy 357.604674 -25.040897) (xy 357.567457 -25.082434) (xy 357.524589 -25.118109) (xy 357.476983 -25.147163)
			(xy 357.425654 -25.168975) (xy 357.371697 -25.183081) (xy 357.31626 -25.189181) (xy 357.260526 -25.187144)
			(xy 357.205683 -25.177014) (xy 357.152899 -25.159007) (xy 357.103299 -25.133506) (xy 357.057941 -25.101055)
			(xy 357.017792 -25.062346) (xy 356.983706 -25.018203) (xy 356.95641 -24.969568) (xy 356.936487 -24.917477)
			(xy 356.924361 -24.86304) (xy 356.92029 -24.807418) (xy 355.4349 -24.807418) (xy 355.434391 -24.835304)
			(xy 355.426271 -24.89048) (xy 355.410203 -24.943887) (xy 355.386531 -24.994384) (xy 355.355758 -25.040897)
			(xy 355.318541 -25.082434) (xy 355.275673 -25.118109) (xy 355.228067 -25.147163) (xy 355.176738 -25.168975)
			(xy 355.122781 -25.183081) (xy 355.067344 -25.189181) (xy 355.01161 -25.187144) (xy 354.956767 -25.177014)
			(xy 354.903983 -25.159007) (xy 354.854383 -25.133506) (xy 354.809025 -25.101055) (xy 354.768876 -25.062346)
			(xy 354.73479 -25.018203) (xy 354.707494 -24.969568) (xy 354.687571 -24.917477) (xy 354.675445 -24.86304)
			(xy 354.671374 -24.807418) (xy 331.828368 -24.807418) (xy 331.823321 -24.841712) (xy 331.807253 -24.895119)
			(xy 331.783581 -24.945616) (xy 331.752808 -24.992129) (xy 331.715591 -25.033666) (xy 331.672723 -25.069341)
			(xy 331.625117 -25.098395) (xy 331.573788 -25.120207) (xy 331.519831 -25.134313) (xy 331.464394 -25.140413)
			(xy 331.40866 -25.138376) (xy 331.353817 -25.128246) (xy 331.301033 -25.110239) (xy 331.251433 -25.084738)
			(xy 331.206075 -25.052287) (xy 331.165926 -25.013578) (xy 331.13184 -24.969435) (xy 331.104544 -24.9208)
			(xy 331.084621 -24.868709) (xy 331.072495 -24.814272) (xy 331.068424 -24.75865) (xy 329.036409 -24.75865)
			(xy 329.072092 -24.798475) (xy 329.102865 -24.844988) (xy 329.126537 -24.895485) (xy 329.142605 -24.948892)
			(xy 329.150725 -25.004068) (xy 329.151234 -25.031954) (xy 329.150725 -25.05984) (xy 329.142605 -25.115016)
			(xy 329.126537 -25.168423) (xy 329.102865 -25.21892) (xy 329.072092 -25.265433) (xy 329.034875 -25.30697)
			(xy 328.992007 -25.342645) (xy 328.944401 -25.371699) (xy 328.893072 -25.393511) (xy 328.839115 -25.407617)
			(xy 328.783678 -25.413717) (xy 328.727944 -25.41168) (xy 328.673101 -25.40155) (xy 328.620317 -25.383543)
			(xy 328.570717 -25.358042) (xy 328.525359 -25.325591) (xy 328.48521 -25.286882) (xy 328.451124 -25.242739)
			(xy 328.423828 -25.194104) (xy 328.403905 -25.142013) (xy 328.391779 -25.087576) (xy 328.387708 -25.031954)
			(xy 324.522407 -25.031954) (xy 324.565695 -25.050349) (xy 324.613301 -25.079403) (xy 324.656169 -25.115078)
			(xy 324.693386 -25.156615) (xy 324.724159 -25.203128) (xy 324.747831 -25.253625) (xy 324.763899 -25.307032)
			(xy 324.772019 -25.362208) (xy 324.772528 -25.390094) (xy 324.772019 -25.41798) (xy 324.763899 -25.473156)
			(xy 324.747831 -25.526563) (xy 324.732742 -25.55875) (xy 332.841598 -25.55875) (xy 332.845669 -25.503128)
			(xy 332.857795 -25.448691) (xy 332.877718 -25.3966) (xy 332.905014 -25.347965) (xy 332.9391 -25.303822)
			(xy 332.979249 -25.265113) (xy 333.024607 -25.232662) (xy 333.074207 -25.207161) (xy 333.126991 -25.189154)
			(xy 333.181834 -25.179024) (xy 333.237568 -25.176987) (xy 333.293005 -25.183087) (xy 333.346962 -25.197193)
			(xy 333.398291 -25.219005) (xy 333.445897 -25.248059) (xy 333.488765 -25.283734) (xy 333.525982 -25.325271)
			(xy 333.556755 -25.371784) (xy 333.565338 -25.390094) (xy 362.109256 -25.390094) (xy 362.113327 -25.334472)
			(xy 362.125453 -25.280035) (xy 362.145376 -25.227944) (xy 362.172672 -25.179309) (xy 362.206758 -25.135166)
			(xy 362.246907 -25.096457) (xy 362.292265 -25.064006) (xy 362.341865 -25.038505) (xy 362.394649 -25.020498)
			(xy 362.449492 -25.010368) (xy 362.505226 -25.008331) (xy 362.560663 -25.014431) (xy 362.61462 -25.028537)
			(xy 362.622661 -25.031954) (xy 366.487962 -25.031954) (xy 366.492033 -24.976332) (xy 366.504159 -24.921895)
			(xy 366.524082 -24.869804) (xy 366.551378 -24.821169) (xy 366.585464 -24.777026) (xy 366.625613 -24.738317)
			(xy 366.670971 -24.705866) (xy 366.720571 -24.680365) (xy 366.773355 -24.662358) (xy 366.828198 -24.652228)
			(xy 366.883932 -24.650191) (xy 366.939369 -24.656291) (xy 366.993326 -24.670397) (xy 367.044655 -24.692209)
			(xy 367.092261 -24.721263) (xy 367.135129 -24.756938) (xy 367.136663 -24.75865) (xy 369.168678 -24.75865)
			(xy 369.172749 -24.703028) (xy 369.184875 -24.648591) (xy 369.204798 -24.5965) (xy 369.232094 -24.547865)
			(xy 369.26618 -24.503722) (xy 369.306329 -24.465013) (xy 369.351687 -24.432562) (xy 369.401287 -24.407061)
			(xy 369.454071 -24.389054) (xy 369.508914 -24.378924) (xy 369.564648 -24.376887) (xy 369.620085 -24.382987)
			(xy 369.674042 -24.397093) (xy 369.725371 -24.418905) (xy 369.772977 -24.447959) (xy 369.815845 -24.483634)
			(xy 369.853062 -24.525171) (xy 369.883835 -24.571684) (xy 369.907507 -24.622181) (xy 369.923575 -24.675588)
			(xy 369.931695 -24.730764) (xy 369.932204 -24.75865) (xy 369.931695 -24.786536) (xy 369.928622 -24.807418)
			(xy 380.671322 -24.807418) (xy 380.675393 -24.751796) (xy 380.687519 -24.697359) (xy 380.707442 -24.645268)
			(xy 380.734738 -24.596633) (xy 380.768824 -24.55249) (xy 380.808973 -24.513781) (xy 380.854331 -24.48133)
			(xy 380.903931 -24.455829) (xy 380.956715 -24.437822) (xy 381.011558 -24.427692) (xy 381.067292 -24.425655)
			(xy 381.122729 -24.431755) (xy 381.176686 -24.445861) (xy 381.228015 -24.467673) (xy 381.275621 -24.496727)
			(xy 381.318489 -24.532402) (xy 381.355706 -24.573939) (xy 381.386479 -24.620452) (xy 381.410151 -24.670949)
			(xy 381.426219 -24.724356) (xy 381.434339 -24.779532) (xy 381.434848 -24.807418) (xy 382.920238 -24.807418)
			(xy 382.924309 -24.751796) (xy 382.936435 -24.697359) (xy 382.956358 -24.645268) (xy 382.983654 -24.596633)
			(xy 383.01774 -24.55249) (xy 383.057889 -24.513781) (xy 383.103247 -24.48133) (xy 383.152847 -24.455829)
			(xy 383.205631 -24.437822) (xy 383.260474 -24.427692) (xy 383.316208 -24.425655) (xy 383.371645 -24.431755)
			(xy 383.425602 -24.445861) (xy 383.476931 -24.467673) (xy 383.524537 -24.496727) (xy 383.567405 -24.532402)
			(xy 383.604622 -24.573939) (xy 383.635395 -24.620452) (xy 383.659067 -24.670949) (xy 383.675135 -24.724356)
			(xy 383.683255 -24.779532) (xy 383.683764 -24.807418) (xy 383.683255 -24.835304) (xy 383.675135 -24.89048)
			(xy 383.659067 -24.943887) (xy 383.635395 -24.994384) (xy 383.604622 -25.040897) (xy 383.567405 -25.082434)
			(xy 383.524537 -25.118109) (xy 383.476931 -25.147163) (xy 383.425602 -25.168975) (xy 383.371645 -25.183081)
			(xy 383.316208 -25.189181) (xy 383.260474 -25.187144) (xy 383.205631 -25.177014) (xy 383.152847 -25.159007)
			(xy 383.103247 -25.133506) (xy 383.057889 -25.101055) (xy 383.01774 -25.062346) (xy 382.983654 -25.018203)
			(xy 382.956358 -24.969568) (xy 382.936435 -24.917477) (xy 382.924309 -24.86304) (xy 382.920238 -24.807418)
			(xy 381.434848 -24.807418) (xy 381.434339 -24.835304) (xy 381.426219 -24.89048) (xy 381.410151 -24.943887)
			(xy 381.386479 -24.994384) (xy 381.355706 -25.040897) (xy 381.318489 -25.082434) (xy 381.275621 -25.118109)
			(xy 381.228015 -25.147163) (xy 381.176686 -25.168975) (xy 381.122729 -25.183081) (xy 381.067292 -25.189181)
			(xy 381.011558 -25.187144) (xy 380.956715 -25.177014) (xy 380.903931 -25.159007) (xy 380.854331 -25.133506)
			(xy 380.808973 -25.101055) (xy 380.768824 -25.062346) (xy 380.734738 -25.018203) (xy 380.707442 -24.969568)
			(xy 380.687519 -24.917477) (xy 380.675393 -24.86304) (xy 380.671322 -24.807418) (xy 369.928622 -24.807418)
			(xy 369.923575 -24.841712) (xy 369.907507 -24.895119) (xy 369.883835 -24.945616) (xy 369.853062 -24.992129)
			(xy 369.815845 -25.033666) (xy 369.772977 -25.069341) (xy 369.725371 -25.098395) (xy 369.674042 -25.120207)
			(xy 369.620085 -25.134313) (xy 369.564648 -25.140413) (xy 369.508914 -25.138376) (xy 369.454071 -25.128246)
			(xy 369.401287 -25.110239) (xy 369.351687 -25.084738) (xy 369.306329 -25.052287) (xy 369.26618 -25.013578)
			(xy 369.232094 -24.969435) (xy 369.204798 -24.9208) (xy 369.184875 -24.868709) (xy 369.172749 -24.814272)
			(xy 369.168678 -24.75865) (xy 367.136663 -24.75865) (xy 367.172346 -24.798475) (xy 367.203119 -24.844988)
			(xy 367.226791 -24.895485) (xy 367.242859 -24.948892) (xy 367.250979 -25.004068) (xy 367.251488 -25.031954)
			(xy 367.250979 -25.05984) (xy 367.242859 -25.115016) (xy 367.226791 -25.168423) (xy 367.203119 -25.21892)
			(xy 367.172346 -25.265433) (xy 367.135129 -25.30697) (xy 367.092261 -25.342645) (xy 367.044655 -25.371699)
			(xy 366.993326 -25.393511) (xy 366.939369 -25.407617) (xy 366.883932 -25.413717) (xy 366.828198 -25.41168)
			(xy 366.773355 -25.40155) (xy 366.720571 -25.383543) (xy 366.670971 -25.358042) (xy 366.625613 -25.325591)
			(xy 366.585464 -25.286882) (xy 366.551378 -25.242739) (xy 366.524082 -25.194104) (xy 366.504159 -25.142013)
			(xy 366.492033 -25.087576) (xy 366.487962 -25.031954) (xy 362.622661 -25.031954) (xy 362.665949 -25.050349)
			(xy 362.713555 -25.079403) (xy 362.756423 -25.115078) (xy 362.79364 -25.156615) (xy 362.824413 -25.203128)
			(xy 362.848085 -25.253625) (xy 362.864153 -25.307032) (xy 362.872273 -25.362208) (xy 362.872782 -25.390094)
			(xy 362.872273 -25.41798) (xy 362.864153 -25.473156) (xy 362.848085 -25.526563) (xy 362.832996 -25.55875)
			(xy 370.941852 -25.55875) (xy 370.945923 -25.503128) (xy 370.958049 -25.448691) (xy 370.977972 -25.3966)
			(xy 371.005268 -25.347965) (xy 371.039354 -25.303822) (xy 371.079503 -25.265113) (xy 371.124861 -25.232662)
			(xy 371.174461 -25.207161) (xy 371.227245 -25.189154) (xy 371.282088 -25.179024) (xy 371.337822 -25.176987)
			(xy 371.393259 -25.183087) (xy 371.447216 -25.197193) (xy 371.498545 -25.219005) (xy 371.546151 -25.248059)
			(xy 371.589019 -25.283734) (xy 371.626236 -25.325271) (xy 371.657009 -25.371784) (xy 371.665592 -25.390094)
			(xy 388.109204 -25.390094) (xy 388.113275 -25.334472) (xy 388.125401 -25.280035) (xy 388.145324 -25.227944)
			(xy 388.17262 -25.179309) (xy 388.206706 -25.135166) (xy 388.246855 -25.096457) (xy 388.292213 -25.064006)
			(xy 388.341813 -25.038505) (xy 388.394597 -25.020498) (xy 388.44944 -25.010368) (xy 388.505174 -25.008331)
			(xy 388.560611 -25.014431) (xy 388.614568 -25.028537) (xy 388.622609 -25.031954) (xy 392.48791 -25.031954)
			(xy 392.491981 -24.976332) (xy 392.504107 -24.921895) (xy 392.52403 -24.869804) (xy 392.551326 -24.821169)
			(xy 392.585412 -24.777026) (xy 392.625561 -24.738317) (xy 392.670919 -24.705866) (xy 392.720519 -24.680365)
			(xy 392.773303 -24.662358) (xy 392.828146 -24.652228) (xy 392.88388 -24.650191) (xy 392.939317 -24.656291)
			(xy 392.993274 -24.670397) (xy 393.044603 -24.692209) (xy 393.092209 -24.721263) (xy 393.135077 -24.756938)
			(xy 393.136611 -24.75865) (xy 395.168626 -24.75865) (xy 395.172697 -24.703028) (xy 395.184823 -24.648591)
			(xy 395.204746 -24.5965) (xy 395.232042 -24.547865) (xy 395.266128 -24.503722) (xy 395.306277 -24.465013)
			(xy 395.351635 -24.432562) (xy 395.401235 -24.407061) (xy 395.454019 -24.389054) (xy 395.508862 -24.378924)
			(xy 395.564596 -24.376887) (xy 395.620033 -24.382987) (xy 395.67399 -24.397093) (xy 395.725319 -24.418905)
			(xy 395.772925 -24.447959) (xy 395.815793 -24.483634) (xy 395.85301 -24.525171) (xy 395.883783 -24.571684)
			(xy 395.907455 -24.622181) (xy 395.923523 -24.675588) (xy 395.931643 -24.730764) (xy 395.932152 -24.75865)
			(xy 395.931643 -24.786536) (xy 395.92857 -24.807418) (xy 406.67127 -24.807418) (xy 406.675341 -24.751796)
			(xy 406.687467 -24.697359) (xy 406.70739 -24.645268) (xy 406.734686 -24.596633) (xy 406.768772 -24.55249)
			(xy 406.808921 -24.513781) (xy 406.854279 -24.48133) (xy 406.903879 -24.455829) (xy 406.956663 -24.437822)
			(xy 407.011506 -24.427692) (xy 407.06724 -24.425655) (xy 407.122677 -24.431755) (xy 407.176634 -24.445861)
			(xy 407.227963 -24.467673) (xy 407.275569 -24.496727) (xy 407.318437 -24.532402) (xy 407.355654 -24.573939)
			(xy 407.386427 -24.620452) (xy 407.410099 -24.670949) (xy 407.426167 -24.724356) (xy 407.434287 -24.779532)
			(xy 407.434796 -24.807418) (xy 408.920186 -24.807418) (xy 408.924257 -24.751796) (xy 408.936383 -24.697359)
			(xy 408.956306 -24.645268) (xy 408.983602 -24.596633) (xy 409.017688 -24.55249) (xy 409.057837 -24.513781)
			(xy 409.103195 -24.48133) (xy 409.152795 -24.455829) (xy 409.205579 -24.437822) (xy 409.260422 -24.427692)
			(xy 409.316156 -24.425655) (xy 409.371593 -24.431755) (xy 409.42555 -24.445861) (xy 409.476879 -24.467673)
			(xy 409.524485 -24.496727) (xy 409.567353 -24.532402) (xy 409.60457 -24.573939) (xy 409.635343 -24.620452)
			(xy 409.659015 -24.670949) (xy 409.675083 -24.724356) (xy 409.683203 -24.779532) (xy 409.683712 -24.807418)
			(xy 409.683203 -24.835304) (xy 409.675083 -24.89048) (xy 409.659015 -24.943887) (xy 409.635343 -24.994384)
			(xy 409.60457 -25.040897) (xy 409.567353 -25.082434) (xy 409.524485 -25.118109) (xy 409.476879 -25.147163)
			(xy 409.42555 -25.168975) (xy 409.371593 -25.183081) (xy 409.316156 -25.189181) (xy 409.260422 -25.187144)
			(xy 409.205579 -25.177014) (xy 409.152795 -25.159007) (xy 409.103195 -25.133506) (xy 409.057837 -25.101055)
			(xy 409.017688 -25.062346) (xy 408.983602 -25.018203) (xy 408.956306 -24.969568) (xy 408.936383 -24.917477)
			(xy 408.924257 -24.86304) (xy 408.920186 -24.807418) (xy 407.434796 -24.807418) (xy 407.434287 -24.835304)
			(xy 407.426167 -24.89048) (xy 407.410099 -24.943887) (xy 407.386427 -24.994384) (xy 407.355654 -25.040897)
			(xy 407.318437 -25.082434) (xy 407.275569 -25.118109) (xy 407.227963 -25.147163) (xy 407.176634 -25.168975)
			(xy 407.122677 -25.183081) (xy 407.06724 -25.189181) (xy 407.011506 -25.187144) (xy 406.956663 -25.177014)
			(xy 406.903879 -25.159007) (xy 406.854279 -25.133506) (xy 406.808921 -25.101055) (xy 406.768772 -25.062346)
			(xy 406.734686 -25.018203) (xy 406.70739 -24.969568) (xy 406.687467 -24.917477) (xy 406.675341 -24.86304)
			(xy 406.67127 -24.807418) (xy 395.92857 -24.807418) (xy 395.923523 -24.841712) (xy 395.907455 -24.895119)
			(xy 395.883783 -24.945616) (xy 395.85301 -24.992129) (xy 395.815793 -25.033666) (xy 395.772925 -25.069341)
			(xy 395.725319 -25.098395) (xy 395.67399 -25.120207) (xy 395.620033 -25.134313) (xy 395.564596 -25.140413)
			(xy 395.508862 -25.138376) (xy 395.454019 -25.128246) (xy 395.401235 -25.110239) (xy 395.351635 -25.084738)
			(xy 395.306277 -25.052287) (xy 395.266128 -25.013578) (xy 395.232042 -24.969435) (xy 395.204746 -24.9208)
			(xy 395.184823 -24.868709) (xy 395.172697 -24.814272) (xy 395.168626 -24.75865) (xy 393.136611 -24.75865)
			(xy 393.172294 -24.798475) (xy 393.203067 -24.844988) (xy 393.226739 -24.895485) (xy 393.242807 -24.948892)
			(xy 393.250927 -25.004068) (xy 393.251436 -25.031954) (xy 393.250927 -25.05984) (xy 393.242807 -25.115016)
			(xy 393.226739 -25.168423) (xy 393.203067 -25.21892) (xy 393.172294 -25.265433) (xy 393.135077 -25.30697)
			(xy 393.092209 -25.342645) (xy 393.044603 -25.371699) (xy 392.993274 -25.393511) (xy 392.939317 -25.407617)
			(xy 392.88388 -25.413717) (xy 392.828146 -25.41168) (xy 392.773303 -25.40155) (xy 392.720519 -25.383543)
			(xy 392.670919 -25.358042) (xy 392.625561 -25.325591) (xy 392.585412 -25.286882) (xy 392.551326 -25.242739)
			(xy 392.52403 -25.194104) (xy 392.504107 -25.142013) (xy 392.491981 -25.087576) (xy 392.48791 -25.031954)
			(xy 388.622609 -25.031954) (xy 388.665897 -25.050349) (xy 388.713503 -25.079403) (xy 388.756371 -25.115078)
			(xy 388.793588 -25.156615) (xy 388.824361 -25.203128) (xy 388.848033 -25.253625) (xy 388.864101 -25.307032)
			(xy 388.872221 -25.362208) (xy 388.87273 -25.390094) (xy 388.872221 -25.41798) (xy 388.864101 -25.473156)
			(xy 388.848033 -25.526563) (xy 388.832944 -25.55875) (xy 396.9418 -25.55875) (xy 396.945871 -25.503128)
			(xy 396.957997 -25.448691) (xy 396.97792 -25.3966) (xy 397.005216 -25.347965) (xy 397.039302 -25.303822)
			(xy 397.079451 -25.265113) (xy 397.124809 -25.232662) (xy 397.174409 -25.207161) (xy 397.227193 -25.189154)
			(xy 397.282036 -25.179024) (xy 397.33777 -25.176987) (xy 397.393207 -25.183087) (xy 397.447164 -25.197193)
			(xy 397.498493 -25.219005) (xy 397.546099 -25.248059) (xy 397.588967 -25.283734) (xy 397.626184 -25.325271)
			(xy 397.656957 -25.371784) (xy 397.66554 -25.390094) (xy 414.109152 -25.390094) (xy 414.113223 -25.334472)
			(xy 414.125349 -25.280035) (xy 414.145272 -25.227944) (xy 414.172568 -25.179309) (xy 414.206654 -25.135166)
			(xy 414.246803 -25.096457) (xy 414.292161 -25.064006) (xy 414.341761 -25.038505) (xy 414.394545 -25.020498)
			(xy 414.449388 -25.010368) (xy 414.505122 -25.008331) (xy 414.560559 -25.014431) (xy 414.614516 -25.028537)
			(xy 414.622557 -25.031954) (xy 418.487858 -25.031954) (xy 418.491929 -24.976332) (xy 418.504055 -24.921895)
			(xy 418.523978 -24.869804) (xy 418.551274 -24.821169) (xy 418.58536 -24.777026) (xy 418.625509 -24.738317)
			(xy 418.670867 -24.705866) (xy 418.720467 -24.680365) (xy 418.773251 -24.662358) (xy 418.828094 -24.652228)
			(xy 418.883828 -24.650191) (xy 418.939265 -24.656291) (xy 418.993222 -24.670397) (xy 419.044551 -24.692209)
			(xy 419.092157 -24.721263) (xy 419.135025 -24.756938) (xy 419.136559 -24.75865) (xy 421.168574 -24.75865)
			(xy 421.172645 -24.703028) (xy 421.184771 -24.648591) (xy 421.204694 -24.5965) (xy 421.23199 -24.547865)
			(xy 421.266076 -24.503722) (xy 421.306225 -24.465013) (xy 421.351583 -24.432562) (xy 421.401183 -24.407061)
			(xy 421.453967 -24.389054) (xy 421.50881 -24.378924) (xy 421.564544 -24.376887) (xy 421.619981 -24.382987)
			(xy 421.673938 -24.397093) (xy 421.725267 -24.418905) (xy 421.772873 -24.447959) (xy 421.815741 -24.483634)
			(xy 421.852958 -24.525171) (xy 421.883731 -24.571684) (xy 421.907403 -24.622181) (xy 421.923471 -24.675588)
			(xy 421.931591 -24.730764) (xy 421.9321 -24.75865) (xy 421.931591 -24.786536) (xy 421.928518 -24.807418)
			(xy 432.671218 -24.807418) (xy 432.675289 -24.751796) (xy 432.687415 -24.697359) (xy 432.707338 -24.645268)
			(xy 432.734634 -24.596633) (xy 432.76872 -24.55249) (xy 432.808869 -24.513781) (xy 432.854227 -24.48133)
			(xy 432.903827 -24.455829) (xy 432.956611 -24.437822) (xy 433.011454 -24.427692) (xy 433.067188 -24.425655)
			(xy 433.122625 -24.431755) (xy 433.176582 -24.445861) (xy 433.227911 -24.467673) (xy 433.275517 -24.496727)
			(xy 433.318385 -24.532402) (xy 433.355602 -24.573939) (xy 433.386375 -24.620452) (xy 433.410047 -24.670949)
			(xy 433.426115 -24.724356) (xy 433.434235 -24.779532) (xy 433.434744 -24.807418) (xy 434.920134 -24.807418)
			(xy 434.924205 -24.751796) (xy 434.936331 -24.697359) (xy 434.956254 -24.645268) (xy 434.98355 -24.596633)
			(xy 435.017636 -24.55249) (xy 435.057785 -24.513781) (xy 435.103143 -24.48133) (xy 435.152743 -24.455829)
			(xy 435.205527 -24.437822) (xy 435.26037 -24.427692) (xy 435.316104 -24.425655) (xy 435.371541 -24.431755)
			(xy 435.425498 -24.445861) (xy 435.476827 -24.467673) (xy 435.524433 -24.496727) (xy 435.567301 -24.532402)
			(xy 435.604518 -24.573939) (xy 435.635291 -24.620452) (xy 435.658963 -24.670949) (xy 435.675031 -24.724356)
			(xy 435.683151 -24.779532) (xy 435.68366 -24.807418) (xy 435.683151 -24.835304) (xy 435.675031 -24.89048)
			(xy 435.658963 -24.943887) (xy 435.635291 -24.994384) (xy 435.604518 -25.040897) (xy 435.567301 -25.082434)
			(xy 435.524433 -25.118109) (xy 435.476827 -25.147163) (xy 435.425498 -25.168975) (xy 435.371541 -25.183081)
			(xy 435.316104 -25.189181) (xy 435.26037 -25.187144) (xy 435.205527 -25.177014) (xy 435.152743 -25.159007)
			(xy 435.103143 -25.133506) (xy 435.057785 -25.101055) (xy 435.017636 -25.062346) (xy 434.98355 -25.018203)
			(xy 434.956254 -24.969568) (xy 434.936331 -24.917477) (xy 434.924205 -24.86304) (xy 434.920134 -24.807418)
			(xy 433.434744 -24.807418) (xy 433.434235 -24.835304) (xy 433.426115 -24.89048) (xy 433.410047 -24.943887)
			(xy 433.386375 -24.994384) (xy 433.355602 -25.040897) (xy 433.318385 -25.082434) (xy 433.275517 -25.118109)
			(xy 433.227911 -25.147163) (xy 433.176582 -25.168975) (xy 433.122625 -25.183081) (xy 433.067188 -25.189181)
			(xy 433.011454 -25.187144) (xy 432.956611 -25.177014) (xy 432.903827 -25.159007) (xy 432.854227 -25.133506)
			(xy 432.808869 -25.101055) (xy 432.76872 -25.062346) (xy 432.734634 -25.018203) (xy 432.707338 -24.969568)
			(xy 432.687415 -24.917477) (xy 432.675289 -24.86304) (xy 432.671218 -24.807418) (xy 421.928518 -24.807418)
			(xy 421.923471 -24.841712) (xy 421.907403 -24.895119) (xy 421.883731 -24.945616) (xy 421.852958 -24.992129)
			(xy 421.815741 -25.033666) (xy 421.772873 -25.069341) (xy 421.725267 -25.098395) (xy 421.673938 -25.120207)
			(xy 421.619981 -25.134313) (xy 421.564544 -25.140413) (xy 421.50881 -25.138376) (xy 421.453967 -25.128246)
			(xy 421.401183 -25.110239) (xy 421.351583 -25.084738) (xy 421.306225 -25.052287) (xy 421.266076 -25.013578)
			(xy 421.23199 -24.969435) (xy 421.204694 -24.9208) (xy 421.184771 -24.868709) (xy 421.172645 -24.814272)
			(xy 421.168574 -24.75865) (xy 419.136559 -24.75865) (xy 419.172242 -24.798475) (xy 419.203015 -24.844988)
			(xy 419.226687 -24.895485) (xy 419.242755 -24.948892) (xy 419.250875 -25.004068) (xy 419.251384 -25.031954)
			(xy 419.250875 -25.05984) (xy 419.242755 -25.115016) (xy 419.226687 -25.168423) (xy 419.203015 -25.21892)
			(xy 419.172242 -25.265433) (xy 419.135025 -25.30697) (xy 419.092157 -25.342645) (xy 419.044551 -25.371699)
			(xy 418.993222 -25.393511) (xy 418.939265 -25.407617) (xy 418.883828 -25.413717) (xy 418.828094 -25.41168)
			(xy 418.773251 -25.40155) (xy 418.720467 -25.383543) (xy 418.670867 -25.358042) (xy 418.625509 -25.325591)
			(xy 418.58536 -25.286882) (xy 418.551274 -25.242739) (xy 418.523978 -25.194104) (xy 418.504055 -25.142013)
			(xy 418.491929 -25.087576) (xy 418.487858 -25.031954) (xy 414.622557 -25.031954) (xy 414.665845 -25.050349)
			(xy 414.713451 -25.079403) (xy 414.756319 -25.115078) (xy 414.793536 -25.156615) (xy 414.824309 -25.203128)
			(xy 414.847981 -25.253625) (xy 414.864049 -25.307032) (xy 414.872169 -25.362208) (xy 414.872678 -25.390094)
			(xy 414.872169 -25.41798) (xy 414.864049 -25.473156) (xy 414.847981 -25.526563) (xy 414.832892 -25.55875)
			(xy 422.941748 -25.55875) (xy 422.945819 -25.503128) (xy 422.957945 -25.448691) (xy 422.977868 -25.3966)
			(xy 423.005164 -25.347965) (xy 423.03925 -25.303822) (xy 423.079399 -25.265113) (xy 423.124757 -25.232662)
			(xy 423.174357 -25.207161) (xy 423.227141 -25.189154) (xy 423.281984 -25.179024) (xy 423.337718 -25.176987)
			(xy 423.393155 -25.183087) (xy 423.447112 -25.197193) (xy 423.498441 -25.219005) (xy 423.546047 -25.248059)
			(xy 423.588915 -25.283734) (xy 423.626132 -25.325271) (xy 423.656905 -25.371784) (xy 423.665488 -25.390094)
			(xy 440.1091 -25.390094) (xy 440.113171 -25.334472) (xy 440.125297 -25.280035) (xy 440.14522 -25.227944)
			(xy 440.172516 -25.179309) (xy 440.206602 -25.135166) (xy 440.246751 -25.096457) (xy 440.292109 -25.064006)
			(xy 440.341709 -25.038505) (xy 440.394493 -25.020498) (xy 440.449336 -25.010368) (xy 440.50507 -25.008331)
			(xy 440.560507 -25.014431) (xy 440.614464 -25.028537) (xy 440.622505 -25.031954) (xy 444.487806 -25.031954)
			(xy 444.491877 -24.976332) (xy 444.504003 -24.921895) (xy 444.523926 -24.869804) (xy 444.551222 -24.821169)
			(xy 444.585308 -24.777026) (xy 444.625457 -24.738317) (xy 444.670815 -24.705866) (xy 444.720415 -24.680365)
			(xy 444.773199 -24.662358) (xy 444.828042 -24.652228) (xy 444.883776 -24.650191) (xy 444.939213 -24.656291)
			(xy 444.99317 -24.670397) (xy 445.044499 -24.692209) (xy 445.092105 -24.721263) (xy 445.134973 -24.756938)
			(xy 445.136507 -24.75865) (xy 447.168522 -24.75865) (xy 447.172593 -24.703028) (xy 447.184719 -24.648591)
			(xy 447.204642 -24.5965) (xy 447.231938 -24.547865) (xy 447.266024 -24.503722) (xy 447.306173 -24.465013)
			(xy 447.351531 -24.432562) (xy 447.401131 -24.407061) (xy 447.453915 -24.389054) (xy 447.508758 -24.378924)
			(xy 447.564492 -24.376887) (xy 447.619929 -24.382987) (xy 447.673886 -24.397093) (xy 447.725215 -24.418905)
			(xy 447.772821 -24.447959) (xy 447.815689 -24.483634) (xy 447.852906 -24.525171) (xy 447.883679 -24.571684)
			(xy 447.907351 -24.622181) (xy 447.923419 -24.675588) (xy 447.931539 -24.730764) (xy 447.932048 -24.75865)
			(xy 447.931539 -24.786536) (xy 447.923419 -24.841712) (xy 447.907351 -24.895119) (xy 447.883679 -24.945616)
			(xy 447.852906 -24.992129) (xy 447.815689 -25.033666) (xy 447.772821 -25.069341) (xy 447.725215 -25.098395)
			(xy 447.673886 -25.120207) (xy 447.619929 -25.134313) (xy 447.564492 -25.140413) (xy 447.508758 -25.138376)
			(xy 447.453915 -25.128246) (xy 447.401131 -25.110239) (xy 447.351531 -25.084738) (xy 447.306173 -25.052287)
			(xy 447.266024 -25.013578) (xy 447.231938 -24.969435) (xy 447.204642 -24.9208) (xy 447.184719 -24.868709)
			(xy 447.172593 -24.814272) (xy 447.168522 -24.75865) (xy 445.136507 -24.75865) (xy 445.17219 -24.798475)
			(xy 445.202963 -24.844988) (xy 445.226635 -24.895485) (xy 445.242703 -24.948892) (xy 445.250823 -25.004068)
			(xy 445.251332 -25.031954) (xy 445.250823 -25.05984) (xy 445.242703 -25.115016) (xy 445.226635 -25.168423)
			(xy 445.202963 -25.21892) (xy 445.17219 -25.265433) (xy 445.134973 -25.30697) (xy 445.092105 -25.342645)
			(xy 445.044499 -25.371699) (xy 444.99317 -25.393511) (xy 444.939213 -25.407617) (xy 444.883776 -25.413717)
			(xy 444.828042 -25.41168) (xy 444.773199 -25.40155) (xy 444.720415 -25.383543) (xy 444.670815 -25.358042)
			(xy 444.625457 -25.325591) (xy 444.585308 -25.286882) (xy 444.551222 -25.242739) (xy 444.523926 -25.194104)
			(xy 444.504003 -25.142013) (xy 444.491877 -25.087576) (xy 444.487806 -25.031954) (xy 440.622505 -25.031954)
			(xy 440.665793 -25.050349) (xy 440.713399 -25.079403) (xy 440.756267 -25.115078) (xy 440.793484 -25.156615)
			(xy 440.824257 -25.203128) (xy 440.847929 -25.253625) (xy 440.863997 -25.307032) (xy 440.872117 -25.362208)
			(xy 440.872626 -25.390094) (xy 440.872117 -25.41798) (xy 440.863997 -25.473156) (xy 440.847929 -25.526563)
			(xy 440.83284 -25.55875) (xy 448.941696 -25.55875) (xy 448.945767 -25.503128) (xy 448.957893 -25.448691)
			(xy 448.977816 -25.3966) (xy 449.005112 -25.347965) (xy 449.039198 -25.303822) (xy 449.079347 -25.265113)
			(xy 449.124705 -25.232662) (xy 449.174305 -25.207161) (xy 449.227089 -25.189154) (xy 449.281932 -25.179024)
			(xy 449.337666 -25.176987) (xy 449.393103 -25.183087) (xy 449.44706 -25.197193) (xy 449.498389 -25.219005)
			(xy 449.545995 -25.248059) (xy 449.588863 -25.283734) (xy 449.62608 -25.325271) (xy 449.656853 -25.371784)
			(xy 449.680525 -25.422281) (xy 449.696593 -25.475688) (xy 449.704713 -25.530864) (xy 449.705222 -25.55875)
			(xy 449.704713 -25.586636) (xy 449.696593 -25.641812) (xy 449.680525 -25.695219) (xy 449.656853 -25.745716)
			(xy 449.62608 -25.792229) (xy 449.588863 -25.833766) (xy 449.545995 -25.869441) (xy 449.498389 -25.898495)
			(xy 449.44706 -25.920307) (xy 449.393103 -25.934413) (xy 449.337666 -25.940513) (xy 449.281932 -25.938476)
			(xy 449.227089 -25.928346) (xy 449.174305 -25.910339) (xy 449.124705 -25.884838) (xy 449.079347 -25.852387)
			(xy 449.039198 -25.813678) (xy 449.005112 -25.769535) (xy 448.977816 -25.7209) (xy 448.957893 -25.668809)
			(xy 448.945767 -25.614372) (xy 448.941696 -25.55875) (xy 440.83284 -25.55875) (xy 440.824257 -25.57706)
			(xy 440.793484 -25.623573) (xy 440.756267 -25.66511) (xy 440.713399 -25.700785) (xy 440.665793 -25.729839)
			(xy 440.614464 -25.751651) (xy 440.560507 -25.765757) (xy 440.50507 -25.771857) (xy 440.449336 -25.76982)
			(xy 440.394493 -25.75969) (xy 440.341709 -25.741683) (xy 440.292109 -25.716182) (xy 440.246751 -25.683731)
			(xy 440.206602 -25.645022) (xy 440.172516 -25.600879) (xy 440.14522 -25.552244) (xy 440.125297 -25.500153)
			(xy 440.113171 -25.445716) (xy 440.1091 -25.390094) (xy 423.665488 -25.390094) (xy 423.680577 -25.422281)
			(xy 423.696645 -25.475688) (xy 423.704765 -25.530864) (xy 423.705274 -25.55875) (xy 423.704765 -25.586636)
			(xy 423.696645 -25.641812) (xy 423.680577 -25.695219) (xy 423.656905 -25.745716) (xy 423.626132 -25.792229)
			(xy 423.588915 -25.833766) (xy 423.546047 -25.869441) (xy 423.498441 -25.898495) (xy 423.447112 -25.920307)
			(xy 423.393155 -25.934413) (xy 423.337718 -25.940513) (xy 423.281984 -25.938476) (xy 423.227141 -25.928346)
			(xy 423.174357 -25.910339) (xy 423.124757 -25.884838) (xy 423.079399 -25.852387) (xy 423.03925 -25.813678)
			(xy 423.005164 -25.769535) (xy 422.977868 -25.7209) (xy 422.957945 -25.668809) (xy 422.945819 -25.614372)
			(xy 422.941748 -25.55875) (xy 414.832892 -25.55875) (xy 414.824309 -25.57706) (xy 414.793536 -25.623573)
			(xy 414.756319 -25.66511) (xy 414.713451 -25.700785) (xy 414.665845 -25.729839) (xy 414.614516 -25.751651)
			(xy 414.560559 -25.765757) (xy 414.505122 -25.771857) (xy 414.449388 -25.76982) (xy 414.394545 -25.75969)
			(xy 414.341761 -25.741683) (xy 414.292161 -25.716182) (xy 414.246803 -25.683731) (xy 414.206654 -25.645022)
			(xy 414.172568 -25.600879) (xy 414.145272 -25.552244) (xy 414.125349 -25.500153) (xy 414.113223 -25.445716)
			(xy 414.109152 -25.390094) (xy 397.66554 -25.390094) (xy 397.680629 -25.422281) (xy 397.696697 -25.475688)
			(xy 397.704817 -25.530864) (xy 397.705326 -25.55875) (xy 397.704817 -25.586636) (xy 397.696697 -25.641812)
			(xy 397.680629 -25.695219) (xy 397.656957 -25.745716) (xy 397.626184 -25.792229) (xy 397.588967 -25.833766)
			(xy 397.546099 -25.869441) (xy 397.498493 -25.898495) (xy 397.447164 -25.920307) (xy 397.393207 -25.934413)
			(xy 397.33777 -25.940513) (xy 397.282036 -25.938476) (xy 397.227193 -25.928346) (xy 397.174409 -25.910339)
			(xy 397.124809 -25.884838) (xy 397.079451 -25.852387) (xy 397.039302 -25.813678) (xy 397.005216 -25.769535)
			(xy 396.97792 -25.7209) (xy 396.957997 -25.668809) (xy 396.945871 -25.614372) (xy 396.9418 -25.55875)
			(xy 388.832944 -25.55875) (xy 388.824361 -25.57706) (xy 388.793588 -25.623573) (xy 388.756371 -25.66511)
			(xy 388.713503 -25.700785) (xy 388.665897 -25.729839) (xy 388.614568 -25.751651) (xy 388.560611 -25.765757)
			(xy 388.505174 -25.771857) (xy 388.44944 -25.76982) (xy 388.394597 -25.75969) (xy 388.341813 -25.741683)
			(xy 388.292213 -25.716182) (xy 388.246855 -25.683731) (xy 388.206706 -25.645022) (xy 388.17262 -25.600879)
			(xy 388.145324 -25.552244) (xy 388.125401 -25.500153) (xy 388.113275 -25.445716) (xy 388.109204 -25.390094)
			(xy 371.665592 -25.390094) (xy 371.680681 -25.422281) (xy 371.696749 -25.475688) (xy 371.704869 -25.530864)
			(xy 371.705378 -25.55875) (xy 371.704869 -25.586636) (xy 371.696749 -25.641812) (xy 371.680681 -25.695219)
			(xy 371.657009 -25.745716) (xy 371.626236 -25.792229) (xy 371.589019 -25.833766) (xy 371.546151 -25.869441)
			(xy 371.498545 -25.898495) (xy 371.447216 -25.920307) (xy 371.393259 -25.934413) (xy 371.337822 -25.940513)
			(xy 371.282088 -25.938476) (xy 371.227245 -25.928346) (xy 371.174461 -25.910339) (xy 371.124861 -25.884838)
			(xy 371.079503 -25.852387) (xy 371.039354 -25.813678) (xy 371.005268 -25.769535) (xy 370.977972 -25.7209)
			(xy 370.958049 -25.668809) (xy 370.945923 -25.614372) (xy 370.941852 -25.55875) (xy 362.832996 -25.55875)
			(xy 362.824413 -25.57706) (xy 362.79364 -25.623573) (xy 362.756423 -25.66511) (xy 362.713555 -25.700785)
			(xy 362.665949 -25.729839) (xy 362.61462 -25.751651) (xy 362.560663 -25.765757) (xy 362.505226 -25.771857)
			(xy 362.449492 -25.76982) (xy 362.394649 -25.75969) (xy 362.341865 -25.741683) (xy 362.292265 -25.716182)
			(xy 362.246907 -25.683731) (xy 362.206758 -25.645022) (xy 362.172672 -25.600879) (xy 362.145376 -25.552244)
			(xy 362.125453 -25.500153) (xy 362.113327 -25.445716) (xy 362.109256 -25.390094) (xy 333.565338 -25.390094)
			(xy 333.580427 -25.422281) (xy 333.596495 -25.475688) (xy 333.604615 -25.530864) (xy 333.605124 -25.55875)
			(xy 333.604615 -25.586636) (xy 333.596495 -25.641812) (xy 333.580427 -25.695219) (xy 333.556755 -25.745716)
			(xy 333.525982 -25.792229) (xy 333.488765 -25.833766) (xy 333.445897 -25.869441) (xy 333.398291 -25.898495)
			(xy 333.346962 -25.920307) (xy 333.293005 -25.934413) (xy 333.237568 -25.940513) (xy 333.181834 -25.938476)
			(xy 333.126991 -25.928346) (xy 333.074207 -25.910339) (xy 333.024607 -25.884838) (xy 332.979249 -25.852387)
			(xy 332.9391 -25.813678) (xy 332.905014 -25.769535) (xy 332.877718 -25.7209) (xy 332.857795 -25.668809)
			(xy 332.845669 -25.614372) (xy 332.841598 -25.55875) (xy 324.732742 -25.55875) (xy 324.724159 -25.57706)
			(xy 324.693386 -25.623573) (xy 324.656169 -25.66511) (xy 324.613301 -25.700785) (xy 324.565695 -25.729839)
			(xy 324.514366 -25.751651) (xy 324.460409 -25.765757) (xy 324.404972 -25.771857) (xy 324.349238 -25.76982)
			(xy 324.294395 -25.75969) (xy 324.241611 -25.741683) (xy 324.192011 -25.716182) (xy 324.146653 -25.683731)
			(xy 324.106504 -25.645022) (xy 324.072418 -25.600879) (xy 324.045122 -25.552244) (xy 324.025199 -25.500153)
			(xy 324.013073 -25.445716) (xy 324.009002 -25.390094) (xy 307.56539 -25.390094) (xy 307.580479 -25.422281)
			(xy 307.596547 -25.475688) (xy 307.604667 -25.530864) (xy 307.605176 -25.55875) (xy 307.604667 -25.586636)
			(xy 307.596547 -25.641812) (xy 307.580479 -25.695219) (xy 307.556807 -25.745716) (xy 307.526034 -25.792229)
			(xy 307.488817 -25.833766) (xy 307.445949 -25.869441) (xy 307.398343 -25.898495) (xy 307.347014 -25.920307)
			(xy 307.293057 -25.934413) (xy 307.23762 -25.940513) (xy 307.181886 -25.938476) (xy 307.127043 -25.928346)
			(xy 307.074259 -25.910339) (xy 307.024659 -25.884838) (xy 306.979301 -25.852387) (xy 306.939152 -25.813678)
			(xy 306.905066 -25.769535) (xy 306.87777 -25.7209) (xy 306.857847 -25.668809) (xy 306.845721 -25.614372)
			(xy 306.84165 -25.55875) (xy 298.732794 -25.55875) (xy 298.724211 -25.57706) (xy 298.693438 -25.623573)
			(xy 298.656221 -25.66511) (xy 298.613353 -25.700785) (xy 298.565747 -25.729839) (xy 298.514418 -25.751651)
			(xy 298.460461 -25.765757) (xy 298.405024 -25.771857) (xy 298.34929 -25.76982) (xy 298.294447 -25.75969)
			(xy 298.241663 -25.741683) (xy 298.192063 -25.716182) (xy 298.146705 -25.683731) (xy 298.106556 -25.645022)
			(xy 298.07247 -25.600879) (xy 298.045174 -25.552244) (xy 298.025251 -25.500153) (xy 298.013125 -25.445716)
			(xy 298.009054 -25.390094) (xy 281.565442 -25.390094) (xy 281.580531 -25.422281) (xy 281.596599 -25.475688)
			(xy 281.604719 -25.530864) (xy 281.605228 -25.55875) (xy 281.604719 -25.586636) (xy 281.596599 -25.641812)
			(xy 281.580531 -25.695219) (xy 281.556859 -25.745716) (xy 281.526086 -25.792229) (xy 281.488869 -25.833766)
			(xy 281.446001 -25.869441) (xy 281.398395 -25.898495) (xy 281.347066 -25.920307) (xy 281.293109 -25.934413)
			(xy 281.237672 -25.940513) (xy 281.181938 -25.938476) (xy 281.127095 -25.928346) (xy 281.074311 -25.910339)
			(xy 281.024711 -25.884838) (xy 280.979353 -25.852387) (xy 280.939204 -25.813678) (xy 280.905118 -25.769535)
			(xy 280.877822 -25.7209) (xy 280.857899 -25.668809) (xy 280.845773 -25.614372) (xy 280.841702 -25.55875)
			(xy 272.732846 -25.55875) (xy 272.724263 -25.57706) (xy 272.69349 -25.623573) (xy 272.656273 -25.66511)
			(xy 272.613405 -25.700785) (xy 272.565799 -25.729839) (xy 272.51447 -25.751651) (xy 272.460513 -25.765757)
			(xy 272.405076 -25.771857) (xy 272.349342 -25.76982) (xy 272.294499 -25.75969) (xy 272.241715 -25.741683)
			(xy 272.192115 -25.716182) (xy 272.146757 -25.683731) (xy 272.106608 -25.645022) (xy 272.072522 -25.600879)
			(xy 272.045226 -25.552244) (xy 272.025303 -25.500153) (xy 272.013177 -25.445716) (xy 272.009106 -25.390094)
			(xy 255.565494 -25.390094) (xy 255.580583 -25.422281) (xy 255.596651 -25.475688) (xy 255.604771 -25.530864)
			(xy 255.60528 -25.55875) (xy 255.604771 -25.586636) (xy 255.596651 -25.641812) (xy 255.580583 -25.695219)
			(xy 255.556911 -25.745716) (xy 255.526138 -25.792229) (xy 255.488921 -25.833766) (xy 255.446053 -25.869441)
			(xy 255.398447 -25.898495) (xy 255.347118 -25.920307) (xy 255.293161 -25.934413) (xy 255.237724 -25.940513)
			(xy 255.18199 -25.938476) (xy 255.127147 -25.928346) (xy 255.074363 -25.910339) (xy 255.024763 -25.884838)
			(xy 254.979405 -25.852387) (xy 254.939256 -25.813678) (xy 254.90517 -25.769535) (xy 254.877874 -25.7209)
			(xy 254.857951 -25.668809) (xy 254.845825 -25.614372) (xy 254.841754 -25.55875) (xy 246.732898 -25.55875)
			(xy 246.724315 -25.57706) (xy 246.693542 -25.623573) (xy 246.656325 -25.66511) (xy 246.613457 -25.700785)
			(xy 246.565851 -25.729839) (xy 246.514522 -25.751651) (xy 246.460565 -25.765757) (xy 246.405128 -25.771857)
			(xy 246.349394 -25.76982) (xy 246.294551 -25.75969) (xy 246.241767 -25.741683) (xy 246.192167 -25.716182)
			(xy 246.146809 -25.683731) (xy 246.10666 -25.645022) (xy 246.072574 -25.600879) (xy 246.045278 -25.552244)
			(xy 246.025355 -25.500153) (xy 246.013229 -25.445716) (xy 246.009158 -25.390094) (xy 217.465494 -25.390094)
			(xy 217.480583 -25.422281) (xy 217.496651 -25.475688) (xy 217.504771 -25.530864) (xy 217.50528 -25.55875)
			(xy 217.504771 -25.586636) (xy 217.496651 -25.641812) (xy 217.480583 -25.695219) (xy 217.456911 -25.745716)
			(xy 217.426138 -25.792229) (xy 217.388921 -25.833766) (xy 217.346053 -25.869441) (xy 217.298447 -25.898495)
			(xy 217.247118 -25.920307) (xy 217.193161 -25.934413) (xy 217.137724 -25.940513) (xy 217.08199 -25.938476)
			(xy 217.027147 -25.928346) (xy 216.974363 -25.910339) (xy 216.924763 -25.884838) (xy 216.879405 -25.852387)
			(xy 216.839256 -25.813678) (xy 216.80517 -25.769535) (xy 216.777874 -25.7209) (xy 216.757951 -25.668809)
			(xy 216.745825 -25.614372) (xy 216.741754 -25.55875) (xy 208.632898 -25.55875) (xy 208.624315 -25.57706)
			(xy 208.593542 -25.623573) (xy 208.556325 -25.66511) (xy 208.513457 -25.700785) (xy 208.465851 -25.729839)
			(xy 208.414522 -25.751651) (xy 208.360565 -25.765757) (xy 208.305128 -25.771857) (xy 208.249394 -25.76982)
			(xy 208.194551 -25.75969) (xy 208.141767 -25.741683) (xy 208.092167 -25.716182) (xy 208.046809 -25.683731)
			(xy 208.00666 -25.645022) (xy 207.972574 -25.600879) (xy 207.945278 -25.552244) (xy 207.925355 -25.500153)
			(xy 207.913229 -25.445716) (xy 207.909158 -25.390094) (xy 191.465546 -25.390094) (xy 191.480635 -25.422281)
			(xy 191.496703 -25.475688) (xy 191.504823 -25.530864) (xy 191.505332 -25.55875) (xy 191.504823 -25.586636)
			(xy 191.496703 -25.641812) (xy 191.480635 -25.695219) (xy 191.456963 -25.745716) (xy 191.42619 -25.792229)
			(xy 191.388973 -25.833766) (xy 191.346105 -25.869441) (xy 191.298499 -25.898495) (xy 191.24717 -25.920307)
			(xy 191.193213 -25.934413) (xy 191.137776 -25.940513) (xy 191.082042 -25.938476) (xy 191.027199 -25.928346)
			(xy 190.974415 -25.910339) (xy 190.924815 -25.884838) (xy 190.879457 -25.852387) (xy 190.839308 -25.813678)
			(xy 190.805222 -25.769535) (xy 190.777926 -25.7209) (xy 190.758003 -25.668809) (xy 190.745877 -25.614372)
			(xy 190.741806 -25.55875) (xy 182.63295 -25.55875) (xy 182.624367 -25.57706) (xy 182.593594 -25.623573)
			(xy 182.556377 -25.66511) (xy 182.513509 -25.700785) (xy 182.465903 -25.729839) (xy 182.414574 -25.751651)
			(xy 182.360617 -25.765757) (xy 182.30518 -25.771857) (xy 182.249446 -25.76982) (xy 182.194603 -25.75969)
			(xy 182.141819 -25.741683) (xy 182.092219 -25.716182) (xy 182.046861 -25.683731) (xy 182.006712 -25.645022)
			(xy 181.972626 -25.600879) (xy 181.94533 -25.552244) (xy 181.925407 -25.500153) (xy 181.913281 -25.445716)
			(xy 181.90921 -25.390094) (xy 165.465598 -25.390094) (xy 165.480687 -25.422281) (xy 165.496755 -25.475688)
			(xy 165.504875 -25.530864) (xy 165.505384 -25.55875) (xy 165.504875 -25.586636) (xy 165.496755 -25.641812)
			(xy 165.480687 -25.695219) (xy 165.457015 -25.745716) (xy 165.426242 -25.792229) (xy 165.389025 -25.833766)
			(xy 165.346157 -25.869441) (xy 165.298551 -25.898495) (xy 165.247222 -25.920307) (xy 165.193265 -25.934413)
			(xy 165.137828 -25.940513) (xy 165.082094 -25.938476) (xy 165.027251 -25.928346) (xy 164.974467 -25.910339)
			(xy 164.924867 -25.884838) (xy 164.879509 -25.852387) (xy 164.83936 -25.813678) (xy 164.805274 -25.769535)
			(xy 164.777978 -25.7209) (xy 164.758055 -25.668809) (xy 164.745929 -25.614372) (xy 164.741858 -25.55875)
			(xy 156.633002 -25.55875) (xy 156.624419 -25.57706) (xy 156.593646 -25.623573) (xy 156.556429 -25.66511)
			(xy 156.513561 -25.700785) (xy 156.465955 -25.729839) (xy 156.414626 -25.751651) (xy 156.360669 -25.765757)
			(xy 156.305232 -25.771857) (xy 156.249498 -25.76982) (xy 156.194655 -25.75969) (xy 156.141871 -25.741683)
			(xy 156.092271 -25.716182) (xy 156.046913 -25.683731) (xy 156.006764 -25.645022) (xy 155.972678 -25.600879)
			(xy 155.945382 -25.552244) (xy 155.925459 -25.500153) (xy 155.913333 -25.445716) (xy 155.909262 -25.390094)
			(xy 139.46565 -25.390094) (xy 139.480739 -25.422281) (xy 139.496807 -25.475688) (xy 139.504927 -25.530864)
			(xy 139.505436 -25.55875) (xy 139.504927 -25.586636) (xy 139.496807 -25.641812) (xy 139.480739 -25.695219)
			(xy 139.457067 -25.745716) (xy 139.426294 -25.792229) (xy 139.389077 -25.833766) (xy 139.346209 -25.869441)
			(xy 139.298603 -25.898495) (xy 139.247274 -25.920307) (xy 139.193317 -25.934413) (xy 139.13788 -25.940513)
			(xy 139.082146 -25.938476) (xy 139.027303 -25.928346) (xy 138.974519 -25.910339) (xy 138.924919 -25.884838)
			(xy 138.879561 -25.852387) (xy 138.839412 -25.813678) (xy 138.805326 -25.769535) (xy 138.77803 -25.7209)
			(xy 138.758107 -25.668809) (xy 138.745981 -25.614372) (xy 138.74191 -25.55875) (xy 130.633054 -25.55875)
			(xy 130.624471 -25.57706) (xy 130.593698 -25.623573) (xy 130.556481 -25.66511) (xy 130.513613 -25.700785)
			(xy 130.466007 -25.729839) (xy 130.414678 -25.751651) (xy 130.360721 -25.765757) (xy 130.305284 -25.771857)
			(xy 130.24955 -25.76982) (xy 130.194707 -25.75969) (xy 130.141923 -25.741683) (xy 130.092323 -25.716182)
			(xy 130.046965 -25.683731) (xy 130.006816 -25.645022) (xy 129.97273 -25.600879) (xy 129.945434 -25.552244)
			(xy 129.925511 -25.500153) (xy 129.913385 -25.445716) (xy 129.909314 -25.390094) (xy 101.365396 -25.390094)
			(xy 101.380485 -25.422281) (xy 101.396553 -25.475688) (xy 101.404673 -25.530864) (xy 101.405182 -25.55875)
			(xy 101.404673 -25.586636) (xy 101.396553 -25.641812) (xy 101.380485 -25.695219) (xy 101.356813 -25.745716)
			(xy 101.32604 -25.792229) (xy 101.288823 -25.833766) (xy 101.245955 -25.869441) (xy 101.198349 -25.898495)
			(xy 101.14702 -25.920307) (xy 101.093063 -25.934413) (xy 101.037626 -25.940513) (xy 100.981892 -25.938476)
			(xy 100.927049 -25.928346) (xy 100.874265 -25.910339) (xy 100.824665 -25.884838) (xy 100.779307 -25.852387)
			(xy 100.739158 -25.813678) (xy 100.705072 -25.769535) (xy 100.677776 -25.7209) (xy 100.657853 -25.668809)
			(xy 100.645727 -25.614372) (xy 100.641656 -25.55875) (xy 92.5328 -25.55875) (xy 92.524217 -25.57706)
			(xy 92.493444 -25.623573) (xy 92.456227 -25.66511) (xy 92.413359 -25.700785) (xy 92.365753 -25.729839)
			(xy 92.314424 -25.751651) (xy 92.260467 -25.765757) (xy 92.20503 -25.771857) (xy 92.149296 -25.76982)
			(xy 92.094453 -25.75969) (xy 92.041669 -25.741683) (xy 91.992069 -25.716182) (xy 91.946711 -25.683731)
			(xy 91.906562 -25.645022) (xy 91.872476 -25.600879) (xy 91.84518 -25.552244) (xy 91.825257 -25.500153)
			(xy 91.813131 -25.445716) (xy 91.80906 -25.390094) (xy 75.365448 -25.390094) (xy 75.380537 -25.422281)
			(xy 75.396605 -25.475688) (xy 75.404725 -25.530864) (xy 75.405234 -25.55875) (xy 75.404725 -25.586636)
			(xy 75.396605 -25.641812) (xy 75.380537 -25.695219) (xy 75.356865 -25.745716) (xy 75.326092 -25.792229)
			(xy 75.288875 -25.833766) (xy 75.246007 -25.869441) (xy 75.198401 -25.898495) (xy 75.147072 -25.920307)
			(xy 75.093115 -25.934413) (xy 75.037678 -25.940513) (xy 74.981944 -25.938476) (xy 74.927101 -25.928346)
			(xy 74.874317 -25.910339) (xy 74.824717 -25.884838) (xy 74.779359 -25.852387) (xy 74.73921 -25.813678)
			(xy 74.705124 -25.769535) (xy 74.677828 -25.7209) (xy 74.657905 -25.668809) (xy 74.645779 -25.614372)
			(xy 74.641708 -25.55875) (xy 66.532852 -25.55875) (xy 66.524269 -25.57706) (xy 66.493496 -25.623573)
			(xy 66.456279 -25.66511) (xy 66.413411 -25.700785) (xy 66.365805 -25.729839) (xy 66.314476 -25.751651)
			(xy 66.260519 -25.765757) (xy 66.205082 -25.771857) (xy 66.149348 -25.76982) (xy 66.094505 -25.75969)
			(xy 66.041721 -25.741683) (xy 65.992121 -25.716182) (xy 65.946763 -25.683731) (xy 65.906614 -25.645022)
			(xy 65.872528 -25.600879) (xy 65.845232 -25.552244) (xy 65.825309 -25.500153) (xy 65.813183 -25.445716)
			(xy 65.809112 -25.390094) (xy 49.3655 -25.390094) (xy 49.380589 -25.422281) (xy 49.396657 -25.475688)
			(xy 49.404777 -25.530864) (xy 49.405286 -25.55875) (xy 49.404777 -25.586636) (xy 49.396657 -25.641812)
			(xy 49.380589 -25.695219) (xy 49.356917 -25.745716) (xy 49.326144 -25.792229) (xy 49.288927 -25.833766)
			(xy 49.246059 -25.869441) (xy 49.198453 -25.898495) (xy 49.147124 -25.920307) (xy 49.093167 -25.934413)
			(xy 49.03773 -25.940513) (xy 48.981996 -25.938476) (xy 48.927153 -25.928346) (xy 48.874369 -25.910339)
			(xy 48.824769 -25.884838) (xy 48.779411 -25.852387) (xy 48.739262 -25.813678) (xy 48.705176 -25.769535)
			(xy 48.67788 -25.7209) (xy 48.657957 -25.668809) (xy 48.645831 -25.614372) (xy 48.64176 -25.55875)
			(xy 40.532904 -25.55875) (xy 40.524321 -25.57706) (xy 40.493548 -25.623573) (xy 40.456331 -25.66511)
			(xy 40.413463 -25.700785) (xy 40.365857 -25.729839) (xy 40.314528 -25.751651) (xy 40.260571 -25.765757)
			(xy 40.205134 -25.771857) (xy 40.1494 -25.76982) (xy 40.094557 -25.75969) (xy 40.041773 -25.741683)
			(xy 39.992173 -25.716182) (xy 39.946815 -25.683731) (xy 39.906666 -25.645022) (xy 39.87258 -25.600879)
			(xy 39.845284 -25.552244) (xy 39.825361 -25.500153) (xy 39.813235 -25.445716) (xy 39.809164 -25.390094)
			(xy 18.701327 -25.390094) (xy 18.693286 -25.393511) (xy 18.639329 -25.407617) (xy 18.583892 -25.413717)
			(xy 18.528158 -25.41168) (xy 18.473315 -25.40155) (xy 18.420531 -25.383543) (xy 18.370931 -25.358042)
			(xy 18.325573 -25.325591) (xy 18.285424 -25.286882) (xy 18.251338 -25.242739) (xy 18.224042 -25.194104)
			(xy 18.204119 -25.142013) (xy 18.191993 -25.087576) (xy 18.187922 -25.031954) (xy 14.322621 -25.031954)
			(xy 14.365909 -25.050349) (xy 14.413515 -25.079403) (xy 14.456383 -25.115078) (xy 14.4936 -25.156615)
			(xy 14.524373 -25.203128) (xy 14.548045 -25.253625) (xy 14.564113 -25.307032) (xy 14.572233 -25.362208)
			(xy 14.572742 -25.390094) (xy 14.572233 -25.41798) (xy 14.564113 -25.473156) (xy 14.548045 -25.526563)
			(xy 14.524373 -25.57706) (xy 14.4936 -25.623573) (xy 14.456383 -25.66511) (xy 14.413515 -25.700785)
			(xy 14.365909 -25.729839) (xy 14.31458 -25.751651) (xy 14.260623 -25.765757) (xy 14.205186 -25.771857)
			(xy 14.149452 -25.76982) (xy 14.094609 -25.75969) (xy 14.041825 -25.741683) (xy 13.992225 -25.716182)
			(xy 13.946867 -25.683731) (xy 13.906718 -25.645022) (xy 13.872632 -25.600879) (xy 13.845336 -25.552244)
			(xy 13.825413 -25.500153) (xy 13.813287 -25.445716) (xy 13.809216 -25.390094) (xy 0.715772 -25.390094)
			(xy 0.715772 -26.035) (xy 1.649982 -26.035) (xy 1.654053 -25.979378) (xy 1.666179 -25.924941) (xy 1.686102 -25.87285)
			(xy 1.713398 -25.824215) (xy 1.747484 -25.780072) (xy 1.787633 -25.741363) (xy 1.832991 -25.708912)
			(xy 1.882591 -25.683411) (xy 1.935375 -25.665404) (xy 1.990218 -25.655274) (xy 2.045952 -25.653237)
			(xy 2.101389 -25.659337) (xy 2.155346 -25.673443) (xy 2.206675 -25.695255) (xy 2.254281 -25.724309)
			(xy 2.297149 -25.759984) (xy 2.334366 -25.801521) (xy 2.365139 -25.848034) (xy 2.388811 -25.898531)
			(xy 2.402435 -25.943814) (xy 4.265674 -25.943814) (xy 4.269745 -25.888192) (xy 4.281871 -25.833755)
			(xy 4.301794 -25.781664) (xy 4.32909 -25.733029) (xy 4.363176 -25.688886) (xy 4.403325 -25.650177)
			(xy 4.448683 -25.617726) (xy 4.498283 -25.592225) (xy 4.551067 -25.574218) (xy 4.60591 -25.564088)
			(xy 4.661644 -25.562051) (xy 4.717081 -25.568151) (xy 4.771038 -25.582257) (xy 4.822367 -25.604069)
			(xy 4.869973 -25.633123) (xy 4.912841 -25.668798) (xy 4.950058 -25.710335) (xy 4.980831 -25.756848)
			(xy 5.004503 -25.807345) (xy 5.020571 -25.860752) (xy 5.028691 -25.915928) (xy 5.0292 -25.943814)
			(xy 5.028691 -25.9717) (xy 5.020571 -26.026876) (xy 5.018509 -26.03373) (xy 5.317488 -26.03373) (xy 5.321559 -25.978108)
			(xy 5.333685 -25.923671) (xy 5.353608 -25.87158) (xy 5.380904 -25.822945) (xy 5.41499 -25.778802)
			(xy 5.455139 -25.740093) (xy 5.500497 -25.707642) (xy 5.550097 -25.682141) (xy 5.602881 -25.664134)
			(xy 5.657724 -25.654004) (xy 5.713458 -25.651967) (xy 5.768895 -25.658067) (xy 5.822852 -25.672173)
			(xy 5.874181 -25.693985) (xy 5.921787 -25.723039) (xy 5.964655 -25.758714) (xy 6.001872 -25.800251)
			(xy 6.032645 -25.846764) (xy 6.056317 -25.897261) (xy 6.072385 -25.950668) (xy 6.080505 -26.005844)
			(xy 6.081014 -26.03373) (xy 6.080505 -26.061616) (xy 6.072385 -26.116792) (xy 6.056317 -26.170199)
			(xy 6.032645 -26.220696) (xy 6.002411 -26.266394) (xy 8.520684 -26.266394) (xy 8.52117 -26.239143)
			(xy 8.528926 -26.185195) (xy 8.544281 -26.1329) (xy 8.566923 -26.083323) (xy 8.596389 -26.037473)
			(xy 8.63208 -25.996282) (xy 8.673271 -25.960591) (xy 8.719121 -25.931125) (xy 8.768698 -25.908483)
			(xy 8.820993 -25.893128) (xy 8.874941 -25.885372) (xy 8.929443 -25.885372) (xy 8.983391 -25.893128)
			(xy 9.035686 -25.908483) (xy 9.085263 -25.931125) (xy 9.131113 -25.960591) (xy 9.172304 -25.996282)
			(xy 9.207995 -26.037473) (xy 9.237461 -26.083323) (xy 9.260103 -26.1329) (xy 9.275458 -26.185195)
			(xy 9.283214 -26.239143) (xy 9.2837 -26.266394) (xy 9.283148 -26.295882) (xy 9.274053 -26.354152)
			(xy 9.256095 -26.410328) (xy 9.229702 -26.463068) (xy 9.195503 -26.511116) (xy 9.154314 -26.553325)
			(xy 9.131046 -26.571448) (xy 9.119897 -26.580312) (xy 9.102719 -26.603023) (xy 9.092477 -26.629593)
			(xy 9.089965 -26.657958) (xy 9.095379 -26.685914) (xy 9.108298 -26.71129) (xy 9.127719 -26.732115)
			(xy 9.139682 -26.73985) (xy 9.163414 -26.754761) (xy 9.206651 -26.790425) (xy 9.244203 -26.832031)
			(xy 9.275264 -26.878684) (xy 9.299164 -26.92938) (xy 9.31539 -26.983027) (xy 9.323591 -27.03847)
			(xy 9.324086 -27.066494) (xy 9.3236 -27.093745) (xy 9.315844 -27.147693) (xy 9.300489 -27.199988)
			(xy 9.277847 -27.249565) (xy 9.248381 -27.295415) (xy 9.21269 -27.336606) (xy 9.171499 -27.372297)
			(xy 9.125649 -27.401763) (xy 9.076072 -27.424405) (xy 9.023777 -27.43976) (xy 8.969829 -27.447516)
			(xy 8.915327 -27.447516) (xy 8.861379 -27.43976) (xy 8.809084 -27.424405) (xy 8.759507 -27.401763)
			(xy 8.713657 -27.372297) (xy 8.672466 -27.336606) (xy 8.636775 -27.295415) (xy 8.607309 -27.249565)
			(xy 8.584667 -27.199988) (xy 8.569312 -27.147693) (xy 8.561556 -27.093745) (xy 8.56107 -27.066494)
			(xy 8.561625 -27.037006) (xy 8.570721 -26.978737) (xy 8.588679 -26.922562) (xy 8.615072 -26.869822)
			(xy 8.64927 -26.821774) (xy 8.690457 -26.779564) (xy 8.713724 -26.76144) (xy 8.724787 -26.752474)
			(xy 8.741969 -26.729789) (xy 8.752221 -26.703241) (xy 8.754746 -26.674895) (xy 8.749348 -26.646954)
			(xy 8.736445 -26.621589) (xy 8.717042 -26.600771) (xy 8.705088 -26.593038) (xy 8.681343 -26.578146)
			(xy 8.638109 -26.542477) (xy 8.600558 -26.500868) (xy 8.569499 -26.454211) (xy 8.545601 -26.403513)
			(xy 8.529377 -26.349864) (xy 8.521178 -26.294418) (xy 8.520684 -26.266394) (xy 6.002411 -26.266394)
			(xy 6.001872 -26.267209) (xy 5.964655 -26.308746) (xy 5.921787 -26.344421) (xy 5.874181 -26.373475)
			(xy 5.822852 -26.395287) (xy 5.768895 -26.409393) (xy 5.713458 -26.415493) (xy 5.657724 -26.413456)
			(xy 5.602881 -26.403326) (xy 5.550097 -26.385319) (xy 5.500497 -26.359818) (xy 5.455139 -26.327367)
			(xy 5.41499 -26.288658) (xy 5.380904 -26.244515) (xy 5.353608 -26.19588) (xy 5.333685 -26.143789)
			(xy 5.321559 -26.089352) (xy 5.317488 -26.03373) (xy 5.018509 -26.03373) (xy 5.004503 -26.080283)
			(xy 4.980831 -26.13078) (xy 4.950058 -26.177293) (xy 4.912841 -26.21883) (xy 4.869973 -26.254505)
			(xy 4.822367 -26.283559) (xy 4.771038 -26.305371) (xy 4.717081 -26.319477) (xy 4.661644 -26.325577)
			(xy 4.60591 -26.32354) (xy 4.551067 -26.31341) (xy 4.498283 -26.295403) (xy 4.448683 -26.269902)
			(xy 4.403325 -26.237451) (xy 4.363176 -26.198742) (xy 4.32909 -26.154599) (xy 4.301794 -26.105964)
			(xy 4.281871 -26.053873) (xy 4.269745 -25.999436) (xy 4.265674 -25.943814) (xy 2.402435 -25.943814)
			(xy 2.404879 -25.951938) (xy 2.412999 -26.007114) (xy 2.413508 -26.035) (xy 2.412999 -26.062886)
			(xy 2.404879 -26.118062) (xy 2.388811 -26.171469) (xy 2.365139 -26.221966) (xy 2.334366 -26.268479)
			(xy 2.297149 -26.310016) (xy 2.254281 -26.345691) (xy 2.206675 -26.374745) (xy 2.155346 -26.396557)
			(xy 2.101389 -26.410663) (xy 2.045952 -26.416763) (xy 1.990218 -26.414726) (xy 1.935375 -26.404596)
			(xy 1.882591 -26.386589) (xy 1.832991 -26.361088) (xy 1.787633 -26.328637) (xy 1.747484 -26.289928)
			(xy 1.713398 -26.245785) (xy 1.686102 -26.19715) (xy 1.666179 -26.145059) (xy 1.654053 -26.090622)
			(xy 1.649982 -26.035) (xy 0.715772 -26.035) (xy 0.715772 -29.330142) (xy 2.191256 -29.330142) (xy 2.195327 -29.27452)
			(xy 2.207453 -29.220083) (xy 2.227376 -29.167992) (xy 2.254672 -29.119357) (xy 2.288758 -29.075214)
			(xy 2.328907 -29.036505) (xy 2.374265 -29.004054) (xy 2.423865 -28.978553) (xy 2.476649 -28.960546)
			(xy 2.531492 -28.950416) (xy 2.587226 -28.948379) (xy 2.642663 -28.954479) (xy 2.69662 -28.968585)
			(xy 2.747949 -28.990397) (xy 2.795555 -29.019451) (xy 2.838423 -29.055126) (xy 2.87564 -29.096663)
			(xy 2.906413 -29.143176) (xy 2.930085 -29.193673) (xy 2.946153 -29.24708) (xy 2.954273 -29.302256)
			(xy 2.954782 -29.330142) (xy 2.954281 -29.357574) (xy 3.464304 -29.357574) (xy 3.468375 -29.301952)
			(xy 3.480501 -29.247515) (xy 3.500424 -29.195424) (xy 3.52772 -29.146789) (xy 3.561806 -29.102646)
			(xy 3.601955 -29.063937) (xy 3.647313 -29.031486) (xy 3.696913 -29.005985) (xy 3.749697 -28.987978)
			(xy 3.80454 -28.977848) (xy 3.860274 -28.975811) (xy 3.915711 -28.981911) (xy 3.969668 -28.996017)
			(xy 4.020997 -29.017829) (xy 4.068603 -29.046883) (xy 4.111471 -29.082558) (xy 4.147142 -29.12237)
			(xy 8.607044 -29.12237) (xy 8.607044 -28.25877) (xy 8.607534 -28.228802) (xy 8.615357 -28.16938)
			(xy 8.63087 -28.111487) (xy 8.653806 -28.056114) (xy 8.683773 -28.004208) (xy 8.72026 -27.956658)
			(xy 8.76264 -27.914278) (xy 8.81019 -27.877791) (xy 8.862096 -27.847824) (xy 8.917469 -27.824888)
			(xy 8.975362 -27.809375) (xy 9.034784 -27.801552) (xy 9.09472 -27.801552) (xy 9.154142 -27.809375)
			(xy 9.212035 -27.824888) (xy 9.267408 -27.847824) (xy 9.319314 -27.877791) (xy 9.366864 -27.914278)
			(xy 9.409244 -27.956658) (xy 9.445731 -28.004208) (xy 9.475698 -28.056114) (xy 9.498634 -28.111487)
			(xy 9.514147 -28.16938) (xy 9.52197 -28.228802) (xy 9.52246 -28.25877) (xy 9.52246 -29.12237) (xy 9.52197 -29.152338)
			(xy 9.514147 -29.21176) (xy 9.498634 -29.269653) (xy 9.475698 -29.325026) (xy 9.445731 -29.376932)
			(xy 9.409244 -29.424482) (xy 9.366864 -29.466862) (xy 9.319314 -29.503349) (xy 9.267408 -29.533316)
			(xy 9.212035 -29.556252) (xy 9.154142 -29.571765) (xy 9.09472 -29.579588) (xy 9.034784 -29.579588)
			(xy 8.975362 -29.571765) (xy 8.917469 -29.556252) (xy 8.862096 -29.533316) (xy 8.81019 -29.503349)
			(xy 8.76264 -29.466862) (xy 8.72026 -29.424482) (xy 8.683773 -29.376932) (xy 8.653806 -29.325026)
			(xy 8.63087 -29.269653) (xy 8.615357 -29.21176) (xy 8.607534 -29.152338) (xy 8.607044 -29.12237)
			(xy 4.147142 -29.12237) (xy 4.148688 -29.124095) (xy 4.179461 -29.170608) (xy 4.203133 -29.221105)
			(xy 4.219201 -29.274512) (xy 4.227321 -29.329688) (xy 4.22783 -29.357574) (xy 4.227321 -29.38546)
			(xy 4.219201 -29.440636) (xy 4.203133 -29.494043) (xy 4.179461 -29.54454) (xy 4.148688 -29.591053)
			(xy 4.111471 -29.63259) (xy 4.068603 -29.668265) (xy 4.020997 -29.697319) (xy 3.969668 -29.719131)
			(xy 3.915711 -29.733237) (xy 3.860274 -29.739337) (xy 3.80454 -29.7373) (xy 3.749697 -29.72717) (xy 3.696913 -29.709163)
			(xy 3.647313 -29.683662) (xy 3.601955 -29.651211) (xy 3.561806 -29.612502) (xy 3.52772 -29.568359)
			(xy 3.500424 -29.519724) (xy 3.480501 -29.467633) (xy 3.468375 -29.413196) (xy 3.464304 -29.357574)
			(xy 2.954281 -29.357574) (xy 2.954273 -29.358028) (xy 2.946153 -29.413204) (xy 2.930085 -29.466611)
			(xy 2.906413 -29.517108) (xy 2.87564 -29.563621) (xy 2.838423 -29.605158) (xy 2.795555 -29.640833)
			(xy 2.747949 -29.669887) (xy 2.69662 -29.691699) (xy 2.642663 -29.705805) (xy 2.587226 -29.711905)
			(xy 2.531492 -29.709868) (xy 2.476649 -29.699738) (xy 2.423865 -29.681731) (xy 2.374265 -29.65623)
			(xy 2.328907 -29.623779) (xy 2.288758 -29.58507) (xy 2.254672 -29.540927) (xy 2.227376 -29.492292)
			(xy 2.207453 -29.440201) (xy 2.195327 -29.385764) (xy 2.191256 -29.330142) (xy 0.715772 -29.330142)
			(xy 0.715772 -30.922468) (xy 6.752844 -30.922468) (xy 6.752844 -30.058868) (xy 6.753334 -30.0289)
			(xy 6.761157 -29.969478) (xy 6.77667 -29.911585) (xy 6.799606 -29.856212) (xy 6.829573 -29.804306)
			(xy 6.86606 -29.756756) (xy 6.90844 -29.714376) (xy 6.95599 -29.677889) (xy 7.007896 -29.647922)
			(xy 7.063269 -29.624986) (xy 7.121162 -29.609473) (xy 7.180584 -29.60165) (xy 7.24052 -29.60165)
			(xy 7.299942 -29.609473) (xy 7.357835 -29.624986) (xy 7.413208 -29.647922) (xy 7.465114 -29.677889)
			(xy 7.512664 -29.714376) (xy 7.555044 -29.756756) (xy 7.591531 -29.804306) (xy 7.621498 -29.856212)
			(xy 7.644434 -29.911585) (xy 7.659947 -29.969478) (xy 7.66777 -30.0289) (xy 7.66826 -30.058868) (xy 7.66826 -30.92069)
			(xy 21.489416 -30.92069) (xy 21.489416 -30.05709) (xy 21.489906 -30.027106) (xy 21.497734 -29.96765)
			(xy 21.513255 -29.909725) (xy 21.536204 -29.854321) (xy 21.566188 -29.802387) (xy 21.602694 -29.754811)
			(xy 21.645099 -29.712406) (xy 21.692675 -29.6759) (xy 21.744609 -29.645916) (xy 21.800013 -29.622967)
			(xy 21.857938 -29.607446) (xy 21.917394 -29.599618) (xy 21.977362 -29.599618) (xy 22.036818 -29.607446)
			(xy 22.094743 -29.622967) (xy 22.150147 -29.645916) (xy 22.202081 -29.6759) (xy 22.249657 -29.712406)
			(xy 22.292062 -29.754811) (xy 22.328568 -29.802387) (xy 22.358552 -29.854321) (xy 22.381501 -29.909725)
			(xy 22.397022 -29.96765) (xy 22.40485 -30.027106) (xy 22.40534 -30.05709) (xy 22.40534 -30.92069)
			(xy 22.40485 -30.950674) (xy 22.397022 -31.01013) (xy 22.381501 -31.068055) (xy 22.358552 -31.123459)
			(xy 22.328568 -31.175393) (xy 22.292062 -31.222969) (xy 22.249657 -31.265374) (xy 22.202081 -31.30188)
			(xy 22.150147 -31.331864) (xy 22.094743 -31.354813) (xy 22.036818 -31.370334) (xy 21.977362 -31.378162)
			(xy 21.917394 -31.378162) (xy 21.857938 -31.370334) (xy 21.800013 -31.354813) (xy 21.744609 -31.331864)
			(xy 21.692675 -31.30188) (xy 21.645099 -31.265374) (xy 21.602694 -31.222969) (xy 21.566188 -31.175393)
			(xy 21.536204 -31.123459) (xy 21.513255 -31.068055) (xy 21.497734 -31.01013) (xy 21.489906 -30.950674)
			(xy 21.489416 -30.92069) (xy 7.66826 -30.92069) (xy 7.66826 -30.922468) (xy 7.66777 -30.952436) (xy 7.659947 -31.011858)
			(xy 7.644434 -31.069751) (xy 7.621498 -31.125124) (xy 7.591531 -31.17703) (xy 7.555044 -31.22458)
			(xy 7.512664 -31.26696) (xy 7.465114 -31.303447) (xy 7.413208 -31.333414) (xy 7.357835 -31.35635)
			(xy 7.299942 -31.371863) (xy 7.24052 -31.379686) (xy 7.180584 -31.379686) (xy 7.121162 -31.371863)
			(xy 7.063269 -31.35635) (xy 7.007896 -31.333414) (xy 6.95599 -31.303447) (xy 6.90844 -31.26696) (xy 6.86606 -31.22458)
			(xy 6.829573 -31.17703) (xy 6.799606 -31.125124) (xy 6.77667 -31.069751) (xy 6.761157 -31.011858)
			(xy 6.753334 -30.952436) (xy 6.752844 -30.922468) (xy 0.715772 -30.922468) (xy 0.715772 -32.722312)
			(xy 8.607044 -32.722312) (xy 8.607044 -31.858712) (xy 8.607534 -31.828744) (xy 8.615357 -31.769322)
			(xy 8.63087 -31.711429) (xy 8.653806 -31.656056) (xy 8.683773 -31.60415) (xy 8.72026 -31.5566) (xy 8.76264 -31.51422)
			(xy 8.81019 -31.477733) (xy 8.862096 -31.447766) (xy 8.917469 -31.42483) (xy 8.975362 -31.409317)
			(xy 9.034784 -31.401494) (xy 9.09472 -31.401494) (xy 9.154142 -31.409317) (xy 9.212035 -31.42483)
			(xy 9.267408 -31.447766) (xy 9.319314 -31.477733) (xy 9.366864 -31.51422) (xy 9.409244 -31.5566)
			(xy 9.445731 -31.60415) (xy 9.475698 -31.656056) (xy 9.498634 -31.711429) (xy 9.514147 -31.769322)
			(xy 9.52197 -31.828744) (xy 9.52246 -31.858712) (xy 9.52246 -32.714184) (xy 18.847308 -32.714184)
			(xy 18.847308 -31.850584) (xy 18.847798 -31.8206) (xy 18.855626 -31.761144) (xy 18.871147 -31.703219)
			(xy 18.894096 -31.647815) (xy 18.92408 -31.595881) (xy 18.960586 -31.548305) (xy 19.002991 -31.5059)
			(xy 19.050567 -31.469394) (xy 19.102501 -31.43941) (xy 19.157905 -31.416461) (xy 19.21583 -31.40094)
			(xy 19.275286 -31.393112) (xy 19.335254 -31.393112) (xy 19.39471 -31.40094) (xy 19.452635 -31.416461)
			(xy 19.508039 -31.43941) (xy 19.559973 -31.469394) (xy 19.607549 -31.5059) (xy 19.649954 -31.548305)
			(xy 19.68646 -31.595881) (xy 19.716444 -31.647815) (xy 19.739393 -31.703219) (xy 19.754914 -31.761144)
			(xy 19.762742 -31.8206) (xy 19.763232 -31.850584) (xy 19.763232 -32.714184) (xy 19.762742 -32.744168)
			(xy 19.754914 -32.803624) (xy 19.739393 -32.861549) (xy 19.716444 -32.916953) (xy 19.68646 -32.968887)
			(xy 19.649954 -33.016463) (xy 19.607549 -33.058868) (xy 19.559973 -33.095374) (xy 19.508039 -33.125358)
			(xy 19.452635 -33.148307) (xy 19.39471 -33.163828) (xy 19.335254 -33.171656) (xy 19.275286 -33.171656)
			(xy 19.21583 -33.163828) (xy 19.157905 -33.148307) (xy 19.102501 -33.125358) (xy 19.050567 -33.095374)
			(xy 19.002991 -33.058868) (xy 18.960586 -33.016463) (xy 18.92408 -32.968887) (xy 18.894096 -32.916953)
			(xy 18.871147 -32.861549) (xy 18.855626 -32.803624) (xy 18.847798 -32.744168) (xy 18.847308 -32.714184)
			(xy 9.52246 -32.714184) (xy 9.52246 -32.722312) (xy 9.52197 -32.75228) (xy 9.514147 -32.811702) (xy 9.498634 -32.869595)
			(xy 9.475698 -32.924968) (xy 9.445731 -32.976874) (xy 9.409244 -33.024424) (xy 9.366864 -33.066804)
			(xy 9.319314 -33.103291) (xy 9.267408 -33.133258) (xy 9.212035 -33.156194) (xy 9.154142 -33.171707)
			(xy 9.09472 -33.17953) (xy 9.034784 -33.17953) (xy 8.975362 -33.171707) (xy 8.917469 -33.156194)
			(xy 8.862096 -33.133258) (xy 8.81019 -33.103291) (xy 8.76264 -33.066804) (xy 8.72026 -33.024424)
			(xy 8.683773 -32.976874) (xy 8.653806 -32.924968) (xy 8.63087 -32.869595) (xy 8.615357 -32.811702)
			(xy 8.607534 -32.75228) (xy 8.607044 -32.722312) (xy 0.715772 -32.722312) (xy 0.715772 -33.710626)
			(xy 2.52425 -33.710626) (xy 2.528321 -33.655004) (xy 2.540447 -33.600567) (xy 2.56037 -33.548476)
			(xy 2.587666 -33.499841) (xy 2.621752 -33.455698) (xy 2.661901 -33.416989) (xy 2.707259 -33.384538)
			(xy 2.756859 -33.359037) (xy 2.809643 -33.34103) (xy 2.864486 -33.3309) (xy 2.92022 -33.328863) (xy 2.975657 -33.334963)
			(xy 3.029614 -33.349069) (xy 3.080943 -33.370881) (xy 3.128549 -33.399935) (xy 3.171417 -33.43561)
			(xy 3.208634 -33.477147) (xy 3.239407 -33.52366) (xy 3.263079 -33.574157) (xy 3.279147 -33.627564)
			(xy 3.287267 -33.68274) (xy 3.287776 -33.710626) (xy 3.287267 -33.738512) (xy 3.279596 -33.790636)
			(xy 3.426966 -33.790636) (xy 3.431037 -33.735014) (xy 3.443163 -33.680577) (xy 3.463086 -33.628486)
			(xy 3.490382 -33.579851) (xy 3.524468 -33.535708) (xy 3.564617 -33.496999) (xy 3.609975 -33.464548)
			(xy 3.659575 -33.439047) (xy 3.712359 -33.42104) (xy 3.767202 -33.41091) (xy 3.822936 -33.408873)
			(xy 3.878373 -33.414973) (xy 3.93233 -33.429079) (xy 3.983659 -33.450891) (xy 4.031265 -33.479945)
			(xy 4.074133 -33.51562) (xy 4.11135 -33.557157) (xy 4.142123 -33.60367) (xy 4.165795 -33.654167)
			(xy 4.181863 -33.707574) (xy 4.189983 -33.76275) (xy 4.190334 -33.782) (xy 4.661152 -33.782) (xy 4.665223 -33.726378)
			(xy 4.677349 -33.671941) (xy 4.697272 -33.61985) (xy 4.724568 -33.571215) (xy 4.758654 -33.527072)
			(xy 4.798803 -33.488363) (xy 4.844161 -33.455912) (xy 4.893761 -33.430411) (xy 4.946545 -33.412404)
			(xy 5.001388 -33.402274) (xy 5.057122 -33.400237) (xy 5.112559 -33.406337) (xy 5.166516 -33.420443)
			(xy 5.217845 -33.442255) (xy 5.265451 -33.471309) (xy 5.308319 -33.506984) (xy 5.345536 -33.548521)
			(xy 5.376309 -33.595034) (xy 5.399981 -33.645531) (xy 5.416049 -33.698938) (xy 5.424169 -33.754114)
			(xy 5.424678 -33.782) (xy 5.424169 -33.809886) (xy 5.416049 -33.865062) (xy 5.399981 -33.918469)
			(xy 5.376309 -33.968966) (xy 5.345536 -34.015479) (xy 5.308319 -34.057016) (xy 5.265451 -34.092691)
			(xy 5.217845 -34.121745) (xy 5.166516 -34.143557) (xy 5.112559 -34.157663) (xy 5.057122 -34.163763)
			(xy 5.001388 -34.161726) (xy 4.946545 -34.151596) (xy 4.893761 -34.133589) (xy 4.844161 -34.108088)
			(xy 4.798803 -34.075637) (xy 4.758654 -34.036928) (xy 4.724568 -33.992785) (xy 4.697272 -33.94415)
			(xy 4.677349 -33.892059) (xy 4.665223 -33.837622) (xy 4.661152 -33.782) (xy 4.190334 -33.782) (xy 4.190492 -33.790636)
			(xy 4.189983 -33.818522) (xy 4.181863 -33.873698) (xy 4.165795 -33.927105) (xy 4.142123 -33.977602)
			(xy 4.11135 -34.024115) (xy 4.074133 -34.065652) (xy 4.031265 -34.101327) (xy 3.983659 -34.130381)
			(xy 3.93233 -34.152193) (xy 3.878373 -34.166299) (xy 3.822936 -34.172399) (xy 3.767202 -34.170362)
			(xy 3.712359 -34.160232) (xy 3.659575 -34.142225) (xy 3.609975 -34.116724) (xy 3.564617 -34.084273)
			(xy 3.524468 -34.045564) (xy 3.490382 -34.001421) (xy 3.463086 -33.952786) (xy 3.443163 -33.900695)
			(xy 3.431037 -33.846258) (xy 3.426966 -33.790636) (xy 3.279596 -33.790636) (xy 3.279147 -33.793688)
			(xy 3.263079 -33.847095) (xy 3.239407 -33.897592) (xy 3.208634 -33.944105) (xy 3.171417 -33.985642)
			(xy 3.128549 -34.021317) (xy 3.080943 -34.050371) (xy 3.029614 -34.072183) (xy 2.975657 -34.086289)
			(xy 2.92022 -34.092389) (xy 2.864486 -34.090352) (xy 2.809643 -34.080222) (xy 2.756859 -34.062215)
			(xy 2.707259 -34.036714) (xy 2.661901 -34.004263) (xy 2.621752 -33.965554) (xy 2.587666 -33.921411)
			(xy 2.56037 -33.872776) (xy 2.540447 -33.820685) (xy 2.528321 -33.766248) (xy 2.52425 -33.710626)
			(xy 0.715772 -33.710626) (xy 0.715772 -34.490406) (xy 1.92481 -34.490406) (xy 1.928881 -34.434784)
			(xy 1.941007 -34.380347) (xy 1.96093 -34.328256) (xy 1.988226 -34.279621) (xy 2.022312 -34.235478)
			(xy 2.062461 -34.196769) (xy 2.107819 -34.164318) (xy 2.157419 -34.138817) (xy 2.210203 -34.12081)
			(xy 2.265046 -34.11068) (xy 2.32078 -34.108643) (xy 2.376217 -34.114743) (xy 2.430174 -34.128849)
			(xy 2.481503 -34.150661) (xy 2.529109 -34.179715) (xy 2.571977 -34.21539) (xy 2.609194 -34.256927)
			(xy 2.639967 -34.30344) (xy 2.663639 -34.353937) (xy 2.679707 -34.407344) (xy 2.687827 -34.46252)
			(xy 2.688336 -34.490406) (xy 2.687827 -34.518292) (xy 2.687221 -34.52241) (xy 6.752844 -34.52241)
			(xy 6.752844 -33.65881) (xy 6.753334 -33.628842) (xy 6.761157 -33.56942) (xy 6.77667 -33.511527)
			(xy 6.799606 -33.456154) (xy 6.829573 -33.404248) (xy 6.86606 -33.356698) (xy 6.90844 -33.314318)
			(xy 6.95599 -33.277831) (xy 7.007896 -33.247864) (xy 7.063269 -33.224928) (xy 7.121162 -33.209415)
			(xy 7.180584 -33.201592) (xy 7.24052 -33.201592) (xy 7.299942 -33.209415) (xy 7.357835 -33.224928)
			(xy 7.413208 -33.247864) (xy 7.465114 -33.277831) (xy 7.512664 -33.314318) (xy 7.555044 -33.356698)
			(xy 7.591531 -33.404248) (xy 7.621498 -33.456154) (xy 7.644434 -33.511527) (xy 7.659947 -33.56942)
			(xy 7.66777 -33.628842) (xy 7.66826 -33.65881) (xy 7.66826 -34.520886) (xy 21.489416 -34.520886)
			(xy 21.489416 -33.657286) (xy 21.489906 -33.627302) (xy 21.497734 -33.567846) (xy 21.513255 -33.509921)
			(xy 21.536204 -33.454517) (xy 21.566188 -33.402583) (xy 21.602694 -33.355007) (xy 21.645099 -33.312602)
			(xy 21.692675 -33.276096) (xy 21.744609 -33.246112) (xy 21.800013 -33.223163) (xy 21.857938 -33.207642)
			(xy 21.917394 -33.199814) (xy 21.977362 -33.199814) (xy 22.036818 -33.207642) (xy 22.094743 -33.223163)
			(xy 22.150147 -33.246112) (xy 22.202081 -33.276096) (xy 22.249657 -33.312602) (xy 22.292062 -33.355007)
			(xy 22.328568 -33.402583) (xy 22.358552 -33.454517) (xy 22.381501 -33.509921) (xy 22.397022 -33.567846)
			(xy 22.40485 -33.627302) (xy 22.40534 -33.657286) (xy 22.40534 -34.520886) (xy 22.40485 -34.55087)
			(xy 22.397022 -34.610326) (xy 22.381501 -34.668251) (xy 22.358552 -34.723655) (xy 22.328568 -34.775589)
			(xy 22.292062 -34.823165) (xy 22.249657 -34.86557) (xy 22.202081 -34.902076) (xy 22.150147 -34.93206)
			(xy 22.094743 -34.955009) (xy 22.036818 -34.97053) (xy 21.977362 -34.978358) (xy 21.917394 -34.978358)
			(xy 21.857938 -34.97053) (xy 21.800013 -34.955009) (xy 21.744609 -34.93206) (xy 21.692675 -34.902076)
			(xy 21.645099 -34.86557) (xy 21.602694 -34.823165) (xy 21.566188 -34.775589) (xy 21.536204 -34.723655)
			(xy 21.513255 -34.668251) (xy 21.497734 -34.610326) (xy 21.489906 -34.55087) (xy 21.489416 -34.520886)
			(xy 7.66826 -34.520886) (xy 7.66826 -34.52241) (xy 7.66777 -34.552378) (xy 7.659947 -34.6118) (xy 7.644434 -34.669693)
			(xy 7.621498 -34.725066) (xy 7.591531 -34.776972) (xy 7.555044 -34.824522) (xy 7.512664 -34.866902)
			(xy 7.465114 -34.903389) (xy 7.413208 -34.933356) (xy 7.357835 -34.956292) (xy 7.299942 -34.971805)
			(xy 7.24052 -34.979628) (xy 7.180584 -34.979628) (xy 7.121162 -34.971805) (xy 7.063269 -34.956292)
			(xy 7.007896 -34.933356) (xy 6.95599 -34.903389) (xy 6.90844 -34.866902) (xy 6.86606 -34.824522)
			(xy 6.829573 -34.776972) (xy 6.799606 -34.725066) (xy 6.77667 -34.669693) (xy 6.761157 -34.6118)
			(xy 6.753334 -34.552378) (xy 6.752844 -34.52241) (xy 2.687221 -34.52241) (xy 2.679707 -34.573468)
			(xy 2.663639 -34.626875) (xy 2.639967 -34.677372) (xy 2.609194 -34.723885) (xy 2.571977 -34.765422)
			(xy 2.529109 -34.801097) (xy 2.481503 -34.830151) (xy 2.430174 -34.851963) (xy 2.376217 -34.866069)
			(xy 2.32078 -34.872169) (xy 2.265046 -34.870132) (xy 2.210203 -34.860002) (xy 2.157419 -34.841995)
			(xy 2.107819 -34.816494) (xy 2.062461 -34.784043) (xy 2.022312 -34.745334) (xy 1.988226 -34.701191)
			(xy 1.96093 -34.652556) (xy 1.941007 -34.600465) (xy 1.928881 -34.546028) (xy 1.92481 -34.490406)
			(xy 0.715772 -34.490406) (xy 0.715772 -35.91941) (xy 2.665728 -35.91941) (xy 2.669799 -35.863788)
			(xy 2.681925 -35.809351) (xy 2.701848 -35.75726) (xy 2.729144 -35.708625) (xy 2.76323 -35.664482)
			(xy 2.803379 -35.625773) (xy 2.848737 -35.593322) (xy 2.898337 -35.567821) (xy 2.951121 -35.549814)
			(xy 3.005964 -35.539684) (xy 3.061698 -35.537647) (xy 3.117135 -35.543747) (xy 3.171092 -35.557853)
			(xy 3.222421 -35.579665) (xy 3.270027 -35.608719) (xy 3.312895 -35.644394) (xy 3.350112 -35.685931)
			(xy 3.380885 -35.732444) (xy 3.404557 -35.782941) (xy 3.420625 -35.836348) (xy 3.427317 -35.881818)
			(xy 3.668774 -35.881818) (xy 3.672845 -35.826196) (xy 3.684971 -35.771759) (xy 3.704894 -35.719668)
			(xy 3.73219 -35.671033) (xy 3.766276 -35.62689) (xy 3.806425 -35.588181) (xy 3.851783 -35.55573)
			(xy 3.901383 -35.530229) (xy 3.954167 -35.512222) (xy 4.00901 -35.502092) (xy 4.064744 -35.500055)
			(xy 4.120181 -35.506155) (xy 4.174138 -35.520261) (xy 4.225467 -35.542073) (xy 4.273073 -35.571127)
			(xy 4.315941 -35.606802) (xy 4.353158 -35.648339) (xy 4.383931 -35.694852) (xy 4.407603 -35.745349)
			(xy 4.423671 -35.798756) (xy 4.431791 -35.853932) (xy 4.4323 -35.881818) (xy 4.43186 -35.905948)
			(xy 4.661152 -35.905948) (xy 4.665223 -35.850326) (xy 4.677349 -35.795889) (xy 4.697272 -35.743798)
			(xy 4.724568 -35.695163) (xy 4.758654 -35.65102) (xy 4.798803 -35.612311) (xy 4.844161 -35.57986)
			(xy 4.893761 -35.554359) (xy 4.946545 -35.536352) (xy 5.001388 -35.526222) (xy 5.057122 -35.524185)
			(xy 5.112559 -35.530285) (xy 5.166516 -35.544391) (xy 5.217845 -35.566203) (xy 5.265451 -35.595257)
			(xy 5.308319 -35.630932) (xy 5.345536 -35.672469) (xy 5.376309 -35.718982) (xy 5.399981 -35.769479)
			(xy 5.416049 -35.822886) (xy 5.424169 -35.878062) (xy 5.424678 -35.905948) (xy 5.424169 -35.933834)
			(xy 5.416049 -35.98901) (xy 5.399981 -36.042417) (xy 5.376309 -36.092914) (xy 5.345536 -36.139427)
			(xy 5.308319 -36.180964) (xy 5.265451 -36.216639) (xy 5.217845 -36.245693) (xy 5.166516 -36.267505)
			(xy 5.112559 -36.281611) (xy 5.057122 -36.287711) (xy 5.001388 -36.285674) (xy 4.946545 -36.275544)
			(xy 4.893761 -36.257537) (xy 4.844161 -36.232036) (xy 4.798803 -36.199585) (xy 4.758654 -36.160876)
			(xy 4.724568 -36.116733) (xy 4.697272 -36.068098) (xy 4.677349 -36.016007) (xy 4.665223 -35.96157)
			(xy 4.661152 -35.905948) (xy 4.43186 -35.905948) (xy 4.431791 -35.909704) (xy 4.423671 -35.96488)
			(xy 4.407603 -36.018287) (xy 4.383931 -36.068784) (xy 4.353158 -36.115297) (xy 4.315941 -36.156834)
			(xy 4.273073 -36.192509) (xy 4.225467 -36.221563) (xy 4.174138 -36.243375) (xy 4.120181 -36.257481)
			(xy 4.064744 -36.263581) (xy 4.00901 -36.261544) (xy 3.954167 -36.251414) (xy 3.901383 -36.233407)
			(xy 3.851783 -36.207906) (xy 3.806425 -36.175455) (xy 3.766276 -36.136746) (xy 3.73219 -36.092603)
			(xy 3.704894 -36.043968) (xy 3.684971 -35.991877) (xy 3.672845 -35.93744) (xy 3.668774 -35.881818)
			(xy 3.427317 -35.881818) (xy 3.428745 -35.891524) (xy 3.429254 -35.91941) (xy 3.428745 -35.947296)
			(xy 3.420625 -36.002472) (xy 3.404557 -36.055879) (xy 3.380885 -36.106376) (xy 3.350112 -36.152889)
			(xy 3.312895 -36.194426) (xy 3.270027 -36.230101) (xy 3.222421 -36.259155) (xy 3.171092 -36.280967)
			(xy 3.117135 -36.295073) (xy 3.061698 -36.301173) (xy 3.005964 -36.299136) (xy 2.951121 -36.289006)
			(xy 2.898337 -36.270999) (xy 2.848737 -36.245498) (xy 2.803379 -36.213047) (xy 2.76323 -36.174338)
			(xy 2.729144 -36.130195) (xy 2.701848 -36.08156) (xy 2.681925 -36.029469) (xy 2.669799 -35.975032)
			(xy 2.665728 -35.91941) (xy 0.715772 -35.91941) (xy 0.715772 -36.60013) (xy 11.998205 -36.60013)
			(xy 12.00221 -36.512222) (xy 12.014193 -36.425042) (xy 12.034053 -36.339313) (xy 12.061628 -36.255745)
			(xy 12.096687 -36.175031) (xy 12.13894 -36.097839) (xy 12.188038 -36.02481) (xy 12.243574 -35.956548)
			(xy 12.305086 -35.893618) (xy 12.372067 -35.836544) (xy 12.44396 -35.785796) (xy 12.520169 -35.741796)
			(xy 12.600064 -35.704909) (xy 12.682983 -35.67544) (xy 12.768238 -35.653633) (xy 12.855122 -35.639669)
			(xy 12.942916 -35.633663) (xy 13.030893 -35.635667) (xy 13.118323 -35.645662) (xy 13.204482 -35.663566)
			(xy 13.288656 -35.68923) (xy 13.370147 -35.722443) (xy 13.448281 -35.762929) (xy 13.522409 -35.810351)
			(xy 13.591917 -35.864318) (xy 13.605216 -35.876738) (xy 18.717258 -35.876738) (xy 18.721329 -35.821116)
			(xy 18.733455 -35.766679) (xy 18.753378 -35.714588) (xy 18.780674 -35.665953) (xy 18.81476 -35.62181)
			(xy 18.854909 -35.583101) (xy 18.900267 -35.55065) (xy 18.949867 -35.525149) (xy 19.002651 -35.507142)
			(xy 19.057494 -35.497012) (xy 19.113228 -35.494975) (xy 19.168665 -35.501075) (xy 19.222622 -35.515181)
			(xy 19.273951 -35.536993) (xy 19.321557 -35.566047) (xy 19.364425 -35.601722) (xy 19.401642 -35.643259)
			(xy 19.432415 -35.689772) (xy 19.456087 -35.740269) (xy 19.472155 -35.793676) (xy 19.480275 -35.848852)
			(xy 19.480784 -35.876738) (xy 22.789388 -35.876738) (xy 22.789874 -35.849487) (xy 22.79763 -35.795539)
			(xy 22.812985 -35.743244) (xy 22.835627 -35.693667) (xy 22.865093 -35.647817) (xy 22.900784 -35.606626)
			(xy 22.941975 -35.570935) (xy 22.987825 -35.541469) (xy 23.037402 -35.518827) (xy 23.089697 -35.503472)
			(xy 23.143645 -35.495716) (xy 23.198147 -35.495716) (xy 23.252095 -35.503472) (xy 23.30439 -35.518827)
			(xy 23.353967 -35.541469) (xy 23.399817 -35.570935) (xy 23.441008 -35.606626) (xy 23.476699 -35.647817)
			(xy 23.506165 -35.693667) (xy 23.528807 -35.743244) (xy 23.544162 -35.795539) (xy 23.551918 -35.849487)
			(xy 23.552404 -35.876738) (xy 23.551879 -35.905485) (xy 23.543214 -35.962323) (xy 23.526116 -36.017217)
			(xy 23.500973 -36.068923) (xy 23.485094 -36.092892) (xy 23.477483 -36.104722) (xy 23.468486 -36.131366)
			(xy 23.467098 -36.159453) (xy 23.473425 -36.186853) (xy 23.486986 -36.211489) (xy 23.506754 -36.23149)
			(xy 23.531228 -36.24534) (xy 23.544784 -36.249102) (xy 23.57205 -36.256313) (xy 23.624227 -36.277717)
			(xy 23.672687 -36.306568) (xy 23.716372 -36.342237) (xy 23.754332 -36.383948) (xy 23.785739 -36.43079)
			(xy 23.796546 -36.453572) (xy 23.928576 -36.453572) (xy 23.932647 -36.39795) (xy 23.944773 -36.343513)
			(xy 23.964696 -36.291422) (xy 23.991992 -36.242787) (xy 24.026078 -36.198644) (xy 24.066227 -36.159935)
			(xy 24.111585 -36.127484) (xy 24.161185 -36.101983) (xy 24.213969 -36.083976) (xy 24.268812 -36.073846)
			(xy 24.324546 -36.071809) (xy 24.379983 -36.077909) (xy 24.43394 -36.092015) (xy 24.485269 -36.113827)
			(xy 24.532875 -36.142881) (xy 24.575743 -36.178556) (xy 24.61296 -36.220093) (xy 24.643733 -36.266606)
			(xy 24.667405 -36.317103) (xy 24.683473 -36.37051) (xy 24.691593 -36.425686) (xy 24.692102 -36.453572)
			(xy 24.691593 -36.481458) (xy 24.683473 -36.536634) (xy 24.667405 -36.590041) (xy 24.643733 -36.640538)
			(xy 24.61296 -36.687051) (xy 24.575743 -36.728588) (xy 24.532875 -36.764263) (xy 24.485269 -36.793317)
			(xy 24.43394 -36.815129) (xy 24.379983 -36.829235) (xy 24.324546 -36.835335) (xy 24.268812 -36.833298)
			(xy 24.213969 -36.823168) (xy 24.161185 -36.805161) (xy 24.111585 -36.77966) (xy 24.066227 -36.747209)
			(xy 24.026078 -36.7085) (xy 23.991992 -36.664357) (xy 23.964696 -36.615722) (xy 23.944773 -36.563631)
			(xy 23.932647 -36.509194) (xy 23.928576 -36.453572) (xy 23.796546 -36.453572) (xy 23.80991 -36.481746)
			(xy 23.826318 -36.535704) (xy 23.834606 -36.591489) (xy 23.835106 -36.619688) (xy 23.83462 -36.646939)
			(xy 23.826864 -36.700887) (xy 23.811509 -36.753182) (xy 23.788867 -36.802759) (xy 23.759401 -36.848609)
			(xy 23.72371 -36.8898) (xy 23.682519 -36.925491) (xy 23.636669 -36.954957) (xy 23.587092 -36.977599)
			(xy 23.534797 -36.992954) (xy 23.480849 -37.00071) (xy 23.426347 -37.00071) (xy 23.372399 -36.992954)
			(xy 23.320104 -36.977599) (xy 23.270527 -36.954957) (xy 23.224677 -36.925491) (xy 23.183486 -36.8898)
			(xy 23.147795 -36.848609) (xy 23.118329 -36.802759) (xy 23.095687 -36.753182) (xy 23.080332 -36.700887)
			(xy 23.072576 -36.646939) (xy 23.07209 -36.619688) (xy 23.072629 -36.590941) (xy 23.08129 -36.534104)
			(xy 23.098384 -36.47921) (xy 23.123523 -36.427504) (xy 23.1394 -36.403534) (xy 23.146982 -36.391686)
			(xy 23.155984 -36.365049) (xy 23.157376 -36.336966) (xy 23.151054 -36.309568) (xy 23.137497 -36.284935)
			(xy 23.117734 -36.264935) (xy 23.093264 -36.251086) (xy 23.07971 -36.247324) (xy 23.05245 -36.240094)
			(xy 23.000274 -36.21869) (xy 22.951816 -36.189841) (xy 22.908131 -36.154174) (xy 22.870172 -36.112467)
			(xy 22.838764 -36.065626) (xy 22.814591 -36.014674) (xy 22.798181 -35.960719) (xy 22.78989 -35.904936)
			(xy 22.789388 -35.876738) (xy 19.480784 -35.876738) (xy 19.480275 -35.904624) (xy 19.472155 -35.9598)
			(xy 19.456087 -36.013207) (xy 19.432415 -36.063704) (xy 19.401642 -36.110217) (xy 19.364425 -36.151754)
			(xy 19.321557 -36.187429) (xy 19.273951 -36.216483) (xy 19.222622 -36.238295) (xy 19.168665 -36.252401)
			(xy 19.113228 -36.258501) (xy 19.057494 -36.256464) (xy 19.002651 -36.246334) (xy 18.949867 -36.228327)
			(xy 18.900267 -36.202826) (xy 18.854909 -36.170375) (xy 18.81476 -36.131666) (xy 18.780674 -36.087523)
			(xy 18.753378 -36.038888) (xy 18.733455 -35.986797) (xy 18.721329 -35.93236) (xy 18.717258 -35.876738)
			(xy 13.605216 -35.876738) (xy 13.656231 -35.924383) (xy 13.714815 -35.990047) (xy 13.767186 -36.060766)
			(xy 13.812909 -36.135954) (xy 13.851606 -36.214989) (xy 13.882955 -36.297215) (xy 13.906697 -36.381951)
			(xy 13.922635 -36.468495) (xy 13.926421 -36.50996) (xy 20.613876 -36.50996) (xy 20.617947 -36.454338)
			(xy 20.630073 -36.399901) (xy 20.649996 -36.34781) (xy 20.677292 -36.299175) (xy 20.711378 -36.255032)
			(xy 20.751527 -36.216323) (xy 20.796885 -36.183872) (xy 20.846485 -36.158371) (xy 20.899269 -36.140364)
			(xy 20.954112 -36.130234) (xy 21.009846 -36.128197) (xy 21.065283 -36.134297) (xy 21.11924 -36.148403)
			(xy 21.170569 -36.170215) (xy 21.218175 -36.199269) (xy 21.261043 -36.234944) (xy 21.29826 -36.276481)
			(xy 21.329033 -36.322994) (xy 21.352705 -36.373491) (xy 21.368773 -36.426898) (xy 21.376893 -36.482074)
			(xy 21.377402 -36.50996) (xy 21.376893 -36.537846) (xy 21.368773 -36.593022) (xy 21.352705 -36.646429)
			(xy 21.329033 -36.696926) (xy 21.29826 -36.743439) (xy 21.261043 -36.784976) (xy 21.218175 -36.820651)
			(xy 21.170569 -36.849705) (xy 21.11924 -36.871517) (xy 21.065283 -36.885623) (xy 21.009846 -36.891723)
			(xy 20.954112 -36.889686) (xy 20.899269 -36.879556) (xy 20.846485 -36.861549) (xy 20.796885 -36.836048)
			(xy 20.751527 -36.803597) (xy 20.711378 -36.764888) (xy 20.677292 -36.720745) (xy 20.649996 -36.67211)
			(xy 20.630073 -36.620019) (xy 20.617947 -36.565582) (xy 20.613876 -36.50996) (xy 13.926421 -36.50996)
			(xy 13.930637 -36.55613) (xy 13.931138 -36.60013) (xy 13.930637 -36.64413) (xy 13.922635 -36.731765)
			(xy 13.906697 -36.818309) (xy 13.882955 -36.903045) (xy 13.851606 -36.985271) (xy 13.812909 -37.064306)
			(xy 13.767186 -37.139494) (xy 13.714815 -37.210213) (xy 13.656231 -37.275877) (xy 13.591917 -37.335942)
			(xy 13.522409 -37.389909) (xy 13.448281 -37.437331) (xy 13.375275 -37.47516) (xy 17.75917 -37.47516)
			(xy 17.763241 -37.419538) (xy 17.775367 -37.365101) (xy 17.79529 -37.31301) (xy 17.822586 -37.264375)
			(xy 17.856672 -37.220232) (xy 17.896821 -37.181523) (xy 17.942179 -37.149072) (xy 17.991779 -37.123571)
			(xy 18.044563 -37.105564) (xy 18.099406 -37.095434) (xy 18.15514 -37.093397) (xy 18.210577 -37.099497)
			(xy 18.264534 -37.113603) (xy 18.315863 -37.135415) (xy 18.363469 -37.164469) (xy 18.406337 -37.200144)
			(xy 18.443554 -37.241681) (xy 18.474327 -37.288194) (xy 18.497999 -37.338691) (xy 18.514067 -37.392098)
			(xy 18.522187 -37.447274) (xy 18.522696 -37.47516) (xy 18.522187 -37.503046) (xy 18.514067 -37.558222)
			(xy 18.497999 -37.611629) (xy 18.474327 -37.662126) (xy 18.474174 -37.662358) (xy 19.948396 -37.662358)
			(xy 19.952467 -37.606736) (xy 19.964593 -37.552299) (xy 19.984516 -37.500208) (xy 20.011812 -37.451573)
			(xy 20.045898 -37.40743) (xy 20.086047 -37.368721) (xy 20.131405 -37.33627) (xy 20.181005 -37.310769)
			(xy 20.233789 -37.292762) (xy 20.288632 -37.282632) (xy 20.344366 -37.280595) (xy 20.399803 -37.286695)
			(xy 20.45376 -37.300801) (xy 20.505089 -37.322613) (xy 20.552695 -37.351667) (xy 20.595563 -37.387342)
			(xy 20.63278 -37.428879) (xy 20.663553 -37.475392) (xy 20.687225 -37.525889) (xy 20.703293 -37.579296)
			(xy 20.711413 -37.634472) (xy 20.711922 -37.662358) (xy 20.711413 -37.690244) (xy 20.703293 -37.74542)
			(xy 20.687225 -37.798827) (xy 20.663553 -37.849324) (xy 20.63278 -37.895837) (xy 20.595563 -37.937374)
			(xy 20.552695 -37.973049) (xy 20.505089 -38.002103) (xy 20.45376 -38.023915) (xy 20.399803 -38.038021)
			(xy 20.344366 -38.044121) (xy 20.288632 -38.042084) (xy 20.233789 -38.031954) (xy 20.181005 -38.013947)
			(xy 20.131405 -37.988446) (xy 20.086047 -37.955995) (xy 20.045898 -37.917286) (xy 20.011812 -37.873143)
			(xy 19.984516 -37.824508) (xy 19.964593 -37.772417) (xy 19.952467 -37.71798) (xy 19.948396 -37.662358)
			(xy 18.474174 -37.662358) (xy 18.443554 -37.708639) (xy 18.406337 -37.750176) (xy 18.363469 -37.785851)
			(xy 18.315863 -37.814905) (xy 18.264534 -37.836717) (xy 18.210577 -37.850823) (xy 18.15514 -37.856923)
			(xy 18.099406 -37.854886) (xy 18.044563 -37.844756) (xy 17.991779 -37.826749) (xy 17.942179 -37.801248)
			(xy 17.896821 -37.768797) (xy 17.856672 -37.730088) (xy 17.822586 -37.685945) (xy 17.79529 -37.63731)
			(xy 17.775367 -37.585219) (xy 17.763241 -37.530782) (xy 17.75917 -37.47516) (xy 13.375275 -37.47516)
			(xy 13.370147 -37.477817) (xy 13.288656 -37.51103) (xy 13.204482 -37.536694) (xy 13.118323 -37.554598)
			(xy 13.030893 -37.564593) (xy 12.942916 -37.566597) (xy 12.855122 -37.560591) (xy 12.768238 -37.546627)
			(xy 12.682983 -37.52482) (xy 12.600064 -37.495351) (xy 12.520169 -37.458464) (xy 12.44396 -37.414464)
			(xy 12.372067 -37.363716) (xy 12.305086 -37.306642) (xy 12.243574 -37.243712) (xy 12.188038 -37.17545)
			(xy 12.13894 -37.102421) (xy 12.096687 -37.025229) (xy 12.061628 -36.944515) (xy 12.034053 -36.860947)
			(xy 12.014193 -36.775218) (xy 12.00221 -36.688038) (xy 11.998205 -36.60013) (xy 0.715772 -36.60013)
			(xy 0.715772 -38.928802) (xy 3.912868 -38.928802) (xy 3.916939 -38.87318) (xy 3.929065 -38.818743)
			(xy 3.948988 -38.766652) (xy 3.976284 -38.718017) (xy 4.01037 -38.673874) (xy 4.050519 -38.635165)
			(xy 4.095877 -38.602714) (xy 4.145477 -38.577213) (xy 4.198261 -38.559206) (xy 4.253104 -38.549076)
			(xy 4.308838 -38.547039) (xy 4.364275 -38.553139) (xy 4.418232 -38.567245) (xy 4.469561 -38.589057)
			(xy 4.517167 -38.618111) (xy 4.560035 -38.653786) (xy 4.597252 -38.695323) (xy 4.628025 -38.741836)
			(xy 4.651697 -38.792333) (xy 4.667765 -38.84574) (xy 4.675885 -38.900916) (xy 4.676394 -38.928802)
			(xy 5.182868 -38.928802) (xy 5.186939 -38.87318) (xy 5.199065 -38.818743) (xy 5.218988 -38.766652)
			(xy 5.246284 -38.718017) (xy 5.28037 -38.673874) (xy 5.320519 -38.635165) (xy 5.365877 -38.602714)
			(xy 5.415477 -38.577213) (xy 5.468261 -38.559206) (xy 5.523104 -38.549076) (xy 5.578838 -38.547039)
			(xy 5.634275 -38.553139) (xy 5.688232 -38.567245) (xy 5.739561 -38.589057) (xy 5.787167 -38.618111)
			(xy 5.830035 -38.653786) (xy 5.867252 -38.695323) (xy 5.89016 -38.729948) (xy 23.70102 -38.729948)
			(xy 23.70102 -38.675452) (xy 23.708776 -38.621511) (xy 23.724129 -38.569222) (xy 23.746767 -38.519651)
			(xy 23.776229 -38.473806) (xy 23.811916 -38.432621) (xy 23.853101 -38.396933) (xy 23.898946 -38.36747)
			(xy 23.948517 -38.344831) (xy 24.000805 -38.329477) (xy 24.054746 -38.321721) (xy 24.081994 -38.321234)
			(xy 24.110299 -38.321713) (xy 24.166288 -38.330064) (xy 24.220429 -38.3466) (xy 24.27153 -38.370957)
			(xy 24.31847 -38.4026) (xy 24.360216 -38.440834) (xy 24.395854 -38.484818) (xy 24.41067 -38.50894)
			(xy 24.41834 -38.520924) (xy 24.438944 -38.540523) (xy 24.46416 -38.553667) (xy 24.492027 -38.559332)
			(xy 24.520374 -38.557078) (xy 24.546994 -38.54708) (xy 24.569817 -38.530116) (xy 24.578818 -38.5191)
			(xy 24.596999 -38.49622) (xy 24.639163 -38.455756) (xy 24.687 -38.422189) (xy 24.739393 -38.396303)
			(xy 24.795118 -38.378701) (xy 24.852875 -38.369796) (xy 24.882094 -38.36924) (xy 24.909345 -38.36973)
			(xy 24.963292 -38.377487) (xy 25.015586 -38.392842) (xy 25.065162 -38.415484) (xy 25.111012 -38.44495)
			(xy 25.152202 -38.480641) (xy 25.187893 -38.521831) (xy 25.217358 -38.567681) (xy 25.239999 -38.617258)
			(xy 25.255354 -38.669552) (xy 25.26311 -38.723499) (xy 25.26311 -38.778001) (xy 25.255354 -38.831948)
			(xy 25.239999 -38.884242) (xy 25.217358 -38.933819) (xy 25.187893 -38.979669) (xy 25.152202 -39.020859)
			(xy 25.111012 -39.05655) (xy 25.065162 -39.086016) (xy 25.015586 -39.108658) (xy 24.963292 -39.124013)
			(xy 24.909345 -39.13177) (xy 24.882094 -39.132256) (xy 24.853789 -39.131792) (xy 24.797798 -39.123438)
			(xy 24.743657 -39.1069) (xy 24.692556 -39.08254) (xy 24.645616 -39.050895) (xy 24.60387 -39.01266)
			(xy 24.568234 -38.968673) (xy 24.553418 -38.94455) (xy 24.545763 -38.932555) (xy 24.525156 -38.912957)
			(xy 24.499936 -38.899815) (xy 24.472067 -38.894152) (xy 24.443718 -38.896408) (xy 24.417096 -38.906408)
			(xy 24.394272 -38.923373) (xy 24.38527 -38.93439) (xy 24.367093 -38.957274) (xy 24.324929 -38.997738)
			(xy 24.277091 -39.031305) (xy 24.224697 -39.057191) (xy 24.168971 -39.074791) (xy 24.111214 -39.083694)
			(xy 24.081994 -39.08425) (xy 24.054746 -39.083679) (xy 24.000805 -39.075923) (xy 23.948517 -39.060569)
			(xy 23.898946 -39.03793) (xy 23.853101 -39.008467) (xy 23.811916 -38.972779) (xy 23.776229 -38.931594)
			(xy 23.746767 -38.885749) (xy 23.724129 -38.836178) (xy 23.708776 -38.783889) (xy 23.70102 -38.729948)
			(xy 5.89016 -38.729948) (xy 5.898025 -38.741836) (xy 5.921697 -38.792333) (xy 5.937765 -38.84574)
			(xy 5.945885 -38.900916) (xy 5.946394 -38.928802) (xy 5.945885 -38.956688) (xy 5.937765 -39.011864)
			(xy 5.921697 -39.065271) (xy 5.898025 -39.115768) (xy 5.867252 -39.162281) (xy 5.830035 -39.203818)
			(xy 5.787167 -39.239493) (xy 5.739561 -39.268547) (xy 5.688232 -39.290359) (xy 5.634275 -39.304465)
			(xy 5.578838 -39.310565) (xy 5.523104 -39.308528) (xy 5.468261 -39.298398) (xy 5.415477 -39.280391)
			(xy 5.365877 -39.25489) (xy 5.320519 -39.222439) (xy 5.28037 -39.18373) (xy 5.246284 -39.139587)
			(xy 5.218988 -39.090952) (xy 5.199065 -39.038861) (xy 5.186939 -38.984424) (xy 5.182868 -38.928802)
			(xy 4.676394 -38.928802) (xy 4.675885 -38.956688) (xy 4.667765 -39.011864) (xy 4.651697 -39.065271)
			(xy 4.628025 -39.115768) (xy 4.597252 -39.162281) (xy 4.560035 -39.203818) (xy 4.517167 -39.239493)
			(xy 4.469561 -39.268547) (xy 4.418232 -39.290359) (xy 4.364275 -39.304465) (xy 4.308838 -39.310565)
			(xy 4.253104 -39.308528) (xy 4.198261 -39.298398) (xy 4.145477 -39.280391) (xy 4.095877 -39.25489)
			(xy 4.050519 -39.222439) (xy 4.01037 -39.18373) (xy 3.976284 -39.139587) (xy 3.948988 -39.090952)
			(xy 3.929065 -39.038861) (xy 3.916939 -38.984424) (xy 3.912868 -38.928802) (xy 0.715772 -38.928802)
			(xy 0.715772 -39.97198) (xy 25.895806 -39.97198) (xy 25.899877 -39.916358) (xy 25.912003 -39.861921)
			(xy 25.931926 -39.80983) (xy 25.959222 -39.761195) (xy 25.993308 -39.717052) (xy 26.033457 -39.678343)
			(xy 26.078815 -39.645892) (xy 26.128415 -39.620391) (xy 26.181199 -39.602384) (xy 26.236042 -39.592254)
			(xy 26.291776 -39.590217) (xy 26.347213 -39.596317) (xy 26.40117 -39.610423) (xy 26.452499 -39.632235)
			(xy 26.500105 -39.661289) (xy 26.542973 -39.696964) (xy 26.58019 -39.738501) (xy 26.610963 -39.785014)
			(xy 26.634635 -39.835511) (xy 26.650703 -39.888918) (xy 26.658823 -39.944094) (xy 26.659332 -39.97198)
			(xy 26.658823 -39.999866) (xy 26.650703 -40.055042) (xy 26.634635 -40.108449) (xy 26.610963 -40.158946)
			(xy 26.58019 -40.205459) (xy 26.542973 -40.246996) (xy 26.500105 -40.282671) (xy 26.452499 -40.311725)
			(xy 26.40117 -40.333537) (xy 26.347213 -40.347643) (xy 26.291776 -40.353743) (xy 26.236042 -40.351706)
			(xy 26.181199 -40.341576) (xy 26.128415 -40.323569) (xy 26.078815 -40.298068) (xy 26.033457 -40.265617)
			(xy 25.993308 -40.226908) (xy 25.959222 -40.182765) (xy 25.931926 -40.13413) (xy 25.912003 -40.082039)
			(xy 25.899877 -40.027602) (xy 25.895806 -39.97198) (xy 0.715772 -39.97198) (xy 0.715772 -41.166542)
			(xy 2.403856 -41.166542) (xy 2.404383 -41.137625) (xy 2.413107 -41.080453) (xy 2.430362 -41.025254)
			(xy 2.455752 -40.973292) (xy 2.488695 -40.925758) (xy 2.528436 -40.883741) (xy 2.550922 -40.865552)
			(xy 2.559745 -40.85796) (xy 2.569919 -40.837048) (xy 2.57048 -40.82542) (xy 2.57048 -40.745664) (xy 2.569954 -40.73403)
			(xy 2.559757 -40.713121) (xy 2.550922 -40.705532) (xy 2.528438 -40.687342) (xy 2.488703 -40.645322)
			(xy 2.455764 -40.597787) (xy 2.430376 -40.545825) (xy 2.41312 -40.490628) (xy 2.404391 -40.433458)
			(xy 2.403856 -40.404542) (xy 2.404342 -40.377291) (xy 2.412098 -40.323343) (xy 2.427453 -40.271048)
			(xy 2.450095 -40.221471) (xy 2.479561 -40.175621) (xy 2.515252 -40.13443) (xy 2.556443 -40.098739)
			(xy 2.602293 -40.069273) (xy 2.65187 -40.046631) (xy 2.704165 -40.031276) (xy 2.758113 -40.02352)
			(xy 2.812615 -40.02352) (xy 2.866563 -40.031276) (xy 2.918858 -40.046631) (xy 2.968435 -40.069273)
			(xy 3.014285 -40.098739) (xy 3.055476 -40.13443) (xy 3.091167 -40.175621) (xy 3.120633 -40.221471)
			(xy 3.143275 -40.271048) (xy 3.15863 -40.323343) (xy 3.166386 -40.377291) (xy 3.166872 -40.404542)
			(xy 3.166323 -40.433458) (xy 3.157602 -40.490628) (xy 3.140351 -40.545827) (xy 3.114965 -40.597789)
			(xy 3.082026 -40.645324) (xy 3.04229 -40.687341) (xy 3.019806 -40.705532) (xy 3.010995 -40.713136)
			(xy 3.000813 -40.734039) (xy 3.000248 -40.745664) (xy 3.000248 -40.82542) (xy 3.000773 -40.837054)
			(xy 3.01097 -40.857964) (xy 3.019806 -40.865552) (xy 3.042287 -40.883746) (xy 3.082022 -40.925765)
			(xy 3.114961 -40.9733) (xy 3.14035 -41.02526) (xy 3.157607 -41.080457) (xy 3.166337 -41.137626) (xy 3.166872 -41.166542)
			(xy 5.443982 -41.166542) (xy 5.4445 -41.137625) (xy 5.453225 -41.080452) (xy 5.470481 -41.025252)
			(xy 5.495872 -40.97329) (xy 5.528818 -40.925756) (xy 5.568561 -40.883741) (xy 5.591048 -40.865552)
			(xy 5.599875 -40.857964) (xy 5.610046 -40.837048) (xy 5.610606 -40.82542) (xy 5.610606 -40.745664)
			(xy 5.610071 -40.734032) (xy 5.599879 -40.713122) (xy 5.591048 -40.705532) (xy 5.568569 -40.687336)
			(xy 5.528836 -40.645316) (xy 5.495898 -40.597781) (xy 5.470509 -40.545821) (xy 5.453251 -40.490625)
			(xy 5.444519 -40.433457) (xy 5.443982 -40.404542) (xy 5.444468 -40.377291) (xy 5.452224 -40.323343)
			(xy 5.467579 -40.271048) (xy 5.490221 -40.221471) (xy 5.519687 -40.175621) (xy 5.555378 -40.13443)
			(xy 5.596569 -40.098739) (xy 5.642419 -40.069273) (xy 5.691996 -40.046631) (xy 5.744291 -40.031276)
			(xy 5.798239 -40.02352) (xy 5.852741 -40.02352) (xy 5.906689 -40.031276) (xy 5.958984 -40.046631)
			(xy 6.008561 -40.069273) (xy 6.054411 -40.098739) (xy 6.095602 -40.13443) (xy 6.131293 -40.175621)
			(xy 6.160759 -40.221471) (xy 6.183401 -40.271048) (xy 6.198756 -40.323343) (xy 6.206512 -40.377291)
			(xy 6.206998 -40.404542) (xy 6.206439 -40.433457) (xy 6.197718 -40.490627) (xy 6.180469 -40.545825)
			(xy 6.155085 -40.597787) (xy 6.122148 -40.645322) (xy 6.082414 -40.687341) (xy 6.059932 -40.705532)
			(xy 6.051109 -40.713123) (xy 6.040937 -40.734036) (xy 6.040374 -40.745664) (xy 6.040374 -40.82542)
			(xy 6.04089 -40.837056) (xy 6.051092 -40.857967) (xy 6.059932 -40.865552) (xy 6.082412 -40.883747)
			(xy 6.122147 -40.925766) (xy 6.155087 -40.9733) (xy 6.180476 -41.025261) (xy 6.197733 -41.080457)
			(xy 6.206463 -41.137626) (xy 6.206998 -41.166542) (xy 6.206512 -41.193793) (xy 6.198756 -41.247741)
			(xy 6.192586 -41.268755) (xy 15.843927 -41.268755) (xy 15.843927 -41.214245) (xy 15.851685 -41.160289)
			(xy 15.867043 -41.107986) (xy 15.889688 -41.058401) (xy 15.919159 -41.012544) (xy 15.954857 -40.971348)
			(xy 15.996054 -40.935652) (xy 16.041912 -40.906182) (xy 16.091497 -40.883538) (xy 16.1438 -40.868182)
			(xy 16.197757 -40.860426) (xy 16.225012 -40.859964) (xy 16.253751 -40.86049) (xy 16.310578 -40.869114)
			(xy 16.365468 -40.886164) (xy 16.41718 -40.911254) (xy 16.464543 -40.943818) (xy 16.48587 -40.963088)
			(xy 16.492728 -40.969692) (xy 16.510762 -40.976804) (xy 16.599662 -40.976804) (xy 16.617696 -40.969692)
			(xy 16.624554 -40.963088) (xy 16.645883 -40.94382) (xy 16.693244 -40.911251) (xy 16.744955 -40.886157)
			(xy 16.799845 -40.869106) (xy 16.856673 -40.860484) (xy 16.885412 -40.859964) (xy 16.912661 -40.860507)
			(xy 16.966603 -40.868264) (xy 17.018892 -40.883619) (xy 17.068464 -40.90626) (xy 17.11431 -40.935724)
			(xy 17.155496 -40.971413) (xy 17.191183 -41.0126) (xy 17.220646 -41.058446) (xy 17.243285 -41.108019)
			(xy 17.258638 -41.160309) (xy 17.266394 -41.214251) (xy 17.266394 -41.268749) (xy 17.258638 -41.322691)
			(xy 17.243285 -41.374981) (xy 17.220646 -41.424554) (xy 17.191183 -41.4704) (xy 17.155496 -41.511587)
			(xy 17.11431 -41.547276) (xy 17.068464 -41.57674) (xy 17.018892 -41.599381) (xy 16.966603 -41.614736)
			(xy 16.912661 -41.622493) (xy 16.885412 -41.62298) (xy 16.856674 -41.622428) (xy 16.799849 -41.613809)
			(xy 16.74496 -41.596764) (xy 16.693248 -41.57168) (xy 16.645883 -41.539123) (xy 16.624554 -41.519856)
			(xy 16.617696 -41.513252) (xy 16.599662 -41.50614) (xy 16.510762 -41.50614) (xy 16.492728 -41.513252)
			(xy 16.48587 -41.519856) (xy 16.464537 -41.53912) (xy 16.417177 -41.571687) (xy 16.365467 -41.596781)
			(xy 16.310577 -41.613834) (xy 16.253751 -41.622458) (xy 16.225012 -41.62298) (xy 16.197757 -41.622574)
			(xy 16.1438 -41.614818) (xy 16.091497 -41.599462) (xy 16.041912 -41.576818) (xy 15.996054 -41.547348)
			(xy 15.954857 -41.511652) (xy 15.919159 -41.470456) (xy 15.889688 -41.424599) (xy 15.867043 -41.375014)
			(xy 15.851685 -41.322711) (xy 15.843927 -41.268755) (xy 6.192586 -41.268755) (xy 6.183401 -41.300036)
			(xy 6.160759 -41.349613) (xy 6.131293 -41.395463) (xy 6.095602 -41.436654) (xy 6.054411 -41.472345)
			(xy 6.008561 -41.501811) (xy 5.958984 -41.524453) (xy 5.906689 -41.539808) (xy 5.852741 -41.547564)
			(xy 5.798239 -41.547564) (xy 5.744291 -41.539808) (xy 5.691996 -41.524453) (xy 5.642419 -41.501811)
			(xy 5.596569 -41.472345) (xy 5.555378 -41.436654) (xy 5.519687 -41.395463) (xy 5.490221 -41.349613)
			(xy 5.467579 -41.300036) (xy 5.452224 -41.247741) (xy 5.444468 -41.193793) (xy 5.443982 -41.166542)
			(xy 3.166872 -41.166542) (xy 3.166386 -41.193793) (xy 3.15863 -41.247741) (xy 3.143275 -41.300036)
			(xy 3.120633 -41.349613) (xy 3.091167 -41.395463) (xy 3.055476 -41.436654) (xy 3.014285 -41.472345)
			(xy 2.968435 -41.501811) (xy 2.918858 -41.524453) (xy 2.866563 -41.539808) (xy 2.812615 -41.547564)
			(xy 2.758113 -41.547564) (xy 2.704165 -41.539808) (xy 2.65187 -41.524453) (xy 2.602293 -41.501811)
			(xy 2.556443 -41.472345) (xy 2.515252 -41.436654) (xy 2.479561 -41.395463) (xy 2.450095 -41.349613)
			(xy 2.427453 -41.300036) (xy 2.412098 -41.247741) (xy 2.404342 -41.193793) (xy 2.403856 -41.166542)
			(xy 0.715772 -41.166542) (xy 0.715772 -42.250614) (xy 2.72872 -42.250614) (xy 2.732791 -42.194992)
			(xy 2.744917 -42.140555) (xy 2.76484 -42.088464) (xy 2.792136 -42.039829) (xy 2.826222 -41.995686)
			(xy 2.866371 -41.956977) (xy 2.911729 -41.924526) (xy 2.961329 -41.899025) (xy 3.014113 -41.881018)
			(xy 3.068956 -41.870888) (xy 3.12469 -41.868851) (xy 3.180127 -41.874951) (xy 3.234084 -41.889057)
			(xy 3.285413 -41.910869) (xy 3.333019 -41.939923) (xy 3.375887 -41.975598) (xy 3.413104 -42.017135)
			(xy 3.443877 -42.063648) (xy 3.467549 -42.114145) (xy 3.483617 -42.167552) (xy 3.491737 -42.222728)
			(xy 3.492246 -42.250614) (xy 3.491737 -42.2785) (xy 3.483617 -42.333676) (xy 3.467549 -42.387083)
			(xy 3.460557 -42.401998) (xy 4.015484 -42.401998) (xy 4.019555 -42.346376) (xy 4.031681 -42.291939)
			(xy 4.051604 -42.239848) (xy 4.0789 -42.191213) (xy 4.112986 -42.14707) (xy 4.153135 -42.108361)
			(xy 4.198493 -42.07591) (xy 4.248093 -42.050409) (xy 4.300877 -42.032402) (xy 4.35572 -42.022272)
			(xy 4.411454 -42.020235) (xy 4.466891 -42.026335) (xy 4.520848 -42.040441) (xy 4.572177 -42.062253)
			(xy 4.619783 -42.091307) (xy 4.662651 -42.126982) (xy 4.699868 -42.168519) (xy 4.730641 -42.215032)
			(xy 4.754313 -42.265529) (xy 4.770381 -42.318936) (xy 4.774531 -42.347134) (xy 5.291072 -42.347134)
			(xy 5.295143 -42.291512) (xy 5.307269 -42.237075) (xy 5.327192 -42.184984) (xy 5.354488 -42.136349)
			(xy 5.388574 -42.092206) (xy 5.428723 -42.053497) (xy 5.474081 -42.021046) (xy 5.523681 -41.995545)
			(xy 5.576465 -41.977538) (xy 5.631308 -41.967408) (xy 5.687042 -41.965371) (xy 5.742479 -41.971471)
			(xy 5.796436 -41.985577) (xy 5.847765 -42.007389) (xy 5.895371 -42.036443) (xy 5.938239 -42.072118)
			(xy 5.975456 -42.113655) (xy 6.006229 -42.160168) (xy 6.029901 -42.210665) (xy 6.045969 -42.264072)
			(xy 6.054089 -42.319248) (xy 6.054598 -42.347134) (xy 6.054089 -42.37502) (xy 6.045969 -42.430196)
			(xy 6.029901 -42.483603) (xy 6.006229 -42.5341) (xy 5.975456 -42.580613) (xy 5.938239 -42.62215)
			(xy 5.895371 -42.657825) (xy 5.847765 -42.686879) (xy 5.796436 -42.708691) (xy 5.742479 -42.722797)
			(xy 5.687042 -42.728897) (xy 5.631308 -42.72686) (xy 5.576465 -42.71673) (xy 5.523681 -42.698723)
			(xy 5.474081 -42.673222) (xy 5.428723 -42.640771) (xy 5.388574 -42.602062) (xy 5.354488 -42.557919)
			(xy 5.327192 -42.509284) (xy 5.307269 -42.457193) (xy 5.295143 -42.402756) (xy 5.291072 -42.347134)
			(xy 4.774531 -42.347134) (xy 4.778501 -42.374112) (xy 4.77901 -42.401998) (xy 4.778501 -42.429884)
			(xy 4.770381 -42.48506) (xy 4.754313 -42.538467) (xy 4.730641 -42.588964) (xy 4.699868 -42.635477)
			(xy 4.662651 -42.677014) (xy 4.619783 -42.712689) (xy 4.572177 -42.741743) (xy 4.520848 -42.763555)
			(xy 4.466891 -42.777661) (xy 4.411454 -42.783761) (xy 4.35572 -42.781724) (xy 4.300877 -42.771594)
			(xy 4.248093 -42.753587) (xy 4.198493 -42.728086) (xy 4.153135 -42.695635) (xy 4.112986 -42.656926)
			(xy 4.0789 -42.612783) (xy 4.051604 -42.564148) (xy 4.031681 -42.512057) (xy 4.019555 -42.45762)
			(xy 4.015484 -42.401998) (xy 3.460557 -42.401998) (xy 3.443877 -42.43758) (xy 3.413104 -42.484093)
			(xy 3.375887 -42.52563) (xy 3.333019 -42.561305) (xy 3.285413 -42.590359) (xy 3.234084 -42.612171)
			(xy 3.180127 -42.626277) (xy 3.12469 -42.632377) (xy 3.068956 -42.63034) (xy 3.014113 -42.62021)
			(xy 2.961329 -42.602203) (xy 2.911729 -42.576702) (xy 2.866371 -42.544251) (xy 2.826222 -42.505542)
			(xy 2.792136 -42.461399) (xy 2.76484 -42.412764) (xy 2.744917 -42.360673) (xy 2.732791 -42.306236)
			(xy 2.72872 -42.250614) (xy 0.715772 -42.250614) (xy 0.715772 -43.305222) (xy 18.307304 -43.305222)
			(xy 18.307782 -43.277852) (xy 18.315597 -43.223674) (xy 18.331083 -43.171171) (xy 18.353922 -43.121424)
			(xy 18.383644 -43.075456) (xy 18.401284 -43.054524) (xy 18.401538 -43.05427) (xy 18.407106 -43.047171)
			(xy 18.413363 -43.030264) (xy 18.41373 -43.02125) (xy 18.41373 -42.954194) (xy 18.413369 -42.945178)
			(xy 18.407123 -42.928261) (xy 18.401538 -42.921174) (xy 18.401284 -42.921174) (xy 18.401284 -42.92092)
			(xy 18.383638 -42.899993) (xy 18.353928 -42.854019) (xy 18.331094 -42.80427) (xy 18.315604 -42.751768)
			(xy 18.307777 -42.697591) (xy 18.307304 -42.670222) (xy 18.30784 -42.641484) (xy 18.316459 -42.584657)
			(xy 18.333507 -42.529766) (xy 18.358595 -42.478054) (xy 18.391158 -42.430691) (xy 18.410428 -42.409364)
			(xy 18.417032 -42.402506) (xy 18.424144 -42.384472) (xy 18.424144 -42.295572) (xy 18.417032 -42.277538)
			(xy 18.410428 -42.27068) (xy 18.391179 -42.249334) (xy 18.358613 -42.201975) (xy 18.333519 -42.150267)
			(xy 18.316468 -42.095379) (xy 18.307843 -42.038554) (xy 18.30784 -41.981078) (xy 18.31646 -41.924253)
			(xy 18.333508 -41.869363) (xy 18.358596 -41.817653) (xy 18.391159 -41.770291) (xy 18.410428 -41.748964)
			(xy 18.417032 -41.742106) (xy 18.424144 -41.724072) (xy 18.424144 -41.635172) (xy 18.417032 -41.617138)
			(xy 18.410428 -41.61028) (xy 18.391166 -41.588945) (xy 18.358599 -41.541585) (xy 18.333505 -41.489876)
			(xy 18.316452 -41.434987) (xy 18.307827 -41.37816) (xy 18.307304 -41.349422) (xy 18.30779 -41.322171)
			(xy 18.315546 -41.268223) (xy 18.330901 -41.215928) (xy 18.353543 -41.166351) (xy 18.383009 -41.120501)
			(xy 18.4187 -41.07931) (xy 18.459891 -41.043619) (xy 18.505741 -41.014153) (xy 18.555318 -40.991511)
			(xy 18.607613 -40.976156) (xy 18.661561 -40.9684) (xy 18.716063 -40.9684) (xy 18.739184 -40.971724)
			(xy 26.594052 -40.971724) (xy 26.598123 -40.916102) (xy 26.610249 -40.861665) (xy 26.630172 -40.809574)
			(xy 26.657468 -40.760939) (xy 26.691554 -40.716796) (xy 26.731703 -40.678087) (xy 26.777061 -40.645636)
			(xy 26.826661 -40.620135) (xy 26.879445 -40.602128) (xy 26.934288 -40.591998) (xy 26.990022 -40.589961)
			(xy 27.045459 -40.596061) (xy 27.099416 -40.610167) (xy 27.150745 -40.631979) (xy 27.198351 -40.661033)
			(xy 27.241219 -40.696708) (xy 27.278436 -40.738245) (xy 27.309209 -40.784758) (xy 27.332881 -40.835255)
			(xy 27.348949 -40.888662) (xy 27.357069 -40.943838) (xy 27.357578 -40.971724) (xy 27.357069 -40.99961)
			(xy 27.348949 -41.054786) (xy 27.332881 -41.108193) (xy 27.309209 -41.15869) (xy 27.278436 -41.205203)
			(xy 27.241219 -41.24674) (xy 27.198351 -41.282415) (xy 27.150745 -41.311469) (xy 27.099416 -41.333281)
			(xy 27.045459 -41.347387) (xy 26.990022 -41.353487) (xy 26.934288 -41.35145) (xy 26.879445 -41.34132)
			(xy 26.826661 -41.323313) (xy 26.777061 -41.297812) (xy 26.731703 -41.265361) (xy 26.691554 -41.226652)
			(xy 26.657468 -41.182509) (xy 26.630172 -41.133874) (xy 26.610249 -41.081783) (xy 26.598123 -41.027346)
			(xy 26.594052 -40.971724) (xy 18.739184 -40.971724) (xy 18.770011 -40.976156) (xy 18.822306 -40.991511)
			(xy 18.871883 -41.014153) (xy 18.917733 -41.043619) (xy 18.958924 -41.07931) (xy 18.994615 -41.120501)
			(xy 19.024081 -41.166351) (xy 19.046723 -41.215928) (xy 19.062078 -41.268223) (xy 19.069834 -41.322171)
			(xy 19.07032 -41.349422) (xy 19.069804 -41.378161) (xy 19.061179 -41.434989) (xy 19.044127 -41.489879)
			(xy 19.019033 -41.541591) (xy 18.986467 -41.588953) (xy 18.967196 -41.61028) (xy 18.960592 -41.617138)
			(xy 18.95348 -41.635172) (xy 18.95348 -41.724072) (xy 18.960592 -41.742106) (xy 18.967196 -41.748964)
			(xy 18.986488 -41.770272) (xy 19.019051 -41.817639) (xy 19.04414 -41.869353) (xy 19.061187 -41.924247)
			(xy 19.069807 -41.981076) (xy 19.069805 -42.038556) (xy 19.06118 -42.095385) (xy 19.044128 -42.150276)
			(xy 19.019034 -42.201989) (xy 18.986468 -42.249353) (xy 18.967196 -42.27068) (xy 18.960592 -42.277538)
			(xy 18.95348 -42.295572) (xy 18.95348 -42.384472) (xy 18.960592 -42.402506) (xy 18.967196 -42.409364)
			(xy 18.986466 -42.430692) (xy 19.019035 -42.478053) (xy 19.044128 -42.529764) (xy 19.061179 -42.584655)
			(xy 19.0698 -42.641483) (xy 19.07032 -42.670222) (xy 19.069886 -42.697594) (xy 19.062064 -42.751775)
			(xy 19.046568 -42.804279) (xy 19.02601 -42.849038) (xy 20.892006 -42.849038) (xy 20.896077 -42.793416)
			(xy 20.908203 -42.738979) (xy 20.928126 -42.686888) (xy 20.955422 -42.638253) (xy 20.989508 -42.59411)
			(xy 21.029657 -42.555401) (xy 21.075015 -42.52295) (xy 21.124615 -42.497449) (xy 21.177399 -42.479442)
			(xy 21.232242 -42.469312) (xy 21.287976 -42.467275) (xy 21.343413 -42.473375) (xy 21.39737 -42.487481)
			(xy 21.448699 -42.509293) (xy 21.496305 -42.538347) (xy 21.539173 -42.574022) (xy 21.57639 -42.615559)
			(xy 21.607163 -42.662072) (xy 21.630835 -42.712569) (xy 21.646903 -42.765976) (xy 21.655023 -42.821152)
			(xy 21.655384 -42.84091) (xy 26.933142 -42.84091) (xy 26.937213 -42.785288) (xy 26.949339 -42.730851)
			(xy 26.969262 -42.67876) (xy 26.996558 -42.630125) (xy 27.030644 -42.585982) (xy 27.070793 -42.547273)
			(xy 27.116151 -42.514822) (xy 27.165751 -42.489321) (xy 27.218535 -42.471314) (xy 27.273378 -42.461184)
			(xy 27.329112 -42.459147) (xy 27.384549 -42.465247) (xy 27.438506 -42.479353) (xy 27.489835 -42.501165)
			(xy 27.537441 -42.530219) (xy 27.580309 -42.565894) (xy 27.617526 -42.607431) (xy 27.648299 -42.653944)
			(xy 27.671971 -42.704441) (xy 27.688039 -42.757848) (xy 27.696159 -42.813024) (xy 27.696668 -42.84091)
			(xy 27.696159 -42.868796) (xy 27.688039 -42.923972) (xy 27.671971 -42.977379) (xy 27.648299 -43.027876)
			(xy 27.617526 -43.074389) (xy 27.580309 -43.115926) (xy 27.537441 -43.151601) (xy 27.489835 -43.180655)
			(xy 27.438506 -43.202467) (xy 27.384549 -43.216573) (xy 27.329112 -43.222673) (xy 27.273378 -43.220636)
			(xy 27.218535 -43.210506) (xy 27.165751 -43.192499) (xy 27.116151 -43.166998) (xy 27.070793 -43.134547)
			(xy 27.030644 -43.095838) (xy 26.996558 -43.051695) (xy 26.969262 -43.00306) (xy 26.949339 -42.950969)
			(xy 26.937213 -42.896532) (xy 26.933142 -42.84091) (xy 21.655384 -42.84091) (xy 21.655532 -42.849038)
			(xy 21.655023 -42.876924) (xy 21.646903 -42.9321) (xy 21.630835 -42.985507) (xy 21.607163 -43.036004)
			(xy 21.57639 -43.082517) (xy 21.539173 -43.124054) (xy 21.496305 -43.159729) (xy 21.448699 -43.188783)
			(xy 21.39737 -43.210595) (xy 21.343413 -43.224701) (xy 21.287976 -43.230801) (xy 21.232242 -43.228764)
			(xy 21.177399 -43.218634) (xy 21.124615 -43.200627) (xy 21.075015 -43.175126) (xy 21.029657 -43.142675)
			(xy 20.989508 -43.103966) (xy 20.955422 -43.059823) (xy 20.928126 -43.011188) (xy 20.908203 -42.959097)
			(xy 20.896077 -42.90466) (xy 20.892006 -42.849038) (xy 19.02601 -42.849038) (xy 19.023719 -42.854026)
			(xy 18.993986 -42.89999) (xy 18.97634 -42.92092) (xy 18.976086 -42.921174) (xy 18.970503 -42.928263)
			(xy 18.964254 -42.945178) (xy 18.963894 -42.954194) (xy 18.963894 -43.02125) (xy 18.964277 -43.030264)
			(xy 18.970507 -43.047181) (xy 18.976086 -43.05427) (xy 18.97634 -43.05427) (xy 18.97634 -43.054524)
			(xy 18.993964 -43.075468) (xy 19.023676 -43.121438) (xy 19.046515 -43.171183) (xy 19.06201 -43.223681)
			(xy 19.069843 -43.277854) (xy 19.07032 -43.305222) (xy 19.069834 -43.332473) (xy 19.062078 -43.386421)
			(xy 19.046723 -43.438716) (xy 19.024081 -43.488293) (xy 18.994615 -43.534143) (xy 18.958924 -43.575334)
			(xy 18.917733 -43.611025) (xy 18.871883 -43.640491) (xy 18.822306 -43.663133) (xy 18.770011 -43.678488)
			(xy 18.716063 -43.686244) (xy 18.661561 -43.686244) (xy 18.607613 -43.678488) (xy 18.555318 -43.663133)
			(xy 18.505741 -43.640491) (xy 18.459891 -43.611025) (xy 18.4187 -43.575334) (xy 18.383009 -43.534143)
			(xy 18.353543 -43.488293) (xy 18.330901 -43.438716) (xy 18.315546 -43.386421) (xy 18.30779 -43.332473)
			(xy 18.307304 -43.305222) (xy 0.715772 -43.305222) (xy 0.715772 -43.73626) (xy 20.213064 -43.73626)
			(xy 20.217135 -43.680638) (xy 20.229261 -43.626201) (xy 20.249184 -43.57411) (xy 20.27648 -43.525475)
			(xy 20.310566 -43.481332) (xy 20.350715 -43.442623) (xy 20.396073 -43.410172) (xy 20.445673 -43.384671)
			(xy 20.498457 -43.366664) (xy 20.5533 -43.356534) (xy 20.609034 -43.354497) (xy 20.664471 -43.360597)
			(xy 20.718428 -43.374703) (xy 20.769757 -43.396515) (xy 20.817363 -43.425569) (xy 20.860231 -43.461244)
			(xy 20.897448 -43.502781) (xy 20.928221 -43.549294) (xy 20.951893 -43.599791) (xy 20.967961 -43.653198)
			(xy 20.976081 -43.708374) (xy 20.97659 -43.73626) (xy 20.976081 -43.764146) (xy 20.967961 -43.819322)
			(xy 20.956652 -43.85691) (xy 24.719786 -43.85691) (xy 24.723857 -43.801288) (xy 24.735983 -43.746851)
			(xy 24.755906 -43.69476) (xy 24.783202 -43.646125) (xy 24.817288 -43.601982) (xy 24.857437 -43.563273)
			(xy 24.902795 -43.530822) (xy 24.952395 -43.505321) (xy 25.005179 -43.487314) (xy 25.060022 -43.477184)
			(xy 25.115756 -43.475147) (xy 25.171193 -43.481247) (xy 25.22515 -43.495353) (xy 25.276479 -43.517165)
			(xy 25.324085 -43.546219) (xy 25.366953 -43.581894) (xy 25.40417 -43.623431) (xy 25.434943 -43.669944)
			(xy 25.458615 -43.720441) (xy 25.474683 -43.773848) (xy 25.482803 -43.829024) (xy 25.483312 -43.85691)
			(xy 25.482803 -43.884796) (xy 25.474683 -43.939972) (xy 25.458615 -43.993379) (xy 25.434943 -44.043876)
			(xy 25.40417 -44.090389) (xy 25.366953 -44.131926) (xy 25.324085 -44.167601) (xy 25.276479 -44.196655)
			(xy 25.22515 -44.218467) (xy 25.171193 -44.232573) (xy 25.115756 -44.238673) (xy 25.060022 -44.236636)
			(xy 25.005179 -44.226506) (xy 24.952395 -44.208499) (xy 24.902795 -44.182998) (xy 24.857437 -44.150547)
			(xy 24.817288 -44.111838) (xy 24.783202 -44.067695) (xy 24.755906 -44.01906) (xy 24.735983 -43.966969)
			(xy 24.723857 -43.912532) (xy 24.719786 -43.85691) (xy 20.956652 -43.85691) (xy 20.951893 -43.872729)
			(xy 20.928221 -43.923226) (xy 20.897448 -43.969739) (xy 20.860231 -44.011276) (xy 20.817363 -44.046951)
			(xy 20.769757 -44.076005) (xy 20.718428 -44.097817) (xy 20.664471 -44.111923) (xy 20.609034 -44.118023)
			(xy 20.5533 -44.115986) (xy 20.498457 -44.105856) (xy 20.445673 -44.087849) (xy 20.396073 -44.062348)
			(xy 20.350715 -44.029897) (xy 20.310566 -43.991188) (xy 20.27648 -43.947045) (xy 20.249184 -43.89841)
			(xy 20.229261 -43.846319) (xy 20.217135 -43.791882) (xy 20.213064 -43.73626) (xy 0.715772 -43.73626)
			(xy 0.715772 -44.689522) (xy 3.862068 -44.689522) (xy 3.866139 -44.6339) (xy 3.878265 -44.579463)
			(xy 3.898188 -44.527372) (xy 3.925484 -44.478737) (xy 3.95957 -44.434594) (xy 3.999719 -44.395885)
			(xy 4.045077 -44.363434) (xy 4.094677 -44.337933) (xy 4.147461 -44.319926) (xy 4.202304 -44.309796)
			(xy 4.258038 -44.307759) (xy 4.313475 -44.313859) (xy 4.367432 -44.327965) (xy 4.418761 -44.349777)
			(xy 4.466367 -44.378831) (xy 4.509235 -44.414506) (xy 4.546452 -44.456043) (xy 4.577225 -44.502556)
			(xy 4.600897 -44.553053) (xy 4.616965 -44.60646) (xy 4.625085 -44.661636) (xy 4.625594 -44.689522)
			(xy 4.625085 -44.717408) (xy 4.616965 -44.772584) (xy 4.600897 -44.825991) (xy 4.577225 -44.876488)
			(xy 4.546452 -44.923001) (xy 4.509235 -44.964538) (xy 4.466367 -45.000213) (xy 4.418761 -45.029267)
			(xy 4.367432 -45.051079) (xy 4.313475 -45.065185) (xy 4.258038 -45.071285) (xy 4.202304 -45.069248)
			(xy 4.147461 -45.059118) (xy 4.094677 -45.041111) (xy 4.045077 -45.01561) (xy 3.999719 -44.983159)
			(xy 3.95957 -44.94445) (xy 3.925484 -44.900307) (xy 3.898188 -44.851672) (xy 3.878265 -44.799581)
			(xy 3.866139 -44.745144) (xy 3.862068 -44.689522) (xy 0.715772 -44.689522) (xy 0.715772 -45.071792)
			(xy 6.365492 -45.071792) (xy 6.369563 -45.01617) (xy 6.381689 -44.961733) (xy 6.401612 -44.909642)
			(xy 6.428908 -44.861007) (xy 6.462994 -44.816864) (xy 6.503143 -44.778155) (xy 6.548501 -44.745704)
			(xy 6.598101 -44.720203) (xy 6.650885 -44.702196) (xy 6.705728 -44.692066) (xy 6.761462 -44.690029)
			(xy 6.816899 -44.696129) (xy 6.870856 -44.710235) (xy 6.922185 -44.732047) (xy 6.969791 -44.761101)
			(xy 7.012659 -44.796776) (xy 7.049876 -44.838313) (xy 7.080649 -44.884826) (xy 7.104321 -44.935323)
			(xy 7.120389 -44.98873) (xy 7.128509 -45.043906) (xy 7.129018 -45.071792) (xy 7.128509 -45.099678)
			(xy 7.126333 -45.114464) (xy 20.06549 -45.114464) (xy 20.069561 -45.058842) (xy 20.081687 -45.004405)
			(xy 20.10161 -44.952314) (xy 20.128906 -44.903679) (xy 20.162992 -44.859536) (xy 20.203141 -44.820827)
			(xy 20.248499 -44.788376) (xy 20.298099 -44.762875) (xy 20.350883 -44.744868) (xy 20.405726 -44.734738)
			(xy 20.46146 -44.732701) (xy 20.516897 -44.738801) (xy 20.570854 -44.752907) (xy 20.622183 -44.774719)
			(xy 20.669789 -44.803773) (xy 20.712657 -44.839448) (xy 20.742639 -44.87291) (xy 26.933142 -44.87291)
			(xy 26.937213 -44.817288) (xy 26.949339 -44.762851) (xy 26.969262 -44.71076) (xy 26.996558 -44.662125)
			(xy 27.030644 -44.617982) (xy 27.070793 -44.579273) (xy 27.116151 -44.546822) (xy 27.165751 -44.521321)
			(xy 27.218535 -44.503314) (xy 27.273378 -44.493184) (xy 27.329112 -44.491147) (xy 27.384549 -44.497247)
			(xy 27.438506 -44.511353) (xy 27.489835 -44.533165) (xy 27.537441 -44.562219) (xy 27.580309 -44.597894)
			(xy 27.617526 -44.639431) (xy 27.648299 -44.685944) (xy 27.671971 -44.736441) (xy 27.688039 -44.789848)
			(xy 27.696159 -44.845024) (xy 27.696668 -44.87291) (xy 27.696159 -44.900796) (xy 27.688039 -44.955972)
			(xy 27.671971 -45.009379) (xy 27.648299 -45.059876) (xy 27.617526 -45.106389) (xy 27.580309 -45.147926)
			(xy 27.537441 -45.183601) (xy 27.489835 -45.212655) (xy 27.438506 -45.234467) (xy 27.384549 -45.248573)
			(xy 27.329112 -45.254673) (xy 27.273378 -45.252636) (xy 27.218535 -45.242506) (xy 27.165751 -45.224499)
			(xy 27.116151 -45.198998) (xy 27.070793 -45.166547) (xy 27.030644 -45.127838) (xy 26.996558 -45.083695)
			(xy 26.969262 -45.03506) (xy 26.949339 -44.982969) (xy 26.937213 -44.928532) (xy 26.933142 -44.87291)
			(xy 20.742639 -44.87291) (xy 20.749874 -44.880985) (xy 20.780647 -44.927498) (xy 20.804319 -44.977995)
			(xy 20.820387 -45.031402) (xy 20.828507 -45.086578) (xy 20.829016 -45.114464) (xy 20.828507 -45.14235)
			(xy 20.820387 -45.197526) (xy 20.804319 -45.250933) (xy 20.780647 -45.30143) (xy 20.749874 -45.347943)
			(xy 20.744232 -45.35424) (xy 24.703784 -45.35424) (xy 24.707855 -45.298618) (xy 24.719981 -45.244181)
			(xy 24.739904 -45.19209) (xy 24.7672 -45.143455) (xy 24.801286 -45.099312) (xy 24.841435 -45.060603)
			(xy 24.886793 -45.028152) (xy 24.936393 -45.002651) (xy 24.989177 -44.984644) (xy 25.04402 -44.974514)
			(xy 25.099754 -44.972477) (xy 25.155191 -44.978577) (xy 25.209148 -44.992683) (xy 25.260477 -45.014495)
			(xy 25.308083 -45.043549) (xy 25.350951 -45.079224) (xy 25.388168 -45.120761) (xy 25.418941 -45.167274)
			(xy 25.442613 -45.217771) (xy 25.458681 -45.271178) (xy 25.466801 -45.326354) (xy 25.46731 -45.35424)
			(xy 25.466801 -45.382126) (xy 25.458681 -45.437302) (xy 25.442613 -45.490709) (xy 25.418941 -45.541206)
			(xy 25.388168 -45.587719) (xy 25.350951 -45.629256) (xy 25.308083 -45.664931) (xy 25.260477 -45.693985)
			(xy 25.209148 -45.715797) (xy 25.155191 -45.729903) (xy 25.099754 -45.736003) (xy 25.04402 -45.733966)
			(xy 24.989177 -45.723836) (xy 24.936393 -45.705829) (xy 24.886793 -45.680328) (xy 24.841435 -45.647877)
			(xy 24.801286 -45.609168) (xy 24.7672 -45.565025) (xy 24.739904 -45.51639) (xy 24.719981 -45.464299)
			(xy 24.707855 -45.409862) (xy 24.703784 -45.35424) (xy 20.744232 -45.35424) (xy 20.712657 -45.38948)
			(xy 20.669789 -45.425155) (xy 20.622183 -45.454209) (xy 20.570854 -45.476021) (xy 20.516897 -45.490127)
			(xy 20.46146 -45.496227) (xy 20.405726 -45.49419) (xy 20.350883 -45.48406) (xy 20.298099 -45.466053)
			(xy 20.248499 -45.440552) (xy 20.203141 -45.408101) (xy 20.162992 -45.369392) (xy 20.128906 -45.325249)
			(xy 20.10161 -45.276614) (xy 20.081687 -45.224523) (xy 20.069561 -45.170086) (xy 20.06549 -45.114464)
			(xy 7.126333 -45.114464) (xy 7.120389 -45.154854) (xy 7.104321 -45.208261) (xy 7.080649 -45.258758)
			(xy 7.049876 -45.305271) (xy 7.012659 -45.346808) (xy 6.969791 -45.382483) (xy 6.922185 -45.411537)
			(xy 6.870856 -45.433349) (xy 6.816899 -45.447455) (xy 6.761462 -45.453555) (xy 6.705728 -45.451518)
			(xy 6.650885 -45.441388) (xy 6.598101 -45.423381) (xy 6.548501 -45.39788) (xy 6.503143 -45.365429)
			(xy 6.462994 -45.32672) (xy 6.428908 -45.282577) (xy 6.401612 -45.233942) (xy 6.381689 -45.181851)
			(xy 6.369563 -45.127414) (xy 6.365492 -45.071792) (xy 0.715772 -45.071792) (xy 0.715772 -45.851318)
			(xy 7.87476 -45.851318) (xy 7.878831 -45.795696) (xy 7.890957 -45.741259) (xy 7.91088 -45.689168)
			(xy 7.938176 -45.640533) (xy 7.972262 -45.59639) (xy 8.012411 -45.557681) (xy 8.057769 -45.52523)
			(xy 8.107369 -45.499729) (xy 8.160153 -45.481722) (xy 8.214996 -45.471592) (xy 8.27073 -45.469555)
			(xy 8.326167 -45.475655) (xy 8.380124 -45.489761) (xy 8.431453 -45.511573) (xy 8.479059 -45.540627)
			(xy 8.521927 -45.576302) (xy 8.559144 -45.617839) (xy 8.589917 -45.664352) (xy 8.613589 -45.714849)
			(xy 8.629657 -45.768256) (xy 8.637777 -45.823432) (xy 8.638286 -45.851318) (xy 8.637777 -45.879204)
			(xy 8.630854 -45.926248) (xy 11.930886 -45.926248) (xy 11.934957 -45.870626) (xy 11.947083 -45.816189)
			(xy 11.967006 -45.764098) (xy 11.994302 -45.715463) (xy 12.028388 -45.67132) (xy 12.068537 -45.632611)
			(xy 12.113895 -45.60016) (xy 12.163495 -45.574659) (xy 12.216279 -45.556652) (xy 12.271122 -45.546522)
			(xy 12.326856 -45.544485) (xy 12.382293 -45.550585) (xy 12.43625 -45.564691) (xy 12.487579 -45.586503)
			(xy 12.535185 -45.615557) (xy 12.578053 -45.651232) (xy 12.61527 -45.692769) (xy 12.646043 -45.739282)
			(xy 12.669715 -45.789779) (xy 12.685783 -45.843186) (xy 12.693903 -45.898362) (xy 12.694412 -45.926248)
			(xy 12.693903 -45.954134) (xy 12.685783 -46.00931) (xy 12.669715 -46.062717) (xy 12.66058 -46.082204)
			(xy 18.052542 -46.082204) (xy 18.052959 -46.054949) (xy 18.060717 -46.000994) (xy 18.076075 -45.948692)
			(xy 18.098721 -45.899109) (xy 18.128193 -45.853253) (xy 18.163892 -45.812059) (xy 18.20509 -45.776365)
			(xy 18.250949 -45.746899) (xy 18.300535 -45.724259) (xy 18.352839 -45.708907) (xy 18.406795 -45.701156)
			(xy 18.43405 -45.700696) (xy 18.460954 -45.70112) (xy 18.514226 -45.708699) (xy 18.565905 -45.723685)
			(xy 18.614967 -45.745781) (xy 18.660438 -45.774549) (xy 18.701419 -45.80942) (xy 18.737095 -45.8497)
			(xy 18.752312 -45.871892) (xy 18.759424 -45.882814) (xy 18.782284 -45.894752) (xy 18.894552 -45.89272)
			(xy 18.916904 -45.879766) (xy 18.923762 -45.86859) (xy 18.938655 -45.844969) (xy 18.974339 -45.802018)
			(xy 19.015902 -45.764726) (xy 19.062457 -45.733891) (xy 19.113009 -45.710171) (xy 19.166479 -45.694072)
			(xy 19.221724 -45.685939) (xy 19.249644 -45.685456) (xy 19.276638 -45.685892) (xy 19.330087 -45.693504)
			(xy 19.381931 -45.70857) (xy 19.431135 -45.730789) (xy 19.476718 -45.759719) (xy 19.497548 -45.776896)
			(xy 19.505676 -45.784008) (xy 19.52625 -45.790104) (xy 19.611594 -45.779182) (xy 19.62214 -45.777415)
			(xy 19.640422 -45.766355) (xy 19.6469 -45.757846) (xy 19.66226 -45.73662) (xy 19.697846 -45.698167)
			(xy 19.738362 -45.664948) (xy 19.783044 -45.637589) (xy 19.831051 -45.616605) (xy 19.881479 -45.602391)
			(xy 19.933378 -45.595214) (xy 19.959574 -45.594778) (xy 19.986827 -45.595268) (xy 20.040779 -45.603021)
			(xy 20.093078 -45.618374) (xy 20.142659 -45.641015) (xy 20.188514 -45.670481) (xy 20.229708 -45.706173)
			(xy 20.265404 -45.747365) (xy 20.294873 -45.793218) (xy 20.317516 -45.842798) (xy 20.332873 -45.895096)
			(xy 20.340631 -45.949047) (xy 20.340631 -46.003553) (xy 20.332873 -46.057504) (xy 20.317516 -46.109802)
			(xy 20.294873 -46.159382) (xy 20.265404 -46.205235) (xy 20.229708 -46.246427) (xy 20.188514 -46.282119)
			(xy 20.142659 -46.311585) (xy 20.093078 -46.334226) (xy 20.040779 -46.349579) (xy 19.986827 -46.357332)
			(xy 19.959574 -46.357794) (xy 19.932581 -46.357336) (xy 19.879133 -46.349728) (xy 19.82729 -46.334666)
			(xy 19.778085 -46.312452) (xy 19.732501 -46.283528) (xy 19.71167 -46.266354) (xy 19.703542 -46.259242)
			(xy 19.682968 -46.253146) (xy 19.597624 -46.264068) (xy 19.587085 -46.265862) (xy 19.568801 -46.276903)
			(xy 19.562318 -46.285404) (xy 19.544699 -46.3097) (xy 19.503108 -46.352962) (xy 19.479514 -46.37151)
			(xy 19.47164 -46.377352) (xy 19.461226 -46.394878) (xy 19.448018 -46.485302) (xy 19.452844 -46.504606)
			(xy 19.458686 -46.51248) (xy 19.458686 -46.512734) (xy 19.47619 -46.537477) (xy 19.503992 -46.59133)
			(xy 19.522928 -46.648903) (xy 19.530131 -46.693836) (xy 24.676354 -46.693836) (xy 24.67684 -46.666585)
			(xy 24.684596 -46.612637) (xy 24.699951 -46.560342) (xy 24.722593 -46.510765) (xy 24.752059 -46.464915)
			(xy 24.78775 -46.423724) (xy 24.828941 -46.388033) (xy 24.874791 -46.358567) (xy 24.924368 -46.335925)
			(xy 24.976663 -46.32057) (xy 25.030611 -46.312814) (xy 25.085113 -46.312814) (xy 25.139061 -46.32057)
			(xy 25.191356 -46.335925) (xy 25.240933 -46.358567) (xy 25.286783 -46.388033) (xy 25.327974 -46.423724)
			(xy 25.363665 -46.464915) (xy 25.393131 -46.510765) (xy 25.415773 -46.560342) (xy 25.431128 -46.612637)
			(xy 25.438884 -46.666585) (xy 25.43937 -46.693836) (xy 25.438901 -46.720264) (xy 25.431591 -46.772611)
			(xy 25.417117 -46.823446) (xy 25.395755 -46.871793) (xy 25.38222 -46.894496) (xy 25.381966 -46.89475)
			(xy 25.37663 -46.904768) (xy 25.374372 -46.927318) (xy 25.377648 -46.938184) (xy 25.40381 -47.01286)
			(xy 25.408168 -47.023389) (xy 25.424274 -47.039472) (xy 25.434798 -47.043848) (xy 25.435052 -47.043848)
			(xy 25.459562 -47.052914) (xy 25.506014 -47.076857) (xy 25.548766 -47.106914) (xy 25.587018 -47.142522)
			(xy 25.620054 -47.183015) (xy 25.647258 -47.227636) (xy 25.668119 -47.275552) (xy 25.682249 -47.325865)
			(xy 25.689383 -47.377636) (xy 25.689814 -47.403766) (xy 25.689328 -47.431017) (xy 25.687805 -47.441612)
			(xy 26.961844 -47.441612) (xy 26.965915 -47.38599) (xy 26.978041 -47.331553) (xy 26.997964 -47.279462)
			(xy 27.02526 -47.230827) (xy 27.059346 -47.186684) (xy 27.099495 -47.147975) (xy 27.144853 -47.115524)
			(xy 27.194453 -47.090023) (xy 27.247237 -47.072016) (xy 27.30208 -47.061886) (xy 27.357814 -47.059849)
			(xy 27.413251 -47.065949) (xy 27.467208 -47.080055) (xy 27.518537 -47.101867) (xy 27.566143 -47.130921)
			(xy 27.609011 -47.166596) (xy 27.646228 -47.208133) (xy 27.677001 -47.254646) (xy 27.700673 -47.305143)
			(xy 27.716741 -47.35855) (xy 27.724861 -47.413726) (xy 27.72537 -47.441612) (xy 27.724861 -47.469498)
			(xy 27.716741 -47.524674) (xy 27.700673 -47.578081) (xy 27.677001 -47.628578) (xy 27.646228 -47.675091)
			(xy 27.609011 -47.716628) (xy 27.566143 -47.752303) (xy 27.518537 -47.781357) (xy 27.467208 -47.803169)
			(xy 27.413251 -47.817275) (xy 27.357814 -47.823375) (xy 27.30208 -47.821338) (xy 27.247237 -47.811208)
			(xy 27.194453 -47.793201) (xy 27.144853 -47.7677) (xy 27.099495 -47.735249) (xy 27.059346 -47.69654)
			(xy 27.02526 -47.652397) (xy 26.997964 -47.603762) (xy 26.978041 -47.551671) (xy 26.965915 -47.497234)
			(xy 26.961844 -47.441612) (xy 25.687805 -47.441612) (xy 25.681572 -47.484965) (xy 25.666217 -47.53726)
			(xy 25.643575 -47.586837) (xy 25.614109 -47.632687) (xy 25.578418 -47.673878) (xy 25.537227 -47.709569)
			(xy 25.491377 -47.739035) (xy 25.4418 -47.761677) (xy 25.389505 -47.777032) (xy 25.335557 -47.784788)
			(xy 25.281055 -47.784788) (xy 25.227107 -47.777032) (xy 25.174812 -47.761677) (xy 25.125235 -47.739035)
			(xy 25.079385 -47.709569) (xy 25.038194 -47.673878) (xy 25.002503 -47.632687) (xy 24.973037 -47.586837)
			(xy 24.950395 -47.53726) (xy 24.93504 -47.484965) (xy 24.927284 -47.431017) (xy 24.926798 -47.403766)
			(xy 24.927272 -47.377338) (xy 24.934581 -47.324991) (xy 24.949054 -47.274156) (xy 24.970413 -47.225809)
			(xy 24.983948 -47.203106) (xy 24.984202 -47.202852) (xy 24.989537 -47.192833) (xy 24.991798 -47.170283)
			(xy 24.98852 -47.159418) (xy 24.962358 -47.084742) (xy 24.958014 -47.074206) (xy 24.941898 -47.058126)
			(xy 24.93137 -47.053754) (xy 24.931116 -47.053754) (xy 24.9066 -47.044704) (xy 24.860148 -47.020757)
			(xy 24.817398 -46.990698) (xy 24.779147 -46.955088) (xy 24.746112 -46.914592) (xy 24.718909 -46.869969)
			(xy 24.698048 -46.822053) (xy 24.683919 -46.771738) (xy 24.676785 -46.719966) (xy 24.676354 -46.693836)
			(xy 19.530131 -46.693836) (xy 19.532521 -46.708745) (xy 19.533108 -46.739048) (xy 19.532667 -46.7663)
			(xy 19.524904 -46.82025) (xy 19.509543 -46.872545) (xy 19.486896 -46.922123) (xy 19.457425 -46.967973)
			(xy 19.421729 -47.009163) (xy 19.380534 -47.044853) (xy 19.334681 -47.074319) (xy 19.2851 -47.096959)
			(xy 19.232803 -47.112314) (xy 19.178852 -47.12007) (xy 19.1516 -47.120556) (xy 19.125567 -47.120101)
			(xy 19.073984 -47.113015) (xy 19.023843 -47.098987) (xy 18.976072 -47.078278) (xy 18.931557 -47.051271)
			(xy 18.911062 -47.035212) (xy 18.903294 -47.029488) (xy 18.884892 -47.023736) (xy 18.875248 -47.024036)
			(xy 18.795492 -47.030386) (xy 18.777712 -47.039022) (xy 18.771362 -47.046388) (xy 18.753173 -47.066026)
			(xy 18.712267 -47.100549) (xy 18.66694 -47.129019) (xy 18.61808 -47.150878) (xy 18.566645 -47.165697)
			(xy 18.513645 -47.173186) (xy 18.486882 -47.173642) (xy 18.459632 -47.173139) (xy 18.405687 -47.165381)
			(xy 18.353394 -47.150025) (xy 18.303819 -47.127385) (xy 18.25797 -47.09792) (xy 18.216781 -47.06223)
			(xy 18.18109 -47.021042) (xy 18.151623 -46.975195) (xy 18.12898 -46.925621) (xy 18.113622 -46.873329)
			(xy 18.105862 -46.819384) (xy 18.105374 -46.792134) (xy 18.105905 -46.76336) (xy 18.114556 -46.706467)
			(xy 18.131651 -46.651517) (xy 18.156803 -46.599756) (xy 18.189441 -46.55236) (xy 18.208752 -46.531022)
			(xy 18.216118 -46.523148) (xy 18.22323 -46.503336) (xy 18.215864 -46.40707) (xy 18.205958 -46.388274)
			(xy 18.197576 -46.38167) (xy 18.175382 -46.363456) (xy 18.136175 -46.321517) (xy 18.103692 -46.274179)
			(xy 18.078665 -46.222509) (xy 18.06166 -46.167674) (xy 18.05306 -46.11091) (xy 18.052542 -46.082204)
			(xy 12.66058 -46.082204) (xy 12.646043 -46.113214) (xy 12.61527 -46.159727) (xy 12.578053 -46.201264)
			(xy 12.535185 -46.236939) (xy 12.487579 -46.265993) (xy 12.43625 -46.287805) (xy 12.382293 -46.301911)
			(xy 12.326856 -46.308011) (xy 12.271122 -46.305974) (xy 12.216279 -46.295844) (xy 12.163495 -46.277837)
			(xy 12.113895 -46.252336) (xy 12.068537 -46.219885) (xy 12.028388 -46.181176) (xy 11.994302 -46.137033)
			(xy 11.967006 -46.088398) (xy 11.947083 -46.036307) (xy 11.934957 -45.98187) (xy 11.930886 -45.926248)
			(xy 8.630854 -45.926248) (xy 8.629657 -45.93438) (xy 8.613589 -45.987787) (xy 8.589917 -46.038284)
			(xy 8.559144 -46.084797) (xy 8.521927 -46.126334) (xy 8.479059 -46.162009) (xy 8.431453 -46.191063)
			(xy 8.380124 -46.212875) (xy 8.326167 -46.226981) (xy 8.27073 -46.233081) (xy 8.214996 -46.231044)
			(xy 8.160153 -46.220914) (xy 8.107369 -46.202907) (xy 8.057769 -46.177406) (xy 8.012411 -46.144955)
			(xy 7.972262 -46.106246) (xy 7.938176 -46.062103) (xy 7.91088 -46.013468) (xy 7.890957 -45.961377)
			(xy 7.878831 -45.90694) (xy 7.87476 -45.851318) (xy 0.715772 -45.851318) (xy 0.715772 -48.30699)
			(xy 24.553924 -48.30699) (xy 24.557995 -48.251368) (xy 24.570121 -48.196931) (xy 24.590044 -48.14484)
			(xy 24.61734 -48.096205) (xy 24.651426 -48.052062) (xy 24.691575 -48.013353) (xy 24.736933 -47.980902)
			(xy 24.786533 -47.955401) (xy 24.839317 -47.937394) (xy 24.89416 -47.927264) (xy 24.949894 -47.925227)
			(xy 25.005331 -47.931327) (xy 25.059288 -47.945433) (xy 25.110617 -47.967245) (xy 25.158223 -47.996299)
			(xy 25.201091 -48.031974) (xy 25.238308 -48.073511) (xy 25.269081 -48.120024) (xy 25.292753 -48.170521)
			(xy 25.308821 -48.223928) (xy 25.316941 -48.279104) (xy 25.31745 -48.30699) (xy 25.316941 -48.334876)
			(xy 25.308821 -48.390052) (xy 25.292753 -48.443459) (xy 25.269081 -48.493956) (xy 25.238308 -48.540469)
			(xy 25.201091 -48.582006) (xy 25.158223 -48.617681) (xy 25.110617 -48.646735) (xy 25.059288 -48.668547)
			(xy 25.005331 -48.682653) (xy 24.949894 -48.688753) (xy 24.89416 -48.686716) (xy 24.839317 -48.676586)
			(xy 24.786533 -48.658579) (xy 24.736933 -48.633078) (xy 24.691575 -48.600627) (xy 24.651426 -48.561918)
			(xy 24.61734 -48.517775) (xy 24.590044 -48.46914) (xy 24.570121 -48.417049) (xy 24.557995 -48.362612)
			(xy 24.553924 -48.30699) (xy 0.715772 -48.30699) (xy 0.715772 -48.753014) (xy 21.168358 -48.753014)
			(xy 21.172429 -48.697392) (xy 21.184555 -48.642955) (xy 21.204478 -48.590864) (xy 21.231774 -48.542229)
			(xy 21.26586 -48.498086) (xy 21.306009 -48.459377) (xy 21.351367 -48.426926) (xy 21.400967 -48.401425)
			(xy 21.453751 -48.383418) (xy 21.508594 -48.373288) (xy 21.564328 -48.371251) (xy 21.619765 -48.377351)
			(xy 21.673722 -48.391457) (xy 21.725051 -48.413269) (xy 21.772657 -48.442323) (xy 21.815525 -48.477998)
			(xy 21.852742 -48.519535) (xy 21.883515 -48.566048) (xy 21.907187 -48.616545) (xy 21.923255 -48.669952)
			(xy 21.931375 -48.725128) (xy 21.931884 -48.753014) (xy 21.931375 -48.7809) (xy 21.923255 -48.836076)
			(xy 21.907187 -48.889483) (xy 21.905791 -48.89246) (xy 23.214074 -48.89246) (xy 23.218145 -48.836838)
			(xy 23.230271 -48.782401) (xy 23.250194 -48.73031) (xy 23.27749 -48.681675) (xy 23.311576 -48.637532)
			(xy 23.351725 -48.598823) (xy 23.397083 -48.566372) (xy 23.446683 -48.540871) (xy 23.499467 -48.522864)
			(xy 23.55431 -48.512734) (xy 23.610044 -48.510697) (xy 23.665481 -48.516797) (xy 23.719438 -48.530903)
			(xy 23.770767 -48.552715) (xy 23.818373 -48.581769) (xy 23.861241 -48.617444) (xy 23.898458 -48.658981)
			(xy 23.929231 -48.705494) (xy 23.952903 -48.755991) (xy 23.968971 -48.809398) (xy 23.977091 -48.864574)
			(xy 23.9776 -48.89246) (xy 23.977091 -48.920346) (xy 23.974653 -48.93691) (xy 26.933142 -48.93691)
			(xy 26.937213 -48.881288) (xy 26.949339 -48.826851) (xy 26.969262 -48.77476) (xy 26.996558 -48.726125)
			(xy 27.030644 -48.681982) (xy 27.070793 -48.643273) (xy 27.116151 -48.610822) (xy 27.165751 -48.585321)
			(xy 27.218535 -48.567314) (xy 27.273378 -48.557184) (xy 27.329112 -48.555147) (xy 27.384549 -48.561247)
			(xy 27.438506 -48.575353) (xy 27.489835 -48.597165) (xy 27.537441 -48.626219) (xy 27.580309 -48.661894)
			(xy 27.617526 -48.703431) (xy 27.648299 -48.749944) (xy 27.671971 -48.800441) (xy 27.688039 -48.853848)
			(xy 27.696159 -48.909024) (xy 27.696668 -48.93691) (xy 27.696159 -48.964796) (xy 27.688039 -49.019972)
			(xy 27.671971 -49.073379) (xy 27.648299 -49.123876) (xy 27.617526 -49.170389) (xy 27.580309 -49.211926)
			(xy 27.537441 -49.247601) (xy 27.489835 -49.276655) (xy 27.438506 -49.298467) (xy 27.384549 -49.312573)
			(xy 27.329112 -49.318673) (xy 27.273378 -49.316636) (xy 27.218535 -49.306506) (xy 27.165751 -49.288499)
			(xy 27.116151 -49.262998) (xy 27.070793 -49.230547) (xy 27.030644 -49.191838) (xy 26.996558 -49.147695)
			(xy 26.969262 -49.09906) (xy 26.949339 -49.046969) (xy 26.937213 -48.992532) (xy 26.933142 -48.93691)
			(xy 23.974653 -48.93691) (xy 23.968971 -48.975522) (xy 23.952903 -49.028929) (xy 23.929231 -49.079426)
			(xy 23.898458 -49.125939) (xy 23.861241 -49.167476) (xy 23.818373 -49.203151) (xy 23.770767 -49.232205)
			(xy 23.719438 -49.254017) (xy 23.665481 -49.268123) (xy 23.610044 -49.274223) (xy 23.55431 -49.272186)
			(xy 23.499467 -49.262056) (xy 23.446683 -49.244049) (xy 23.397083 -49.218548) (xy 23.351725 -49.186097)
			(xy 23.311576 -49.147388) (xy 23.27749 -49.103245) (xy 23.250194 -49.05461) (xy 23.230271 -49.002519)
			(xy 23.218145 -48.948082) (xy 23.214074 -48.89246) (xy 21.905791 -48.89246) (xy 21.883515 -48.93998)
			(xy 21.852742 -48.986493) (xy 21.815525 -49.02803) (xy 21.772657 -49.063705) (xy 21.725051 -49.092759)
			(xy 21.673722 -49.114571) (xy 21.619765 -49.128677) (xy 21.564328 -49.134777) (xy 21.508594 -49.13274)
			(xy 21.453751 -49.12261) (xy 21.400967 -49.104603) (xy 21.351367 -49.079102) (xy 21.306009 -49.046651)
			(xy 21.26586 -49.007942) (xy 21.231774 -48.963799) (xy 21.204478 -48.915164) (xy 21.184555 -48.863073)
			(xy 21.172429 -48.808636) (xy 21.168358 -48.753014) (xy 0.715772 -48.753014) (xy 0.715772 -49.601951)
			(xy 6.113002 -49.601951) (xy 6.113002 -49.547449) (xy 6.120758 -49.493502) (xy 6.136113 -49.441208)
			(xy 6.158754 -49.391632) (xy 6.18822 -49.345782) (xy 6.223911 -49.304592) (xy 6.2651 -49.268901)
			(xy 6.31095 -49.239435) (xy 6.360526 -49.216794) (xy 6.41282 -49.201439) (xy 6.466767 -49.193682)
			(xy 6.494018 -49.193196) (xy 6.521389 -49.193652) (xy 6.575568 -49.201473) (xy 6.628071 -49.216964)
			(xy 6.677818 -49.239808) (xy 6.723784 -49.269534) (xy 6.744716 -49.287176) (xy 6.74497 -49.28743)
			(xy 6.752059 -49.293013) (xy 6.768974 -49.299261) (xy 6.77799 -49.299622) (xy 6.845046 -49.299622)
			(xy 6.85406 -49.299235) (xy 6.870977 -49.293008) (xy 6.878066 -49.28743) (xy 6.878066 -49.287176)
			(xy 6.87832 -49.287176) (xy 6.899253 -49.269535) (xy 6.945221 -49.239811) (xy 6.994967 -49.216965)
			(xy 7.047469 -49.201469) (xy 7.101647 -49.19364) (xy 7.156389 -49.19364) (xy 7.210567 -49.201469)
			(xy 7.263069 -49.216965) (xy 7.312815 -49.239811) (xy 7.358783 -49.269535) (xy 7.379716 -49.287176)
			(xy 7.37997 -49.28743) (xy 7.387059 -49.293013) (xy 7.403974 -49.299261) (xy 7.41299 -49.299622)
			(xy 7.480046 -49.299622) (xy 7.48906 -49.299235) (xy 7.505977 -49.293008) (xy 7.513066 -49.28743)
			(xy 7.513066 -49.287176) (xy 7.51332 -49.287176) (xy 7.534253 -49.269535) (xy 7.580221 -49.239811)
			(xy 7.629967 -49.216965) (xy 7.682469 -49.201469) (xy 7.736647 -49.19364) (xy 7.791389 -49.19364)
			(xy 7.845567 -49.201469) (xy 7.898069 -49.216965) (xy 7.947815 -49.239811) (xy 7.993783 -49.269535)
			(xy 8.014716 -49.287176) (xy 8.01497 -49.28743) (xy 8.022059 -49.293013) (xy 8.038974 -49.299261)
			(xy 8.04799 -49.299622) (xy 8.115046 -49.299622) (xy 8.12406 -49.299235) (xy 8.140977 -49.293008)
			(xy 8.148066 -49.28743) (xy 8.148066 -49.287176) (xy 8.14832 -49.287176) (xy 8.169268 -49.269557)
			(xy 8.215237 -49.239843) (xy 8.26498 -49.217004) (xy 8.317477 -49.201508) (xy 8.37165 -49.193673)
			(xy 8.399018 -49.193196) (xy 8.426271 -49.193651) (xy 8.480223 -49.201408) (xy 8.532522 -49.216764)
			(xy 8.582102 -49.239407) (xy 8.627956 -49.268875) (xy 8.66915 -49.304569) (xy 8.704844 -49.345762)
			(xy 8.734312 -49.391616) (xy 8.756955 -49.441197) (xy 8.772312 -49.493495) (xy 8.780069 -49.547447)
			(xy 8.780069 -49.601953) (xy 8.772312 -49.655905) (xy 8.756955 -49.708203) (xy 8.734312 -49.757784)
			(xy 8.704844 -49.803638) (xy 8.66915 -49.844831) (xy 8.627956 -49.880525) (xy 8.582102 -49.909993)
			(xy 8.532522 -49.932636) (xy 8.480223 -49.947992) (xy 8.446017 -49.95291) (xy 26.933142 -49.95291)
			(xy 26.937213 -49.897288) (xy 26.949339 -49.842851) (xy 26.969262 -49.79076) (xy 26.996558 -49.742125)
			(xy 27.030644 -49.697982) (xy 27.070793 -49.659273) (xy 27.116151 -49.626822) (xy 27.165751 -49.601321)
			(xy 27.218535 -49.583314) (xy 27.273378 -49.573184) (xy 27.329112 -49.571147) (xy 27.384549 -49.577247)
			(xy 27.438506 -49.591353) (xy 27.463441 -49.601949) (xy 32.112982 -49.601949) (xy 32.112982 -49.547451)
			(xy 32.120737 -49.493506) (xy 32.13609 -49.441215) (xy 32.158729 -49.39164) (xy 32.188192 -49.345792)
			(xy 32.223879 -49.304603) (xy 32.265065 -49.268912) (xy 32.310911 -49.239445) (xy 32.360483 -49.216802)
			(xy 32.412773 -49.201444) (xy 32.466717 -49.193684) (xy 32.493966 -49.193196) (xy 32.521335 -49.193683)
			(xy 32.575514 -49.201496) (xy 32.628016 -49.21698) (xy 32.677764 -49.239817) (xy 32.723732 -49.269537)
			(xy 32.744664 -49.287176) (xy 32.744918 -49.28743) (xy 32.751993 -49.293034) (xy 32.768919 -49.299269)
			(xy 32.777938 -49.299622) (xy 32.844994 -49.299622) (xy 32.85401 -49.299257) (xy 32.870927 -49.293014)
			(xy 32.878014 -49.28743) (xy 32.878014 -49.287176) (xy 32.878268 -49.287176) (xy 32.899201 -49.269535)
			(xy 32.945169 -49.239811) (xy 32.994915 -49.216965) (xy 33.047417 -49.201469) (xy 33.101595 -49.19364)
			(xy 33.156337 -49.19364) (xy 33.210515 -49.201469) (xy 33.263017 -49.216965) (xy 33.312763 -49.239811)
			(xy 33.358731 -49.269535) (xy 33.379664 -49.287176) (xy 33.379918 -49.28743) (xy 33.386993 -49.293034)
			(xy 33.403919 -49.299269) (xy 33.412938 -49.299622) (xy 33.479994 -49.299622) (xy 33.48901 -49.299257)
			(xy 33.505927 -49.293014) (xy 33.513014 -49.28743) (xy 33.513014 -49.287176) (xy 33.513268 -49.287176)
			(xy 33.534201 -49.269535) (xy 33.580169 -49.239811) (xy 33.629915 -49.216965) (xy 33.682417 -49.201469)
			(xy 33.736595 -49.19364) (xy 33.791337 -49.19364) (xy 33.845515 -49.201469) (xy 33.898017 -49.216965)
			(xy 33.947763 -49.239811) (xy 33.993731 -49.269535) (xy 34.014664 -49.287176) (xy 34.014918 -49.28743)
			(xy 34.021993 -49.293034) (xy 34.038919 -49.299269) (xy 34.047938 -49.299622) (xy 34.114994 -49.299622)
			(xy 34.12401 -49.299257) (xy 34.140927 -49.293014) (xy 34.148014 -49.28743) (xy 34.148014 -49.287176)
			(xy 34.148268 -49.287176) (xy 34.169198 -49.269535) (xy 34.215172 -49.239824) (xy 34.26492 -49.216989)
			(xy 34.317421 -49.201498) (xy 34.371597 -49.19367) (xy 34.398966 -49.193196) (xy 34.426221 -49.193649)
			(xy 34.480176 -49.201402) (xy 34.532478 -49.216755) (xy 34.582063 -49.239396) (xy 34.627921 -49.268864)
			(xy 34.669118 -49.304558) (xy 34.704816 -49.345752) (xy 34.734287 -49.391607) (xy 34.756933 -49.44119)
			(xy 34.772291 -49.493491) (xy 34.780049 -49.547445) (xy 34.780049 -49.601955) (xy 34.772291 -49.655909)
			(xy 34.756933 -49.70821) (xy 34.734287 -49.757793) (xy 34.704816 -49.803648) (xy 34.669118 -49.844842)
			(xy 34.627921 -49.880536) (xy 34.582063 -49.910004) (xy 34.532478 -49.932645) (xy 34.480176 -49.947998)
			(xy 34.426221 -49.955751) (xy 34.398966 -49.956212) (xy 34.371595 -49.955763) (xy 34.317416 -49.947941)
			(xy 34.264912 -49.932447) (xy 34.215166 -49.909602) (xy 34.169199 -49.879874) (xy 34.148268 -49.862232)
			(xy 34.148014 -49.861978) (xy 34.140929 -49.856389) (xy 34.124011 -49.850144) (xy 34.114994 -49.849786)
			(xy 34.047938 -49.849786) (xy 34.038923 -49.850164) (xy 34.022006 -49.856397) (xy 34.014918 -49.861978)
			(xy 34.014664 -49.862232) (xy 33.993731 -49.879873) (xy 33.947763 -49.909597) (xy 33.898017 -49.932443)
			(xy 33.845515 -49.947939) (xy 33.791337 -49.955768) (xy 33.736595 -49.955768) (xy 33.682417 -49.947939)
			(xy 33.629915 -49.932443) (xy 33.580169 -49.909597) (xy 33.534201 -49.879873) (xy 33.513268 -49.862232)
			(xy 33.513014 -49.861978) (xy 33.505929 -49.856389) (xy 33.489011 -49.850144) (xy 33.479994 -49.849786)
			(xy 33.412938 -49.849786) (xy 33.403923 -49.850164) (xy 33.387006 -49.856397) (xy 33.379918 -49.861978)
			(xy 33.379918 -49.862232) (xy 33.379664 -49.862232) (xy 33.358731 -49.879873) (xy 33.312763 -49.909597)
			(xy 33.263017 -49.932443) (xy 33.210515 -49.947939) (xy 33.156337 -49.955768) (xy 33.101595 -49.955768)
			(xy 33.047417 -49.947939) (xy 32.994915 -49.932443) (xy 32.945169 -49.909597) (xy 32.899201 -49.879873)
			(xy 32.878268 -49.862232) (xy 32.878014 -49.861978) (xy 32.870929 -49.856389) (xy 32.854011 -49.850144)
			(xy 32.844994 -49.849786) (xy 32.777938 -49.849786) (xy 32.768923 -49.850164) (xy 32.752006 -49.856397)
			(xy 32.744918 -49.861978) (xy 32.744918 -49.862232) (xy 32.744664 -49.862232) (xy 32.723723 -49.87986)
			(xy 32.677752 -49.909572) (xy 32.628007 -49.93241) (xy 32.575508 -49.947904) (xy 32.521334 -49.955736)
			(xy 32.493966 -49.956212) (xy 32.466717 -49.955716) (xy 32.412773 -49.947956) (xy 32.360483 -49.932598)
			(xy 32.310911 -49.909955) (xy 32.265065 -49.880488) (xy 32.223879 -49.844797) (xy 32.188192 -49.803608)
			(xy 32.158729 -49.75776) (xy 32.13609 -49.708185) (xy 32.120737 -49.655894) (xy 32.112982 -49.601949)
			(xy 27.463441 -49.601949) (xy 27.489835 -49.613165) (xy 27.537441 -49.642219) (xy 27.580309 -49.677894)
			(xy 27.617526 -49.719431) (xy 27.648299 -49.765944) (xy 27.671971 -49.816441) (xy 27.688039 -49.869848)
			(xy 27.696159 -49.925024) (xy 27.696668 -49.95291) (xy 27.696159 -49.980796) (xy 27.688039 -50.035972)
			(xy 27.671971 -50.089379) (xy 27.648299 -50.139876) (xy 27.617526 -50.186389) (xy 27.580309 -50.227926)
			(xy 27.537441 -50.263601) (xy 27.489835 -50.292655) (xy 27.438506 -50.314467) (xy 27.384549 -50.328573)
			(xy 27.329112 -50.334673) (xy 27.273378 -50.332636) (xy 27.218535 -50.322506) (xy 27.165751 -50.304499)
			(xy 27.116151 -50.278998) (xy 27.070793 -50.246547) (xy 27.030644 -50.207838) (xy 26.996558 -50.163695)
			(xy 26.969262 -50.11506) (xy 26.949339 -50.062969) (xy 26.937213 -50.008532) (xy 26.933142 -49.95291)
			(xy 8.446017 -49.95291) (xy 8.426271 -49.955749) (xy 8.399018 -49.956212) (xy 8.371648 -49.955732)
			(xy 8.31747 -49.947917) (xy 8.264967 -49.932431) (xy 8.21522 -49.909593) (xy 8.169252 -49.879872)
			(xy 8.14832 -49.862232) (xy 8.148066 -49.861978) (xy 8.140966 -49.85641) (xy 8.12406 -49.850153)
			(xy 8.115046 -49.849786) (xy 8.04799 -49.849786) (xy 8.038973 -49.850141) (xy 8.022056 -49.856391)
			(xy 8.01497 -49.861978) (xy 8.014716 -49.862232) (xy 7.993783 -49.879873) (xy 7.947815 -49.909597)
			(xy 7.898069 -49.932443) (xy 7.845567 -49.947939) (xy 7.791389 -49.955768) (xy 7.736647 -49.955768)
			(xy 7.682469 -49.947939) (xy 7.629967 -49.932443) (xy 7.580221 -49.909597) (xy 7.534253 -49.879873)
			(xy 7.51332 -49.862232) (xy 7.513066 -49.861978) (xy 7.505966 -49.85641) (xy 7.48906 -49.850153)
			(xy 7.480046 -49.849786) (xy 7.41299 -49.849786) (xy 7.403973 -49.850141) (xy 7.387056 -49.856391)
			(xy 7.37997 -49.861978) (xy 7.37997 -49.862232) (xy 7.379716 -49.862232) (xy 7.358783 -49.879873)
			(xy 7.312815 -49.909597) (xy 7.263069 -49.932443) (xy 7.210567 -49.947939) (xy 7.156389 -49.955768)
			(xy 7.101647 -49.955768) (xy 7.047469 -49.947939) (xy 6.994967 -49.932443) (xy 6.945221 -49.909597)
			(xy 6.899253 -49.879873) (xy 6.87832 -49.862232) (xy 6.878066 -49.861978) (xy 6.870966 -49.85641)
			(xy 6.85406 -49.850153) (xy 6.845046 -49.849786) (xy 6.77799 -49.849786) (xy 6.768973 -49.850141)
			(xy 6.752056 -49.856391) (xy 6.74497 -49.861978) (xy 6.74497 -49.862232) (xy 6.744716 -49.862232)
			(xy 6.723793 -49.879882) (xy 6.677817 -49.909591) (xy 6.628067 -49.932424) (xy 6.575565 -49.947913)
			(xy 6.521388 -49.955739) (xy 6.494018 -49.956212) (xy 6.466767 -49.955718) (xy 6.41282 -49.947961)
			(xy 6.360526 -49.932606) (xy 6.31095 -49.909965) (xy 6.2651 -49.880499) (xy 6.223911 -49.844808)
			(xy 6.18822 -49.803618) (xy 6.158754 -49.757768) (xy 6.136113 -49.708192) (xy 6.120758 -49.655898)
			(xy 6.113002 -49.601951) (xy 0.715772 -49.601951) (xy 0.715772 -51.243992) (xy 7.133082 -51.243992)
			(xy 7.133523 -51.216621) (xy 7.141344 -51.16244) (xy 7.156838 -51.109936) (xy 7.179686 -51.060189)
			(xy 7.209417 -51.014224) (xy 7.227062 -50.993294) (xy 7.227316 -50.99304) (xy 7.232894 -50.985947)
			(xy 7.239145 -50.969035) (xy 7.239508 -50.96002) (xy 7.239508 -50.892964) (xy 7.239167 -50.883946)
			(xy 7.232908 -50.867029) (xy 7.227316 -50.859944) (xy 7.227062 -50.859944) (xy 7.227062 -50.85969)
			(xy 7.209398 -50.838778) (xy 7.179691 -50.792799) (xy 7.156861 -50.743046) (xy 7.141375 -50.690541)
			(xy 7.133553 -50.636362) (xy 7.133082 -50.608992) (xy 7.13357 -50.581741) (xy 7.141328 -50.527794)
			(xy 7.156683 -50.4755) (xy 7.179325 -50.425923) (xy 7.208791 -50.380073) (xy 7.244482 -50.338883)
			(xy 7.285672 -50.303192) (xy 7.331521 -50.273726) (xy 7.381098 -50.251084) (xy 7.433392 -50.235728)
			(xy 7.487339 -50.22797) (xy 7.51459 -50.227484) (xy 7.543508 -50.227978) (xy 7.600682 -50.236707)
			(xy 7.655883 -50.253968) (xy 7.707845 -50.279364) (xy 7.755378 -50.312314) (xy 7.797392 -50.352061)
			(xy 7.81558 -50.37455) (xy 7.823197 -50.383347) (xy 7.844091 -50.393534) (xy 7.855712 -50.394108)
			(xy 7.935468 -50.394108) (xy 7.947095 -50.393533) (xy 7.968005 -50.383369) (xy 7.9756 -50.37455)
			(xy 7.993778 -50.352056) (xy 8.035802 -50.312324) (xy 8.08334 -50.279388) (xy 8.135304 -50.254001)
			(xy 8.190503 -50.236747) (xy 8.247673 -50.228019) (xy 8.27659 -50.227484) (xy 8.303842 -50.227965)
			(xy 8.357792 -50.23572) (xy 8.410089 -50.251074) (xy 8.459669 -50.273715) (xy 8.505522 -50.303181)
			(xy 8.546714 -50.338873) (xy 8.582408 -50.380064) (xy 8.611876 -50.425915) (xy 8.634519 -50.475494)
			(xy 8.649876 -50.52779) (xy 8.657634 -50.58174) (xy 8.658098 -50.608992) (xy 8.657626 -50.635306)
			(xy 8.650392 -50.687434) (xy 8.636074 -50.738077) (xy 8.614942 -50.786276) (xy 8.587397 -50.831119)
			(xy 8.553959 -50.871759) (xy 8.534908 -50.889916) (xy 8.527499 -50.897431) (xy 8.518978 -50.916716)
			(xy 8.518398 -50.927254) (xy 8.518398 -51.00193) (xy 8.518952 -51.012477) (xy 8.522033 -51.019456)
			(xy 24.749504 -51.019456) (xy 24.753575 -50.963834) (xy 24.765701 -50.909397) (xy 24.785624 -50.857306)
			(xy 24.81292 -50.808671) (xy 24.847006 -50.764528) (xy 24.887155 -50.725819) (xy 24.932513 -50.693368)
			(xy 24.982113 -50.667867) (xy 25.034897 -50.64986) (xy 25.08974 -50.63973) (xy 25.145474 -50.637693)
			(xy 25.200911 -50.643793) (xy 25.254868 -50.657899) (xy 25.306197 -50.679711) (xy 25.353803 -50.708765)
			(xy 25.396671 -50.74444) (xy 25.433888 -50.785977) (xy 25.464661 -50.83249) (xy 25.488333 -50.882987)
			(xy 25.504401 -50.936394) (xy 25.512521 -50.99157) (xy 25.51303 -51.019456) (xy 25.512521 -51.047342)
			(xy 25.504401 -51.102518) (xy 25.488333 -51.155925) (xy 25.464661 -51.206422) (xy 25.439805 -51.243992)
			(xy 33.13303 -51.243992) (xy 33.133484 -51.216621) (xy 33.141304 -51.162441) (xy 33.156795 -51.109938)
			(xy 33.17964 -51.060191) (xy 33.209367 -51.014225) (xy 33.22701 -50.993294) (xy 33.227264 -50.99304)
			(xy 33.232848 -50.985952) (xy 33.239094 -50.969036) (xy 33.239456 -50.96002) (xy 33.239456 -50.892964)
			(xy 33.239126 -50.883944) (xy 33.232861 -50.867027) (xy 33.227264 -50.859944) (xy 33.22701 -50.859944)
			(xy 33.22701 -50.85969) (xy 33.209354 -50.838771) (xy 33.179645 -50.792795) (xy 33.156812 -50.743044)
			(xy 33.141325 -50.69054) (xy 33.133501 -50.636362) (xy 33.13303 -50.608992) (xy 33.133448 -50.581737)
			(xy 33.141207 -50.527783) (xy 33.156566 -50.475482) (xy 33.179212 -50.425899) (xy 33.208685 -50.380044)
			(xy 33.244383 -50.338851) (xy 33.285581 -50.303157) (xy 33.331439 -50.27369) (xy 33.381025 -50.25105)
			(xy 33.433328 -50.235697) (xy 33.487283 -50.227945) (xy 33.514538 -50.227484) (xy 33.543455 -50.228015)
			(xy 33.600627 -50.236737) (xy 33.655827 -50.25399) (xy 33.707789 -50.27938) (xy 33.755323 -50.312322)
			(xy 33.797339 -50.352064) (xy 33.815528 -50.37455) (xy 33.823124 -50.383368) (xy 33.844033 -50.393544)
			(xy 33.85566 -50.394108) (xy 33.935416 -50.394108) (xy 33.947047 -50.393561) (xy 33.967956 -50.383377)
			(xy 33.975548 -50.37455) (xy 33.993756 -50.352081) (xy 34.035774 -50.312347) (xy 34.083305 -50.279408)
			(xy 34.135263 -50.254018) (xy 34.190457 -50.236757) (xy 34.247623 -50.228023) (xy 34.276538 -50.227484)
			(xy 34.30379 -50.227942) (xy 34.357738 -50.235704) (xy 34.410033 -50.251063) (xy 34.45961 -50.273708)
			(xy 34.50546 -50.303178) (xy 34.546649 -50.338872) (xy 34.58234 -50.380065) (xy 34.611806 -50.425917)
			(xy 34.634447 -50.475495) (xy 34.649802 -50.527791) (xy 34.65756 -50.58174) (xy 34.658046 -50.608992)
			(xy 34.657591 -50.635307) (xy 34.650356 -50.687436) (xy 34.636035 -50.73808) (xy 34.614901 -50.786279)
			(xy 34.587352 -50.831122) (xy 34.553909 -50.871761) (xy 34.534856 -50.889916) (xy 34.527454 -50.897437)
			(xy 34.518928 -50.916717) (xy 34.518346 -50.927254) (xy 34.518346 -51.00193) (xy 34.518886 -51.012479)
			(xy 34.527412 -51.031775) (xy 34.534856 -51.039268) (xy 34.553948 -51.057386) (xy 34.5874 -51.098025)
			(xy 34.614953 -51.142874) (xy 34.636084 -51.191082) (xy 34.650394 -51.241735) (xy 34.657611 -51.293874)
			(xy 34.658046 -51.320192) (xy 34.657515 -51.347441) (xy 34.64976 -51.401385) (xy 34.634408 -51.453677)
			(xy 34.611771 -51.503252) (xy 34.582309 -51.5491) (xy 34.546622 -51.59029) (xy 34.505437 -51.625981)
			(xy 34.459592 -51.655449) (xy 34.41002 -51.678092) (xy 34.35773 -51.693451) (xy 34.303787 -51.701212)
			(xy 34.276538 -51.7017) (xy 34.248874 -51.701158) (xy 34.194126 -51.693164) (xy 34.141105 -51.677353)
			(xy 34.090921 -51.654055) (xy 34.044625 -51.623758) (xy 34.003186 -51.587097) (xy 33.967472 -51.544839)
			(xy 33.952434 -51.521614) (xy 33.945791 -51.511943) (xy 33.925934 -51.499497) (xy 33.914334 -51.497738)
			(xy 33.834324 -51.489864) (xy 33.822686 -51.48925) (xy 33.80085 -51.497317) (xy 33.792414 -51.505358)
			(xy 33.79216 -51.505612) (xy 33.774083 -51.524197) (xy 33.73375 -51.556775) (xy 33.689375 -51.583587)
			(xy 33.641776 -51.604139) (xy 33.591831 -51.618052) (xy 33.540461 -51.625069) (xy 33.514538 -51.6255)
			(xy 33.487286 -51.625009) (xy 33.433335 -51.617257) (xy 33.381038 -51.601906) (xy 33.331457 -51.579267)
			(xy 33.285603 -51.549802) (xy 33.24441 -51.514111) (xy 33.208716 -51.472921) (xy 33.179247 -51.427069)
			(xy 33.156605 -51.377491) (xy 33.141249 -51.325194) (xy 33.133493 -51.271244) (xy 33.13303 -51.243992)
			(xy 25.439805 -51.243992) (xy 25.433888 -51.252935) (xy 25.396671 -51.294472) (xy 25.353803 -51.330147)
			(xy 25.306197 -51.359201) (xy 25.254868 -51.381013) (xy 25.200911 -51.395119) (xy 25.145474 -51.401219)
			(xy 25.08974 -51.399182) (xy 25.034897 -51.389052) (xy 24.982113 -51.371045) (xy 24.932513 -51.345544)
			(xy 24.887155 -51.313093) (xy 24.847006 -51.274384) (xy 24.81292 -51.230241) (xy 24.785624 -51.181606)
			(xy 24.765701 -51.129515) (xy 24.753575 -51.075078) (xy 24.749504 -51.019456) (xy 8.522033 -51.019456)
			(xy 8.52747 -51.031772) (xy 8.534908 -51.039268) (xy 8.553991 -51.057396) (xy 8.587445 -51.098032)
			(xy 8.615001 -51.142878) (xy 8.636134 -51.191084) (xy 8.650446 -51.241736) (xy 8.657663 -51.293874)
			(xy 8.658098 -51.320192) (xy 8.657637 -51.347445) (xy 8.649881 -51.401397) (xy 8.634526 -51.453695)
			(xy 8.611883 -51.503276) (xy 8.582415 -51.54913) (xy 8.546721 -51.590323) (xy 8.505528 -51.626016)
			(xy 8.459674 -51.655484) (xy 8.410093 -51.678126) (xy 8.357795 -51.693481) (xy 8.303843 -51.701237)
			(xy 8.27659 -51.7017) (xy 8.248925 -51.701196) (xy 8.194175 -51.693195) (xy 8.141153 -51.677377)
			(xy 8.090969 -51.654073) (xy 8.044674 -51.62377) (xy 8.003236 -51.587104) (xy 7.967523 -51.544841)
			(xy 7.952486 -51.521614) (xy 7.945866 -51.511924) (xy 7.925992 -51.499488) (xy 7.914386 -51.497738)
			(xy 7.834376 -51.489864) (xy 7.822737 -51.489221) (xy 7.800899 -51.497308) (xy 7.792466 -51.505358)
			(xy 7.792212 -51.505612) (xy 7.77411 -51.524172) (xy 7.733782 -51.556752) (xy 7.689412 -51.583567)
			(xy 7.641818 -51.604124) (xy 7.591878 -51.618042) (xy 7.540512 -51.625065) (xy 7.51459 -51.6255)
			(xy 7.487338 -51.625031) (xy 7.433389 -51.617273) (xy 7.381094 -51.601917) (xy 7.331516 -51.579274)
			(xy 7.285665 -51.549806) (xy 7.244475 -51.514112) (xy 7.208784 -51.47292) (xy 7.179318 -51.427068)
			(xy 7.156677 -51.377489) (xy 7.141323 -51.325193) (xy 7.133567 -51.271244) (xy 7.133082 -51.243992)
			(xy 0.715772 -51.243992) (xy 0.715772 -52.035456) (xy 26.94127 -52.035456) (xy 26.945341 -51.979834)
			(xy 26.957467 -51.925397) (xy 26.97739 -51.873306) (xy 27.004686 -51.824671) (xy 27.038772 -51.780528)
			(xy 27.078921 -51.741819) (xy 27.124279 -51.709368) (xy 27.173879 -51.683867) (xy 27.226663 -51.66586)
			(xy 27.281506 -51.65573) (xy 27.33724 -51.653693) (xy 27.392677 -51.659793) (xy 27.446634 -51.673899)
			(xy 27.497963 -51.695711) (xy 27.545569 -51.724765) (xy 27.588437 -51.76044) (xy 27.625654 -51.801977)
			(xy 27.656427 -51.84849) (xy 27.680099 -51.898987) (xy 27.696167 -51.952394) (xy 27.704287 -52.00757)
			(xy 27.704796 -52.035456) (xy 27.704287 -52.063342) (xy 27.696167 -52.118518) (xy 27.680099 -52.171925)
			(xy 27.656427 -52.222422) (xy 27.625654 -52.268935) (xy 27.588437 -52.310472) (xy 27.545569 -52.346147)
			(xy 27.497963 -52.375201) (xy 27.446634 -52.397013) (xy 27.392677 -52.411119) (xy 27.33724 -52.417219)
			(xy 27.281506 -52.415182) (xy 27.226663 -52.405052) (xy 27.173879 -52.387045) (xy 27.124279 -52.361544)
			(xy 27.078921 -52.329093) (xy 27.038772 -52.290384) (xy 27.004686 -52.246241) (xy 26.97739 -52.197606)
			(xy 26.957467 -52.145515) (xy 26.945341 -52.091078) (xy 26.94127 -52.035456) (xy 0.715772 -52.035456)
			(xy 0.715772 -52.555973) (xy 6.583889 -52.555973) (xy 6.583889 -52.501467) (xy 6.591646 -52.447517)
			(xy 6.607002 -52.395219) (xy 6.629645 -52.345639) (xy 6.659113 -52.299786) (xy 6.694807 -52.258594)
			(xy 6.735999 -52.222901) (xy 6.781853 -52.193433) (xy 6.831433 -52.170791) (xy 6.88373 -52.155435)
			(xy 6.937681 -52.147679) (xy 6.964934 -52.147216) (xy 6.992305 -52.147658) (xy 7.046485 -52.155481)
			(xy 7.098989 -52.170976) (xy 7.148735 -52.193823) (xy 7.194701 -52.223552) (xy 7.215632 -52.241196)
			(xy 7.215886 -52.24145) (xy 7.222968 -52.247043) (xy 7.239888 -52.253285) (xy 7.248906 -52.253642)
			(xy 7.315962 -52.253642) (xy 7.324979 -52.253279) (xy 7.341896 -52.247037) (xy 7.348982 -52.24145)
			(xy 7.348982 -52.241196) (xy 7.349236 -52.241196) (xy 7.370181 -52.223573) (xy 7.41615 -52.193859)
			(xy 7.465894 -52.17102) (xy 7.518392 -52.155525) (xy 7.572566 -52.147692) (xy 7.599934 -52.147216)
			(xy 7.627185 -52.147694) (xy 7.681133 -52.155451) (xy 7.733428 -52.170807) (xy 7.783005 -52.193448)
			(xy 7.828856 -52.222915) (xy 7.870046 -52.258607) (xy 7.905737 -52.299798) (xy 7.935204 -52.345648)
			(xy 7.957845 -52.395226) (xy 7.9732 -52.447521) (xy 7.980956 -52.501469) (xy 7.980956 -52.555971)
			(xy 7.9732 -52.609919) (xy 7.957845 -52.662214) (xy 7.935204 -52.711792) (xy 7.905737 -52.757642)
			(xy 7.870046 -52.798833) (xy 7.828856 -52.834525) (xy 7.783005 -52.863992) (xy 7.733428 -52.886633)
			(xy 7.681133 -52.901989) (xy 7.627185 -52.909746) (xy 7.599934 -52.910232) (xy 7.572564 -52.909763)
			(xy 7.518384 -52.901948) (xy 7.46588 -52.886461) (xy 7.416133 -52.863619) (xy 7.370167 -52.833894)
			(xy 7.349236 -52.816252) (xy 7.348982 -52.815998) (xy 7.341905 -52.810398) (xy 7.324981 -52.804159)
			(xy 7.315962 -52.803806) (xy 7.248906 -52.803806) (xy 7.239889 -52.804165) (xy 7.222972 -52.810411)
			(xy 7.215886 -52.815998) (xy 7.215886 -52.816252) (xy 7.215632 -52.816252) (xy 7.194693 -52.833882)
			(xy 7.148723 -52.863597) (xy 7.098977 -52.886435) (xy 7.046478 -52.901928) (xy 6.992303 -52.909758)
			(xy 6.964934 -52.910232) (xy 6.937681 -52.909761) (xy 6.88373 -52.902005) (xy 6.831433 -52.886649)
			(xy 6.781853 -52.864007) (xy 6.735999 -52.834539) (xy 6.694807 -52.798846) (xy 6.659113 -52.757654)
			(xy 6.629645 -52.711801) (xy 6.607002 -52.662221) (xy 6.591646 -52.609923) (xy 6.583889 -52.555973)
			(xy 0.715772 -52.555973) (xy 0.715772 -53.496543) (xy 6.133541 -53.496543) (xy 6.133541 -53.442037)
			(xy 6.141298 -53.388085) (xy 6.156655 -53.335787) (xy 6.179298 -53.286206) (xy 6.208766 -53.240352)
			(xy 6.24446 -53.199159) (xy 6.285654 -53.163465) (xy 6.331508 -53.133997) (xy 6.381088 -53.111354)
			(xy 6.433387 -53.095998) (xy 6.487339 -53.088241) (xy 6.514592 -53.087778) (xy 6.541963 -53.08823)
			(xy 6.596143 -53.096048) (xy 6.648647 -53.111539) (xy 6.698394 -53.134385) (xy 6.74436 -53.164114)
			(xy 6.76529 -53.181758) (xy 6.765544 -53.182012) (xy 6.772641 -53.187583) (xy 6.78955 -53.193839)
			(xy 6.798564 -53.194204) (xy 6.86562 -53.194204) (xy 6.874638 -53.193856) (xy 6.891555 -53.187602)
			(xy 6.89864 -53.182012) (xy 6.89864 -53.181758) (xy 6.898894 -53.181758) (xy 6.919812 -53.164101)
			(xy 6.965789 -53.134393) (xy 7.01554 -53.111561) (xy 7.068044 -53.096074) (xy 7.122222 -53.08825)
			(xy 7.149592 -53.087778) (xy 7.176843 -53.088272) (xy 7.23079 -53.096029) (xy 7.283084 -53.111384)
			(xy 7.33266 -53.134025) (xy 7.37851 -53.163491) (xy 7.419699 -53.199182) (xy 7.45539 -53.240372)
			(xy 7.484856 -53.286222) (xy 7.507497 -53.335798) (xy 7.522852 -53.388092) (xy 7.530608 -53.442039)
			(xy 7.530608 -53.496541) (xy 7.522852 -53.550488) (xy 7.507497 -53.602782) (xy 7.484856 -53.652358)
			(xy 7.45539 -53.698208) (xy 7.419699 -53.739398) (xy 7.37851 -53.775089) (xy 7.33266 -53.804555)
			(xy 7.283084 -53.827196) (xy 7.23079 -53.842551) (xy 7.176843 -53.850308) (xy 7.149592 -53.850794)
			(xy 7.122222 -53.850334) (xy 7.068042 -53.842515) (xy 7.015539 -53.827025) (xy 6.965792 -53.804181)
			(xy 6.919826 -53.774456) (xy 6.898894 -53.756814) (xy 6.89864 -53.75656) (xy 6.89155 -53.750979)
			(xy 6.874636 -53.74473) (xy 6.86562 -53.744368) (xy 6.798564 -53.744368) (xy 6.789546 -53.744715)
			(xy 6.77263 -53.75097) (xy 6.765544 -53.75656) (xy 6.765544 -53.756814) (xy 6.76529 -53.756814) (xy 6.744374 -53.774473)
			(xy 6.698397 -53.804182) (xy 6.648645 -53.827014) (xy 6.596141 -53.8425) (xy 6.541962 -53.850323)
			(xy 6.514592 -53.850794) (xy 6.487339 -53.850339) (xy 6.433387 -53.842582) (xy 6.381088 -53.827226)
			(xy 6.331508 -53.804583) (xy 6.285654 -53.775115) (xy 6.24446 -53.739421) (xy 6.208766 -53.698228)
			(xy 6.179298 -53.652374) (xy 6.156655 -53.602793) (xy 6.141298 -53.550495) (xy 6.133541 -53.496543)
			(xy 0.715772 -53.496543) (xy 0.715772 -54.989041) (xy 3.901168 -54.989041) (xy 3.901168 -54.934539)
			(xy 3.908924 -54.880592) (xy 3.924279 -54.828297) (xy 3.94692 -54.77872) (xy 3.976386 -54.73287)
			(xy 4.012077 -54.69168) (xy 4.053267 -54.655988) (xy 4.099117 -54.626522) (xy 4.148693 -54.603881)
			(xy 4.200988 -54.588525) (xy 4.254935 -54.580768) (xy 4.282186 -54.580282) (xy 4.310277 -54.580788)
			(xy 4.365854 -54.589013) (xy 4.419622 -54.605302) (xy 4.47042 -54.629303) (xy 4.517147 -54.660496)
			(xy 4.558792 -54.698207) (xy 4.594455 -54.741618) (xy 4.609338 -54.765448) (xy 4.614672 -54.774338)
			(xy 4.63169 -54.78653) (xy 4.724908 -54.80685) (xy 4.745482 -54.802532) (xy 4.754118 -54.79669) (xy 4.778175 -54.780679)
			(xy 4.830109 -54.755339) (xy 4.885269 -54.738117) (xy 4.942395 -54.729405) (xy 4.971288 -54.728872)
			(xy 4.998541 -54.729337) (xy 5.012973 -54.731412) (xy 13.520674 -54.731412) (xy 13.521129 -54.704041)
			(xy 13.528947 -54.649861) (xy 13.544437 -54.597357) (xy 13.567282 -54.54761) (xy 13.597011 -54.501645)
			(xy 13.614654 -54.480714) (xy 13.614908 -54.48046) (xy 13.620476 -54.473361) (xy 13.626734 -54.456454)
			(xy 13.6271 -54.44744) (xy 13.6271 -54.380384) (xy 13.626751 -54.371366) (xy 13.620498 -54.35445)
			(xy 13.614908 -54.347364) (xy 13.614654 -54.347364) (xy 13.614654 -54.34711) (xy 13.597024 -54.326168)
			(xy 13.567297 -54.280203) (xy 13.544449 -54.230458) (xy 13.528951 -54.177957) (xy 13.52112 -54.123779)
			(xy 13.521119 -54.069039) (xy 13.528947 -54.014861) (xy 13.544443 -53.962359) (xy 13.567288 -53.912613)
			(xy 13.597013 -53.866646) (xy 13.614654 -53.845714) (xy 13.614908 -53.84546) (xy 13.620476 -53.838361)
			(xy 13.626734 -53.821454) (xy 13.6271 -53.81244) (xy 13.6271 -53.745384) (xy 13.626751 -53.736366)
			(xy 13.620498 -53.71945) (xy 13.614908 -53.712364) (xy 13.614654 -53.712364) (xy 13.614654 -53.71211)
			(xy 13.597024 -53.691168) (xy 13.567297 -53.645203) (xy 13.544449 -53.595458) (xy 13.528951 -53.542957)
			(xy 13.52112 -53.488779) (xy 13.521119 -53.434039) (xy 13.528947 -53.379861) (xy 13.544443 -53.327359)
			(xy 13.567288 -53.277613) (xy 13.597013 -53.231646) (xy 13.614654 -53.210714) (xy 13.614908 -53.21046)
			(xy 13.620476 -53.203361) (xy 13.626734 -53.186454) (xy 13.6271 -53.17744) (xy 13.6271 -53.110384)
			(xy 13.626751 -53.101366) (xy 13.620498 -53.08445) (xy 13.614908 -53.077364) (xy 13.614654 -53.077364)
			(xy 13.614654 -53.07711) (xy 13.597015 -53.056178) (xy 13.567301 -53.010206) (xy 13.544464 -52.960459)
			(xy 13.528973 -52.907958) (xy 13.521147 -52.853781) (xy 13.520674 -52.826412) (xy 13.52116 -52.799161)
			(xy 13.528916 -52.745213) (xy 13.544271 -52.692918) (xy 13.566913 -52.643341) (xy 13.596379 -52.597491)
			(xy 13.63207 -52.5563) (xy 13.673261 -52.520609) (xy 13.719111 -52.491143) (xy 13.768688 -52.468501)
			(xy 13.820983 -52.453146) (xy 13.874931 -52.44539) (xy 13.929433 -52.44539) (xy 13.983381 -52.453146)
			(xy 14.035676 -52.468501) (xy 14.085253 -52.491143) (xy 14.131103 -52.520609) (xy 14.172294 -52.5563)
			(xy 14.207985 -52.597491) (xy 14.237451 -52.643341) (xy 14.260093 -52.692918) (xy 14.275448 -52.745213)
			(xy 14.283204 -52.799161) (xy 14.28369 -52.826412) (xy 14.283233 -52.853783) (xy 14.275414 -52.907962)
			(xy 14.259922 -52.960466) (xy 14.237079 -53.010212) (xy 14.207352 -53.056179) (xy 14.18971 -53.07711)
			(xy 14.189456 -53.077364) (xy 14.183873 -53.084453) (xy 14.177625 -53.101368) (xy 14.177264 -53.110384)
			(xy 14.177264 -53.17744) (xy 14.17761 -53.186458) (xy 14.183866 -53.203374) (xy 14.189456 -53.21046)
			(xy 14.18971 -53.21046) (xy 14.18971 -53.210714) (xy 14.207361 -53.231638) (xy 14.237082 -53.277608)
			(xy 14.259925 -53.327356) (xy 14.275419 -53.379859) (xy 14.283245 -53.434038) (xy 14.283244 -53.48878)
			(xy 14.275415 -53.542958) (xy 14.259918 -53.595461) (xy 14.237074 -53.645208) (xy 14.20735 -53.691177)
			(xy 14.18971 -53.71211) (xy 14.189456 -53.712364) (xy 14.183873 -53.719453) (xy 14.177625 -53.736368)
			(xy 14.177264 -53.745384) (xy 14.177264 -53.81244) (xy 14.17761 -53.821458) (xy 14.183866 -53.838374)
			(xy 14.189456 -53.84546) (xy 14.18971 -53.84546) (xy 14.18971 -53.845714) (xy 14.207361 -53.866638)
			(xy 14.237082 -53.912608) (xy 14.259925 -53.962356) (xy 14.275419 -54.014859) (xy 14.283245 -54.069038)
			(xy 14.283244 -54.12378) (xy 14.275415 -54.177958) (xy 14.259918 -54.230461) (xy 14.237074 -54.280208)
			(xy 14.20735 -54.326177) (xy 14.18971 -54.34711) (xy 14.189456 -54.347364) (xy 14.183873 -54.354453)
			(xy 14.177625 -54.371368) (xy 14.177264 -54.380384) (xy 14.177264 -54.44744) (xy 14.17761 -54.456458)
			(xy 14.183866 -54.473374) (xy 14.189456 -54.48046) (xy 14.18971 -54.48046) (xy 14.18971 -54.480714)
			(xy 14.207324 -54.501666) (xy 14.237039 -54.547634) (xy 14.25988 -54.597376) (xy 14.275377 -54.649872)
			(xy 14.283212 -54.704044) (xy 14.28369 -54.731412) (xy 14.283204 -54.758663) (xy 14.27854 -54.791102)
			(xy 16.176498 -54.791102) (xy 16.176966 -54.763732) (xy 16.184783 -54.709553) (xy 16.200272 -54.65705)
			(xy 16.223113 -54.607303) (xy 16.252837 -54.561336) (xy 16.270478 -54.540404) (xy 16.270732 -54.54015)
			(xy 16.276307 -54.533056) (xy 16.28256 -54.516145) (xy 16.282924 -54.50713) (xy 16.282924 -54.440074)
			(xy 16.282574 -54.431056) (xy 16.276321 -54.41414) (xy 16.270732 -54.407054) (xy 16.270478 -54.407054)
			(xy 16.270478 -54.4068) (xy 16.252841 -54.385865) (xy 16.22312 -54.339896) (xy 16.200278 -54.29015)
			(xy 16.184783 -54.237649) (xy 16.176956 -54.183471) (xy 16.176955 -54.128732) (xy 16.184783 -54.074554)
			(xy 16.200277 -54.022053) (xy 16.223119 -53.972307) (xy 16.252839 -53.926338) (xy 16.270478 -53.905404)
			(xy 16.270732 -53.90515) (xy 16.276307 -53.898056) (xy 16.28256 -53.881145) (xy 16.282924 -53.87213)
			(xy 16.282924 -53.805074) (xy 16.282574 -53.796056) (xy 16.276321 -53.77914) (xy 16.270732 -53.772054)
			(xy 16.270478 -53.772054) (xy 16.270478 -53.7718) (xy 16.252841 -53.750865) (xy 16.22312 -53.704896)
			(xy 16.200278 -53.65515) (xy 16.184783 -53.602649) (xy 16.176956 -53.548471) (xy 16.176955 -53.493732)
			(xy 16.184783 -53.439554) (xy 16.200277 -53.387053) (xy 16.223119 -53.337307) (xy 16.252839 -53.291338)
			(xy 16.270478 -53.270404) (xy 16.270732 -53.27015) (xy 16.276307 -53.263056) (xy 16.28256 -53.246145)
			(xy 16.282924 -53.23713) (xy 16.282924 -53.170074) (xy 16.282574 -53.161056) (xy 16.276321 -53.14414)
			(xy 16.270732 -53.137054) (xy 16.270478 -53.137054) (xy 16.270478 -53.1368) (xy 16.252822 -53.115882)
			(xy 16.223113 -53.069905) (xy 16.200281 -53.020154) (xy 16.184794 -52.96765) (xy 16.17697 -52.913472)
			(xy 16.176498 -52.886102) (xy 16.176984 -52.858851) (xy 16.18474 -52.804903) (xy 16.200095 -52.752608)
			(xy 16.222737 -52.703031) (xy 16.252203 -52.657181) (xy 16.287894 -52.61599) (xy 16.329085 -52.580299)
			(xy 16.374935 -52.550833) (xy 16.424512 -52.528191) (xy 16.476807 -52.512836) (xy 16.530755 -52.50508)
			(xy 16.585257 -52.50508) (xy 16.639205 -52.512836) (xy 16.6915 -52.528191) (xy 16.7306 -52.546048)
			(xy 21.679696 -52.546048) (xy 21.679696 -52.491552) (xy 21.687451 -52.43761) (xy 21.702804 -52.385321)
			(xy 21.725441 -52.335749) (xy 21.754902 -52.289902) (xy 21.790588 -52.248715) (xy 21.831772 -52.213025)
			(xy 21.877615 -52.183559) (xy 21.927185 -52.160917) (xy 21.979473 -52.145559) (xy 22.033414 -52.137799)
			(xy 22.060662 -52.13731) (xy 22.088032 -52.137796) (xy 22.14221 -52.145609) (xy 22.194713 -52.161093)
			(xy 22.24446 -52.18393) (xy 22.290428 -52.213651) (xy 22.31136 -52.23129) (xy 22.311614 -52.231544)
			(xy 22.318689 -52.237148) (xy 22.335615 -52.243383) (xy 22.344634 -52.243736) (xy 22.41169 -52.243736)
			(xy 22.420705 -52.243366) (xy 22.437622 -52.237127) (xy 22.44471 -52.231544) (xy 22.44471 -52.23129)
			(xy 22.444964 -52.23129) (xy 22.465897 -52.213649) (xy 22.511865 -52.183925) (xy 22.561611 -52.161079)
			(xy 22.614113 -52.145583) (xy 22.668291 -52.137754) (xy 22.723033 -52.137754) (xy 22.777211 -52.145583)
			(xy 22.829713 -52.161079) (xy 22.879459 -52.183925) (xy 22.925427 -52.213649) (xy 22.94636 -52.23129)
			(xy 22.946614 -52.231544) (xy 22.953689 -52.237148) (xy 22.970615 -52.243383) (xy 22.979634 -52.243736)
			(xy 23.04669 -52.243736) (xy 23.055705 -52.243366) (xy 23.072622 -52.237127) (xy 23.07971 -52.231544)
			(xy 23.07971 -52.23129) (xy 23.079964 -52.23129) (xy 23.100898 -52.213653) (xy 23.14687 -52.183941)
			(xy 23.196617 -52.161105) (xy 23.249118 -52.145613) (xy 23.303293 -52.137784) (xy 23.330662 -52.13731)
			(xy 23.357918 -52.137734) (xy 23.411876 -52.145487) (xy 23.464181 -52.160841) (xy 23.513768 -52.183482)
			(xy 23.559628 -52.212951) (xy 23.600827 -52.248646) (xy 23.636527 -52.289842) (xy 23.666 -52.335699)
			(xy 23.688646 -52.385284) (xy 23.704005 -52.437587) (xy 23.711763 -52.491544) (xy 23.711763 -52.546056)
			(xy 23.705819 -52.587398) (xy 24.755346 -52.587398) (xy 24.759417 -52.531776) (xy 24.771543 -52.477339)
			(xy 24.791466 -52.425248) (xy 24.818762 -52.376613) (xy 24.852848 -52.33247) (xy 24.892997 -52.293761)
			(xy 24.938355 -52.26131) (xy 24.987955 -52.235809) (xy 25.040739 -52.217802) (xy 25.095582 -52.207672)
			(xy 25.151316 -52.205635) (xy 25.206753 -52.211735) (xy 25.26071 -52.225841) (xy 25.312039 -52.247653)
			(xy 25.359645 -52.276707) (xy 25.402513 -52.312382) (xy 25.43973 -52.353919) (xy 25.470503 -52.400432)
			(xy 25.494175 -52.450929) (xy 25.510243 -52.504336) (xy 25.517839 -52.555949) (xy 32.583902 -52.555949)
			(xy 32.583902 -52.501451) (xy 32.591658 -52.447509) (xy 32.607011 -52.395219) (xy 32.629649 -52.345646)
			(xy 32.659112 -52.299799) (xy 32.694799 -52.258612) (xy 32.735985 -52.222923) (xy 32.78183 -52.193458)
			(xy 32.831402 -52.170817) (xy 32.883691 -52.155462) (xy 32.937633 -52.147703) (xy 32.964882 -52.147216)
			(xy 32.992252 -52.147689) (xy 33.046431 -52.155504) (xy 33.098934 -52.170992) (xy 33.148681 -52.193832)
			(xy 33.194648 -52.223555) (xy 33.21558 -52.241196) (xy 33.215834 -52.24145) (xy 33.222931 -52.247021)
			(xy 33.23984 -52.253276) (xy 33.248854 -52.253642) (xy 33.31591 -52.253642) (xy 33.324929 -52.253302)
			(xy 33.341846 -52.247044) (xy 33.34893 -52.24145) (xy 33.34893 -52.241196) (xy 33.349184 -52.241196)
			(xy 33.370111 -52.22355) (xy 33.416085 -52.19384) (xy 33.465834 -52.171005) (xy 33.518336 -52.155515)
			(xy 33.572512 -52.147689) (xy 33.599882 -52.147216) (xy 33.627137 -52.14763) (xy 33.681094 -52.155385)
			(xy 33.733397 -52.170741) (xy 33.782983 -52.193383) (xy 33.828841 -52.222853) (xy 33.870038 -52.258549)
			(xy 33.905736 -52.299745) (xy 33.935208 -52.345601) (xy 33.957853 -52.395186) (xy 33.973211 -52.447489)
			(xy 33.980969 -52.501445) (xy 33.980969 -52.555955) (xy 33.973211 -52.609911) (xy 33.957853 -52.662214)
			(xy 33.935208 -52.711799) (xy 33.905736 -52.757655) (xy 33.870038 -52.798851) (xy 33.828841 -52.834547)
			(xy 33.782983 -52.864017) (xy 33.733397 -52.886659) (xy 33.681094 -52.902015) (xy 33.627137 -52.90977)
			(xy 33.599882 -52.910232) (xy 33.572511 -52.909793) (xy 33.51833 -52.901971) (xy 33.465826 -52.886477)
			(xy 33.416079 -52.863629) (xy 33.370114 -52.833897) (xy 33.349184 -52.816252) (xy 33.34893 -52.815998)
			(xy 33.341839 -52.810418) (xy 33.324926 -52.804167) (xy 33.31591 -52.803806) (xy 33.248854 -52.803806)
			(xy 33.23984 -52.804188) (xy 33.222922 -52.810418) (xy 33.215834 -52.815998) (xy 33.215834 -52.816252)
			(xy 33.21558 -52.816252) (xy 33.194622 -52.83386) (xy 33.148657 -52.863578) (xy 33.098916 -52.886421)
			(xy 33.046421 -52.901919) (xy 32.99225 -52.909754) (xy 32.964882 -52.910232) (xy 32.937633 -52.909697)
			(xy 32.883691 -52.901938) (xy 32.831402 -52.886583) (xy 32.78183 -52.863942) (xy 32.735985 -52.834477)
			(xy 32.694799 -52.798788) (xy 32.659112 -52.757601) (xy 32.629649 -52.711754) (xy 32.607011 -52.662181)
			(xy 32.591658 -52.609891) (xy 32.583902 -52.555949) (xy 25.517839 -52.555949) (xy 25.518363 -52.559512)
			(xy 25.518872 -52.587398) (xy 25.518363 -52.615284) (xy 25.510243 -52.67046) (xy 25.494175 -52.723867)
			(xy 25.470503 -52.774364) (xy 25.43973 -52.820877) (xy 25.402513 -52.862414) (xy 25.359645 -52.898089)
			(xy 25.312039 -52.927143) (xy 25.26071 -52.948955) (xy 25.206753 -52.963061) (xy 25.151316 -52.969161)
			(xy 25.095582 -52.967124) (xy 25.040739 -52.956994) (xy 24.987955 -52.938987) (xy 24.938355 -52.913486)
			(xy 24.892997 -52.881035) (xy 24.852848 -52.842326) (xy 24.818762 -52.798183) (xy 24.791466 -52.749548)
			(xy 24.771543 -52.697457) (xy 24.759417 -52.64302) (xy 24.755346 -52.587398) (xy 23.705819 -52.587398)
			(xy 23.704005 -52.600013) (xy 23.688646 -52.652316) (xy 23.666 -52.701901) (xy 23.636527 -52.747758)
			(xy 23.600827 -52.788954) (xy 23.559628 -52.824649) (xy 23.513768 -52.854118) (xy 23.464181 -52.876759)
			(xy 23.411876 -52.892113) (xy 23.357918 -52.899866) (xy 23.330662 -52.900326) (xy 23.303292 -52.899842)
			(xy 23.249113 -52.892031) (xy 23.19661 -52.876547) (xy 23.146862 -52.853709) (xy 23.100895 -52.823987)
			(xy 23.079964 -52.806346) (xy 23.07971 -52.806092) (xy 23.072625 -52.800503) (xy 23.055707 -52.794258)
			(xy 23.04669 -52.7939) (xy 22.979634 -52.7939) (xy 22.970619 -52.794273) (xy 22.953702 -52.800509)
			(xy 22.946614 -52.806092) (xy 22.94636 -52.806346) (xy 22.925427 -52.823987) (xy 22.879459 -52.853711)
			(xy 22.829713 -52.876557) (xy 22.777211 -52.892053) (xy 22.723033 -52.899882) (xy 22.668291 -52.899882)
			(xy 22.614113 -52.892053) (xy 22.561611 -52.876557) (xy 22.511865 -52.853711) (xy 22.465897 -52.823987)
			(xy 22.444964 -52.806346) (xy 22.44471 -52.806092) (xy 22.437625 -52.800503) (xy 22.420707 -52.794258)
			(xy 22.41169 -52.7939) (xy 22.344634 -52.7939) (xy 22.335619 -52.794273) (xy 22.318702 -52.800509)
			(xy 22.311614 -52.806092) (xy 22.311614 -52.806346) (xy 22.31136 -52.806346) (xy 22.290409 -52.823962)
			(xy 22.244442 -52.853679) (xy 22.1947 -52.87652) (xy 22.142203 -52.892017) (xy 22.08803 -52.89985)
			(xy 22.060662 -52.900326) (xy 22.033414 -52.899801) (xy 21.979473 -52.892041) (xy 21.927185 -52.876683)
			(xy 21.877615 -52.854041) (xy 21.831772 -52.824575) (xy 21.790588 -52.788885) (xy 21.754902 -52.747698)
			(xy 21.725441 -52.701851) (xy 21.702804 -52.652279) (xy 21.687451 -52.59999) (xy 21.679696 -52.546048)
			(xy 16.7306 -52.546048) (xy 16.741077 -52.550833) (xy 16.786927 -52.580299) (xy 16.828118 -52.61599)
			(xy 16.863809 -52.657181) (xy 16.893275 -52.703031) (xy 16.915917 -52.752608) (xy 16.931272 -52.804903)
			(xy 16.939028 -52.858851) (xy 16.939514 -52.886102) (xy 16.939046 -52.913472) (xy 16.931228 -52.967651)
			(xy 16.915739 -53.020154) (xy 16.892898 -53.069901) (xy 16.863175 -53.115868) (xy 16.845534 -53.1368)
			(xy 16.84528 -53.137054) (xy 16.839704 -53.144148) (xy 16.833452 -53.161059) (xy 16.833088 -53.170074)
			(xy 16.833088 -53.23713) (xy 16.833434 -53.246148) (xy 16.839689 -53.263065) (xy 16.84528 -53.27015)
			(xy 16.845534 -53.27015) (xy 16.845534 -53.270404) (xy 16.863178 -53.291334) (xy 16.892906 -53.337302)
			(xy 16.915754 -53.387048) (xy 16.931251 -53.439551) (xy 16.939081 -53.49373) (xy 16.93908 -53.548473)
			(xy 16.931251 -53.602652) (xy 16.915753 -53.655155) (xy 16.892905 -53.704901) (xy 16.863176 -53.750868)
			(xy 16.846604 -53.77053) (xy 17.210786 -53.77053) (xy 17.211293 -53.741612) (xy 17.22002 -53.684439)
			(xy 17.237278 -53.629239) (xy 17.262671 -53.577276) (xy 17.295619 -53.529743) (xy 17.335364 -53.487728)
			(xy 17.357852 -53.46954) (xy 17.36664 -53.461915) (xy 17.376832 -53.441027) (xy 17.37741 -53.429408)
			(xy 17.37741 -53.349652) (xy 17.376881 -53.338019) (xy 17.366685 -53.31711) (xy 17.357852 -53.30952)
			(xy 17.335368 -53.29133) (xy 17.295635 -53.249308) (xy 17.262698 -53.201773) (xy 17.23731 -53.149812)
			(xy 17.220053 -53.094615) (xy 17.211322 -53.037446) (xy 17.210786 -53.00853) (xy 17.211283 -52.981278)
			(xy 17.219036 -52.927329) (xy 17.234388 -52.875032) (xy 17.257026 -52.825452) (xy 17.286491 -52.779599)
			(xy 17.322181 -52.738406) (xy 17.36337 -52.702712) (xy 17.409221 -52.673244) (xy 17.458798 -52.6506)
			(xy 17.511094 -52.635244) (xy 17.565042 -52.627486) (xy 17.592294 -52.627022) (xy 17.618608 -52.627486)
			(xy 17.670737 -52.634721) (xy 17.72138 -52.64904) (xy 17.769579 -52.670173) (xy 17.814423 -52.69772)
			(xy 17.855062 -52.73116) (xy 17.873218 -52.750212) (xy 17.880729 -52.757625) (xy 17.900017 -52.766143)
			(xy 17.910556 -52.766722) (xy 17.985232 -52.766722) (xy 17.995778 -52.766163) (xy 18.015073 -52.757648)
			(xy 18.02257 -52.750212) (xy 18.04075 -52.73118) (xy 18.081374 -52.697721) (xy 18.126209 -52.670158)
			(xy 18.174405 -52.649015) (xy 18.225049 -52.634693) (xy 18.277179 -52.627463) (xy 18.303494 -52.627022)
			(xy 18.330748 -52.627461) (xy 18.384701 -52.635218) (xy 18.437002 -52.650575) (xy 18.486584 -52.673219)
			(xy 18.532438 -52.702689) (xy 18.573632 -52.738385) (xy 18.609326 -52.779581) (xy 18.638793 -52.825437)
			(xy 18.661434 -52.875021) (xy 18.676787 -52.927322) (xy 18.684541 -52.981276) (xy 18.685002 -53.00853)
			(xy 18.684512 -53.036196) (xy 18.682281 -53.051456) (xy 26.94127 -53.051456) (xy 26.945341 -52.995834)
			(xy 26.957467 -52.941397) (xy 26.97739 -52.889306) (xy 27.004686 -52.840671) (xy 27.038772 -52.796528)
			(xy 27.078921 -52.757819) (xy 27.124279 -52.725368) (xy 27.173879 -52.699867) (xy 27.226663 -52.68186)
			(xy 27.281506 -52.67173) (xy 27.33724 -52.669693) (xy 27.392677 -52.675793) (xy 27.446634 -52.689899)
			(xy 27.497963 -52.711711) (xy 27.545569 -52.740765) (xy 27.588437 -52.77644) (xy 27.625654 -52.817977)
			(xy 27.656427 -52.86449) (xy 27.680099 -52.914987) (xy 27.696167 -52.968394) (xy 27.704287 -53.02357)
			(xy 27.704796 -53.051456) (xy 27.704287 -53.079342) (xy 27.696167 -53.134518) (xy 27.680099 -53.187925)
			(xy 27.656427 -53.238422) (xy 27.625654 -53.284935) (xy 27.588437 -53.326472) (xy 27.545569 -53.362147)
			(xy 27.497963 -53.391201) (xy 27.446634 -53.413013) (xy 27.392677 -53.427119) (xy 27.33724 -53.433219)
			(xy 27.281506 -53.431182) (xy 27.226663 -53.421052) (xy 27.173879 -53.403045) (xy 27.124279 -53.377544)
			(xy 27.078921 -53.345093) (xy 27.038772 -53.306384) (xy 27.004686 -53.262241) (xy 26.97739 -53.213606)
			(xy 26.957467 -53.161515) (xy 26.945341 -53.107078) (xy 26.94127 -53.051456) (xy 18.682281 -53.051456)
			(xy 18.676509 -53.090946) (xy 18.660688 -53.143968) (xy 18.637381 -53.194152) (xy 18.607077 -53.240448)
			(xy 18.570409 -53.281885) (xy 18.528144 -53.317597) (xy 18.504916 -53.332634) (xy 18.495219 -53.339246)
			(xy 18.482787 -53.359126) (xy 18.48104 -53.370734) (xy 18.473166 -53.450744) (xy 18.47251 -53.462383)
			(xy 18.480606 -53.484222) (xy 18.48866 -53.492654) (xy 18.488914 -53.492908) (xy 18.507484 -53.511)
			(xy 18.540063 -53.55133) (xy 18.566877 -53.595702) (xy 18.587432 -53.643298) (xy 18.601348 -53.69324)
			(xy 18.608368 -53.744608) (xy 18.608802 -53.77053) (xy 18.60835 -53.797782) (xy 18.600589 -53.851732)
			(xy 18.58523 -53.904027) (xy 18.562585 -53.953605) (xy 18.533115 -53.999456) (xy 18.49742 -54.040646)
			(xy 18.456227 -54.076337) (xy 18.410373 -54.105802) (xy 18.360793 -54.128443) (xy 18.308496 -54.143797)
			(xy 18.254546 -54.151553) (xy 18.227294 -54.152038) (xy 18.199923 -54.151591) (xy 18.145742 -54.143771)
			(xy 18.093239 -54.128278) (xy 18.043492 -54.105432) (xy 17.997526 -54.075702) (xy 17.976596 -54.058058)
			(xy 17.976342 -54.057804) (xy 17.969247 -54.052229) (xy 17.952337 -54.045975) (xy 17.943322 -54.045612)
			(xy 17.876266 -54.045612) (xy 17.867247 -54.04595) (xy 17.85033 -54.052211) (xy 17.843246 -54.057804)
			(xy 17.843246 -54.058058) (xy 17.842992 -54.058058) (xy 17.822068 -54.075708) (xy 17.776094 -54.105419)
			(xy 17.726344 -54.128254) (xy 17.673842 -54.143742) (xy 17.619664 -54.151567) (xy 17.592294 -54.152038)
			(xy 17.565044 -54.151528) (xy 17.511099 -54.143771) (xy 17.458806 -54.128417) (xy 17.409231 -54.105777)
			(xy 17.363382 -54.076313) (xy 17.322193 -54.040624) (xy 17.286501 -53.999437) (xy 17.257034 -53.95359)
			(xy 17.234391 -53.904016) (xy 17.219034 -53.851725) (xy 17.211274 -53.79778) (xy 17.210786 -53.77053)
			(xy 16.846604 -53.77053) (xy 16.845534 -53.7718) (xy 16.84528 -53.772054) (xy 16.839704 -53.779148)
			(xy 16.833452 -53.796059) (xy 16.833088 -53.805074) (xy 16.833088 -53.87213) (xy 16.833434 -53.881148)
			(xy 16.839689 -53.898065) (xy 16.84528 -53.90515) (xy 16.845534 -53.90515) (xy 16.845534 -53.905404)
			(xy 16.863178 -53.926334) (xy 16.892906 -53.972302) (xy 16.915754 -54.022048) (xy 16.931251 -54.074551)
			(xy 16.939081 -54.12873) (xy 16.93908 -54.183473) (xy 16.931251 -54.237652) (xy 16.915753 -54.290155)
			(xy 16.90196 -54.320186) (xy 19.130518 -54.320186) (xy 19.130971 -54.292815) (xy 19.138792 -54.238635)
			(xy 19.154283 -54.186132) (xy 19.177128 -54.136385) (xy 19.206855 -54.090419) (xy 19.224498 -54.069488)
			(xy 19.224752 -54.069234) (xy 19.230337 -54.062146) (xy 19.236583 -54.04523) (xy 19.236944 -54.036214)
			(xy 19.236944 -53.969158) (xy 19.236572 -53.960142) (xy 19.230336 -53.943225) (xy 19.224752 -53.936138)
			(xy 19.224498 -53.936138) (xy 19.224498 -53.935884) (xy 19.206885 -53.914931) (xy 19.177169 -53.868964)
			(xy 19.154328 -53.819222) (xy 19.138831 -53.766726) (xy 19.130996 -53.712554) (xy 19.130518 -53.685186)
			(xy 19.131004 -53.657935) (xy 19.13876 -53.603987) (xy 19.154115 -53.551692) (xy 19.176757 -53.502115)
			(xy 19.206223 -53.456265) (xy 19.241914 -53.415074) (xy 19.283105 -53.379383) (xy 19.328955 -53.349917)
			(xy 19.378532 -53.327275) (xy 19.430827 -53.31192) (xy 19.484775 -53.304164) (xy 19.539277 -53.304164)
			(xy 19.593225 -53.31192) (xy 19.64552 -53.327275) (xy 19.695097 -53.349917) (xy 19.740947 -53.379383)
			(xy 19.782138 -53.415074) (xy 19.817829 -53.456265) (xy 19.843722 -53.496556) (xy 32.133441 -53.496556)
			(xy 32.133441 -53.442044) (xy 32.141199 -53.388088) (xy 32.156558 -53.335785) (xy 32.179204 -53.2862)
			(xy 32.208677 -53.240343) (xy 32.244376 -53.199148) (xy 32.285575 -53.163453) (xy 32.331435 -53.133985)
			(xy 32.381022 -53.111344) (xy 32.433327 -53.095991) (xy 32.487284 -53.088238) (xy 32.51454 -53.087778)
			(xy 32.54191 -53.08826) (xy 32.596089 -53.096071) (xy 32.648593 -53.111555) (xy 32.69834 -53.134394)
			(xy 32.744307 -53.164117) (xy 32.765238 -53.181758) (xy 32.765492 -53.182012) (xy 32.772576 -53.187603)
			(xy 32.789495 -53.193847) (xy 32.798512 -53.194204) (xy 32.865568 -53.194204) (xy 32.874583 -53.193831)
			(xy 32.8915 -53.187594) (xy 32.898588 -53.182012) (xy 32.898588 -53.181758) (xy 32.898842 -53.181758)
			(xy 32.919779 -53.164126) (xy 32.965751 -53.134414) (xy 33.015498 -53.111578) (xy 33.067997 -53.096085)
			(xy 33.122171 -53.088253) (xy 33.14954 -53.087778) (xy 33.176788 -53.088295) (xy 33.23073 -53.096056)
			(xy 33.283018 -53.111414) (xy 33.332588 -53.134056) (xy 33.378432 -53.163523) (xy 33.419616 -53.199213)
			(xy 33.455301 -53.2404) (xy 33.484763 -53.286247) (xy 33.5074 -53.33582) (xy 33.522753 -53.388109)
			(xy 33.530508 -53.442052) (xy 33.530508 -53.496548) (xy 33.522753 -53.550491) (xy 33.5074 -53.60278)
			(xy 33.484763 -53.652353) (xy 33.455301 -53.6982) (xy 33.419616 -53.739387) (xy 33.378432 -53.775077)
			(xy 33.332588 -53.804544) (xy 33.283018 -53.827186) (xy 33.23073 -53.842544) (xy 33.176788 -53.850305)
			(xy 33.14954 -53.850794) (xy 33.122171 -53.850306) (xy 33.067992 -53.842494) (xy 33.015489 -53.82701)
			(xy 32.965742 -53.804173) (xy 32.919774 -53.774453) (xy 32.898842 -53.756814) (xy 32.898588 -53.75656)
			(xy 32.891513 -53.750957) (xy 32.874587 -53.744721) (xy 32.865568 -53.744368) (xy 32.798512 -53.744368)
			(xy 32.789497 -53.744738) (xy 32.77258 -53.750977) (xy 32.765492 -53.75656) (xy 32.765492 -53.756814)
			(xy 32.765238 -53.756814) (xy 32.744304 -53.774451) (xy 32.698332 -53.804163) (xy 32.648585 -53.826999)
			(xy 32.596084 -53.84249) (xy 32.541909 -53.850319) (xy 32.51454 -53.850794) (xy 32.487284 -53.850362)
			(xy 32.433327 -53.842609) (xy 32.381022 -53.827256) (xy 32.331435 -53.804615) (xy 32.285575 -53.775147)
			(xy 32.244376 -53.739452) (xy 32.208677 -53.698257) (xy 32.179204 -53.6524) (xy 32.156558 -53.602815)
			(xy 32.141199 -53.550512) (xy 32.133441 -53.496556) (xy 19.843722 -53.496556) (xy 19.847295 -53.502115)
			(xy 19.869937 -53.551692) (xy 19.885292 -53.603987) (xy 19.893048 -53.657935) (xy 19.893534 -53.685186)
			(xy 19.893076 -53.712557) (xy 19.885259 -53.766737) (xy 19.869769 -53.819241) (xy 19.846925 -53.868987)
			(xy 19.817197 -53.914953) (xy 19.799554 -53.935884) (xy 19.7993 -53.936138) (xy 19.793733 -53.943238)
			(xy 19.787475 -53.960145) (xy 19.787108 -53.969158) (xy 19.787108 -54.036214) (xy 19.787457 -54.045232)
			(xy 19.79371 -54.062149) (xy 19.7993 -54.069234) (xy 19.799554 -54.069234) (xy 19.799554 -54.069488)
			(xy 19.817194 -54.09042) (xy 19.846907 -54.136392) (xy 19.869744 -54.186139) (xy 19.885234 -54.23864)
			(xy 19.893061 -54.292817) (xy 19.893534 -54.320186) (xy 19.893048 -54.347437) (xy 19.885292 -54.401385)
			(xy 19.869937 -54.45368) (xy 19.847295 -54.503257) (xy 19.817829 -54.549107) (xy 19.782138 -54.590298)
			(xy 19.740947 -54.625989) (xy 19.695097 -54.655455) (xy 19.64552 -54.678097) (xy 19.593225 -54.693452)
			(xy 19.539277 -54.701208) (xy 19.484775 -54.701208) (xy 19.430827 -54.693452) (xy 19.378532 -54.678097)
			(xy 19.328955 -54.655455) (xy 19.283105 -54.625989) (xy 19.241914 -54.590298) (xy 19.206223 -54.549107)
			(xy 19.176757 -54.503257) (xy 19.154115 -54.45368) (xy 19.13876 -54.401385) (xy 19.131004 -54.347437)
			(xy 19.130518 -54.320186) (xy 16.90196 -54.320186) (xy 16.892905 -54.339901) (xy 16.863176 -54.385868)
			(xy 16.845534 -54.4068) (xy 16.84528 -54.407054) (xy 16.839704 -54.414148) (xy 16.833452 -54.431059)
			(xy 16.833088 -54.440074) (xy 16.833088 -54.50713) (xy 16.833434 -54.516148) (xy 16.839689 -54.533065)
			(xy 16.84528 -54.54015) (xy 16.845534 -54.54015) (xy 16.845534 -54.540404) (xy 16.863194 -54.561319)
			(xy 16.892901 -54.607297) (xy 16.915733 -54.657049) (xy 16.931219 -54.709553) (xy 16.939042 -54.763732)
			(xy 16.939159 -54.770528) (xy 20.07108 -54.770528) (xy 20.071543 -54.743157) (xy 20.079359 -54.688977)
			(xy 20.094847 -54.636474) (xy 20.11769 -54.586727) (xy 20.147417 -54.540761) (xy 20.16506 -54.51983)
			(xy 20.165314 -54.519576) (xy 20.170918 -54.512502) (xy 20.177154 -54.495575) (xy 20.177506 -54.486556)
			(xy 20.177506 -54.4195) (xy 20.177148 -54.410483) (xy 20.170901 -54.393566) (xy 20.165314 -54.38648)
			(xy 20.16506 -54.38648) (xy 20.16506 -54.386226) (xy 20.147413 -54.3653) (xy 20.117704 -54.319325)
			(xy 20.09487 -54.269576) (xy 20.07938 -54.217074) (xy 20.071553 -54.162898) (xy 20.07108 -54.135528)
			(xy 20.071566 -54.108277) (xy 20.079322 -54.054329) (xy 20.094677 -54.002034) (xy 20.117319 -53.952457)
			(xy 20.146785 -53.906607) (xy 20.182476 -53.865416) (xy 20.223667 -53.829725) (xy 20.269517 -53.800259)
			(xy 20.319094 -53.777617) (xy 20.371389 -53.762262) (xy 20.425337 -53.754506) (xy 20.479839 -53.754506)
			(xy 20.533787 -53.762262) (xy 20.586082 -53.777617) (xy 20.635659 -53.800259) (xy 20.681509 -53.829725)
			(xy 20.7227 -53.865416) (xy 20.758391 -53.906607) (xy 20.787857 -53.952457) (xy 20.792932 -53.96357)
			(xy 24.77211 -53.96357) (xy 24.776181 -53.907948) (xy 24.788307 -53.853511) (xy 24.80823 -53.80142)
			(xy 24.835526 -53.752785) (xy 24.869612 -53.708642) (xy 24.909761 -53.669933) (xy 24.955119 -53.637482)
			(xy 25.004719 -53.611981) (xy 25.057503 -53.593974) (xy 25.112346 -53.583844) (xy 25.16808 -53.581807)
			(xy 25.223517 -53.587907) (xy 25.277474 -53.602013) (xy 25.328803 -53.623825) (xy 25.376409 -53.652879)
			(xy 25.419277 -53.688554) (xy 25.456494 -53.730091) (xy 25.487267 -53.776604) (xy 25.510939 -53.827101)
			(xy 25.527007 -53.880508) (xy 25.535127 -53.935684) (xy 25.535636 -53.96357) (xy 25.535127 -53.991456)
			(xy 25.527007 -54.046632) (xy 25.510939 -54.100039) (xy 25.487267 -54.150536) (xy 25.456494 -54.197049)
			(xy 25.419277 -54.238586) (xy 25.376409 -54.274261) (xy 25.328803 -54.303315) (xy 25.277474 -54.325127)
			(xy 25.223517 -54.339233) (xy 25.16808 -54.345333) (xy 25.112346 -54.343296) (xy 25.057503 -54.333166)
			(xy 25.004719 -54.315159) (xy 24.955119 -54.289658) (xy 24.909761 -54.257207) (xy 24.869612 -54.218498)
			(xy 24.835526 -54.174355) (xy 24.80823 -54.12572) (xy 24.788307 -54.073629) (xy 24.776181 -54.019192)
			(xy 24.77211 -53.96357) (xy 20.792932 -53.96357) (xy 20.810499 -54.002034) (xy 20.825854 -54.054329)
			(xy 20.83361 -54.108277) (xy 20.834096 -54.135528) (xy 20.833647 -54.162899) (xy 20.825825 -54.217079)
			(xy 20.810332 -54.269582) (xy 20.787487 -54.319329) (xy 20.757759 -54.365295) (xy 20.740116 -54.386226)
			(xy 20.739862 -54.38648) (xy 20.734273 -54.393565) (xy 20.728029 -54.410483) (xy 20.72767 -54.4195)
			(xy 20.72767 -54.486556) (xy 20.728055 -54.49557) (xy 20.734284 -54.512487) (xy 20.739862 -54.519576)
			(xy 20.740116 -54.519576) (xy 20.740116 -54.51983) (xy 20.757738 -54.540776) (xy 20.787452 -54.586745)
			(xy 20.810291 -54.636489) (xy 20.825786 -54.688987) (xy 20.833619 -54.74316) (xy 20.834096 -54.770528)
			(xy 20.83361 -54.797779) (xy 20.825854 -54.851727) (xy 20.810499 -54.904022) (xy 20.787857 -54.953599)
			(xy 20.765071 -54.989055) (xy 29.901045 -54.989055) (xy 29.901045 -54.934545) (xy 29.908803 -54.880589)
			(xy 29.924161 -54.828287) (xy 29.946807 -54.778704) (xy 29.976279 -54.732848) (xy 30.011977 -54.691653)
			(xy 30.053175 -54.655958) (xy 30.099034 -54.62649) (xy 30.148619 -54.603849) (xy 30.200923 -54.588496)
			(xy 30.254879 -54.580743) (xy 30.282134 -54.580282) (xy 30.310226 -54.58075) (xy 30.365805 -54.588982)
			(xy 30.419575 -54.605278) (xy 30.470372 -54.629285) (xy 30.517098 -54.660484) (xy 30.558743 -54.698199)
			(xy 30.594404 -54.741616) (xy 30.609286 -54.765448) (xy 30.61462 -54.774338) (xy 30.631638 -54.78653)
			(xy 30.724856 -54.80685) (xy 30.74543 -54.802532) (xy 30.754066 -54.79669) (xy 30.778137 -54.780701)
			(xy 30.830066 -54.755356) (xy 30.885222 -54.738127) (xy 30.942344 -54.729409) (xy 30.971236 -54.728872)
			(xy 30.998487 -54.729344) (xy 31.052434 -54.737105) (xy 31.104728 -54.752464) (xy 31.154304 -54.775108)
			(xy 31.200153 -54.804576) (xy 31.241343 -54.840269) (xy 31.277034 -54.881459) (xy 31.3065 -54.92731)
			(xy 31.329142 -54.976887) (xy 31.344498 -55.029181) (xy 31.352257 -55.083129) (xy 31.352744 -55.11038)
			(xy 31.35228 -55.13775) (xy 31.344464 -55.19193) (xy 31.328975 -55.244434) (xy 31.306132 -55.294181)
			(xy 31.276406 -55.340147) (xy 31.258764 -55.361078) (xy 31.25851 -55.361332) (xy 31.252947 -55.368435)
			(xy 31.246686 -55.385339) (xy 31.246318 -55.394352) (xy 31.246318 -55.461408) (xy 31.246667 -55.470426)
			(xy 31.25292 -55.487343) (xy 31.25851 -55.494428) (xy 31.258764 -55.494428) (xy 31.258764 -55.494682)
			(xy 31.276385 -55.51563) (xy 31.306112 -55.561595) (xy 31.328959 -55.611339) (xy 31.344457 -55.663839)
			(xy 31.352288 -55.718015) (xy 31.35229 -55.772755) (xy 31.344463 -55.826932) (xy 31.328969 -55.879433)
			(xy 31.306126 -55.929178) (xy 31.276404 -55.975145) (xy 31.258764 -55.996078) (xy 31.25851 -55.996332)
			(xy 31.252947 -56.003435) (xy 31.246686 -56.020339) (xy 31.246318 -56.029352) (xy 31.246318 -56.096408)
			(xy 31.246667 -56.105426) (xy 31.25292 -56.122343) (xy 31.25851 -56.129428) (xy 31.258764 -56.129428)
			(xy 31.258764 -56.129682) (xy 31.276403 -56.150615) (xy 31.306116 -56.196587) (xy 31.328952 -56.246334)
			(xy 31.344443 -56.298835) (xy 31.352271 -56.353011) (xy 31.352744 -56.38038) (xy 31.352258 -56.407631)
			(xy 31.344502 -56.461579) (xy 31.329147 -56.513874) (xy 31.306505 -56.563451) (xy 31.277039 -56.609301)
			(xy 31.241348 -56.650492) (xy 31.200157 -56.686183) (xy 31.154307 -56.715649) (xy 31.10473 -56.738291)
			(xy 31.052435 -56.753646) (xy 30.998487 -56.761402) (xy 30.943985 -56.761402) (xy 30.890037 -56.753646)
			(xy 30.837742 -56.738291) (xy 30.788165 -56.715649) (xy 30.742315 -56.686183) (xy 30.701124 -56.650492)
			(xy 30.665433 -56.609301) (xy 30.635967 -56.563451) (xy 30.613325 -56.513874) (xy 30.59797 -56.461579)
			(xy 30.590214 -56.407631) (xy 30.589728 -56.38038) (xy 30.590176 -56.353009) (xy 30.597997 -56.298829)
			(xy 30.61349 -56.246325) (xy 30.636336 -56.196579) (xy 30.666065 -56.150613) (xy 30.683708 -56.129682)
			(xy 30.683962 -56.129428) (xy 30.68955 -56.122343) (xy 30.695794 -56.105425) (xy 30.696154 -56.096408)
			(xy 30.696154 -56.029352) (xy 30.695782 -56.020336) (xy 30.689546 -56.003419) (xy 30.683962 -55.996332)
			(xy 30.683708 -55.996332) (xy 30.683708 -55.996078) (xy 30.666049 -55.975161) (xy 30.636326 -55.92919)
			(xy 30.613483 -55.879441) (xy 30.597989 -55.826937) (xy 30.590163 -55.772756) (xy 30.590165 -55.718014)
			(xy 30.597995 -55.663834) (xy 30.613494 -55.611331) (xy 30.63634 -55.561584) (xy 30.666067 -55.515615)
			(xy 30.683708 -55.494682) (xy 30.683962 -55.494428) (xy 30.68955 -55.487343) (xy 30.695794 -55.470425)
			(xy 30.696154 -55.461408) (xy 30.696154 -55.394352) (xy 30.695782 -55.385336) (xy 30.689546 -55.368419)
			(xy 30.683962 -55.361332) (xy 30.683708 -55.360824) (xy 30.672765 -55.348089) (xy 30.652923 -55.320998)
			(xy 30.644084 -55.306722) (xy 30.63875 -55.297832) (xy 30.621732 -55.28564) (xy 30.528514 -55.26532)
			(xy 30.50794 -55.269638) (xy 30.499304 -55.27548) (xy 30.475239 -55.291478) (xy 30.423308 -55.316822)
			(xy 30.368151 -55.334048) (xy 30.311026 -55.342763) (xy 30.282134 -55.343298) (xy 30.254879 -55.342857)
			(xy 30.200923 -55.335104) (xy 30.148619 -55.319751) (xy 30.099034 -55.29711) (xy 30.053175 -55.267642)
			(xy 30.011977 -55.231947) (xy 29.976279 -55.190752) (xy 29.946807 -55.144896) (xy 29.924161 -55.095313)
			(xy 29.908803 -55.043011) (xy 29.901045 -54.989055) (xy 20.765071 -54.989055) (xy 20.758391 -54.999449)
			(xy 20.7227 -55.04064) (xy 20.681509 -55.076331) (xy 20.635659 -55.105797) (xy 20.586082 -55.128439)
			(xy 20.533787 -55.143794) (xy 20.479839 -55.15155) (xy 20.425337 -55.15155) (xy 20.371389 -55.143794)
			(xy 20.319094 -55.128439) (xy 20.269517 -55.105797) (xy 20.223667 -55.076331) (xy 20.182476 -55.04064)
			(xy 20.146785 -54.999449) (xy 20.117319 -54.953599) (xy 20.094677 -54.904022) (xy 20.079322 -54.851727)
			(xy 20.071566 -54.797779) (xy 20.07108 -54.770528) (xy 16.939159 -54.770528) (xy 16.939514 -54.791102)
			(xy 16.939028 -54.818353) (xy 16.931272 -54.872301) (xy 16.915917 -54.924596) (xy 16.893275 -54.974173)
			(xy 16.863809 -55.020023) (xy 16.828118 -55.061214) (xy 16.786927 -55.096905) (xy 16.741077 -55.126371)
			(xy 16.6915 -55.149013) (xy 16.639205 -55.164368) (xy 16.585257 -55.172124) (xy 16.530755 -55.172124)
			(xy 16.476807 -55.164368) (xy 16.424512 -55.149013) (xy 16.374935 -55.126371) (xy 16.329085 -55.096905)
			(xy 16.287894 -55.061214) (xy 16.252203 -55.020023) (xy 16.222737 -54.974173) (xy 16.200095 -54.924596)
			(xy 16.18474 -54.872301) (xy 16.176984 -54.818353) (xy 16.176498 -54.791102) (xy 14.27854 -54.791102)
			(xy 14.275448 -54.812611) (xy 14.260093 -54.864906) (xy 14.237451 -54.914483) (xy 14.207985 -54.960333)
			(xy 14.172294 -55.001524) (xy 14.131103 -55.037215) (xy 14.085253 -55.066681) (xy 14.035676 -55.089323)
			(xy 13.983381 -55.104678) (xy 13.929433 -55.112434) (xy 13.874931 -55.112434) (xy 13.820983 -55.104678)
			(xy 13.768688 -55.089323) (xy 13.719111 -55.066681) (xy 13.673261 -55.037215) (xy 13.63207 -55.001524)
			(xy 13.596379 -54.960333) (xy 13.566913 -54.914483) (xy 13.544271 -54.864906) (xy 13.528916 -54.812611)
			(xy 13.52116 -54.758663) (xy 13.520674 -54.731412) (xy 5.012973 -54.731412) (xy 5.052492 -54.737094)
			(xy 5.104789 -54.75245) (xy 5.15437 -54.775092) (xy 5.200223 -54.80456) (xy 5.241415 -54.840253)
			(xy 5.277109 -54.881446) (xy 5.306577 -54.927299) (xy 5.32922 -54.976879) (xy 5.344576 -55.029176)
			(xy 5.352333 -55.083127) (xy 5.352796 -55.11038) (xy 5.352319 -55.13775) (xy 5.344504 -55.191929)
			(xy 5.329018 -55.244432) (xy 5.306178 -55.294179) (xy 5.276456 -55.340146) (xy 5.258816 -55.361078)
			(xy 5.258562 -55.361332) (xy 5.252994 -55.368431) (xy 5.246737 -55.385338) (xy 5.24637 -55.394352)
			(xy 5.24637 -55.461408) (xy 5.24673 -55.470424) (xy 5.252976 -55.487341) (xy 5.258562 -55.494428)
			(xy 5.258816 -55.494428) (xy 5.258816 -55.494682) (xy 5.276457 -55.515615) (xy 5.306181 -55.561583)
			(xy 5.329026 -55.611329) (xy 5.344522 -55.663831) (xy 5.352351 -55.718009) (xy 5.352351 -55.722266)
			(xy 25.834084 -55.722266) (xy 25.838155 -55.666644) (xy 25.850281 -55.612207) (xy 25.870204 -55.560116)
			(xy 25.8975 -55.511481) (xy 25.931586 -55.467338) (xy 25.971735 -55.428629) (xy 26.017093 -55.396178)
			(xy 26.066693 -55.370677) (xy 26.119477 -55.35267) (xy 26.17432 -55.34254) (xy 26.230054 -55.340503)
			(xy 26.285491 -55.346603) (xy 26.339448 -55.360709) (xy 26.390777 -55.382521) (xy 26.438383 -55.411575)
			(xy 26.449534 -55.420855) (xy 28.224645 -55.420855) (xy 28.224645 -55.366345) (xy 28.232403 -55.312389)
			(xy 28.247761 -55.260087) (xy 28.270407 -55.210504) (xy 28.299879 -55.164648) (xy 28.335577 -55.123453)
			(xy 28.376775 -55.087758) (xy 28.422634 -55.05829) (xy 28.472219 -55.035649) (xy 28.524523 -55.020296)
			(xy 28.578479 -55.012543) (xy 28.605734 -55.012082) (xy 28.632048 -55.012533) (xy 28.684177 -55.019772)
			(xy 28.73482 -55.034094) (xy 28.783019 -55.05523) (xy 28.827862 -55.082779) (xy 28.868502 -55.11622)
			(xy 28.886658 -55.135272) (xy 28.894197 -55.142653) (xy 28.913464 -55.15119) (xy 28.923996 -55.151782)
			(xy 28.998672 -55.151782) (xy 29.009222 -55.151257) (xy 29.028518 -55.142719) (xy 29.03601 -55.135272)
			(xy 29.054162 -55.116213) (xy 29.094793 -55.082757) (xy 29.139634 -55.0552) (xy 29.187836 -55.034062)
			(xy 29.238484 -55.019745) (xy 29.290618 -55.012521) (xy 29.316934 -55.012082) (xy 29.344183 -55.012591)
			(xy 29.398125 -55.020351) (xy 29.450415 -55.035708) (xy 29.499986 -55.058351) (xy 29.545831 -55.087817)
			(xy 29.587016 -55.123508) (xy 29.622703 -55.164696) (xy 29.652165 -55.210544) (xy 29.674803 -55.260117)
			(xy 29.690156 -55.312408) (xy 29.697912 -55.366351) (xy 29.697912 -55.420849) (xy 29.690156 -55.474792)
			(xy 29.674803 -55.527083) (xy 29.652165 -55.576656) (xy 29.622703 -55.622504) (xy 29.587016 -55.663692)
			(xy 29.545831 -55.699383) (xy 29.499986 -55.728849) (xy 29.450415 -55.751492) (xy 29.398125 -55.766849)
			(xy 29.344183 -55.774609) (xy 29.316934 -55.775098) (xy 29.290619 -55.774675) (xy 29.238488 -55.767431)
			(xy 29.187844 -55.753104) (xy 29.139646 -55.731963) (xy 29.094803 -55.704409) (xy 29.054165 -55.670963)
			(xy 29.03601 -55.651908) (xy 29.028485 -55.64451) (xy 29.009208 -55.635983) (xy 28.998672 -55.635398)
			(xy 28.923996 -55.635398) (xy 28.913445 -55.635912) (xy 28.894149 -55.644458) (xy 28.886658 -55.651908)
			(xy 28.868517 -55.670978) (xy 28.827884 -55.704434) (xy 28.783041 -55.731991) (xy 28.734837 -55.753127)
			(xy 28.684187 -55.767441) (xy 28.632051 -55.774662) (xy 28.605734 -55.775098) (xy 28.578479 -55.774657)
			(xy 28.524523 -55.766904) (xy 28.472219 -55.751551) (xy 28.422634 -55.72891) (xy 28.376775 -55.699442)
			(xy 28.335577 -55.663747) (xy 28.299879 -55.622552) (xy 28.270407 -55.576696) (xy 28.247761 -55.527113)
			(xy 28.232403 -55.474811) (xy 28.224645 -55.420855) (xy 26.449534 -55.420855) (xy 26.481251 -55.44725)
			(xy 26.518468 -55.488787) (xy 26.549241 -55.5353) (xy 26.572913 -55.585797) (xy 26.588981 -55.639204)
			(xy 26.597101 -55.69438) (xy 26.59761 -55.722266) (xy 26.597101 -55.750152) (xy 26.588981 -55.805328)
			(xy 26.572913 -55.858735) (xy 26.549241 -55.909232) (xy 26.518468 -55.955745) (xy 26.481251 -55.997282)
			(xy 26.438383 -56.032957) (xy 26.390777 -56.062011) (xy 26.339448 -56.083823) (xy 26.285491 -56.097929)
			(xy 26.230054 -56.104029) (xy 26.17432 -56.101992) (xy 26.119477 -56.091862) (xy 26.066693 -56.073855)
			(xy 26.017093 -56.048354) (xy 25.971735 -56.015903) (xy 25.931586 -55.977194) (xy 25.8975 -55.933051)
			(xy 25.870204 -55.884416) (xy 25.850281 -55.832325) (xy 25.838155 -55.777888) (xy 25.834084 -55.722266)
			(xy 5.352351 -55.722266) (xy 5.352351 -55.772751) (xy 5.344522 -55.826929) (xy 5.329026 -55.879431)
			(xy 5.306181 -55.929177) (xy 5.276457 -55.975145) (xy 5.258816 -55.996078) (xy 5.258562 -55.996332)
			(xy 5.252994 -56.003431) (xy 5.246737 -56.020338) (xy 5.24637 -56.029352) (xy 5.24637 -56.096408)
			(xy 5.24673 -56.105424) (xy 5.252976 -56.122341) (xy 5.258562 -56.129428) (xy 5.258816 -56.129428)
			(xy 5.258816 -56.129682) (xy 5.276463 -56.150608) (xy 5.306173 -56.196583) (xy 5.329007 -56.246332)
			(xy 5.344496 -56.298834) (xy 5.352323 -56.35301) (xy 5.352796 -56.38038) (xy 5.35231 -56.407631)
			(xy 5.344554 -56.461579) (xy 5.329199 -56.513874) (xy 5.306557 -56.563451) (xy 5.277091 -56.609301)
			(xy 5.2414 -56.650492) (xy 5.200209 -56.686183) (xy 5.154359 -56.715649) (xy 5.104782 -56.738291)
			(xy 5.052487 -56.753646) (xy 4.998539 -56.761402) (xy 4.944037 -56.761402) (xy 4.890089 -56.753646)
			(xy 4.837794 -56.738291) (xy 4.788217 -56.715649) (xy 4.742367 -56.686183) (xy 4.701176 -56.650492)
			(xy 4.665485 -56.609301) (xy 4.636019 -56.563451) (xy 4.613377 -56.513874) (xy 4.598022 -56.461579)
			(xy 4.590266 -56.407631) (xy 4.58978 -56.38038) (xy 4.590215 -56.353008) (xy 4.598037 -56.298827)
			(xy 4.613533 -56.246323) (xy 4.636382 -56.196577) (xy 4.666114 -56.150612) (xy 4.68376 -56.129682)
			(xy 4.684014 -56.129428) (xy 4.689597 -56.122339) (xy 4.695845 -56.105424) (xy 4.696206 -56.096408)
			(xy 4.696206 -56.029352) (xy 4.695823 -56.020338) (xy 4.689593 -56.003421) (xy 4.684014 -55.996332)
			(xy 4.68376 -55.996332) (xy 4.68376 -55.996078) (xy 4.666119 -55.975145) (xy 4.636394 -55.929178)
			(xy 4.613549 -55.879431) (xy 4.598052 -55.826929) (xy 4.590224 -55.772751) (xy 4.590224 -55.718009)
			(xy 4.598052 -55.663831) (xy 4.613549 -55.611329) (xy 4.636394 -55.561582) (xy 4.666119 -55.515615)
			(xy 4.68376 -55.494682) (xy 4.684014 -55.494428) (xy 4.689597 -55.487339) (xy 4.695845 -55.470424)
			(xy 4.696206 -55.461408) (xy 4.696206 -55.394352) (xy 4.695823 -55.385338) (xy 4.689593 -55.368421)
			(xy 4.684014 -55.361332) (xy 4.68376 -55.360824) (xy 4.672814 -55.348091) (xy 4.652974 -55.320999)
			(xy 4.644136 -55.306722) (xy 4.638802 -55.297832) (xy 4.621784 -55.28564) (xy 4.528566 -55.26532)
			(xy 4.507992 -55.269638) (xy 4.499356 -55.27548) (xy 4.475304 -55.291499) (xy 4.423368 -55.316838)
			(xy 4.368207 -55.334058) (xy 4.31108 -55.342767) (xy 4.282186 -55.343298) (xy 4.254935 -55.342812)
			(xy 4.200988 -55.335055) (xy 4.148693 -55.319699) (xy 4.099117 -55.297058) (xy 4.053267 -55.267592)
			(xy 4.012077 -55.2319) (xy 3.976386 -55.19071) (xy 3.94692 -55.14486) (xy 3.924279 -55.095283) (xy 3.908924 -55.042988)
			(xy 3.901168 -54.989041) (xy 0.715772 -54.989041) (xy 0.715772 -55.420841) (xy 2.224768 -55.420841)
			(xy 2.224768 -55.366339) (xy 2.232524 -55.312392) (xy 2.247879 -55.260097) (xy 2.27052 -55.21052)
			(xy 2.299986 -55.16467) (xy 2.335677 -55.12348) (xy 2.376867 -55.087788) (xy 2.422717 -55.058322)
			(xy 2.472293 -55.035681) (xy 2.524588 -55.020325) (xy 2.578535 -55.012568) (xy 2.605786 -55.012082)
			(xy 2.632099 -55.012565) (xy 2.684227 -55.019797) (xy 2.734869 -55.034114) (xy 2.783068 -55.055243)
			(xy 2.827912 -55.082786) (xy 2.868553 -55.116222) (xy 2.88671 -55.135272) (xy 2.89423 -55.142676)
			(xy 2.913511 -55.1512) (xy 2.924048 -55.151782) (xy 2.998724 -55.151782) (xy 3.009271 -55.151231)
			(xy 3.028567 -55.142712) (xy 3.036062 -55.135272) (xy 3.054189 -55.116188) (xy 3.094825 -55.082735)
			(xy 3.139672 -55.05518) (xy 3.187878 -55.034047) (xy 3.23853 -55.019735) (xy 3.290668 -55.012517)
			(xy 3.316986 -55.012082) (xy 3.344239 -55.012545) (xy 3.39819 -55.020302) (xy 3.450489 -55.035657)
			(xy 3.500069 -55.0583) (xy 3.545923 -55.087767) (xy 3.587116 -55.123461) (xy 3.62281 -55.164654)
			(xy 3.652279 -55.210507) (xy 3.674921 -55.260088) (xy 3.690278 -55.312386) (xy 3.698035 -55.366337)
			(xy 3.698035 -55.420843) (xy 3.690278 -55.474794) (xy 3.674921 -55.527092) (xy 3.652279 -55.576673)
			(xy 3.62281 -55.622526) (xy 3.587116 -55.663719) (xy 3.545923 -55.699413) (xy 3.500069 -55.72888)
			(xy 3.450489 -55.751523) (xy 3.39819 -55.766878) (xy 3.344239 -55.774635) (xy 3.316986 -55.775098)
			(xy 3.290672 -55.774641) (xy 3.238543 -55.767404) (xy 3.1879 -55.753083) (xy 3.139701 -55.731948)
			(xy 3.094858 -55.704401) (xy 3.054218 -55.67096) (xy 3.036062 -55.651908) (xy 3.028555 -55.644489)
			(xy 3.009264 -55.635974) (xy 2.998724 -55.635398) (xy 2.924048 -55.635398) (xy 2.9135 -55.63594)
			(xy 2.894204 -55.644466) (xy 2.88671 -55.651908) (xy 2.868544 -55.670953) (xy 2.827916 -55.704411)
			(xy 2.783078 -55.731971) (xy 2.73488 -55.753111) (xy 2.684234 -55.767431) (xy 2.632102 -55.774658)
			(xy 2.605786 -55.775098) (xy 2.578535 -55.774612) (xy 2.524588 -55.766855) (xy 2.472293 -55.751499)
			(xy 2.422717 -55.728858) (xy 2.376867 -55.699392) (xy 2.335677 -55.6637) (xy 2.299986 -55.62251)
			(xy 2.27052 -55.57666) (xy 2.247879 -55.527083) (xy 2.232524 -55.474788) (xy 2.224768 -55.420841)
			(xy 0.715772 -55.420841) (xy 0.715772 -57.002934) (xy 21.563584 -57.002934) (xy 21.564105 -56.974843)
			(xy 21.572327 -56.919267) (xy 21.588614 -56.865499) (xy 21.612612 -56.814702) (xy 21.643803 -56.767974)
			(xy 21.681511 -56.726329) (xy 21.724921 -56.690665) (xy 21.74875 -56.675782) (xy 21.75764 -56.670448)
			(xy 21.769832 -56.65343) (xy 21.790152 -56.560212) (xy 21.785834 -56.539638) (xy 21.779992 -56.531002)
			(xy 21.76399 -56.50694) (xy 21.738648 -56.455008) (xy 21.721423 -56.399849) (xy 21.712708 -56.342725)
			(xy 21.712174 -56.313832) (xy 21.712685 -56.286581) (xy 21.720437 -56.232632) (xy 21.735788 -56.180337)
			(xy 21.758426 -56.130758) (xy 21.787889 -56.084905) (xy 21.823577 -56.043713) (xy 21.864765 -56.008019)
			(xy 21.910614 -55.97855) (xy 21.96019 -55.955906) (xy 22.012484 -55.940548) (xy 22.066431 -55.932789)
			(xy 22.093682 -55.932324) (xy 22.121052 -55.932795) (xy 22.175231 -55.940611) (xy 22.227735 -55.956098)
			(xy 22.277481 -55.978939) (xy 22.323448 -56.008663) (xy 22.34438 -56.026304) (xy 22.344634 -56.026558)
			(xy 22.35173 -56.03213) (xy 22.36864 -56.038384) (xy 22.377654 -56.03875) (xy 22.44471 -56.03875)
			(xy 22.453729 -56.038408) (xy 22.470646 -56.032151) (xy 22.47773 -56.026558) (xy 22.47773 -56.026304)
			(xy 22.477984 -56.026304) (xy 22.498917 -56.008663) (xy 22.544885 -55.978939) (xy 22.594631 -55.956093)
			(xy 22.647133 -55.940597) (xy 22.701311 -55.932768) (xy 22.756053 -55.932768) (xy 22.810231 -55.940597)
			(xy 22.862733 -55.956093) (xy 22.912479 -55.978939) (xy 22.958447 -56.008663) (xy 22.97938 -56.026304)
			(xy 22.979634 -56.026558) (xy 22.98673 -56.03213) (xy 23.00364 -56.038384) (xy 23.012654 -56.03875)
			(xy 23.07971 -56.03875) (xy 23.088729 -56.038408) (xy 23.105646 -56.032151) (xy 23.11273 -56.026558)
			(xy 23.11273 -56.026304) (xy 23.112984 -56.026304) (xy 23.133912 -56.00866) (xy 23.179886 -55.978948)
			(xy 23.229634 -55.956113) (xy 23.282136 -55.940624) (xy 23.336313 -55.932797) (xy 23.363682 -55.932324)
			(xy 23.390938 -55.932722) (xy 23.444895 -55.940477) (xy 23.4972 -55.955833) (xy 23.546787 -55.978476)
			(xy 23.592646 -56.007946) (xy 23.633844 -56.043643) (xy 23.669543 -56.08484) (xy 23.699015 -56.130698)
			(xy 23.721661 -56.180283) (xy 23.737019 -56.232587) (xy 23.744777 -56.286544) (xy 23.744777 -56.297068)
			(xy 24.086564 -56.297068) (xy 24.090635 -56.241446) (xy 24.102761 -56.187009) (xy 24.122684 -56.134918)
			(xy 24.14998 -56.086283) (xy 24.184066 -56.04214) (xy 24.224215 -56.003431) (xy 24.269573 -55.97098)
			(xy 24.319173 -55.945479) (xy 24.371957 -55.927472) (xy 24.4268 -55.917342) (xy 24.482534 -55.915305)
			(xy 24.537971 -55.921405) (xy 24.591928 -55.935511) (xy 24.643257 -55.957323) (xy 24.690863 -55.986377)
			(xy 24.733731 -56.022052) (xy 24.770948 -56.063589) (xy 24.801721 -56.110102) (xy 24.825393 -56.160599)
			(xy 24.841461 -56.214006) (xy 24.849581 -56.269182) (xy 24.85009 -56.297068) (xy 24.849581 -56.324954)
			(xy 24.841461 -56.38013) (xy 24.825393 -56.433537) (xy 24.801721 -56.484034) (xy 24.770948 -56.530547)
			(xy 24.733731 -56.572084) (xy 24.690863 -56.607759) (xy 24.643257 -56.636813) (xy 24.591928 -56.658625)
			(xy 24.537971 -56.672731) (xy 24.482534 -56.678831) (xy 24.4268 -56.676794) (xy 24.371957 -56.666664)
			(xy 24.319173 -56.648657) (xy 24.269573 -56.623156) (xy 24.224215 -56.590705) (xy 24.184066 -56.551996)
			(xy 24.14998 -56.507853) (xy 24.122684 -56.459218) (xy 24.102761 -56.407127) (xy 24.090635 -56.35269)
			(xy 24.086564 -56.297068) (xy 23.744777 -56.297068) (xy 23.744777 -56.341056) (xy 23.737019 -56.395013)
			(xy 23.721661 -56.447317) (xy 23.699015 -56.496902) (xy 23.669543 -56.54276) (xy 23.633844 -56.583957)
			(xy 23.592646 -56.619654) (xy 23.546787 -56.649124) (xy 23.4972 -56.671767) (xy 23.444895 -56.687123)
			(xy 23.390938 -56.694878) (xy 23.363682 -56.69534) (xy 23.336311 -56.694899) (xy 23.28213 -56.687077)
			(xy 23.229626 -56.671583) (xy 23.179879 -56.648736) (xy 23.133914 -56.619005) (xy 23.112984 -56.60136)
			(xy 23.11273 -56.601106) (xy 23.105639 -56.595527) (xy 23.088726 -56.589275) (xy 23.07971 -56.588914)
			(xy 23.012654 -56.588914) (xy 23.003639 -56.589294) (xy 22.986722 -56.595525) (xy 22.979634 -56.601106)
			(xy 22.979634 -56.60136) (xy 22.97938 -56.60136) (xy 22.958447 -56.619001) (xy 22.912479 -56.648725)
			(xy 22.862733 -56.671571) (xy 22.810231 -56.687067) (xy 22.756053 -56.694896) (xy 22.701311 -56.694896)
			(xy 22.647133 -56.687067) (xy 22.594631 -56.671571) (xy 22.544885 -56.648725) (xy 22.498917 -56.619001)
			(xy 22.477984 -56.60136) (xy 22.47773 -56.601106) (xy 22.470639 -56.595527) (xy 22.453726 -56.589275)
			(xy 22.44471 -56.588914) (xy 22.377654 -56.588914) (xy 22.368639 -56.589294) (xy 22.351722 -56.595525)
			(xy 22.344634 -56.601106) (xy 22.344126 -56.60136) (xy 22.331394 -56.612307) (xy 22.304301 -56.632146)
			(xy 22.290024 -56.640984) (xy 22.281134 -56.646318) (xy 22.268942 -56.663336) (xy 22.248622 -56.756554)
			(xy 22.25294 -56.777128) (xy 22.258782 -56.785764) (xy 22.274767 -56.809837) (xy 22.300113 -56.861765)
			(xy 22.317343 -56.91692) (xy 22.326063 -56.974042) (xy 22.3266 -57.002934) (xy 22.326114 -57.030185)
			(xy 22.318358 -57.084133) (xy 22.303003 -57.136428) (xy 22.280361 -57.186005) (xy 22.250895 -57.231855)
			(xy 22.215204 -57.273046) (xy 22.174013 -57.308737) (xy 22.128163 -57.338203) (xy 22.078586 -57.360845)
			(xy 22.026291 -57.3762) (xy 21.972343 -57.383956) (xy 21.917841 -57.383956) (xy 21.863893 -57.3762)
			(xy 21.811598 -57.360845) (xy 21.762021 -57.338203) (xy 21.716171 -57.308737) (xy 21.67498 -57.273046)
			(xy 21.639289 -57.231855) (xy 21.609823 -57.186005) (xy 21.587181 -57.136428) (xy 21.571826 -57.084133)
			(xy 21.56407 -57.030185) (xy 21.563584 -57.002934) (xy 0.715772 -57.002934) (xy 0.715772 -57.48528)
			(xy 4.606034 -57.48528) (xy 4.610105 -57.429658) (xy 4.622231 -57.375221) (xy 4.642154 -57.32313)
			(xy 4.66945 -57.274495) (xy 4.703536 -57.230352) (xy 4.743685 -57.191643) (xy 4.789043 -57.159192)
			(xy 4.838643 -57.133691) (xy 4.891427 -57.115684) (xy 4.94627 -57.105554) (xy 5.002004 -57.103517)
			(xy 5.057441 -57.109617) (xy 5.111398 -57.123723) (xy 5.162727 -57.145535) (xy 5.210333 -57.174589)
			(xy 5.253201 -57.210264) (xy 5.290418 -57.251801) (xy 5.321191 -57.298314) (xy 5.344863 -57.348811)
			(xy 5.360931 -57.402218) (xy 5.369051 -57.457394) (xy 5.36956 -57.48528) (xy 30.605982 -57.48528)
			(xy 30.610053 -57.429658) (xy 30.622179 -57.375221) (xy 30.642102 -57.32313) (xy 30.669398 -57.274495)
			(xy 30.703484 -57.230352) (xy 30.743633 -57.191643) (xy 30.788991 -57.159192) (xy 30.838591 -57.133691)
			(xy 30.891375 -57.115684) (xy 30.946218 -57.105554) (xy 31.001952 -57.103517) (xy 31.057389 -57.109617)
			(xy 31.111346 -57.123723) (xy 31.162675 -57.145535) (xy 31.210281 -57.174589) (xy 31.253149 -57.210264)
			(xy 31.290366 -57.251801) (xy 31.321139 -57.298314) (xy 31.344811 -57.348811) (xy 31.360879 -57.402218)
			(xy 31.368999 -57.457394) (xy 31.369508 -57.48528) (xy 31.368999 -57.513166) (xy 31.360879 -57.568342)
			(xy 31.344811 -57.621749) (xy 31.321139 -57.672246) (xy 31.290366 -57.718759) (xy 31.253149 -57.760296)
			(xy 31.210281 -57.795971) (xy 31.162675 -57.825025) (xy 31.111346 -57.846837) (xy 31.057389 -57.860943)
			(xy 31.001952 -57.867043) (xy 30.946218 -57.865006) (xy 30.891375 -57.854876) (xy 30.838591 -57.836869)
			(xy 30.788991 -57.811368) (xy 30.743633 -57.778917) (xy 30.703484 -57.740208) (xy 30.669398 -57.696065)
			(xy 30.642102 -57.64743) (xy 30.622179 -57.595339) (xy 30.610053 -57.540902) (xy 30.605982 -57.48528)
			(xy 5.36956 -57.48528) (xy 5.369051 -57.513166) (xy 5.360931 -57.568342) (xy 5.344863 -57.621749)
			(xy 5.321191 -57.672246) (xy 5.290418 -57.718759) (xy 5.253201 -57.760296) (xy 5.210333 -57.795971)
			(xy 5.162727 -57.825025) (xy 5.111398 -57.846837) (xy 5.057441 -57.860943) (xy 5.002004 -57.867043)
			(xy 4.94627 -57.865006) (xy 4.891427 -57.854876) (xy 4.838643 -57.836869) (xy 4.789043 -57.811368)
			(xy 4.743685 -57.778917) (xy 4.703536 -57.740208) (xy 4.66945 -57.696065) (xy 4.642154 -57.64743)
			(xy 4.622231 -57.595339) (xy 4.610105 -57.540902) (xy 4.606034 -57.48528) (xy 0.715772 -57.48528)
			(xy 0.715772 -58.076084) (xy 5.358128 -58.076084) (xy 5.362199 -58.020462) (xy 5.374325 -57.966025)
			(xy 5.394248 -57.913934) (xy 5.421544 -57.865299) (xy 5.45563 -57.821156) (xy 5.495779 -57.782447)
			(xy 5.541137 -57.749996) (xy 5.590737 -57.724495) (xy 5.643521 -57.706488) (xy 5.698364 -57.696358)
			(xy 5.754098 -57.694321) (xy 5.809535 -57.700421) (xy 5.863492 -57.714527) (xy 5.914821 -57.736339)
			(xy 5.962427 -57.765393) (xy 6.005295 -57.801068) (xy 6.042512 -57.842605) (xy 6.058848 -57.867296)
			(xy 7.643112 -57.867296) (xy 7.647183 -57.811674) (xy 7.659309 -57.757237) (xy 7.679232 -57.705146)
			(xy 7.706528 -57.656511) (xy 7.740614 -57.612368) (xy 7.780763 -57.573659) (xy 7.826121 -57.541208)
			(xy 7.875721 -57.515707) (xy 7.928505 -57.4977) (xy 7.983348 -57.48757) (xy 8.039082 -57.485533)
			(xy 8.094519 -57.491633) (xy 8.148476 -57.505739) (xy 8.199805 -57.527551) (xy 8.247411 -57.556605)
			(xy 8.290279 -57.59228) (xy 8.327496 -57.633817) (xy 8.358269 -57.68033) (xy 8.381941 -57.730827)
			(xy 8.398009 -57.784234) (xy 8.406129 -57.83941) (xy 8.406638 -57.867296) (xy 8.406129 -57.895182)
			(xy 8.398009 -57.950358) (xy 8.381941 -58.003765) (xy 8.358269 -58.054262) (xy 8.327496 -58.100775)
			(xy 8.290279 -58.142312) (xy 8.247411 -58.177987) (xy 8.199805 -58.207041) (xy 8.148476 -58.228853)
			(xy 8.094519 -58.242959) (xy 8.039082 -58.249059) (xy 7.983348 -58.247022) (xy 7.928505 -58.236892)
			(xy 7.875721 -58.218885) (xy 7.826121 -58.193384) (xy 7.780763 -58.160933) (xy 7.740614 -58.122224)
			(xy 7.706528 -58.078081) (xy 7.679232 -58.029446) (xy 7.659309 -57.977355) (xy 7.647183 -57.922918)
			(xy 7.643112 -57.867296) (xy 6.058848 -57.867296) (xy 6.073285 -57.889118) (xy 6.096957 -57.939615)
			(xy 6.113025 -57.993022) (xy 6.121145 -58.048198) (xy 6.121654 -58.076084) (xy 6.121145 -58.10397)
			(xy 6.113025 -58.159146) (xy 6.096957 -58.212553) (xy 6.073285 -58.26305) (xy 6.042512 -58.309563)
			(xy 6.005295 -58.3511) (xy 5.962427 -58.386775) (xy 5.914821 -58.415829) (xy 5.863492 -58.437641)
			(xy 5.809535 -58.451747) (xy 5.754098 -58.457847) (xy 5.698364 -58.45581) (xy 5.643521 -58.44568)
			(xy 5.590737 -58.427673) (xy 5.541137 -58.402172) (xy 5.495779 -58.369721) (xy 5.45563 -58.331012)
			(xy 5.421544 -58.286869) (xy 5.394248 -58.238234) (xy 5.374325 -58.186143) (xy 5.362199 -58.131706)
			(xy 5.358128 -58.076084) (xy 0.715772 -58.076084) (xy 0.715772 -58.561224) (xy 6.562342 -58.561224)
			(xy 6.566413 -58.505602) (xy 6.578539 -58.451165) (xy 6.598462 -58.399074) (xy 6.625758 -58.350439)
			(xy 6.659844 -58.306296) (xy 6.699993 -58.267587) (xy 6.745351 -58.235136) (xy 6.794951 -58.209635)
			(xy 6.847735 -58.191628) (xy 6.902578 -58.181498) (xy 6.958312 -58.179461) (xy 7.013749 -58.185561)
			(xy 7.067706 -58.199667) (xy 7.119035 -58.221479) (xy 7.166641 -58.250533) (xy 7.209509 -58.286208)
			(xy 7.246726 -58.327745) (xy 7.277499 -58.374258) (xy 7.301171 -58.424755) (xy 7.308681 -58.449718)
			(xy 8.808972 -58.449718) (xy 8.813043 -58.394096) (xy 8.825169 -58.339659) (xy 8.845092 -58.287568)
			(xy 8.872388 -58.238933) (xy 8.906474 -58.19479) (xy 8.946623 -58.156081) (xy 8.991981 -58.12363)
			(xy 9.041581 -58.098129) (xy 9.094365 -58.080122) (xy 9.149208 -58.069992) (xy 9.204942 -58.067955)
			(xy 9.260379 -58.074055) (xy 9.314336 -58.088161) (xy 9.365665 -58.109973) (xy 9.413271 -58.139027)
			(xy 9.456139 -58.174702) (xy 9.493356 -58.216239) (xy 9.524129 -58.262752) (xy 9.547801 -58.313249)
			(xy 9.563869 -58.366656) (xy 9.571989 -58.421832) (xy 9.572498 -58.449718) (xy 9.571989 -58.477604)
			(xy 9.563869 -58.53278) (xy 9.547801 -58.586187) (xy 9.524129 -58.636684) (xy 9.495912 -58.679334)
			(xy 21.995384 -58.679334) (xy 21.995813 -58.653019) (xy 22.003056 -58.600889) (xy 22.017383 -58.550246)
			(xy 22.038523 -58.502047) (xy 22.066076 -58.457204) (xy 22.09952 -58.416566) (xy 22.118574 -58.39841)
			(xy 22.125969 -58.390883) (xy 22.134498 -58.371607) (xy 22.135084 -58.361072) (xy 22.135084 -58.286396)
			(xy 22.134575 -58.275844) (xy 22.126026 -58.256549) (xy 22.118574 -58.249058) (xy 22.0995 -58.230921)
			(xy 22.066046 -58.190287) (xy 22.03849 -58.145442) (xy 22.017355 -58.097238) (xy 22.003041 -58.046588)
			(xy 21.99582 -57.994451) (xy 21.995384 -57.968134) (xy 21.99587 -57.940883) (xy 22.003626 -57.886935)
			(xy 22.018981 -57.83464) (xy 22.041623 -57.785063) (xy 22.071089 -57.739213) (xy 22.10678 -57.698022)
			(xy 22.147971 -57.662331) (xy 22.193821 -57.632865) (xy 22.243398 -57.610223) (xy 22.295693 -57.594868)
			(xy 22.349641 -57.587112) (xy 22.404143 -57.587112) (xy 22.458091 -57.594868) (xy 22.510386 -57.610223)
			(xy 22.559963 -57.632865) (xy 22.605813 -57.662331) (xy 22.647004 -57.698022) (xy 22.682695 -57.739213)
			(xy 22.712161 -57.785063) (xy 22.734803 -57.83464) (xy 22.750158 -57.886935) (xy 22.757914 -57.940883)
			(xy 22.7584 -57.968134) (xy 22.757955 -57.994449) (xy 22.750716 -58.046578) (xy 22.743448 -58.072274)
			(xy 25.993596 -58.072274) (xy 25.997667 -58.016652) (xy 26.009793 -57.962215) (xy 26.029716 -57.910124)
			(xy 26.057012 -57.861489) (xy 26.091098 -57.817346) (xy 26.131247 -57.778637) (xy 26.176605 -57.746186)
			(xy 26.226205 -57.720685) (xy 26.278989 -57.702678) (xy 26.333832 -57.692548) (xy 26.389566 -57.690511)
			(xy 26.445003 -57.696611) (xy 26.49896 -57.710717) (xy 26.550289 -57.732529) (xy 26.597895 -57.761583)
			(xy 26.640763 -57.797258) (xy 26.67798 -57.838795) (xy 26.708753 -57.885308) (xy 26.732425 -57.935805)
			(xy 26.748493 -57.989212) (xy 26.756613 -58.044388) (xy 26.757122 -58.072274) (xy 26.757052 -58.076084)
			(xy 31.358076 -58.076084) (xy 31.362147 -58.020462) (xy 31.374273 -57.966025) (xy 31.394196 -57.913934)
			(xy 31.421492 -57.865299) (xy 31.455578 -57.821156) (xy 31.495727 -57.782447) (xy 31.541085 -57.749996)
			(xy 31.590685 -57.724495) (xy 31.643469 -57.706488) (xy 31.698312 -57.696358) (xy 31.754046 -57.694321)
			(xy 31.809483 -57.700421) (xy 31.86344 -57.714527) (xy 31.914769 -57.736339) (xy 31.962375 -57.765393)
			(xy 32.005243 -57.801068) (xy 32.04246 -57.842605) (xy 32.058796 -57.867296) (xy 33.64306 -57.867296)
			(xy 33.647131 -57.811674) (xy 33.659257 -57.757237) (xy 33.67918 -57.705146) (xy 33.706476 -57.656511)
			(xy 33.740562 -57.612368) (xy 33.780711 -57.573659) (xy 33.826069 -57.541208) (xy 33.875669 -57.515707)
			(xy 33.928453 -57.4977) (xy 33.983296 -57.48757) (xy 34.03903 -57.485533) (xy 34.094467 -57.491633)
			(xy 34.148424 -57.505739) (xy 34.199753 -57.527551) (xy 34.247359 -57.556605) (xy 34.290227 -57.59228)
			(xy 34.327444 -57.633817) (xy 34.358217 -57.68033) (xy 34.381889 -57.730827) (xy 34.397957 -57.784234)
			(xy 34.406077 -57.83941) (xy 34.406586 -57.867296) (xy 34.406077 -57.895182) (xy 34.397957 -57.950358)
			(xy 34.381889 -58.003765) (xy 34.358217 -58.054262) (xy 34.327444 -58.100775) (xy 34.290227 -58.142312)
			(xy 34.247359 -58.177987) (xy 34.199753 -58.207041) (xy 34.148424 -58.228853) (xy 34.094467 -58.242959)
			(xy 34.03903 -58.249059) (xy 33.983296 -58.247022) (xy 33.928453 -58.236892) (xy 33.875669 -58.218885)
			(xy 33.826069 -58.193384) (xy 33.780711 -58.160933) (xy 33.740562 -58.122224) (xy 33.706476 -58.078081)
			(xy 33.67918 -58.029446) (xy 33.659257 -57.977355) (xy 33.647131 -57.922918) (xy 33.64306 -57.867296)
			(xy 32.058796 -57.867296) (xy 32.073233 -57.889118) (xy 32.096905 -57.939615) (xy 32.112973 -57.993022)
			(xy 32.121093 -58.048198) (xy 32.121602 -58.076084) (xy 32.121093 -58.10397) (xy 32.112973 -58.159146)
			(xy 32.096905 -58.212553) (xy 32.073233 -58.26305) (xy 32.04246 -58.309563) (xy 32.005243 -58.3511)
			(xy 31.962375 -58.386775) (xy 31.914769 -58.415829) (xy 31.86344 -58.437641) (xy 31.809483 -58.451747)
			(xy 31.754046 -58.457847) (xy 31.698312 -58.45581) (xy 31.643469 -58.44568) (xy 31.590685 -58.427673)
			(xy 31.541085 -58.402172) (xy 31.495727 -58.369721) (xy 31.455578 -58.331012) (xy 31.421492 -58.286869)
			(xy 31.394196 -58.238234) (xy 31.374273 -58.186143) (xy 31.362147 -58.131706) (xy 31.358076 -58.076084)
			(xy 26.757052 -58.076084) (xy 26.756613 -58.10016) (xy 26.748493 -58.155336) (xy 26.732425 -58.208743)
			(xy 26.708753 -58.25924) (xy 26.67798 -58.305753) (xy 26.640763 -58.34729) (xy 26.597895 -58.382965)
			(xy 26.550289 -58.412019) (xy 26.49896 -58.433831) (xy 26.445003 -58.447937) (xy 26.389566 -58.454037)
			(xy 26.333832 -58.452) (xy 26.278989 -58.44187) (xy 26.226205 -58.423863) (xy 26.176605 -58.398362)
			(xy 26.131247 -58.365911) (xy 26.091098 -58.327202) (xy 26.057012 -58.283059) (xy 26.029716 -58.234424)
			(xy 26.009793 -58.182333) (xy 25.997667 -58.127896) (xy 25.993596 -58.072274) (xy 22.743448 -58.072274)
			(xy 22.736392 -58.097221) (xy 22.715256 -58.14542) (xy 22.687705 -58.190263) (xy 22.654263 -58.230902)
			(xy 22.63521 -58.249058) (xy 22.627826 -58.256595) (xy 22.619291 -58.275863) (xy 22.6187 -58.286396)
			(xy 22.6187 -58.361072) (xy 22.619231 -58.371621) (xy 22.627765 -58.390917) (xy 22.63521 -58.39841)
			(xy 22.654265 -58.416566) (xy 22.687722 -58.457196) (xy 22.715281 -58.502036) (xy 22.736419 -58.550237)
			(xy 22.739525 -58.561224) (xy 32.56229 -58.561224) (xy 32.566361 -58.505602) (xy 32.578487 -58.451165)
			(xy 32.59841 -58.399074) (xy 32.625706 -58.350439) (xy 32.659792 -58.306296) (xy 32.699941 -58.267587)
			(xy 32.745299 -58.235136) (xy 32.794899 -58.209635) (xy 32.847683 -58.191628) (xy 32.902526 -58.181498)
			(xy 32.95826 -58.179461) (xy 33.013697 -58.185561) (xy 33.067654 -58.199667) (xy 33.118983 -58.221479)
			(xy 33.166589 -58.250533) (xy 33.209457 -58.286208) (xy 33.246674 -58.327745) (xy 33.277447 -58.374258)
			(xy 33.301119 -58.424755) (xy 33.308629 -58.449718) (xy 34.80892 -58.449718) (xy 34.812991 -58.394096)
			(xy 34.825117 -58.339659) (xy 34.84504 -58.287568) (xy 34.872336 -58.238933) (xy 34.906422 -58.19479)
			(xy 34.946571 -58.156081) (xy 34.991929 -58.12363) (xy 35.041529 -58.098129) (xy 35.094313 -58.080122)
			(xy 35.149156 -58.069992) (xy 35.20489 -58.067955) (xy 35.260327 -58.074055) (xy 35.314284 -58.088161)
			(xy 35.365613 -58.109973) (xy 35.413219 -58.139027) (xy 35.456087 -58.174702) (xy 35.493304 -58.216239)
			(xy 35.524077 -58.262752) (xy 35.547749 -58.313249) (xy 35.563817 -58.366656) (xy 35.571937 -58.421832)
			(xy 35.572446 -58.449718) (xy 35.571937 -58.477604) (xy 35.563817 -58.53278) (xy 35.547749 -58.586187)
			(xy 35.524077 -58.636684) (xy 35.493304 -58.683197) (xy 35.456087 -58.724734) (xy 35.413219 -58.760409)
			(xy 35.365613 -58.789463) (xy 35.314284 -58.811275) (xy 35.260327 -58.825381) (xy 35.20489 -58.831481)
			(xy 35.149156 -58.829444) (xy 35.094313 -58.819314) (xy 35.041529 -58.801307) (xy 34.991929 -58.775806)
			(xy 34.946571 -58.743355) (xy 34.906422 -58.704646) (xy 34.872336 -58.660503) (xy 34.84504 -58.611868)
			(xy 34.825117 -58.559777) (xy 34.812991 -58.50534) (xy 34.80892 -58.449718) (xy 33.308629 -58.449718)
			(xy 33.317187 -58.478162) (xy 33.325307 -58.533338) (xy 33.325816 -58.561224) (xy 33.325307 -58.58911)
			(xy 33.317187 -58.644286) (xy 33.301119 -58.697693) (xy 33.277447 -58.74819) (xy 33.246674 -58.794703)
			(xy 33.209457 -58.83624) (xy 33.166589 -58.871915) (xy 33.118983 -58.900969) (xy 33.067654 -58.922781)
			(xy 33.013697 -58.936887) (xy 32.95826 -58.942987) (xy 32.902526 -58.94095) (xy 32.847683 -58.93082)
			(xy 32.794899 -58.912813) (xy 32.745299 -58.887312) (xy 32.699941 -58.854861) (xy 32.659792 -58.816152)
			(xy 32.625706 -58.772009) (xy 32.59841 -58.723374) (xy 32.578487 -58.671283) (xy 32.566361 -58.616846)
			(xy 32.56229 -58.561224) (xy 22.739525 -58.561224) (xy 22.750737 -58.600884) (xy 22.757961 -58.653018)
			(xy 22.7584 -58.679334) (xy 22.757914 -58.706585) (xy 22.750158 -58.760533) (xy 22.734803 -58.812828)
			(xy 22.712161 -58.862405) (xy 22.682695 -58.908255) (xy 22.647004 -58.949446) (xy 22.605813 -58.985137)
			(xy 22.559963 -59.014603) (xy 22.510386 -59.037245) (xy 22.458091 -59.0526) (xy 22.404143 -59.060356)
			(xy 22.349641 -59.060356) (xy 22.295693 -59.0526) (xy 22.243398 -59.037245) (xy 22.193821 -59.014603)
			(xy 22.147971 -58.985137) (xy 22.10678 -58.949446) (xy 22.071089 -58.908255) (xy 22.041623 -58.862405)
			(xy 22.018981 -58.812828) (xy 22.003626 -58.760533) (xy 21.99587 -58.706585) (xy 21.995384 -58.679334)
			(xy 9.495912 -58.679334) (xy 9.493356 -58.683197) (xy 9.456139 -58.724734) (xy 9.413271 -58.760409)
			(xy 9.365665 -58.789463) (xy 9.314336 -58.811275) (xy 9.260379 -58.825381) (xy 9.204942 -58.831481)
			(xy 9.149208 -58.829444) (xy 9.094365 -58.819314) (xy 9.041581 -58.801307) (xy 8.991981 -58.775806)
			(xy 8.946623 -58.743355) (xy 8.906474 -58.704646) (xy 8.872388 -58.660503) (xy 8.845092 -58.611868)
			(xy 8.825169 -58.559777) (xy 8.813043 -58.50534) (xy 8.808972 -58.449718) (xy 7.308681 -58.449718)
			(xy 7.317239 -58.478162) (xy 7.325359 -58.533338) (xy 7.325868 -58.561224) (xy 7.325359 -58.58911)
			(xy 7.317239 -58.644286) (xy 7.301171 -58.697693) (xy 7.277499 -58.74819) (xy 7.246726 -58.794703)
			(xy 7.209509 -58.83624) (xy 7.166641 -58.871915) (xy 7.119035 -58.900969) (xy 7.067706 -58.922781)
			(xy 7.013749 -58.936887) (xy 6.958312 -58.942987) (xy 6.902578 -58.94095) (xy 6.847735 -58.93082)
			(xy 6.794951 -58.912813) (xy 6.745351 -58.887312) (xy 6.699993 -58.854861) (xy 6.659844 -58.816152)
			(xy 6.625758 -58.772009) (xy 6.598462 -58.723374) (xy 6.578539 -58.671283) (xy 6.566413 -58.616846)
			(xy 6.562342 -58.561224) (xy 0.715772 -58.561224) (xy 0.715772 -59.174634) (xy 5.093206 -59.174634)
			(xy 5.097277 -59.119012) (xy 5.109403 -59.064575) (xy 5.129326 -59.012484) (xy 5.156622 -58.963849)
			(xy 5.190708 -58.919706) (xy 5.230857 -58.880997) (xy 5.276215 -58.848546) (xy 5.325815 -58.823045)
			(xy 5.378599 -58.805038) (xy 5.433442 -58.794908) (xy 5.489176 -58.792871) (xy 5.544613 -58.798971)
			(xy 5.59857 -58.813077) (xy 5.649899 -58.834889) (xy 5.697505 -58.863943) (xy 5.740373 -58.899618)
			(xy 5.77759 -58.941155) (xy 5.808363 -58.987668) (xy 5.832035 -59.038165) (xy 5.848103 -59.091572)
			(xy 5.856223 -59.146748) (xy 5.856732 -59.174634) (xy 31.093154 -59.174634) (xy 31.097225 -59.119012)
			(xy 31.109351 -59.064575) (xy 31.129274 -59.012484) (xy 31.15657 -58.963849) (xy 31.190656 -58.919706)
			(xy 31.230805 -58.880997) (xy 31.276163 -58.848546) (xy 31.325763 -58.823045) (xy 31.378547 -58.805038)
			(xy 31.43339 -58.794908) (xy 31.489124 -58.792871) (xy 31.544561 -58.798971) (xy 31.598518 -58.813077)
			(xy 31.649847 -58.834889) (xy 31.697453 -58.863943) (xy 31.740321 -58.899618) (xy 31.777538 -58.941155)
			(xy 31.808311 -58.987668) (xy 31.831983 -59.038165) (xy 31.848051 -59.091572) (xy 31.856171 -59.146748)
			(xy 31.85668 -59.174634) (xy 31.856171 -59.20252) (xy 31.848051 -59.257696) (xy 31.831983 -59.311103)
			(xy 31.808311 -59.3616) (xy 31.777538 -59.408113) (xy 31.740321 -59.44965) (xy 31.697453 -59.485325)
			(xy 31.649847 -59.514379) (xy 31.598518 -59.536191) (xy 31.544561 -59.550297) (xy 31.489124 -59.556397)
			(xy 31.43339 -59.55436) (xy 31.378547 -59.54423) (xy 31.325763 -59.526223) (xy 31.276163 -59.500722)
			(xy 31.230805 -59.468271) (xy 31.190656 -59.429562) (xy 31.15657 -59.385419) (xy 31.129274 -59.336784)
			(xy 31.109351 -59.284693) (xy 31.097225 -59.230256) (xy 31.093154 -59.174634) (xy 5.856732 -59.174634)
			(xy 5.856223 -59.20252) (xy 5.848103 -59.257696) (xy 5.832035 -59.311103) (xy 5.808363 -59.3616)
			(xy 5.77759 -59.408113) (xy 5.740373 -59.44965) (xy 5.697505 -59.485325) (xy 5.649899 -59.514379)
			(xy 5.59857 -59.536191) (xy 5.544613 -59.550297) (xy 5.489176 -59.556397) (xy 5.433442 -59.55436)
			(xy 5.378599 -59.54423) (xy 5.325815 -59.526223) (xy 5.276215 -59.500722) (xy 5.230857 -59.468271)
			(xy 5.190708 -59.429562) (xy 5.156622 -59.385419) (xy 5.129326 -59.336784) (xy 5.109403 -59.284693)
			(xy 5.097277 -59.230256) (xy 5.093206 -59.174634) (xy 0.715772 -59.174634) (xy 0.715772 -60.019261)
			(xy 22.135824 -60.019261) (xy 22.135824 -59.964759) (xy 22.14358 -59.910811) (xy 22.158935 -59.858516)
			(xy 22.181576 -59.808938) (xy 22.211043 -59.763088) (xy 22.246734 -59.721897) (xy 22.287924 -59.686205)
			(xy 22.333775 -59.656738) (xy 22.383352 -59.634097) (xy 22.435647 -59.618741) (xy 22.489595 -59.610984)
			(xy 22.516846 -59.610498) (xy 22.544215 -59.610996) (xy 22.598393 -59.618806) (xy 22.650895 -59.634288)
			(xy 22.700643 -59.657123) (xy 22.746611 -59.68684) (xy 22.767544 -59.704478) (xy 22.767798 -59.704732)
			(xy 22.774878 -59.710327) (xy 22.7918 -59.716568) (xy 22.800818 -59.716924) (xy 22.867874 -59.716924)
			(xy 22.876889 -59.716549) (xy 22.893806 -59.710313) (xy 22.900894 -59.704732) (xy 22.900894 -59.704478)
			(xy 22.901148 -59.704478) (xy 22.922081 -59.686837) (xy 22.968049 -59.657113) (xy 23.017795 -59.634267)
			(xy 23.070297 -59.618771) (xy 23.124475 -59.610942) (xy 23.179217 -59.610942) (xy 23.233395 -59.618771)
			(xy 23.285897 -59.634267) (xy 23.335643 -59.657113) (xy 23.381611 -59.686837) (xy 23.402544 -59.704478)
			(xy 23.402798 -59.704732) (xy 23.409878 -59.710327) (xy 23.4268 -59.716568) (xy 23.435818 -59.716924)
			(xy 23.502874 -59.716924) (xy 23.511889 -59.716549) (xy 23.528806 -59.710313) (xy 23.535894 -59.704732)
			(xy 23.535894 -59.704478) (xy 23.536148 -59.704478) (xy 23.557086 -59.686846) (xy 23.603058 -59.657134)
			(xy 23.652804 -59.634297) (xy 23.705303 -59.618804) (xy 23.759477 -59.610974) (xy 23.786846 -59.610498)
			(xy 23.814099 -59.610969) (xy 23.86805 -59.618725) (xy 23.920347 -59.634081) (xy 23.969927 -59.656723)
			(xy 24.015781 -59.686191) (xy 24.056973 -59.721884) (xy 24.092667 -59.763076) (xy 24.122135 -59.808929)
			(xy 24.144778 -59.858509) (xy 24.160134 -59.910807) (xy 24.167891 -59.964757) (xy 24.167891 -60.019263)
			(xy 24.160134 -60.073213) (xy 24.144778 -60.125511) (xy 24.122135 -60.175091) (xy 24.092667 -60.220944)
			(xy 24.056973 -60.262136) (xy 24.015781 -60.297829) (xy 23.969927 -60.327297) (xy 23.920347 -60.349939)
			(xy 23.86805 -60.365295) (xy 23.814099 -60.373051) (xy 23.786846 -60.373514) (xy 23.759477 -60.373018)
			(xy 23.705299 -60.365207) (xy 23.652797 -60.349724) (xy 23.603049 -60.32689) (xy 23.557081 -60.297172)
			(xy 23.536148 -60.279534) (xy 23.535894 -60.27928) (xy 23.528815 -60.273683) (xy 23.511892 -60.267443)
			(xy 23.502874 -60.267088) (xy 23.435818 -60.267088) (xy 23.426802 -60.267456) (xy 23.409885 -60.273696)
			(xy 23.402798 -60.27928) (xy 23.402544 -60.279534) (xy 23.381611 -60.297175) (xy 23.335643 -60.326899)
			(xy 23.285897 -60.349745) (xy 23.233395 -60.365241) (xy 23.179217 -60.37307) (xy 23.124475 -60.37307)
			(xy 23.070297 -60.365241) (xy 23.017795 -60.349745) (xy 22.968049 -60.326899) (xy 22.922081 -60.297175)
			(xy 22.901148 -60.279534) (xy 22.900894 -60.27928) (xy 22.893815 -60.273683) (xy 22.876892 -60.267443)
			(xy 22.867874 -60.267088) (xy 22.800818 -60.267088) (xy 22.791802 -60.267456) (xy 22.774885 -60.273696)
			(xy 22.767798 -60.27928) (xy 22.767798 -60.279534) (xy 22.767544 -60.279534) (xy 22.746611 -60.297171)
			(xy 22.700638 -60.326882) (xy 22.65089 -60.349718) (xy 22.59839 -60.36521) (xy 22.544215 -60.373039)
			(xy 22.516846 -60.373514) (xy 22.489595 -60.373036) (xy 22.435647 -60.365279) (xy 22.383352 -60.349923)
			(xy 22.333775 -60.327282) (xy 22.287924 -60.297815) (xy 22.246734 -60.262123) (xy 22.211043 -60.220932)
			(xy 22.181576 -60.175082) (xy 22.158935 -60.125504) (xy 22.14358 -60.073209) (xy 22.135824 -60.019261)
			(xy 0.715772 -60.019261) (xy 0.715772 -60.781946) (xy 5.674358 -60.781946) (xy 5.678429 -60.726324)
			(xy 5.690555 -60.671887) (xy 5.710478 -60.619796) (xy 5.737774 -60.571161) (xy 5.77186 -60.527018)
			(xy 5.812009 -60.488309) (xy 5.857367 -60.455858) (xy 5.906967 -60.430357) (xy 5.959751 -60.41235)
			(xy 6.014594 -60.40222) (xy 6.070328 -60.400183) (xy 6.125765 -60.406283) (xy 6.179722 -60.420389)
			(xy 6.231051 -60.442201) (xy 6.278657 -60.471255) (xy 6.321525 -60.50693) (xy 6.358742 -60.548467)
			(xy 6.389515 -60.59498) (xy 6.407505 -60.633356) (xy 7.797036 -60.633356) (xy 7.801107 -60.577734)
			(xy 7.813233 -60.523297) (xy 7.833156 -60.471206) (xy 7.860452 -60.422571) (xy 7.894538 -60.378428)
			(xy 7.934687 -60.339719) (xy 7.980045 -60.307268) (xy 8.029645 -60.281767) (xy 8.082429 -60.26376)
			(xy 8.137272 -60.25363) (xy 8.193006 -60.251593) (xy 8.248443 -60.257693) (xy 8.3024 -60.271799)
			(xy 8.353729 -60.293611) (xy 8.401335 -60.322665) (xy 8.444203 -60.35834) (xy 8.48142 -60.399877)
			(xy 8.512193 -60.44639) (xy 8.535865 -60.496887) (xy 8.551933 -60.550294) (xy 8.560053 -60.60547)
			(xy 8.560562 -60.633356) (xy 33.796984 -60.633356) (xy 33.801055 -60.577734) (xy 33.813181 -60.523297)
			(xy 33.833104 -60.471206) (xy 33.8604 -60.422571) (xy 33.894486 -60.378428) (xy 33.934635 -60.339719)
			(xy 33.979993 -60.307268) (xy 34.029593 -60.281767) (xy 34.082377 -60.26376) (xy 34.13722 -60.25363)
			(xy 34.192954 -60.251593) (xy 34.248391 -60.257693) (xy 34.302348 -60.271799) (xy 34.353677 -60.293611)
			(xy 34.401283 -60.322665) (xy 34.444151 -60.35834) (xy 34.481368 -60.399877) (xy 34.512141 -60.44639)
			(xy 34.535813 -60.496887) (xy 34.551881 -60.550294) (xy 34.560001 -60.60547) (xy 34.56051 -60.633356)
			(xy 34.560001 -60.661242) (xy 34.551881 -60.716418) (xy 34.535813 -60.769825) (xy 34.512141 -60.820322)
			(xy 34.481368 -60.866835) (xy 34.444151 -60.908372) (xy 34.401283 -60.944047) (xy 34.353677 -60.973101)
			(xy 34.302348 -60.994913) (xy 34.248391 -61.009019) (xy 34.192954 -61.015119) (xy 34.13722 -61.013082)
			(xy 34.082377 -61.002952) (xy 34.029593 -60.984945) (xy 33.979993 -60.959444) (xy 33.934635 -60.926993)
			(xy 33.894486 -60.888284) (xy 33.8604 -60.844141) (xy 33.833104 -60.795506) (xy 33.813181 -60.743415)
			(xy 33.801055 -60.688978) (xy 33.796984 -60.633356) (xy 8.560562 -60.633356) (xy 8.560053 -60.661242)
			(xy 8.551933 -60.716418) (xy 8.535865 -60.769825) (xy 8.512193 -60.820322) (xy 8.48142 -60.866835)
			(xy 8.444203 -60.908372) (xy 8.401335 -60.944047) (xy 8.353729 -60.973101) (xy 8.3024 -60.994913)
			(xy 8.248443 -61.009019) (xy 8.193006 -61.015119) (xy 8.137272 -61.013082) (xy 8.082429 -61.002952)
			(xy 8.029645 -60.984945) (xy 7.980045 -60.959444) (xy 7.934687 -60.926993) (xy 7.894538 -60.888284)
			(xy 7.860452 -60.844141) (xy 7.833156 -60.795506) (xy 7.813233 -60.743415) (xy 7.801107 -60.688978)
			(xy 7.797036 -60.633356) (xy 6.407505 -60.633356) (xy 6.413187 -60.645477) (xy 6.429255 -60.698884)
			(xy 6.437375 -60.75406) (xy 6.437884 -60.781946) (xy 6.437375 -60.809832) (xy 6.429255 -60.865008)
			(xy 6.413187 -60.918415) (xy 6.389515 -60.968912) (xy 6.358742 -61.015425) (xy 6.321525 -61.056962)
			(xy 6.278657 -61.092637) (xy 6.231051 -61.121691) (xy 6.179722 -61.143503) (xy 6.125765 -61.157609)
			(xy 6.070328 -61.163709) (xy 6.014594 -61.161672) (xy 5.959751 -61.151542) (xy 5.906967 -61.133535)
			(xy 5.857367 -61.108034) (xy 5.812009 -61.075583) (xy 5.77186 -61.036874) (xy 5.737774 -60.992731)
			(xy 5.710478 -60.944096) (xy 5.690555 -60.892005) (xy 5.678429 -60.837568) (xy 5.674358 -60.781946)
			(xy 0.715772 -60.781946) (xy 0.715772 -61.487812) (xy 32.30448 -61.487812) (xy 32.308551 -61.43219)
			(xy 32.320677 -61.377753) (xy 32.3406 -61.325662) (xy 32.367896 -61.277027) (xy 32.401982 -61.232884)
			(xy 32.442131 -61.194175) (xy 32.487489 -61.161724) (xy 32.537089 -61.136223) (xy 32.589873 -61.118216)
			(xy 32.644716 -61.108086) (xy 32.70045 -61.106049) (xy 32.755887 -61.112149) (xy 32.809844 -61.126255)
			(xy 32.861173 -61.148067) (xy 32.908779 -61.177121) (xy 32.951647 -61.212796) (xy 32.988864 -61.254333)
			(xy 33.019637 -61.300846) (xy 33.043309 -61.351343) (xy 33.055404 -61.391546) (xy 34.838638 -61.391546)
			(xy 34.842709 -61.335924) (xy 34.854835 -61.281487) (xy 34.874758 -61.229396) (xy 34.902054 -61.180761)
			(xy 34.93614 -61.136618) (xy 34.976289 -61.097909) (xy 35.021647 -61.065458) (xy 35.071247 -61.039957)
			(xy 35.124031 -61.02195) (xy 35.178874 -61.01182) (xy 35.234608 -61.009783) (xy 35.290045 -61.015883)
			(xy 35.344002 -61.029989) (xy 35.395331 -61.051801) (xy 35.442937 -61.080855) (xy 35.485805 -61.11653)
			(xy 35.523022 -61.158067) (xy 35.553795 -61.20458) (xy 35.577467 -61.255077) (xy 35.593535 -61.308484)
			(xy 35.601655 -61.36366) (xy 35.602164 -61.391546) (xy 35.601655 -61.419432) (xy 35.593535 -61.474608)
			(xy 35.577467 -61.528015) (xy 35.553795 -61.578512) (xy 35.523022 -61.625025) (xy 35.485805 -61.666562)
			(xy 35.442937 -61.702237) (xy 35.395331 -61.731291) (xy 35.344002 -61.753103) (xy 35.290045 -61.767209)
			(xy 35.234608 -61.773309) (xy 35.178874 -61.771272) (xy 35.124031 -61.761142) (xy 35.071247 -61.743135)
			(xy 35.021647 -61.717634) (xy 34.976289 -61.685183) (xy 34.93614 -61.646474) (xy 34.902054 -61.602331)
			(xy 34.874758 -61.553696) (xy 34.854835 -61.501605) (xy 34.842709 -61.447168) (xy 34.838638 -61.391546)
			(xy 33.055404 -61.391546) (xy 33.059377 -61.40475) (xy 33.067497 -61.459926) (xy 33.068006 -61.487812)
			(xy 33.067497 -61.515698) (xy 33.059377 -61.570874) (xy 33.043309 -61.624281) (xy 33.019637 -61.674778)
			(xy 32.988864 -61.721291) (xy 32.951647 -61.762828) (xy 32.908779 -61.798503) (xy 32.861173 -61.827557)
			(xy 32.809844 -61.849369) (xy 32.755887 -61.863475) (xy 32.70045 -61.869575) (xy 32.644716 -61.867538)
			(xy 32.589873 -61.857408) (xy 32.537089 -61.839401) (xy 32.487489 -61.8139) (xy 32.442131 -61.781449)
			(xy 32.401982 -61.74274) (xy 32.367896 -61.698597) (xy 32.3406 -61.649962) (xy 32.320677 -61.597871)
			(xy 32.308551 -61.543434) (xy 32.30448 -61.487812) (xy 0.715772 -61.487812) (xy 0.715772 -62.121034)
			(xy 4.242306 -62.121034) (xy 4.246377 -62.065412) (xy 4.258503 -62.010975) (xy 4.278426 -61.958884)
			(xy 4.305722 -61.910249) (xy 4.339808 -61.866106) (xy 4.379957 -61.827397) (xy 4.425315 -61.794946)
			(xy 4.474915 -61.769445) (xy 4.527699 -61.751438) (xy 4.582542 -61.741308) (xy 4.638276 -61.739271)
			(xy 4.693713 -61.745371) (xy 4.74767 -61.759477) (xy 4.798999 -61.781289) (xy 4.846605 -61.810343)
			(xy 4.889473 -61.846018) (xy 4.92669 -61.887555) (xy 4.957463 -61.934068) (xy 4.981135 -61.984565)
			(xy 4.997203 -62.037972) (xy 5.005323 -62.093148) (xy 5.005832 -62.121034) (xy 5.005323 -62.14892)
			(xy 4.997203 -62.204096) (xy 4.981135 -62.257503) (xy 4.957463 -62.308) (xy 4.92669 -62.354513) (xy 4.889473 -62.39605)
			(xy 4.846605 -62.431725) (xy 4.798999 -62.460779) (xy 4.74767 -62.482591) (xy 4.693713 -62.496697)
			(xy 4.638276 -62.502797) (xy 4.582542 -62.50076) (xy 4.527699 -62.49063) (xy 4.474915 -62.472623)
			(xy 4.425315 -62.447122) (xy 4.379957 -62.414671) (xy 4.339808 -62.375962) (xy 4.305722 -62.331819)
			(xy 4.278426 -62.283184) (xy 4.258503 -62.231093) (xy 4.246377 -62.176656) (xy 4.242306 -62.121034)
			(xy 0.715772 -62.121034) (xy 0.715772 -62.733236) (xy 7.66615 -62.733236) (xy 7.666153 -62.678729)
			(xy 7.673912 -62.624777) (xy 7.689272 -62.572478) (xy 7.711917 -62.522898) (xy 7.741389 -62.477045)
			(xy 7.777086 -62.435854) (xy 7.818282 -62.400161) (xy 7.864138 -62.370696) (xy 7.913721 -62.348056)
			(xy 7.966021 -62.332703) (xy 8.019974 -62.324949) (xy 8.047228 -62.324488) (xy 8.070783 -62.324863)
			(xy 8.117527 -62.330723) (xy 8.140446 -62.336172) (xy 8.154202 -62.33921) (xy 8.182352 -62.338354)
			(xy 8.209199 -62.329848) (xy 8.232706 -62.314337) (xy 8.251087 -62.292999) (xy 8.262946 -62.267454)
			(xy 8.267383 -62.239643) (xy 8.264061 -62.211677) (xy 8.259064 -62.198504) (xy 8.249754 -62.175114)
			(xy 8.236628 -62.126514) (xy 8.230005 -62.076609) (xy 8.2296 -62.051438) (xy 8.230067 -62.024185)
			(xy 8.237825 -61.970235) (xy 8.253181 -61.917937) (xy 8.275824 -61.868357) (xy 8.305292 -61.822505)
			(xy 8.340985 -61.781312) (xy 8.382178 -61.745619) (xy 8.428031 -61.716152) (xy 8.477611 -61.69351)
			(xy 8.529909 -61.678154) (xy 8.583859 -61.670397) (xy 8.638365 -61.670397) (xy 8.692315 -61.678155)
			(xy 8.744613 -61.693511) (xy 8.794193 -61.716154) (xy 8.840045 -61.745622) (xy 8.881238 -61.781315)
			(xy 8.916931 -61.822508) (xy 8.946398 -61.868361) (xy 8.96904 -61.917941) (xy 8.984396 -61.970239)
			(xy 8.992153 -62.024189) (xy 8.992153 -62.078695) (xy 8.986065 -62.121034) (xy 30.242254 -62.121034)
			(xy 30.246325 -62.065412) (xy 30.258451 -62.010975) (xy 30.278374 -61.958884) (xy 30.30567 -61.910249)
			(xy 30.339756 -61.866106) (xy 30.379905 -61.827397) (xy 30.425263 -61.794946) (xy 30.474863 -61.769445)
			(xy 30.527647 -61.751438) (xy 30.58249 -61.741308) (xy 30.638224 -61.739271) (xy 30.693661 -61.745371)
			(xy 30.747618 -61.759477) (xy 30.798947 -61.781289) (xy 30.846553 -61.810343) (xy 30.889421 -61.846018)
			(xy 30.926638 -61.887555) (xy 30.957411 -61.934068) (xy 30.981083 -61.984565) (xy 30.997151 -62.037972)
			(xy 31.005271 -62.093148) (xy 31.00578 -62.121034) (xy 31.005271 -62.14892) (xy 30.997151 -62.204096)
			(xy 30.981083 -62.257503) (xy 30.957411 -62.308) (xy 30.926638 -62.354513) (xy 30.889421 -62.39605)
			(xy 30.846553 -62.431725) (xy 30.798947 -62.460779) (xy 30.747618 -62.482591) (xy 30.693661 -62.496697)
			(xy 30.638224 -62.502797) (xy 30.58249 -62.50076) (xy 30.527647 -62.49063) (xy 30.474863 -62.472623)
			(xy 30.425263 -62.447122) (xy 30.379905 -62.414671) (xy 30.339756 -62.375962) (xy 30.30567 -62.331819)
			(xy 30.278374 -62.283184) (xy 30.258451 -62.231093) (xy 30.246325 -62.176656) (xy 30.242254 -62.121034)
			(xy 8.986065 -62.121034) (xy 8.984395 -62.132645) (xy 8.969039 -62.184943) (xy 8.946396 -62.234523)
			(xy 8.916928 -62.280375) (xy 8.881235 -62.321568) (xy 8.840042 -62.357261) (xy 8.794189 -62.386728)
			(xy 8.744609 -62.40937) (xy 8.692311 -62.424726) (xy 8.638361 -62.432483) (xy 8.611108 -62.432946)
			(xy 8.587554 -62.432564) (xy 8.540809 -62.426708) (xy 8.51789 -62.421262) (xy 8.504134 -62.418214)
			(xy 8.475978 -62.419062) (xy 8.449124 -62.427564) (xy 8.425611 -62.443076) (xy 8.407227 -62.464418)
			(xy 8.395369 -62.489969) (xy 8.390937 -62.517786) (xy 8.394269 -62.545757) (xy 8.399272 -62.55893)
			(xy 8.408595 -62.582315) (xy 8.421715 -62.630918) (xy 8.428333 -62.680824) (xy 8.428736 -62.705996)
			(xy 8.428249 -62.73325) (xy 8.420492 -62.787202) (xy 8.405136 -62.839502) (xy 8.382493 -62.889083)
			(xy 8.353024 -62.934938) (xy 8.317329 -62.976131) (xy 8.276135 -63.011826) (xy 8.230281 -63.041294)
			(xy 8.180699 -63.063937) (xy 8.1284 -63.079293) (xy 8.074447 -63.087049) (xy 8.01994 -63.087048)
			(xy 7.965987 -63.07929) (xy 7.913688 -63.063932) (xy 7.864108 -63.041288) (xy 7.818254 -63.011818)
			(xy 7.777061 -62.976122) (xy 7.741368 -62.934927) (xy 7.711901 -62.889071) (xy 7.689259 -62.839489)
			(xy 7.673905 -62.787189) (xy 7.66615 -62.733236) (xy 0.715772 -62.733236) (xy 0.715772 -63.273432)
			(xy 3.576826 -63.273432) (xy 3.580897 -63.21781) (xy 3.593023 -63.163373) (xy 3.612946 -63.111282)
			(xy 3.640242 -63.062647) (xy 3.674328 -63.018504) (xy 3.714477 -62.979795) (xy 3.759835 -62.947344)
			(xy 3.809435 -62.921843) (xy 3.862219 -62.903836) (xy 3.917062 -62.893706) (xy 3.972796 -62.891669)
			(xy 4.028233 -62.897769) (xy 4.08219 -62.911875) (xy 4.133519 -62.933687) (xy 4.181125 -62.962741)
			(xy 4.223993 -62.998416) (xy 4.26121 -63.039953) (xy 4.291983 -63.086466) (xy 4.315655 -63.136963)
			(xy 4.331723 -63.19037) (xy 4.335134 -63.213549) (xy 22.120888 -63.213549) (xy 22.120888 -63.159051)
			(xy 22.128643 -63.105109) (xy 22.143996 -63.052818) (xy 22.166634 -63.003245) (xy 22.196095 -62.957398)
			(xy 22.231782 -62.91621) (xy 22.272966 -62.880519) (xy 22.31881 -62.851053) (xy 22.368381 -62.82841)
			(xy 22.420669 -62.813052) (xy 22.474611 -62.805291) (xy 22.50186 -62.804802) (xy 22.529229 -62.805291)
			(xy 22.583408 -62.813103) (xy 22.63591 -62.828587) (xy 22.685658 -62.851424) (xy 22.731626 -62.881143)
			(xy 22.752558 -62.898782) (xy 22.752812 -62.899036) (xy 22.759888 -62.904638) (xy 22.776813 -62.910874)
			(xy 22.785832 -62.911228) (xy 22.852888 -62.911228) (xy 22.861904 -62.910859) (xy 22.87882 -62.904619)
			(xy 22.885908 -62.899036) (xy 22.885908 -62.898782) (xy 22.886162 -62.898782) (xy 22.907095 -62.881141)
			(xy 22.953063 -62.851417) (xy 23.002809 -62.828571) (xy 23.055311 -62.813075) (xy 23.109489 -62.805246)
			(xy 23.164231 -62.805246) (xy 23.218409 -62.813075) (xy 23.270911 -62.828571) (xy 23.320657 -62.851417)
			(xy 23.366625 -62.881141) (xy 23.387558 -62.898782) (xy 23.387812 -62.899036) (xy 23.394888 -62.904638)
			(xy 23.411813 -62.910874) (xy 23.420832 -62.911228) (xy 23.487888 -62.911228) (xy 23.496904 -62.910859)
			(xy 23.51382 -62.904619) (xy 23.520908 -62.899036) (xy 23.520908 -62.898782) (xy 23.521162 -62.898782)
			(xy 23.542095 -62.881144) (xy 23.588068 -62.851433) (xy 23.637815 -62.828597) (xy 23.690316 -62.813106)
			(xy 23.744491 -62.805277) (xy 23.77186 -62.804802) (xy 23.799115 -62.805242) (xy 23.853072 -62.812995)
			(xy 23.905376 -62.828348) (xy 23.954963 -62.850989) (xy 24.000822 -62.880456) (xy 24.042021 -62.916151)
			(xy 24.07772 -62.957346) (xy 24.107192 -63.003202) (xy 24.129838 -63.052786) (xy 24.13966 -63.086234)
			(xy 27.387548 -63.086234) (xy 27.391619 -63.030612) (xy 27.403745 -62.976175) (xy 27.423668 -62.924084)
			(xy 27.450964 -62.875449) (xy 27.48505 -62.831306) (xy 27.525199 -62.792597) (xy 27.570557 -62.760146)
			(xy 27.620157 -62.734645) (xy 27.672941 -62.716638) (xy 27.727784 -62.706508) (xy 27.783518 -62.704471)
			(xy 27.797377 -62.705996) (xy 33.665158 -62.705996) (xy 33.669229 -62.650374) (xy 33.681355 -62.595937)
			(xy 33.701278 -62.543846) (xy 33.728574 -62.495211) (xy 33.76266 -62.451068) (xy 33.802809 -62.412359)
			(xy 33.848167 -62.379908) (xy 33.897767 -62.354407) (xy 33.950551 -62.3364) (xy 34.005394 -62.32627)
			(xy 34.061128 -62.324233) (xy 34.116565 -62.330333) (xy 34.170522 -62.344439) (xy 34.221851 -62.366251)
			(xy 34.269457 -62.395305) (xy 34.312325 -62.43098) (xy 34.349542 -62.472517) (xy 34.380315 -62.51903)
			(xy 34.403987 -62.569527) (xy 34.420055 -62.622934) (xy 34.428175 -62.67811) (xy 34.428684 -62.705996)
			(xy 34.428175 -62.733882) (xy 34.420055 -62.789058) (xy 34.403987 -62.842465) (xy 34.380315 -62.892962)
			(xy 34.349542 -62.939475) (xy 34.312325 -62.981012) (xy 34.269457 -63.016687) (xy 34.221851 -63.045741)
			(xy 34.170522 -63.067553) (xy 34.116565 -63.081659) (xy 34.061128 -63.087759) (xy 34.005394 -63.085722)
			(xy 33.950551 -63.075592) (xy 33.897767 -63.057585) (xy 33.848167 -63.032084) (xy 33.802809 -62.999633)
			(xy 33.76266 -62.960924) (xy 33.728574 -62.916781) (xy 33.701278 -62.868146) (xy 33.681355 -62.816055)
			(xy 33.669229 -62.761618) (xy 33.665158 -62.705996) (xy 27.797377 -62.705996) (xy 27.838955 -62.710571)
			(xy 27.892912 -62.724677) (xy 27.944241 -62.746489) (xy 27.991847 -62.775543) (xy 28.034715 -62.811218)
			(xy 28.071932 -62.852755) (xy 28.102705 -62.899268) (xy 28.126377 -62.949765) (xy 28.142445 -63.003172)
			(xy 28.150565 -63.058348) (xy 28.151074 -63.086234) (xy 28.150565 -63.11412) (xy 28.142445 -63.169296)
			(xy 28.126377 -63.222703) (xy 28.102705 -63.2732) (xy 28.102552 -63.273432) (xy 29.576774 -63.273432)
			(xy 29.580845 -63.21781) (xy 29.592971 -63.163373) (xy 29.612894 -63.111282) (xy 29.64019 -63.062647)
			(xy 29.674276 -63.018504) (xy 29.714425 -62.979795) (xy 29.759783 -62.947344) (xy 29.809383 -62.921843)
			(xy 29.862167 -62.903836) (xy 29.91701 -62.893706) (xy 29.972744 -62.891669) (xy 30.028181 -62.897769)
			(xy 30.082138 -62.911875) (xy 30.133467 -62.933687) (xy 30.181073 -62.962741) (xy 30.223941 -62.998416)
			(xy 30.261158 -63.039953) (xy 30.291931 -63.086466) (xy 30.315603 -63.136963) (xy 30.331671 -63.19037)
			(xy 30.339791 -63.245546) (xy 30.3403 -63.273432) (xy 30.339791 -63.301318) (xy 30.331671 -63.356494)
			(xy 30.315603 -63.409901) (xy 30.291931 -63.460398) (xy 30.261158 -63.506911) (xy 30.223941 -63.548448)
			(xy 30.181073 -63.584123) (xy 30.133467 -63.613177) (xy 30.082138 -63.634989) (xy 30.028181 -63.649095)
			(xy 29.972744 -63.655195) (xy 29.91701 -63.653158) (xy 29.862167 -63.643028) (xy 29.809383 -63.625021)
			(xy 29.759783 -63.59952) (xy 29.714425 -63.567069) (xy 29.674276 -63.52836) (xy 29.64019 -63.484217)
			(xy 29.612894 -63.435582) (xy 29.592971 -63.383491) (xy 29.580845 -63.329054) (xy 29.576774 -63.273432)
			(xy 28.102552 -63.273432) (xy 28.071932 -63.319713) (xy 28.034715 -63.36125) (xy 27.991847 -63.396925)
			(xy 27.944241 -63.425979) (xy 27.892912 -63.447791) (xy 27.838955 -63.461897) (xy 27.783518 -63.467997)
			(xy 27.727784 -63.46596) (xy 27.672941 -63.45583) (xy 27.620157 -63.437823) (xy 27.570557 -63.412322)
			(xy 27.525199 -63.379871) (xy 27.48505 -63.341162) (xy 27.450964 -63.297019) (xy 27.423668 -63.248384)
			(xy 27.403745 -63.196293) (xy 27.391619 -63.141856) (xy 27.387548 -63.086234) (xy 24.13966 -63.086234)
			(xy 24.145197 -63.105089) (xy 24.152955 -63.159045) (xy 24.152955 -63.213555) (xy 24.145197 -63.267511)
			(xy 24.129838 -63.319814) (xy 24.107192 -63.369398) (xy 24.07772 -63.415254) (xy 24.042021 -63.456449)
			(xy 24.000822 -63.492144) (xy 23.954963 -63.521611) (xy 23.905376 -63.544252) (xy 23.853072 -63.559605)
			(xy 23.799115 -63.567358) (xy 23.77186 -63.567818) (xy 23.74449 -63.567337) (xy 23.690311 -63.559526)
			(xy 23.637807 -63.544041) (xy 23.58806 -63.521202) (xy 23.542093 -63.491479) (xy 23.521162 -63.473838)
			(xy 23.520908 -63.473584) (xy 23.513825 -63.467993) (xy 23.496905 -63.461749) (xy 23.487888 -63.461392)
			(xy 23.420832 -63.461392) (xy 23.411817 -63.461766) (xy 23.3949 -63.468002) (xy 23.387812 -63.473584)
			(xy 23.387558 -63.473838) (xy 23.366625 -63.491479) (xy 23.320657 -63.521203) (xy 23.270911 -63.544049)
			(xy 23.218409 -63.559545) (xy 23.164231 -63.567374) (xy 23.109489 -63.567374) (xy 23.055311 -63.559545)
			(xy 23.002809 -63.544049) (xy 22.953063 -63.521203) (xy 22.907095 -63.491479) (xy 22.886162 -63.473838)
			(xy 22.885908 -63.473584) (xy 22.878825 -63.467993) (xy 22.861905 -63.461749) (xy 22.852888 -63.461392)
			(xy 22.785832 -63.461392) (xy 22.776817 -63.461766) (xy 22.7599 -63.468002) (xy 22.752812 -63.473584)
			(xy 22.752812 -63.473838) (xy 22.752558 -63.473838) (xy 22.73162 -63.49147) (xy 22.685648 -63.521181)
			(xy 22.635902 -63.544018) (xy 22.583403 -63.559511) (xy 22.529229 -63.567343) (xy 22.50186 -63.567818)
			(xy 22.474611 -63.567309) (xy 22.420669 -63.559548) (xy 22.368381 -63.54419) (xy 22.31881 -63.521547)
			(xy 22.272966 -63.492081) (xy 22.231782 -63.45639) (xy 22.196095 -63.415202) (xy 22.166634 -63.369355)
			(xy 22.143996 -63.319782) (xy 22.128643 -63.267491) (xy 22.120888 -63.213549) (xy 4.335134 -63.213549)
			(xy 4.339843 -63.245546) (xy 4.340352 -63.273432) (xy 4.339843 -63.301318) (xy 4.331723 -63.356494)
			(xy 4.315655 -63.409901) (xy 4.291983 -63.460398) (xy 4.26121 -63.506911) (xy 4.223993 -63.548448)
			(xy 4.181125 -63.584123) (xy 4.133519 -63.613177) (xy 4.08219 -63.634989) (xy 4.028233 -63.649095)
			(xy 3.972796 -63.655195) (xy 3.917062 -63.653158) (xy 3.862219 -63.643028) (xy 3.809435 -63.625021)
			(xy 3.759835 -63.59952) (xy 3.714477 -63.567069) (xy 3.674328 -63.52836) (xy 3.640242 -63.484217)
			(xy 3.612946 -63.435582) (xy 3.593023 -63.383491) (xy 3.580897 -63.329054) (xy 3.576826 -63.273432)
			(xy 0.715772 -63.273432) (xy 0.715772 -64.737234) (xy 1.896362 -64.737234) (xy 1.900433 -64.681612)
			(xy 1.912559 -64.627175) (xy 1.932482 -64.575084) (xy 1.959778 -64.526449) (xy 1.993864 -64.482306)
			(xy 2.034013 -64.443597) (xy 2.079371 -64.411146) (xy 2.128971 -64.385645) (xy 2.181755 -64.367638)
			(xy 2.236598 -64.357508) (xy 2.292332 -64.355471) (xy 2.347769 -64.361571) (xy 2.401726 -64.375677)
			(xy 2.453055 -64.397489) (xy 2.500661 -64.426543) (xy 2.543529 -64.462218) (xy 2.580746 -64.503755)
			(xy 2.611519 -64.550268) (xy 2.635191 -64.600765) (xy 2.651259 -64.654172) (xy 2.659379 -64.709348)
			(xy 2.659888 -64.737234) (xy 2.659379 -64.76512) (xy 2.651259 -64.820296) (xy 2.635191 -64.873703)
			(xy 2.611519 -64.9242) (xy 2.580746 -64.970713) (xy 2.543529 -65.01225) (xy 2.500661 -65.047925)
			(xy 2.453055 -65.076979) (xy 2.401726 -65.098791) (xy 2.347769 -65.112897) (xy 2.292332 -65.118997)
			(xy 2.236598 -65.11696) (xy 2.181755 -65.10683) (xy 2.128971 -65.088823) (xy 2.079371 -65.063322)
			(xy 2.034013 -65.030871) (xy 1.993864 -64.992162) (xy 1.959778 -64.948019) (xy 1.932482 -64.899384)
			(xy 1.912559 -64.847293) (xy 1.900433 -64.792856) (xy 1.896362 -64.737234) (xy 0.715772 -64.737234)
			(xy 0.715772 -65.124076) (xy 6.107428 -65.124076) (xy 6.111499 -65.068454) (xy 6.123625 -65.014017)
			(xy 6.143548 -64.961926) (xy 6.170844 -64.913291) (xy 6.20493 -64.869148) (xy 6.245079 -64.830439)
			(xy 6.290437 -64.797988) (xy 6.340037 -64.772487) (xy 6.392821 -64.75448) (xy 6.447664 -64.74435)
			(xy 6.503398 -64.742313) (xy 6.558835 -64.748413) (xy 6.612792 -64.762519) (xy 6.664121 -64.784331)
			(xy 6.711727 -64.813385) (xy 6.754595 -64.84906) (xy 6.791812 -64.890597) (xy 6.822585 -64.93711)
			(xy 6.846257 -64.987607) (xy 6.862325 -65.041014) (xy 6.870445 -65.09619) (xy 6.870532 -65.100962)
			(xy 20.132546 -65.100962) (xy 20.136617 -65.04534) (xy 20.148743 -64.990903) (xy 20.168666 -64.938812)
			(xy 20.195962 -64.890177) (xy 20.230048 -64.846034) (xy 20.270197 -64.807325) (xy 20.315555 -64.774874)
			(xy 20.365155 -64.749373) (xy 20.417939 -64.731366) (xy 20.472782 -64.721236) (xy 20.528516 -64.719199)
			(xy 20.583953 -64.725299) (xy 20.63791 -64.739405) (xy 20.689239 -64.761217) (xy 20.736845 -64.790271)
			(xy 20.779713 -64.825946) (xy 20.81693 -64.867483) (xy 20.847703 -64.913996) (xy 20.871375 -64.964493)
			(xy 20.887443 -65.0179) (xy 20.895563 -65.073076) (xy 20.896072 -65.100962) (xy 20.89565 -65.124076)
			(xy 32.107376 -65.124076) (xy 32.111447 -65.068454) (xy 32.123573 -65.014017) (xy 32.143496 -64.961926)
			(xy 32.170792 -64.913291) (xy 32.204878 -64.869148) (xy 32.245027 -64.830439) (xy 32.290385 -64.797988)
			(xy 32.339985 -64.772487) (xy 32.392769 -64.75448) (xy 32.447612 -64.74435) (xy 32.503346 -64.742313)
			(xy 32.558783 -64.748413) (xy 32.61274 -64.762519) (xy 32.664069 -64.784331) (xy 32.711675 -64.813385)
			(xy 32.754543 -64.84906) (xy 32.79176 -64.890597) (xy 32.822533 -64.93711) (xy 32.846205 -64.987607)
			(xy 32.862273 -65.041014) (xy 32.870393 -65.09619) (xy 32.870902 -65.124076) (xy 32.870393 -65.151962)
			(xy 32.862273 -65.207138) (xy 32.846205 -65.260545) (xy 32.822533 -65.311042) (xy 32.79176 -65.357555)
			(xy 32.754543 -65.399092) (xy 32.711675 -65.434767) (xy 32.664069 -65.463821) (xy 32.61274 -65.485633)
			(xy 32.558783 -65.499739) (xy 32.503346 -65.505839) (xy 32.447612 -65.503802) (xy 32.392769 -65.493672)
			(xy 32.339985 -65.475665) (xy 32.290385 -65.450164) (xy 32.245027 -65.417713) (xy 32.204878 -65.379004)
			(xy 32.170792 -65.334861) (xy 32.143496 -65.286226) (xy 32.123573 -65.234135) (xy 32.111447 -65.179698)
			(xy 32.107376 -65.124076) (xy 20.89565 -65.124076) (xy 20.895563 -65.128848) (xy 20.887443 -65.184024)
			(xy 20.871375 -65.237431) (xy 20.847703 -65.287928) (xy 20.81693 -65.334441) (xy 20.779713 -65.375978)
			(xy 20.736845 -65.411653) (xy 20.689239 -65.440707) (xy 20.63791 -65.462519) (xy 20.583953 -65.476625)
			(xy 20.528516 -65.482725) (xy 20.472782 -65.480688) (xy 20.417939 -65.470558) (xy 20.365155 -65.452551)
			(xy 20.315555 -65.42705) (xy 20.270197 -65.394599) (xy 20.230048 -65.35589) (xy 20.195962 -65.311747)
			(xy 20.168666 -65.263112) (xy 20.148743 -65.211021) (xy 20.136617 -65.156584) (xy 20.132546 -65.100962)
			(xy 6.870532 -65.100962) (xy 6.870954 -65.124076) (xy 6.870445 -65.151962) (xy 6.862325 -65.207138)
			(xy 6.846257 -65.260545) (xy 6.822585 -65.311042) (xy 6.791812 -65.357555) (xy 6.754595 -65.399092)
			(xy 6.711727 -65.434767) (xy 6.664121 -65.463821) (xy 6.612792 -65.485633) (xy 6.558835 -65.499739)
			(xy 6.503398 -65.505839) (xy 6.447664 -65.503802) (xy 6.392821 -65.493672) (xy 6.340037 -65.475665)
			(xy 6.290437 -65.450164) (xy 6.245079 -65.417713) (xy 6.20493 -65.379004) (xy 6.170844 -65.334861)
			(xy 6.143548 -65.286226) (xy 6.123625 -65.234135) (xy 6.111499 -65.179698) (xy 6.107428 -65.124076)
			(xy 0.715772 -65.124076) (xy 0.715772 -65.882774) (xy 3.101592 -65.882774) (xy 3.105663 -65.827152)
			(xy 3.117789 -65.772715) (xy 3.137712 -65.720624) (xy 3.165008 -65.671989) (xy 3.199094 -65.627846)
			(xy 3.239243 -65.589137) (xy 3.284601 -65.556686) (xy 3.334201 -65.531185) (xy 3.386985 -65.513178)
			(xy 3.441828 -65.503048) (xy 3.497562 -65.501011) (xy 3.552999 -65.507111) (xy 3.606956 -65.521217)
			(xy 3.658285 -65.543029) (xy 3.705891 -65.572083) (xy 3.748759 -65.607758) (xy 3.785976 -65.649295)
			(xy 3.816749 -65.695808) (xy 3.840421 -65.746305) (xy 3.843193 -65.75552) (xy 14.34668 -65.75552)
			(xy 14.350751 -65.699898) (xy 14.362877 -65.645461) (xy 14.3828 -65.59337) (xy 14.410096 -65.544735)
			(xy 14.444182 -65.500592) (xy 14.484331 -65.461883) (xy 14.529689 -65.429432) (xy 14.579289 -65.403931)
			(xy 14.632073 -65.385924) (xy 14.686916 -65.375794) (xy 14.74265 -65.373757) (xy 14.798087 -65.379857)
			(xy 14.852044 -65.393963) (xy 14.903373 -65.415775) (xy 14.950979 -65.444829) (xy 14.993847 -65.480504)
			(xy 15.031064 -65.522041) (xy 15.061837 -65.568554) (xy 15.085509 -65.619051) (xy 15.101577 -65.672458)
			(xy 15.109697 -65.727634) (xy 15.110206 -65.75552) (xy 15.109697 -65.783406) (xy 15.101577 -65.838582)
			(xy 15.085509 -65.891989) (xy 15.061837 -65.942486) (xy 15.031064 -65.988999) (xy 14.993847 -66.030536)
			(xy 14.950979 -66.066211) (xy 14.903373 -66.095265) (xy 14.852044 -66.117077) (xy 14.798087 -66.131183)
			(xy 14.74265 -66.137283) (xy 14.686916 -66.135246) (xy 14.632073 -66.125116) (xy 14.579289 -66.107109)
			(xy 14.529689 -66.081608) (xy 14.484331 -66.049157) (xy 14.444182 -66.010448) (xy 14.410096 -65.966305)
			(xy 14.3828 -65.91767) (xy 14.362877 -65.865579) (xy 14.350751 -65.811142) (xy 14.34668 -65.75552)
			(xy 3.843193 -65.75552) (xy 3.856489 -65.799712) (xy 3.864609 -65.854888) (xy 3.865118 -65.882774)
			(xy 3.864609 -65.91066) (xy 3.856489 -65.965836) (xy 3.840421 -66.019243) (xy 3.816749 -66.06974)
			(xy 3.785976 -66.116253) (xy 3.748759 -66.15779) (xy 3.705891 -66.193465) (xy 3.658285 -66.222519)
			(xy 3.606956 -66.244331) (xy 3.552999 -66.258437) (xy 3.497562 -66.264537) (xy 3.441828 -66.2625)
			(xy 3.386985 -66.25237) (xy 3.334201 -66.234363) (xy 3.284601 -66.208862) (xy 3.239243 -66.176411)
			(xy 3.199094 -66.137702) (xy 3.165008 -66.093559) (xy 3.137712 -66.044924) (xy 3.117789 -65.992833)
			(xy 3.105663 -65.938396) (xy 3.101592 -65.882774) (xy 0.715772 -65.882774) (xy 0.715772 -66.567812)
			(xy 6.304532 -66.567812) (xy 6.308603 -66.51219) (xy 6.320729 -66.457753) (xy 6.340652 -66.405662)
			(xy 6.367948 -66.357027) (xy 6.402034 -66.312884) (xy 6.442183 -66.274175) (xy 6.487541 -66.241724)
			(xy 6.537141 -66.216223) (xy 6.589925 -66.198216) (xy 6.644768 -66.188086) (xy 6.700502 -66.186049)
			(xy 6.755939 -66.192149) (xy 6.809896 -66.206255) (xy 6.861225 -66.228067) (xy 6.908831 -66.257121)
			(xy 6.951699 -66.292796) (xy 6.988916 -66.334333) (xy 7.019689 -66.380846) (xy 7.043361 -66.431343)
			(xy 7.059429 -66.48475) (xy 7.067549 -66.539926) (xy 7.068058 -66.567812) (xy 7.067549 -66.595698)
			(xy 7.059429 -66.650874) (xy 7.043361 -66.704281) (xy 7.019689 -66.754778) (xy 6.988916 -66.801291)
			(xy 6.951699 -66.842828) (xy 6.908831 -66.878503) (xy 6.861225 -66.907557) (xy 6.809896 -66.929369)
			(xy 6.755939 -66.943475) (xy 6.700502 -66.949575) (xy 6.644768 -66.947538) (xy 6.589925 -66.937408)
			(xy 6.537141 -66.919401) (xy 6.487541 -66.8939) (xy 6.442183 -66.861449) (xy 6.402034 -66.82274)
			(xy 6.367948 -66.778597) (xy 6.340652 -66.729962) (xy 6.320729 -66.677871) (xy 6.308603 -66.623434)
			(xy 6.304532 -66.567812) (xy 0.715772 -66.567812) (xy 0.715772 -67.201034) (xy 4.242306 -67.201034)
			(xy 4.246377 -67.145412) (xy 4.258503 -67.090975) (xy 4.278426 -67.038884) (xy 4.305722 -66.990249)
			(xy 4.339808 -66.946106) (xy 4.379957 -66.907397) (xy 4.425315 -66.874946) (xy 4.474915 -66.849445)
			(xy 4.527699 -66.831438) (xy 4.582542 -66.821308) (xy 4.638276 -66.819271) (xy 4.693713 -66.825371)
			(xy 4.74767 -66.839477) (xy 4.798999 -66.861289) (xy 4.846605 -66.890343) (xy 4.889473 -66.926018)
			(xy 4.92669 -66.967555) (xy 4.957463 -67.014068) (xy 4.981135 -67.064565) (xy 4.997203 -67.117972)
			(xy 4.998822 -67.128971) (xy 14.366728 -67.128971) (xy 14.366728 -67.074469) (xy 14.374484 -67.020521)
			(xy 14.389839 -66.968227) (xy 14.41248 -66.91865) (xy 14.441946 -66.872799) (xy 14.477638 -66.831609)
			(xy 14.518828 -66.795918) (xy 14.564678 -66.766451) (xy 14.614255 -66.74381) (xy 14.666549 -66.728455)
			(xy 14.720497 -66.720698) (xy 14.747748 -66.720212) (xy 14.775117 -66.720706) (xy 14.829295 -66.728516)
			(xy 14.881798 -66.743999) (xy 14.931546 -66.766834) (xy 14.977514 -66.796553) (xy 14.998446 -66.814192)
			(xy 14.9987 -66.814446) (xy 15.005778 -66.820044) (xy 15.022702 -66.826283) (xy 15.03172 -66.826638)
			(xy 15.098776 -66.826638) (xy 15.107791 -66.826261) (xy 15.124707 -66.820026) (xy 15.131796 -66.814446)
			(xy 15.131796 -66.814192) (xy 15.13205 -66.814192) (xy 15.152989 -66.796562) (xy 15.19896 -66.766849)
			(xy 15.248706 -66.744011) (xy 15.301205 -66.728518) (xy 15.355379 -66.720687) (xy 15.382748 -66.720212)
			(xy 15.410001 -66.720675) (xy 15.463952 -66.728432) (xy 15.51625 -66.743788) (xy 15.565831 -66.76643)
			(xy 15.611684 -66.795898) (xy 15.652877 -66.831592) (xy 15.688571 -66.872784) (xy 15.718039 -66.918638)
			(xy 15.740682 -66.968218) (xy 15.756038 -67.020516) (xy 15.763795 -67.074467) (xy 15.763795 -67.128973)
			(xy 15.756038 -67.182924) (xy 15.740682 -67.235222) (xy 15.718039 -67.284802) (xy 15.688571 -67.330656)
			(xy 15.652877 -67.371848) (xy 15.611684 -67.407542) (xy 15.565831 -67.43701) (xy 15.51625 -67.459652)
			(xy 15.463952 -67.475008) (xy 15.410001 -67.482765) (xy 15.382748 -67.483228) (xy 15.355378 -67.482751)
			(xy 15.301199 -67.474939) (xy 15.248695 -67.459453) (xy 15.198948 -67.436613) (xy 15.152981 -67.406889)
			(xy 15.13205 -67.389248) (xy 15.131796 -67.388994) (xy 15.124715 -67.383399) (xy 15.107794 -67.377158)
			(xy 15.098776 -67.376802) (xy 15.03172 -67.376802) (xy 15.022704 -67.377168) (xy 15.005787 -67.383409)
			(xy 14.9987 -67.388994) (xy 14.9987 -67.389248) (xy 14.998446 -67.389248) (xy 14.977501 -67.406871)
			(xy 14.931532 -67.436587) (xy 14.881788 -67.459427) (xy 14.82929 -67.474922) (xy 14.775116 -67.482753)
			(xy 14.747748 -67.483228) (xy 14.720497 -67.482742) (xy 14.666549 -67.474985) (xy 14.614255 -67.45963)
			(xy 14.564678 -67.436989) (xy 14.518828 -67.407522) (xy 14.477638 -67.371831) (xy 14.441946 -67.330641)
			(xy 14.41248 -67.28479) (xy 14.389839 -67.235213) (xy 14.374484 -67.182919) (xy 14.366728 -67.128971)
			(xy 4.998822 -67.128971) (xy 5.005323 -67.173148) (xy 5.005832 -67.201034) (xy 5.005323 -67.22892)
			(xy 4.997203 -67.284096) (xy 4.981135 -67.337503) (xy 4.957463 -67.388) (xy 4.92669 -67.434513) (xy 4.889473 -67.47605)
			(xy 4.846605 -67.511725) (xy 4.798999 -67.540779) (xy 4.74767 -67.562591) (xy 4.693713 -67.576697)
			(xy 4.638276 -67.582797) (xy 4.582542 -67.58076) (xy 4.527699 -67.57063) (xy 4.474915 -67.552623)
			(xy 4.425315 -67.527122) (xy 4.379957 -67.494671) (xy 4.339808 -67.455962) (xy 4.305722 -67.411819)
			(xy 4.278426 -67.363184) (xy 4.258503 -67.311093) (xy 4.246377 -67.256656) (xy 4.242306 -67.201034)
			(xy 0.715772 -67.201034) (xy 0.715772 -67.785996) (xy 7.66521 -67.785996) (xy 7.669281 -67.730374)
			(xy 7.681407 -67.675937) (xy 7.70133 -67.623846) (xy 7.728626 -67.575211) (xy 7.762712 -67.531068)
			(xy 7.802861 -67.492359) (xy 7.848219 -67.459908) (xy 7.897819 -67.434407) (xy 7.950603 -67.4164)
			(xy 8.005446 -67.40627) (xy 8.06118 -67.404233) (xy 8.116617 -67.410333) (xy 8.170574 -67.424439)
			(xy 8.221903 -67.446251) (xy 8.269509 -67.475305) (xy 8.284829 -67.488054) (xy 18.779234 -67.488054)
			(xy 18.783305 -67.432432) (xy 18.795431 -67.377995) (xy 18.815354 -67.325904) (xy 18.84265 -67.277269)
			(xy 18.876736 -67.233126) (xy 18.916885 -67.194417) (xy 18.962243 -67.161966) (xy 19.011843 -67.136465)
			(xy 19.064627 -67.118458) (xy 19.11947 -67.108328) (xy 19.175204 -67.106291) (xy 19.230641 -67.112391)
			(xy 19.284598 -67.126497) (xy 19.335927 -67.148309) (xy 19.383533 -67.177363) (xy 19.426401 -67.213038)
			(xy 19.463618 -67.254575) (xy 19.494391 -67.301088) (xy 19.518063 -67.351585) (xy 19.534131 -67.404992)
			(xy 19.542251 -67.460168) (xy 19.54276 -67.488054) (xy 19.542251 -67.51594) (xy 19.539066 -67.537584)
			(xy 20.071332 -67.537584) (xy 20.075403 -67.481962) (xy 20.087529 -67.427525) (xy 20.107452 -67.375434)
			(xy 20.134748 -67.326799) (xy 20.168834 -67.282656) (xy 20.208983 -67.243947) (xy 20.254341 -67.211496)
			(xy 20.303941 -67.185995) (xy 20.356725 -67.167988) (xy 20.411568 -67.157858) (xy 20.467302 -67.155821)
			(xy 20.522739 -67.161921) (xy 20.576696 -67.176027) (xy 20.628025 -67.197839) (xy 20.675631 -67.226893)
			(xy 20.718499 -67.262568) (xy 20.755716 -67.304105) (xy 20.786489 -67.350618) (xy 20.810161 -67.401115)
			(xy 20.826229 -67.454522) (xy 20.834349 -67.509698) (xy 20.834858 -67.537584) (xy 20.834349 -67.56547)
			(xy 20.830304 -67.592956) (xy 21.345396 -67.592956) (xy 21.349467 -67.537334) (xy 21.361593 -67.482897)
			(xy 21.381516 -67.430806) (xy 21.408812 -67.382171) (xy 21.442898 -67.338028) (xy 21.483047 -67.299319)
			(xy 21.528405 -67.266868) (xy 21.578005 -67.241367) (xy 21.630789 -67.22336) (xy 21.685632 -67.21323)
			(xy 21.741366 -67.211193) (xy 21.796803 -67.217293) (xy 21.85076 -67.231399) (xy 21.902089 -67.253211)
			(xy 21.949695 -67.282265) (xy 21.992563 -67.31794) (xy 22.02978 -67.359477) (xy 22.060553 -67.40599)
			(xy 22.084225 -67.456487) (xy 22.100293 -67.509894) (xy 22.10841 -67.565052) (xy 24.446693 -67.565052)
			(xy 24.446693 -67.510548) (xy 24.454451 -67.456599) (xy 24.469807 -67.404304) (xy 24.49245 -67.354726)
			(xy 24.521919 -67.308875) (xy 24.557613 -67.267686) (xy 24.598806 -67.231996) (xy 24.644659 -67.202532)
			(xy 24.694239 -67.179894) (xy 24.746536 -67.164542) (xy 24.800486 -67.156791) (xy 24.827738 -67.15633)
			(xy 24.855107 -67.156825) (xy 24.909285 -67.164635) (xy 24.961788 -67.180117) (xy 25.011536 -67.202952)
			(xy 25.057504 -67.232671) (xy 25.078436 -67.25031) (xy 25.07869 -67.250564) (xy 25.08577 -67.25616)
			(xy 25.102692 -67.262399) (xy 25.11171 -67.262756) (xy 25.178766 -67.262756) (xy 25.187782 -67.262392)
			(xy 25.2047 -67.25615) (xy 25.211786 -67.250564) (xy 25.211786 -67.25031) (xy 25.21204 -67.25031)
			(xy 25.232985 -67.232687) (xy 25.278954 -67.202973) (xy 25.328698 -67.180133) (xy 25.381196 -67.164638)
			(xy 25.43537 -67.156806) (xy 25.462738 -67.15633) (xy 25.48999 -67.156742) (xy 25.543939 -67.164504)
			(xy 25.596235 -67.179864) (xy 25.645812 -67.20251) (xy 25.691662 -67.23198) (xy 25.732852 -67.267675)
			(xy 25.768543 -67.308868) (xy 25.798009 -67.354721) (xy 25.820649 -67.404301) (xy 25.836004 -67.456598)
			(xy 25.84376 -67.510548) (xy 25.84376 -67.565052) (xy 25.836004 -67.619002) (xy 25.820649 -67.671299)
			(xy 25.798009 -67.720879) (xy 25.768543 -67.766732) (xy 25.732852 -67.807925) (xy 25.691662 -67.84362)
			(xy 25.645812 -67.87309) (xy 25.596235 -67.895736) (xy 25.543939 -67.911096) (xy 25.48999 -67.918858)
			(xy 25.462738 -67.919346) (xy 25.435368 -67.918871) (xy 25.381189 -67.911057) (xy 25.328685 -67.895571)
			(xy 25.278938 -67.872731) (xy 25.232971 -67.843007) (xy 25.21204 -67.825366) (xy 25.211786 -67.825112)
			(xy 25.204707 -67.819515) (xy 25.187784 -67.813274) (xy 25.178766 -67.81292) (xy 25.11171 -67.81292)
			(xy 25.102693 -67.813277) (xy 25.085776 -67.819524) (xy 25.07869 -67.825112) (xy 25.07869 -67.825366)
			(xy 25.078436 -67.825366) (xy 25.057497 -67.842996) (xy 25.011527 -67.872711) (xy 24.961781 -67.895549)
			(xy 24.909282 -67.911042) (xy 24.855107 -67.918871) (xy 24.827738 -67.919346) (xy 24.800486 -67.918809)
			(xy 24.746536 -67.911058) (xy 24.694239 -67.895706) (xy 24.644659 -67.873068) (xy 24.598806 -67.843604)
			(xy 24.557613 -67.807914) (xy 24.521919 -67.766725) (xy 24.49245 -67.720874) (xy 24.469807 -67.671296)
			(xy 24.454451 -67.619001) (xy 24.446693 -67.565052) (xy 22.10841 -67.565052) (xy 22.108413 -67.56507)
			(xy 22.108922 -67.592956) (xy 22.108413 -67.620842) (xy 22.100293 -67.676018) (xy 22.084225 -67.729425)
			(xy 22.060553 -67.779922) (xy 22.02978 -67.826435) (xy 21.992563 -67.867972) (xy 21.949695 -67.903647)
			(xy 21.902089 -67.932701) (xy 21.85076 -67.954513) (xy 21.796803 -67.968619) (xy 21.741366 -67.974719)
			(xy 21.685632 -67.972682) (xy 21.630789 -67.962552) (xy 21.578005 -67.944545) (xy 21.528405 -67.919044)
			(xy 21.483047 -67.886593) (xy 21.442898 -67.847884) (xy 21.408812 -67.803741) (xy 21.381516 -67.755106)
			(xy 21.361593 -67.703015) (xy 21.349467 -67.648578) (xy 21.345396 -67.592956) (xy 20.830304 -67.592956)
			(xy 20.826229 -67.620646) (xy 20.810161 -67.674053) (xy 20.786489 -67.72455) (xy 20.755716 -67.771063)
			(xy 20.718499 -67.8126) (xy 20.675631 -67.848275) (xy 20.628025 -67.877329) (xy 20.576696 -67.899141)
			(xy 20.522739 -67.913247) (xy 20.467302 -67.919347) (xy 20.411568 -67.91731) (xy 20.356725 -67.90718)
			(xy 20.303941 -67.889173) (xy 20.254341 -67.863672) (xy 20.208983 -67.831221) (xy 20.168834 -67.792512)
			(xy 20.134748 -67.748369) (xy 20.107452 -67.699734) (xy 20.087529 -67.647643) (xy 20.075403 -67.593206)
			(xy 20.071332 -67.537584) (xy 19.539066 -67.537584) (xy 19.534131 -67.571116) (xy 19.518063 -67.624523)
			(xy 19.494391 -67.67502) (xy 19.463618 -67.721533) (xy 19.426401 -67.76307) (xy 19.383533 -67.798745)
			(xy 19.335927 -67.827799) (xy 19.284598 -67.849611) (xy 19.230641 -67.863717) (xy 19.175204 -67.869817)
			(xy 19.11947 -67.86778) (xy 19.064627 -67.85765) (xy 19.011843 -67.839643) (xy 18.962243 -67.814142)
			(xy 18.916885 -67.781691) (xy 18.876736 -67.742982) (xy 18.84265 -67.698839) (xy 18.815354 -67.650204)
			(xy 18.795431 -67.598113) (xy 18.783305 -67.543676) (xy 18.779234 -67.488054) (xy 8.284829 -67.488054)
			(xy 8.312377 -67.51098) (xy 8.349594 -67.552517) (xy 8.380367 -67.59903) (xy 8.404039 -67.649527)
			(xy 8.420107 -67.702934) (xy 8.428227 -67.75811) (xy 8.428736 -67.785996) (xy 8.428227 -67.813882)
			(xy 8.420107 -67.869058) (xy 8.404039 -67.922465) (xy 8.380367 -67.972962) (xy 8.349594 -68.019475)
			(xy 8.312377 -68.061012) (xy 8.269509 -68.096687) (xy 8.221903 -68.125741) (xy 8.170574 -68.147553)
			(xy 8.116617 -68.161659) (xy 8.06118 -68.167759) (xy 8.005446 -68.165722) (xy 7.950603 -68.155592)
			(xy 7.897819 -68.137585) (xy 7.848219 -68.112084) (xy 7.802861 -68.079633) (xy 7.762712 -68.040924)
			(xy 7.728626 -67.996781) (xy 7.70133 -67.948146) (xy 7.681407 -67.896055) (xy 7.669281 -67.841618)
			(xy 7.66521 -67.785996) (xy 0.715772 -67.785996) (xy 0.715772 -68.353432) (xy 3.576826 -68.353432)
			(xy 3.580897 -68.29781) (xy 3.593023 -68.243373) (xy 3.612946 -68.191282) (xy 3.640242 -68.142647)
			(xy 3.674328 -68.098504) (xy 3.714477 -68.059795) (xy 3.759835 -68.027344) (xy 3.809435 -68.001843)
			(xy 3.862219 -67.983836) (xy 3.917062 -67.973706) (xy 3.972796 -67.971669) (xy 4.028233 -67.977769)
			(xy 4.08219 -67.991875) (xy 4.133519 -68.013687) (xy 4.181125 -68.042741) (xy 4.223993 -68.078416)
			(xy 4.26121 -68.119953) (xy 4.291983 -68.166466) (xy 4.315655 -68.216963) (xy 4.331723 -68.27037)
			(xy 4.339843 -68.325546) (xy 4.340352 -68.353432) (xy 4.339843 -68.381318) (xy 4.331723 -68.436494)
			(xy 4.315655 -68.489901) (xy 4.291983 -68.540398) (xy 4.261413 -68.586604) (xy 16.625316 -68.586604)
			(xy 16.625781 -68.559234) (xy 16.633598 -68.505054) (xy 16.649087 -68.452551) (xy 16.67193 -68.402804)
			(xy 16.701655 -68.356838) (xy 16.719296 -68.335906) (xy 16.71955 -68.335652) (xy 16.725127 -68.328559)
			(xy 16.731378 -68.311647) (xy 16.731742 -68.302632) (xy 16.731742 -68.235576) (xy 16.731409 -68.226556)
			(xy 16.725146 -68.209639) (xy 16.71955 -68.202556) (xy 16.719296 -68.202556) (xy 16.719296 -68.202302)
			(xy 16.701644 -68.181381) (xy 16.671934 -68.135405) (xy 16.649101 -68.085655) (xy 16.633613 -68.033152)
			(xy 16.625788 -67.978974) (xy 16.625316 -67.951604) (xy 16.625759 -67.92435) (xy 16.633516 -67.870397)
			(xy 16.648873 -67.818098) (xy 16.671517 -67.768516) (xy 16.700987 -67.722662) (xy 16.736682 -67.681468)
			(xy 16.777878 -67.645775) (xy 16.823733 -67.616307) (xy 16.873316 -67.593666) (xy 16.925617 -67.578312)
			(xy 16.97957 -67.570558) (xy 17.006824 -67.570096) (xy 17.033138 -67.570549) (xy 17.085268 -67.577787)
			(xy 17.13591 -67.592109) (xy 17.184109 -67.613244) (xy 17.228953 -67.640793) (xy 17.269592 -67.674233)
			(xy 17.287748 -67.693286) (xy 17.295252 -67.700709) (xy 17.314545 -67.709221) (xy 17.325086 -67.709796)
			(xy 17.399762 -67.709796) (xy 17.410311 -67.709261) (xy 17.429607 -67.70073) (xy 17.4371 -67.693286)
			(xy 17.45526 -67.674235) (xy 17.495889 -67.640778) (xy 17.540728 -67.613219) (xy 17.588928 -67.592079)
			(xy 17.639575 -67.577761) (xy 17.691708 -67.570535) (xy 17.718024 -67.570096) (xy 17.745395 -67.570549)
			(xy 17.799574 -67.57837) (xy 17.852078 -67.593862) (xy 17.901824 -67.616707) (xy 17.947791 -67.646434)
			(xy 17.968722 -67.664076) (xy 17.968976 -67.66433) (xy 17.976063 -67.669916) (xy 17.99298 -67.676162)
			(xy 18.001996 -67.676522) (xy 18.069052 -67.676522) (xy 18.078066 -67.676137) (xy 18.094983 -67.669908)
			(xy 18.102072 -67.66433) (xy 18.102072 -67.664076) (xy 18.102326 -67.664076) (xy 18.123272 -67.646454)
			(xy 18.169241 -67.616741) (xy 18.218985 -67.593902) (xy 18.271483 -67.578407) (xy 18.325656 -67.570573)
			(xy 18.353024 -67.570096) (xy 18.380276 -67.570555) (xy 18.434225 -67.578315) (xy 18.48652 -67.593674)
			(xy 18.536098 -67.616318) (xy 18.581948 -67.645787) (xy 18.623138 -67.681481) (xy 18.65883 -67.722674)
			(xy 18.688295 -67.768527) (xy 18.710936 -67.818106) (xy 18.726291 -67.870402) (xy 18.734047 -67.924352)
			(xy 18.734532 -67.951604) (xy 18.734085 -67.978975) (xy 18.726265 -68.033156) (xy 18.710772 -68.08566)
			(xy 18.687926 -68.135406) (xy 18.658196 -68.181372) (xy 18.640552 -68.202302) (xy 18.640298 -68.202556)
			(xy 18.634723 -68.209651) (xy 18.62847 -68.226561) (xy 18.628106 -68.235576) (xy 18.628106 -68.302632)
			(xy 18.628447 -68.311651) (xy 18.634705 -68.328567) (xy 18.640298 -68.335652) (xy 18.640552 -68.335652)
			(xy 18.640552 -68.335906) (xy 18.6582 -68.356831) (xy 18.687912 -68.402805) (xy 18.710747 -68.452554)
			(xy 18.726236 -68.505057) (xy 18.73406 -68.559234) (xy 18.734532 -68.586604) (xy 18.734026 -68.613854)
			(xy 18.72627 -68.6678) (xy 18.710915 -68.720093) (xy 18.694275 -68.75653) (xy 22.17039 -68.75653)
			(xy 22.170876 -68.729161) (xy 22.178689 -68.674982) (xy 22.194174 -68.62248) (xy 22.217011 -68.572732)
			(xy 22.246731 -68.526765) (xy 22.26437 -68.505832) (xy 22.264624 -68.505578) (xy 22.270229 -68.498504)
			(xy 22.276464 -68.481577) (xy 22.276816 -68.472558) (xy 22.276816 -68.405502) (xy 22.276454 -68.396486)
			(xy 22.27021 -68.379569) (xy 22.264624 -68.372482) (xy 22.26437 -68.372482) (xy 22.26437 -68.372228)
			(xy 22.246726 -68.3513) (xy 22.217016 -68.305326) (xy 22.194181 -68.255577) (xy 22.178691 -68.203076)
			(xy 22.170864 -68.148899) (xy 22.17039 -68.12153) (xy 22.170883 -68.094278) (xy 22.178636 -68.040328)
			(xy 22.193988 -67.988031) (xy 22.216627 -67.938451) (xy 22.246092 -67.892598) (xy 22.281782 -67.851405)
			(xy 22.322972 -67.815711) (xy 22.368823 -67.786242) (xy 22.418401 -67.763599) (xy 22.470697 -67.748243)
			(xy 22.524646 -67.740485) (xy 22.551898 -67.740022) (xy 22.579268 -67.740484) (xy 22.633448 -67.748302)
			(xy 22.685951 -67.763792) (xy 22.735698 -67.786634) (xy 22.781665 -67.81636) (xy 22.802596 -67.834002)
			(xy 22.80285 -67.834256) (xy 22.809942 -67.839834) (xy 22.826855 -67.846085) (xy 22.83587 -67.846448)
			(xy 22.902926 -67.846448) (xy 22.911946 -67.846115) (xy 22.928863 -67.839852) (xy 22.935946 -67.834256)
			(xy 22.935946 -67.834002) (xy 22.9362 -67.834002) (xy 22.957121 -67.81635) (xy 23.003097 -67.78664)
			(xy 23.052847 -67.763806) (xy 23.10535 -67.748318) (xy 23.159528 -67.740494) (xy 23.186898 -67.740022)
			(xy 23.213212 -67.740484) (xy 23.265341 -67.747719) (xy 23.315984 -67.762038) (xy 23.364184 -67.783172)
			(xy 23.409027 -67.810719) (xy 23.449666 -67.84416) (xy 23.467822 -67.863212) (xy 23.475332 -67.870627)
			(xy 23.494621 -67.879144) (xy 23.50516 -67.879722) (xy 23.579836 -67.879722) (xy 23.590382 -67.879165)
			(xy 23.609678 -67.870649) (xy 23.617174 -67.863212) (xy 23.635352 -67.844178) (xy 23.675976 -67.810719)
			(xy 23.720812 -67.783157) (xy 23.769008 -67.762014) (xy 23.819652 -67.747693) (xy 23.871783 -67.740463)
			(xy 23.898098 -67.740022) (xy 23.925352 -67.740457) (xy 23.979306 -67.748215) (xy 24.031606 -67.763572)
			(xy 24.081188 -67.786217) (xy 24.127043 -67.815687) (xy 24.168236 -67.851384) (xy 24.20393 -67.89258)
			(xy 24.233397 -67.938437) (xy 24.256038 -67.98802) (xy 24.271391 -68.040322) (xy 24.279145 -68.094276)
			(xy 24.279606 -68.12153) (xy 24.279156 -68.148901) (xy 24.271334 -68.203081) (xy 24.255841 -68.255584)
			(xy 24.232996 -68.30533) (xy 24.203268 -68.351297) (xy 24.185626 -68.372228) (xy 24.185372 -68.372482)
			(xy 24.179784 -68.379567) (xy 24.173539 -68.396485) (xy 24.17318 -68.405502) (xy 24.17318 -68.472558)
			(xy 24.173561 -68.481572) (xy 24.179792 -68.498489) (xy 24.185372 -68.505578) (xy 24.185626 -68.505578)
			(xy 24.185626 -68.505832) (xy 24.203251 -68.526776) (xy 24.232964 -68.572746) (xy 24.255802 -68.62249)
			(xy 24.271297 -68.674988) (xy 24.279129 -68.729162) (xy 24.279606 -68.75653) (xy 24.27915 -68.783782)
			(xy 24.271389 -68.837731) (xy 24.25603 -68.890026) (xy 24.233386 -68.939604) (xy 24.203916 -68.985454)
			(xy 24.168221 -69.026644) (xy 24.127029 -69.062335) (xy 24.081176 -69.091801) (xy 24.031596 -69.114442)
			(xy 23.9793 -69.129796) (xy 23.92535 -69.137552) (xy 23.898098 -69.138038) (xy 23.871783 -69.137592)
			(xy 23.819653 -69.130355) (xy 23.769009 -69.116033) (xy 23.72081 -69.094897) (xy 23.675967 -69.067346)
			(xy 23.635329 -69.033902) (xy 23.617174 -69.014848) (xy 23.609657 -69.00744) (xy 23.590374 -68.998918)
			(xy 23.579836 -68.998338) (xy 23.50516 -68.998338) (xy 23.494611 -68.998875) (xy 23.475315 -69.007403)
			(xy 23.467822 -69.014848) (xy 23.449658 -69.033895) (xy 23.409029 -69.067351) (xy 23.36419 -69.09491)
			(xy 23.315991 -69.11605) (xy 23.265346 -69.130369) (xy 23.213213 -69.137597) (xy 23.186898 -69.138038)
			(xy 23.159527 -69.137588) (xy 23.105347 -69.129769) (xy 23.052843 -69.114277) (xy 23.003096 -69.091431)
			(xy 22.957131 -69.061702) (xy 22.9362 -69.044058) (xy 22.935946 -69.043804) (xy 22.92885 -69.038231)
			(xy 22.911941 -69.031976) (xy 22.902926 -69.031612) (xy 22.83587 -69.031612) (xy 22.826851 -69.031952)
			(xy 22.809934 -69.038211) (xy 22.80285 -69.043804) (xy 22.80285 -69.044058) (xy 22.802596 -69.044058)
			(xy 22.781671 -69.061706) (xy 22.735697 -69.091418) (xy 22.685948 -69.114253) (xy 22.633445 -69.129742)
			(xy 22.579268 -69.137566) (xy 22.551898 -69.138038) (xy 22.524648 -69.137524) (xy 22.470703 -69.129768)
			(xy 22.418411 -69.114414) (xy 22.368835 -69.091775) (xy 22.322986 -69.062311) (xy 22.281797 -69.026623)
			(xy 22.246105 -68.985436) (xy 22.216638 -68.939589) (xy 22.193995 -68.890016) (xy 22.178638 -68.837724)
			(xy 22.170878 -68.78378) (xy 22.17039 -68.75653) (xy 18.694275 -68.75653) (xy 18.688275 -68.769669)
			(xy 18.658811 -68.815518) (xy 18.623122 -68.856707) (xy 18.581934 -68.892399) (xy 18.536086 -68.921866)
			(xy 18.486512 -68.944508) (xy 18.43422 -68.959865) (xy 18.380274 -68.967625) (xy 18.353024 -68.968112)
			(xy 18.325654 -68.967629) (xy 18.271476 -68.959815) (xy 18.218973 -68.944329) (xy 18.169226 -68.921492)
			(xy 18.123258 -68.891771) (xy 18.102326 -68.874132) (xy 18.102072 -68.873878) (xy 18.094971 -68.868313)
			(xy 18.078065 -68.862054) (xy 18.069052 -68.861686) (xy 18.001996 -68.861686) (xy 17.992979 -68.862044)
			(xy 17.976063 -68.868291) (xy 17.968976 -68.873878) (xy 17.968976 -68.874132) (xy 17.968722 -68.874132)
			(xy 17.947797 -68.891779) (xy 17.901821 -68.921489) (xy 17.852072 -68.944323) (xy 17.79957 -68.959812)
			(xy 17.745394 -68.967639) (xy 17.718024 -68.968112) (xy 17.691711 -68.967625) (xy 17.639583 -68.960393)
			(xy 17.588941 -68.946078) (xy 17.540742 -68.924949) (xy 17.495898 -68.897407) (xy 17.455257 -68.863972)
			(xy 17.4371 -68.844922) (xy 17.429577 -68.837522) (xy 17.410298 -68.828996) (xy 17.399762 -68.828412)
			(xy 17.325086 -68.828412) (xy 17.314533 -68.828916) (xy 17.295238 -68.837468) (xy 17.287748 -68.844922)
			(xy 17.269615 -68.864) (xy 17.22898 -68.897454) (xy 17.184135 -68.92501) (xy 17.13593 -68.946144)
			(xy 17.085278 -68.960457) (xy 17.033141 -68.967676) (xy 17.006824 -68.968112) (xy 16.979572 -68.967622)
			(xy 16.925622 -68.959869) (xy 16.873325 -68.944516) (xy 16.823745 -68.921877) (xy 16.777892 -68.892411)
			(xy 16.736699 -68.85672) (xy 16.701005 -68.81553) (xy 16.671537 -68.769679) (xy 16.648894 -68.720101)
			(xy 16.633537 -68.667805) (xy 16.62578 -68.613856) (xy 16.625316 -68.586604) (xy 4.261413 -68.586604)
			(xy 4.26121 -68.586911) (xy 4.223993 -68.628448) (xy 4.181125 -68.664123) (xy 4.133519 -68.693177)
			(xy 4.08219 -68.714989) (xy 4.028233 -68.729095) (xy 3.972796 -68.735195) (xy 3.917062 -68.733158)
			(xy 3.862219 -68.723028) (xy 3.809435 -68.705021) (xy 3.759835 -68.67952) (xy 3.714477 -68.647069)
			(xy 3.674328 -68.60836) (xy 3.640242 -68.564217) (xy 3.612946 -68.515582) (xy 3.593023 -68.463491)
			(xy 3.580897 -68.409054) (xy 3.576826 -68.353432) (xy 0.715772 -68.353432) (xy 0.715772 -69.182234)
			(xy 1.405126 -69.182234) (xy 1.409197 -69.126612) (xy 1.421323 -69.072175) (xy 1.441246 -69.020084)
			(xy 1.468542 -68.971449) (xy 1.502628 -68.927306) (xy 1.542777 -68.888597) (xy 1.588135 -68.856146)
			(xy 1.637735 -68.830645) (xy 1.690519 -68.812638) (xy 1.745362 -68.802508) (xy 1.801096 -68.800471)
			(xy 1.856533 -68.806571) (xy 1.91049 -68.820677) (xy 1.961819 -68.842489) (xy 2.009425 -68.871543)
			(xy 2.052293 -68.907218) (xy 2.08951 -68.948755) (xy 2.120283 -68.995268) (xy 2.143955 -69.045765)
			(xy 2.160023 -69.099172) (xy 2.168143 -69.154348) (xy 2.168652 -69.182234) (xy 2.168143 -69.21012)
			(xy 2.160023 -69.265296) (xy 2.143955 -69.318703) (xy 2.120283 -69.3692) (xy 2.08951 -69.415713)
			(xy 2.052293 -69.45725) (xy 2.009425 -69.492925) (xy 1.961819 -69.521979) (xy 1.91049 -69.543791)
			(xy 1.856533 -69.557897) (xy 1.801096 -69.563997) (xy 1.745362 -69.56196) (xy 1.690519 -69.55183)
			(xy 1.637735 -69.533823) (xy 1.588135 -69.508322) (xy 1.542777 -69.475871) (xy 1.502628 -69.437162)
			(xy 1.468542 -69.393019) (xy 1.441246 -69.344384) (xy 1.421323 -69.292293) (xy 1.409197 -69.237856)
			(xy 1.405126 -69.182234) (xy 0.715772 -69.182234) (xy 0.715772 -70.204076) (xy 6.107428 -70.204076)
			(xy 6.111499 -70.148454) (xy 6.123625 -70.094017) (xy 6.143548 -70.041926) (xy 6.170844 -69.993291)
			(xy 6.20493 -69.949148) (xy 6.245079 -69.910439) (xy 6.290437 -69.877988) (xy 6.340037 -69.852487)
			(xy 6.392821 -69.83448) (xy 6.447664 -69.82435) (xy 6.503398 -69.822313) (xy 6.558835 -69.828413)
			(xy 6.612792 -69.842519) (xy 6.664121 -69.864331) (xy 6.711727 -69.893385) (xy 6.754595 -69.92906)
			(xy 6.791812 -69.970597) (xy 6.822585 -70.01711) (xy 6.846257 -70.067607) (xy 6.862325 -70.121014)
			(xy 6.870445 -70.17619) (xy 6.870954 -70.204076) (xy 6.870445 -70.231962) (xy 6.862325 -70.287138)
			(xy 6.846257 -70.340545) (xy 6.822585 -70.391042) (xy 6.791812 -70.437555) (xy 6.754595 -70.479092)
			(xy 6.711727 -70.514767) (xy 6.664121 -70.543821) (xy 6.612792 -70.565633) (xy 6.558835 -70.579739)
			(xy 6.503398 -70.585839) (xy 6.447664 -70.583802) (xy 6.392821 -70.573672) (xy 6.340037 -70.555665)
			(xy 6.290437 -70.530164) (xy 6.245079 -70.497713) (xy 6.20493 -70.459004) (xy 6.170844 -70.414861)
			(xy 6.143548 -70.366226) (xy 6.123625 -70.314135) (xy 6.111499 -70.259698) (xy 6.107428 -70.204076)
			(xy 0.715772 -70.204076) (xy 0.715772 -71.288402) (xy 1.735072 -71.288402) (xy 1.739143 -71.23278)
			(xy 1.751269 -71.178343) (xy 1.771192 -71.126252) (xy 1.798488 -71.077617) (xy 1.832574 -71.033474)
			(xy 1.872723 -70.994765) (xy 1.918081 -70.962314) (xy 1.967681 -70.936813) (xy 2.020465 -70.918806)
			(xy 2.075308 -70.908676) (xy 2.131042 -70.906639) (xy 2.186479 -70.912739) (xy 2.240436 -70.926845)
			(xy 2.291765 -70.948657) (xy 2.339371 -70.977711) (xy 2.382239 -71.013386) (xy 2.419456 -71.054923)
			(xy 2.450229 -71.101436) (xy 2.473901 -71.151933) (xy 2.489969 -71.20534) (xy 2.498089 -71.260516)
			(xy 2.498598 -71.288402) (xy 2.498089 -71.316288) (xy 2.489969 -71.371464) (xy 2.473901 -71.424871)
			(xy 2.450229 -71.475368) (xy 2.419456 -71.521881) (xy 2.382239 -71.563418) (xy 2.339371 -71.599093)
			(xy 2.291765 -71.628147) (xy 2.240436 -71.649959) (xy 2.186479 -71.664065) (xy 2.131042 -71.670165)
			(xy 2.075308 -71.668128) (xy 2.020465 -71.657998) (xy 1.967681 -71.639991) (xy 1.918081 -71.61449)
			(xy 1.872723 -71.582039) (xy 1.832574 -71.54333) (xy 1.798488 -71.499187) (xy 1.771192 -71.450552)
			(xy 1.751269 -71.398461) (xy 1.739143 -71.344024) (xy 1.735072 -71.288402) (xy 0.715772 -71.288402)
			(xy 0.715772 -71.673974) (xy 3.37896 -71.673974) (xy 3.383031 -71.618352) (xy 3.395157 -71.563915)
			(xy 3.41508 -71.511824) (xy 3.442376 -71.463189) (xy 3.476462 -71.419046) (xy 3.516611 -71.380337)
			(xy 3.561969 -71.347886) (xy 3.611569 -71.322385) (xy 3.664353 -71.304378) (xy 3.719196 -71.294248)
			(xy 3.77493 -71.292211) (xy 3.830367 -71.298311) (xy 3.884324 -71.312417) (xy 3.935653 -71.334229)
			(xy 3.983259 -71.363283) (xy 4.026127 -71.398958) (xy 4.033123 -71.406766) (xy 7.013446 -71.406766)
			(xy 7.017517 -71.351144) (xy 7.029643 -71.296707) (xy 7.049566 -71.244616) (xy 7.076862 -71.195981)
			(xy 7.110948 -71.151838) (xy 7.151097 -71.113129) (xy 7.196455 -71.080678) (xy 7.246055 -71.055177)
			(xy 7.298839 -71.03717) (xy 7.353682 -71.02704) (xy 7.409416 -71.025003) (xy 7.464853 -71.031103)
			(xy 7.51881 -71.045209) (xy 7.570139 -71.067021) (xy 7.617745 -71.096075) (xy 7.643747 -71.117714)
			(xy 9.0457 -71.117714) (xy 9.049771 -71.062092) (xy 9.061897 -71.007655) (xy 9.08182 -70.955564)
			(xy 9.109116 -70.906929) (xy 9.143202 -70.862786) (xy 9.183351 -70.824077) (xy 9.228709 -70.791626)
			(xy 9.278309 -70.766125) (xy 9.331093 -70.748118) (xy 9.385936 -70.737988) (xy 9.44167 -70.735951)
			(xy 9.497107 -70.742051) (xy 9.551064 -70.756157) (xy 9.602393 -70.777969) (xy 9.649999 -70.807023)
			(xy 9.692867 -70.842698) (xy 9.730084 -70.884235) (xy 9.760857 -70.930748) (xy 9.784529 -70.981245)
			(xy 9.800597 -71.034652) (xy 9.808717 -71.089828) (xy 9.809226 -71.117714) (xy 9.808717 -71.1456)
			(xy 9.800597 -71.200776) (xy 9.784529 -71.254183) (xy 9.760857 -71.30468) (xy 9.730084 -71.351193)
			(xy 9.692867 -71.39273) (xy 9.649999 -71.428405) (xy 9.602393 -71.457459) (xy 9.551064 -71.479271)
			(xy 9.497107 -71.493377) (xy 9.44167 -71.499477) (xy 9.385936 -71.49744) (xy 9.331093 -71.48731)
			(xy 9.278309 -71.469303) (xy 9.228709 -71.443802) (xy 9.183351 -71.411351) (xy 9.143202 -71.372642)
			(xy 9.109116 -71.328499) (xy 9.08182 -71.279864) (xy 9.061897 -71.227773) (xy 9.049771 -71.173336)
			(xy 9.0457 -71.117714) (xy 7.643747 -71.117714) (xy 7.660613 -71.13175) (xy 7.69783 -71.173287) (xy 7.728603 -71.2198)
			(xy 7.752275 -71.270297) (xy 7.768343 -71.323704) (xy 7.776463 -71.37888) (xy 7.776972 -71.406766)
			(xy 7.776463 -71.434652) (xy 7.768343 -71.489828) (xy 7.752275 -71.543235) (xy 7.746355 -71.555864)
			(xy 19.194524 -71.555864) (xy 19.198595 -71.500242) (xy 19.210721 -71.445805) (xy 19.230644 -71.393714)
			(xy 19.25794 -71.345079) (xy 19.292026 -71.300936) (xy 19.332175 -71.262227) (xy 19.377533 -71.229776)
			(xy 19.427133 -71.204275) (xy 19.479917 -71.186268) (xy 19.53476 -71.176138) (xy 19.590494 -71.174101)
			(xy 19.645931 -71.180201) (xy 19.699888 -71.194307) (xy 19.751217 -71.216119) (xy 19.798823 -71.245173)
			(xy 19.841691 -71.280848) (xy 19.878908 -71.322385) (xy 19.909681 -71.368898) (xy 19.933353 -71.419395)
			(xy 19.949421 -71.472802) (xy 19.957541 -71.527978) (xy 19.95805 -71.555864) (xy 19.957541 -71.58375)
			(xy 19.951702 -71.623428) (xy 20.703538 -71.623428) (xy 20.707609 -71.567806) (xy 20.719735 -71.513369)
			(xy 20.739658 -71.461278) (xy 20.766954 -71.412643) (xy 20.80104 -71.3685) (xy 20.841189 -71.329791)
			(xy 20.886547 -71.29734) (xy 20.936147 -71.271839) (xy 20.988931 -71.253832) (xy 21.043774 -71.243702)
			(xy 21.099508 -71.241665) (xy 21.154945 -71.247765) (xy 21.208902 -71.261871) (xy 21.260231 -71.283683)
			(xy 21.307837 -71.312737) (xy 21.350705 -71.348412) (xy 21.387922 -71.389949) (xy 21.418695 -71.436462)
			(xy 21.442367 -71.486959) (xy 21.458435 -71.540366) (xy 21.466555 -71.595542) (xy 21.467064 -71.623428)
			(xy 21.466555 -71.651314) (xy 21.458435 -71.70649) (xy 21.442367 -71.759897) (xy 21.418695 -71.810394)
			(xy 21.387922 -71.856907) (xy 21.350705 -71.898444) (xy 21.307837 -71.934119) (xy 21.260231 -71.963173)
			(xy 21.208902 -71.984985) (xy 21.154945 -71.999091) (xy 21.099508 -72.005191) (xy 21.043774 -72.003154)
			(xy 20.988931 -71.993024) (xy 20.936147 -71.975017) (xy 20.886547 -71.949516) (xy 20.841189 -71.917065)
			(xy 20.80104 -71.878356) (xy 20.766954 -71.834213) (xy 20.739658 -71.785578) (xy 20.719735 -71.733487)
			(xy 20.707609 -71.67905) (xy 20.703538 -71.623428) (xy 19.951702 -71.623428) (xy 19.949421 -71.638926)
			(xy 19.933353 -71.692333) (xy 19.909681 -71.74283) (xy 19.878908 -71.789343) (xy 19.841691 -71.83088)
			(xy 19.798823 -71.866555) (xy 19.751217 -71.895609) (xy 19.699888 -71.917421) (xy 19.645931 -71.931527)
			(xy 19.590494 -71.937627) (xy 19.53476 -71.93559) (xy 19.479917 -71.92546) (xy 19.427133 -71.907453)
			(xy 19.377533 -71.881952) (xy 19.332175 -71.849501) (xy 19.292026 -71.810792) (xy 19.25794 -71.766649)
			(xy 19.230644 -71.718014) (xy 19.210721 -71.665923) (xy 19.198595 -71.611486) (xy 19.194524 -71.555864)
			(xy 7.746355 -71.555864) (xy 7.728603 -71.593732) (xy 7.69783 -71.640245) (xy 7.660613 -71.681782)
			(xy 7.617745 -71.717457) (xy 7.570139 -71.746511) (xy 7.51881 -71.768323) (xy 7.464853 -71.782429)
			(xy 7.409416 -71.788529) (xy 7.353682 -71.786492) (xy 7.298839 -71.776362) (xy 7.246055 -71.758355)
			(xy 7.196455 -71.732854) (xy 7.151097 -71.700403) (xy 7.110948 -71.661694) (xy 7.076862 -71.617551)
			(xy 7.049566 -71.568916) (xy 7.029643 -71.516825) (xy 7.017517 -71.462388) (xy 7.013446 -71.406766)
			(xy 4.033123 -71.406766) (xy 4.063344 -71.440495) (xy 4.094117 -71.487008) (xy 4.117789 -71.537505)
			(xy 4.133857 -71.590912) (xy 4.141977 -71.646088) (xy 4.142486 -71.673974) (xy 4.141977 -71.70186)
			(xy 4.133857 -71.757036) (xy 4.117789 -71.810443) (xy 4.094117 -71.86094) (xy 4.063344 -71.907453)
			(xy 4.026127 -71.94899) (xy 3.983259 -71.984665) (xy 3.935653 -72.013719) (xy 3.884324 -72.035531)
			(xy 3.830367 -72.049637) (xy 3.77493 -72.055737) (xy 3.719196 -72.0537) (xy 3.664353 -72.04357) (xy 3.611569 -72.025563)
			(xy 3.561969 -72.000062) (xy 3.516611 -71.967611) (xy 3.476462 -71.928902) (xy 3.442376 -71.884759)
			(xy 3.41508 -71.836124) (xy 3.395157 -71.784033) (xy 3.383031 -71.729596) (xy 3.37896 -71.673974)
			(xy 0.715772 -71.673974) (xy 0.715772 -73.289668) (xy 3.554728 -73.289668) (xy 3.558799 -73.234046)
			(xy 3.570925 -73.179609) (xy 3.590848 -73.127518) (xy 3.618144 -73.078883) (xy 3.65223 -73.03474)
			(xy 3.692379 -72.996031) (xy 3.737737 -72.96358) (xy 3.787337 -72.938079) (xy 3.840121 -72.920072)
			(xy 3.894964 -72.909942) (xy 3.950698 -72.907905) (xy 4.006135 -72.914005) (xy 4.060092 -72.928111)
			(xy 4.111421 -72.949923) (xy 4.159027 -72.978977) (xy 4.201895 -73.014652) (xy 4.239112 -73.056189)
			(xy 4.269885 -73.102702) (xy 4.293557 -73.153199) (xy 4.309625 -73.206606) (xy 4.317745 -73.261782)
			(xy 4.318254 -73.289668) (xy 4.317745 -73.317554) (xy 4.309625 -73.37273) (xy 4.293557 -73.426137)
			(xy 4.269885 -73.476634) (xy 4.239112 -73.523147) (xy 4.201895 -73.564684) (xy 4.159027 -73.600359)
			(xy 4.111421 -73.629413) (xy 4.060092 -73.651225) (xy 4.006135 -73.665331) (xy 3.950698 -73.671431)
			(xy 3.894964 -73.669394) (xy 3.840121 -73.659264) (xy 3.787337 -73.641257) (xy 3.737737 -73.615756)
			(xy 3.692379 -73.583305) (xy 3.65223 -73.544596) (xy 3.618144 -73.500453) (xy 3.590848 -73.451818)
			(xy 3.570925 -73.399727) (xy 3.558799 -73.34529) (xy 3.554728 -73.289668) (xy 0.715772 -73.289668)
			(xy 0.715772 -74.106024) (xy 8.468612 -74.106024) (xy 8.472683 -74.050402) (xy 8.484809 -73.995965)
			(xy 8.504732 -73.943874) (xy 8.532028 -73.895239) (xy 8.566114 -73.851096) (xy 8.606263 -73.812387)
			(xy 8.651621 -73.779936) (xy 8.701221 -73.754435) (xy 8.754005 -73.736428) (xy 8.808848 -73.726298)
			(xy 8.864582 -73.724261) (xy 8.920019 -73.730361) (xy 8.973976 -73.744467) (xy 9.025305 -73.766279)
			(xy 9.072911 -73.795333) (xy 9.115779 -73.831008) (xy 9.152996 -73.872545) (xy 9.183769 -73.919058)
			(xy 9.207441 -73.969555) (xy 9.223509 -74.022962) (xy 9.231629 -74.078138) (xy 9.232138 -74.106024)
			(xy 9.231629 -74.13391) (xy 9.223509 -74.189086) (xy 9.207441 -74.242493) (xy 9.183769 -74.29299)
			(xy 9.152996 -74.339503) (xy 9.115779 -74.38104) (xy 9.072911 -74.416715) (xy 9.025305 -74.445769)
			(xy 8.973976 -74.467581) (xy 8.920019 -74.481687) (xy 8.864582 -74.487787) (xy 8.808848 -74.48575)
			(xy 8.754005 -74.47562) (xy 8.701221 -74.457613) (xy 8.651621 -74.432112) (xy 8.606263 -74.399661)
			(xy 8.566114 -74.360952) (xy 8.532028 -74.316809) (xy 8.504732 -74.268174) (xy 8.484809 -74.216083)
			(xy 8.472683 -74.161646) (xy 8.468612 -74.106024) (xy 0.715772 -74.106024) (xy 0.715772 -75.087226)
			(xy 6.381748 -75.087226) (xy 6.385819 -75.031604) (xy 6.397945 -74.977167) (xy 6.417868 -74.925076)
			(xy 6.445164 -74.876441) (xy 6.47925 -74.832298) (xy 6.519399 -74.793589) (xy 6.564757 -74.761138)
			(xy 6.614357 -74.735637) (xy 6.667141 -74.71763) (xy 6.721984 -74.7075) (xy 6.777718 -74.705463)
			(xy 6.833155 -74.711563) (xy 6.887112 -74.725669) (xy 6.938441 -74.747481) (xy 6.986047 -74.776535)
			(xy 7.028915 -74.81221) (xy 7.066132 -74.853747) (xy 7.096905 -74.90026) (xy 7.120577 -74.950757)
			(xy 7.136645 -75.004164) (xy 7.144765 -75.05934) (xy 7.145274 -75.087226) (xy 7.144765 -75.115112)
			(xy 7.136645 -75.170288) (xy 7.120577 -75.223695) (xy 7.096905 -75.274192) (xy 7.066132 -75.320705)
			(xy 7.028915 -75.362242) (xy 6.986047 -75.397917) (xy 6.938441 -75.426971) (xy 6.887112 -75.448783)
			(xy 6.833155 -75.462889) (xy 6.777718 -75.468989) (xy 6.721984 -75.466952) (xy 6.667141 -75.456822)
			(xy 6.614357 -75.438815) (xy 6.564757 -75.413314) (xy 6.519399 -75.380863) (xy 6.47925 -75.342154)
			(xy 6.445164 -75.298011) (xy 6.417868 -75.249376) (xy 6.397945 -75.197285) (xy 6.385819 -75.142848)
			(xy 6.381748 -75.087226) (xy 0.715772 -75.087226) (xy 0.715772 -78.58887) (xy 41.399966 -78.58887)
			(xy 41.404037 -78.533248) (xy 41.416163 -78.478811) (xy 41.436086 -78.42672) (xy 41.463382 -78.378085)
			(xy 41.497468 -78.333942) (xy 41.537617 -78.295233) (xy 41.582975 -78.262782) (xy 41.632575 -78.237281)
			(xy 41.685359 -78.219274) (xy 41.740202 -78.209144) (xy 41.795936 -78.207107) (xy 41.851373 -78.213207)
			(xy 41.90533 -78.227313) (xy 41.912773 -78.230476) (xy 65.148204 -78.230476) (xy 65.152275 -78.174854)
			(xy 65.164401 -78.120417) (xy 65.184324 -78.068326) (xy 65.21162 -78.019691) (xy 65.245706 -77.975548)
			(xy 65.285855 -77.936839) (xy 65.331213 -77.904388) (xy 65.380813 -77.878887) (xy 65.433597 -77.86088)
			(xy 65.48844 -77.85075) (xy 65.544174 -77.848713) (xy 65.599611 -77.854813) (xy 65.653568 -77.868919)
			(xy 65.704897 -77.890731) (xy 65.752503 -77.919785) (xy 65.795371 -77.95546) (xy 65.832588 -77.996997)
			(xy 65.863361 -78.04351) (xy 65.887033 -78.094007) (xy 65.903101 -78.147414) (xy 65.911221 -78.20259)
			(xy 65.91173 -78.230476) (xy 65.911221 -78.258362) (xy 65.903101 -78.313538) (xy 65.887033 -78.366945)
			(xy 65.863361 -78.417442) (xy 65.832588 -78.463955) (xy 65.795371 -78.505492) (xy 65.752503 -78.541167)
			(xy 65.704897 -78.570221) (xy 65.653568 -78.592033) (xy 65.599611 -78.606139) (xy 65.544174 -78.612239)
			(xy 65.48844 -78.610202) (xy 65.433597 -78.600072) (xy 65.380813 -78.582065) (xy 65.331213 -78.556564)
			(xy 65.285855 -78.524113) (xy 65.245706 -78.485404) (xy 65.21162 -78.441261) (xy 65.184324 -78.392626)
			(xy 65.164401 -78.340535) (xy 65.152275 -78.286098) (xy 65.148204 -78.230476) (xy 41.912773 -78.230476)
			(xy 41.956659 -78.249125) (xy 42.004265 -78.278179) (xy 42.047133 -78.313854) (xy 42.08435 -78.355391)
			(xy 42.115123 -78.401904) (xy 42.138795 -78.452401) (xy 42.154863 -78.505808) (xy 42.162983 -78.560984)
			(xy 42.163492 -78.58887) (xy 42.162983 -78.616756) (xy 42.154863 -78.671932) (xy 42.138795 -78.725339)
			(xy 42.115123 -78.775836) (xy 42.08435 -78.822349) (xy 42.047133 -78.863886) (xy 42.004265 -78.899561)
			(xy 41.956659 -78.928615) (xy 41.90533 -78.950427) (xy 41.851373 -78.964533) (xy 41.795936 -78.970633)
			(xy 41.740202 -78.968596) (xy 41.685359 -78.958466) (xy 41.632575 -78.940459) (xy 41.582975 -78.914958)
			(xy 41.537617 -78.882507) (xy 41.497468 -78.843798) (xy 41.463382 -78.799655) (xy 41.436086 -78.75102)
			(xy 41.416163 -78.698929) (xy 41.404037 -78.644492) (xy 41.399966 -78.58887) (xy 0.715772 -78.58887)
			(xy 0.715772 -79.164434) (xy 42.852592 -79.164434) (xy 42.856663 -79.108812) (xy 42.868789 -79.054375)
			(xy 42.888712 -79.002284) (xy 42.916008 -78.953649) (xy 42.950094 -78.909506) (xy 42.990243 -78.870797)
			(xy 43.035601 -78.838346) (xy 43.085201 -78.812845) (xy 43.137985 -78.794838) (xy 43.192828 -78.784708)
			(xy 43.248562 -78.782671) (xy 43.303999 -78.788771) (xy 43.357956 -78.802877) (xy 43.409285 -78.824689)
			(xy 43.456891 -78.853743) (xy 43.499759 -78.889418) (xy 43.536976 -78.930955) (xy 43.567749 -78.977468)
			(xy 43.591421 -79.027965) (xy 43.607489 -79.081372) (xy 43.615609 -79.136548) (xy 43.616118 -79.164434)
			(xy 43.615798 -79.18196) (xy 79.591662 -79.18196) (xy 79.592148 -79.154709) (xy 79.599904 -79.100761)
			(xy 79.615259 -79.048466) (xy 79.637901 -78.998889) (xy 79.667367 -78.953039) (xy 79.703058 -78.911848)
			(xy 79.744249 -78.876157) (xy 79.790099 -78.846691) (xy 79.839676 -78.824049) (xy 79.891971 -78.808694)
			(xy 79.945919 -78.800938) (xy 80.000421 -78.800938) (xy 80.054369 -78.808694) (xy 80.106664 -78.824049)
			(xy 80.156241 -78.846691) (xy 80.202091 -78.876157) (xy 80.243282 -78.911848) (xy 80.278973 -78.953039)
			(xy 80.308439 -78.998889) (xy 80.331081 -79.048466) (xy 80.346436 -79.100761) (xy 80.354192 -79.154709)
			(xy 80.354678 -79.18196) (xy 80.354093 -79.210842) (xy 80.345378 -79.267945) (xy 80.328157 -79.323083)
			(xy 80.302823 -79.374995) (xy 80.269955 -79.422497) (xy 80.230304 -79.464502) (xy 80.207866 -79.482696)
			(xy 80.19695 -79.491864) (xy 80.180205 -79.514917) (xy 80.17047 -79.541695) (xy 80.168502 -79.570119)
			(xy 80.174454 -79.597983) (xy 80.187863 -79.623123) (xy 80.207689 -79.643587) (xy 80.219804 -79.651098)
			(xy 80.244418 -79.665742) (xy 80.289288 -79.701335) (xy 80.328334 -79.743237) (xy 80.360676 -79.790504)
			(xy 80.385589 -79.842076) (xy 80.402512 -79.896792) (xy 80.411065 -79.953423) (xy 80.411574 -79.98206)
			(xy 80.411088 -80.009311) (xy 80.403332 -80.063259) (xy 80.387977 -80.115554) (xy 80.386651 -80.118458)
			(xy 88.214706 -80.118458) (xy 88.218777 -80.062836) (xy 88.230903 -80.008399) (xy 88.250826 -79.956308)
			(xy 88.278122 -79.907673) (xy 88.312208 -79.86353) (xy 88.352357 -79.824821) (xy 88.397715 -79.79237)
			(xy 88.447315 -79.766869) (xy 88.500099 -79.748862) (xy 88.554942 -79.738732) (xy 88.610676 -79.736695)
			(xy 88.666113 -79.742795) (xy 88.72007 -79.756901) (xy 88.771399 -79.778713) (xy 88.819005 -79.807767)
			(xy 88.861873 -79.843442) (xy 88.89909 -79.884979) (xy 88.929863 -79.931492) (xy 88.953535 -79.981989)
			(xy 88.969603 -80.035396) (xy 88.977723 -80.090572) (xy 88.978232 -80.118458) (xy 88.977723 -80.146344)
			(xy 88.969603 -80.20152) (xy 88.953535 -80.254927) (xy 88.929863 -80.305424) (xy 88.89909 -80.351937)
			(xy 88.861873 -80.393474) (xy 88.819005 -80.429149) (xy 88.771399 -80.458203) (xy 88.72007 -80.480015)
			(xy 88.666113 -80.494121) (xy 88.610676 -80.500221) (xy 88.554942 -80.498184) (xy 88.500099 -80.488054)
			(xy 88.447315 -80.470047) (xy 88.397715 -80.444546) (xy 88.352357 -80.412095) (xy 88.312208 -80.373386)
			(xy 88.278122 -80.329243) (xy 88.250826 -80.280608) (xy 88.230903 -80.228517) (xy 88.218777 -80.17408)
			(xy 88.214706 -80.118458) (xy 80.386651 -80.118458) (xy 80.365335 -80.165131) (xy 80.335869 -80.210981)
			(xy 80.300178 -80.252172) (xy 80.258987 -80.287863) (xy 80.213137 -80.317329) (xy 80.16356 -80.339971)
			(xy 80.111265 -80.355326) (xy 80.057317 -80.363082) (xy 80.002815 -80.363082) (xy 79.948867 -80.355326)
			(xy 79.896572 -80.339971) (xy 79.846995 -80.317329) (xy 79.801145 -80.287863) (xy 79.759954 -80.252172)
			(xy 79.724263 -80.210981) (xy 79.694797 -80.165131) (xy 79.672155 -80.115554) (xy 79.6568 -80.063259)
			(xy 79.649044 -80.009311) (xy 79.648558 -79.98206) (xy 79.649073 -79.953175) (xy 79.6578 -79.896068)
			(xy 79.675034 -79.840929) (xy 79.700381 -79.789016) (xy 79.733262 -79.741517) (xy 79.772926 -79.699515)
			(xy 79.79537 -79.681324) (xy 79.806276 -79.672141) (xy 79.823033 -79.649095) (xy 79.832777 -79.622319)
			(xy 79.834749 -79.593893) (xy 79.828797 -79.566027) (xy 79.815384 -79.540887) (xy 79.795551 -79.520428)
			(xy 79.783432 -79.512922) (xy 79.758835 -79.49825) (xy 79.713963 -79.462663) (xy 79.674916 -79.420767)
			(xy 79.64257 -79.373504) (xy 79.617655 -79.321937) (xy 79.600729 -79.267224) (xy 79.592172 -79.210596)
			(xy 79.591662 -79.18196) (xy 43.615798 -79.18196) (xy 43.615609 -79.19232) (xy 43.607489 -79.247496)
			(xy 43.591421 -79.300903) (xy 43.567749 -79.3514) (xy 43.536976 -79.397913) (xy 43.499759 -79.43945)
			(xy 43.456891 -79.475125) (xy 43.409285 -79.504179) (xy 43.357956 -79.525991) (xy 43.303999 -79.540097)
			(xy 43.248562 -79.546197) (xy 43.192828 -79.54416) (xy 43.137985 -79.53403) (xy 43.085201 -79.516023)
			(xy 43.035601 -79.490522) (xy 42.990243 -79.458071) (xy 42.950094 -79.419362) (xy 42.916008 -79.375219)
			(xy 42.888712 -79.326584) (xy 42.868789 -79.274493) (xy 42.856663 -79.220056) (xy 42.852592 -79.164434)
			(xy 0.715772 -79.164434) (xy 0.715772 -79.727552) (xy 58.25185 -79.727552) (xy 58.255921 -79.67193)
			(xy 58.268047 -79.617493) (xy 58.28797 -79.565402) (xy 58.315266 -79.516767) (xy 58.349352 -79.472624)
			(xy 58.389501 -79.433915) (xy 58.434859 -79.401464) (xy 58.484459 -79.375963) (xy 58.537243 -79.357956)
			(xy 58.592086 -79.347826) (xy 58.64782 -79.345789) (xy 58.703257 -79.351889) (xy 58.757214 -79.365995)
			(xy 58.808543 -79.387807) (xy 58.856149 -79.416861) (xy 58.899017 -79.452536) (xy 58.936234 -79.494073)
			(xy 58.967007 -79.540586) (xy 58.990679 -79.591083) (xy 59.006747 -79.64449) (xy 59.014867 -79.699666)
			(xy 59.015376 -79.727552) (xy 59.014867 -79.755438) (xy 59.006747 -79.810614) (xy 58.990679 -79.864021)
			(xy 58.967007 -79.914518) (xy 58.936234 -79.961031) (xy 58.899017 -80.002568) (xy 58.878183 -80.019906)
			(xy 72.500742 -80.019906) (xy 72.504813 -79.964284) (xy 72.516939 -79.909847) (xy 72.536862 -79.857756)
			(xy 72.564158 -79.809121) (xy 72.598244 -79.764978) (xy 72.638393 -79.726269) (xy 72.683751 -79.693818)
			(xy 72.733351 -79.668317) (xy 72.786135 -79.65031) (xy 72.840978 -79.64018) (xy 72.896712 -79.638143)
			(xy 72.952149 -79.644243) (xy 73.006106 -79.658349) (xy 73.057435 -79.680161) (xy 73.105041 -79.709215)
			(xy 73.147909 -79.74489) (xy 73.185126 -79.786427) (xy 73.215899 -79.83294) (xy 73.239571 -79.883437)
			(xy 73.255639 -79.936844) (xy 73.263759 -79.99202) (xy 73.264268 -80.019906) (xy 73.263759 -80.047792)
			(xy 73.255639 -80.102968) (xy 73.239571 -80.156375) (xy 73.215899 -80.206872) (xy 73.185126 -80.253385)
			(xy 73.147909 -80.294922) (xy 73.105041 -80.330597) (xy 73.057435 -80.359651) (xy 73.006106 -80.381463)
			(xy 72.952149 -80.395569) (xy 72.896712 -80.401669) (xy 72.840978 -80.399632) (xy 72.786135 -80.389502)
			(xy 72.733351 -80.371495) (xy 72.683751 -80.345994) (xy 72.638393 -80.313543) (xy 72.598244 -80.274834)
			(xy 72.564158 -80.230691) (xy 72.536862 -80.182056) (xy 72.516939 -80.129965) (xy 72.504813 -80.075528)
			(xy 72.500742 -80.019906) (xy 58.878183 -80.019906) (xy 58.856149 -80.038243) (xy 58.808543 -80.067297)
			(xy 58.757214 -80.089109) (xy 58.703257 -80.103215) (xy 58.64782 -80.109315) (xy 58.592086 -80.107278)
			(xy 58.537243 -80.097148) (xy 58.484459 -80.079141) (xy 58.434859 -80.05364) (xy 58.389501 -80.021189)
			(xy 58.349352 -79.98248) (xy 58.315266 -79.938337) (xy 58.28797 -79.889702) (xy 58.268047 -79.837611)
			(xy 58.255921 -79.783174) (xy 58.25185 -79.727552) (xy 0.715772 -79.727552) (xy 0.715772 -81.120488)
			(xy 88.099136 -81.120488) (xy 88.103207 -81.064866) (xy 88.115333 -81.010429) (xy 88.135256 -80.958338)
			(xy 88.162552 -80.909703) (xy 88.196638 -80.86556) (xy 88.236787 -80.826851) (xy 88.282145 -80.7944)
			(xy 88.331745 -80.768899) (xy 88.384529 -80.750892) (xy 88.439372 -80.740762) (xy 88.495106 -80.738725)
			(xy 88.550543 -80.744825) (xy 88.6045 -80.758931) (xy 88.655829 -80.780743) (xy 88.703435 -80.809797)
			(xy 88.746303 -80.845472) (xy 88.78352 -80.887009) (xy 88.814293 -80.933522) (xy 88.837965 -80.984019)
			(xy 88.854033 -81.037426) (xy 88.862153 -81.092602) (xy 88.862662 -81.120488) (xy 88.862153 -81.148374)
			(xy 88.854033 -81.20355) (xy 88.837965 -81.256957) (xy 88.814293 -81.307454) (xy 88.78352 -81.353967)
			(xy 88.746303 -81.395504) (xy 88.703435 -81.431179) (xy 88.655829 -81.460233) (xy 88.6045 -81.482045)
			(xy 88.550543 -81.496151) (xy 88.495106 -81.502251) (xy 88.439372 -81.500214) (xy 88.384529 -81.490084)
			(xy 88.331745 -81.472077) (xy 88.282145 -81.446576) (xy 88.236787 -81.414125) (xy 88.196638 -81.375416)
			(xy 88.162552 -81.331273) (xy 88.135256 -81.282638) (xy 88.115333 -81.230547) (xy 88.103207 -81.17611)
			(xy 88.099136 -81.120488) (xy 0.715772 -81.120488) (xy 0.715772 -81.839308) (xy 88.80551 -81.839308)
			(xy 88.809581 -81.783686) (xy 88.821707 -81.729249) (xy 88.84163 -81.677158) (xy 88.868926 -81.628523)
			(xy 88.903012 -81.58438) (xy 88.943161 -81.545671) (xy 88.988519 -81.51322) (xy 89.038119 -81.487719)
			(xy 89.090903 -81.469712) (xy 89.145746 -81.459582) (xy 89.20148 -81.457545) (xy 89.256917 -81.463645)
			(xy 89.310874 -81.477751) (xy 89.362203 -81.499563) (xy 89.409809 -81.528617) (xy 89.452677 -81.564292)
			(xy 89.489894 -81.605829) (xy 89.520667 -81.652342) (xy 89.544339 -81.702839) (xy 89.560407 -81.756246)
			(xy 89.568527 -81.811422) (xy 89.569036 -81.839308) (xy 89.568527 -81.867194) (xy 89.560407 -81.92237)
			(xy 89.544339 -81.975777) (xy 89.520667 -82.026274) (xy 89.489894 -82.072787) (xy 89.452677 -82.114324)
			(xy 89.409809 -82.149999) (xy 89.362203 -82.179053) (xy 89.310874 -82.200865) (xy 89.256917 -82.214971)
			(xy 89.20148 -82.221071) (xy 89.145746 -82.219034) (xy 89.090903 -82.208904) (xy 89.038119 -82.190897)
			(xy 88.988519 -82.165396) (xy 88.943161 -82.132945) (xy 88.903012 -82.094236) (xy 88.868926 -82.050093)
			(xy 88.84163 -82.001458) (xy 88.821707 -81.949367) (xy 88.809581 -81.89493) (xy 88.80551 -81.839308)
			(xy 0.715772 -81.839308) (xy 0.715772 -82.427572) (xy 78.932784 -82.427572) (xy 78.936855 -82.37195)
			(xy 78.948981 -82.317513) (xy 78.968904 -82.265422) (xy 78.9962 -82.216787) (xy 79.030286 -82.172644)
			(xy 79.070435 -82.133935) (xy 79.115793 -82.101484) (xy 79.165393 -82.075983) (xy 79.218177 -82.057976)
			(xy 79.27302 -82.047846) (xy 79.328754 -82.045809) (xy 79.384191 -82.051909) (xy 79.438148 -82.066015)
			(xy 79.489477 -82.087827) (xy 79.537083 -82.116881) (xy 79.579951 -82.152556) (xy 79.617168 -82.194093)
			(xy 79.647941 -82.240606) (xy 79.671613 -82.291103) (xy 79.687681 -82.34451) (xy 79.692578 -82.377788)
			(xy 80.519014 -82.377788) (xy 80.523085 -82.322166) (xy 80.535211 -82.267729) (xy 80.555134 -82.215638)
			(xy 80.58243 -82.167003) (xy 80.616516 -82.12286) (xy 80.656665 -82.084151) (xy 80.702023 -82.0517)
			(xy 80.751623 -82.026199) (xy 80.804407 -82.008192) (xy 80.85925 -81.998062) (xy 80.914984 -81.996025)
			(xy 80.970421 -82.002125) (xy 81.024378 -82.016231) (xy 81.075707 -82.038043) (xy 81.123313 -82.067097)
			(xy 81.166181 -82.102772) (xy 81.203398 -82.144309) (xy 81.234171 -82.190822) (xy 81.257843 -82.241319)
			(xy 81.273911 -82.294726) (xy 81.282031 -82.349902) (xy 81.28254 -82.377788) (xy 81.282031 -82.405674)
			(xy 81.273911 -82.46085) (xy 81.257843 -82.514257) (xy 81.234171 -82.564754) (xy 81.203398 -82.611267)
			(xy 81.166181 -82.652804) (xy 81.123313 -82.688479) (xy 81.075707 -82.717533) (xy 81.024378 -82.739345)
			(xy 80.970421 -82.753451) (xy 80.914984 -82.759551) (xy 80.85925 -82.757514) (xy 80.804407 -82.747384)
			(xy 80.751623 -82.729377) (xy 80.702023 -82.703876) (xy 80.656665 -82.671425) (xy 80.616516 -82.632716)
			(xy 80.58243 -82.588573) (xy 80.555134 -82.539938) (xy 80.535211 -82.487847) (xy 80.523085 -82.43341)
			(xy 80.519014 -82.377788) (xy 79.692578 -82.377788) (xy 79.695801 -82.399686) (xy 79.69631 -82.427572)
			(xy 79.695801 -82.455458) (xy 79.687681 -82.510634) (xy 79.671613 -82.564041) (xy 79.647941 -82.614538)
			(xy 79.617168 -82.661051) (xy 79.579951 -82.702588) (xy 79.537083 -82.738263) (xy 79.489477 -82.767317)
			(xy 79.438148 -82.789129) (xy 79.384191 -82.803235) (xy 79.328754 -82.809335) (xy 79.27302 -82.807298)
			(xy 79.218177 -82.797168) (xy 79.165393 -82.779161) (xy 79.115793 -82.75366) (xy 79.070435 -82.721209)
			(xy 79.030286 -82.6825) (xy 78.9962 -82.638357) (xy 78.968904 -82.589722) (xy 78.948981 -82.537631)
			(xy 78.936855 -82.483194) (xy 78.932784 -82.427572) (xy 0.715772 -82.427572) (xy 0.715772 -82.852768)
			(xy 0.716788 -82.86242) (xy 0.71841 -82.869667) (xy 0.725241 -82.882846) (xy 0.73025 -82.888328)
			(xy 2.864104 -85.022182) (xy 2.867634 -85.025496) (xy 2.867697 -85.025538) (xy 44.856389 -85.025538)
			(xy 44.856389 -84.896398) (xy 44.864339 -84.767503) (xy 44.880209 -84.639343) (xy 44.903938 -84.512402)
			(xy 44.935437 -84.387163) (xy 44.974586 -84.2641) (xy 45.021237 -84.143681) (xy 45.075212 -84.026362)
			(xy 45.136307 -83.912588) (xy 45.20429 -83.802791) (xy 45.278904 -83.697388) (xy 45.359865 -83.596778)
			(xy 45.446865 -83.501343) (xy 45.539576 -83.411444) (xy 45.637646 -83.327423) (xy 45.740701 -83.249599)
			(xy 45.848352 -83.178267) (xy 45.960191 -83.113697) (xy 46.075792 -83.056135) (xy 46.194717 -83.005798)
			(xy 46.316516 -82.962878) (xy 46.440726 -82.927537) (xy 46.566875 -82.89991) (xy 46.694487 -82.880101)
			(xy 46.823076 -82.868185) (xy 46.952154 -82.864209) (xy 47.081232 -82.868185) (xy 47.209821 -82.880101)
			(xy 47.337433 -82.89991) (xy 47.463582 -82.927537) (xy 47.587792 -82.962878) (xy 47.709591 -83.005798)
			(xy 47.828516 -83.056135) (xy 47.944117 -83.113697) (xy 48.055956 -83.178267) (xy 48.163607 -83.249599)
			(xy 48.266662 -83.327423) (xy 48.364732 -83.411444) (xy 48.457443 -83.501343) (xy 48.485589 -83.532218)
			(xy 76.311504 -83.532218) (xy 76.315575 -83.476596) (xy 76.327701 -83.422159) (xy 76.347624 -83.370068)
			(xy 76.37492 -83.321433) (xy 76.409006 -83.27729) (xy 76.449155 -83.238581) (xy 76.494513 -83.20613)
			(xy 76.544113 -83.180629) (xy 76.596897 -83.162622) (xy 76.65174 -83.152492) (xy 76.707474 -83.150455)
			(xy 76.762911 -83.156555) (xy 76.816868 -83.170661) (xy 76.868197 -83.192473) (xy 76.915803 -83.221527)
			(xy 76.958671 -83.257202) (xy 76.995888 -83.298739) (xy 77.026661 -83.345252) (xy 77.050333 -83.395749)
			(xy 77.066401 -83.449156) (xy 77.074521 -83.504332) (xy 77.07503 -83.532218) (xy 77.074521 -83.560104)
			(xy 77.066401 -83.61528) (xy 77.050333 -83.668687) (xy 77.026661 -83.719184) (xy 76.995888 -83.765697)
			(xy 76.958671 -83.807234) (xy 76.915803 -83.842909) (xy 76.868197 -83.871963) (xy 76.816868 -83.893775)
			(xy 76.762911 -83.907881) (xy 76.707474 -83.913981) (xy 76.65174 -83.911944) (xy 76.596897 -83.901814)
			(xy 76.544113 -83.883807) (xy 76.494513 -83.858306) (xy 76.449155 -83.825855) (xy 76.409006 -83.787146)
			(xy 76.37492 -83.743003) (xy 76.347624 -83.694368) (xy 76.327701 -83.642277) (xy 76.315575 -83.58784)
			(xy 76.311504 -83.532218) (xy 48.485589 -83.532218) (xy 48.544443 -83.596778) (xy 48.625404 -83.697388)
			(xy 48.700018 -83.802791) (xy 48.768001 -83.912588) (xy 48.829096 -84.026362) (xy 48.883071 -84.143681)
			(xy 48.929722 -84.2641) (xy 48.968871 -84.387163) (xy 48.991299 -84.476336) (xy 79.867758 -84.476336)
			(xy 79.871829 -84.420714) (xy 79.883955 -84.366277) (xy 79.903878 -84.314186) (xy 79.931174 -84.265551)
			(xy 79.96526 -84.221408) (xy 80.005409 -84.182699) (xy 80.050767 -84.150248) (xy 80.100367 -84.124747)
			(xy 80.153151 -84.10674) (xy 80.207994 -84.09661) (xy 80.263728 -84.094573) (xy 80.319165 -84.100673)
			(xy 80.373122 -84.114779) (xy 80.424451 -84.136591) (xy 80.472057 -84.165645) (xy 80.514925 -84.20132)
			(xy 80.552142 -84.242857) (xy 80.582915 -84.28937) (xy 80.606587 -84.339867) (xy 80.622655 -84.393274)
			(xy 80.630775 -84.44845) (xy 80.631284 -84.476336) (xy 80.630775 -84.504222) (xy 80.622655 -84.559398)
			(xy 80.606587 -84.612805) (xy 80.582915 -84.663302) (xy 80.552142 -84.709815) (xy 80.514925 -84.751352)
			(xy 80.472057 -84.787027) (xy 80.424451 -84.816081) (xy 80.373122 -84.837893) (xy 80.319165 -84.851999)
			(xy 80.263728 -84.858099) (xy 80.207994 -84.856062) (xy 80.153151 -84.845932) (xy 80.100367 -84.827925)
			(xy 80.050767 -84.802424) (xy 80.005409 -84.769973) (xy 79.96526 -84.731264) (xy 79.931174 -84.687121)
			(xy 79.903878 -84.638486) (xy 79.883955 -84.586395) (xy 79.871829 -84.531958) (xy 79.867758 -84.476336)
			(xy 48.991299 -84.476336) (xy 49.00037 -84.512402) (xy 49.024099 -84.639343) (xy 49.039969 -84.767503)
			(xy 49.047919 -84.896398) (xy 49.048416 -84.960968) (xy 49.047919 -85.025538) (xy 49.039969 -85.154433)
			(xy 49.024099 -85.282593) (xy 49.004976 -85.384894) (xy 59.304426 -85.384894) (xy 59.308497 -85.329272)
			(xy 59.320623 -85.274835) (xy 59.340546 -85.222744) (xy 59.367842 -85.174109) (xy 59.401928 -85.129966)
			(xy 59.442077 -85.091257) (xy 59.487435 -85.058806) (xy 59.537035 -85.033305) (xy 59.589819 -85.015298)
			(xy 59.644662 -85.005168) (xy 59.700396 -85.003131) (xy 59.755833 -85.009231) (xy 59.80979 -85.023337)
			(xy 59.861119 -85.045149) (xy 59.908725 -85.074203) (xy 59.951593 -85.109878) (xy 59.98881 -85.151415)
			(xy 60.019583 -85.197928) (xy 60.043255 -85.248425) (xy 60.059323 -85.301832) (xy 60.067443 -85.357008)
			(xy 60.067669 -85.3694) (xy 88.294462 -85.3694) (xy 88.298533 -85.313778) (xy 88.310659 -85.259341)
			(xy 88.330582 -85.20725) (xy 88.357878 -85.158615) (xy 88.391964 -85.114472) (xy 88.432113 -85.075763)
			(xy 88.477471 -85.043312) (xy 88.527071 -85.017811) (xy 88.579855 -84.999804) (xy 88.634698 -84.989674)
			(xy 88.690432 -84.987637) (xy 88.745869 -84.993737) (xy 88.799826 -85.007843) (xy 88.851155 -85.029655)
			(xy 88.898761 -85.058709) (xy 88.941629 -85.094384) (xy 88.978846 -85.135921) (xy 89.009619 -85.182434)
			(xy 89.033291 -85.232931) (xy 89.049359 -85.286338) (xy 89.057479 -85.341514) (xy 89.057988 -85.3694)
			(xy 89.057479 -85.397286) (xy 89.049359 -85.452462) (xy 89.033291 -85.505869) (xy 89.009619 -85.556366)
			(xy 88.978846 -85.602879) (xy 88.941629 -85.644416) (xy 88.898761 -85.680091) (xy 88.851155 -85.709145)
			(xy 88.799826 -85.730957) (xy 88.745869 -85.745063) (xy 88.690432 -85.751163) (xy 88.634698 -85.749126)
			(xy 88.579855 -85.738996) (xy 88.527071 -85.720989) (xy 88.477471 -85.695488) (xy 88.432113 -85.663037)
			(xy 88.391964 -85.624328) (xy 88.357878 -85.580185) (xy 88.330582 -85.53155) (xy 88.310659 -85.479459)
			(xy 88.298533 -85.425022) (xy 88.294462 -85.3694) (xy 60.067669 -85.3694) (xy 60.067952 -85.384894)
			(xy 60.067443 -85.41278) (xy 60.059323 -85.467956) (xy 60.043255 -85.521363) (xy 60.019583 -85.57186)
			(xy 59.98881 -85.618373) (xy 59.951593 -85.65991) (xy 59.908725 -85.695585) (xy 59.861119 -85.724639)
			(xy 59.80979 -85.746451) (xy 59.755833 -85.760557) (xy 59.700396 -85.766657) (xy 59.644662 -85.76462)
			(xy 59.589819 -85.75449) (xy 59.537035 -85.736483) (xy 59.487435 -85.710982) (xy 59.442077 -85.678531)
			(xy 59.401928 -85.639822) (xy 59.367842 -85.595679) (xy 59.340546 -85.547044) (xy 59.320623 -85.494953)
			(xy 59.308497 -85.440516) (xy 59.304426 -85.384894) (xy 49.004976 -85.384894) (xy 49.00037 -85.409534)
			(xy 48.968871 -85.534773) (xy 48.929722 -85.657836) (xy 48.883071 -85.778255) (xy 48.829096 -85.895574)
			(xy 48.768001 -86.009348) (xy 48.700018 -86.119145) (xy 48.625404 -86.224548) (xy 48.606543 -86.247986)
			(xy 75.238608 -86.247986) (xy 75.242679 -86.192364) (xy 75.254805 -86.137927) (xy 75.274728 -86.085836)
			(xy 75.302024 -86.037201) (xy 75.33611 -85.993058) (xy 75.376259 -85.954349) (xy 75.421617 -85.921898)
			(xy 75.471217 -85.896397) (xy 75.524001 -85.87839) (xy 75.578844 -85.86826) (xy 75.634578 -85.866223)
			(xy 75.690015 -85.872323) (xy 75.743972 -85.886429) (xy 75.795301 -85.908241) (xy 75.842907 -85.937295)
			(xy 75.885775 -85.97297) (xy 75.922992 -86.014507) (xy 75.953765 -86.06102) (xy 75.977437 -86.111517)
			(xy 75.993505 -86.164924) (xy 76.001625 -86.2201) (xy 76.002134 -86.247986) (xy 76.001625 -86.275872)
			(xy 75.993505 -86.331048) (xy 75.977437 -86.384455) (xy 75.953765 -86.434952) (xy 75.922992 -86.481465)
			(xy 75.885775 -86.523002) (xy 75.842907 -86.558677) (xy 75.795301 -86.587731) (xy 75.743972 -86.609543)
			(xy 75.690015 -86.623649) (xy 75.634578 -86.629749) (xy 75.578844 -86.627712) (xy 75.524001 -86.617582)
			(xy 75.471217 -86.599575) (xy 75.421617 -86.574074) (xy 75.376259 -86.541623) (xy 75.33611 -86.502914)
			(xy 75.302024 -86.458771) (xy 75.274728 -86.410136) (xy 75.254805 -86.358045) (xy 75.242679 -86.303608)
			(xy 75.238608 -86.247986) (xy 48.606543 -86.247986) (xy 48.544443 -86.325158) (xy 48.457443 -86.420593)
			(xy 48.364732 -86.510492) (xy 48.266662 -86.594513) (xy 48.163607 -86.672337) (xy 48.055956 -86.743669)
			(xy 47.944117 -86.808239) (xy 47.828516 -86.865801) (xy 47.709591 -86.916138) (xy 47.587792 -86.959058)
			(xy 47.466826 -86.993476) (xy 59.629038 -86.993476) (xy 59.633109 -86.937854) (xy 59.645235 -86.883417)
			(xy 59.665158 -86.831326) (xy 59.692454 -86.782691) (xy 59.72654 -86.738548) (xy 59.766689 -86.699839)
			(xy 59.812047 -86.667388) (xy 59.861647 -86.641887) (xy 59.914431 -86.62388) (xy 59.969274 -86.61375)
			(xy 60.025008 -86.611713) (xy 60.080445 -86.617813) (xy 60.134402 -86.631919) (xy 60.185731 -86.653731)
			(xy 60.233337 -86.682785) (xy 60.276205 -86.71846) (xy 60.313422 -86.759997) (xy 60.344195 -86.80651)
			(xy 60.367867 -86.857007) (xy 60.383935 -86.910414) (xy 60.392055 -86.96559) (xy 60.392564 -86.993476)
			(xy 60.392055 -87.021362) (xy 60.383935 -87.076538) (xy 60.367867 -87.129945) (xy 60.344195 -87.180442)
			(xy 60.313422 -87.226955) (xy 60.276205 -87.268492) (xy 60.233337 -87.304167) (xy 60.185731 -87.333221)
			(xy 60.134402 -87.355033) (xy 60.080445 -87.369139) (xy 60.025008 -87.375239) (xy 59.969274 -87.373202)
			(xy 59.914431 -87.363072) (xy 59.861647 -87.345065) (xy 59.812047 -87.319564) (xy 59.766689 -87.287113)
			(xy 59.72654 -87.248404) (xy 59.692454 -87.204261) (xy 59.665158 -87.155626) (xy 59.645235 -87.103535)
			(xy 59.633109 -87.049098) (xy 59.629038 -86.993476) (xy 47.466826 -86.993476) (xy 47.463582 -86.994399)
			(xy 47.337433 -87.022026) (xy 47.209821 -87.041835) (xy 47.081232 -87.053751) (xy 46.952154 -87.057728)
			(xy 46.823076 -87.053751) (xy 46.694487 -87.041835) (xy 46.566875 -87.022026) (xy 46.440726 -86.994399)
			(xy 46.316516 -86.959058) (xy 46.194717 -86.916138) (xy 46.075792 -86.865801) (xy 45.960191 -86.808239)
			(xy 45.848352 -86.743669) (xy 45.740701 -86.672337) (xy 45.637646 -86.594513) (xy 45.539576 -86.510492)
			(xy 45.446865 -86.420593) (xy 45.359865 -86.325158) (xy 45.278904 -86.224548) (xy 45.20429 -86.119145)
			(xy 45.136307 -86.009348) (xy 45.075212 -85.895574) (xy 45.021237 -85.778255) (xy 44.974586 -85.657836)
			(xy 44.935437 -85.534773) (xy 44.903938 -85.409534) (xy 44.880209 -85.282593) (xy 44.864339 -85.154433)
			(xy 44.856389 -85.025538) (xy 2.867697 -85.025538) (xy 2.87569 -85.030864) (xy 2.880106 -85.03285)
			(xy 2.889504 -85.036914) (xy 3.045714 -85.036914) (xy 3.055783 -85.03734) (xy 3.074382 -85.04506)
			(xy 3.081782 -85.0519) (xy 4.369054 -86.339172) (xy 4.375894 -86.346572) (xy 4.38361 -86.365171)
			(xy 4.38404 -86.37524) (xy 4.38404 -88.375998) (xy 79.899 -88.375998) (xy 79.903071 -88.320376) (xy 79.915197 -88.265939)
			(xy 79.93512 -88.213848) (xy 79.962416 -88.165213) (xy 79.996502 -88.12107) (xy 80.036651 -88.082361)
			(xy 80.082009 -88.04991) (xy 80.131609 -88.024409) (xy 80.184393 -88.006402) (xy 80.239236 -87.996272)
			(xy 80.29497 -87.994235) (xy 80.350407 -88.000335) (xy 80.404364 -88.014441) (xy 80.455693 -88.036253)
			(xy 80.503299 -88.065307) (xy 80.546167 -88.100982) (xy 80.583384 -88.142519) (xy 80.614157 -88.189032)
			(xy 80.637829 -88.239529) (xy 80.653897 -88.292936) (xy 80.662017 -88.348112) (xy 80.662526 -88.375998)
			(xy 80.662164 -88.39581) (xy 81.257646 -88.39581) (xy 81.261717 -88.340188) (xy 81.273843 -88.285751)
			(xy 81.293766 -88.23366) (xy 81.321062 -88.185025) (xy 81.355148 -88.140882) (xy 81.395297 -88.102173)
			(xy 81.440655 -88.069722) (xy 81.490255 -88.044221) (xy 81.543039 -88.026214) (xy 81.597882 -88.016084)
			(xy 81.653616 -88.014047) (xy 81.709053 -88.020147) (xy 81.76301 -88.034253) (xy 81.814339 -88.056065)
			(xy 81.861945 -88.085119) (xy 81.904813 -88.120794) (xy 81.94203 -88.162331) (xy 81.972803 -88.208844)
			(xy 81.996475 -88.259341) (xy 82.012543 -88.312748) (xy 82.020663 -88.367924) (xy 82.021172 -88.39581)
			(xy 82.020663 -88.423696) (xy 82.012543 -88.478872) (xy 81.996475 -88.532279) (xy 81.972803 -88.582776)
			(xy 81.94203 -88.629289) (xy 81.904813 -88.670826) (xy 81.861945 -88.706501) (xy 81.814339 -88.735555)
			(xy 81.76301 -88.757367) (xy 81.709053 -88.771473) (xy 81.653616 -88.777573) (xy 81.597882 -88.775536)
			(xy 81.543039 -88.765406) (xy 81.490255 -88.747399) (xy 81.440655 -88.721898) (xy 81.395297 -88.689447)
			(xy 81.355148 -88.650738) (xy 81.321062 -88.606595) (xy 81.293766 -88.55796) (xy 81.273843 -88.505869)
			(xy 81.261717 -88.451432) (xy 81.257646 -88.39581) (xy 80.662164 -88.39581) (xy 80.662017 -88.403884)
			(xy 80.653897 -88.45906) (xy 80.637829 -88.512467) (xy 80.614157 -88.562964) (xy 80.583384 -88.609477)
			(xy 80.546167 -88.651014) (xy 80.503299 -88.686689) (xy 80.455693 -88.715743) (xy 80.404364 -88.737555)
			(xy 80.350407 -88.751661) (xy 80.29497 -88.757761) (xy 80.239236 -88.755724) (xy 80.184393 -88.745594)
			(xy 80.131609 -88.727587) (xy 80.082009 -88.702086) (xy 80.036651 -88.669635) (xy 79.996502 -88.630926)
			(xy 79.962416 -88.586783) (xy 79.93512 -88.538148) (xy 79.915197 -88.486057) (xy 79.903071 -88.43162)
			(xy 79.899 -88.375998) (xy 4.38404 -88.375998) (xy 4.38404 -88.956642) (xy 73.632566 -88.956642)
			(xy 73.636637 -88.90102) (xy 73.648763 -88.846583) (xy 73.668686 -88.794492) (xy 73.695982 -88.745857)
			(xy 73.730068 -88.701714) (xy 73.770217 -88.663005) (xy 73.815575 -88.630554) (xy 73.865175 -88.605053)
			(xy 73.917959 -88.587046) (xy 73.972802 -88.576916) (xy 74.028536 -88.574879) (xy 74.083973 -88.580979)
			(xy 74.13793 -88.595085) (xy 74.189259 -88.616897) (xy 74.236865 -88.645951) (xy 74.279733 -88.681626)
			(xy 74.31695 -88.723163) (xy 74.347723 -88.769676) (xy 74.371395 -88.820173) (xy 74.387463 -88.87358)
			(xy 74.395583 -88.928756) (xy 74.396092 -88.956642) (xy 74.395583 -88.984528) (xy 74.387463 -89.039704)
			(xy 74.371395 -89.093111) (xy 74.347723 -89.143608) (xy 74.31695 -89.190121) (xy 74.279733 -89.231658)
			(xy 74.236865 -89.267333) (xy 74.189259 -89.296387) (xy 74.13793 -89.318199) (xy 74.083973 -89.332305)
			(xy 74.028536 -89.338405) (xy 73.972802 -89.336368) (xy 73.917959 -89.326238) (xy 73.865175 -89.308231)
			(xy 73.815575 -89.28273) (xy 73.770217 -89.250279) (xy 73.730068 -89.21157) (xy 73.695982 -89.167427)
			(xy 73.668686 -89.118792) (xy 73.648763 -89.066701) (xy 73.636637 -89.012264) (xy 73.632566 -88.956642)
			(xy 4.38404 -88.956642) (xy 4.38404 -90.67345) (xy 78.092805 -90.67345) (xy 78.092805 -90.61895)
			(xy 78.100561 -90.565006) (xy 78.115916 -90.512714) (xy 78.138556 -90.46314) (xy 78.168021 -90.417292)
			(xy 78.203711 -90.376105) (xy 78.244899 -90.340416) (xy 78.290747 -90.310952) (xy 78.340322 -90.288313)
			(xy 78.392614 -90.27296) (xy 78.446558 -90.265205) (xy 78.473808 -90.264742) (xy 78.502403 -90.265284)
			(xy 78.558952 -90.273808) (xy 78.613596 -90.29068) (xy 78.665108 -90.31552) (xy 78.712334 -90.347773)
			(xy 78.754216 -90.386715) (xy 78.789815 -90.431473) (xy 78.804516 -90.456004) (xy 78.811628 -90.46845)
			(xy 78.836012 -90.481912) (xy 78.954376 -90.47734) (xy 78.977998 -90.461846) (xy 78.984094 -90.449146)
			(xy 78.99612 -90.425159) (xy 79.025818 -90.38047) (xy 79.061486 -90.340385) (xy 79.102419 -90.305692)
			(xy 79.147809 -90.277078) (xy 79.196761 -90.255107) (xy 79.248309 -90.240213) (xy 79.301436 -90.232689)
			(xy 79.328264 -90.23223) (xy 79.356708 -90.232791) (xy 79.412966 -90.24124) (xy 79.467344 -90.257954)
			(xy 79.518634 -90.282563) (xy 79.565698 -90.314521) (xy 79.607491 -90.353118) (xy 79.625698 -90.374978)
			(xy 79.633364 -90.383659) (xy 79.654258 -90.393588) (xy 79.66583 -90.394028) (xy 79.757778 -90.393012)
			(xy 79.778606 -90.382344) (xy 79.785718 -90.372946) (xy 79.803889 -90.350096) (xy 79.84603 -90.309696)
			(xy 79.893832 -90.276184) (xy 79.94618 -90.250343) (xy 80.001852 -90.232776) (xy 80.059551 -90.223892)
			(xy 80.08874 -90.22334) (xy 80.118546 -90.223887) (xy 80.17743 -90.233183) (xy 80.234151 -90.251528)
			(xy 80.287327 -90.278474) (xy 80.335662 -90.313366) (xy 80.377981 -90.355353) (xy 80.39608 -90.379042)
			(xy 80.39608 -90.379296) (xy 80.401344 -90.385904) (xy 80.415284 -90.395435) (xy 80.431577 -90.399872)
			(xy 80.440022 -90.399616) (xy 80.53832 -90.39352) (xy 80.560164 -90.379804) (xy 80.566514 -90.368628)
			(xy 80.573821 -90.355969) (xy 80.590095 -90.331685) (xy 80.599026 -90.320114) (xy 80.59928 -90.31986)
			(xy 80.604302 -90.31275) (xy 80.609756 -90.296233) (xy 80.609391 -90.278843) (xy 80.606646 -90.270584)
			(xy 80.575404 -90.18905) (xy 80.572004 -90.181) (xy 80.560703 -90.167687) (xy 80.545577 -90.158961)
			(xy 80.53705 -90.157046) (xy 80.536796 -90.157046) (xy 80.510611 -90.151994) (xy 80.459872 -90.135581)
			(xy 80.411913 -90.11226) (xy 80.367671 -90.082486) (xy 80.328007 -90.04684) (xy 80.293695 -90.006016)
			(xy 80.265404 -89.960811) (xy 80.243686 -89.912106) (xy 80.228964 -89.86085) (xy 80.221525 -89.808044)
			(xy 80.221074 -89.78138) (xy 80.22156 -89.754129) (xy 80.229316 -89.700181) (xy 80.244671 -89.647886)
			(xy 80.267313 -89.598309) (xy 80.296779 -89.552459) (xy 80.33247 -89.511268) (xy 80.373661 -89.475577)
			(xy 80.419511 -89.446111) (xy 80.469088 -89.423469) (xy 80.521383 -89.408114) (xy 80.575331 -89.400358)
			(xy 80.629833 -89.400358) (xy 80.683781 -89.408114) (xy 80.736076 -89.423469) (xy 80.785653 -89.446111)
			(xy 80.831503 -89.475577) (xy 80.872694 -89.511268) (xy 80.908385 -89.552459) (xy 80.937851 -89.598309)
			(xy 80.960493 -89.647886) (xy 80.975848 -89.700181) (xy 80.983604 -89.754129) (xy 80.98409 -89.78138)
			(xy 80.983637 -89.806797) (xy 80.97689 -89.857181) (xy 80.963512 -89.906223) (xy 80.943741 -89.953054)
			(xy 80.917926 -89.996845) (xy 80.902556 -90.017092) (xy 80.902302 -90.017346) (xy 80.897279 -90.024457)
			(xy 80.891819 -90.040973) (xy 80.892186 -90.058363) (xy 80.894936 -90.066622) (xy 80.926178 -90.148156)
			(xy 80.929587 -90.156201) (xy 80.940885 -90.169514) (xy 80.956007 -90.178243) (xy 80.964532 -90.18016)
			(xy 80.964786 -90.18016) (xy 80.99097 -90.18522) (xy 81.041709 -90.201631) (xy 81.089668 -90.22495)
			(xy 81.133911 -90.254723) (xy 81.173575 -90.290368) (xy 81.207888 -90.331191) (xy 81.236179 -90.376396)
			(xy 81.257897 -90.425101) (xy 81.272619 -90.476356) (xy 81.280058 -90.529162) (xy 81.280508 -90.555826)
			(xy 81.280046 -90.583078) (xy 81.272286 -90.637026) (xy 81.256928 -90.689322) (xy 81.234284 -90.738899)
			(xy 81.204815 -90.784749) (xy 81.169121 -90.825939) (xy 81.127928 -90.86163) (xy 81.082076 -90.891096)
			(xy 81.032497 -90.913737) (xy 80.980201 -90.929092) (xy 80.926252 -90.936848) (xy 80.899 -90.937334)
			(xy 80.869194 -90.936769) (xy 80.81031 -90.927478) (xy 80.75359 -90.909137) (xy 80.700414 -90.882195)
			(xy 80.652078 -90.847306) (xy 80.609759 -90.805321) (xy 80.59166 -90.781632) (xy 80.59166 -90.781378)
			(xy 80.586379 -90.774786) (xy 80.572446 -90.765254) (xy 80.556161 -90.760808) (xy 80.547718 -90.761058)
			(xy 80.44942 -90.767154) (xy 80.427576 -90.78087) (xy 80.421226 -90.792046) (xy 80.406632 -90.816935)
			(xy 80.371059 -90.86236) (xy 80.329055 -90.901915) (xy 80.281578 -90.934698) (xy 80.229708 -90.959964)
			(xy 80.174626 -90.977136) (xy 80.117588 -90.985825) (xy 80.08874 -90.986356) (xy 80.060293 -90.985868)
			(xy 80.004031 -90.977405) (xy 79.949652 -90.960676) (xy 79.898362 -90.936053) (xy 79.8513 -90.904082)
			(xy 79.809511 -90.865473) (xy 79.791306 -90.843608) (xy 79.783641 -90.834926) (xy 79.762746 -90.824998)
			(xy 79.751174 -90.824558) (xy 79.659226 -90.825574) (xy 79.638398 -90.836242) (xy 79.631286 -90.84564)
			(xy 79.613109 -90.868485) (xy 79.57097 -90.908886) (xy 79.523169 -90.942399) (xy 79.470823 -90.968241)
			(xy 79.415151 -90.985809) (xy 79.357453 -90.994694) (xy 79.328264 -90.995246) (xy 79.299668 -90.994733)
			(xy 79.243117 -90.986204) (xy 79.188472 -90.969328) (xy 79.13696 -90.944483) (xy 79.089734 -90.912226)
			(xy 79.047853 -90.87328) (xy 79.012256 -90.828517) (xy 78.997556 -90.803984) (xy 78.990444 -90.791538)
			(xy 78.96606 -90.778076) (xy 78.847696 -90.782648) (xy 78.824074 -90.798142) (xy 78.817978 -90.810842)
			(xy 78.805968 -90.834838) (xy 78.776268 -90.879527) (xy 78.740599 -90.919614) (xy 78.699664 -90.954306)
			(xy 78.654271 -90.982919) (xy 78.605316 -91.004888) (xy 78.553766 -91.01978) (xy 78.500637 -91.027301)
			(xy 78.473808 -91.027758) (xy 78.446558 -91.027195) (xy 78.392614 -91.01944) (xy 78.340322 -91.004087)
			(xy 78.290747 -90.981448) (xy 78.244899 -90.951984) (xy 78.203711 -90.916295) (xy 78.168021 -90.875108)
			(xy 78.138556 -90.82926) (xy 78.115916 -90.779686) (xy 78.100561 -90.727394) (xy 78.092805 -90.67345)
			(xy 4.38404 -90.67345) (xy 4.38404 -91.315794) (xy 31.655256 -91.315794) (xy 31.659327 -91.260172)
			(xy 31.671453 -91.205735) (xy 31.691376 -91.153644) (xy 31.718672 -91.105009) (xy 31.752758 -91.060866)
			(xy 31.792907 -91.022157) (xy 31.838265 -90.989706) (xy 31.887865 -90.964205) (xy 31.940649 -90.946198)
			(xy 31.995492 -90.936068) (xy 32.051226 -90.934031) (xy 32.106663 -90.940131) (xy 32.16062 -90.954237)
			(xy 32.211949 -90.976049) (xy 32.259555 -91.005103) (xy 32.302423 -91.040778) (xy 32.33964 -91.082315)
			(xy 32.370413 -91.128828) (xy 32.394085 -91.179325) (xy 32.410153 -91.232732) (xy 32.410228 -91.233244)
			(xy 58.865514 -91.233244) (xy 58.869585 -91.177622) (xy 58.881711 -91.123185) (xy 58.901634 -91.071094)
			(xy 58.92893 -91.022459) (xy 58.963016 -90.978316) (xy 59.003165 -90.939607) (xy 59.048523 -90.907156)
			(xy 59.098123 -90.881655) (xy 59.150907 -90.863648) (xy 59.20575 -90.853518) (xy 59.261484 -90.851481)
			(xy 59.316921 -90.857581) (xy 59.370878 -90.871687) (xy 59.422207 -90.893499) (xy 59.469813 -90.922553)
			(xy 59.512681 -90.958228) (xy 59.549898 -90.999765) (xy 59.580671 -91.046278) (xy 59.604343 -91.096775)
			(xy 59.620411 -91.150182) (xy 59.628531 -91.205358) (xy 59.62904 -91.233244) (xy 59.628531 -91.26113)
			(xy 59.620411 -91.316306) (xy 59.604343 -91.369713) (xy 59.580671 -91.42021) (xy 59.549898 -91.466723)
			(xy 59.512681 -91.50826) (xy 59.469813 -91.543935) (xy 59.422207 -91.572989) (xy 59.370878 -91.594801)
			(xy 59.316921 -91.608907) (xy 59.261484 -91.615007) (xy 59.20575 -91.61297) (xy 59.150907 -91.60284)
			(xy 59.098123 -91.584833) (xy 59.048523 -91.559332) (xy 59.003165 -91.526881) (xy 58.963016 -91.488172)
			(xy 58.92893 -91.444029) (xy 58.901634 -91.395394) (xy 58.881711 -91.343303) (xy 58.869585 -91.288866)
			(xy 58.865514 -91.233244) (xy 32.410228 -91.233244) (xy 32.418273 -91.287908) (xy 32.418782 -91.315794)
			(xy 32.418273 -91.34368) (xy 32.410153 -91.398856) (xy 32.394085 -91.452263) (xy 32.370413 -91.50276)
			(xy 32.33964 -91.549273) (xy 32.302423 -91.59081) (xy 32.259555 -91.626485) (xy 32.211949 -91.655539)
			(xy 32.16062 -91.677351) (xy 32.106663 -91.691457) (xy 32.051226 -91.697557) (xy 31.995492 -91.69552)
			(xy 31.940649 -91.68539) (xy 31.887865 -91.667383) (xy 31.838265 -91.641882) (xy 31.792907 -91.609431)
			(xy 31.752758 -91.570722) (xy 31.718672 -91.526579) (xy 31.691376 -91.477944) (xy 31.671453 -91.425853)
			(xy 31.659327 -91.371416) (xy 31.655256 -91.315794) (xy 4.38404 -91.315794) (xy 4.38404 -92.927424)
			(xy 31.559244 -92.927424) (xy 31.563315 -92.871802) (xy 31.575441 -92.817365) (xy 31.595364 -92.765274)
			(xy 31.62266 -92.716639) (xy 31.656746 -92.672496) (xy 31.696895 -92.633787) (xy 31.742253 -92.601336)
			(xy 31.791853 -92.575835) (xy 31.844637 -92.557828) (xy 31.89948 -92.547698) (xy 31.955214 -92.545661)
			(xy 32.010651 -92.551761) (xy 32.064608 -92.565867) (xy 32.115937 -92.587679) (xy 32.163543 -92.616733)
			(xy 32.206411 -92.652408) (xy 32.243628 -92.693945) (xy 32.274401 -92.740458) (xy 32.298073 -92.790955)
			(xy 32.314141 -92.844362) (xy 32.322261 -92.899538) (xy 32.32277 -92.927424) (xy 32.322261 -92.95531)
			(xy 32.314141 -93.010486) (xy 32.298073 -93.063893) (xy 32.274401 -93.11439) (xy 32.243628 -93.160903)
			(xy 32.206411 -93.20244) (xy 32.163543 -93.238115) (xy 32.115937 -93.267169) (xy 32.064608 -93.288981)
			(xy 32.010651 -93.303087) (xy 31.955214 -93.309187) (xy 31.89948 -93.30715) (xy 31.844637 -93.29702)
			(xy 31.791853 -93.279013) (xy 31.742253 -93.253512) (xy 31.696895 -93.221061) (xy 31.656746 -93.182352)
			(xy 31.62266 -93.138209) (xy 31.595364 -93.089574) (xy 31.575441 -93.037483) (xy 31.563315 -92.983046)
			(xy 31.559244 -92.927424) (xy 4.38404 -92.927424) (xy 4.38404 -95.12554) (xy 24.574752 -95.12554)
			(xy 24.578823 -95.069918) (xy 24.590949 -95.015481) (xy 24.610872 -94.96339) (xy 24.638168 -94.914755)
			(xy 24.672254 -94.870612) (xy 24.712403 -94.831903) (xy 24.757761 -94.799452) (xy 24.807361 -94.773951)
			(xy 24.860145 -94.755944) (xy 24.914988 -94.745814) (xy 24.970722 -94.743777) (xy 25.026159 -94.749877)
			(xy 25.080116 -94.763983) (xy 25.131445 -94.785795) (xy 25.179051 -94.814849) (xy 25.221919 -94.850524)
			(xy 25.259136 -94.892061) (xy 25.289909 -94.938574) (xy 25.313581 -94.989071) (xy 25.329649 -95.042478)
			(xy 25.337769 -95.097654) (xy 25.338278 -95.12554) (xy 25.337769 -95.153426) (xy 25.329649 -95.208602)
			(xy 25.32774 -95.214948) (xy 47.274239 -95.214948) (xy 47.278194 -95.123111) (xy 47.290029 -95.031954)
			(xy 47.309656 -94.942151) (xy 47.33693 -94.854369) (xy 47.37165 -94.769255) (xy 47.413558 -94.687442)
			(xy 47.462344 -94.609534) (xy 47.517647 -94.536109) (xy 47.579057 -94.467709) (xy 47.646119 -94.404842)
			(xy 47.718338 -94.347972) (xy 47.795178 -94.297521) (xy 47.876071 -94.253862) (xy 47.960417 -94.217319)
			(xy 48.047593 -94.188162) (xy 48.136952 -94.166608) (xy 48.227833 -94.152814) (xy 48.319564 -94.146884)
			(xy 48.411465 -94.148862) (xy 48.502856 -94.158733) (xy 48.59306 -94.176423) (xy 48.681409 -94.201803)
			(xy 48.767249 -94.234683) (xy 48.849945 -94.274821) (xy 48.928885 -94.32192) (xy 49.003483 -94.37563)
			(xy 49.073189 -94.435554) (xy 49.137484 -94.501248) (xy 49.195895 -94.572226) (xy 49.247987 -94.647963)
			(xy 49.293376 -94.727898) (xy 49.331726 -94.811438) (xy 49.362751 -94.897966) (xy 49.386224 -94.986841)
			(xy 49.40197 -95.077405) (xy 49.409872 -95.168987) (xy 49.410366 -95.214948) (xy 71.639189 -95.214948)
			(xy 71.643144 -95.123111) (xy 71.654979 -95.031954) (xy 71.674606 -94.942151) (xy 71.70188 -94.854369)
			(xy 71.7366 -94.769255) (xy 71.778508 -94.687442) (xy 71.827294 -94.609534) (xy 71.882597 -94.536109)
			(xy 71.944007 -94.467709) (xy 72.011069 -94.404842) (xy 72.083288 -94.347972) (xy 72.160128 -94.297521)
			(xy 72.241021 -94.253862) (xy 72.325367 -94.217319) (xy 72.412543 -94.188162) (xy 72.501902 -94.166608)
			(xy 72.592783 -94.152814) (xy 72.684514 -94.146884) (xy 72.776415 -94.148862) (xy 72.867806 -94.158733)
			(xy 72.95801 -94.176423) (xy 73.046359 -94.201803) (xy 73.132199 -94.234683) (xy 73.214895 -94.274821)
			(xy 73.293835 -94.32192) (xy 73.368433 -94.37563) (xy 73.438139 -94.435554) (xy 73.502434 -94.501248)
			(xy 73.560845 -94.572226) (xy 73.561265 -94.572836) (xy 88.806526 -94.572836) (xy 88.810597 -94.517214)
			(xy 88.822723 -94.462777) (xy 88.842646 -94.410686) (xy 88.869942 -94.362051) (xy 88.904028 -94.317908)
			(xy 88.944177 -94.279199) (xy 88.989535 -94.246748) (xy 89.039135 -94.221247) (xy 89.091919 -94.20324)
			(xy 89.146762 -94.19311) (xy 89.202496 -94.191073) (xy 89.257933 -94.197173) (xy 89.31189 -94.211279)
			(xy 89.363219 -94.233091) (xy 89.410825 -94.262145) (xy 89.453693 -94.29782) (xy 89.49091 -94.339357)
			(xy 89.521683 -94.38587) (xy 89.545355 -94.436367) (xy 89.561423 -94.489774) (xy 89.569543 -94.54495)
			(xy 89.570052 -94.572836) (xy 89.569543 -94.600722) (xy 89.561423 -94.655898) (xy 89.545355 -94.709305)
			(xy 89.521683 -94.759802) (xy 89.49091 -94.806315) (xy 89.453693 -94.847852) (xy 89.410825 -94.883527)
			(xy 89.363219 -94.912581) (xy 89.31189 -94.934393) (xy 89.257933 -94.948499) (xy 89.202496 -94.954599)
			(xy 89.146762 -94.952562) (xy 89.091919 -94.942432) (xy 89.039135 -94.924425) (xy 88.989535 -94.898924)
			(xy 88.944177 -94.866473) (xy 88.904028 -94.827764) (xy 88.869942 -94.783621) (xy 88.842646 -94.734986)
			(xy 88.822723 -94.682895) (xy 88.810597 -94.628458) (xy 88.806526 -94.572836) (xy 73.561265 -94.572836)
			(xy 73.612937 -94.647963) (xy 73.658326 -94.727898) (xy 73.696676 -94.811438) (xy 73.727701 -94.897966)
			(xy 73.751174 -94.986841) (xy 73.76692 -95.077405) (xy 73.774822 -95.168987) (xy 73.775316 -95.214948)
			(xy 73.774822 -95.260909) (xy 73.76692 -95.352491) (xy 73.751174 -95.443055) (xy 73.727701 -95.53193)
			(xy 73.696676 -95.618458) (xy 73.658326 -95.701998) (xy 73.612937 -95.781933) (xy 73.560845 -95.85767)
			(xy 73.502434 -95.928648) (xy 73.442733 -95.989648) (xy 75.563982 -95.989648) (xy 75.568053 -95.934026)
			(xy 75.580179 -95.879589) (xy 75.600102 -95.827498) (xy 75.627398 -95.778863) (xy 75.661484 -95.73472)
			(xy 75.701633 -95.696011) (xy 75.746991 -95.66356) (xy 75.796591 -95.638059) (xy 75.849375 -95.620052)
			(xy 75.904218 -95.609922) (xy 75.959952 -95.607885) (xy 76.015389 -95.613985) (xy 76.069346 -95.628091)
			(xy 76.120675 -95.649903) (xy 76.168281 -95.678957) (xy 76.211149 -95.714632) (xy 76.248366 -95.756169)
			(xy 76.278649 -95.801942) (xy 88.641426 -95.801942) (xy 88.645497 -95.74632) (xy 88.657623 -95.691883)
			(xy 88.677546 -95.639792) (xy 88.704842 -95.591157) (xy 88.738928 -95.547014) (xy 88.779077 -95.508305)
			(xy 88.824435 -95.475854) (xy 88.874035 -95.450353) (xy 88.926819 -95.432346) (xy 88.981662 -95.422216)
			(xy 89.037396 -95.420179) (xy 89.092833 -95.426279) (xy 89.14679 -95.440385) (xy 89.198119 -95.462197)
			(xy 89.245725 -95.491251) (xy 89.288593 -95.526926) (xy 89.32581 -95.568463) (xy 89.356583 -95.614976)
			(xy 89.380255 -95.665473) (xy 89.396323 -95.71888) (xy 89.404443 -95.774056) (xy 89.404952 -95.801942)
			(xy 89.404443 -95.829828) (xy 89.396323 -95.885004) (xy 89.380255 -95.938411) (xy 89.356583 -95.988908)
			(xy 89.32581 -96.035421) (xy 89.288593 -96.076958) (xy 89.245725 -96.112633) (xy 89.198119 -96.141687)
			(xy 89.14679 -96.163499) (xy 89.092833 -96.177605) (xy 89.037396 -96.183705) (xy 88.981662 -96.181668)
			(xy 88.926819 -96.171538) (xy 88.874035 -96.153531) (xy 88.824435 -96.12803) (xy 88.779077 -96.095579)
			(xy 88.738928 -96.05687) (xy 88.704842 -96.012727) (xy 88.677546 -95.964092) (xy 88.657623 -95.912001)
			(xy 88.645497 -95.857564) (xy 88.641426 -95.801942) (xy 76.278649 -95.801942) (xy 76.279139 -95.802682)
			(xy 76.302811 -95.853179) (xy 76.318879 -95.906586) (xy 76.326999 -95.961762) (xy 76.327508 -95.989648)
			(xy 76.326999 -96.017534) (xy 76.318879 -96.07271) (xy 76.302811 -96.126117) (xy 76.279139 -96.176614)
			(xy 76.248366 -96.223127) (xy 76.211149 -96.264664) (xy 76.168281 -96.300339) (xy 76.120675 -96.329393)
			(xy 76.069346 -96.351205) (xy 76.015389 -96.365311) (xy 75.959952 -96.371411) (xy 75.904218 -96.369374)
			(xy 75.849375 -96.359244) (xy 75.796591 -96.341237) (xy 75.746991 -96.315736) (xy 75.701633 -96.283285)
			(xy 75.661484 -96.244576) (xy 75.627398 -96.200433) (xy 75.600102 -96.151798) (xy 75.580179 -96.099707)
			(xy 75.568053 -96.04527) (xy 75.563982 -95.989648) (xy 73.442733 -95.989648) (xy 73.438139 -95.994342)
			(xy 73.368433 -96.054266) (xy 73.293835 -96.107976) (xy 73.214895 -96.155075) (xy 73.132199 -96.195213)
			(xy 73.046359 -96.228093) (xy 72.95801 -96.253473) (xy 72.867806 -96.271163) (xy 72.776415 -96.281034)
			(xy 72.684514 -96.283012) (xy 72.592783 -96.277082) (xy 72.501902 -96.263288) (xy 72.412543 -96.241734)
			(xy 72.325367 -96.212577) (xy 72.241021 -96.176034) (xy 72.160128 -96.132375) (xy 72.083288 -96.081924)
			(xy 72.011069 -96.025054) (xy 71.944007 -95.962187) (xy 71.882597 -95.893787) (xy 71.827294 -95.820362)
			(xy 71.778508 -95.742454) (xy 71.7366 -95.660641) (xy 71.70188 -95.575527) (xy 71.674606 -95.487745)
			(xy 71.654979 -95.397942) (xy 71.643144 -95.306785) (xy 71.639189 -95.214948) (xy 49.410366 -95.214948)
			(xy 49.409872 -95.260909) (xy 49.40197 -95.352491) (xy 49.386224 -95.443055) (xy 49.362751 -95.53193)
			(xy 49.331726 -95.618458) (xy 49.293376 -95.701998) (xy 49.247987 -95.781933) (xy 49.195895 -95.85767)
			(xy 49.137484 -95.928648) (xy 49.073189 -95.994342) (xy 49.003483 -96.054266) (xy 48.928885 -96.107976)
			(xy 48.849945 -96.155075) (xy 48.767249 -96.195213) (xy 48.681409 -96.228093) (xy 48.59306 -96.253473)
			(xy 48.502856 -96.271163) (xy 48.411465 -96.281034) (xy 48.319564 -96.283012) (xy 48.227833 -96.277082)
			(xy 48.136952 -96.263288) (xy 48.047593 -96.241734) (xy 47.960417 -96.212577) (xy 47.876071 -96.176034)
			(xy 47.795178 -96.132375) (xy 47.718338 -96.081924) (xy 47.646119 -96.025054) (xy 47.579057 -95.962187)
			(xy 47.517647 -95.893787) (xy 47.462344 -95.820362) (xy 47.413558 -95.742454) (xy 47.37165 -95.660641)
			(xy 47.33693 -95.575527) (xy 47.309656 -95.487745) (xy 47.290029 -95.397942) (xy 47.278194 -95.306785)
			(xy 47.274239 -95.214948) (xy 25.32774 -95.214948) (xy 25.313581 -95.262009) (xy 25.289909 -95.312506)
			(xy 25.259136 -95.359019) (xy 25.221919 -95.400556) (xy 25.179051 -95.436231) (xy 25.131445 -95.465285)
			(xy 25.080116 -95.487097) (xy 25.026159 -95.501203) (xy 24.970722 -95.507303) (xy 24.914988 -95.505266)
			(xy 24.860145 -95.495136) (xy 24.807361 -95.477129) (xy 24.757761 -95.451628) (xy 24.712403 -95.419177)
			(xy 24.672254 -95.380468) (xy 24.638168 -95.336325) (xy 24.610872 -95.28769) (xy 24.590949 -95.235599)
			(xy 24.578823 -95.181162) (xy 24.574752 -95.12554) (xy 4.38404 -95.12554) (xy 4.38404 -95.986092)
			(xy 25.048462 -95.986092) (xy 25.052533 -95.93047) (xy 25.064659 -95.876033) (xy 25.084582 -95.823942)
			(xy 25.111878 -95.775307) (xy 25.145964 -95.731164) (xy 25.186113 -95.692455) (xy 25.231471 -95.660004)
			(xy 25.281071 -95.634503) (xy 25.333855 -95.616496) (xy 25.388698 -95.606366) (xy 25.444432 -95.604329)
			(xy 25.499869 -95.610429) (xy 25.553826 -95.624535) (xy 25.605155 -95.646347) (xy 25.652761 -95.675401)
			(xy 25.695629 -95.711076) (xy 25.732846 -95.752613) (xy 25.763619 -95.799126) (xy 25.787291 -95.849623)
			(xy 25.803359 -95.90303) (xy 25.811479 -95.958206) (xy 25.811988 -95.986092) (xy 25.811479 -96.013978)
			(xy 25.803359 -96.069154) (xy 25.787291 -96.122561) (xy 25.767678 -96.1644) (xy 37.225476 -96.1644)
			(xy 37.229547 -96.108778) (xy 37.241673 -96.054341) (xy 37.261596 -96.00225) (xy 37.288892 -95.953615)
			(xy 37.322978 -95.909472) (xy 37.363127 -95.870763) (xy 37.408485 -95.838312) (xy 37.458085 -95.812811)
			(xy 37.510869 -95.794804) (xy 37.565712 -95.784674) (xy 37.621446 -95.782637) (xy 37.676883 -95.788737)
			(xy 37.73084 -95.802843) (xy 37.782169 -95.824655) (xy 37.829775 -95.853709) (xy 37.872643 -95.889384)
			(xy 37.90986 -95.930921) (xy 37.940633 -95.977434) (xy 37.964305 -96.027931) (xy 37.980373 -96.081338)
			(xy 37.988493 -96.136514) (xy 37.989002 -96.1644) (xy 37.988493 -96.192286) (xy 37.980373 -96.247462)
			(xy 37.964305 -96.300869) (xy 37.940633 -96.351366) (xy 37.90986 -96.397879) (xy 37.872643 -96.439416)
			(xy 37.829775 -96.475091) (xy 37.782169 -96.504145) (xy 37.73084 -96.525957) (xy 37.676883 -96.540063)
			(xy 37.621446 -96.546163) (xy 37.565712 -96.544126) (xy 37.510869 -96.533996) (xy 37.458085 -96.515989)
			(xy 37.408485 -96.490488) (xy 37.363127 -96.458037) (xy 37.322978 -96.419328) (xy 37.288892 -96.375185)
			(xy 37.261596 -96.32655) (xy 37.241673 -96.274459) (xy 37.229547 -96.220022) (xy 37.225476 -96.1644)
			(xy 25.767678 -96.1644) (xy 25.763619 -96.173058) (xy 25.732846 -96.219571) (xy 25.695629 -96.261108)
			(xy 25.652761 -96.296783) (xy 25.605155 -96.325837) (xy 25.553826 -96.347649) (xy 25.499869 -96.361755)
			(xy 25.444432 -96.367855) (xy 25.388698 -96.365818) (xy 25.333855 -96.355688) (xy 25.281071 -96.337681)
			(xy 25.231471 -96.31218) (xy 25.186113 -96.279729) (xy 25.145964 -96.24102) (xy 25.111878 -96.196877)
			(xy 25.084582 -96.148242) (xy 25.064659 -96.096151) (xy 25.052533 -96.041714) (xy 25.048462 -95.986092)
			(xy 4.38404 -95.986092) (xy 4.38404 -97.021904) (xy 25.034746 -97.021904) (xy 25.038817 -96.966282)
			(xy 25.050943 -96.911845) (xy 25.070866 -96.859754) (xy 25.098162 -96.811119) (xy 25.132248 -96.766976)
			(xy 25.172397 -96.728267) (xy 25.217755 -96.695816) (xy 25.267355 -96.670315) (xy 25.320139 -96.652308)
			(xy 25.374982 -96.642178) (xy 25.430716 -96.640141) (xy 25.486153 -96.646241) (xy 25.54011 -96.660347)
			(xy 25.591439 -96.682159) (xy 25.639045 -96.711213) (xy 25.681913 -96.746888) (xy 25.71913 -96.788425)
			(xy 25.749903 -96.834938) (xy 25.773575 -96.885435) (xy 25.789643 -96.938842) (xy 25.797763 -96.994018)
			(xy 25.798272 -97.021904) (xy 25.797763 -97.04979) (xy 25.789643 -97.104966) (xy 25.773575 -97.158373)
			(xy 25.763249 -97.1804) (xy 37.225476 -97.1804) (xy 37.229547 -97.124778) (xy 37.241673 -97.070341)
			(xy 37.261596 -97.01825) (xy 37.288892 -96.969615) (xy 37.322978 -96.925472) (xy 37.363127 -96.886763)
			(xy 37.408485 -96.854312) (xy 37.458085 -96.828811) (xy 37.510869 -96.810804) (xy 37.565712 -96.800674)
			(xy 37.621446 -96.798637) (xy 37.676883 -96.804737) (xy 37.73084 -96.818843) (xy 37.782169 -96.840655)
			(xy 37.829775 -96.869709) (xy 37.872643 -96.905384) (xy 37.90986 -96.946921) (xy 37.940633 -96.993434)
			(xy 37.964305 -97.043931) (xy 37.967842 -97.055686) (xy 51.605432 -97.055686) (xy 51.609503 -97.000064)
			(xy 51.621629 -96.945627) (xy 51.641552 -96.893536) (xy 51.668848 -96.844901) (xy 51.702934 -96.800758)
			(xy 51.743083 -96.762049) (xy 51.788441 -96.729598) (xy 51.838041 -96.704097) (xy 51.890825 -96.68609)
			(xy 51.945668 -96.67596) (xy 52.001402 -96.673923) (xy 52.056839 -96.680023) (xy 52.110796 -96.694129)
			(xy 52.162125 -96.715941) (xy 52.209731 -96.744995) (xy 52.252599 -96.78067) (xy 52.289816 -96.822207)
			(xy 52.320589 -96.86872) (xy 52.335721 -96.901) (xy 69.321932 -96.901) (xy 69.326003 -96.845378)
			(xy 69.338129 -96.790941) (xy 69.358052 -96.73885) (xy 69.385348 -96.690215) (xy 69.419434 -96.646072)
			(xy 69.459583 -96.607363) (xy 69.504941 -96.574912) (xy 69.554541 -96.549411) (xy 69.607325 -96.531404)
			(xy 69.662168 -96.521274) (xy 69.717902 -96.519237) (xy 69.773339 -96.525337) (xy 69.827296 -96.539443)
			(xy 69.878625 -96.561255) (xy 69.926231 -96.590309) (xy 69.969099 -96.625984) (xy 70.006316 -96.667521)
			(xy 70.037089 -96.714034) (xy 70.060761 -96.764531) (xy 70.076829 -96.817938) (xy 70.084949 -96.873114)
			(xy 70.085458 -96.901) (xy 70.084949 -96.928886) (xy 70.076829 -96.984062) (xy 70.060761 -97.037469)
			(xy 70.059604 -97.039938) (xy 74.725528 -97.039938) (xy 74.729599 -96.984316) (xy 74.741725 -96.929879)
			(xy 74.761648 -96.877788) (xy 74.788944 -96.829153) (xy 74.82303 -96.78501) (xy 74.863179 -96.746301)
			(xy 74.908537 -96.71385) (xy 74.958137 -96.688349) (xy 75.010921 -96.670342) (xy 75.065764 -96.660212)
			(xy 75.121498 -96.658175) (xy 75.176935 -96.664275) (xy 75.230892 -96.678381) (xy 75.282221 -96.700193)
			(xy 75.329827 -96.729247) (xy 75.372695 -96.764922) (xy 75.409912 -96.806459) (xy 75.440685 -96.852972)
			(xy 75.464357 -96.903469) (xy 75.480425 -96.956876) (xy 75.488545 -97.012052) (xy 75.489054 -97.039938)
			(xy 75.488545 -97.067824) (xy 75.480425 -97.123) (xy 75.464357 -97.176407) (xy 75.440685 -97.226904)
			(xy 75.409912 -97.273417) (xy 75.372695 -97.314954) (xy 75.329827 -97.350629) (xy 75.282221 -97.379683)
			(xy 75.230892 -97.401495) (xy 75.176935 -97.415601) (xy 75.121498 -97.421701) (xy 75.065764 -97.419664)
			(xy 75.010921 -97.409534) (xy 74.958137 -97.391527) (xy 74.908537 -97.366026) (xy 74.863179 -97.333575)
			(xy 74.82303 -97.294866) (xy 74.788944 -97.250723) (xy 74.761648 -97.202088) (xy 74.741725 -97.149997)
			(xy 74.729599 -97.09556) (xy 74.725528 -97.039938) (xy 70.059604 -97.039938) (xy 70.037089 -97.087966)
			(xy 70.006316 -97.134479) (xy 69.969099 -97.176016) (xy 69.926231 -97.211691) (xy 69.878625 -97.240745)
			(xy 69.827296 -97.262557) (xy 69.773339 -97.276663) (xy 69.717902 -97.282763) (xy 69.662168 -97.280726)
			(xy 69.607325 -97.270596) (xy 69.554541 -97.252589) (xy 69.504941 -97.227088) (xy 69.459583 -97.194637)
			(xy 69.419434 -97.155928) (xy 69.385348 -97.111785) (xy 69.358052 -97.06315) (xy 69.338129 -97.011059)
			(xy 69.326003 -96.956622) (xy 69.321932 -96.901) (xy 52.335721 -96.901) (xy 52.344261 -96.919217)
			(xy 52.360329 -96.972624) (xy 52.368449 -97.0278) (xy 52.368958 -97.055686) (xy 52.368449 -97.083572)
			(xy 52.360329 -97.138748) (xy 52.344261 -97.192155) (xy 52.320589 -97.242652) (xy 52.289816 -97.289165)
			(xy 52.252599 -97.330702) (xy 52.209731 -97.366377) (xy 52.162125 -97.395431) (xy 52.110796 -97.417243)
			(xy 52.056839 -97.431349) (xy 52.001402 -97.437449) (xy 51.945668 -97.435412) (xy 51.890825 -97.425282)
			(xy 51.838041 -97.407275) (xy 51.788441 -97.381774) (xy 51.743083 -97.349323) (xy 51.702934 -97.310614)
			(xy 51.668848 -97.266471) (xy 51.641552 -97.217836) (xy 51.621629 -97.165745) (xy 51.609503 -97.111308)
			(xy 51.605432 -97.055686) (xy 37.967842 -97.055686) (xy 37.980373 -97.097338) (xy 37.988493 -97.152514)
			(xy 37.989002 -97.1804) (xy 37.988493 -97.208286) (xy 37.980373 -97.263462) (xy 37.964305 -97.316869)
			(xy 37.940633 -97.367366) (xy 37.90986 -97.413879) (xy 37.872643 -97.455416) (xy 37.829775 -97.491091)
			(xy 37.782169 -97.520145) (xy 37.73084 -97.541957) (xy 37.676883 -97.556063) (xy 37.621446 -97.562163)
			(xy 37.565712 -97.560126) (xy 37.510869 -97.549996) (xy 37.458085 -97.531989) (xy 37.408485 -97.506488)
			(xy 37.363127 -97.474037) (xy 37.322978 -97.435328) (xy 37.288892 -97.391185) (xy 37.261596 -97.34255)
			(xy 37.241673 -97.290459) (xy 37.229547 -97.236022) (xy 37.225476 -97.1804) (xy 25.763249 -97.1804)
			(xy 25.749903 -97.20887) (xy 25.71913 -97.255383) (xy 25.681913 -97.29692) (xy 25.639045 -97.332595)
			(xy 25.591439 -97.361649) (xy 25.54011 -97.383461) (xy 25.486153 -97.397567) (xy 25.430716 -97.403667)
			(xy 25.374982 -97.40163) (xy 25.320139 -97.3915) (xy 25.267355 -97.373493) (xy 25.217755 -97.347992)
			(xy 25.172397 -97.315541) (xy 25.132248 -97.276832) (xy 25.098162 -97.232689) (xy 25.070866 -97.184054)
			(xy 25.050943 -97.131963) (xy 25.038817 -97.077526) (xy 25.034746 -97.021904) (xy 4.38404 -97.021904)
			(xy 4.38404 -97.64014) (xy 73.918062 -97.64014) (xy 73.922133 -97.584518) (xy 73.934259 -97.530081)
			(xy 73.954182 -97.47799) (xy 73.981478 -97.429355) (xy 74.015564 -97.385212) (xy 74.055713 -97.346503)
			(xy 74.101071 -97.314052) (xy 74.150671 -97.288551) (xy 74.203455 -97.270544) (xy 74.258298 -97.260414)
			(xy 74.314032 -97.258377) (xy 74.369469 -97.264477) (xy 74.423426 -97.278583) (xy 74.474755 -97.300395)
			(xy 74.522361 -97.329449) (xy 74.565229 -97.365124) (xy 74.602446 -97.406661) (xy 74.633219 -97.453174)
			(xy 74.656891 -97.503671) (xy 74.672959 -97.557078) (xy 74.681079 -97.612254) (xy 74.681588 -97.64014)
			(xy 74.681079 -97.668026) (xy 74.672959 -97.723202) (xy 74.656891 -97.776609) (xy 74.633219 -97.827106)
			(xy 74.602446 -97.873619) (xy 74.565229 -97.915156) (xy 74.522361 -97.950831) (xy 74.474755 -97.979885)
			(xy 74.423426 -98.001697) (xy 74.369469 -98.015803) (xy 74.314032 -98.021903) (xy 74.258298 -98.019866)
			(xy 74.203455 -98.009736) (xy 74.150671 -97.991729) (xy 74.101071 -97.966228) (xy 74.055713 -97.933777)
			(xy 74.015564 -97.895068) (xy 73.981478 -97.850925) (xy 73.954182 -97.80229) (xy 73.934259 -97.750199)
			(xy 73.922133 -97.695762) (xy 73.918062 -97.64014) (xy 4.38404 -97.64014) (xy 4.38404 -98.171) (xy 75.563982 -98.171)
			(xy 75.568053 -98.115378) (xy 75.580179 -98.060941) (xy 75.600102 -98.00885) (xy 75.627398 -97.960215)
			(xy 75.661484 -97.916072) (xy 75.701633 -97.877363) (xy 75.746991 -97.844912) (xy 75.796591 -97.819411)
			(xy 75.849375 -97.801404) (xy 75.904218 -97.791274) (xy 75.959952 -97.789237) (xy 76.015389 -97.795337)
			(xy 76.069346 -97.809443) (xy 76.120675 -97.831255) (xy 76.168281 -97.860309) (xy 76.211149 -97.895984)
			(xy 76.248366 -97.937521) (xy 76.258988 -97.953576) (xy 88.342976 -97.953576) (xy 88.347047 -97.897954)
			(xy 88.359173 -97.843517) (xy 88.379096 -97.791426) (xy 88.406392 -97.742791) (xy 88.440478 -97.698648)
			(xy 88.480627 -97.659939) (xy 88.525985 -97.627488) (xy 88.575585 -97.601987) (xy 88.628369 -97.58398)
			(xy 88.683212 -97.57385) (xy 88.738946 -97.571813) (xy 88.794383 -97.577913) (xy 88.84834 -97.592019)
			(xy 88.899669 -97.613831) (xy 88.947275 -97.642885) (xy 88.990143 -97.67856) (xy 89.02736 -97.720097)
			(xy 89.058133 -97.76661) (xy 89.081805 -97.817107) (xy 89.083049 -97.821242) (xy 89.657426 -97.821242)
			(xy 89.661497 -97.76562) (xy 89.673623 -97.711183) (xy 89.693546 -97.659092) (xy 89.720842 -97.610457)
			(xy 89.754928 -97.566314) (xy 89.795077 -97.527605) (xy 89.840435 -97.495154) (xy 89.890035 -97.469653)
			(xy 89.942819 -97.451646) (xy 89.997662 -97.441516) (xy 90.053396 -97.439479) (xy 90.108833 -97.445579)
			(xy 90.16279 -97.459685) (xy 90.214119 -97.481497) (xy 90.261725 -97.510551) (xy 90.304593 -97.546226)
			(xy 90.34181 -97.587763) (xy 90.372583 -97.634276) (xy 90.396255 -97.684773) (xy 90.412323 -97.73818)
			(xy 90.420443 -97.793356) (xy 90.420952 -97.821242) (xy 90.420443 -97.849128) (xy 90.412323 -97.904304)
			(xy 90.396255 -97.957711) (xy 90.372583 -98.008208) (xy 90.34181 -98.054721) (xy 90.304593 -98.096258)
			(xy 90.261725 -98.131933) (xy 90.214119 -98.160987) (xy 90.16279 -98.182799) (xy 90.108833 -98.196905)
			(xy 90.053396 -98.203005) (xy 89.997662 -98.200968) (xy 89.942819 -98.190838) (xy 89.890035 -98.172831)
			(xy 89.840435 -98.14733) (xy 89.795077 -98.114879) (xy 89.754928 -98.07617) (xy 89.720842 -98.032027)
			(xy 89.693546 -97.983392) (xy 89.673623 -97.931301) (xy 89.661497 -97.876864) (xy 89.657426 -97.821242)
			(xy 89.083049 -97.821242) (xy 89.097873 -97.870514) (xy 89.105993 -97.92569) (xy 89.106502 -97.953576)
			(xy 89.105993 -97.981462) (xy 89.097873 -98.036638) (xy 89.081805 -98.090045) (xy 89.058133 -98.140542)
			(xy 89.02736 -98.187055) (xy 88.990143 -98.228592) (xy 88.947275 -98.264267) (xy 88.899669 -98.293321)
			(xy 88.84834 -98.315133) (xy 88.794383 -98.329239) (xy 88.738946 -98.335339) (xy 88.683212 -98.333302)
			(xy 88.628369 -98.323172) (xy 88.575585 -98.305165) (xy 88.525985 -98.279664) (xy 88.480627 -98.247213)
			(xy 88.440478 -98.208504) (xy 88.406392 -98.164361) (xy 88.379096 -98.115726) (xy 88.359173 -98.063635)
			(xy 88.347047 -98.009198) (xy 88.342976 -97.953576) (xy 76.258988 -97.953576) (xy 76.279139 -97.984034)
			(xy 76.302811 -98.034531) (xy 76.318879 -98.087938) (xy 76.326999 -98.143114) (xy 76.327508 -98.171)
			(xy 76.326999 -98.198886) (xy 76.318879 -98.254062) (xy 76.302811 -98.307469) (xy 76.279139 -98.357966)
			(xy 76.248366 -98.404479) (xy 76.211149 -98.446016) (xy 76.168281 -98.481691) (xy 76.120675 -98.510745)
			(xy 76.069346 -98.532557) (xy 76.015389 -98.546663) (xy 75.959952 -98.552763) (xy 75.904218 -98.550726)
			(xy 75.849375 -98.540596) (xy 75.796591 -98.522589) (xy 75.746991 -98.497088) (xy 75.701633 -98.464637)
			(xy 75.661484 -98.425928) (xy 75.627398 -98.381785) (xy 75.600102 -98.33315) (xy 75.580179 -98.281059)
			(xy 75.568053 -98.226622) (xy 75.563982 -98.171) (xy 4.38404 -98.171) (xy 4.38404 -100.177854) (xy 37.31006 -100.177854)
			(xy 37.31006 -99.314254) (xy 37.31055 -99.284286) (xy 37.318373 -99.224864) (xy 37.333886 -99.166971)
			(xy 37.356822 -99.111598) (xy 37.386789 -99.059692) (xy 37.423276 -99.012142) (xy 37.465656 -98.969762)
			(xy 37.513206 -98.933275) (xy 37.565112 -98.903308) (xy 37.620485 -98.880372) (xy 37.678378 -98.864859)
			(xy 37.7378 -98.857036) (xy 37.797736 -98.857036) (xy 37.857158 -98.864859) (xy 37.915051 -98.880372)
			(xy 37.970424 -98.903308) (xy 38.02233 -98.933275) (xy 38.06988 -98.969762) (xy 38.11226 -99.012142)
			(xy 38.148747 -99.059692) (xy 38.178714 -99.111598) (xy 38.20165 -99.166971) (xy 38.217163 -99.224864)
			(xy 38.224986 -99.284286) (xy 38.225476 -99.314254) (xy 38.225476 -100.17633) (xy 53.639212 -100.17633)
			(xy 53.639212 -99.31273) (xy 53.639702 -99.282762) (xy 53.647525 -99.22334) (xy 53.663038 -99.165447)
			(xy 53.685974 -99.110074) (xy 53.715941 -99.058168) (xy 53.752428 -99.010618) (xy 53.794808 -98.968238)
			(xy 53.842358 -98.931751) (xy 53.894264 -98.901784) (xy 53.949637 -98.878848) (xy 54.00753 -98.863335)
			(xy 54.066952 -98.855512) (xy 54.126888 -98.855512) (xy 54.18631 -98.863335) (xy 54.244203 -98.878848)
			(xy 54.299576 -98.901784) (xy 54.351482 -98.931751) (xy 54.399032 -98.968238) (xy 54.441412 -99.010618)
			(xy 54.477899 -99.058168) (xy 54.507866 -99.110074) (xy 54.530802 -99.165447) (xy 54.546315 -99.22334)
			(xy 54.554138 -99.282762) (xy 54.554628 -99.31273) (xy 54.554628 -99.439984) (xy 75.309982 -99.439984)
			(xy 75.314053 -99.384362) (xy 75.326179 -99.329925) (xy 75.346102 -99.277834) (xy 75.373398 -99.229199)
			(xy 75.407484 -99.185056) (xy 75.447633 -99.146347) (xy 75.492991 -99.113896) (xy 75.542591 -99.088395)
			(xy 75.595375 -99.070388) (xy 75.650218 -99.060258) (xy 75.705952 -99.058221) (xy 75.761389 -99.064321)
			(xy 75.815346 -99.078427) (xy 75.866675 -99.100239) (xy 75.914281 -99.129293) (xy 75.957149 -99.164968)
			(xy 75.994366 -99.206505) (xy 76.025139 -99.253018) (xy 76.048811 -99.303515) (xy 76.064879 -99.356922)
			(xy 76.072999 -99.412098) (xy 76.073508 -99.439984) (xy 76.073336 -99.449382) (xy 87.906096 -99.449382)
			(xy 87.910167 -99.39376) (xy 87.922293 -99.339323) (xy 87.942216 -99.287232) (xy 87.969512 -99.238597)
			(xy 88.003598 -99.194454) (xy 88.043747 -99.155745) (xy 88.089105 -99.123294) (xy 88.138705 -99.097793)
			(xy 88.191489 -99.079786) (xy 88.246332 -99.069656) (xy 88.302066 -99.067619) (xy 88.357503 -99.073719)
			(xy 88.41146 -99.087825) (xy 88.462789 -99.109637) (xy 88.510395 -99.138691) (xy 88.553263 -99.174366)
			(xy 88.59048 -99.215903) (xy 88.621253 -99.262416) (xy 88.644925 -99.312913) (xy 88.660993 -99.36632)
			(xy 88.669113 -99.421496) (xy 88.669622 -99.449382) (xy 88.669113 -99.477268) (xy 88.660993 -99.532444)
			(xy 88.644925 -99.585851) (xy 88.621253 -99.636348) (xy 88.59048 -99.682861) (xy 88.553263 -99.724398)
			(xy 88.510395 -99.760073) (xy 88.462789 -99.789127) (xy 88.41146 -99.810939) (xy 88.357503 -99.825045)
			(xy 88.302066 -99.831145) (xy 88.246332 -99.829108) (xy 88.191489 -99.818978) (xy 88.138705 -99.800971)
			(xy 88.089105 -99.77547) (xy 88.043747 -99.743019) (xy 88.003598 -99.70431) (xy 87.969512 -99.660167)
			(xy 87.942216 -99.611532) (xy 87.922293 -99.559441) (xy 87.910167 -99.505004) (xy 87.906096 -99.449382)
			(xy 76.073336 -99.449382) (xy 76.072999 -99.46787) (xy 76.064879 -99.523046) (xy 76.048811 -99.576453)
			(xy 76.025139 -99.62695) (xy 75.994366 -99.673463) (xy 75.957149 -99.715) (xy 75.914281 -99.750675)
			(xy 75.866675 -99.779729) (xy 75.815346 -99.801541) (xy 75.761389 -99.815647) (xy 75.705952 -99.821747)
			(xy 75.650218 -99.81971) (xy 75.595375 -99.80958) (xy 75.542591 -99.791573) (xy 75.492991 -99.766072)
			(xy 75.447633 -99.733621) (xy 75.407484 -99.694912) (xy 75.373398 -99.650769) (xy 75.346102 -99.602134)
			(xy 75.326179 -99.550043) (xy 75.314053 -99.495606) (xy 75.309982 -99.439984) (xy 54.554628 -99.439984)
			(xy 54.554628 -100.17633) (xy 54.554138 -100.206298) (xy 54.546315 -100.26572) (xy 54.530802 -100.323613)
			(xy 54.519319 -100.351336) (xy 70.122032 -100.351336) (xy 70.126103 -100.295714) (xy 70.138229 -100.241277)
			(xy 70.158152 -100.189186) (xy 70.185448 -100.140551) (xy 70.219534 -100.096408) (xy 70.259683 -100.057699)
			(xy 70.305041 -100.025248) (xy 70.354641 -99.999747) (xy 70.407425 -99.98174) (xy 70.462268 -99.97161)
			(xy 70.518002 -99.969573) (xy 70.573439 -99.975673) (xy 70.627396 -99.989779) (xy 70.678725 -100.011591)
			(xy 70.725163 -100.039932) (xy 73.876914 -100.039932) (xy 73.880985 -99.98431) (xy 73.893111 -99.929873)
			(xy 73.913034 -99.877782) (xy 73.94033 -99.829147) (xy 73.974416 -99.785004) (xy 74.014565 -99.746295)
			(xy 74.059923 -99.713844) (xy 74.109523 -99.688343) (xy 74.162307 -99.670336) (xy 74.21715 -99.660206)
			(xy 74.272884 -99.658169) (xy 74.328321 -99.664269) (xy 74.382278 -99.678375) (xy 74.433607 -99.700187)
			(xy 74.481213 -99.729241) (xy 74.524081 -99.764916) (xy 74.561298 -99.806453) (xy 74.592071 -99.852966)
			(xy 74.615743 -99.903463) (xy 74.631811 -99.95687) (xy 74.639931 -100.012046) (xy 74.64044 -100.039932)
			(xy 74.639931 -100.067818) (xy 74.631811 -100.122994) (xy 74.615743 -100.176401) (xy 74.592071 -100.226898)
			(xy 74.561298 -100.273411) (xy 74.524081 -100.314948) (xy 74.481213 -100.350623) (xy 74.433607 -100.379677)
			(xy 74.382278 -100.401489) (xy 74.328321 -100.415595) (xy 74.272884 -100.421695) (xy 74.21715 -100.419658)
			(xy 74.162307 -100.409528) (xy 74.109523 -100.391521) (xy 74.059923 -100.36602) (xy 74.014565 -100.333569)
			(xy 73.974416 -100.29486) (xy 73.94033 -100.250717) (xy 73.913034 -100.202082) (xy 73.893111 -100.149991)
			(xy 73.880985 -100.095554) (xy 73.876914 -100.039932) (xy 70.725163 -100.039932) (xy 70.726331 -100.040645)
			(xy 70.769199 -100.07632) (xy 70.806416 -100.117857) (xy 70.837189 -100.16437) (xy 70.860861 -100.214867)
			(xy 70.876929 -100.268274) (xy 70.885049 -100.32345) (xy 70.885558 -100.351336) (xy 70.885049 -100.379222)
			(xy 70.876929 -100.434398) (xy 70.860861 -100.487805) (xy 70.837189 -100.538302) (xy 70.806416 -100.584815)
			(xy 70.769199 -100.626352) (xy 70.726331 -100.662027) (xy 70.678725 -100.691081) (xy 70.627396 -100.712893)
			(xy 70.573439 -100.726999) (xy 70.518002 -100.733099) (xy 70.462268 -100.731062) (xy 70.407425 -100.720932)
			(xy 70.354641 -100.702925) (xy 70.305041 -100.677424) (xy 70.259683 -100.644973) (xy 70.219534 -100.606264)
			(xy 70.185448 -100.562121) (xy 70.158152 -100.513486) (xy 70.138229 -100.461395) (xy 70.126103 -100.406958)
			(xy 70.122032 -100.351336) (xy 54.519319 -100.351336) (xy 54.507866 -100.378986) (xy 54.477899 -100.430892)
			(xy 54.441412 -100.478442) (xy 54.399032 -100.520822) (xy 54.351482 -100.557309) (xy 54.299576 -100.587276)
			(xy 54.244203 -100.610212) (xy 54.18631 -100.625725) (xy 54.126888 -100.633548) (xy 54.066952 -100.633548)
			(xy 54.00753 -100.625725) (xy 53.949637 -100.610212) (xy 53.894264 -100.587276) (xy 53.842358 -100.557309)
			(xy 53.794808 -100.520822) (xy 53.752428 -100.478442) (xy 53.715941 -100.430892) (xy 53.685974 -100.378986)
			(xy 53.663038 -100.323613) (xy 53.647525 -100.26572) (xy 53.639702 -100.206298) (xy 53.639212 -100.17633)
			(xy 38.225476 -100.17633) (xy 38.225476 -100.177854) (xy 38.224986 -100.207822) (xy 38.217163 -100.267244)
			(xy 38.20165 -100.325137) (xy 38.178714 -100.38051) (xy 38.148747 -100.432416) (xy 38.11226 -100.479966)
			(xy 38.06988 -100.522346) (xy 38.02233 -100.558833) (xy 37.970424 -100.5888) (xy 37.915051 -100.611736)
			(xy 37.857158 -100.627249) (xy 37.797736 -100.635072) (xy 37.7378 -100.635072) (xy 37.678378 -100.627249)
			(xy 37.620485 -100.611736) (xy 37.565112 -100.5888) (xy 37.513206 -100.558833) (xy 37.465656 -100.522346)
			(xy 37.423276 -100.479966) (xy 37.386789 -100.432416) (xy 37.356822 -100.38051) (xy 37.333886 -100.325137)
			(xy 37.318373 -100.267244) (xy 37.31055 -100.207822) (xy 37.31006 -100.177854) (xy 4.38404 -100.177854)
			(xy 4.38404 -101.984302) (xy 35.277552 -101.984302) (xy 35.277552 -101.120702) (xy 35.278042 -101.090734)
			(xy 35.285865 -101.031312) (xy 35.301378 -100.973419) (xy 35.324314 -100.918046) (xy 35.354281 -100.86614)
			(xy 35.390768 -100.81859) (xy 35.433148 -100.77621) (xy 35.480698 -100.739723) (xy 35.532604 -100.709756)
			(xy 35.587977 -100.68682) (xy 35.64587 -100.671307) (xy 35.705292 -100.663484) (xy 35.765228 -100.663484)
			(xy 35.82465 -100.671307) (xy 35.882543 -100.68682) (xy 35.937916 -100.709756) (xy 35.989822 -100.739723)
			(xy 36.037372 -100.77621) (xy 36.079752 -100.81859) (xy 36.116239 -100.86614) (xy 36.146206 -100.918046)
			(xy 36.169142 -100.973419) (xy 36.184655 -101.031312) (xy 36.192478 -101.090734) (xy 36.192968 -101.120702)
			(xy 36.192968 -101.976428) (xy 51.785012 -101.976428) (xy 51.785012 -101.112828) (xy 51.785502 -101.08286)
			(xy 51.793325 -101.023438) (xy 51.808838 -100.965545) (xy 51.831774 -100.910172) (xy 51.861741 -100.858266)
			(xy 51.898228 -100.810716) (xy 51.940608 -100.768336) (xy 51.988158 -100.731849) (xy 52.040064 -100.701882)
			(xy 52.095437 -100.678946) (xy 52.15333 -100.663433) (xy 52.212752 -100.65561) (xy 52.272688 -100.65561)
			(xy 52.33211 -100.663433) (xy 52.390003 -100.678946) (xy 52.445376 -100.701882) (xy 52.497282 -100.731849)
			(xy 52.542273 -100.766372) (xy 57.5978 -100.766372) (xy 57.601871 -100.71075) (xy 57.613997 -100.656313)
			(xy 57.63392 -100.604222) (xy 57.661216 -100.555587) (xy 57.695302 -100.511444) (xy 57.735451 -100.472735)
			(xy 57.780809 -100.440284) (xy 57.830409 -100.414783) (xy 57.883193 -100.396776) (xy 57.938036 -100.386646)
			(xy 57.99377 -100.384609) (xy 58.049207 -100.390709) (xy 58.103164 -100.404815) (xy 58.154493 -100.426627)
			(xy 58.202099 -100.455681) (xy 58.244967 -100.491356) (xy 58.282184 -100.532893) (xy 58.312957 -100.579406)
			(xy 58.336629 -100.629903) (xy 58.352697 -100.68331) (xy 58.360817 -100.738486) (xy 58.361326 -100.766372)
			(xy 58.360817 -100.794258) (xy 58.352697 -100.849434) (xy 58.336629 -100.902841) (xy 58.312957 -100.953338)
			(xy 58.282184 -100.999851) (xy 58.244967 -101.041388) (xy 58.202099 -101.077063) (xy 58.154493 -101.106117)
			(xy 58.103164 -101.127929) (xy 58.049207 -101.142035) (xy 57.99377 -101.148135) (xy 57.938036 -101.146098)
			(xy 57.883193 -101.135968) (xy 57.830409 -101.117961) (xy 57.780809 -101.09246) (xy 57.735451 -101.060009)
			(xy 57.695302 -101.0213) (xy 57.661216 -100.977157) (xy 57.63392 -100.928522) (xy 57.613997 -100.876431)
			(xy 57.601871 -100.821994) (xy 57.5978 -100.766372) (xy 52.542273 -100.766372) (xy 52.544832 -100.768336)
			(xy 52.587212 -100.810716) (xy 52.623699 -100.858266) (xy 52.653666 -100.910172) (xy 52.676602 -100.965545)
			(xy 52.692115 -101.023438) (xy 52.699938 -101.08286) (xy 52.700428 -101.112828) (xy 52.700428 -101.240082)
			(xy 74.293982 -101.240082) (xy 74.298053 -101.18446) (xy 74.310179 -101.130023) (xy 74.330102 -101.077932)
			(xy 74.357398 -101.029297) (xy 74.391484 -100.985154) (xy 74.431633 -100.946445) (xy 74.476991 -100.913994)
			(xy 74.526591 -100.888493) (xy 74.579375 -100.870486) (xy 74.634218 -100.860356) (xy 74.689952 -100.858319)
			(xy 74.745389 -100.864419) (xy 74.799346 -100.878525) (xy 74.850675 -100.900337) (xy 74.898281 -100.929391)
			(xy 74.941149 -100.965066) (xy 74.978366 -101.006603) (xy 75.009139 -101.053116) (xy 75.016889 -101.069648)
			(xy 75.586334 -101.069648) (xy 75.590405 -101.014026) (xy 75.602531 -100.959589) (xy 75.622454 -100.907498)
			(xy 75.64975 -100.858863) (xy 75.683836 -100.81472) (xy 75.723985 -100.776011) (xy 75.769343 -100.74356)
			(xy 75.818943 -100.718059) (xy 75.871727 -100.700052) (xy 75.92657 -100.689922) (xy 75.982304 -100.687885)
			(xy 76.037741 -100.693985) (xy 76.091698 -100.708091) (xy 76.143027 -100.729903) (xy 76.190633 -100.758957)
			(xy 76.233501 -100.794632) (xy 76.270718 -100.836169) (xy 76.301491 -100.882682) (xy 76.325163 -100.933179)
			(xy 76.341231 -100.986586) (xy 76.349351 -101.041762) (xy 76.34986 -101.069648) (xy 76.349351 -101.097534)
			(xy 76.341231 -101.15271) (xy 76.325163 -101.206117) (xy 76.301491 -101.256614) (xy 76.270718 -101.303127)
			(xy 76.233501 -101.344664) (xy 76.190633 -101.380339) (xy 76.143027 -101.409393) (xy 76.091698 -101.431205)
			(xy 76.037741 -101.445311) (xy 75.982304 -101.451411) (xy 75.92657 -101.449374) (xy 75.871727 -101.439244)
			(xy 75.818943 -101.421237) (xy 75.769343 -101.395736) (xy 75.723985 -101.363285) (xy 75.683836 -101.324576)
			(xy 75.64975 -101.280433) (xy 75.622454 -101.231798) (xy 75.602531 -101.179707) (xy 75.590405 -101.12527)
			(xy 75.586334 -101.069648) (xy 75.016889 -101.069648) (xy 75.032811 -101.103613) (xy 75.048879 -101.15702)
			(xy 75.056999 -101.212196) (xy 75.057508 -101.240082) (xy 75.056999 -101.267968) (xy 75.048879 -101.323144)
			(xy 75.032811 -101.376551) (xy 75.009139 -101.427048) (xy 74.978366 -101.473561) (xy 74.941149 -101.515098)
			(xy 74.898281 -101.550773) (xy 74.851748 -101.579172) (xy 87.770714 -101.579172) (xy 87.774785 -101.52355)
			(xy 87.786911 -101.469113) (xy 87.806834 -101.417022) (xy 87.83413 -101.368387) (xy 87.868216 -101.324244)
			(xy 87.908365 -101.285535) (xy 87.953723 -101.253084) (xy 88.003323 -101.227583) (xy 88.056107 -101.209576)
			(xy 88.11095 -101.199446) (xy 88.166684 -101.197409) (xy 88.222121 -101.203509) (xy 88.276078 -101.217615)
			(xy 88.327407 -101.239427) (xy 88.375013 -101.268481) (xy 88.417881 -101.304156) (xy 88.455098 -101.345693)
			(xy 88.485871 -101.392206) (xy 88.509543 -101.442703) (xy 88.525611 -101.49611) (xy 88.533731 -101.551286)
			(xy 88.53424 -101.579172) (xy 88.533731 -101.607058) (xy 88.525611 -101.662234) (xy 88.509543 -101.715641)
			(xy 88.485871 -101.766138) (xy 88.455098 -101.812651) (xy 88.417881 -101.854188) (xy 88.375013 -101.889863)
			(xy 88.327407 -101.918917) (xy 88.276078 -101.940729) (xy 88.222121 -101.954835) (xy 88.166684 -101.960935)
			(xy 88.11095 -101.958898) (xy 88.056107 -101.948768) (xy 88.003323 -101.930761) (xy 87.953723 -101.90526)
			(xy 87.908365 -101.872809) (xy 87.868216 -101.8341) (xy 87.83413 -101.789957) (xy 87.806834 -101.741322)
			(xy 87.786911 -101.689231) (xy 87.774785 -101.634794) (xy 87.770714 -101.579172) (xy 74.851748 -101.579172)
			(xy 74.850675 -101.579827) (xy 74.799346 -101.601639) (xy 74.745389 -101.615745) (xy 74.689952 -101.621845)
			(xy 74.634218 -101.619808) (xy 74.579375 -101.609678) (xy 74.526591 -101.591671) (xy 74.476991 -101.56617)
			(xy 74.431633 -101.533719) (xy 74.391484 -101.49501) (xy 74.357398 -101.450867) (xy 74.330102 -101.402232)
			(xy 74.310179 -101.350141) (xy 74.298053 -101.295704) (xy 74.293982 -101.240082) (xy 52.700428 -101.240082)
			(xy 52.700428 -101.976428) (xy 52.699938 -102.006396) (xy 52.692115 -102.065818) (xy 52.676602 -102.123711)
			(xy 52.653666 -102.179084) (xy 52.623699 -102.23099) (xy 52.587212 -102.27854) (xy 52.544832 -102.32092)
			(xy 52.497282 -102.357407) (xy 52.445376 -102.387374) (xy 52.390003 -102.41031) (xy 52.33211 -102.425823)
			(xy 52.272688 -102.433646) (xy 52.212752 -102.433646) (xy 52.15333 -102.425823) (xy 52.095437 -102.41031)
			(xy 52.040064 -102.387374) (xy 51.988158 -102.357407) (xy 51.940608 -102.32092) (xy 51.898228 -102.27854)
			(xy 51.861741 -102.23099) (xy 51.831774 -102.179084) (xy 51.808838 -102.123711) (xy 51.793325 -102.065818)
			(xy 51.785502 -102.006396) (xy 51.785012 -101.976428) (xy 36.192968 -101.976428) (xy 36.192968 -101.984302)
			(xy 36.192478 -102.01427) (xy 36.184655 -102.073692) (xy 36.169142 -102.131585) (xy 36.146206 -102.186958)
			(xy 36.116239 -102.238864) (xy 36.079752 -102.286414) (xy 36.037372 -102.328794) (xy 35.989822 -102.365281)
			(xy 35.937916 -102.395248) (xy 35.882543 -102.418184) (xy 35.82465 -102.433697) (xy 35.765228 -102.44152)
			(xy 35.705292 -102.44152) (xy 35.64587 -102.433697) (xy 35.587977 -102.418184) (xy 35.532604 -102.395248)
			(xy 35.480698 -102.365281) (xy 35.433148 -102.328794) (xy 35.390768 -102.286414) (xy 35.354281 -102.238864)
			(xy 35.324314 -102.186958) (xy 35.301378 -102.131585) (xy 35.285865 -102.073692) (xy 35.278042 -102.01427)
			(xy 35.277552 -101.984302) (xy 4.38404 -101.984302) (xy 4.38404 -103.777796) (xy 37.31006 -103.777796)
			(xy 37.31006 -102.914196) (xy 37.31055 -102.884228) (xy 37.318373 -102.824806) (xy 37.333886 -102.766913)
			(xy 37.356822 -102.71154) (xy 37.386789 -102.659634) (xy 37.423276 -102.612084) (xy 37.465656 -102.569704)
			(xy 37.513206 -102.533217) (xy 37.565112 -102.50325) (xy 37.620485 -102.480314) (xy 37.678378 -102.464801)
			(xy 37.7378 -102.456978) (xy 37.797736 -102.456978) (xy 37.857158 -102.464801) (xy 37.915051 -102.480314)
			(xy 37.970424 -102.50325) (xy 38.02233 -102.533217) (xy 38.06988 -102.569704) (xy 38.11226 -102.612084)
			(xy 38.148747 -102.659634) (xy 38.178714 -102.71154) (xy 38.20165 -102.766913) (xy 38.217163 -102.824806)
			(xy 38.224986 -102.884228) (xy 38.225476 -102.914196) (xy 38.225476 -103.776272) (xy 53.639212 -103.776272)
			(xy 53.639212 -102.912672) (xy 53.639702 -102.882704) (xy 53.647525 -102.823282) (xy 53.663038 -102.765389)
			(xy 53.685974 -102.710016) (xy 53.715941 -102.65811) (xy 53.752428 -102.61056) (xy 53.794808 -102.56818)
			(xy 53.842358 -102.531693) (xy 53.894264 -102.501726) (xy 53.949637 -102.47879) (xy 54.00753 -102.463277)
			(xy 54.066952 -102.455454) (xy 54.126888 -102.455454) (xy 54.18631 -102.463277) (xy 54.244203 -102.47879)
			(xy 54.268852 -102.489) (xy 74.801982 -102.489) (xy 74.806053 -102.433378) (xy 74.818179 -102.378941)
			(xy 74.838102 -102.32685) (xy 74.865398 -102.278215) (xy 74.899484 -102.234072) (xy 74.939633 -102.195363)
			(xy 74.984991 -102.162912) (xy 75.034591 -102.137411) (xy 75.087375 -102.119404) (xy 75.142218 -102.109274)
			(xy 75.197952 -102.107237) (xy 75.253389 -102.113337) (xy 75.307346 -102.127443) (xy 75.358675 -102.149255)
			(xy 75.406281 -102.178309) (xy 75.449149 -102.213984) (xy 75.486366 -102.255521) (xy 75.517139 -102.302034)
			(xy 75.540811 -102.352531) (xy 75.556879 -102.405938) (xy 75.564999 -102.461114) (xy 75.565508 -102.489)
			(xy 75.564999 -102.516886) (xy 75.556879 -102.572062) (xy 75.540811 -102.625469) (xy 75.517139 -102.675966)
			(xy 75.486366 -102.722479) (xy 75.449149 -102.764016) (xy 75.406281 -102.799691) (xy 75.358675 -102.828745)
			(xy 75.307346 -102.850557) (xy 75.253389 -102.864663) (xy 75.197952 -102.870763) (xy 75.142218 -102.868726)
			(xy 75.087375 -102.858596) (xy 75.034591 -102.840589) (xy 74.984991 -102.815088) (xy 74.939633 -102.782637)
			(xy 74.899484 -102.743928) (xy 74.865398 -102.699785) (xy 74.838102 -102.65115) (xy 74.818179 -102.599059)
			(xy 74.806053 -102.544622) (xy 74.801982 -102.489) (xy 54.268852 -102.489) (xy 54.299576 -102.501726)
			(xy 54.351482 -102.531693) (xy 54.399032 -102.56818) (xy 54.441412 -102.61056) (xy 54.477899 -102.65811)
			(xy 54.507866 -102.710016) (xy 54.530802 -102.765389) (xy 54.546315 -102.823282) (xy 54.554138 -102.882704)
			(xy 54.554628 -102.912672) (xy 54.554628 -103.13924) (xy 89.507058 -103.13924) (xy 89.511129 -103.083618)
			(xy 89.523255 -103.029181) (xy 89.543178 -102.97709) (xy 89.570474 -102.928455) (xy 89.60456 -102.884312)
			(xy 89.644709 -102.845603) (xy 89.690067 -102.813152) (xy 89.739667 -102.787651) (xy 89.792451 -102.769644)
			(xy 89.847294 -102.759514) (xy 89.903028 -102.757477) (xy 89.958465 -102.763577) (xy 90.012422 -102.777683)
			(xy 90.063751 -102.799495) (xy 90.111357 -102.828549) (xy 90.154225 -102.864224) (xy 90.191442 -102.905761)
			(xy 90.222215 -102.952274) (xy 90.245887 -103.002771) (xy 90.261955 -103.056178) (xy 90.270075 -103.111354)
			(xy 90.270584 -103.13924) (xy 90.270075 -103.167126) (xy 90.261955 -103.222302) (xy 90.245887 -103.275709)
			(xy 90.222215 -103.326206) (xy 90.191442 -103.372719) (xy 90.154225 -103.414256) (xy 90.111357 -103.449931)
			(xy 90.063751 -103.478985) (xy 90.012422 -103.500797) (xy 89.958465 -103.514903) (xy 89.903028 -103.521003)
			(xy 89.847294 -103.518966) (xy 89.792451 -103.508836) (xy 89.739667 -103.490829) (xy 89.690067 -103.465328)
			(xy 89.644709 -103.432877) (xy 89.60456 -103.394168) (xy 89.570474 -103.350025) (xy 89.543178 -103.30139)
			(xy 89.523255 -103.249299) (xy 89.511129 -103.194862) (xy 89.507058 -103.13924) (xy 54.554628 -103.13924)
			(xy 54.554628 -103.776272) (xy 54.554138 -103.80624) (xy 54.546315 -103.865662) (xy 54.540865 -103.886)
			(xy 75.309982 -103.886) (xy 75.314053 -103.830378) (xy 75.326179 -103.775941) (xy 75.346102 -103.72385)
			(xy 75.373398 -103.675215) (xy 75.407484 -103.631072) (xy 75.447633 -103.592363) (xy 75.492991 -103.559912)
			(xy 75.542591 -103.534411) (xy 75.595375 -103.516404) (xy 75.650218 -103.506274) (xy 75.705952 -103.504237)
			(xy 75.761389 -103.510337) (xy 75.815346 -103.524443) (xy 75.866675 -103.546255) (xy 75.914281 -103.575309)
			(xy 75.957149 -103.610984) (xy 75.994366 -103.652521) (xy 76.025139 -103.699034) (xy 76.048811 -103.749531)
			(xy 76.064879 -103.802938) (xy 76.072999 -103.858114) (xy 76.073508 -103.886) (xy 76.072999 -103.913886)
			(xy 76.064879 -103.969062) (xy 76.048811 -104.022469) (xy 76.025139 -104.072966) (xy 75.994366 -104.119479)
			(xy 75.957149 -104.161016) (xy 75.914281 -104.196691) (xy 75.866675 -104.225745) (xy 75.815346 -104.247557)
			(xy 75.761389 -104.261663) (xy 75.705952 -104.267763) (xy 75.650218 -104.265726) (xy 75.595375 -104.255596)
			(xy 75.542591 -104.237589) (xy 75.492991 -104.212088) (xy 75.447633 -104.179637) (xy 75.407484 -104.140928)
			(xy 75.373398 -104.096785) (xy 75.346102 -104.04815) (xy 75.326179 -103.996059) (xy 75.314053 -103.941622)
			(xy 75.309982 -103.886) (xy 54.540865 -103.886) (xy 54.530802 -103.923555) (xy 54.507866 -103.978928)
			(xy 54.477899 -104.030834) (xy 54.441412 -104.078384) (xy 54.399032 -104.120764) (xy 54.351482 -104.157251)
			(xy 54.299576 -104.187218) (xy 54.244203 -104.210154) (xy 54.18631 -104.225667) (xy 54.126888 -104.23349)
			(xy 54.066952 -104.23349) (xy 54.00753 -104.225667) (xy 53.949637 -104.210154) (xy 53.894264 -104.187218)
			(xy 53.842358 -104.157251) (xy 53.794808 -104.120764) (xy 53.752428 -104.078384) (xy 53.715941 -104.030834)
			(xy 53.685974 -103.978928) (xy 53.663038 -103.923555) (xy 53.647525 -103.865662) (xy 53.639702 -103.80624)
			(xy 53.639212 -103.776272) (xy 38.225476 -103.776272) (xy 38.225476 -103.777796) (xy 38.224986 -103.807764)
			(xy 38.217163 -103.867186) (xy 38.20165 -103.925079) (xy 38.178714 -103.980452) (xy 38.148747 -104.032358)
			(xy 38.11226 -104.079908) (xy 38.06988 -104.122288) (xy 38.02233 -104.158775) (xy 37.970424 -104.188742)
			(xy 37.915051 -104.211678) (xy 37.857158 -104.227191) (xy 37.797736 -104.235014) (xy 37.7378 -104.235014)
			(xy 37.678378 -104.227191) (xy 37.620485 -104.211678) (xy 37.565112 -104.188742) (xy 37.513206 -104.158775)
			(xy 37.465656 -104.122288) (xy 37.423276 -104.079908) (xy 37.386789 -104.032358) (xy 37.356822 -103.980452)
			(xy 37.333886 -103.925079) (xy 37.318373 -103.867186) (xy 37.31055 -103.807764) (xy 37.31006 -103.777796)
			(xy 4.38404 -103.777796) (xy 4.38404 -105.584498) (xy 34.667952 -105.584498) (xy 34.667952 -104.720898)
			(xy 34.668442 -104.69093) (xy 34.676265 -104.631508) (xy 34.691778 -104.573615) (xy 34.714714 -104.518242)
			(xy 34.744681 -104.466336) (xy 34.781168 -104.418786) (xy 34.823548 -104.376406) (xy 34.871098 -104.339919)
			(xy 34.923004 -104.309952) (xy 34.978377 -104.287016) (xy 35.03627 -104.271503) (xy 35.095692 -104.26368)
			(xy 35.155628 -104.26368) (xy 35.21505 -104.271503) (xy 35.272943 -104.287016) (xy 35.328316 -104.309952)
			(xy 35.380222 -104.339919) (xy 35.427772 -104.376406) (xy 35.470152 -104.418786) (xy 35.506639 -104.466336)
			(xy 35.536606 -104.518242) (xy 35.559542 -104.573615) (xy 35.575055 -104.631508) (xy 35.582878 -104.69093)
			(xy 35.583368 -104.720898) (xy 35.583368 -105.57637) (xy 51.785012 -105.57637) (xy 51.785012 -104.71277)
			(xy 51.785502 -104.682802) (xy 51.793325 -104.62338) (xy 51.808838 -104.565487) (xy 51.831774 -104.510114)
			(xy 51.861741 -104.458208) (xy 51.898228 -104.410658) (xy 51.940608 -104.368278) (xy 51.988158 -104.331791)
			(xy 52.040064 -104.301824) (xy 52.095437 -104.278888) (xy 52.15333 -104.263375) (xy 52.212752 -104.255552)
			(xy 52.272688 -104.255552) (xy 52.33211 -104.263375) (xy 52.390003 -104.278888) (xy 52.445376 -104.301824)
			(xy 52.497282 -104.331791) (xy 52.544832 -104.368278) (xy 52.587212 -104.410658) (xy 52.623699 -104.458208)
			(xy 52.653666 -104.510114) (xy 52.676602 -104.565487) (xy 52.692115 -104.62338) (xy 52.698901 -104.674924)
			(xy 88.559384 -104.674924) (xy 88.563455 -104.619302) (xy 88.575581 -104.564865) (xy 88.595504 -104.512774)
			(xy 88.6228 -104.464139) (xy 88.656886 -104.419996) (xy 88.697035 -104.381287) (xy 88.742393 -104.348836)
			(xy 88.791993 -104.323335) (xy 88.844777 -104.305328) (xy 88.89962 -104.295198) (xy 88.955354 -104.293161)
			(xy 89.010791 -104.299261) (xy 89.064748 -104.313367) (xy 89.116077 -104.335179) (xy 89.163683 -104.364233)
			(xy 89.206551 -104.399908) (xy 89.243768 -104.441445) (xy 89.274541 -104.487958) (xy 89.298213 -104.538455)
			(xy 89.314281 -104.591862) (xy 89.322401 -104.647038) (xy 89.32291 -104.674924) (xy 89.322401 -104.70281)
			(xy 89.314281 -104.757986) (xy 89.298213 -104.811393) (xy 89.274541 -104.86189) (xy 89.243768 -104.908403)
			(xy 89.206551 -104.94994) (xy 89.163683 -104.985615) (xy 89.116077 -105.014669) (xy 89.064748 -105.036481)
			(xy 89.010791 -105.050587) (xy 88.955354 -105.056687) (xy 88.89962 -105.05465) (xy 88.844777 -105.04452)
			(xy 88.791993 -105.026513) (xy 88.742393 -105.001012) (xy 88.697035 -104.968561) (xy 88.656886 -104.929852)
			(xy 88.6228 -104.885709) (xy 88.595504 -104.837074) (xy 88.575581 -104.784983) (xy 88.563455 -104.730546)
			(xy 88.559384 -104.674924) (xy 52.698901 -104.674924) (xy 52.699938 -104.682802) (xy 52.700428 -104.71277)
			(xy 52.700428 -105.57637) (xy 52.699938 -105.606338) (xy 52.692115 -105.66576) (xy 52.676602 -105.723653)
			(xy 52.653666 -105.779026) (xy 52.623699 -105.830932) (xy 52.587212 -105.878482) (xy 52.544832 -105.920862)
			(xy 52.497282 -105.957349) (xy 52.445376 -105.987316) (xy 52.390003 -106.010252) (xy 52.33211 -106.025765)
			(xy 52.272688 -106.033588) (xy 52.212752 -106.033588) (xy 52.15333 -106.025765) (xy 52.095437 -106.010252)
			(xy 52.040064 -105.987316) (xy 51.988158 -105.957349) (xy 51.940608 -105.920862) (xy 51.898228 -105.878482)
			(xy 51.861741 -105.830932) (xy 51.831774 -105.779026) (xy 51.808838 -105.723653) (xy 51.793325 -105.66576)
			(xy 51.785502 -105.606338) (xy 51.785012 -105.57637) (xy 35.583368 -105.57637) (xy 35.583368 -105.584498)
			(xy 35.582878 -105.614466) (xy 35.575055 -105.673888) (xy 35.559542 -105.731781) (xy 35.536606 -105.787154)
			(xy 35.506639 -105.83906) (xy 35.470152 -105.88661) (xy 35.427772 -105.92899) (xy 35.380222 -105.965477)
			(xy 35.328316 -105.995444) (xy 35.272943 -106.01838) (xy 35.21505 -106.033893) (xy 35.155628 -106.041716)
			(xy 35.095692 -106.041716) (xy 35.03627 -106.033893) (xy 34.978377 -106.01838) (xy 34.923004 -105.995444)
			(xy 34.871098 -105.965477) (xy 34.823548 -105.92899) (xy 34.781168 -105.88661) (xy 34.744681 -105.83906)
			(xy 34.714714 -105.787154) (xy 34.691778 -105.731781) (xy 34.676265 -105.673888) (xy 34.668442 -105.614466)
			(xy 34.667952 -105.584498) (xy 4.38404 -105.584498) (xy 4.38404 -107.377738) (xy 37.31006 -107.377738)
			(xy 37.31006 -106.514138) (xy 37.31055 -106.48417) (xy 37.318373 -106.424748) (xy 37.333886 -106.366855)
			(xy 37.356822 -106.311482) (xy 37.386789 -106.259576) (xy 37.423276 -106.212026) (xy 37.465656 -106.169646)
			(xy 37.513206 -106.133159) (xy 37.565112 -106.103192) (xy 37.620485 -106.080256) (xy 37.678378 -106.064743)
			(xy 37.7378 -106.05692) (xy 37.797736 -106.05692) (xy 37.857158 -106.064743) (xy 37.915051 -106.080256)
			(xy 37.970424 -106.103192) (xy 38.02233 -106.133159) (xy 38.06988 -106.169646) (xy 38.11226 -106.212026)
			(xy 38.148747 -106.259576) (xy 38.178714 -106.311482) (xy 38.20165 -106.366855) (xy 38.217163 -106.424748)
			(xy 38.224986 -106.48417) (xy 38.225476 -106.514138) (xy 38.225476 -107.376214) (xy 53.639212 -107.376214)
			(xy 53.639212 -106.512614) (xy 53.639702 -106.482646) (xy 53.647525 -106.423224) (xy 53.663038 -106.365331)
			(xy 53.685974 -106.309958) (xy 53.715941 -106.258052) (xy 53.752428 -106.210502) (xy 53.794808 -106.168122)
			(xy 53.842358 -106.131635) (xy 53.894264 -106.101668) (xy 53.949637 -106.078732) (xy 54.00753 -106.063219)
			(xy 54.066952 -106.055396) (xy 54.126888 -106.055396) (xy 54.18631 -106.063219) (xy 54.244203 -106.078732)
			(xy 54.299576 -106.101668) (xy 54.351482 -106.131635) (xy 54.399032 -106.168122) (xy 54.441412 -106.210502)
			(xy 54.477899 -106.258052) (xy 54.507866 -106.309958) (xy 54.530802 -106.365331) (xy 54.546315 -106.423224)
			(xy 54.554138 -106.482646) (xy 54.554628 -106.512614) (xy 54.554628 -107.210352) (xy 64.762632 -107.210352)
			(xy 64.766703 -107.15473) (xy 64.778829 -107.100293) (xy 64.798752 -107.048202) (xy 64.826048 -106.999567)
			(xy 64.860134 -106.955424) (xy 64.900283 -106.916715) (xy 64.945641 -106.884264) (xy 64.995241 -106.858763)
			(xy 65.048025 -106.840756) (xy 65.102868 -106.830626) (xy 65.158602 -106.828589) (xy 65.214039 -106.834689)
			(xy 65.267996 -106.848795) (xy 65.319325 -106.870607) (xy 65.366931 -106.899661) (xy 65.409799 -106.935336)
			(xy 65.447016 -106.976873) (xy 65.477789 -107.023386) (xy 65.501461 -107.073883) (xy 65.517529 -107.12729)
			(xy 65.525649 -107.182466) (xy 65.526158 -107.210352) (xy 85.74278 -107.210352) (xy 85.74328 -107.181612)
			(xy 85.751909 -107.124784) (xy 85.768965 -107.069893) (xy 85.794062 -107.018182) (xy 85.826631 -106.97082)
			(xy 85.845904 -106.949494) (xy 85.852508 -106.942636) (xy 85.85962 -106.924602) (xy 85.85962 -106.835702)
			(xy 85.852508 -106.817668) (xy 85.845904 -106.81081) (xy 85.826587 -106.789524) (xy 85.794025 -106.742154)
			(xy 85.768937 -106.690435) (xy 85.751891 -106.635539) (xy 85.743274 -106.578706) (xy 85.743279 -106.521224)
			(xy 85.751907 -106.464393) (xy 85.768963 -106.409499) (xy 85.79406 -106.357785) (xy 85.826631 -106.310421)
			(xy 85.845904 -106.289094) (xy 85.852508 -106.282236) (xy 85.85962 -106.264202) (xy 85.85962 -106.175302)
			(xy 85.852508 -106.157268) (xy 85.845904 -106.15041) (xy 85.826622 -106.129093) (xy 85.794055 -106.081729)
			(xy 85.768963 -106.030015) (xy 85.751916 -105.975122) (xy 85.743298 -105.918292) (xy 85.74278 -105.889552)
			(xy 85.743266 -105.862301) (xy 85.751022 -105.808353) (xy 85.766377 -105.756058) (xy 85.789019 -105.706481)
			(xy 85.818485 -105.660631) (xy 85.854176 -105.61944) (xy 85.895367 -105.583749) (xy 85.941217 -105.554283)
			(xy 85.990794 -105.531641) (xy 86.043089 -105.516286) (xy 86.097037 -105.50853) (xy 86.151539 -105.50853)
			(xy 86.205487 -105.516286) (xy 86.257782 -105.531641) (xy 86.307359 -105.554283) (xy 86.353209 -105.583749)
			(xy 86.3944 -105.61944) (xy 86.430091 -105.660631) (xy 86.459557 -105.706481) (xy 86.482199 -105.756058)
			(xy 86.497554 -105.808353) (xy 86.50531 -105.862301) (xy 86.505796 -105.889552) (xy 86.505305 -105.918292)
			(xy 86.496675 -105.975121) (xy 86.479617 -106.030012) (xy 86.454518 -106.081723) (xy 86.421946 -106.129084)
			(xy 86.402672 -106.15041) (xy 86.396068 -106.157268) (xy 86.388956 -106.175302) (xy 86.388956 -106.264202)
			(xy 86.396068 -106.282236) (xy 86.402672 -106.289094) (xy 86.421895 -106.310462) (xy 86.454463 -106.357817)
			(xy 86.479557 -106.409522) (xy 86.496611 -106.464407) (xy 86.505238 -106.521229) (xy 86.505243 -106.578702)
			(xy 86.496626 -106.635525) (xy 86.479583 -106.690412) (xy 86.454498 -106.742122) (xy 86.421939 -106.789483)
			(xy 86.402672 -106.81081) (xy 86.396068 -106.817668) (xy 86.388956 -106.835702) (xy 86.388956 -106.924602)
			(xy 86.396068 -106.942636) (xy 86.402672 -106.949494) (xy 86.421969 -106.970798) (xy 86.454531 -107.018167)
			(xy 86.473954 -107.058206) (xy 89.573862 -107.058206) (xy 89.5744 -107.029468) (xy 89.58302 -106.972641)
			(xy 89.600068 -106.917751) (xy 89.625156 -106.866039) (xy 89.657717 -106.818676) (xy 89.676986 -106.797348)
			(xy 89.68359 -106.79049) (xy 89.690702 -106.772456) (xy 89.690702 -106.683556) (xy 89.68359 -106.665522)
			(xy 89.676986 -106.658664) (xy 89.657723 -106.637331) (xy 89.625161 -106.589969) (xy 89.600071 -106.538258)
			(xy 89.583023 -106.483368) (xy 89.5744 -106.426542) (xy 89.5744 -106.369066) (xy 89.583021 -106.31224)
			(xy 89.600068 -106.257351) (xy 89.625156 -106.205639) (xy 89.657717 -106.158276) (xy 89.676986 -106.136948)
			(xy 89.68359 -106.13009) (xy 89.690702 -106.112056) (xy 89.690702 -106.023156) (xy 89.68359 -106.005122)
			(xy 89.676986 -105.998264) (xy 89.657726 -105.976927) (xy 89.625156 -105.929569) (xy 89.600061 -105.87786)
			(xy 89.583008 -105.822971) (xy 89.574384 -105.766145) (xy 89.573862 -105.737406) (xy 89.574348 -105.710155)
			(xy 89.582104 -105.656207) (xy 89.597459 -105.603912) (xy 89.620101 -105.554335) (xy 89.649567 -105.508485)
			(xy 89.685258 -105.467294) (xy 89.726449 -105.431603) (xy 89.772299 -105.402137) (xy 89.821876 -105.379495)
			(xy 89.874171 -105.36414) (xy 89.928119 -105.356384) (xy 89.982621 -105.356384) (xy 90.036569 -105.36414)
			(xy 90.088864 -105.379495) (xy 90.138441 -105.402137) (xy 90.184291 -105.431603) (xy 90.225482 -105.467294)
			(xy 90.261173 -105.508485) (xy 90.290639 -105.554335) (xy 90.313281 -105.603912) (xy 90.328636 -105.656207)
			(xy 90.336392 -105.710155) (xy 90.336878 -105.737406) (xy 90.336337 -105.766144) (xy 90.327715 -105.82297)
			(xy 90.310668 -105.877859) (xy 90.285581 -105.929571) (xy 90.253022 -105.976936) (xy 90.233754 -105.998264)
			(xy 90.22715 -106.005122) (xy 90.220038 -106.023156) (xy 90.220038 -106.112056) (xy 90.22715 -106.13009)
			(xy 90.233754 -106.136948) (xy 90.253032 -106.158269) (xy 90.285599 -106.205632) (xy 90.310691 -106.257344)
			(xy 90.327742 -106.312236) (xy 90.336365 -106.369065) (xy 90.336364 -106.426544) (xy 90.32774 -106.483372)
			(xy 90.310688 -106.538264) (xy 90.285594 -106.589976) (xy 90.253026 -106.637338) (xy 90.233754 -106.658664)
			(xy 90.22715 -106.665522) (xy 90.220038 -106.683556) (xy 90.220038 -106.772456) (xy 90.22715 -106.79049)
			(xy 90.233754 -106.797348) (xy 90.253026 -106.818674) (xy 90.285593 -106.866036) (xy 90.310685 -106.917748)
			(xy 90.327735 -106.972639) (xy 90.336357 -107.029467) (xy 90.336878 -107.058206) (xy 90.336392 -107.085457)
			(xy 90.328636 -107.139405) (xy 90.313281 -107.1917) (xy 90.290639 -107.241277) (xy 90.261173 -107.287127)
			(xy 90.225482 -107.328318) (xy 90.184291 -107.364009) (xy 90.138441 -107.393475) (xy 90.088864 -107.416117)
			(xy 90.036569 -107.431472) (xy 89.982621 -107.439228) (xy 89.928119 -107.439228) (xy 89.874171 -107.431472)
			(xy 89.821876 -107.416117) (xy 89.772299 -107.393475) (xy 89.726449 -107.364009) (xy 89.685258 -107.328318)
			(xy 89.649567 -107.287127) (xy 89.620101 -107.241277) (xy 89.597459 -107.1917) (xy 89.582104 -107.139405)
			(xy 89.574348 -107.085457) (xy 89.573862 -107.058206) (xy 86.473954 -107.058206) (xy 86.479619 -107.069884)
			(xy 86.496663 -107.12478) (xy 86.505279 -107.181611) (xy 86.505796 -107.210352) (xy 86.50531 -107.237603)
			(xy 86.497554 -107.291551) (xy 86.482199 -107.343846) (xy 86.459557 -107.393423) (xy 86.430091 -107.439273)
			(xy 86.3944 -107.480464) (xy 86.353209 -107.516155) (xy 86.307359 -107.545621) (xy 86.257782 -107.568263)
			(xy 86.205487 -107.583618) (xy 86.151539 -107.591374) (xy 86.097037 -107.591374) (xy 86.043089 -107.583618)
			(xy 85.990794 -107.568263) (xy 85.941217 -107.545621) (xy 85.895367 -107.516155) (xy 85.854176 -107.480464)
			(xy 85.818485 -107.439273) (xy 85.789019 -107.393423) (xy 85.766377 -107.343846) (xy 85.751022 -107.291551)
			(xy 85.743266 -107.237603) (xy 85.74278 -107.210352) (xy 65.526158 -107.210352) (xy 65.525649 -107.238238)
			(xy 65.517529 -107.293414) (xy 65.501461 -107.346821) (xy 65.477789 -107.397318) (xy 65.447016 -107.443831)
			(xy 65.409799 -107.485368) (xy 65.366931 -107.521043) (xy 65.319325 -107.550097) (xy 65.267996 -107.571909)
			(xy 65.214039 -107.586015) (xy 65.158602 -107.592115) (xy 65.102868 -107.590078) (xy 65.048025 -107.579948)
			(xy 64.995241 -107.561941) (xy 64.945641 -107.53644) (xy 64.900283 -107.503989) (xy 64.860134 -107.46528)
			(xy 64.826048 -107.421137) (xy 64.798752 -107.372502) (xy 64.778829 -107.320411) (xy 64.766703 -107.265974)
			(xy 64.762632 -107.210352) (xy 54.554628 -107.210352) (xy 54.554628 -107.376214) (xy 54.554138 -107.406182)
			(xy 54.546315 -107.465604) (xy 54.530802 -107.523497) (xy 54.507866 -107.57887) (xy 54.477899 -107.630776)
			(xy 54.441412 -107.678326) (xy 54.399032 -107.720706) (xy 54.351482 -107.757193) (xy 54.299576 -107.78716)
			(xy 54.244203 -107.810096) (xy 54.18631 -107.825609) (xy 54.126888 -107.833432) (xy 54.066952 -107.833432)
			(xy 54.00753 -107.825609) (xy 53.949637 -107.810096) (xy 53.894264 -107.78716) (xy 53.842358 -107.757193)
			(xy 53.794808 -107.720706) (xy 53.752428 -107.678326) (xy 53.715941 -107.630776) (xy 53.685974 -107.57887)
			(xy 53.663038 -107.523497) (xy 53.647525 -107.465604) (xy 53.639702 -107.406182) (xy 53.639212 -107.376214)
			(xy 38.225476 -107.376214) (xy 38.225476 -107.377738) (xy 38.224986 -107.407706) (xy 38.217163 -107.467128)
			(xy 38.20165 -107.525021) (xy 38.178714 -107.580394) (xy 38.148747 -107.6323) (xy 38.11226 -107.67985)
			(xy 38.06988 -107.72223) (xy 38.02233 -107.758717) (xy 37.970424 -107.788684) (xy 37.915051 -107.81162)
			(xy 37.857158 -107.827133) (xy 37.797736 -107.834956) (xy 37.7378 -107.834956) (xy 37.678378 -107.827133)
			(xy 37.620485 -107.81162) (xy 37.565112 -107.788684) (xy 37.513206 -107.758717) (xy 37.465656 -107.72223)
			(xy 37.423276 -107.67985) (xy 37.386789 -107.6323) (xy 37.356822 -107.580394) (xy 37.333886 -107.525021)
			(xy 37.318373 -107.467128) (xy 37.31055 -107.407706) (xy 37.31006 -107.377738) (xy 4.38404 -107.377738)
			(xy 4.38404 -109.18444) (xy 34.667952 -109.18444) (xy 34.667952 -108.32084) (xy 34.668442 -108.290872)
			(xy 34.676265 -108.23145) (xy 34.691778 -108.173557) (xy 34.714714 -108.118184) (xy 34.744681 -108.066278)
			(xy 34.781168 -108.018728) (xy 34.823548 -107.976348) (xy 34.871098 -107.939861) (xy 34.923004 -107.909894)
			(xy 34.978377 -107.886958) (xy 35.03627 -107.871445) (xy 35.095692 -107.863622) (xy 35.155628 -107.863622)
			(xy 35.21505 -107.871445) (xy 35.272943 -107.886958) (xy 35.328316 -107.909894) (xy 35.380222 -107.939861)
			(xy 35.427772 -107.976348) (xy 35.470152 -108.018728) (xy 35.506639 -108.066278) (xy 35.536606 -108.118184)
			(xy 35.559542 -108.173557) (xy 35.575055 -108.23145) (xy 35.582878 -108.290872) (xy 35.583368 -108.32084)
			(xy 35.583368 -109.176312) (xy 51.785012 -109.176312) (xy 51.785012 -108.312712) (xy 51.785502 -108.282744)
			(xy 51.793325 -108.223322) (xy 51.808838 -108.165429) (xy 51.831774 -108.110056) (xy 51.861741 -108.05815)
			(xy 51.898228 -108.0106) (xy 51.940608 -107.96822) (xy 51.988158 -107.931733) (xy 52.040064 -107.901766)
			(xy 52.095437 -107.87883) (xy 52.15333 -107.863317) (xy 52.212752 -107.855494) (xy 52.272688 -107.855494)
			(xy 52.33211 -107.863317) (xy 52.390003 -107.87883) (xy 52.445376 -107.901766) (xy 52.497282 -107.931733)
			(xy 52.544832 -107.96822) (xy 52.587212 -108.0106) (xy 52.623699 -108.05815) (xy 52.653666 -108.110056)
			(xy 52.676602 -108.165429) (xy 52.692115 -108.223322) (xy 52.699938 -108.282744) (xy 52.700428 -108.312712)
			(xy 52.700428 -109.176312) (xy 52.699938 -109.20628) (xy 52.692115 -109.265702) (xy 52.676602 -109.323595)
			(xy 52.653666 -109.378968) (xy 52.623699 -109.430874) (xy 52.587212 -109.478424) (xy 52.544832 -109.520804)
			(xy 52.497282 -109.557291) (xy 52.445376 -109.587258) (xy 52.390003 -109.610194) (xy 52.33211 -109.625707)
			(xy 52.272688 -109.63353) (xy 52.212752 -109.63353) (xy 52.15333 -109.625707) (xy 52.095437 -109.610194)
			(xy 52.040064 -109.587258) (xy 51.988158 -109.557291) (xy 51.940608 -109.520804) (xy 51.898228 -109.478424)
			(xy 51.861741 -109.430874) (xy 51.831774 -109.378968) (xy 51.808838 -109.323595) (xy 51.793325 -109.265702)
			(xy 51.785502 -109.20628) (xy 51.785012 -109.176312) (xy 35.583368 -109.176312) (xy 35.583368 -109.18444)
			(xy 35.582878 -109.214408) (xy 35.575055 -109.27383) (xy 35.559542 -109.331723) (xy 35.536606 -109.387096)
			(xy 35.506639 -109.439002) (xy 35.470152 -109.486552) (xy 35.427772 -109.528932) (xy 35.380222 -109.565419)
			(xy 35.328316 -109.595386) (xy 35.272943 -109.618322) (xy 35.21505 -109.633835) (xy 35.155628 -109.641658)
			(xy 35.095692 -109.641658) (xy 35.03627 -109.633835) (xy 34.978377 -109.618322) (xy 34.923004 -109.595386)
			(xy 34.871098 -109.565419) (xy 34.823548 -109.528932) (xy 34.781168 -109.486552) (xy 34.744681 -109.439002)
			(xy 34.714714 -109.387096) (xy 34.691778 -109.331723) (xy 34.676265 -109.27383) (xy 34.668442 -109.214408)
			(xy 34.667952 -109.18444) (xy 4.38404 -109.18444) (xy 4.38404 -110.977934) (xy 37.31006 -110.977934)
			(xy 37.31006 -110.114334) (xy 37.31055 -110.084366) (xy 37.318373 -110.024944) (xy 37.333886 -109.967051)
			(xy 37.356822 -109.911678) (xy 37.386789 -109.859772) (xy 37.423276 -109.812222) (xy 37.465656 -109.769842)
			(xy 37.513206 -109.733355) (xy 37.565112 -109.703388) (xy 37.620485 -109.680452) (xy 37.678378 -109.664939)
			(xy 37.7378 -109.657116) (xy 37.797736 -109.657116) (xy 37.857158 -109.664939) (xy 37.915051 -109.680452)
			(xy 37.970424 -109.703388) (xy 38.02233 -109.733355) (xy 38.06988 -109.769842) (xy 38.11226 -109.812222)
			(xy 38.148747 -109.859772) (xy 38.178714 -109.911678) (xy 38.20165 -109.967051) (xy 38.217163 -110.024944)
			(xy 38.224986 -110.084366) (xy 38.225476 -110.114334) (xy 38.225476 -110.97641) (xy 53.639212 -110.97641)
			(xy 53.639212 -110.11281) (xy 53.639702 -110.082842) (xy 53.647525 -110.02342) (xy 53.663038 -109.965527)
			(xy 53.685974 -109.910154) (xy 53.715941 -109.858248) (xy 53.752428 -109.810698) (xy 53.794808 -109.768318)
			(xy 53.842358 -109.731831) (xy 53.894264 -109.701864) (xy 53.949637 -109.678928) (xy 54.00753 -109.663415)
			(xy 54.066952 -109.655592) (xy 54.126888 -109.655592) (xy 54.18631 -109.663415) (xy 54.244203 -109.678928)
			(xy 54.299576 -109.701864) (xy 54.351482 -109.731831) (xy 54.399032 -109.768318) (xy 54.441412 -109.810698)
			(xy 54.477899 -109.858248) (xy 54.507866 -109.910154) (xy 54.530802 -109.965527) (xy 54.546315 -110.02342)
			(xy 54.554138 -110.082842) (xy 54.554628 -110.11281) (xy 54.554628 -110.530132) (xy 70.429118 -110.530132)
			(xy 70.433189 -110.47451) (xy 70.445315 -110.420073) (xy 70.465238 -110.367982) (xy 70.492534 -110.319347)
			(xy 70.52662 -110.275204) (xy 70.566769 -110.236495) (xy 70.612127 -110.204044) (xy 70.661727 -110.178543)
			(xy 70.714511 -110.160536) (xy 70.769354 -110.150406) (xy 70.825088 -110.148369) (xy 70.880525 -110.154469)
			(xy 70.934482 -110.168575) (xy 70.985811 -110.190387) (xy 71.033417 -110.219441) (xy 71.076285 -110.255116)
			(xy 71.113502 -110.296653) (xy 71.144275 -110.343166) (xy 71.167947 -110.393663) (xy 71.184015 -110.44707)
			(xy 71.192135 -110.502246) (xy 71.192644 -110.530132) (xy 71.192135 -110.558018) (xy 71.184015 -110.613194)
			(xy 71.167947 -110.666601) (xy 71.144275 -110.717098) (xy 71.113502 -110.763611) (xy 71.076285 -110.805148)
			(xy 71.033417 -110.840823) (xy 70.985811 -110.869877) (xy 70.934482 -110.891689) (xy 70.880525 -110.905795)
			(xy 70.825088 -110.911895) (xy 70.769354 -110.909858) (xy 70.714511 -110.899728) (xy 70.661727 -110.881721)
			(xy 70.612127 -110.85622) (xy 70.566769 -110.823769) (xy 70.52662 -110.78506) (xy 70.492534 -110.740917)
			(xy 70.465238 -110.692282) (xy 70.445315 -110.640191) (xy 70.433189 -110.585754) (xy 70.429118 -110.530132)
			(xy 54.554628 -110.530132) (xy 54.554628 -110.97641) (xy 54.554138 -111.006378) (xy 54.546315 -111.0658)
			(xy 54.530802 -111.123693) (xy 54.507866 -111.179066) (xy 54.477899 -111.230972) (xy 54.441412 -111.278522)
			(xy 54.399032 -111.320902) (xy 54.381908 -111.334042) (xy 64.26403 -111.334042) (xy 64.268101 -111.27842)
			(xy 64.280227 -111.223983) (xy 64.30015 -111.171892) (xy 64.327446 -111.123257) (xy 64.361532 -111.079114)
			(xy 64.401681 -111.040405) (xy 64.447039 -111.007954) (xy 64.496639 -110.982453) (xy 64.549423 -110.964446)
			(xy 64.604266 -110.954316) (xy 64.66 -110.952279) (xy 64.715437 -110.958379) (xy 64.769394 -110.972485)
			(xy 64.820723 -110.994297) (xy 64.868329 -111.023351) (xy 64.911197 -111.059026) (xy 64.948414 -111.100563)
			(xy 64.979187 -111.147076) (xy 65.002859 -111.197573) (xy 65.018927 -111.25098) (xy 65.027047 -111.306156)
			(xy 65.027556 -111.334042) (xy 65.027047 -111.361928) (xy 65.018927 -111.417104) (xy 65.002859 -111.470511)
			(xy 64.979187 -111.521008) (xy 64.948414 -111.567521) (xy 64.911197 -111.609058) (xy 64.868329 -111.644733)
			(xy 64.820723 -111.673787) (xy 64.769394 -111.695599) (xy 64.715437 -111.709705) (xy 64.66 -111.715805)
			(xy 64.604266 -111.713768) (xy 64.549423 -111.703638) (xy 64.496639 -111.685631) (xy 64.447039 -111.66013)
			(xy 64.401681 -111.627679) (xy 64.361532 -111.58897) (xy 64.327446 -111.544827) (xy 64.30015 -111.496192)
			(xy 64.280227 -111.444101) (xy 64.268101 -111.389664) (xy 64.26403 -111.334042) (xy 54.381908 -111.334042)
			(xy 54.351482 -111.357389) (xy 54.299576 -111.387356) (xy 54.244203 -111.410292) (xy 54.18631 -111.425805)
			(xy 54.126888 -111.433628) (xy 54.066952 -111.433628) (xy 54.00753 -111.425805) (xy 53.949637 -111.410292)
			(xy 53.894264 -111.387356) (xy 53.842358 -111.357389) (xy 53.794808 -111.320902) (xy 53.752428 -111.278522)
			(xy 53.715941 -111.230972) (xy 53.685974 -111.179066) (xy 53.663038 -111.123693) (xy 53.647525 -111.0658)
			(xy 53.639702 -111.006378) (xy 53.639212 -110.97641) (xy 38.225476 -110.97641) (xy 38.225476 -110.977934)
			(xy 38.224986 -111.007902) (xy 38.217163 -111.067324) (xy 38.20165 -111.125217) (xy 38.178714 -111.18059)
			(xy 38.148747 -111.232496) (xy 38.11226 -111.280046) (xy 38.06988 -111.322426) (xy 38.02233 -111.358913)
			(xy 37.970424 -111.38888) (xy 37.915051 -111.411816) (xy 37.857158 -111.427329) (xy 37.797736 -111.435152)
			(xy 37.7378 -111.435152) (xy 37.678378 -111.427329) (xy 37.620485 -111.411816) (xy 37.565112 -111.38888)
			(xy 37.513206 -111.358913) (xy 37.465656 -111.322426) (xy 37.423276 -111.280046) (xy 37.386789 -111.232496)
			(xy 37.356822 -111.18059) (xy 37.333886 -111.125217) (xy 37.318373 -111.067324) (xy 37.31055 -111.007902)
			(xy 37.31006 -110.977934) (xy 4.38404 -110.977934) (xy 4.38404 -112.501426) (xy 11.973304 -112.501426)
			(xy 11.977375 -112.445804) (xy 11.989501 -112.391367) (xy 12.009424 -112.339276) (xy 12.03672 -112.290641)
			(xy 12.070806 -112.246498) (xy 12.110955 -112.207789) (xy 12.156313 -112.175338) (xy 12.205913 -112.149837)
			(xy 12.258697 -112.13183) (xy 12.31354 -112.1217) (xy 12.369274 -112.119663) (xy 12.424711 -112.125763)
			(xy 12.478668 -112.139869) (xy 12.529997 -112.161681) (xy 12.577603 -112.190735) (xy 12.620471 -112.22641)
			(xy 12.657688 -112.267947) (xy 12.688461 -112.31446) (xy 12.712133 -112.364957) (xy 12.728201 -112.418364)
			(xy 12.736321 -112.47354) (xy 12.73683 -112.501426) (xy 12.736321 -112.529312) (xy 12.728201 -112.584488)
			(xy 12.712133 -112.637895) (xy 12.688461 -112.688392) (xy 12.657688 -112.734905) (xy 12.620471 -112.776442)
			(xy 12.61093 -112.784382) (xy 34.667952 -112.784382) (xy 34.667952 -111.920782) (xy 34.668442 -111.890814)
			(xy 34.676265 -111.831392) (xy 34.691778 -111.773499) (xy 34.714714 -111.718126) (xy 34.744681 -111.66622)
			(xy 34.781168 -111.61867) (xy 34.823548 -111.57629) (xy 34.871098 -111.539803) (xy 34.923004 -111.509836)
			(xy 34.978377 -111.4869) (xy 35.03627 -111.471387) (xy 35.095692 -111.463564) (xy 35.155628 -111.463564)
			(xy 35.21505 -111.471387) (xy 35.272943 -111.4869) (xy 35.328316 -111.509836) (xy 35.380222 -111.539803)
			(xy 35.427772 -111.57629) (xy 35.470152 -111.61867) (xy 35.506639 -111.66622) (xy 35.536606 -111.718126)
			(xy 35.559542 -111.773499) (xy 35.575055 -111.831392) (xy 35.582878 -111.890814) (xy 35.583368 -111.920782)
			(xy 35.583368 -112.776508) (xy 51.785012 -112.776508) (xy 51.785012 -111.912908) (xy 51.785502 -111.88294)
			(xy 51.793325 -111.823518) (xy 51.808838 -111.765625) (xy 51.831774 -111.710252) (xy 51.861741 -111.658346)
			(xy 51.898228 -111.610796) (xy 51.940608 -111.568416) (xy 51.988158 -111.531929) (xy 52.040064 -111.501962)
			(xy 52.095437 -111.479026) (xy 52.15333 -111.463513) (xy 52.212752 -111.45569) (xy 52.272688 -111.45569)
			(xy 52.33211 -111.463513) (xy 52.390003 -111.479026) (xy 52.445376 -111.501962) (xy 52.497282 -111.531929)
			(xy 52.544832 -111.568416) (xy 52.587212 -111.610796) (xy 52.623699 -111.658346) (xy 52.653666 -111.710252)
			(xy 52.676602 -111.765625) (xy 52.692115 -111.823518) (xy 52.699938 -111.88294) (xy 52.699959 -111.884206)
			(xy 70.364348 -111.884206) (xy 70.368419 -111.828584) (xy 70.380545 -111.774147) (xy 70.400468 -111.722056)
			(xy 70.427764 -111.673421) (xy 70.46185 -111.629278) (xy 70.501999 -111.590569) (xy 70.547357 -111.558118)
			(xy 70.596957 -111.532617) (xy 70.649741 -111.51461) (xy 70.704584 -111.50448) (xy 70.760318 -111.502443)
			(xy 70.815755 -111.508543) (xy 70.869712 -111.522649) (xy 70.921041 -111.544461) (xy 70.968647 -111.573515)
			(xy 71.011515 -111.60919) (xy 71.048732 -111.650727) (xy 71.079505 -111.69724) (xy 71.103177 -111.747737)
			(xy 71.119245 -111.801144) (xy 71.127365 -111.85632) (xy 71.127874 -111.884206) (xy 71.127365 -111.912092)
			(xy 71.119245 -111.967268) (xy 71.115196 -111.980726) (xy 73.901554 -111.980726) (xy 73.902106 -111.951988)
			(xy 73.910723 -111.895163) (xy 73.927768 -111.840273) (xy 73.952853 -111.788561) (xy 73.985411 -111.741196)
			(xy 74.004678 -111.719868) (xy 74.011282 -111.71301) (xy 74.018394 -111.694976) (xy 74.018394 -111.606076)
			(xy 74.011282 -111.588042) (xy 74.004678 -111.581184) (xy 73.985435 -111.559834) (xy 73.952873 -111.512474)
			(xy 73.927783 -111.460766) (xy 73.910733 -111.405879) (xy 73.902109 -111.349056) (xy 73.902106 -111.291582)
			(xy 73.910725 -111.234758) (xy 73.927769 -111.17987) (xy 73.952854 -111.128159) (xy 73.985411 -111.080796)
			(xy 74.004678 -111.059468) (xy 74.011282 -111.05261) (xy 74.018394 -111.034576) (xy 74.018394 -110.945676)
			(xy 74.011282 -110.927642) (xy 74.004678 -110.920784) (xy 73.985435 -110.899434) (xy 73.952873 -110.852074)
			(xy 73.927783 -110.800366) (xy 73.910733 -110.745479) (xy 73.902109 -110.688656) (xy 73.902106 -110.631182)
			(xy 73.910725 -110.574358) (xy 73.927769 -110.51947) (xy 73.952854 -110.467759) (xy 73.985411 -110.420396)
			(xy 74.004678 -110.399068) (xy 74.011282 -110.39221) (xy 74.018394 -110.374176) (xy 74.018394 -110.285276)
			(xy 74.011282 -110.267242) (xy 74.004678 -110.260384) (xy 73.985435 -110.239034) (xy 73.952873 -110.191674)
			(xy 73.927783 -110.139966) (xy 73.910733 -110.085079) (xy 73.902109 -110.028256) (xy 73.902106 -109.970782)
			(xy 73.910725 -109.913958) (xy 73.927769 -109.85907) (xy 73.952854 -109.807359) (xy 73.985411 -109.759996)
			(xy 74.004678 -109.738668) (xy 74.011282 -109.73181) (xy 74.018394 -109.713776) (xy 74.018394 -109.624876)
			(xy 74.011282 -109.606842) (xy 74.004678 -109.599984) (xy 73.985426 -109.57864) (xy 73.952856 -109.531284)
			(xy 73.927759 -109.479576) (xy 73.910704 -109.424689) (xy 73.902077 -109.367864) (xy 73.901554 -109.339126)
			(xy 73.902102 -109.311877) (xy 73.909854 -109.257934) (xy 73.925204 -109.205642) (xy 73.94784 -109.156068)
			(xy 73.9773 -109.110219) (xy 74.012984 -109.06903) (xy 74.054168 -109.033338) (xy 74.100012 -109.00387)
			(xy 74.149582 -108.981227) (xy 74.201871 -108.965868) (xy 74.255813 -108.958107) (xy 74.283062 -108.957618)
			(xy 74.309378 -108.958038) (xy 74.361508 -108.965282) (xy 74.412152 -108.97961) (xy 74.460351 -109.000751)
			(xy 74.505193 -109.028306) (xy 74.545831 -109.061753) (xy 74.563986 -109.080808) (xy 74.57151 -109.088206)
			(xy 74.590788 -109.096732) (xy 74.601324 -109.097318) (xy 74.676 -109.097318) (xy 74.686551 -109.096797)
			(xy 74.705845 -109.088256) (xy 74.713338 -109.080808) (xy 74.731484 -109.061743) (xy 74.772115 -109.028286)
			(xy 74.816958 -109.000728) (xy 74.86516 -108.979591) (xy 74.91581 -108.965276) (xy 74.967945 -108.958055)
			(xy 74.994262 -108.957618) (xy 75.021515 -108.958091) (xy 75.075467 -108.965843) (xy 75.127766 -108.981196)
			(xy 75.177348 -109.003836) (xy 75.223203 -109.033302) (xy 75.264396 -109.068995) (xy 75.300091 -109.110188)
			(xy 75.329559 -109.156041) (xy 75.3522 -109.205622) (xy 75.367554 -109.257921) (xy 75.375308 -109.311873)
			(xy 75.37577 -109.339126) (xy 75.375243 -109.367865) (xy 75.366619 -109.424691) (xy 75.349568 -109.479581)
			(xy 75.324478 -109.531293) (xy 75.291915 -109.578656) (xy 75.272646 -109.599984) (xy 75.266042 -109.606842)
			(xy 75.25893 -109.624876) (xy 75.25893 -109.713776) (xy 75.266042 -109.73181) (xy 75.272646 -109.738668)
			(xy 75.291944 -109.759972) (xy 75.324511 -109.807337) (xy 75.349603 -109.859053) (xy 75.366653 -109.913947)
			(xy 75.375273 -109.970778) (xy 75.375271 -110.02826) (xy 75.366644 -110.08509) (xy 75.349589 -110.139983)
			(xy 75.324492 -110.191696) (xy 75.29192 -110.239058) (xy 75.272646 -110.260384) (xy 75.266042 -110.267242)
			(xy 75.25893 -110.285276) (xy 75.25893 -110.374176) (xy 75.266042 -110.39221) (xy 75.272646 -110.399068)
			(xy 75.291944 -110.420372) (xy 75.324511 -110.467737) (xy 75.349603 -110.519453) (xy 75.366653 -110.574347)
			(xy 75.375273 -110.631178) (xy 75.375271 -110.68866) (xy 75.366644 -110.74549) (xy 75.349589 -110.800383)
			(xy 75.324492 -110.852096) (xy 75.29192 -110.899458) (xy 75.272646 -110.920784) (xy 75.266042 -110.927642)
			(xy 75.25893 -110.945676) (xy 75.25893 -111.034576) (xy 75.266042 -111.05261) (xy 75.272646 -111.059468)
			(xy 75.291944 -111.080772) (xy 75.324511 -111.128137) (xy 75.349603 -111.179853) (xy 75.366653 -111.234747)
			(xy 75.375273 -111.291578) (xy 75.375271 -111.34906) (xy 75.366644 -111.40589) (xy 75.349589 -111.460783)
			(xy 75.324492 -111.512496) (xy 75.29192 -111.559858) (xy 75.272646 -111.581184) (xy 75.266042 -111.588042)
			(xy 75.25893 -111.606076) (xy 75.25893 -111.694976) (xy 75.266042 -111.71301) (xy 75.272646 -111.719868)
			(xy 75.291926 -111.741187) (xy 75.324492 -111.788551) (xy 75.349583 -111.840264) (xy 75.366631 -111.895157)
			(xy 75.375251 -111.951986) (xy 75.37577 -111.980726) (xy 75.375369 -112.007981) (xy 75.367608 -112.061936)
			(xy 75.352246 -112.114238) (xy 75.329598 -112.163821) (xy 75.300124 -112.209676) (xy 75.264424 -112.250869)
			(xy 75.223224 -112.286562) (xy 75.177364 -112.316029) (xy 75.127778 -112.338669) (xy 75.075474 -112.354021)
			(xy 75.021517 -112.361774) (xy 74.994262 -112.362234) (xy 74.967948 -112.361781) (xy 74.915819 -112.354542)
			(xy 74.865176 -112.340219) (xy 74.816978 -112.319084) (xy 74.772135 -112.291536) (xy 74.731495 -112.258096)
			(xy 74.713338 -112.239044) (xy 74.705798 -112.231664) (xy 74.686532 -112.223126) (xy 74.676 -112.222534)
			(xy 74.601324 -112.222534) (xy 74.590773 -112.223052) (xy 74.571477 -112.231594) (xy 74.563986 -112.239044)
			(xy 74.545839 -112.258108) (xy 74.505206 -112.291562) (xy 74.460364 -112.319119) (xy 74.412162 -112.340256)
			(xy 74.361513 -112.354572) (xy 74.309378 -112.361796) (xy 74.283062 -112.362234) (xy 74.255811 -112.361758)
			(xy 74.201864 -112.353997) (xy 74.149571 -112.338638) (xy 74.099995 -112.315994) (xy 74.054146 -112.286526)
			(xy 74.012957 -112.250834) (xy 73.977266 -112.209644) (xy 73.9478 -112.163794) (xy 73.925158 -112.114218)
			(xy 73.909801 -112.061924) (xy 73.902042 -112.007977) (xy 73.901554 -111.980726) (xy 71.115196 -111.980726)
			(xy 71.103177 -112.020675) (xy 71.079505 -112.071172) (xy 71.048732 -112.117685) (xy 71.011515 -112.159222)
			(xy 70.968647 -112.194897) (xy 70.921041 -112.223951) (xy 70.869712 -112.245763) (xy 70.815755 -112.259869)
			(xy 70.760318 -112.265969) (xy 70.704584 -112.263932) (xy 70.649741 -112.253802) (xy 70.596957 -112.235795)
			(xy 70.547357 -112.210294) (xy 70.501999 -112.177843) (xy 70.46185 -112.139134) (xy 70.427764 -112.094991)
			(xy 70.400468 -112.046356) (xy 70.380545 -111.994265) (xy 70.368419 -111.939828) (xy 70.364348 -111.884206)
			(xy 52.699959 -111.884206) (xy 52.700428 -111.912908) (xy 52.700428 -112.510824) (xy 63.802512 -112.510824)
			(xy 63.806583 -112.455202) (xy 63.818709 -112.400765) (xy 63.838632 -112.348674) (xy 63.865928 -112.300039)
			(xy 63.900014 -112.255896) (xy 63.940163 -112.217187) (xy 63.985521 -112.184736) (xy 64.035121 -112.159235)
			(xy 64.087905 -112.141228) (xy 64.142748 -112.131098) (xy 64.198482 -112.129061) (xy 64.253919 -112.135161)
			(xy 64.307876 -112.149267) (xy 64.359205 -112.171079) (xy 64.406811 -112.200133) (xy 64.449679 -112.235808)
			(xy 64.486896 -112.277345) (xy 64.517669 -112.323858) (xy 64.541341 -112.374355) (xy 64.555653 -112.421924)
			(xy 69.455028 -112.421924) (xy 69.459099 -112.366302) (xy 69.471225 -112.311865) (xy 69.491148 -112.259774)
			(xy 69.518444 -112.211139) (xy 69.55253 -112.166996) (xy 69.592679 -112.128287) (xy 69.638037 -112.095836)
			(xy 69.687637 -112.070335) (xy 69.740421 -112.052328) (xy 69.795264 -112.042198) (xy 69.850998 -112.040161)
			(xy 69.906435 -112.046261) (xy 69.960392 -112.060367) (xy 70.011721 -112.082179) (xy 70.059327 -112.111233)
			(xy 70.102195 -112.146908) (xy 70.139412 -112.188445) (xy 70.170185 -112.234958) (xy 70.193857 -112.285455)
			(xy 70.209925 -112.338862) (xy 70.218045 -112.394038) (xy 70.218554 -112.421924) (xy 70.218045 -112.44981)
			(xy 70.209925 -112.504986) (xy 70.193857 -112.558393) (xy 70.170185 -112.60889) (xy 70.139412 -112.655403)
			(xy 70.102195 -112.69694) (xy 70.059327 -112.732615) (xy 70.011721 -112.761669) (xy 69.960392 -112.783481)
			(xy 69.906435 -112.797587) (xy 69.850998 -112.803687) (xy 69.795264 -112.80165) (xy 69.740421 -112.79152)
			(xy 69.687637 -112.773513) (xy 69.638037 -112.748012) (xy 69.592679 -112.715561) (xy 69.55253 -112.676852)
			(xy 69.518444 -112.632709) (xy 69.491148 -112.584074) (xy 69.471225 -112.531983) (xy 69.459099 -112.477546)
			(xy 69.455028 -112.421924) (xy 64.555653 -112.421924) (xy 64.557409 -112.427762) (xy 64.565529 -112.482938)
			(xy 64.566038 -112.510824) (xy 64.565529 -112.53871) (xy 64.557409 -112.593886) (xy 64.541341 -112.647293)
			(xy 64.517669 -112.69779) (xy 64.486896 -112.744303) (xy 64.449679 -112.78584) (xy 64.406811 -112.821515)
			(xy 64.384833 -112.834928) (xy 66.496946 -112.834928) (xy 66.497432 -112.807677) (xy 66.505188 -112.753729)
			(xy 66.520543 -112.701434) (xy 66.543185 -112.651857) (xy 66.572651 -112.606007) (xy 66.608342 -112.564816)
			(xy 66.649533 -112.529125) (xy 66.695383 -112.499659) (xy 66.74496 -112.477017) (xy 66.797255 -112.461662)
			(xy 66.851203 -112.453906) (xy 66.905705 -112.453906) (xy 66.959653 -112.461662) (xy 67.011948 -112.477017)
			(xy 67.061525 -112.499659) (xy 67.107375 -112.529125) (xy 67.148566 -112.564816) (xy 67.184257 -112.606007)
			(xy 67.213723 -112.651857) (xy 67.236365 -112.701434) (xy 67.25172 -112.753729) (xy 67.259476 -112.807677)
			(xy 67.259962 -112.834928) (xy 67.259592 -112.858546) (xy 67.253736 -112.905418) (xy 67.248278 -112.9284)
			(xy 67.245153 -112.942907) (xy 67.246479 -112.97254) (xy 67.252438 -112.989614) (xy 70.44004 -112.989614)
			(xy 70.444111 -112.933992) (xy 70.456237 -112.879555) (xy 70.47616 -112.827464) (xy 70.503456 -112.778829)
			(xy 70.537542 -112.734686) (xy 70.577691 -112.695977) (xy 70.623049 -112.663526) (xy 70.672649 -112.638025)
			(xy 70.725433 -112.620018) (xy 70.780276 -112.609888) (xy 70.83601 -112.607851) (xy 70.891447 -112.613951)
			(xy 70.945404 -112.628057) (xy 70.996733 -112.649869) (xy 71.044339 -112.678923) (xy 71.087207 -112.714598)
			(xy 71.124424 -112.756135) (xy 71.155197 -112.802648) (xy 71.178869 -112.853145) (xy 71.194937 -112.906552)
			(xy 71.203057 -112.961728) (xy 71.203566 -112.989614) (xy 71.203057 -113.0175) (xy 71.194937 -113.072676)
			(xy 71.178869 -113.126083) (xy 71.155197 -113.17658) (xy 71.124424 -113.223093) (xy 71.087207 -113.26463)
			(xy 71.044339 -113.300305) (xy 70.996733 -113.329359) (xy 70.945404 -113.351171) (xy 70.891447 -113.365277)
			(xy 70.83601 -113.371377) (xy 70.780276 -113.36934) (xy 70.725433 -113.35921) (xy 70.672649 -113.341203)
			(xy 70.623049 -113.315702) (xy 70.577691 -113.283251) (xy 70.537542 -113.244542) (xy 70.503456 -113.200399)
			(xy 70.47616 -113.151764) (xy 70.456237 -113.099673) (xy 70.444111 -113.045236) (xy 70.44004 -112.989614)
			(xy 67.252438 -112.989614) (xy 67.256253 -113.000546) (xy 67.273654 -113.024568) (xy 67.297217 -113.042587)
			(xy 67.32496 -113.053085) (xy 67.339718 -113.054638) (xy 67.368241 -113.057167) (xy 67.424115 -113.069687)
			(xy 67.47749 -113.090418) (xy 67.527167 -113.118895) (xy 67.572028 -113.154479) (xy 67.611066 -113.196368)
			(xy 67.643403 -113.243623) (xy 67.668313 -113.295181) (xy 67.685236 -113.349883) (xy 67.693791 -113.4065)
			(xy 67.694302 -113.43513) (xy 67.694252 -113.437924) (xy 69.433946 -113.437924) (xy 69.438017 -113.382302)
			(xy 69.450143 -113.327865) (xy 69.470066 -113.275774) (xy 69.497362 -113.227139) (xy 69.531448 -113.182996)
			(xy 69.571597 -113.144287) (xy 69.616955 -113.111836) (xy 69.666555 -113.086335) (xy 69.719339 -113.068328)
			(xy 69.774182 -113.058198) (xy 69.829916 -113.056161) (xy 69.885353 -113.062261) (xy 69.93931 -113.076367)
			(xy 69.990639 -113.098179) (xy 70.038245 -113.127233) (xy 70.081113 -113.162908) (xy 70.11833 -113.204445)
			(xy 70.149103 -113.250958) (xy 70.172775 -113.301455) (xy 70.188843 -113.354862) (xy 70.196963 -113.410038)
			(xy 70.197472 -113.437924) (xy 70.196963 -113.46581) (xy 70.188843 -113.520986) (xy 70.172775 -113.574393)
			(xy 70.149103 -113.62489) (xy 70.11833 -113.671403) (xy 70.081113 -113.71294) (xy 70.038245 -113.748615)
			(xy 69.990639 -113.777669) (xy 69.93931 -113.799481) (xy 69.885353 -113.813587) (xy 69.829916 -113.819687)
			(xy 69.774182 -113.81765) (xy 69.719339 -113.80752) (xy 69.666555 -113.789513) (xy 69.616955 -113.764012)
			(xy 69.571597 -113.731561) (xy 69.531448 -113.692852) (xy 69.497362 -113.648709) (xy 69.470066 -113.600074)
			(xy 69.450143 -113.547983) (xy 69.438017 -113.493546) (xy 69.433946 -113.437924) (xy 67.694252 -113.437924)
			(xy 67.693816 -113.462381) (xy 67.68606 -113.516329) (xy 67.670705 -113.568624) (xy 67.648063 -113.618201)
			(xy 67.618597 -113.664051) (xy 67.582906 -113.705242) (xy 67.541715 -113.740933) (xy 67.495865 -113.770399)
			(xy 67.446288 -113.793041) (xy 67.393993 -113.808396) (xy 67.340045 -113.816152) (xy 67.285543 -113.816152)
			(xy 67.231595 -113.808396) (xy 67.1793 -113.793041) (xy 67.129723 -113.770399) (xy 67.083873 -113.740933)
			(xy 67.042682 -113.705242) (xy 67.006991 -113.664051) (xy 66.977525 -113.618201) (xy 66.954883 -113.568624)
			(xy 66.939528 -113.516329) (xy 66.931772 -113.462381) (xy 66.931286 -113.43513) (xy 66.93165 -113.411512)
			(xy 66.93751 -113.364639) (xy 66.94297 -113.341658) (xy 66.946079 -113.327146) (xy 66.944768 -113.297511)
			(xy 66.935001 -113.269501) (xy 66.917602 -113.245475) (xy 66.894037 -113.227458) (xy 66.86629 -113.216967)
			(xy 66.85153 -113.21542) (xy 66.823006 -113.212891) (xy 66.767129 -113.200377) (xy 66.713751 -113.179649)
			(xy 66.664072 -113.151173) (xy 66.619209 -113.11559) (xy 66.58017 -113.073699) (xy 66.547833 -113.026443)
			(xy 66.522924 -112.974883) (xy 66.506005 -112.920178) (xy 66.497454 -112.863559) (xy 66.496946 -112.834928)
			(xy 64.384833 -112.834928) (xy 64.359205 -112.850569) (xy 64.307876 -112.872381) (xy 64.253919 -112.886487)
			(xy 64.198482 -112.892587) (xy 64.142748 -112.89055) (xy 64.087905 -112.88042) (xy 64.035121 -112.862413)
			(xy 63.985521 -112.836912) (xy 63.940163 -112.804461) (xy 63.900014 -112.765752) (xy 63.865928 -112.721609)
			(xy 63.838632 -112.672974) (xy 63.818709 -112.620883) (xy 63.806583 -112.566446) (xy 63.802512 -112.510824)
			(xy 52.700428 -112.510824) (xy 52.700428 -112.776508) (xy 52.699938 -112.806476) (xy 52.692115 -112.865898)
			(xy 52.676602 -112.923791) (xy 52.653666 -112.979164) (xy 52.623699 -113.03107) (xy 52.587212 -113.07862)
			(xy 52.544832 -113.121) (xy 52.497282 -113.157487) (xy 52.445376 -113.187454) (xy 52.390003 -113.21039)
			(xy 52.33211 -113.225903) (xy 52.272688 -113.233726) (xy 52.212752 -113.233726) (xy 52.15333 -113.225903)
			(xy 52.095437 -113.21039) (xy 52.040064 -113.187454) (xy 51.988158 -113.157487) (xy 51.940608 -113.121)
			(xy 51.898228 -113.07862) (xy 51.861741 -113.03107) (xy 51.831774 -112.979164) (xy 51.808838 -112.923791)
			(xy 51.793325 -112.865898) (xy 51.785502 -112.806476) (xy 51.785012 -112.776508) (xy 35.583368 -112.776508)
			(xy 35.583368 -112.784382) (xy 35.582878 -112.81435) (xy 35.575055 -112.873772) (xy 35.559542 -112.931665)
			(xy 35.536606 -112.987038) (xy 35.506639 -113.038944) (xy 35.470152 -113.086494) (xy 35.427772 -113.128874)
			(xy 35.380222 -113.165361) (xy 35.328316 -113.195328) (xy 35.272943 -113.218264) (xy 35.21505 -113.233777)
			(xy 35.155628 -113.2416) (xy 35.095692 -113.2416) (xy 35.03627 -113.233777) (xy 34.978377 -113.218264)
			(xy 34.923004 -113.195328) (xy 34.871098 -113.165361) (xy 34.823548 -113.128874) (xy 34.781168 -113.086494)
			(xy 34.744681 -113.038944) (xy 34.714714 -112.987038) (xy 34.691778 -112.931665) (xy 34.676265 -112.873772)
			(xy 34.668442 -112.81435) (xy 34.667952 -112.784382) (xy 12.61093 -112.784382) (xy 12.577603 -112.812117)
			(xy 12.529997 -112.841171) (xy 12.478668 -112.862983) (xy 12.424711 -112.877089) (xy 12.369274 -112.883189)
			(xy 12.31354 -112.881152) (xy 12.258697 -112.871022) (xy 12.205913 -112.853015) (xy 12.156313 -112.827514)
			(xy 12.110955 -112.795063) (xy 12.070806 -112.756354) (xy 12.03672 -112.712211) (xy 12.009424 -112.663576)
			(xy 11.989501 -112.611485) (xy 11.977375 -112.557048) (xy 11.973304 -112.501426) (xy 4.38404 -112.501426)
			(xy 4.38404 -113.302034) (xy 14.31366 -113.302034) (xy 14.317731 -113.246412) (xy 14.329857 -113.191975)
			(xy 14.34978 -113.139884) (xy 14.377076 -113.091249) (xy 14.411162 -113.047106) (xy 14.451311 -113.008397)
			(xy 14.496669 -112.975946) (xy 14.546269 -112.950445) (xy 14.599053 -112.932438) (xy 14.653896 -112.922308)
			(xy 14.70963 -112.920271) (xy 14.765067 -112.926371) (xy 14.819024 -112.940477) (xy 14.870353 -112.962289)
			(xy 14.917959 -112.991343) (xy 14.960827 -113.027018) (xy 14.998044 -113.068555) (xy 15.028817 -113.115068)
			(xy 15.052489 -113.165565) (xy 15.057783 -113.183162) (xy 16.31518 -113.183162) (xy 16.319251 -113.12754)
			(xy 16.331377 -113.073103) (xy 16.3513 -113.021012) (xy 16.378596 -112.972377) (xy 16.412682 -112.928234)
			(xy 16.452831 -112.889525) (xy 16.498189 -112.857074) (xy 16.547789 -112.831573) (xy 16.600573 -112.813566)
			(xy 16.655416 -112.803436) (xy 16.71115 -112.801399) (xy 16.766587 -112.807499) (xy 16.820544 -112.821605)
			(xy 16.871873 -112.843417) (xy 16.919479 -112.872471) (xy 16.962347 -112.908146) (xy 16.999564 -112.949683)
			(xy 17.030337 -112.996196) (xy 17.054009 -113.046693) (xy 17.070077 -113.1001) (xy 17.078197 -113.155276)
			(xy 17.078706 -113.183162) (xy 17.078197 -113.211048) (xy 17.072208 -113.251742) (xy 64.306194 -113.251742)
			(xy 64.310265 -113.19612) (xy 64.322391 -113.141683) (xy 64.342314 -113.089592) (xy 64.36961 -113.040957)
			(xy 64.403696 -112.996814) (xy 64.443845 -112.958105) (xy 64.489203 -112.925654) (xy 64.538803 -112.900153)
			(xy 64.591587 -112.882146) (xy 64.64643 -112.872016) (xy 64.702164 -112.869979) (xy 64.757601 -112.876079)
			(xy 64.811558 -112.890185) (xy 64.862887 -112.911997) (xy 64.910493 -112.941051) (xy 64.953361 -112.976726)
			(xy 64.990578 -113.018263) (xy 65.021351 -113.064776) (xy 65.045023 -113.115273) (xy 65.061091 -113.16868)
			(xy 65.069211 -113.223856) (xy 65.06972 -113.251742) (xy 65.069211 -113.279628) (xy 65.061091 -113.334804)
			(xy 65.045023 -113.388211) (xy 65.021351 -113.438708) (xy 64.990578 -113.485221) (xy 64.953361 -113.526758)
			(xy 64.910493 -113.562433) (xy 64.862887 -113.591487) (xy 64.811558 -113.613299) (xy 64.757601 -113.627405)
			(xy 64.702164 -113.633505) (xy 64.64643 -113.631468) (xy 64.591587 -113.621338) (xy 64.538803 -113.603331)
			(xy 64.489203 -113.57783) (xy 64.443845 -113.545379) (xy 64.403696 -113.50667) (xy 64.36961 -113.462527)
			(xy 64.342314 -113.413892) (xy 64.322391 -113.361801) (xy 64.310265 -113.307364) (xy 64.306194 -113.251742)
			(xy 17.072208 -113.251742) (xy 17.070077 -113.266224) (xy 17.054009 -113.319631) (xy 17.030337 -113.370128)
			(xy 16.999564 -113.416641) (xy 16.962347 -113.458178) (xy 16.919479 -113.493853) (xy 16.871873 -113.522907)
			(xy 16.820544 -113.544719) (xy 16.766587 -113.558825) (xy 16.71115 -113.564925) (xy 16.655416 -113.562888)
			(xy 16.600573 -113.552758) (xy 16.547789 -113.534751) (xy 16.498189 -113.50925) (xy 16.452831 -113.476799)
			(xy 16.412682 -113.43809) (xy 16.378596 -113.393947) (xy 16.3513 -113.345312) (xy 16.331377 -113.293221)
			(xy 16.319251 -113.238784) (xy 16.31518 -113.183162) (xy 15.057783 -113.183162) (xy 15.068557 -113.218972)
			(xy 15.076677 -113.274148) (xy 15.077186 -113.302034) (xy 15.076677 -113.32992) (xy 15.068557 -113.385096)
			(xy 15.052489 -113.438503) (xy 15.028817 -113.489) (xy 14.998044 -113.535513) (xy 14.960827 -113.57705)
			(xy 14.917959 -113.612725) (xy 14.870353 -113.641779) (xy 14.819024 -113.663591) (xy 14.765067 -113.677697)
			(xy 14.70963 -113.683797) (xy 14.653896 -113.68176) (xy 14.599053 -113.67163) (xy 14.546269 -113.653623)
			(xy 14.496669 -113.628122) (xy 14.451311 -113.595671) (xy 14.411162 -113.556962) (xy 14.377076 -113.512819)
			(xy 14.34978 -113.464184) (xy 14.329857 -113.412093) (xy 14.317731 -113.357656) (xy 14.31366 -113.302034)
			(xy 4.38404 -113.302034) (xy 4.38404 -113.917222) (xy 70.793862 -113.917222) (xy 70.797933 -113.8616)
			(xy 70.810059 -113.807163) (xy 70.829982 -113.755072) (xy 70.857278 -113.706437) (xy 70.891364 -113.662294)
			(xy 70.931513 -113.623585) (xy 70.976871 -113.591134) (xy 71.026471 -113.565633) (xy 71.079255 -113.547626)
			(xy 71.134098 -113.537496) (xy 71.189832 -113.535459) (xy 71.245269 -113.541559) (xy 71.299226 -113.555665)
			(xy 71.350555 -113.577477) (xy 71.398161 -113.606531) (xy 71.441029 -113.642206) (xy 71.478246 -113.683743)
			(xy 71.509019 -113.730256) (xy 71.532691 -113.780753) (xy 71.548759 -113.83416) (xy 71.556879 -113.889336)
			(xy 71.557388 -113.917222) (xy 71.556879 -113.945108) (xy 71.548759 -114.000284) (xy 71.532691 -114.053691)
			(xy 71.509019 -114.104188) (xy 71.478246 -114.150701) (xy 71.441029 -114.192238) (xy 71.398161 -114.227913)
			(xy 71.350555 -114.256967) (xy 71.299226 -114.278779) (xy 71.245269 -114.292885) (xy 71.189832 -114.298985)
			(xy 71.134098 -114.296948) (xy 71.079255 -114.286818) (xy 71.026471 -114.268811) (xy 70.976871 -114.24331)
			(xy 70.931513 -114.210859) (xy 70.891364 -114.17215) (xy 70.857278 -114.128007) (xy 70.829982 -114.079372)
			(xy 70.810059 -114.027281) (xy 70.797933 -113.972844) (xy 70.793862 -113.917222) (xy 4.38404 -113.917222)
			(xy 4.38404 -114.660426) (xy 11.961366 -114.660426) (xy 11.965437 -114.604804) (xy 11.977563 -114.550367)
			(xy 11.997486 -114.498276) (xy 12.024782 -114.449641) (xy 12.058868 -114.405498) (xy 12.099017 -114.366789)
			(xy 12.144375 -114.334338) (xy 12.193975 -114.308837) (xy 12.246759 -114.29083) (xy 12.301602 -114.2807)
			(xy 12.357336 -114.278663) (xy 12.412773 -114.284763) (xy 12.46673 -114.298869) (xy 12.518059 -114.320681)
			(xy 12.565665 -114.349735) (xy 12.608533 -114.38541) (xy 12.64575 -114.426947) (xy 12.676523 -114.47346)
			(xy 12.700195 -114.523957) (xy 12.716263 -114.577364) (xy 12.716862 -114.581432) (xy 66.299586 -114.581432)
			(xy 66.303657 -114.52581) (xy 66.315783 -114.471373) (xy 66.335706 -114.419282) (xy 66.363002 -114.370647)
			(xy 66.397088 -114.326504) (xy 66.437237 -114.287795) (xy 66.482595 -114.255344) (xy 66.532195 -114.229843)
			(xy 66.584979 -114.211836) (xy 66.639822 -114.201706) (xy 66.695556 -114.199669) (xy 66.750993 -114.205769)
			(xy 66.80495 -114.219875) (xy 66.856279 -114.241687) (xy 66.903885 -114.270741) (xy 66.946753 -114.306416)
			(xy 66.98397 -114.347953) (xy 67.014743 -114.394466) (xy 67.038415 -114.444963) (xy 67.054483 -114.49837)
			(xy 67.062603 -114.553546) (xy 67.063112 -114.581432) (xy 67.062603 -114.609318) (xy 67.054483 -114.664494)
			(xy 67.038415 -114.717901) (xy 67.014743 -114.768398) (xy 66.98397 -114.814911) (xy 66.946753 -114.856448)
			(xy 66.903885 -114.892123) (xy 66.856279 -114.921177) (xy 66.80495 -114.942989) (xy 66.750993 -114.957095)
			(xy 66.695556 -114.963195) (xy 66.639822 -114.961158) (xy 66.584979 -114.951028) (xy 66.532195 -114.933021)
			(xy 66.482595 -114.90752) (xy 66.437237 -114.875069) (xy 66.397088 -114.83636) (xy 66.363002 -114.792217)
			(xy 66.335706 -114.743582) (xy 66.315783 -114.691491) (xy 66.303657 -114.637054) (xy 66.299586 -114.581432)
			(xy 12.716862 -114.581432) (xy 12.724383 -114.63254) (xy 12.724892 -114.660426) (xy 12.724383 -114.688312)
			(xy 12.716263 -114.743488) (xy 12.700195 -114.796895) (xy 12.676523 -114.847392) (xy 12.64575 -114.893905)
			(xy 12.608533 -114.935442) (xy 12.565665 -114.971117) (xy 12.518059 -115.000171) (xy 12.46673 -115.021983)
			(xy 12.412773 -115.036089) (xy 12.357336 -115.042189) (xy 12.301602 -115.040152) (xy 12.246759 -115.030022)
			(xy 12.193975 -115.012015) (xy 12.144375 -114.986514) (xy 12.099017 -114.954063) (xy 12.058868 -114.915354)
			(xy 12.024782 -114.871211) (xy 11.997486 -114.822576) (xy 11.977563 -114.770485) (xy 11.965437 -114.716048)
			(xy 11.961366 -114.660426) (xy 4.38404 -114.660426) (xy 4.38404 -117.434106) (xy 13.37691 -117.434106)
			(xy 13.377377 -117.406736) (xy 13.385194 -117.352557) (xy 13.400683 -117.300053) (xy 13.423525 -117.250307)
			(xy 13.453249 -117.20434) (xy 13.47089 -117.183408) (xy 13.471144 -117.183154) (xy 13.476719 -117.17606)
			(xy 13.482972 -117.159149) (xy 13.483336 -117.150134) (xy 13.483336 -117.083078) (xy 13.482982 -117.074061)
			(xy 13.476732 -117.057144) (xy 13.471144 -117.050058) (xy 13.47089 -117.050058) (xy 13.47089 -117.049804)
			(xy 13.453257 -117.028866) (xy 13.423535 -116.982898) (xy 13.400691 -116.933152) (xy 13.385196 -116.880652)
			(xy 13.377368 -116.826474) (xy 13.377367 -116.771735) (xy 13.385194 -116.717557) (xy 13.400688 -116.665056)
			(xy 13.42353 -116.61531) (xy 13.453251 -116.569341) (xy 13.47089 -116.548408) (xy 13.471144 -116.548154)
			(xy 13.476719 -116.54106) (xy 13.482972 -116.524149) (xy 13.483336 -116.515134) (xy 13.483336 -116.448078)
			(xy 13.482982 -116.439061) (xy 13.476732 -116.422144) (xy 13.471144 -116.415058) (xy 13.47089 -116.415058)
			(xy 13.47089 -116.414804) (xy 13.453238 -116.393883) (xy 13.423528 -116.347907) (xy 13.400695 -116.298156)
			(xy 13.385207 -116.245653) (xy 13.377382 -116.191476) (xy 13.37691 -116.164106) (xy 13.377361 -116.136852)
			(xy 13.385118 -116.0829) (xy 13.400474 -116.030601) (xy 13.423117 -115.98102) (xy 13.452586 -115.935166)
			(xy 13.488281 -115.893972) (xy 13.529475 -115.858279) (xy 13.57533 -115.828811) (xy 13.624912 -115.80617)
			(xy 13.677212 -115.790815) (xy 13.731164 -115.78306) (xy 13.758418 -115.782598) (xy 13.785789 -115.783054)
			(xy 13.839968 -115.790874) (xy 13.892471 -115.806366) (xy 13.942218 -115.82921) (xy 13.988184 -115.858936)
			(xy 14.009116 -115.876578) (xy 14.00937 -115.876832) (xy 14.016458 -115.882416) (xy 14.033374 -115.888663)
			(xy 14.04239 -115.889024) (xy 14.109446 -115.889024) (xy 14.11846 -115.888636) (xy 14.135377 -115.882409)
			(xy 14.142466 -115.876832) (xy 14.142466 -115.876578) (xy 14.14272 -115.876578) (xy 14.163669 -115.85896)
			(xy 14.209637 -115.829245) (xy 14.259381 -115.806406) (xy 14.311877 -115.79091) (xy 14.36605 -115.783075)
			(xy 14.393418 -115.782598) (xy 14.42067 -115.783061) (xy 14.474619 -115.79082) (xy 14.526914 -115.806178)
			(xy 14.576492 -115.828822) (xy 14.622343 -115.85829) (xy 14.663533 -115.893984) (xy 14.699224 -115.935177)
			(xy 14.72869 -115.981029) (xy 14.75133 -116.030608) (xy 14.766685 -116.082905) (xy 14.774441 -116.136854)
			(xy 14.774926 -116.164106) (xy 14.774481 -116.191477) (xy 14.766661 -116.245658) (xy 14.751168 -116.298162)
			(xy 14.728321 -116.347909) (xy 14.69859 -116.393874) (xy 14.680946 -116.414804) (xy 14.680692 -116.415058)
			(xy 14.675116 -116.422152) (xy 14.668863 -116.439063) (xy 14.6685 -116.448078) (xy 14.6685 -116.515134)
			(xy 14.668841 -116.524152) (xy 14.6751 -116.541069) (xy 14.680692 -116.548154) (xy 14.680946 -116.548154)
			(xy 14.680946 -116.548408) (xy 14.698594 -116.569335) (xy 14.72832 -116.615303) (xy 14.751167 -116.66505)
			(xy 14.766664 -116.717554) (xy 14.774493 -116.771733) (xy 14.774492 -116.826476) (xy 14.766662 -116.880655)
			(xy 14.751164 -116.933158) (xy 14.728316 -116.982904) (xy 14.698588 -117.028872) (xy 14.680946 -117.049804)
			(xy 14.680692 -117.050058) (xy 14.675116 -117.057152) (xy 14.668863 -117.074063) (xy 14.6685 -117.083078)
			(xy 14.6685 -117.150134) (xy 14.668841 -117.159152) (xy 14.6751 -117.176069) (xy 14.680692 -117.183154)
			(xy 14.680946 -117.183154) (xy 14.680946 -117.183408) (xy 14.698594 -117.204333) (xy 14.728306 -117.250307)
			(xy 14.751141 -117.300056) (xy 14.76663 -117.352559) (xy 14.774454 -117.406736) (xy 14.774926 -117.434106)
			(xy 14.774786 -117.442234) (xy 15.659098 -117.442234) (xy 15.663169 -117.386612) (xy 15.675295 -117.332175)
			(xy 15.695218 -117.280084) (xy 15.722514 -117.231449) (xy 15.7566 -117.187306) (xy 15.796749 -117.148597)
			(xy 15.842107 -117.116146) (xy 15.891707 -117.090645) (xy 15.944491 -117.072638) (xy 15.999334 -117.062508)
			(xy 16.055068 -117.060471) (xy 16.110505 -117.066571) (xy 16.164462 -117.080677) (xy 16.215791 -117.102489)
			(xy 16.263397 -117.131543) (xy 16.306265 -117.167218) (xy 16.343482 -117.208755) (xy 16.374255 -117.255268)
			(xy 16.397927 -117.305765) (xy 16.413995 -117.359172) (xy 16.422115 -117.414348) (xy 16.422624 -117.442234)
			(xy 16.422115 -117.47012) (xy 16.413995 -117.525296) (xy 16.397927 -117.578703) (xy 16.374255 -117.6292)
			(xy 16.343482 -117.675713) (xy 16.306265 -117.71725) (xy 16.263397 -117.752925) (xy 16.215791 -117.781979)
			(xy 16.164462 -117.803791) (xy 16.110505 -117.817897) (xy 16.055068 -117.823997) (xy 15.999334 -117.82196)
			(xy 15.944491 -117.81183) (xy 15.891707 -117.793823) (xy 15.842107 -117.768322) (xy 15.796749 -117.735871)
			(xy 15.7566 -117.697162) (xy 15.722514 -117.653019) (xy 15.695218 -117.604384) (xy 15.675295 -117.552293)
			(xy 15.663169 -117.497856) (xy 15.659098 -117.442234) (xy 14.774786 -117.442234) (xy 14.774469 -117.460662)
			(xy 14.767101 -117.513262) (xy 14.752509 -117.564331) (xy 14.74216 -117.588792) (xy 14.737815 -117.600161)
			(xy 14.739162 -117.624433) (xy 14.7447 -117.635274) (xy 14.786102 -117.706394) (xy 14.792839 -117.716462)
			(xy 14.813244 -117.729453) (xy 14.825218 -117.731286) (xy 14.853196 -117.734495) (xy 14.90786 -117.748027)
			(xy 14.959939 -117.769449) (xy 15.008302 -117.798296) (xy 15.051898 -117.833941) (xy 15.089779 -117.875609)
			(xy 15.121122 -117.922394) (xy 15.145244 -117.973279) (xy 15.161622 -118.027158) (xy 15.167063 -118.063772)
			(xy 16.806162 -118.063772) (xy 16.810233 -118.00815) (xy 16.822359 -117.953713) (xy 16.842282 -117.901622)
			(xy 16.869578 -117.852987) (xy 16.903664 -117.808844) (xy 16.943813 -117.770135) (xy 16.989171 -117.737684)
			(xy 17.038771 -117.712183) (xy 17.091555 -117.694176) (xy 17.146398 -117.684046) (xy 17.202132 -117.682009)
			(xy 17.257569 -117.688109) (xy 17.311526 -117.702215) (xy 17.362855 -117.724027) (xy 17.410461 -117.753081)
			(xy 17.453329 -117.788756) (xy 17.490546 -117.830293) (xy 17.521319 -117.876806) (xy 17.544991 -117.927303)
			(xy 17.561059 -117.98071) (xy 17.567078 -118.021608) (xy 17.685512 -118.021608) (xy 17.68598 -117.994238)
			(xy 17.693797 -117.940059) (xy 17.709285 -117.887555) (xy 17.732127 -117.837809) (xy 17.761851 -117.791842)
			(xy 17.779492 -117.77091) (xy 17.779746 -117.770656) (xy 17.785321 -117.763562) (xy 17.791573 -117.746651)
			(xy 17.791938 -117.737636) (xy 17.791938 -117.67058) (xy 17.791582 -117.661563) (xy 17.785333 -117.644647)
			(xy 17.779746 -117.63756) (xy 17.779492 -117.63756) (xy 17.779492 -117.637306) (xy 17.761861 -117.616366)
			(xy 17.732138 -117.570399) (xy 17.709294 -117.520653) (xy 17.693799 -117.468153) (xy 17.68597 -117.413976)
			(xy 17.68597 -117.359236) (xy 17.693796 -117.305059) (xy 17.70929 -117.252558) (xy 17.732132 -117.202812)
			(xy 17.761853 -117.156843) (xy 17.779492 -117.13591) (xy 17.779746 -117.135656) (xy 17.785321 -117.128562)
			(xy 17.791573 -117.111651) (xy 17.791938 -117.102636) (xy 17.791938 -117.03558) (xy 17.791582 -117.026563)
			(xy 17.785333 -117.009647) (xy 17.779746 -117.00256) (xy 17.779492 -117.00256) (xy 17.779492 -117.002306)
			(xy 17.761841 -116.981384) (xy 17.732131 -116.935408) (xy 17.709298 -116.885658) (xy 17.693809 -116.833155)
			(xy 17.685984 -116.778978) (xy 17.685512 -116.751608) (xy 17.685963 -116.724354) (xy 17.693719 -116.670402)
			(xy 17.709075 -116.618103) (xy 17.731718 -116.568521) (xy 17.761187 -116.522667) (xy 17.796882 -116.481474)
			(xy 17.838077 -116.44578) (xy 17.883932 -116.416313) (xy 17.933514 -116.393671) (xy 17.985814 -116.378317)
			(xy 18.039766 -116.370562) (xy 18.06702 -116.3701) (xy 18.094391 -116.370554) (xy 18.14857 -116.378375)
			(xy 18.201073 -116.393867) (xy 18.25082 -116.416711) (xy 18.296787 -116.446438) (xy 18.317718 -116.46408)
			(xy 18.317972 -116.464334) (xy 18.32506 -116.469919) (xy 18.341976 -116.476165) (xy 18.350992 -116.476526)
			(xy 18.418048 -116.476526) (xy 18.427062 -116.476139) (xy 18.443979 -116.469912) (xy 18.451068 -116.464334)
			(xy 18.451068 -116.46408) (xy 18.451322 -116.46408) (xy 18.47227 -116.446461) (xy 18.518239 -116.416747)
			(xy 18.567982 -116.393907) (xy 18.620479 -116.378411) (xy 18.674652 -116.370577) (xy 18.70202 -116.3701)
			(xy 18.729272 -116.370559) (xy 18.783221 -116.378319) (xy 18.835517 -116.393677) (xy 18.885095 -116.416321)
			(xy 18.930945 -116.44579) (xy 18.972136 -116.481484) (xy 19.007827 -116.522677) (xy 19.018865 -116.539853)
			(xy 36.544449 -116.539853) (xy 36.544449 -116.485347) (xy 36.552207 -116.431394) (xy 36.567563 -116.379095)
			(xy 36.590206 -116.329514) (xy 36.619675 -116.28366) (xy 36.65537 -116.242467) (xy 36.696563 -116.206773)
			(xy 36.742418 -116.177304) (xy 36.791999 -116.154662) (xy 36.844298 -116.139306) (xy 36.898251 -116.131549)
			(xy 36.925504 -116.131086) (xy 36.951818 -116.131555) (xy 37.003946 -116.13879) (xy 37.054589 -116.153109)
			(xy 37.102788 -116.174242) (xy 37.147631 -116.201787) (xy 37.188271 -116.235225) (xy 37.206428 -116.254276)
			(xy 37.21394 -116.261688) (xy 37.233227 -116.270208) (xy 37.243766 -116.270786) (xy 37.318442 -116.270786)
			(xy 37.32899 -116.270243) (xy 37.348286 -116.261718) (xy 37.35578 -116.254276) (xy 37.372776 -116.236393)
			(xy 37.410614 -116.204732) (xy 37.452222 -116.17822) (xy 37.474398 -116.167408) (xy 37.484558 -116.162582)
			(xy 37.498782 -116.145818) (xy 37.525198 -116.049044) (xy 37.521642 -116.027708) (xy 37.515292 -116.018564)
			(xy 37.515292 -116.01831) (xy 37.499726 -115.994464) (xy 37.475069 -115.943134) (xy 37.458304 -115.888713)
			(xy 37.449802 -115.832406) (xy 37.449252 -115.803934) (xy 37.449827 -115.775043) (xy 37.458508 -115.717917)
			(xy 37.475707 -115.662754) (xy 37.501031 -115.610817) (xy 37.5339 -115.563294) (xy 37.573561 -115.521273)
			(xy 37.619107 -115.485716) (xy 37.669495 -115.457436) (xy 37.723573 -115.437081) (xy 37.780103 -115.425117)
			(xy 37.808916 -115.422934) (xy 37.819838 -115.422426) (xy 37.839142 -115.412266) (xy 37.899848 -115.335304)
			(xy 37.905182 -115.314222) (xy 37.90315 -115.303554) (xy 37.900308 -115.286807) (xy 37.897252 -115.252975)
			(xy 37.897054 -115.23599) (xy 37.897054 -115.235228) (xy 37.89754 -115.207977) (xy 37.905296 -115.154029)
			(xy 37.920651 -115.101734) (xy 37.943293 -115.052157) (xy 37.972759 -115.006307) (xy 38.00845 -114.965116)
			(xy 38.049641 -114.929425) (xy 38.095491 -114.899959) (xy 38.145068 -114.877317) (xy 38.197363 -114.861962)
			(xy 38.251311 -114.854206) (xy 38.305813 -114.854206) (xy 38.359761 -114.861962) (xy 38.412056 -114.877317)
			(xy 38.461633 -114.899959) (xy 38.507483 -114.929425) (xy 38.548674 -114.965116) (xy 38.584365 -115.006307)
			(xy 38.613831 -115.052157) (xy 38.636473 -115.101734) (xy 38.651828 -115.154029) (xy 38.659584 -115.207977)
			(xy 38.66007 -115.235228) (xy 38.659626 -115.264125) (xy 38.650934 -115.32126) (xy 38.633722 -115.37643)
			(xy 38.608384 -115.428372) (xy 38.575501 -115.475897) (xy 38.535825 -115.517919) (xy 38.490263 -115.553474)
			(xy 38.449937 -115.576096) (xy 55.847232 -115.576096) (xy 55.851303 -115.520474) (xy 55.863429 -115.466037)
			(xy 55.883352 -115.413946) (xy 55.910648 -115.365311) (xy 55.944734 -115.321168) (xy 55.984883 -115.282459)
			(xy 56.030241 -115.250008) (xy 56.079841 -115.224507) (xy 56.132625 -115.2065) (xy 56.187468 -115.19637)
			(xy 56.243202 -115.194333) (xy 56.298639 -115.200433) (xy 56.352596 -115.214539) (xy 56.403925 -115.236351)
			(xy 56.451531 -115.265405) (xy 56.476007 -115.285774) (xy 66.930776 -115.285774) (xy 66.934847 -115.230152)
			(xy 66.946973 -115.175715) (xy 66.966896 -115.123624) (xy 66.994192 -115.074989) (xy 67.028278 -115.030846)
			(xy 67.068427 -114.992137) (xy 67.113785 -114.959686) (xy 67.163385 -114.934185) (xy 67.216169 -114.916178)
			(xy 67.271012 -114.906048) (xy 67.326746 -114.904011) (xy 67.382183 -114.910111) (xy 67.43614 -114.924217)
			(xy 67.487469 -114.946029) (xy 67.535075 -114.975083) (xy 67.577943 -115.010758) (xy 67.61516 -115.052295)
			(xy 67.645933 -115.098808) (xy 67.669605 -115.149305) (xy 67.685673 -115.202712) (xy 67.693793 -115.257888)
			(xy 67.694302 -115.285774) (xy 67.693793 -115.31366) (xy 67.686832 -115.360958) (xy 74.11847 -115.360958)
			(xy 74.118953 -115.333588) (xy 74.126764 -115.279409) (xy 74.142248 -115.226906) (xy 74.165087 -115.177158)
			(xy 74.194809 -115.131191) (xy 74.21245 -115.11026) (xy 74.212704 -115.110006) (xy 74.218295 -115.102922)
			(xy 74.224539 -115.086003) (xy 74.224896 -115.076986) (xy 74.224896 -115.00993) (xy 74.224526 -115.000914)
			(xy 74.218288 -114.983997) (xy 74.212704 -114.97691) (xy 74.21245 -114.97691) (xy 74.21245 -114.976656)
			(xy 74.194831 -114.955707) (xy 74.165115 -114.90974) (xy 74.142274 -114.859997) (xy 74.126778 -114.807499)
			(xy 74.118946 -114.753326) (xy 74.11847 -114.725958) (xy 74.118939 -114.698707) (xy 74.1267 -114.64476)
			(xy 74.14206 -114.592466) (xy 74.164704 -114.54289) (xy 74.194173 -114.497041) (xy 74.229866 -114.455852)
			(xy 74.271057 -114.420161) (xy 74.316907 -114.390694) (xy 74.366485 -114.368053) (xy 74.418779 -114.352696)
			(xy 74.472727 -114.344937) (xy 74.499978 -114.34445) (xy 74.527348 -114.344917) (xy 74.581528 -114.352733)
			(xy 74.634031 -114.368221) (xy 74.683778 -114.391063) (xy 74.729745 -114.420788) (xy 74.750676 -114.43843)
			(xy 74.75093 -114.438684) (xy 74.758034 -114.444246) (xy 74.774937 -114.450508) (xy 74.78395 -114.450876)
			(xy 74.851006 -114.450876) (xy 74.860024 -114.450527) (xy 74.876941 -114.444275) (xy 74.884026 -114.438684)
			(xy 74.884026 -114.43843) (xy 74.88428 -114.43843) (xy 74.905213 -114.420791) (xy 74.951185 -114.391079)
			(xy 75.000932 -114.368242) (xy 75.053433 -114.352751) (xy 75.107609 -114.344923) (xy 75.134978 -114.34445)
			(xy 75.162227 -114.344999) (xy 75.21617 -114.352751) (xy 75.268461 -114.368101) (xy 75.318035 -114.390737)
			(xy 75.363884 -114.420197) (xy 75.405073 -114.455882) (xy 75.440765 -114.497065) (xy 75.470233 -114.542909)
			(xy 75.492876 -114.592479) (xy 75.508235 -114.644767) (xy 75.515997 -114.698709) (xy 75.516486 -114.725958)
			(xy 75.515999 -114.753328) (xy 75.508187 -114.807506) (xy 75.492703 -114.860009) (xy 75.469866 -114.909756)
			(xy 75.440145 -114.955724) (xy 75.422506 -114.976656) (xy 75.422252 -114.97691) (xy 75.416649 -114.983985)
			(xy 75.410413 -115.000911) (xy 75.41006 -115.00993) (xy 75.41006 -115.076986) (xy 75.410411 -115.086004)
			(xy 75.416661 -115.102921) (xy 75.422252 -115.110006) (xy 75.422506 -115.110006) (xy 75.422506 -115.11026)
			(xy 75.440141 -115.131196) (xy 75.469853 -115.177167) (xy 75.49269 -115.226914) (xy 75.508182 -115.279414)
			(xy 75.516011 -115.333589) (xy 75.516486 -115.360958) (xy 75.516006 -115.388211) (xy 75.514192 -115.400836)
			(xy 87.260682 -115.400836) (xy 87.264753 -115.345214) (xy 87.276879 -115.290777) (xy 87.296802 -115.238686)
			(xy 87.324098 -115.190051) (xy 87.358184 -115.145908) (xy 87.398333 -115.107199) (xy 87.443691 -115.074748)
			(xy 87.493291 -115.049247) (xy 87.546075 -115.03124) (xy 87.600918 -115.02111) (xy 87.656652 -115.019073)
			(xy 87.712089 -115.025173) (xy 87.766046 -115.039279) (xy 87.817375 -115.061091) (xy 87.864981 -115.090145)
			(xy 87.907849 -115.12582) (xy 87.945066 -115.167357) (xy 87.975839 -115.21387) (xy 87.999511 -115.264367)
			(xy 88.015579 -115.317774) (xy 88.023317 -115.370356) (xy 89.361262 -115.370356) (xy 89.365333 -115.314734)
			(xy 89.377459 -115.260297) (xy 89.397382 -115.208206) (xy 89.424678 -115.159571) (xy 89.458764 -115.115428)
			(xy 89.498913 -115.076719) (xy 89.544271 -115.044268) (xy 89.593871 -115.018767) (xy 89.646655 -115.00076)
			(xy 89.701498 -114.99063) (xy 89.757232 -114.988593) (xy 89.812669 -114.994693) (xy 89.866626 -115.008799)
			(xy 89.917955 -115.030611) (xy 89.965561 -115.059665) (xy 90.008429 -115.09534) (xy 90.045646 -115.136877)
			(xy 90.076419 -115.18339) (xy 90.100091 -115.233887) (xy 90.116159 -115.287294) (xy 90.124279 -115.34247)
			(xy 90.124788 -115.370356) (xy 90.124279 -115.398242) (xy 90.116159 -115.453418) (xy 90.100091 -115.506825)
			(xy 90.076419 -115.557322) (xy 90.045646 -115.603835) (xy 90.008429 -115.645372) (xy 89.965561 -115.681047)
			(xy 89.917955 -115.710101) (xy 89.866626 -115.731913) (xy 89.812669 -115.746019) (xy 89.757232 -115.752119)
			(xy 89.701498 -115.750082) (xy 89.646655 -115.739952) (xy 89.593871 -115.721945) (xy 89.544271 -115.696444)
			(xy 89.498913 -115.663993) (xy 89.458764 -115.625284) (xy 89.424678 -115.581141) (xy 89.397382 -115.532506)
			(xy 89.377459 -115.480415) (xy 89.365333 -115.425978) (xy 89.361262 -115.370356) (xy 88.023317 -115.370356)
			(xy 88.023699 -115.37295) (xy 88.024208 -115.400836) (xy 88.023699 -115.428722) (xy 88.015579 -115.483898)
			(xy 87.999511 -115.537305) (xy 87.975839 -115.587802) (xy 87.945066 -115.634315) (xy 87.907849 -115.675852)
			(xy 87.864981 -115.711527) (xy 87.817375 -115.740581) (xy 87.766046 -115.762393) (xy 87.712089 -115.776499)
			(xy 87.656652 -115.782599) (xy 87.600918 -115.780562) (xy 87.546075 -115.770432) (xy 87.493291 -115.752425)
			(xy 87.443691 -115.726924) (xy 87.398333 -115.694473) (xy 87.358184 -115.655764) (xy 87.324098 -115.611621)
			(xy 87.296802 -115.562986) (xy 87.276879 -115.510895) (xy 87.264753 -115.456458) (xy 87.260682 -115.400836)
			(xy 75.514192 -115.400836) (xy 75.508254 -115.442162) (xy 75.492902 -115.494461) (xy 75.470263 -115.544043)
			(xy 75.440797 -115.589897) (xy 75.405105 -115.631091) (xy 75.363913 -115.666785) (xy 75.31806 -115.696253)
			(xy 75.26848 -115.718895) (xy 75.216182 -115.734249) (xy 75.162231 -115.742004) (xy 75.134978 -115.742466)
			(xy 75.107607 -115.742021) (xy 75.053427 -115.734199) (xy 75.000923 -115.718706) (xy 74.951176 -115.695859)
			(xy 74.905211 -115.66613) (xy 74.88428 -115.648486) (xy 74.884026 -115.648232) (xy 74.876942 -115.642642)
			(xy 74.860023 -115.636399) (xy 74.851006 -115.63604) (xy 74.78395 -115.63604) (xy 74.774934 -115.636412)
			(xy 74.758017 -115.642648) (xy 74.75093 -115.648232) (xy 74.75093 -115.648486) (xy 74.750676 -115.648486)
			(xy 74.729724 -115.666101) (xy 74.683757 -115.695817) (xy 74.634015 -115.718658) (xy 74.581518 -115.734154)
			(xy 74.527346 -115.741989) (xy 74.499978 -115.742466) (xy 74.472723 -115.742065) (xy 74.418767 -115.734304)
			(xy 74.366466 -115.718943) (xy 74.316883 -115.696295) (xy 74.271027 -115.666821) (xy 74.229834 -115.631121)
			(xy 74.194141 -115.589921) (xy 74.164674 -115.544061) (xy 74.142034 -115.494474) (xy 74.126682 -115.44217)
			(xy 74.11893 -115.388213) (xy 74.11847 -115.360958) (xy 67.686832 -115.360958) (xy 67.685673 -115.368836)
			(xy 67.669605 -115.422243) (xy 67.645933 -115.47274) (xy 67.61516 -115.519253) (xy 67.577943 -115.56079)
			(xy 67.535075 -115.596465) (xy 67.487469 -115.625519) (xy 67.43614 -115.647331) (xy 67.382183 -115.661437)
			(xy 67.326746 -115.667537) (xy 67.271012 -115.6655) (xy 67.216169 -115.65537) (xy 67.163385 -115.637363)
			(xy 67.113785 -115.611862) (xy 67.068427 -115.579411) (xy 67.028278 -115.540702) (xy 66.994192 -115.496559)
			(xy 66.966896 -115.447924) (xy 66.946973 -115.395833) (xy 66.934847 -115.341396) (xy 66.930776 -115.285774)
			(xy 56.476007 -115.285774) (xy 56.494399 -115.30108) (xy 56.531616 -115.342617) (xy 56.562389 -115.38913)
			(xy 56.586061 -115.439627) (xy 56.602129 -115.493034) (xy 56.610249 -115.54821) (xy 56.610758 -115.576096)
			(xy 56.610249 -115.603982) (xy 56.602129 -115.659158) (xy 56.586061 -115.712565) (xy 56.562389 -115.763062)
			(xy 56.531616 -115.809575) (xy 56.494399 -115.851112) (xy 56.451531 -115.886787) (xy 56.403925 -115.915841)
			(xy 56.389328 -115.922044) (xy 63.203326 -115.922044) (xy 63.207397 -115.866422) (xy 63.219523 -115.811985)
			(xy 63.239446 -115.759894) (xy 63.266742 -115.711259) (xy 63.300828 -115.667116) (xy 63.340977 -115.628407)
			(xy 63.386335 -115.595956) (xy 63.435935 -115.570455) (xy 63.488719 -115.552448) (xy 63.543562 -115.542318)
			(xy 63.599296 -115.540281) (xy 63.654733 -115.546381) (xy 63.70869 -115.560487) (xy 63.760019 -115.582299)
			(xy 63.807625 -115.611353) (xy 63.850493 -115.647028) (xy 63.88771 -115.688565) (xy 63.918483 -115.735078)
			(xy 63.942155 -115.785575) (xy 63.958223 -115.838982) (xy 63.966343 -115.894158) (xy 63.966852 -115.922044)
			(xy 63.966343 -115.94993) (xy 63.958223 -116.005106) (xy 63.942155 -116.058513) (xy 63.918483 -116.10901)
			(xy 63.88771 -116.155523) (xy 63.850493 -116.19706) (xy 63.807625 -116.232735) (xy 63.760019 -116.261789)
			(xy 63.70869 -116.283601) (xy 63.654733 -116.297707) (xy 63.599296 -116.303807) (xy 63.543562 -116.30177)
			(xy 63.488719 -116.29164) (xy 63.435935 -116.273633) (xy 63.386335 -116.248132) (xy 63.340977 -116.215681)
			(xy 63.300828 -116.176972) (xy 63.266742 -116.132829) (xy 63.239446 -116.084194) (xy 63.219523 -116.032103)
			(xy 63.207397 -115.977666) (xy 63.203326 -115.922044) (xy 56.389328 -115.922044) (xy 56.352596 -115.937653)
			(xy 56.298639 -115.951759) (xy 56.243202 -115.957859) (xy 56.187468 -115.955822) (xy 56.132625 -115.945692)
			(xy 56.079841 -115.927685) (xy 56.030241 -115.902184) (xy 55.984883 -115.869733) (xy 55.944734 -115.831024)
			(xy 55.910648 -115.786881) (xy 55.883352 -115.738246) (xy 55.863429 -115.686155) (xy 55.851303 -115.631718)
			(xy 55.847232 -115.576096) (xy 38.449937 -115.576096) (xy 38.43986 -115.581749) (xy 38.385768 -115.602096)
			(xy 38.329225 -115.614052) (xy 38.300406 -115.616228) (xy 38.289484 -115.616736) (xy 38.27018 -115.626896)
			(xy 38.209474 -115.703858) (xy 38.20414 -115.72494) (xy 38.206172 -115.735608) (xy 38.209022 -115.752353)
			(xy 38.212073 -115.786187) (xy 38.212268 -115.803172) (xy 38.212268 -115.803934) (xy 38.211754 -115.830915)
			(xy 38.204134 -115.884336) (xy 38.189064 -115.936152) (xy 38.166846 -115.985327) (xy 38.137922 -116.030883)
			(xy 38.102869 -116.07191) (xy 38.062387 -116.10759) (xy 38.017282 -116.137212) (xy 37.993066 -116.14912)
			(xy 37.982906 -116.153946) (xy 37.968682 -116.17071) (xy 37.942266 -116.267484) (xy 37.945822 -116.28882)
			(xy 37.952172 -116.297964) (xy 37.952172 -116.298218) (xy 37.967757 -116.322053) (xy 37.992408 -116.373387)
			(xy 38.009167 -116.427812) (xy 38.012148 -116.44757) (xy 66.157092 -116.44757) (xy 66.161163 -116.391948)
			(xy 66.173289 -116.337511) (xy 66.193212 -116.28542) (xy 66.220508 -116.236785) (xy 66.254594 -116.192642)
			(xy 66.294743 -116.153933) (xy 66.340101 -116.121482) (xy 66.389701 -116.095981) (xy 66.442485 -116.077974)
			(xy 66.497328 -116.067844) (xy 66.553062 -116.065807) (xy 66.608499 -116.071907) (xy 66.662456 -116.086013)
			(xy 66.713785 -116.107825) (xy 66.761391 -116.136879) (xy 66.804259 -116.172554) (xy 66.841476 -116.214091)
			(xy 66.872249 -116.260604) (xy 66.895921 -116.311101) (xy 66.911989 -116.364508) (xy 66.920109 -116.419684)
			(xy 66.920618 -116.44757) (xy 66.920109 -116.475456) (xy 66.919839 -116.477288) (xy 71.304402 -116.477288)
			(xy 71.308473 -116.421666) (xy 71.320599 -116.367229) (xy 71.340522 -116.315138) (xy 71.367818 -116.266503)
			(xy 71.401904 -116.22236) (xy 71.442053 -116.183651) (xy 71.487411 -116.1512) (xy 71.537011 -116.125699)
			(xy 71.589795 -116.107692) (xy 71.644638 -116.097562) (xy 71.700372 -116.095525) (xy 71.755809 -116.101625)
			(xy 71.809766 -116.115731) (xy 71.861095 -116.137543) (xy 71.908701 -116.166597) (xy 71.951569 -116.202272)
			(xy 71.988786 -116.243809) (xy 72.019559 -116.290322) (xy 72.043231 -116.340819) (xy 72.059299 -116.394226)
			(xy 72.067419 -116.449402) (xy 72.067928 -116.477288) (xy 72.067419 -116.505174) (xy 72.059299 -116.56035)
			(xy 72.043231 -116.613757) (xy 72.019559 -116.664254) (xy 71.988786 -116.710767) (xy 71.951569 -116.752304)
			(xy 71.908701 -116.787979) (xy 71.861095 -116.817033) (xy 71.809766 -116.838845) (xy 71.755809 -116.852951)
			(xy 71.700372 -116.859051) (xy 71.644638 -116.857014) (xy 71.589795 -116.846884) (xy 71.537011 -116.828877)
			(xy 71.487411 -116.803376) (xy 71.442053 -116.770925) (xy 71.401904 -116.732216) (xy 71.367818 -116.688073)
			(xy 71.340522 -116.639438) (xy 71.320599 -116.587347) (xy 71.308473 -116.53291) (xy 71.304402 -116.477288)
			(xy 66.919839 -116.477288) (xy 66.911989 -116.530632) (xy 66.895921 -116.584039) (xy 66.872249 -116.634536)
			(xy 66.841476 -116.681049) (xy 66.804259 -116.722586) (xy 66.761391 -116.758261) (xy 66.713785 -116.787315)
			(xy 66.662456 -116.809127) (xy 66.608499 -116.823233) (xy 66.553062 -116.829333) (xy 66.497328 -116.827296)
			(xy 66.442485 -116.817166) (xy 66.389701 -116.799159) (xy 66.340101 -116.773658) (xy 66.294743 -116.741207)
			(xy 66.254594 -116.702498) (xy 66.220508 -116.658355) (xy 66.193212 -116.60972) (xy 66.173289 -116.557629)
			(xy 66.161163 -116.503192) (xy 66.157092 -116.44757) (xy 38.012148 -116.44757) (xy 38.017664 -116.484121)
			(xy 38.018212 -116.512594) (xy 38.017739 -116.539847) (xy 38.009983 -116.593797) (xy 37.994628 -116.646094)
			(xy 37.971986 -116.695674) (xy 37.942519 -116.741527) (xy 37.906827 -116.78272) (xy 37.865635 -116.818413)
			(xy 37.819783 -116.847882) (xy 37.770204 -116.870524) (xy 37.717907 -116.885881) (xy 37.663957 -116.893638)
			(xy 37.636704 -116.894102) (xy 37.61039 -116.893631) (xy 37.558262 -116.886397) (xy 37.507619 -116.872079)
			(xy 37.45942 -116.850947) (xy 37.414577 -116.823401) (xy 37.373937 -116.789963) (xy 37.35578 -116.770912)
			(xy 37.348266 -116.763501) (xy 37.32898 -116.754982) (xy 37.318442 -116.754402) (xy 37.243766 -116.754402)
			(xy 37.233219 -116.754953) (xy 37.213923 -116.763473) (xy 37.206428 -116.770912) (xy 37.188254 -116.789949)
			(xy 37.147628 -116.823408) (xy 37.102792 -116.850969) (xy 37.054594 -116.87211) (xy 37.00395 -116.886431)
			(xy 36.951819 -116.893661) (xy 36.925504 -116.894102) (xy 36.898251 -116.893651) (xy 36.844298 -116.885894)
			(xy 36.791999 -116.870538) (xy 36.742418 -116.847896) (xy 36.696563 -116.818427) (xy 36.65537 -116.782733)
			(xy 36.619675 -116.74154) (xy 36.590206 -116.695686) (xy 36.567563 -116.646105) (xy 36.552207 -116.593806)
			(xy 36.544449 -116.539853) (xy 19.018865 -116.539853) (xy 19.037293 -116.56853) (xy 19.059933 -116.618109)
			(xy 19.075287 -116.670406) (xy 19.083043 -116.724356) (xy 19.083528 -116.751608) (xy 19.083084 -116.778979)
			(xy 19.075264 -116.83316) (xy 19.05977 -116.885664) (xy 19.036923 -116.935411) (xy 19.007192 -116.981376)
			(xy 18.989548 -117.002306) (xy 18.989294 -117.00256) (xy 18.983717 -117.009653) (xy 18.977465 -117.026565)
			(xy 18.977102 -117.03558) (xy 18.977102 -117.102636) (xy 18.977442 -117.111655) (xy 18.983701 -117.128571)
			(xy 18.989294 -117.135656) (xy 18.989548 -117.135656) (xy 18.989548 -117.13591) (xy 19.007198 -117.156836)
			(xy 19.036924 -117.202804) (xy 19.05977 -117.252551) (xy 19.075267 -117.305055) (xy 19.083095 -117.359235)
			(xy 19.083095 -117.413977) (xy 19.075265 -117.468157) (xy 19.059766 -117.52066) (xy 19.036918 -117.570406)
			(xy 19.00719 -117.616374) (xy 18.989548 -117.637306) (xy 18.989294 -117.63756) (xy 18.983717 -117.644653)
			(xy 18.977465 -117.661565) (xy 18.977102 -117.67058) (xy 18.977102 -117.737636) (xy 18.977442 -117.746655)
			(xy 18.980308 -117.7544) (xy 37.088062 -117.7544) (xy 37.092133 -117.698778) (xy 37.104259 -117.644341)
			(xy 37.124182 -117.59225) (xy 37.151478 -117.543615) (xy 37.185564 -117.499472) (xy 37.225713 -117.460763)
			(xy 37.271071 -117.428312) (xy 37.320671 -117.402811) (xy 37.373455 -117.384804) (xy 37.428298 -117.374674)
			(xy 37.484032 -117.372637) (xy 37.539469 -117.378737) (xy 37.593426 -117.392843) (xy 37.644755 -117.414655)
			(xy 37.692361 -117.443709) (xy 37.735229 -117.479384) (xy 37.772446 -117.520921) (xy 37.803219 -117.567434)
			(xy 37.826891 -117.617931) (xy 37.842959 -117.671338) (xy 37.85066 -117.723666) (xy 69.689724 -117.723666)
			(xy 69.693795 -117.668044) (xy 69.705921 -117.613607) (xy 69.725844 -117.561516) (xy 69.75314 -117.512881)
			(xy 69.787226 -117.468738) (xy 69.827375 -117.430029) (xy 69.872733 -117.397578) (xy 69.922333 -117.372077)
			(xy 69.975117 -117.35407) (xy 70.02996 -117.34394) (xy 70.085694 -117.341903) (xy 70.141131 -117.348003)
			(xy 70.195088 -117.362109) (xy 70.246417 -117.383921) (xy 70.294023 -117.412975) (xy 70.336891 -117.44865)
			(xy 70.374108 -117.490187) (xy 70.404881 -117.5367) (xy 70.428553 -117.587197) (xy 70.444621 -117.640604)
			(xy 70.452741 -117.69578) (xy 70.45325 -117.723666) (xy 70.452741 -117.751552) (xy 70.451686 -117.758718)
			(xy 74.474832 -117.758718) (xy 74.474832 -116.895118) (xy 74.475322 -116.865134) (xy 74.48315 -116.805678)
			(xy 74.498671 -116.747753) (xy 74.52162 -116.692349) (xy 74.551604 -116.640415) (xy 74.58811 -116.592839)
			(xy 74.630515 -116.550434) (xy 74.678091 -116.513928) (xy 74.730025 -116.483944) (xy 74.785429 -116.460995)
			(xy 74.843354 -116.445474) (xy 74.90281 -116.437646) (xy 74.962778 -116.437646) (xy 75.022234 -116.445474)
			(xy 75.080159 -116.460995) (xy 75.135563 -116.483944) (xy 75.187497 -116.513928) (xy 75.235073 -116.550434)
			(xy 75.277478 -116.592839) (xy 75.313984 -116.640415) (xy 75.330961 -116.66982) (xy 89.3732 -116.66982)
			(xy 89.377271 -116.614198) (xy 89.389397 -116.559761) (xy 89.40932 -116.50767) (xy 89.436616 -116.459035)
			(xy 89.470702 -116.414892) (xy 89.510851 -116.376183) (xy 89.556209 -116.343732) (xy 89.605809 -116.318231)
			(xy 89.658593 -116.300224) (xy 89.713436 -116.290094) (xy 89.76917 -116.288057) (xy 89.824607 -116.294157)
			(xy 89.878564 -116.308263) (xy 89.929893 -116.330075) (xy 89.977499 -116.359129) (xy 90.020367 -116.394804)
			(xy 90.057584 -116.436341) (xy 90.088357 -116.482854) (xy 90.112029 -116.533351) (xy 90.128097 -116.586758)
			(xy 90.136217 -116.641934) (xy 90.136726 -116.66982) (xy 90.136217 -116.697706) (xy 90.128097 -116.752882)
			(xy 90.112029 -116.806289) (xy 90.088357 -116.856786) (xy 90.057584 -116.903299) (xy 90.020367 -116.944836)
			(xy 89.977499 -116.980511) (xy 89.929893 -117.009565) (xy 89.878564 -117.031377) (xy 89.824607 -117.045483)
			(xy 89.76917 -117.051583) (xy 89.713436 -117.049546) (xy 89.658593 -117.039416) (xy 89.605809 -117.021409)
			(xy 89.556209 -116.995908) (xy 89.510851 -116.963457) (xy 89.470702 -116.924748) (xy 89.436616 -116.880605)
			(xy 89.40932 -116.83197) (xy 89.389397 -116.779879) (xy 89.377271 -116.725442) (xy 89.3732 -116.66982)
			(xy 75.330961 -116.66982) (xy 75.343968 -116.692349) (xy 75.366917 -116.747753) (xy 75.382438 -116.805678)
			(xy 75.390266 -116.865134) (xy 75.390756 -116.895118) (xy 75.390756 -117.758718) (xy 75.390266 -117.788702)
			(xy 75.382438 -117.848158) (xy 75.366917 -117.906083) (xy 75.343968 -117.961487) (xy 75.313984 -118.013421)
			(xy 75.277478 -118.060997) (xy 75.235073 -118.103402) (xy 75.187497 -118.139908) (xy 75.135563 -118.169892)
			(xy 75.080159 -118.192841) (xy 75.022234 -118.208362) (xy 74.962778 -118.21619) (xy 74.90281 -118.21619)
			(xy 74.843354 -118.208362) (xy 74.785429 -118.192841) (xy 74.730025 -118.169892) (xy 74.678091 -118.139908)
			(xy 74.630515 -118.103402) (xy 74.58811 -118.060997) (xy 74.551604 -118.013421) (xy 74.52162 -117.961487)
			(xy 74.498671 -117.906083) (xy 74.48315 -117.848158) (xy 74.475322 -117.788702) (xy 74.474832 -117.758718)
			(xy 70.451686 -117.758718) (xy 70.444621 -117.806728) (xy 70.428553 -117.860135) (xy 70.404881 -117.910632)
			(xy 70.374108 -117.957145) (xy 70.336891 -117.998682) (xy 70.294023 -118.034357) (xy 70.246417 -118.063411)
			(xy 70.195088 -118.085223) (xy 70.141131 -118.099329) (xy 70.085694 -118.105429) (xy 70.02996 -118.103392)
			(xy 69.975117 -118.093262) (xy 69.922333 -118.075255) (xy 69.872733 -118.049754) (xy 69.827375 -118.017303)
			(xy 69.787226 -117.978594) (xy 69.75314 -117.934451) (xy 69.725844 -117.885816) (xy 69.705921 -117.833725)
			(xy 69.693795 -117.779288) (xy 69.689724 -117.723666) (xy 37.85066 -117.723666) (xy 37.851079 -117.726514)
			(xy 37.851588 -117.7544) (xy 37.851079 -117.782286) (xy 37.842959 -117.837462) (xy 37.826891 -117.890869)
			(xy 37.803219 -117.941366) (xy 37.772446 -117.987879) (xy 37.735229 -118.029416) (xy 37.692361 -118.065091)
			(xy 37.644755 -118.094145) (xy 37.593426 -118.115957) (xy 37.539469 -118.130063) (xy 37.484032 -118.136163)
			(xy 37.428298 -118.134126) (xy 37.373455 -118.123996) (xy 37.320671 -118.105989) (xy 37.271071 -118.080488)
			(xy 37.225713 -118.048037) (xy 37.185564 -118.009328) (xy 37.151478 -117.965185) (xy 37.124182 -117.91655)
			(xy 37.104259 -117.864459) (xy 37.092133 -117.810022) (xy 37.088062 -117.7544) (xy 18.980308 -117.7544)
			(xy 18.983701 -117.763571) (xy 18.989294 -117.770656) (xy 18.989548 -117.770656) (xy 18.989548 -117.77091)
			(xy 19.007197 -117.791834) (xy 19.036909 -117.837808) (xy 19.059744 -117.887558) (xy 19.075233 -117.94006)
			(xy 19.083057 -117.994238) (xy 19.083528 -118.021608) (xy 19.08303 -118.048859) (xy 19.075273 -118.102805)
			(xy 19.059918 -118.155098) (xy 19.037277 -118.204674) (xy 19.007812 -118.250523) (xy 18.992679 -118.267988)
			(xy 55.586628 -118.267988) (xy 55.590699 -118.212366) (xy 55.602825 -118.157929) (xy 55.622748 -118.105838)
			(xy 55.650044 -118.057203) (xy 55.68413 -118.01306) (xy 55.724279 -117.974351) (xy 55.769637 -117.9419)
			(xy 55.819237 -117.916399) (xy 55.872021 -117.898392) (xy 55.926864 -117.888262) (xy 55.982598 -117.886225)
			(xy 56.038035 -117.892325) (xy 56.091992 -117.906431) (xy 56.143321 -117.928243) (xy 56.190927 -117.957297)
			(xy 56.233795 -117.992972) (xy 56.271012 -118.034509) (xy 56.301785 -118.081022) (xy 56.325457 -118.131519)
			(xy 56.341525 -118.184926) (xy 56.349645 -118.240102) (xy 56.350154 -118.267988) (xy 56.349645 -118.295874)
			(xy 56.344329 -118.331996) (xy 62.895732 -118.331996) (xy 62.899803 -118.276374) (xy 62.911929 -118.221937)
			(xy 62.931852 -118.169846) (xy 62.959148 -118.121211) (xy 62.993234 -118.077068) (xy 63.033383 -118.038359)
			(xy 63.078741 -118.005908) (xy 63.128341 -117.980407) (xy 63.181125 -117.9624) (xy 63.235968 -117.95227)
			(xy 63.291702 -117.950233) (xy 63.347139 -117.956333) (xy 63.401096 -117.970439) (xy 63.452425 -117.992251)
			(xy 63.500031 -118.021305) (xy 63.542899 -118.05698) (xy 63.580116 -118.098517) (xy 63.610889 -118.14503)
			(xy 63.634561 -118.195527) (xy 63.650629 -118.248934) (xy 63.658749 -118.30411) (xy 63.659258 -118.331996)
			(xy 63.658749 -118.359882) (xy 63.650629 -118.415058) (xy 63.634561 -118.468465) (xy 63.610889 -118.518962)
			(xy 63.580116 -118.565475) (xy 63.542899 -118.607012) (xy 63.500031 -118.642687) (xy 63.452425 -118.671741)
			(xy 63.401096 -118.693553) (xy 63.347139 -118.707659) (xy 63.291702 -118.713759) (xy 63.235968 -118.711722)
			(xy 63.181125 -118.701592) (xy 63.128341 -118.683585) (xy 63.078741 -118.658084) (xy 63.033383 -118.625633)
			(xy 62.993234 -118.586924) (xy 62.959148 -118.542781) (xy 62.931852 -118.494146) (xy 62.911929 -118.442055)
			(xy 62.899803 -118.387618) (xy 62.895732 -118.331996) (xy 56.344329 -118.331996) (xy 56.341525 -118.35105)
			(xy 56.325457 -118.404457) (xy 56.301785 -118.454954) (xy 56.271012 -118.501467) (xy 56.233795 -118.543004)
			(xy 56.190927 -118.578679) (xy 56.143321 -118.607733) (xy 56.091992 -118.629545) (xy 56.038035 -118.643651)
			(xy 55.982598 -118.649751) (xy 55.926864 -118.647714) (xy 55.872021 -118.637584) (xy 55.819237 -118.619577)
			(xy 55.769637 -118.594076) (xy 55.724279 -118.561625) (xy 55.68413 -118.522916) (xy 55.650044 -118.478773)
			(xy 55.622748 -118.430138) (xy 55.602825 -118.378047) (xy 55.590699 -118.32361) (xy 55.586628 -118.267988)
			(xy 18.992679 -118.267988) (xy 18.972122 -118.291713) (xy 18.930933 -118.327404) (xy 18.885085 -118.356871)
			(xy 18.835509 -118.379513) (xy 18.783217 -118.39487) (xy 18.729271 -118.402629) (xy 18.70202 -118.403116)
			(xy 18.674649 -118.402659) (xy 18.620469 -118.394842) (xy 18.567965 -118.379352) (xy 18.518218 -118.356508)
			(xy 18.472252 -118.326779) (xy 18.451322 -118.309136) (xy 18.451068 -118.308882) (xy 18.443968 -118.303316)
			(xy 18.427061 -118.297057) (xy 18.418048 -118.29669) (xy 18.350992 -118.29669) (xy 18.341975 -118.297045)
			(xy 18.325058 -118.303294) (xy 18.317972 -118.308882) (xy 18.317972 -118.309136) (xy 18.317718 -118.309136)
			(xy 18.296795 -118.326786) (xy 18.250819 -118.356495) (xy 18.201069 -118.379328) (xy 18.148567 -118.394817)
			(xy 18.09439 -118.402643) (xy 18.06702 -118.403116) (xy 18.039768 -118.402626) (xy 17.985818 -118.394872)
			(xy 17.933522 -118.379519) (xy 17.883942 -118.356879) (xy 17.838089 -118.327414) (xy 17.796897 -118.291723)
			(xy 17.761203 -118.250533) (xy 17.731734 -118.204683) (xy 17.709091 -118.155105) (xy 17.693734 -118.102809)
			(xy 17.685976 -118.04886) (xy 17.685512 -118.021608) (xy 17.567078 -118.021608) (xy 17.569179 -118.035886)
			(xy 17.569688 -118.063772) (xy 17.569179 -118.091658) (xy 17.561059 -118.146834) (xy 17.544991 -118.200241)
			(xy 17.521319 -118.250738) (xy 17.490546 -118.297251) (xy 17.453329 -118.338788) (xy 17.410461 -118.374463)
			(xy 17.362855 -118.403517) (xy 17.311526 -118.425329) (xy 17.257569 -118.439435) (xy 17.202132 -118.445535)
			(xy 17.146398 -118.443498) (xy 17.091555 -118.433368) (xy 17.038771 -118.415361) (xy 16.989171 -118.38986)
			(xy 16.943813 -118.357409) (xy 16.903664 -118.3187) (xy 16.869578 -118.274557) (xy 16.842282 -118.225922)
			(xy 16.822359 -118.173831) (xy 16.810233 -118.119394) (xy 16.806162 -118.063772) (xy 15.167063 -118.063772)
			(xy 15.1699 -118.082859) (xy 15.170404 -118.111016) (xy 15.169918 -118.138267) (xy 15.162162 -118.192215)
			(xy 15.146807 -118.24451) (xy 15.124165 -118.294087) (xy 15.094699 -118.339937) (xy 15.059008 -118.381128)
			(xy 15.017817 -118.416819) (xy 14.971967 -118.446285) (xy 14.92239 -118.468927) (xy 14.870095 -118.484282)
			(xy 14.816147 -118.492038) (xy 14.761645 -118.492038) (xy 14.707697 -118.484282) (xy 14.655402 -118.468927)
			(xy 14.605825 -118.446285) (xy 14.559975 -118.416819) (xy 14.518784 -118.381128) (xy 14.483093 -118.339937)
			(xy 14.453627 -118.294087) (xy 14.430985 -118.24451) (xy 14.41563 -118.192215) (xy 14.407874 -118.138267)
			(xy 14.407388 -118.111016) (xy 14.407851 -118.08446) (xy 14.415217 -118.031861) (xy 14.429807 -117.980792)
			(xy 14.440154 -117.95633) (xy 14.444483 -117.944956) (xy 14.443146 -117.920689) (xy 14.437614 -117.909848)
			(xy 14.396212 -117.838728) (xy 14.389488 -117.828651) (xy 14.369072 -117.815667) (xy 14.357096 -117.813836)
			(xy 14.32762 -117.810473) (xy 14.270151 -117.79575) (xy 14.215655 -117.772305) (xy 14.165446 -117.740706)
			(xy 14.14272 -117.721634) (xy 14.142466 -117.72138) (xy 14.135366 -117.715813) (xy 14.11846 -117.709555)
			(xy 14.109446 -117.709188) (xy 14.04239 -117.709188) (xy 14.033373 -117.709543) (xy 14.016456 -117.715792)
			(xy 14.00937 -117.72138) (xy 14.00937 -117.721634) (xy 14.009116 -117.721634) (xy 13.988193 -117.739284)
			(xy 13.942217 -117.768993) (xy 13.892467 -117.791827) (xy 13.839965 -117.807315) (xy 13.785788 -117.815141)
			(xy 13.758418 -117.815614) (xy 13.731166 -117.815128) (xy 13.677216 -117.807374) (xy 13.624919 -117.79202)
			(xy 13.575339 -117.76938) (xy 13.529486 -117.739915) (xy 13.488294 -117.704223) (xy 13.4526 -117.663033)
			(xy 13.423131 -117.617182) (xy 13.400488 -117.567604) (xy 13.385132 -117.515307) (xy 13.377374 -117.461358)
			(xy 13.37691 -117.434106) (xy 4.38404 -117.434106) (xy 4.38404 -118.089426) (xy 10.195304 -118.089426)
			(xy 10.199375 -118.033804) (xy 10.211501 -117.979367) (xy 10.231424 -117.927276) (xy 10.25872 -117.878641)
			(xy 10.292806 -117.834498) (xy 10.332955 -117.795789) (xy 10.378313 -117.763338) (xy 10.427913 -117.737837)
			(xy 10.480697 -117.71983) (xy 10.53554 -117.7097) (xy 10.591274 -117.707663) (xy 10.646711 -117.713763)
			(xy 10.700668 -117.727869) (xy 10.751997 -117.749681) (xy 10.799603 -117.778735) (xy 10.842471 -117.81441)
			(xy 10.879688 -117.855947) (xy 10.910461 -117.90246) (xy 10.934133 -117.952957) (xy 10.936982 -117.962426)
			(xy 12.227304 -117.962426) (xy 12.231375 -117.906804) (xy 12.243501 -117.852367) (xy 12.263424 -117.800276)
			(xy 12.29072 -117.751641) (xy 12.324806 -117.707498) (xy 12.364955 -117.668789) (xy 12.410313 -117.636338)
			(xy 12.459913 -117.610837) (xy 12.512697 -117.59283) (xy 12.56754 -117.5827) (xy 12.623274 -117.580663)
			(xy 12.678711 -117.586763) (xy 12.732668 -117.600869) (xy 12.783997 -117.622681) (xy 12.831603 -117.651735)
			(xy 12.874471 -117.68741) (xy 12.911688 -117.728947) (xy 12.942461 -117.77546) (xy 12.966133 -117.825957)
			(xy 12.982201 -117.879364) (xy 12.990321 -117.93454) (xy 12.99083 -117.962426) (xy 12.990321 -117.990312)
			(xy 12.982201 -118.045488) (xy 12.966133 -118.098895) (xy 12.942461 -118.149392) (xy 12.911688 -118.195905)
			(xy 12.874471 -118.237442) (xy 12.831603 -118.273117) (xy 12.783997 -118.302171) (xy 12.732668 -118.323983)
			(xy 12.678711 -118.338089) (xy 12.623274 -118.344189) (xy 12.56754 -118.342152) (xy 12.512697 -118.332022)
			(xy 12.459913 -118.314015) (xy 12.410313 -118.288514) (xy 12.364955 -118.256063) (xy 12.324806 -118.217354)
			(xy 12.29072 -118.173211) (xy 12.263424 -118.124576) (xy 12.243501 -118.072485) (xy 12.231375 -118.018048)
			(xy 12.227304 -117.962426) (xy 10.936982 -117.962426) (xy 10.950201 -118.006364) (xy 10.958321 -118.06154)
			(xy 10.95883 -118.089426) (xy 10.958321 -118.117312) (xy 10.950201 -118.172488) (xy 10.934133 -118.225895)
			(xy 10.910461 -118.276392) (xy 10.879688 -118.322905) (xy 10.842471 -118.364442) (xy 10.799603 -118.400117)
			(xy 10.751997 -118.429171) (xy 10.700668 -118.450983) (xy 10.646711 -118.465089) (xy 10.591274 -118.471189)
			(xy 10.53554 -118.469152) (xy 10.480697 -118.459022) (xy 10.427913 -118.441015) (xy 10.378313 -118.415514)
			(xy 10.332955 -118.383063) (xy 10.292806 -118.344354) (xy 10.25872 -118.300211) (xy 10.231424 -118.251576)
			(xy 10.211501 -118.199485) (xy 10.199375 -118.145048) (xy 10.195304 -118.089426) (xy 4.38404 -118.089426)
			(xy 4.38404 -120.248426) (xy 10.195304 -120.248426) (xy 10.199375 -120.192804) (xy 10.211501 -120.138367)
			(xy 10.231424 -120.086276) (xy 10.25872 -120.037641) (xy 10.292806 -119.993498) (xy 10.332955 -119.954789)
			(xy 10.378313 -119.922338) (xy 10.427913 -119.896837) (xy 10.480697 -119.87883) (xy 10.53554 -119.8687)
			(xy 10.591274 -119.866663) (xy 10.646711 -119.872763) (xy 10.700668 -119.886869) (xy 10.751997 -119.908681)
			(xy 10.799603 -119.937735) (xy 10.842471 -119.97341) (xy 10.879688 -120.014947) (xy 10.910461 -120.06146)
			(xy 10.934133 -120.111957) (xy 10.935912 -120.11787) (xy 11.211304 -120.11787) (xy 11.215375 -120.062248)
			(xy 11.227501 -120.007811) (xy 11.247424 -119.95572) (xy 11.27472 -119.907085) (xy 11.308806 -119.862942)
			(xy 11.348955 -119.824233) (xy 11.394313 -119.791782) (xy 11.443913 -119.766281) (xy 11.496697 -119.748274)
			(xy 11.55154 -119.738144) (xy 11.607274 -119.736107) (xy 11.662711 -119.742207) (xy 11.716668 -119.756313)
			(xy 11.767997 -119.778125) (xy 11.815603 -119.807179) (xy 11.858471 -119.842854) (xy 11.895688 -119.884391)
			(xy 11.926461 -119.930904) (xy 11.950133 -119.981401) (xy 11.966201 -120.034808) (xy 11.974321 -120.089984)
			(xy 11.97483 -120.11787) (xy 12.227304 -120.11787) (xy 12.231375 -120.062248) (xy 12.243501 -120.007811)
			(xy 12.263424 -119.95572) (xy 12.29072 -119.907085) (xy 12.324806 -119.862942) (xy 12.364955 -119.824233)
			(xy 12.410313 -119.791782) (xy 12.459913 -119.766281) (xy 12.512697 -119.748274) (xy 12.56754 -119.738144)
			(xy 12.623274 -119.736107) (xy 12.678711 -119.742207) (xy 12.732668 -119.756313) (xy 12.783997 -119.778125)
			(xy 12.831603 -119.807179) (xy 12.874471 -119.842854) (xy 12.911688 -119.884391) (xy 12.942461 -119.930904)
			(xy 12.966133 -119.981401) (xy 12.982201 -120.034808) (xy 12.990321 -120.089984) (xy 12.99083 -120.11787)
			(xy 12.990321 -120.145756) (xy 12.989192 -120.15343) (xy 15.422878 -120.15343) (xy 15.426949 -120.097808)
			(xy 15.439075 -120.043371) (xy 15.458998 -119.99128) (xy 15.486294 -119.942645) (xy 15.52038 -119.898502)
			(xy 15.560529 -119.859793) (xy 15.605887 -119.827342) (xy 15.655487 -119.801841) (xy 15.708271 -119.783834)
			(xy 15.763114 -119.773704) (xy 15.818848 -119.771667) (xy 15.874285 -119.777767) (xy 15.928242 -119.791873)
			(xy 15.979571 -119.813685) (xy 16.027177 -119.842739) (xy 16.070045 -119.878414) (xy 16.107262 -119.919951)
			(xy 16.138035 -119.966464) (xy 16.161707 -120.016961) (xy 16.177775 -120.070368) (xy 16.180355 -120.087898)
			(xy 34.667952 -120.087898) (xy 34.667952 -119.224298) (xy 34.668442 -119.19433) (xy 34.676265 -119.134908)
			(xy 34.691778 -119.077015) (xy 34.714714 -119.021642) (xy 34.744681 -118.969736) (xy 34.781168 -118.922186)
			(xy 34.823548 -118.879806) (xy 34.871098 -118.843319) (xy 34.923004 -118.813352) (xy 34.978377 -118.790416)
			(xy 35.03627 -118.774903) (xy 35.095692 -118.76708) (xy 35.155628 -118.76708) (xy 35.21505 -118.774903)
			(xy 35.272943 -118.790416) (xy 35.328316 -118.813352) (xy 35.380222 -118.843319) (xy 35.427772 -118.879806)
			(xy 35.470152 -118.922186) (xy 35.506639 -118.969736) (xy 35.536606 -119.021642) (xy 35.559542 -119.077015)
			(xy 35.575055 -119.134908) (xy 35.582878 -119.19433) (xy 35.583368 -119.224298) (xy 35.583368 -120.086374)
			(xy 53.639212 -120.086374) (xy 53.639212 -119.222774) (xy 53.639702 -119.192806) (xy 53.647525 -119.133384)
			(xy 53.663038 -119.075491) (xy 53.685974 -119.020118) (xy 53.715941 -118.968212) (xy 53.752428 -118.920662)
			(xy 53.794808 -118.878282) (xy 53.842358 -118.841795) (xy 53.894264 -118.811828) (xy 53.949637 -118.788892)
			(xy 54.00753 -118.773379) (xy 54.066952 -118.765556) (xy 54.126888 -118.765556) (xy 54.18631 -118.773379)
			(xy 54.244203 -118.788892) (xy 54.299576 -118.811828) (xy 54.351482 -118.841795) (xy 54.399032 -118.878282)
			(xy 54.441412 -118.920662) (xy 54.477899 -118.968212) (xy 54.507866 -119.020118) (xy 54.530802 -119.075491)
			(xy 54.546315 -119.133384) (xy 54.554138 -119.192806) (xy 54.554628 -119.222774) (xy 54.554628 -119.567198)
			(xy 66.599308 -119.567198) (xy 66.599308 -118.703598) (xy 66.599798 -118.673614) (xy 66.607626 -118.614158)
			(xy 66.623147 -118.556233) (xy 66.646096 -118.500829) (xy 66.67608 -118.448895) (xy 66.712586 -118.401319)
			(xy 66.754991 -118.358914) (xy 66.802567 -118.322408) (xy 66.854501 -118.292424) (xy 66.909905 -118.269475)
			(xy 66.96783 -118.253954) (xy 67.027286 -118.246126) (xy 67.087254 -118.246126) (xy 67.14671 -118.253954)
			(xy 67.204635 -118.269475) (xy 67.260039 -118.292424) (xy 67.311973 -118.322408) (xy 67.359549 -118.358914)
			(xy 67.401954 -118.401319) (xy 67.43846 -118.448895) (xy 67.468444 -118.500829) (xy 67.491393 -118.556233)
			(xy 67.506914 -118.614158) (xy 67.514742 -118.673614) (xy 67.515232 -118.703598) (xy 67.515232 -118.711218)
			(xy 69.809358 -118.711218) (xy 69.813429 -118.655596) (xy 69.825555 -118.601159) (xy 69.845478 -118.549068)
			(xy 69.872774 -118.500433) (xy 69.90686 -118.45629) (xy 69.947009 -118.417581) (xy 69.992367 -118.38513)
			(xy 70.041967 -118.359629) (xy 70.094751 -118.341622) (xy 70.149594 -118.331492) (xy 70.205328 -118.329455)
			(xy 70.260765 -118.335555) (xy 70.314722 -118.349661) (xy 70.366051 -118.371473) (xy 70.413657 -118.400527)
			(xy 70.456525 -118.436202) (xy 70.493742 -118.477739) (xy 70.524515 -118.524252) (xy 70.548187 -118.574749)
			(xy 70.564255 -118.628156) (xy 70.572375 -118.683332) (xy 70.572884 -118.711218) (xy 70.572375 -118.739104)
			(xy 70.564255 -118.79428) (xy 70.548187 -118.847687) (xy 70.524515 -118.898184) (xy 70.493742 -118.944697)
			(xy 70.456525 -118.986234) (xy 70.413657 -119.021909) (xy 70.366051 -119.050963) (xy 70.314722 -119.072775)
			(xy 70.260765 -119.086881) (xy 70.205328 -119.092981) (xy 70.149594 -119.090944) (xy 70.094751 -119.080814)
			(xy 70.041967 -119.062807) (xy 69.992367 -119.037306) (xy 69.947009 -119.004855) (xy 69.90686 -118.966146)
			(xy 69.872774 -118.922003) (xy 69.845478 -118.873368) (xy 69.825555 -118.821277) (xy 69.813429 -118.76684)
			(xy 69.809358 -118.711218) (xy 67.515232 -118.711218) (xy 67.515232 -119.55907) (xy 81.07426 -119.55907)
			(xy 81.07426 -118.69547) (xy 81.07475 -118.665486) (xy 81.082578 -118.60603) (xy 81.098099 -118.548105)
			(xy 81.121048 -118.492701) (xy 81.151032 -118.440767) (xy 81.187538 -118.393191) (xy 81.229943 -118.350786)
			(xy 81.277519 -118.31428) (xy 81.329453 -118.284296) (xy 81.384857 -118.261347) (xy 81.442782 -118.245826)
			(xy 81.502238 -118.237998) (xy 81.562206 -118.237998) (xy 81.621662 -118.245826) (xy 81.679587 -118.261347)
			(xy 81.734991 -118.284296) (xy 81.786925 -118.31428) (xy 81.834501 -118.350786) (xy 81.876906 -118.393191)
			(xy 81.913412 -118.440767) (xy 81.943396 -118.492701) (xy 81.966345 -118.548105) (xy 81.981866 -118.60603)
			(xy 81.989694 -118.665486) (xy 81.990184 -118.69547) (xy 81.990184 -119.55907) (xy 81.989694 -119.589054)
			(xy 81.981866 -119.64851) (xy 81.966345 -119.706435) (xy 81.943396 -119.761839) (xy 81.913412 -119.813773)
			(xy 81.876906 -119.861349) (xy 81.834501 -119.903754) (xy 81.786925 -119.94026) (xy 81.734991 -119.970244)
			(xy 81.679587 -119.993193) (xy 81.621662 -120.008714) (xy 81.562206 -120.016542) (xy 81.502238 -120.016542)
			(xy 81.442782 -120.008714) (xy 81.384857 -119.993193) (xy 81.329453 -119.970244) (xy 81.277519 -119.94026)
			(xy 81.229943 -119.903754) (xy 81.187538 -119.861349) (xy 81.151032 -119.813773) (xy 81.121048 -119.761839)
			(xy 81.098099 -119.706435) (xy 81.082578 -119.64851) (xy 81.07475 -119.589054) (xy 81.07426 -119.55907)
			(xy 67.515232 -119.55907) (xy 67.515232 -119.567198) (xy 67.514742 -119.597182) (xy 67.506914 -119.656638)
			(xy 67.491393 -119.714563) (xy 67.468444 -119.769967) (xy 67.43846 -119.821901) (xy 67.401954 -119.869477)
			(xy 67.359549 -119.911882) (xy 67.311973 -119.948388) (xy 67.260039 -119.978372) (xy 67.204635 -120.001321)
			(xy 67.14671 -120.016842) (xy 67.087254 -120.02467) (xy 67.027286 -120.02467) (xy 66.96783 -120.016842)
			(xy 66.909905 -120.001321) (xy 66.854501 -119.978372) (xy 66.802567 -119.948388) (xy 66.754991 -119.911882)
			(xy 66.712586 -119.869477) (xy 66.67608 -119.821901) (xy 66.646096 -119.769967) (xy 66.623147 -119.714563)
			(xy 66.607626 -119.656638) (xy 66.599798 -119.597182) (xy 66.599308 -119.567198) (xy 54.554628 -119.567198)
			(xy 54.554628 -120.086374) (xy 54.554138 -120.116342) (xy 54.546315 -120.175764) (xy 54.530802 -120.233657)
			(xy 54.507866 -120.28903) (xy 54.477899 -120.340936) (xy 54.441412 -120.388486) (xy 54.399032 -120.430866)
			(xy 54.351482 -120.467353) (xy 54.299576 -120.49732) (xy 54.244203 -120.520256) (xy 54.18631 -120.535769)
			(xy 54.126888 -120.543592) (xy 54.066952 -120.543592) (xy 54.00753 -120.535769) (xy 53.949637 -120.520256)
			(xy 53.894264 -120.49732) (xy 53.842358 -120.467353) (xy 53.794808 -120.430866) (xy 53.752428 -120.388486)
			(xy 53.715941 -120.340936) (xy 53.685974 -120.28903) (xy 53.663038 -120.233657) (xy 53.647525 -120.175764)
			(xy 53.639702 -120.116342) (xy 53.639212 -120.086374) (xy 35.583368 -120.086374) (xy 35.583368 -120.087898)
			(xy 35.582878 -120.117866) (xy 35.575055 -120.177288) (xy 35.559542 -120.235181) (xy 35.536606 -120.290554)
			(xy 35.506639 -120.34246) (xy 35.470152 -120.39001) (xy 35.427772 -120.43239) (xy 35.380222 -120.468877)
			(xy 35.328316 -120.498844) (xy 35.272943 -120.52178) (xy 35.21505 -120.537293) (xy 35.155628 -120.545116)
			(xy 35.095692 -120.545116) (xy 35.03627 -120.537293) (xy 34.978377 -120.52178) (xy 34.923004 -120.498844)
			(xy 34.871098 -120.468877) (xy 34.823548 -120.43239) (xy 34.781168 -120.39001) (xy 34.744681 -120.34246)
			(xy 34.714714 -120.290554) (xy 34.691778 -120.235181) (xy 34.676265 -120.177288) (xy 34.668442 -120.117866)
			(xy 34.667952 -120.087898) (xy 16.180355 -120.087898) (xy 16.185895 -120.125544) (xy 16.186404 -120.15343)
			(xy 16.185895 -120.181316) (xy 16.177775 -120.236492) (xy 16.161707 -120.289899) (xy 16.138035 -120.340396)
			(xy 16.107262 -120.386909) (xy 16.070045 -120.428446) (xy 16.027177 -120.464121) (xy 15.979571 -120.493175)
			(xy 15.928242 -120.514987) (xy 15.874285 -120.529093) (xy 15.818848 -120.535193) (xy 15.763114 -120.533156)
			(xy 15.708271 -120.523026) (xy 15.655487 -120.505019) (xy 15.605887 -120.479518) (xy 15.560529 -120.447067)
			(xy 15.52038 -120.408358) (xy 15.486294 -120.364215) (xy 15.458998 -120.31558) (xy 15.439075 -120.263489)
			(xy 15.426949 -120.209052) (xy 15.422878 -120.15343) (xy 12.989192 -120.15343) (xy 12.982201 -120.200932)
			(xy 12.966133 -120.254339) (xy 12.942461 -120.304836) (xy 12.911688 -120.351349) (xy 12.874471 -120.392886)
			(xy 12.831603 -120.428561) (xy 12.783997 -120.457615) (xy 12.732668 -120.479427) (xy 12.678711 -120.493533)
			(xy 12.623274 -120.499633) (xy 12.56754 -120.497596) (xy 12.512697 -120.487466) (xy 12.459913 -120.469459)
			(xy 12.410313 -120.443958) (xy 12.364955 -120.411507) (xy 12.324806 -120.372798) (xy 12.29072 -120.328655)
			(xy 12.263424 -120.28002) (xy 12.243501 -120.227929) (xy 12.231375 -120.173492) (xy 12.227304 -120.11787)
			(xy 11.97483 -120.11787) (xy 11.974321 -120.145756) (xy 11.966201 -120.200932) (xy 11.950133 -120.254339)
			(xy 11.926461 -120.304836) (xy 11.895688 -120.351349) (xy 11.858471 -120.392886) (xy 11.815603 -120.428561)
			(xy 11.767997 -120.457615) (xy 11.716668 -120.479427) (xy 11.662711 -120.493533) (xy 11.607274 -120.499633)
			(xy 11.55154 -120.497596) (xy 11.496697 -120.487466) (xy 11.443913 -120.469459) (xy 11.394313 -120.443958)
			(xy 11.348955 -120.411507) (xy 11.308806 -120.372798) (xy 11.27472 -120.328655) (xy 11.247424 -120.28002)
			(xy 11.227501 -120.227929) (xy 11.215375 -120.173492) (xy 11.211304 -120.11787) (xy 10.935912 -120.11787)
			(xy 10.950201 -120.165364) (xy 10.958321 -120.22054) (xy 10.95883 -120.248426) (xy 10.958321 -120.276312)
			(xy 10.950201 -120.331488) (xy 10.934133 -120.384895) (xy 10.910461 -120.435392) (xy 10.879688 -120.481905)
			(xy 10.842471 -120.523442) (xy 10.799603 -120.559117) (xy 10.751997 -120.588171) (xy 10.700668 -120.609983)
			(xy 10.646711 -120.624089) (xy 10.591274 -120.630189) (xy 10.53554 -120.628152) (xy 10.480697 -120.618022)
			(xy 10.427913 -120.600015) (xy 10.378313 -120.574514) (xy 10.332955 -120.542063) (xy 10.292806 -120.503354)
			(xy 10.25872 -120.459211) (xy 10.231424 -120.410576) (xy 10.211501 -120.358485) (xy 10.199375 -120.304048)
			(xy 10.195304 -120.248426) (xy 4.38404 -120.248426) (xy 4.38404 -121.57075) (xy 13.619988 -121.57075)
			(xy 13.620426 -121.544435) (xy 13.627667 -121.492305) (xy 13.641992 -121.441662) (xy 13.66313 -121.393464)
			(xy 13.690682 -121.348621) (xy 13.724125 -121.307982) (xy 13.743178 -121.289826) (xy 13.750567 -121.282294)
			(xy 13.759099 -121.263022) (xy 13.759688 -121.252488) (xy 13.759688 -121.177812) (xy 13.759169 -121.167261)
			(xy 13.750627 -121.147966) (xy 13.743178 -121.140474) (xy 13.724113 -121.122328) (xy 13.690657 -121.081696)
			(xy 13.6631 -121.036854) (xy 13.641963 -120.988651) (xy 13.627648 -120.938002) (xy 13.620425 -120.885867)
			(xy 13.619988 -120.85955) (xy 13.620474 -120.832299) (xy 13.62823 -120.778351) (xy 13.643585 -120.726056)
			(xy 13.666227 -120.676479) (xy 13.695693 -120.630629) (xy 13.731384 -120.589438) (xy 13.772575 -120.553747)
			(xy 13.818425 -120.524281) (xy 13.868002 -120.501639) (xy 13.920297 -120.486284) (xy 13.974245 -120.478528)
			(xy 14.028747 -120.478528) (xy 14.082695 -120.486284) (xy 14.13499 -120.501639) (xy 14.184567 -120.524281)
			(xy 14.230417 -120.553747) (xy 14.271608 -120.589438) (xy 14.307299 -120.630629) (xy 14.336765 -120.676479)
			(xy 14.359407 -120.726056) (xy 14.374762 -120.778351) (xy 14.382518 -120.832299) (xy 14.383004 -120.85955)
			(xy 14.382569 -120.885865) (xy 14.375327 -120.937995) (xy 14.361002 -120.988638) (xy 14.339863 -121.036837)
			(xy 14.312311 -121.08168) (xy 14.278868 -121.122318) (xy 14.259814 -121.140474) (xy 14.252424 -121.148005)
			(xy 14.243892 -121.167278) (xy 14.243304 -121.177812) (xy 14.243304 -121.252488) (xy 14.243825 -121.263039)
			(xy 14.252366 -121.282334) (xy 14.259814 -121.289826) (xy 14.278878 -121.307973) (xy 14.312334 -121.348605)
			(xy 14.339891 -121.393447) (xy 14.361028 -121.44165) (xy 14.375344 -121.492298) (xy 14.382567 -121.544433)
			(xy 14.383004 -121.57075) (xy 14.382518 -121.598001) (xy 14.374762 -121.651949) (xy 14.359407 -121.704244)
			(xy 14.336765 -121.753821) (xy 14.307299 -121.799671) (xy 14.271608 -121.840862) (xy 14.230417 -121.876553)
			(xy 14.202731 -121.894346) (xy 37.31006 -121.894346) (xy 37.31006 -121.030746) (xy 37.31055 -121.000778)
			(xy 37.318373 -120.941356) (xy 37.333886 -120.883463) (xy 37.356822 -120.82809) (xy 37.386789 -120.776184)
			(xy 37.423276 -120.728634) (xy 37.465656 -120.686254) (xy 37.513206 -120.649767) (xy 37.565112 -120.6198)
			(xy 37.620485 -120.596864) (xy 37.678378 -120.581351) (xy 37.7378 -120.573528) (xy 37.797736 -120.573528)
			(xy 37.857158 -120.581351) (xy 37.915051 -120.596864) (xy 37.970424 -120.6198) (xy 38.02233 -120.649767)
			(xy 38.06988 -120.686254) (xy 38.11226 -120.728634) (xy 38.148747 -120.776184) (xy 38.178714 -120.82809)
			(xy 38.20165 -120.883463) (xy 38.217163 -120.941356) (xy 38.224986 -121.000778) (xy 38.225476 -121.030746)
			(xy 38.225476 -121.886472) (xy 51.785012 -121.886472) (xy 51.785012 -121.022872) (xy 51.785502 -120.992904)
			(xy 51.793325 -120.933482) (xy 51.808838 -120.875589) (xy 51.831774 -120.820216) (xy 51.861741 -120.76831)
			(xy 51.898228 -120.72076) (xy 51.940608 -120.67838) (xy 51.988158 -120.641893) (xy 52.040064 -120.611926)
			(xy 52.095437 -120.58899) (xy 52.15333 -120.573477) (xy 52.212752 -120.565654) (xy 52.272688 -120.565654)
			(xy 52.33211 -120.573477) (xy 52.390003 -120.58899) (xy 52.445376 -120.611926) (xy 52.497282 -120.641893)
			(xy 52.544832 -120.67838) (xy 52.587212 -120.72076) (xy 52.623699 -120.76831) (xy 52.653666 -120.820216)
			(xy 52.676602 -120.875589) (xy 52.692115 -120.933482) (xy 52.699938 -120.992904) (xy 52.700428 -121.022872)
			(xy 52.700428 -121.367296) (xy 64.745108 -121.367296) (xy 64.745108 -120.503696) (xy 64.745598 -120.473712)
			(xy 64.753426 -120.414256) (xy 64.768947 -120.356331) (xy 64.791896 -120.300927) (xy 64.82188 -120.248993)
			(xy 64.858386 -120.201417) (xy 64.900791 -120.159012) (xy 64.948367 -120.122506) (xy 65.000301 -120.092522)
			(xy 65.055705 -120.069573) (xy 65.11363 -120.054052) (xy 65.173086 -120.046224) (xy 65.233054 -120.046224)
			(xy 65.29251 -120.054052) (xy 65.350435 -120.069573) (xy 65.405839 -120.092522) (xy 65.457773 -120.122506)
			(xy 65.505349 -120.159012) (xy 65.547754 -120.201417) (xy 65.58426 -120.248993) (xy 65.614244 -120.300927)
			(xy 65.637193 -120.356331) (xy 65.652714 -120.414256) (xy 65.660542 -120.473712) (xy 65.661032 -120.503696)
			(xy 65.661032 -121.365772) (xy 83.716368 -121.365772) (xy 83.716368 -120.502172) (xy 83.716858 -120.472188)
			(xy 83.724686 -120.412732) (xy 83.740207 -120.354807) (xy 83.763156 -120.299403) (xy 83.79314 -120.247469)
			(xy 83.829646 -120.199893) (xy 83.872051 -120.157488) (xy 83.919627 -120.120982) (xy 83.971561 -120.090998)
			(xy 84.026965 -120.068049) (xy 84.08489 -120.052528) (xy 84.144346 -120.0447) (xy 84.204314 -120.0447)
			(xy 84.26377 -120.052528) (xy 84.321695 -120.068049) (xy 84.377099 -120.090998) (xy 84.429033 -120.120982)
			(xy 84.476609 -120.157488) (xy 84.519014 -120.199893) (xy 84.55552 -120.247469) (xy 84.585504 -120.299403)
			(xy 84.608453 -120.354807) (xy 84.623974 -120.412732) (xy 84.631802 -120.472188) (xy 84.632292 -120.502172)
			(xy 84.632292 -121.365772) (xy 84.631802 -121.395756) (xy 84.623974 -121.455212) (xy 84.608453 -121.513137)
			(xy 84.585504 -121.568541) (xy 84.55552 -121.620475) (xy 84.519014 -121.668051) (xy 84.476609 -121.710456)
			(xy 84.429033 -121.746962) (xy 84.377099 -121.776946) (xy 84.321695 -121.799895) (xy 84.26377 -121.815416)
			(xy 84.204314 -121.823244) (xy 84.144346 -121.823244) (xy 84.08489 -121.815416) (xy 84.026965 -121.799895)
			(xy 83.971561 -121.776946) (xy 83.919627 -121.746962) (xy 83.872051 -121.710456) (xy 83.829646 -121.668051)
			(xy 83.79314 -121.620475) (xy 83.763156 -121.568541) (xy 83.740207 -121.513137) (xy 83.724686 -121.455212)
			(xy 83.716858 -121.395756) (xy 83.716368 -121.365772) (xy 65.661032 -121.365772) (xy 65.661032 -121.367296)
			(xy 65.660542 -121.39728) (xy 65.652714 -121.456736) (xy 65.637193 -121.514661) (xy 65.614244 -121.570065)
			(xy 65.58426 -121.621999) (xy 65.547754 -121.669575) (xy 65.505349 -121.71198) (xy 65.457773 -121.748486)
			(xy 65.405839 -121.77847) (xy 65.350435 -121.801419) (xy 65.29251 -121.81694) (xy 65.233054 -121.824768)
			(xy 65.173086 -121.824768) (xy 65.11363 -121.81694) (xy 65.055705 -121.801419) (xy 65.000301 -121.77847)
			(xy 64.948367 -121.748486) (xy 64.900791 -121.71198) (xy 64.858386 -121.669575) (xy 64.82188 -121.621999)
			(xy 64.791896 -121.570065) (xy 64.768947 -121.514661) (xy 64.753426 -121.456736) (xy 64.745598 -121.39728)
			(xy 64.745108 -121.367296) (xy 52.700428 -121.367296) (xy 52.700428 -121.886472) (xy 52.699938 -121.91644)
			(xy 52.692115 -121.975862) (xy 52.676602 -122.033755) (xy 52.653666 -122.089128) (xy 52.623699 -122.141034)
			(xy 52.587212 -122.188584) (xy 52.544832 -122.230964) (xy 52.497282 -122.267451) (xy 52.445376 -122.297418)
			(xy 52.390003 -122.320354) (xy 52.33211 -122.335867) (xy 52.272688 -122.34369) (xy 52.212752 -122.34369)
			(xy 52.15333 -122.335867) (xy 52.095437 -122.320354) (xy 52.040064 -122.297418) (xy 51.988158 -122.267451)
			(xy 51.940608 -122.230964) (xy 51.898228 -122.188584) (xy 51.861741 -122.141034) (xy 51.831774 -122.089128)
			(xy 51.808838 -122.033755) (xy 51.793325 -121.975862) (xy 51.785502 -121.91644) (xy 51.785012 -121.886472)
			(xy 38.225476 -121.886472) (xy 38.225476 -121.894346) (xy 38.224986 -121.924314) (xy 38.217163 -121.983736)
			(xy 38.20165 -122.041629) (xy 38.178714 -122.097002) (xy 38.148747 -122.148908) (xy 38.11226 -122.196458)
			(xy 38.06988 -122.238838) (xy 38.02233 -122.275325) (xy 37.970424 -122.305292) (xy 37.915051 -122.328228)
			(xy 37.857158 -122.343741) (xy 37.797736 -122.351564) (xy 37.7378 -122.351564) (xy 37.678378 -122.343741)
			(xy 37.620485 -122.328228) (xy 37.565112 -122.305292) (xy 37.513206 -122.275325) (xy 37.465656 -122.238838)
			(xy 37.423276 -122.196458) (xy 37.386789 -122.148908) (xy 37.356822 -122.097002) (xy 37.333886 -122.041629)
			(xy 37.318373 -121.983736) (xy 37.31055 -121.924314) (xy 37.31006 -121.894346) (xy 14.202731 -121.894346)
			(xy 14.184567 -121.906019) (xy 14.13499 -121.928661) (xy 14.082695 -121.944016) (xy 14.028747 -121.951772)
			(xy 13.974245 -121.951772) (xy 13.920297 -121.944016) (xy 13.868002 -121.928661) (xy 13.818425 -121.906019)
			(xy 13.772575 -121.876553) (xy 13.731384 -121.840862) (xy 13.695693 -121.799671) (xy 13.666227 -121.753821)
			(xy 13.643585 -121.704244) (xy 13.62823 -121.651949) (xy 13.620474 -121.598001) (xy 13.619988 -121.57075)
			(xy 4.38404 -121.57075) (xy 4.38404 -122.292618) (xy 9.780268 -122.292618) (xy 9.784339 -122.236996)
			(xy 9.796465 -122.182559) (xy 9.816388 -122.130468) (xy 9.843684 -122.081833) (xy 9.87777 -122.03769)
			(xy 9.917919 -121.998981) (xy 9.963277 -121.96653) (xy 10.012877 -121.941029) (xy 10.065661 -121.923022)
			(xy 10.120504 -121.912892) (xy 10.176238 -121.910855) (xy 10.231675 -121.916955) (xy 10.285632 -121.931061)
			(xy 10.336961 -121.952873) (xy 10.384567 -121.981927) (xy 10.427435 -122.017602) (xy 10.464652 -122.059139)
			(xy 10.495425 -122.105652) (xy 10.519097 -122.156149) (xy 10.535165 -122.209556) (xy 10.543285 -122.264732)
			(xy 10.543794 -122.292618) (xy 10.543285 -122.320504) (xy 10.535165 -122.37568) (xy 10.519097 -122.429087)
			(xy 10.49996 -122.46991) (xy 10.936984 -122.46991) (xy 10.941055 -122.414288) (xy 10.953181 -122.359851)
			(xy 10.973104 -122.30776) (xy 11.0004 -122.259125) (xy 11.034486 -122.214982) (xy 11.074635 -122.176273)
			(xy 11.119993 -122.143822) (xy 11.169593 -122.118321) (xy 11.222377 -122.100314) (xy 11.27722 -122.090184)
			(xy 11.332954 -122.088147) (xy 11.388391 -122.094247) (xy 11.442348 -122.108353) (xy 11.493677 -122.130165)
			(xy 11.541283 -122.159219) (xy 11.584151 -122.194894) (xy 11.621368 -122.236431) (xy 11.652141 -122.282944)
			(xy 11.675813 -122.333441) (xy 11.691881 -122.386848) (xy 11.700001 -122.442024) (xy 11.70051 -122.46991)
			(xy 11.700001 -122.497796) (xy 11.691881 -122.552972) (xy 11.675813 -122.606379) (xy 11.652141 -122.656876)
			(xy 11.621368 -122.703389) (xy 11.584151 -122.744926) (xy 11.541283 -122.780601) (xy 11.493677 -122.809655)
			(xy 11.442348 -122.831467) (xy 11.388391 -122.845573) (xy 11.332954 -122.851673) (xy 11.27722 -122.849636)
			(xy 11.222377 -122.839506) (xy 11.169593 -122.821499) (xy 11.119993 -122.795998) (xy 11.074635 -122.763547)
			(xy 11.034486 -122.724838) (xy 11.0004 -122.680695) (xy 10.973104 -122.63206) (xy 10.953181 -122.579969)
			(xy 10.941055 -122.525532) (xy 10.936984 -122.46991) (xy 10.49996 -122.46991) (xy 10.495425 -122.479584)
			(xy 10.464652 -122.526097) (xy 10.427435 -122.567634) (xy 10.384567 -122.603309) (xy 10.336961 -122.632363)
			(xy 10.285632 -122.654175) (xy 10.231675 -122.668281) (xy 10.176238 -122.674381) (xy 10.120504 -122.672344)
			(xy 10.065661 -122.662214) (xy 10.012877 -122.644207) (xy 9.963277 -122.618706) (xy 9.917919 -122.586255)
			(xy 9.87777 -122.547546) (xy 9.843684 -122.503403) (xy 9.816388 -122.454768) (xy 9.796465 -122.402677)
			(xy 9.784339 -122.34824) (xy 9.780268 -122.292618) (xy 4.38404 -122.292618) (xy 4.38404 -123.249761)
			(xy 11.91004 -123.249761) (xy 11.91004 -123.195259) (xy 11.917796 -123.141311) (xy 11.933151 -123.089017)
			(xy 11.955792 -123.03944) (xy 11.985258 -122.99359) (xy 12.02095 -122.9524) (xy 12.06214 -122.916708)
			(xy 12.10799 -122.887242) (xy 12.157567 -122.864601) (xy 12.209861 -122.849246) (xy 12.263809 -122.84149)
			(xy 12.29106 -122.841004) (xy 12.318091 -122.841459) (xy 12.371611 -122.849105) (xy 12.423513 -122.864236)
			(xy 12.472757 -122.886548) (xy 12.518354 -122.915593) (xy 12.559391 -122.950789) (xy 12.577572 -122.970798)
			(xy 12.577826 -122.971052) (xy 12.585282 -122.978685) (xy 12.604757 -122.987361) (xy 12.615418 -122.987816)
			(xy 12.703048 -122.988324) (xy 12.722606 -122.979688) (xy 12.729972 -122.971306) (xy 12.748153 -122.951603)
			(xy 12.78905 -122.916937) (xy 12.834401 -122.888346) (xy 12.883312 -122.866393) (xy 12.934818 -122.851514)
			(xy 12.9879 -122.844) (xy 13.014706 -122.843544) (xy 13.042077 -122.843996) (xy 13.096257 -122.851815)
			(xy 13.148761 -122.867307) (xy 13.198507 -122.890152) (xy 13.244473 -122.919881) (xy 13.265404 -122.937524)
			(xy 13.265658 -122.937778) (xy 13.272746 -122.943362) (xy 13.289662 -122.949608) (xy 13.298678 -122.94997)
			(xy 13.365734 -122.94997) (xy 13.374753 -122.949636) (xy 13.39167 -122.943373) (xy 13.398754 -122.937778)
			(xy 13.398754 -122.937524) (xy 13.399008 -122.937524) (xy 13.419941 -122.919883) (xy 13.465909 -122.890159)
			(xy 13.515655 -122.867313) (xy 13.568157 -122.851817) (xy 13.622335 -122.843988) (xy 13.677077 -122.843988)
			(xy 13.731255 -122.851817) (xy 13.783757 -122.867313) (xy 13.833503 -122.890159) (xy 13.879471 -122.919883)
			(xy 13.900404 -122.937524) (xy 13.900658 -122.937778) (xy 13.907746 -122.943362) (xy 13.924662 -122.949608)
			(xy 13.933678 -122.94997) (xy 14.000734 -122.94997) (xy 14.009753 -122.949636) (xy 14.02667 -122.943373)
			(xy 14.033754 -122.937778) (xy 14.034262 -122.937524) (xy 14.046999 -122.926583) (xy 14.074088 -122.90674)
			(xy 14.088364 -122.8979) (xy 14.097254 -122.892566) (xy 14.109446 -122.875548) (xy 14.129766 -122.78233)
			(xy 14.125448 -122.761756) (xy 14.119606 -122.75312) (xy 14.103613 -122.729052) (xy 14.078269 -122.677122)
			(xy 14.061041 -122.621965) (xy 14.052324 -122.564842) (xy 14.051788 -122.53595) (xy 14.052274 -122.508699)
			(xy 14.06003 -122.454751) (xy 14.075385 -122.402456) (xy 14.098027 -122.352879) (xy 14.127493 -122.307029)
			(xy 14.163184 -122.265838) (xy 14.204375 -122.230147) (xy 14.250225 -122.200681) (xy 14.299802 -122.178039)
			(xy 14.352097 -122.162684) (xy 14.406045 -122.154928) (xy 14.460547 -122.154928) (xy 14.514495 -122.162684)
			(xy 14.56679 -122.178039) (xy 14.616367 -122.200681) (xy 14.662217 -122.230147) (xy 14.703408 -122.265838)
			(xy 14.739099 -122.307029) (xy 14.768565 -122.352879) (xy 14.791207 -122.402456) (xy 14.806562 -122.454751)
			(xy 14.814318 -122.508699) (xy 14.814804 -122.53595) (xy 14.814277 -122.56404) (xy 14.806056 -122.619616)
			(xy 14.789771 -122.673385) (xy 14.765774 -122.724183) (xy 14.734584 -122.77091) (xy 14.696876 -122.812556)
			(xy 14.653467 -122.848219) (xy 14.629638 -122.863102) (xy 14.620748 -122.868436) (xy 14.608556 -122.885454)
			(xy 14.588236 -122.978672) (xy 14.592554 -122.999246) (xy 14.598396 -123.007882) (xy 14.61439 -123.03195)
			(xy 14.639734 -123.08388) (xy 14.656962 -123.139036) (xy 14.665678 -123.19616) (xy 14.666214 -123.225052)
			(xy 14.6657 -123.252303) (xy 14.65795 -123.306252) (xy 14.6426 -123.358549) (xy 14.619964 -123.408128)
			(xy 14.590501 -123.453981) (xy 14.554813 -123.495174) (xy 14.513625 -123.530869) (xy 14.467776 -123.560338)
			(xy 14.418199 -123.582981) (xy 14.365905 -123.598338) (xy 14.311957 -123.606096) (xy 14.284706 -123.60656)
			(xy 14.257335 -123.6061) (xy 14.203156 -123.598282) (xy 14.150652 -123.582792) (xy 14.100905 -123.559949)
			(xy 14.054939 -123.530222) (xy 14.034008 -123.51258) (xy 14.033754 -123.512326) (xy 14.026662 -123.506747)
			(xy 14.009749 -123.500498) (xy 14.000734 -123.500134) (xy 13.933678 -123.500134) (xy 13.924659 -123.500473)
			(xy 13.907742 -123.506732) (xy 13.900658 -123.512326) (xy 13.900404 -123.51258) (xy 13.879471 -123.530221)
			(xy 13.833503 -123.559945) (xy 13.783757 -123.582791) (xy 13.731255 -123.598287) (xy 13.677077 -123.606116)
			(xy 13.622335 -123.606116) (xy 13.568157 -123.598287) (xy 13.515655 -123.582791) (xy 13.465909 -123.559945)
			(xy 13.419941 -123.530221) (xy 13.399008 -123.51258) (xy 13.398754 -123.512326) (xy 13.391662 -123.506747)
			(xy 13.374749 -123.500498) (xy 13.365734 -123.500134) (xy 13.298678 -123.500134) (xy 13.289659 -123.500473)
			(xy 13.272742 -123.506732) (xy 13.265658 -123.512326) (xy 13.265658 -123.51258) (xy 13.265404 -123.51258)
			(xy 13.244479 -123.530228) (xy 13.198504 -123.559939) (xy 13.148755 -123.582773) (xy 13.096253 -123.598262)
			(xy 13.042076 -123.606088) (xy 13.014706 -123.60656) (xy 12.987675 -123.606107) (xy 12.934156 -123.598457)
			(xy 12.882255 -123.583325) (xy 12.833012 -123.561012) (xy 12.787414 -123.531968) (xy 12.746376 -123.496774)
			(xy 12.728194 -123.476766) (xy 12.72794 -123.476512) (xy 12.720488 -123.468874) (xy 12.70101 -123.460199)
			(xy 12.690348 -123.459748) (xy 12.602718 -123.45924) (xy 12.58316 -123.467876) (xy 12.575794 -123.476258)
			(xy 12.557643 -123.495991) (xy 12.516739 -123.530651) (xy 12.471381 -123.559237) (xy 12.422464 -123.581184)
			(xy 12.370954 -123.596059) (xy 12.317867 -123.603567) (xy 12.29106 -123.60402) (xy 12.263809 -123.60353)
			(xy 12.209861 -123.595774) (xy 12.157567 -123.580419) (xy 12.10799 -123.557778) (xy 12.06214 -123.528312)
			(xy 12.02095 -123.49262) (xy 11.985258 -123.45143) (xy 11.955792 -123.40558) (xy 11.933151 -123.356003)
			(xy 11.917796 -123.303709) (xy 11.91004 -123.249761) (xy 4.38404 -123.249761) (xy 4.38404 -123.68784)
			(xy 34.667952 -123.68784) (xy 34.667952 -122.82424) (xy 34.668442 -122.794272) (xy 34.676265 -122.73485)
			(xy 34.691778 -122.676957) (xy 34.714714 -122.621584) (xy 34.744681 -122.569678) (xy 34.781168 -122.522128)
			(xy 34.823548 -122.479748) (xy 34.871098 -122.443261) (xy 34.923004 -122.413294) (xy 34.978377 -122.390358)
			(xy 35.03627 -122.374845) (xy 35.095692 -122.367022) (xy 35.155628 -122.367022) (xy 35.21505 -122.374845)
			(xy 35.272943 -122.390358) (xy 35.328316 -122.413294) (xy 35.380222 -122.443261) (xy 35.427772 -122.479748)
			(xy 35.470152 -122.522128) (xy 35.506639 -122.569678) (xy 35.536606 -122.621584) (xy 35.559542 -122.676957)
			(xy 35.575055 -122.73485) (xy 35.582878 -122.794272) (xy 35.583368 -122.82424) (xy 35.583368 -123.686316)
			(xy 53.639212 -123.686316) (xy 53.639212 -122.822716) (xy 53.639702 -122.792748) (xy 53.647525 -122.733326)
			(xy 53.663038 -122.675433) (xy 53.685974 -122.62006) (xy 53.715941 -122.568154) (xy 53.752428 -122.520604)
			(xy 53.794808 -122.478224) (xy 53.842358 -122.441737) (xy 53.894264 -122.41177) (xy 53.949637 -122.388834)
			(xy 54.00753 -122.373321) (xy 54.066952 -122.365498) (xy 54.126888 -122.365498) (xy 54.18631 -122.373321)
			(xy 54.244203 -122.388834) (xy 54.299576 -122.41177) (xy 54.351482 -122.441737) (xy 54.399032 -122.478224)
			(xy 54.441412 -122.520604) (xy 54.477899 -122.568154) (xy 54.507866 -122.62006) (xy 54.530802 -122.675433)
			(xy 54.546315 -122.733326) (xy 54.554138 -122.792748) (xy 54.554628 -122.822716) (xy 54.554628 -123.16714)
			(xy 66.599308 -123.16714) (xy 66.599308 -122.30354) (xy 66.599798 -122.273556) (xy 66.607626 -122.2141)
			(xy 66.623147 -122.156175) (xy 66.646096 -122.100771) (xy 66.67608 -122.048837) (xy 66.712586 -122.001261)
			(xy 66.754991 -121.958856) (xy 66.802567 -121.92235) (xy 66.854501 -121.892366) (xy 66.909905 -121.869417)
			(xy 66.96783 -121.853896) (xy 67.027286 -121.846068) (xy 67.087254 -121.846068) (xy 67.14671 -121.853896)
			(xy 67.204635 -121.869417) (xy 67.260039 -121.892366) (xy 67.311973 -121.92235) (xy 67.359549 -121.958856)
			(xy 67.401954 -122.001261) (xy 67.43846 -122.048837) (xy 67.468444 -122.100771) (xy 67.491393 -122.156175)
			(xy 67.506914 -122.2141) (xy 67.514742 -122.273556) (xy 67.515232 -122.30354) (xy 67.515232 -123.159266)
			(xy 81.07426 -123.159266) (xy 81.07426 -122.295666) (xy 81.07475 -122.265682) (xy 81.082578 -122.206226)
			(xy 81.098099 -122.148301) (xy 81.121048 -122.092897) (xy 81.151032 -122.040963) (xy 81.187538 -121.993387)
			(xy 81.229943 -121.950982) (xy 81.277519 -121.914476) (xy 81.329453 -121.884492) (xy 81.384857 -121.861543)
			(xy 81.442782 -121.846022) (xy 81.502238 -121.838194) (xy 81.562206 -121.838194) (xy 81.621662 -121.846022)
			(xy 81.679587 -121.861543) (xy 81.734991 -121.884492) (xy 81.786925 -121.914476) (xy 81.834501 -121.950982)
			(xy 81.876906 -121.993387) (xy 81.913412 -122.040963) (xy 81.943396 -122.092897) (xy 81.966345 -122.148301)
			(xy 81.978063 -122.192034) (xy 89.450672 -122.192034) (xy 89.45114 -122.164664) (xy 89.458955 -122.110484)
			(xy 89.474443 -122.05798) (xy 89.497284 -122.008233) (xy 89.52701 -121.962267) (xy 89.544652 -121.941336)
			(xy 89.544906 -121.941082) (xy 89.550507 -121.934005) (xy 89.556745 -121.917081) (xy 89.557098 -121.908062)
			(xy 89.557098 -121.841006) (xy 89.556739 -121.831989) (xy 89.550493 -121.815072) (xy 89.544906 -121.807986)
			(xy 89.544652 -121.807986) (xy 89.544652 -121.807732) (xy 89.527044 -121.786773) (xy 89.497316 -121.74081)
			(xy 89.474467 -121.691068) (xy 89.458967 -121.63857) (xy 89.451134 -121.584395) (xy 89.451131 -121.529656)
			(xy 89.458956 -121.47548) (xy 89.474449 -121.42298) (xy 89.497291 -121.373235) (xy 89.527013 -121.327268)
			(xy 89.544652 -121.306336) (xy 89.544906 -121.306082) (xy 89.550507 -121.299005) (xy 89.556745 -121.282081)
			(xy 89.557098 -121.273062) (xy 89.557098 -121.206006) (xy 89.556739 -121.196989) (xy 89.550493 -121.180072)
			(xy 89.544906 -121.172986) (xy 89.544652 -121.172986) (xy 89.544652 -121.172732) (xy 89.527044 -121.151773)
			(xy 89.497316 -121.10581) (xy 89.474467 -121.056068) (xy 89.458967 -121.00357) (xy 89.451134 -120.949395)
			(xy 89.451131 -120.894656) (xy 89.458956 -120.84048) (xy 89.474449 -120.78798) (xy 89.497291 -120.738235)
			(xy 89.527013 -120.692268) (xy 89.544652 -120.671336) (xy 89.544906 -120.671082) (xy 89.550507 -120.664005)
			(xy 89.556745 -120.647081) (xy 89.557098 -120.638062) (xy 89.557098 -120.571006) (xy 89.556739 -120.561989)
			(xy 89.550493 -120.545072) (xy 89.544906 -120.537986) (xy 89.544652 -120.537986) (xy 89.544652 -120.537732)
			(xy 89.527023 -120.516792) (xy 89.497307 -120.470822) (xy 89.474469 -120.421077) (xy 89.458976 -120.368578)
			(xy 89.451146 -120.314403) (xy 89.450672 -120.287034) (xy 89.451158 -120.259783) (xy 89.458914 -120.205835)
			(xy 89.474269 -120.15354) (xy 89.496911 -120.103963) (xy 89.526377 -120.058113) (xy 89.562068 -120.016922)
			(xy 89.603259 -119.981231) (xy 89.649109 -119.951765) (xy 89.698686 -119.929123) (xy 89.750981 -119.913768)
			(xy 89.804929 -119.906012) (xy 89.859431 -119.906012) (xy 89.913379 -119.913768) (xy 89.965674 -119.929123)
			(xy 90.015251 -119.951765) (xy 90.061101 -119.981231) (xy 90.102292 -120.016922) (xy 90.137983 -120.058113)
			(xy 90.167449 -120.103963) (xy 90.190091 -120.15354) (xy 90.205446 -120.205835) (xy 90.213202 -120.259783)
			(xy 90.213688 -120.287034) (xy 90.213245 -120.314405) (xy 90.205422 -120.368585) (xy 90.189928 -120.421089)
			(xy 90.167081 -120.470835) (xy 90.137351 -120.516801) (xy 90.119708 -120.537732) (xy 90.119454 -120.537986)
			(xy 90.113862 -120.545068) (xy 90.10762 -120.561989) (xy 90.107262 -120.571006) (xy 90.107262 -120.638062)
			(xy 90.107645 -120.647076) (xy 90.113876 -120.663993) (xy 90.119454 -120.671082) (xy 90.119708 -120.671082)
			(xy 90.119708 -120.671336) (xy 90.137381 -120.692242) (xy 90.167101 -120.738216) (xy 90.189943 -120.787966)
			(xy 90.205435 -120.840472) (xy 90.213259 -120.894654) (xy 90.213256 -120.949397) (xy 90.205424 -121.003578)
			(xy 90.189925 -121.056082) (xy 90.167077 -121.105829) (xy 90.13735 -121.151799) (xy 90.119708 -121.172732)
			(xy 90.119454 -121.172986) (xy 90.113862 -121.180068) (xy 90.10762 -121.196989) (xy 90.107262 -121.206006)
			(xy 90.107262 -121.273062) (xy 90.107645 -121.282076) (xy 90.113876 -121.298993) (xy 90.119454 -121.306082)
			(xy 90.119708 -121.306082) (xy 90.119708 -121.306336) (xy 90.137381 -121.327242) (xy 90.167101 -121.373216)
			(xy 90.189943 -121.422966) (xy 90.205435 -121.475472) (xy 90.213259 -121.529654) (xy 90.213256 -121.584397)
			(xy 90.205424 -121.638578) (xy 90.189925 -121.691082) (xy 90.167077 -121.740829) (xy 90.13735 -121.786799)
			(xy 90.119708 -121.807732) (xy 90.119454 -121.807986) (xy 90.113862 -121.815068) (xy 90.10762 -121.831989)
			(xy 90.107262 -121.841006) (xy 90.107262 -121.908062) (xy 90.107645 -121.917076) (xy 90.113876 -121.933993)
			(xy 90.119454 -121.941082) (xy 90.119708 -121.941082) (xy 90.119708 -121.941336) (xy 90.137332 -121.96228)
			(xy 90.167046 -122.00825) (xy 90.189884 -122.057994) (xy 90.205379 -122.110492) (xy 90.213212 -122.164666)
			(xy 90.213688 -122.192034) (xy 90.213202 -122.219285) (xy 90.205446 -122.273233) (xy 90.190091 -122.325528)
			(xy 90.167449 -122.375105) (xy 90.137983 -122.420955) (xy 90.102292 -122.462146) (xy 90.061101 -122.497837)
			(xy 90.015251 -122.527303) (xy 89.965674 -122.549945) (xy 89.913379 -122.5653) (xy 89.859431 -122.573056)
			(xy 89.804929 -122.573056) (xy 89.750981 -122.5653) (xy 89.698686 -122.549945) (xy 89.649109 -122.527303)
			(xy 89.603259 -122.497837) (xy 89.562068 -122.462146) (xy 89.526377 -122.420955) (xy 89.496911 -122.375105)
			(xy 89.474269 -122.325528) (xy 89.458914 -122.273233) (xy 89.451158 -122.219285) (xy 89.450672 -122.192034)
			(xy 81.978063 -122.192034) (xy 81.981866 -122.206226) (xy 81.989694 -122.265682) (xy 81.990184 -122.295666)
			(xy 81.990184 -123.159266) (xy 81.989694 -123.18925) (xy 81.981866 -123.248706) (xy 81.966345 -123.306631)
			(xy 81.943396 -123.362035) (xy 81.913412 -123.413969) (xy 81.876906 -123.461545) (xy 81.834501 -123.50395)
			(xy 81.786925 -123.540456) (xy 81.734991 -123.57044) (xy 81.679587 -123.593389) (xy 81.621662 -123.60891)
			(xy 81.562206 -123.616738) (xy 81.502238 -123.616738) (xy 81.442782 -123.60891) (xy 81.384857 -123.593389)
			(xy 81.329453 -123.57044) (xy 81.277519 -123.540456) (xy 81.229943 -123.50395) (xy 81.187538 -123.461545)
			(xy 81.151032 -123.413969) (xy 81.121048 -123.362035) (xy 81.098099 -123.306631) (xy 81.082578 -123.248706)
			(xy 81.07475 -123.18925) (xy 81.07426 -123.159266) (xy 67.515232 -123.159266) (xy 67.515232 -123.16714)
			(xy 67.514742 -123.197124) (xy 67.506914 -123.25658) (xy 67.491393 -123.314505) (xy 67.468444 -123.369909)
			(xy 67.43846 -123.421843) (xy 67.401954 -123.469419) (xy 67.359549 -123.511824) (xy 67.311973 -123.54833)
			(xy 67.260039 -123.578314) (xy 67.204635 -123.601263) (xy 67.14671 -123.616784) (xy 67.087254 -123.624612)
			(xy 67.027286 -123.624612) (xy 66.96783 -123.616784) (xy 66.909905 -123.601263) (xy 66.854501 -123.578314)
			(xy 66.802567 -123.54833) (xy 66.754991 -123.511824) (xy 66.712586 -123.469419) (xy 66.67608 -123.421843)
			(xy 66.646096 -123.369909) (xy 66.623147 -123.314505) (xy 66.607626 -123.25658) (xy 66.599798 -123.197124)
			(xy 66.599308 -123.16714) (xy 54.554628 -123.16714) (xy 54.554628 -123.686316) (xy 54.554138 -123.716284)
			(xy 54.546315 -123.775706) (xy 54.530802 -123.833599) (xy 54.507866 -123.888972) (xy 54.477899 -123.940878)
			(xy 54.441412 -123.988428) (xy 54.399032 -124.030808) (xy 54.351482 -124.067295) (xy 54.299576 -124.097262)
			(xy 54.244203 -124.120198) (xy 54.18631 -124.135711) (xy 54.126888 -124.143534) (xy 54.066952 -124.143534)
			(xy 54.00753 -124.135711) (xy 53.949637 -124.120198) (xy 53.894264 -124.097262) (xy 53.842358 -124.067295)
			(xy 53.794808 -124.030808) (xy 53.752428 -123.988428) (xy 53.715941 -123.940878) (xy 53.685974 -123.888972)
			(xy 53.663038 -123.833599) (xy 53.647525 -123.775706) (xy 53.639702 -123.716284) (xy 53.639212 -123.686316)
			(xy 35.583368 -123.686316) (xy 35.583368 -123.68784) (xy 35.582878 -123.717808) (xy 35.575055 -123.77723)
			(xy 35.559542 -123.835123) (xy 35.536606 -123.890496) (xy 35.506639 -123.942402) (xy 35.470152 -123.989952)
			(xy 35.427772 -124.032332) (xy 35.380222 -124.068819) (xy 35.328316 -124.098786) (xy 35.272943 -124.121722)
			(xy 35.21505 -124.137235) (xy 35.155628 -124.145058) (xy 35.095692 -124.145058) (xy 35.03627 -124.137235)
			(xy 34.978377 -124.121722) (xy 34.923004 -124.098786) (xy 34.871098 -124.068819) (xy 34.823548 -124.032332)
			(xy 34.781168 -123.989952) (xy 34.744681 -123.942402) (xy 34.714714 -123.890496) (xy 34.691778 -123.835123)
			(xy 34.676265 -123.77723) (xy 34.668442 -123.717808) (xy 34.667952 -123.68784) (xy 4.38404 -123.68784)
			(xy 4.38404 -124.963428) (xy 8.673082 -124.963428) (xy 8.677153 -124.907806) (xy 8.689279 -124.853369)
			(xy 8.709202 -124.801278) (xy 8.736498 -124.752643) (xy 8.770584 -124.7085) (xy 8.810733 -124.669791)
			(xy 8.856091 -124.63734) (xy 8.905691 -124.611839) (xy 8.958475 -124.593832) (xy 9.013318 -124.583702)
			(xy 9.069052 -124.581665) (xy 9.124489 -124.587765) (xy 9.178446 -124.601871) (xy 9.229775 -124.623683)
			(xy 9.277381 -124.652737) (xy 9.320249 -124.688412) (xy 9.357466 -124.729949) (xy 9.388239 -124.776462)
			(xy 9.411911 -124.826959) (xy 9.427979 -124.880366) (xy 9.436099 -124.935542) (xy 9.436608 -124.963428)
			(xy 9.436099 -124.991314) (xy 9.435493 -124.995432) (xy 10.780774 -124.995432) (xy 10.784845 -124.93981)
			(xy 10.796971 -124.885373) (xy 10.816894 -124.833282) (xy 10.84419 -124.784647) (xy 10.878276 -124.740504)
			(xy 10.918425 -124.701795) (xy 10.963783 -124.669344) (xy 11.013383 -124.643843) (xy 11.066167 -124.625836)
			(xy 11.12101 -124.615706) (xy 11.176744 -124.613669) (xy 11.232181 -124.619769) (xy 11.286138 -124.633875)
			(xy 11.337467 -124.655687) (xy 11.385073 -124.684741) (xy 11.427941 -124.720416) (xy 11.465158 -124.761953)
			(xy 11.495931 -124.808466) (xy 11.519603 -124.858963) (xy 11.535671 -124.91237) (xy 11.543791 -124.967546)
			(xy 11.5443 -124.995432) (xy 11.543791 -125.023318) (xy 11.535671 -125.078494) (xy 11.519603 -125.131901)
			(xy 11.495931 -125.182398) (xy 11.465158 -125.228911) (xy 11.427941 -125.270448) (xy 11.385073 -125.306123)
			(xy 11.337467 -125.335177) (xy 11.286138 -125.356989) (xy 11.232181 -125.371095) (xy 11.176744 -125.377195)
			(xy 11.12101 -125.375158) (xy 11.066167 -125.365028) (xy 11.013383 -125.347021) (xy 10.963783 -125.32152)
			(xy 10.918425 -125.289069) (xy 10.878276 -125.25036) (xy 10.84419 -125.206217) (xy 10.816894 -125.157582)
			(xy 10.796971 -125.105491) (xy 10.784845 -125.051054) (xy 10.780774 -124.995432) (xy 9.435493 -124.995432)
			(xy 9.427979 -125.04649) (xy 9.411911 -125.099897) (xy 9.388239 -125.150394) (xy 9.357466 -125.196907)
			(xy 9.320249 -125.238444) (xy 9.277381 -125.274119) (xy 9.229775 -125.303173) (xy 9.178446 -125.324985)
			(xy 9.124489 -125.339091) (xy 9.069052 -125.345191) (xy 9.013318 -125.343154) (xy 8.958475 -125.333024)
			(xy 8.905691 -125.315017) (xy 8.856091 -125.289516) (xy 8.810733 -125.257065) (xy 8.770584 -125.218356)
			(xy 8.736498 -125.174213) (xy 8.709202 -125.125578) (xy 8.689279 -125.073487) (xy 8.677153 -125.01905)
			(xy 8.673082 -124.963428) (xy 4.38404 -124.963428) (xy 4.38404 -125.403356) (xy 15.544292 -125.403356)
			(xy 15.544793 -125.375987) (xy 15.552603 -125.32181) (xy 15.568084 -125.269307) (xy 15.590918 -125.219559)
			(xy 15.620634 -125.173591) (xy 15.638272 -125.152658) (xy 15.638526 -125.152404) (xy 15.64412 -125.145323)
			(xy 15.650361 -125.128402) (xy 15.650718 -125.119384) (xy 15.650718 -125.052328) (xy 15.650344 -125.043313)
			(xy 15.644108 -125.026396) (xy 15.638526 -125.019308) (xy 15.638272 -125.019308) (xy 15.638272 -125.019054)
			(xy 15.62064 -124.998116) (xy 15.590928 -124.952144) (xy 15.568091 -124.902398) (xy 15.552599 -124.849899)
			(xy 15.544768 -124.795725) (xy 15.544292 -124.768356) (xy 15.544778 -124.741105) (xy 15.552534 -124.687157)
			(xy 15.567889 -124.634862) (xy 15.590531 -124.585285) (xy 15.619997 -124.539435) (xy 15.655688 -124.498244)
			(xy 15.696879 -124.462553) (xy 15.742729 -124.433087) (xy 15.792306 -124.410445) (xy 15.844601 -124.39509)
			(xy 15.898549 -124.387334) (xy 15.953051 -124.387334) (xy 16.006999 -124.39509) (xy 16.059294 -124.410445)
			(xy 16.108871 -124.433087) (xy 16.154721 -124.462553) (xy 16.195912 -124.498244) (xy 16.231603 -124.539435)
			(xy 16.261069 -124.585285) (xy 16.283711 -124.634862) (xy 16.299066 -124.687157) (xy 16.306822 -124.741105)
			(xy 16.307308 -124.768356) (xy 16.306814 -124.795725) (xy 16.299003 -124.849903) (xy 16.28352 -124.902406)
			(xy 16.260685 -124.952153) (xy 16.230966 -124.998121) (xy 16.213328 -125.019054) (xy 16.213074 -125.019308)
			(xy 16.207475 -125.026386) (xy 16.201237 -125.043309) (xy 16.200882 -125.052328) (xy 16.200882 -125.119384)
			(xy 16.201251 -125.1284) (xy 16.207491 -125.145316) (xy 16.213074 -125.152404) (xy 16.213328 -125.152404)
			(xy 16.213328 -125.152658) (xy 16.230965 -125.173591) (xy 16.260676 -125.219564) (xy 16.283512 -125.269312)
			(xy 16.299004 -125.321812) (xy 16.306833 -125.375987) (xy 16.307308 -125.403356) (xy 16.306822 -125.430607)
			(xy 16.299066 -125.484555) (xy 16.283711 -125.53685) (xy 16.261069 -125.586427) (xy 16.231603 -125.632277)
			(xy 16.195912 -125.673468) (xy 16.154721 -125.709159) (xy 16.108871 -125.738625) (xy 16.059294 -125.761267)
			(xy 16.006999 -125.776622) (xy 15.953051 -125.784378) (xy 15.898549 -125.784378) (xy 15.844601 -125.776622)
			(xy 15.792306 -125.761267) (xy 15.742729 -125.738625) (xy 15.696879 -125.709159) (xy 15.655688 -125.673468)
			(xy 15.619997 -125.632277) (xy 15.590531 -125.586427) (xy 15.567889 -125.53685) (xy 15.552534 -125.484555)
			(xy 15.544778 -125.430607) (xy 15.544292 -125.403356) (xy 4.38404 -125.403356) (xy 4.38404 -125.979428)
			(xy 8.673082 -125.979428) (xy 8.677153 -125.923806) (xy 8.689279 -125.869369) (xy 8.709202 -125.817278)
			(xy 8.736498 -125.768643) (xy 8.770584 -125.7245) (xy 8.810733 -125.685791) (xy 8.856091 -125.65334)
			(xy 8.905691 -125.627839) (xy 8.958475 -125.609832) (xy 9.013318 -125.599702) (xy 9.069052 -125.597665)
			(xy 9.124489 -125.603765) (xy 9.178446 -125.617871) (xy 9.229775 -125.639683) (xy 9.277381 -125.668737)
			(xy 9.320249 -125.704412) (xy 9.357466 -125.745949) (xy 9.388239 -125.792462) (xy 9.411911 -125.842959)
			(xy 9.427979 -125.896366) (xy 9.436099 -125.951542) (xy 9.436608 -125.979428) (xy 9.436557 -125.982222)
			(xy 11.113006 -125.982222) (xy 11.117077 -125.9266) (xy 11.129203 -125.872163) (xy 11.149126 -125.820072)
			(xy 11.176422 -125.771437) (xy 11.210508 -125.727294) (xy 11.250657 -125.688585) (xy 11.296015 -125.656134)
			(xy 11.345615 -125.630633) (xy 11.398399 -125.612626) (xy 11.453242 -125.602496) (xy 11.508976 -125.600459)
			(xy 11.564413 -125.606559) (xy 11.61837 -125.620665) (xy 11.669699 -125.642477) (xy 11.717305 -125.671531)
			(xy 11.760173 -125.707206) (xy 11.79739 -125.748743) (xy 11.828163 -125.795256) (xy 11.851835 -125.845753)
			(xy 11.854225 -125.853698) (xy 16.484854 -125.853698) (xy 16.485306 -125.826327) (xy 16.493125 -125.772147)
			(xy 16.508617 -125.719643) (xy 16.531462 -125.669896) (xy 16.561191 -125.623931) (xy 16.578834 -125.603)
			(xy 16.579088 -125.602746) (xy 16.58466 -125.595649) (xy 16.590916 -125.57874) (xy 16.59128 -125.569726)
			(xy 16.59128 -125.50267) (xy 16.590942 -125.493651) (xy 16.584682 -125.476734) (xy 16.579088 -125.46965)
			(xy 16.578834 -125.46965) (xy 16.578834 -125.469396) (xy 16.561185 -125.448472) (xy 16.531473 -125.402497)
			(xy 16.508639 -125.352748) (xy 16.49315 -125.300245) (xy 16.485326 -125.246068) (xy 16.484854 -125.218698)
			(xy 16.48534 -125.191447) (xy 16.493096 -125.137499) (xy 16.508451 -125.085204) (xy 16.531093 -125.035627)
			(xy 16.560559 -124.989777) (xy 16.59625 -124.948586) (xy 16.637441 -124.912895) (xy 16.683291 -124.883429)
			(xy 16.732868 -124.860787) (xy 16.785163 -124.845432) (xy 16.839111 -124.837676) (xy 16.893613 -124.837676)
			(xy 16.947561 -124.845432) (xy 16.999856 -124.860787) (xy 17.049433 -124.883429) (xy 17.095283 -124.912895)
			(xy 17.136474 -124.948586) (xy 17.172165 -124.989777) (xy 17.201631 -125.035627) (xy 17.224273 -125.085204)
			(xy 17.239628 -125.137499) (xy 17.247384 -125.191447) (xy 17.24787 -125.218698) (xy 17.24741 -125.246069)
			(xy 17.239592 -125.300248) (xy 17.224102 -125.352752) (xy 17.201258 -125.402498) (xy 17.171532 -125.448465)
			(xy 17.15389 -125.469396) (xy 17.153636 -125.46965) (xy 17.148057 -125.476741) (xy 17.141807 -125.493655)
			(xy 17.141444 -125.50267) (xy 17.141444 -125.569726) (xy 17.141779 -125.578745) (xy 17.148041 -125.595663)
			(xy 17.153636 -125.602746) (xy 17.15389 -125.602746) (xy 17.15389 -125.603) (xy 17.171541 -125.623923)
			(xy 17.201251 -125.669898) (xy 17.224085 -125.719648) (xy 17.239573 -125.772151) (xy 17.247398 -125.826328)
			(xy 17.24787 -125.853698) (xy 17.247384 -125.880949) (xy 17.239628 -125.934897) (xy 17.224273 -125.987192)
			(xy 17.201631 -126.036769) (xy 17.172165 -126.082619) (xy 17.136474 -126.12381) (xy 17.095283 -126.159501)
			(xy 17.049433 -126.188967) (xy 16.999856 -126.211609) (xy 16.947561 -126.226964) (xy 16.893613 -126.23472)
			(xy 16.839111 -126.23472) (xy 16.785163 -126.226964) (xy 16.732868 -126.211609) (xy 16.683291 -126.188967)
			(xy 16.637441 -126.159501) (xy 16.59625 -126.12381) (xy 16.560559 -126.082619) (xy 16.531093 -126.036769)
			(xy 16.508451 -125.987192) (xy 16.493096 -125.934897) (xy 16.48534 -125.880949) (xy 16.484854 -125.853698)
			(xy 11.854225 -125.853698) (xy 11.867903 -125.89916) (xy 11.876023 -125.954336) (xy 11.876532 -125.982222)
			(xy 11.876023 -126.010108) (xy 11.867903 -126.065284) (xy 11.851835 -126.118691) (xy 11.828163 -126.169188)
			(xy 11.79739 -126.215701) (xy 11.760173 -126.257238) (xy 11.717305 -126.292913) (xy 11.669699 -126.321967)
			(xy 11.61837 -126.343779) (xy 11.564413 -126.357885) (xy 11.508976 -126.363985) (xy 11.453242 -126.361948)
			(xy 11.398399 -126.351818) (xy 11.345615 -126.333811) (xy 11.296015 -126.30831) (xy 11.250657 -126.275859)
			(xy 11.210508 -126.23715) (xy 11.176422 -126.193007) (xy 11.149126 -126.144372) (xy 11.129203 -126.092281)
			(xy 11.117077 -126.037844) (xy 11.113006 -125.982222) (xy 9.436557 -125.982222) (xy 9.436099 -126.007314)
			(xy 9.427979 -126.06249) (xy 9.411911 -126.115897) (xy 9.388239 -126.166394) (xy 9.357466 -126.212907)
			(xy 9.320249 -126.254444) (xy 9.277381 -126.290119) (xy 9.229775 -126.319173) (xy 9.178446 -126.340985)
			(xy 9.124489 -126.355091) (xy 9.069052 -126.361191) (xy 9.013318 -126.359154) (xy 8.958475 -126.349024)
			(xy 8.905691 -126.331017) (xy 8.856091 -126.305516) (xy 8.810733 -126.273065) (xy 8.770584 -126.234356)
			(xy 8.736498 -126.190213) (xy 8.709202 -126.141578) (xy 8.689279 -126.089487) (xy 8.677153 -126.03505)
			(xy 8.673082 -125.979428) (xy 4.38404 -125.979428) (xy 4.38404 -126.530354) (xy 17.769586 -126.530354)
			(xy 17.770111 -126.501437) (xy 17.778834 -126.444265) (xy 17.796088 -126.389065) (xy 17.821479 -126.337102)
			(xy 17.854423 -126.289568) (xy 17.894166 -126.247553) (xy 17.916652 -126.229364) (xy 17.925474 -126.221772)
			(xy 17.935648 -126.200859) (xy 17.93621 -126.189232) (xy 17.93621 -126.109476) (xy 17.935667 -126.097845)
			(xy 17.92548 -126.076936) (xy 17.916652 -126.069344) (xy 17.89418 -126.05114) (xy 17.854446 -126.009122)
			(xy 17.821507 -125.961589) (xy 17.796117 -125.90963) (xy 17.778858 -125.854436) (xy 17.770124 -125.797269)
			(xy 17.769586 -125.768354) (xy 17.770035 -125.741102) (xy 17.777798 -125.687153) (xy 17.793158 -125.634858)
			(xy 17.815804 -125.585281) (xy 17.845275 -125.539431) (xy 17.88097 -125.498242) (xy 17.922163 -125.462551)
			(xy 17.968016 -125.433085) (xy 18.017596 -125.410444) (xy 18.069892 -125.395089) (xy 18.123842 -125.387332)
			(xy 18.151094 -125.386846) (xy 18.178465 -125.387304) (xy 18.232645 -125.395122) (xy 18.285148 -125.410613)
			(xy 18.334895 -125.433456) (xy 18.380861 -125.463183) (xy 18.401792 -125.480826) (xy 18.402046 -125.48108)
			(xy 18.409137 -125.486659) (xy 18.426051 -125.492908) (xy 18.435066 -125.493272) (xy 18.502122 -125.493272)
			(xy 18.511141 -125.492932) (xy 18.528058 -125.486673) (xy 18.535142 -125.48108) (xy 18.535142 -125.480826)
			(xy 18.535396 -125.480826) (xy 18.556322 -125.463179) (xy 18.602296 -125.433468) (xy 18.652045 -125.410633)
			(xy 18.704547 -125.395144) (xy 18.758724 -125.387318) (xy 18.786094 -125.386846) (xy 18.813343 -125.387383)
			(xy 18.867287 -125.395138) (xy 18.919577 -125.41049) (xy 18.969152 -125.433127) (xy 19.015 -125.462588)
			(xy 19.056189 -125.498274) (xy 19.091881 -125.539458) (xy 19.121348 -125.585303) (xy 19.143992 -125.634874)
			(xy 19.159351 -125.687163) (xy 19.167113 -125.741105) (xy 19.167602 -125.768354) (xy 19.16705 -125.79727)
			(xy 19.158328 -125.854439) (xy 19.141076 -125.909637) (xy 19.115691 -125.961599) (xy 19.082754 -126.009134)
			(xy 19.043019 -126.051153) (xy 19.020536 -126.069344) (xy 19.011708 -126.076931) (xy 19.001538 -126.097847)
			(xy 19.000978 -126.109476) (xy 19.000978 -126.189232) (xy 19.001521 -126.200863) (xy 19.011708 -126.221772)
			(xy 19.020536 -126.229364) (xy 19.04301 -126.247566) (xy 19.082744 -126.289585) (xy 19.115683 -126.337118)
			(xy 19.141073 -126.389077) (xy 19.158332 -126.444272) (xy 19.167065 -126.501439) (xy 19.167602 -126.530354)
			(xy 19.167102 -126.557606) (xy 19.159351 -126.611556) (xy 19.147251 -126.652782) (xy 19.438874 -126.652782)
			(xy 19.439311 -126.625411) (xy 19.447133 -126.571229) (xy 19.462628 -126.518725) (xy 19.485477 -126.468979)
			(xy 19.515209 -126.423014) (xy 19.532854 -126.402084) (xy 19.533108 -126.40183) (xy 19.538689 -126.39474)
			(xy 19.544939 -126.377826) (xy 19.5453 -126.36881) (xy 19.5453 -126.301754) (xy 19.544917 -126.29274)
			(xy 19.538687 -126.275823) (xy 19.533108 -126.268734) (xy 19.532854 -126.268734) (xy 19.532854 -126.26848)
			(xy 19.515195 -126.247562) (xy 19.485468 -126.201592) (xy 19.462622 -126.151844) (xy 19.447126 -126.099339)
			(xy 19.439299 -126.045158) (xy 19.439301 -125.990415) (xy 19.447132 -125.936234) (xy 19.462632 -125.883731)
			(xy 19.485481 -125.833984) (xy 19.515211 -125.788016) (xy 19.532854 -125.767084) (xy 19.533108 -125.76683)
			(xy 19.538689 -125.75974) (xy 19.544939 -125.742826) (xy 19.5453 -125.73381) (xy 19.5453 -125.666754)
			(xy 19.544917 -125.65774) (xy 19.538687 -125.640823) (xy 19.533108 -125.633734) (xy 19.532854 -125.633734)
			(xy 19.532854 -125.63348) (xy 19.515195 -125.612562) (xy 19.485468 -125.566592) (xy 19.462622 -125.516844)
			(xy 19.447126 -125.464339) (xy 19.439299 -125.410158) (xy 19.439301 -125.355415) (xy 19.447132 -125.301234)
			(xy 19.462632 -125.248731) (xy 19.485481 -125.198984) (xy 19.515211 -125.153016) (xy 19.532854 -125.132084)
			(xy 19.533108 -125.13183) (xy 19.538689 -125.12474) (xy 19.544939 -125.107826) (xy 19.5453 -125.09881)
			(xy 19.5453 -125.031754) (xy 19.544917 -125.02274) (xy 19.538687 -125.005823) (xy 19.533108 -124.998734)
			(xy 19.532854 -124.998734) (xy 19.532854 -124.99848) (xy 19.515247 -124.977522) (xy 19.485529 -124.931557)
			(xy 19.462686 -124.881816) (xy 19.447187 -124.829321) (xy 19.439352 -124.77515) (xy 19.438874 -124.747782)
			(xy 19.43936 -124.720531) (xy 19.447116 -124.666583) (xy 19.462471 -124.614288) (xy 19.485113 -124.564711)
			(xy 19.514579 -124.518861) (xy 19.55027 -124.47767) (xy 19.591461 -124.441979) (xy 19.637311 -124.412513)
			(xy 19.686888 -124.389871) (xy 19.739183 -124.374516) (xy 19.793131 -124.36676) (xy 19.847633 -124.36676)
			(xy 19.901581 -124.374516) (xy 19.953876 -124.389871) (xy 20.003453 -124.412513) (xy 20.049303 -124.441979)
			(xy 20.090494 -124.47767) (xy 20.126185 -124.518861) (xy 20.155651 -124.564711) (xy 20.178293 -124.614288)
			(xy 20.193648 -124.666583) (xy 20.201404 -124.720531) (xy 20.20189 -124.747782) (xy 20.201416 -124.775152)
			(xy 20.1936 -124.829331) (xy 20.178113 -124.881834) (xy 20.155273 -124.931581) (xy 20.12555 -124.977548)
			(xy 20.10791 -124.99848) (xy 20.107656 -124.998734) (xy 20.102086 -125.005831) (xy 20.09583 -125.02274)
			(xy 20.095464 -125.031754) (xy 20.095464 -125.09881) (xy 20.095824 -125.107826) (xy 20.10207 -125.124743)
			(xy 20.107656 -125.13183) (xy 20.10791 -125.13183) (xy 20.10791 -125.132084) (xy 20.125532 -125.153032)
			(xy 20.155254 -125.198998) (xy 20.178098 -125.248742) (xy 20.193594 -125.301241) (xy 20.201424 -125.355417)
			(xy 20.201426 -125.410156) (xy 20.1936 -125.464332) (xy 20.184686 -125.494542) (xy 37.31006 -125.494542)
			(xy 37.31006 -124.630942) (xy 37.31055 -124.600974) (xy 37.318373 -124.541552) (xy 37.333886 -124.483659)
			(xy 37.356822 -124.428286) (xy 37.386789 -124.37638) (xy 37.423276 -124.32883) (xy 37.465656 -124.28645)
			(xy 37.513206 -124.249963) (xy 37.565112 -124.219996) (xy 37.620485 -124.19706) (xy 37.678378 -124.181547)
			(xy 37.7378 -124.173724) (xy 37.797736 -124.173724) (xy 37.857158 -124.181547) (xy 37.915051 -124.19706)
			(xy 37.970424 -124.219996) (xy 38.02233 -124.249963) (xy 38.06988 -124.28645) (xy 38.11226 -124.32883)
			(xy 38.148747 -124.37638) (xy 38.178714 -124.428286) (xy 38.20165 -124.483659) (xy 38.217163 -124.541552)
			(xy 38.224986 -124.600974) (xy 38.225476 -124.630942) (xy 38.225476 -125.486414) (xy 51.785012 -125.486414)
			(xy 51.785012 -124.622814) (xy 51.785502 -124.592846) (xy 51.793325 -124.533424) (xy 51.808838 -124.475531)
			(xy 51.831774 -124.420158) (xy 51.861741 -124.368252) (xy 51.898228 -124.320702) (xy 51.940608 -124.278322)
			(xy 51.988158 -124.241835) (xy 52.040064 -124.211868) (xy 52.095437 -124.188932) (xy 52.15333 -124.173419)
			(xy 52.212752 -124.165596) (xy 52.272688 -124.165596) (xy 52.33211 -124.173419) (xy 52.390003 -124.188932)
			(xy 52.445376 -124.211868) (xy 52.497282 -124.241835) (xy 52.544832 -124.278322) (xy 52.587212 -124.320702)
			(xy 52.623699 -124.368252) (xy 52.653666 -124.420158) (xy 52.676602 -124.475531) (xy 52.692115 -124.533424)
			(xy 52.699938 -124.592846) (xy 52.700428 -124.622814) (xy 52.700428 -124.967238) (xy 64.745108 -124.967238)
			(xy 64.745108 -124.103638) (xy 64.745598 -124.073654) (xy 64.753426 -124.014198) (xy 64.768947 -123.956273)
			(xy 64.791896 -123.900869) (xy 64.82188 -123.848935) (xy 64.858386 -123.801359) (xy 64.900791 -123.758954)
			(xy 64.948367 -123.722448) (xy 65.000301 -123.692464) (xy 65.055705 -123.669515) (xy 65.11363 -123.653994)
			(xy 65.173086 -123.646166) (xy 65.233054 -123.646166) (xy 65.29251 -123.653994) (xy 65.350435 -123.669515)
			(xy 65.405839 -123.692464) (xy 65.457773 -123.722448) (xy 65.505349 -123.758954) (xy 65.547754 -123.801359)
			(xy 65.58426 -123.848935) (xy 65.614244 -123.900869) (xy 65.637193 -123.956273) (xy 65.652714 -124.014198)
			(xy 65.660542 -124.073654) (xy 65.661032 -124.103638) (xy 65.661032 -124.965714) (xy 83.716368 -124.965714)
			(xy 83.716368 -124.102114) (xy 83.716858 -124.07213) (xy 83.724686 -124.012674) (xy 83.740207 -123.954749)
			(xy 83.763156 -123.899345) (xy 83.79314 -123.847411) (xy 83.829646 -123.799835) (xy 83.872051 -123.75743)
			(xy 83.919627 -123.720924) (xy 83.971561 -123.69094) (xy 84.026965 -123.667991) (xy 84.08489 -123.65247)
			(xy 84.144346 -123.644642) (xy 84.204314 -123.644642) (xy 84.26377 -123.65247) (xy 84.321695 -123.667991)
			(xy 84.377099 -123.69094) (xy 84.429033 -123.720924) (xy 84.476609 -123.75743) (xy 84.519014 -123.799835)
			(xy 84.55552 -123.847411) (xy 84.585504 -123.899345) (xy 84.608453 -123.954749) (xy 84.623974 -124.012674)
			(xy 84.631802 -124.07213) (xy 84.632292 -124.102114) (xy 84.632292 -124.965714) (xy 84.631802 -124.995698)
			(xy 84.623974 -125.055154) (xy 84.608453 -125.113079) (xy 84.585504 -125.168483) (xy 84.55552 -125.220417)
			(xy 84.519014 -125.267993) (xy 84.476609 -125.310398) (xy 84.429033 -125.346904) (xy 84.377099 -125.376888)
			(xy 84.321695 -125.399837) (xy 84.26377 -125.415358) (xy 84.204314 -125.423186) (xy 84.144346 -125.423186)
			(xy 84.08489 -125.415358) (xy 84.026965 -125.399837) (xy 83.971561 -125.376888) (xy 83.919627 -125.346904)
			(xy 83.872051 -125.310398) (xy 83.829646 -125.267993) (xy 83.79314 -125.220417) (xy 83.763156 -125.168483)
			(xy 83.740207 -125.113079) (xy 83.724686 -125.055154) (xy 83.716858 -124.995698) (xy 83.716368 -124.965714)
			(xy 65.661032 -124.965714) (xy 65.661032 -124.967238) (xy 65.660542 -124.997222) (xy 65.652714 -125.056678)
			(xy 65.637193 -125.114603) (xy 65.614244 -125.170007) (xy 65.58426 -125.221941) (xy 65.547754 -125.269517)
			(xy 65.505349 -125.311922) (xy 65.457773 -125.348428) (xy 65.405839 -125.378412) (xy 65.350435 -125.401361)
			(xy 65.29251 -125.416882) (xy 65.233054 -125.42471) (xy 65.173086 -125.42471) (xy 65.11363 -125.416882)
			(xy 65.055705 -125.401361) (xy 65.000301 -125.378412) (xy 64.948367 -125.348428) (xy 64.900791 -125.311922)
			(xy 64.858386 -125.269517) (xy 64.82188 -125.221941) (xy 64.791896 -125.170007) (xy 64.768947 -125.114603)
			(xy 64.753426 -125.056678) (xy 64.745598 -124.997222) (xy 64.745108 -124.967238) (xy 52.700428 -124.967238)
			(xy 52.700428 -125.486414) (xy 52.699938 -125.516382) (xy 52.692115 -125.575804) (xy 52.676602 -125.633697)
			(xy 52.653666 -125.68907) (xy 52.623699 -125.740976) (xy 52.587212 -125.788526) (xy 52.544832 -125.830906)
			(xy 52.497282 -125.867393) (xy 52.445376 -125.89736) (xy 52.390003 -125.920296) (xy 52.33211 -125.935809)
			(xy 52.272688 -125.943632) (xy 52.212752 -125.943632) (xy 52.15333 -125.935809) (xy 52.095437 -125.920296)
			(xy 52.040064 -125.89736) (xy 51.988158 -125.867393) (xy 51.940608 -125.830906) (xy 51.898228 -125.788526)
			(xy 51.861741 -125.740976) (xy 51.831774 -125.68907) (xy 51.808838 -125.633697) (xy 51.793325 -125.575804)
			(xy 51.785502 -125.516382) (xy 51.785012 -125.486414) (xy 38.225476 -125.486414) (xy 38.225476 -125.494542)
			(xy 38.224986 -125.52451) (xy 38.217163 -125.583932) (xy 38.20165 -125.641825) (xy 38.178714 -125.697198)
			(xy 38.148747 -125.749104) (xy 38.11226 -125.796654) (xy 38.06988 -125.839034) (xy 38.02233 -125.875521)
			(xy 37.970424 -125.905488) (xy 37.915051 -125.928424) (xy 37.857158 -125.943937) (xy 37.797736 -125.95176)
			(xy 37.7378 -125.95176) (xy 37.678378 -125.943937) (xy 37.620485 -125.928424) (xy 37.565112 -125.905488)
			(xy 37.513206 -125.875521) (xy 37.465656 -125.839034) (xy 37.423276 -125.796654) (xy 37.386789 -125.749104)
			(xy 37.356822 -125.697198) (xy 37.333886 -125.641825) (xy 37.318373 -125.583932) (xy 37.31055 -125.52451)
			(xy 37.31006 -125.494542) (xy 20.184686 -125.494542) (xy 20.178108 -125.516833) (xy 20.155267 -125.566578)
			(xy 20.125548 -125.612547) (xy 20.10791 -125.63348) (xy 20.107656 -125.633734) (xy 20.102086 -125.640831)
			(xy 20.09583 -125.65774) (xy 20.095464 -125.666754) (xy 20.095464 -125.73381) (xy 20.095824 -125.742826)
			(xy 20.10207 -125.759743) (xy 20.107656 -125.76683) (xy 20.10791 -125.76683) (xy 20.10791 -125.767084)
			(xy 20.125532 -125.788032) (xy 20.155254 -125.833998) (xy 20.178098 -125.883742) (xy 20.193594 -125.936241)
			(xy 20.201424 -125.990417) (xy 20.201426 -126.045156) (xy 20.1936 -126.099332) (xy 20.178108 -126.151833)
			(xy 20.155267 -126.201578) (xy 20.125548 -126.247547) (xy 20.10791 -126.26848) (xy 20.107656 -126.268734)
			(xy 20.102086 -126.275831) (xy 20.09583 -126.29274) (xy 20.095464 -126.301754) (xy 20.095464 -126.36881)
			(xy 20.095824 -126.377826) (xy 20.10207 -126.394743) (xy 20.107656 -126.40183) (xy 20.10791 -126.40183)
			(xy 20.10791 -126.402084) (xy 20.125557 -126.42301) (xy 20.155267 -126.468985) (xy 20.178101 -126.518734)
			(xy 20.193591 -126.571236) (xy 20.201417 -126.625412) (xy 20.20189 -126.652782) (xy 20.201404 -126.680033)
			(xy 20.193648 -126.733981) (xy 20.178293 -126.786276) (xy 20.155651 -126.835853) (xy 20.126185 -126.881703)
			(xy 20.090494 -126.922894) (xy 20.049303 -126.958585) (xy 20.003453 -126.988051) (xy 19.953876 -127.010693)
			(xy 19.901581 -127.026048) (xy 19.847633 -127.033804) (xy 19.793131 -127.033804) (xy 19.739183 -127.026048)
			(xy 19.686888 -127.010693) (xy 19.637311 -126.988051) (xy 19.591461 -126.958585) (xy 19.55027 -126.922894)
			(xy 19.514579 -126.881703) (xy 19.485113 -126.835853) (xy 19.462471 -126.786276) (xy 19.447116 -126.733981)
			(xy 19.43936 -126.680033) (xy 19.438874 -126.652782) (xy 19.147251 -126.652782) (xy 19.144001 -126.663853)
			(xy 19.121363 -126.713434) (xy 19.091899 -126.759287) (xy 19.056209 -126.800481) (xy 19.01502 -126.836175)
			(xy 18.969169 -126.865644) (xy 18.919591 -126.888287) (xy 18.867295 -126.903643) (xy 18.813346 -126.911399)
			(xy 18.786094 -126.911862) (xy 18.758723 -126.911409) (xy 18.704543 -126.903589) (xy 18.65204 -126.888098)
			(xy 18.602293 -126.865253) (xy 18.556327 -126.835525) (xy 18.535396 -126.817882) (xy 18.535142 -126.817628)
			(xy 18.528054 -126.812044) (xy 18.511138 -126.805798) (xy 18.502122 -126.805436) (xy 18.435066 -126.805436)
			(xy 18.426047 -126.805769) (xy 18.409129 -126.812032) (xy 18.402046 -126.817628) (xy 18.402046 -126.817882)
			(xy 18.401792 -126.817882) (xy 18.380871 -126.835536) (xy 18.334896 -126.865246) (xy 18.285145 -126.888079)
			(xy 18.232642 -126.903567) (xy 18.178464 -126.911391) (xy 18.151094 -126.911862) (xy 18.123839 -126.91145)
			(xy 18.069884 -126.903691) (xy 18.017582 -126.888332) (xy 17.967999 -126.865685) (xy 17.922144 -126.836213)
			(xy 17.88095 -126.800513) (xy 17.845256 -126.759315) (xy 17.81579 -126.713455) (xy 17.79315 -126.663869)
			(xy 17.777798 -126.611565) (xy 17.770046 -126.557609) (xy 17.769586 -126.530354) (xy 4.38404 -126.530354)
			(xy 4.38404 -127.051308) (xy 10.744198 -127.051308) (xy 10.748269 -126.995686) (xy 10.760395 -126.941249)
			(xy 10.780318 -126.889158) (xy 10.807614 -126.840523) (xy 10.8417 -126.79638) (xy 10.881849 -126.757671)
			(xy 10.927207 -126.72522) (xy 10.976807 -126.699719) (xy 11.029591 -126.681712) (xy 11.084434 -126.671582)
			(xy 11.140168 -126.669545) (xy 11.195605 -126.675645) (xy 11.249562 -126.689751) (xy 11.300891 -126.711563)
			(xy 11.348497 -126.740617) (xy 11.391365 -126.776292) (xy 11.428582 -126.817829) (xy 11.459355 -126.864342)
			(xy 11.483027 -126.914839) (xy 11.499095 -126.968246) (xy 11.507215 -127.023422) (xy 11.507724 -127.051308)
			(xy 11.507215 -127.079194) (xy 11.499095 -127.13437) (xy 11.483027 -127.187777) (xy 11.459355 -127.238274)
			(xy 11.428582 -127.284787) (xy 11.391365 -127.326324) (xy 11.348497 -127.361999) (xy 11.300891 -127.391053)
			(xy 11.249562 -127.412865) (xy 11.195605 -127.426971) (xy 11.140168 -127.433071) (xy 11.084434 -127.431034)
			(xy 11.029591 -127.420904) (xy 10.976807 -127.402897) (xy 10.927207 -127.377396) (xy 10.881849 -127.344945)
			(xy 10.8417 -127.306236) (xy 10.807614 -127.262093) (xy 10.780318 -127.213458) (xy 10.760395 -127.161367)
			(xy 10.748269 -127.10693) (xy 10.744198 -127.051308) (xy 4.38404 -127.051308) (xy 4.38404 -128.252803)
			(xy 9.728405 -128.252803) (xy 9.728405 -128.198297) (xy 9.736162 -128.144346) (xy 9.751519 -128.092048)
			(xy 9.774161 -128.042467) (xy 9.80363 -127.996614) (xy 9.839324 -127.955421) (xy 9.880517 -127.919727)
			(xy 9.926371 -127.89026) (xy 9.975951 -127.867617) (xy 10.02825 -127.852262) (xy 10.082201 -127.844505)
			(xy 10.109454 -127.844042) (xy 10.136824 -127.844525) (xy 10.191003 -127.852337) (xy 10.243506 -127.867822)
			(xy 10.293253 -127.89066) (xy 10.33922 -127.920382) (xy 10.360152 -127.938022) (xy 10.360406 -127.938276)
			(xy 10.36748 -127.94388) (xy 10.384407 -127.950114) (xy 10.393426 -127.950468) (xy 10.460482 -127.950468)
			(xy 10.469499 -127.950109) (xy 10.486416 -127.943863) (xy 10.493502 -127.938276) (xy 10.493502 -127.938022)
			(xy 10.493756 -127.938022) (xy 10.514689 -127.920381) (xy 10.560657 -127.890657) (xy 10.610403 -127.867811)
			(xy 10.662905 -127.852315) (xy 10.717083 -127.844486) (xy 10.771825 -127.844486) (xy 10.826003 -127.852315)
			(xy 10.878505 -127.867811) (xy 10.928251 -127.890657) (xy 10.974219 -127.920381) (xy 10.995152 -127.938022)
			(xy 10.995406 -127.938276) (xy 11.00248 -127.94388) (xy 11.019407 -127.950114) (xy 11.028426 -127.950468)
			(xy 11.095482 -127.950468) (xy 11.104499 -127.950109) (xy 11.121416 -127.943863) (xy 11.128502 -127.938276)
			(xy 11.128502 -127.938022) (xy 11.128756 -127.938022) (xy 11.149697 -127.920393) (xy 11.195667 -127.890679)
			(xy 11.245412 -127.867841) (xy 11.297911 -127.852348) (xy 11.352085 -127.844517) (xy 11.379454 -127.844042)
			(xy 11.406705 -127.844528) (xy 11.460652 -127.852285) (xy 11.512947 -127.867641) (xy 11.562523 -127.890282)
			(xy 11.608373 -127.919748) (xy 11.649563 -127.95544) (xy 11.685254 -127.99663) (xy 11.71472 -128.04248)
			(xy 11.737361 -128.092057) (xy 11.752716 -128.144352) (xy 11.760472 -128.198299) (xy 11.760472 -128.252801)
			(xy 11.752716 -128.306748) (xy 11.737361 -128.359043) (xy 11.71472 -128.40862) (xy 11.685254 -128.45447)
			(xy 11.649563 -128.49566) (xy 11.608373 -128.531352) (xy 11.562523 -128.560818) (xy 11.512947 -128.583459)
			(xy 11.460652 -128.598815) (xy 11.406705 -128.606572) (xy 11.379454 -128.607058) (xy 11.352084 -128.606571)
			(xy 11.297906 -128.598759) (xy 11.245403 -128.583276) (xy 11.195655 -128.560439) (xy 11.149688 -128.530718)
			(xy 11.128756 -128.513078) (xy 11.128502 -128.512824) (xy 11.121425 -128.507223) (xy 11.104501 -128.500987)
			(xy 11.095482 -128.500632) (xy 11.028426 -128.500632) (xy 11.01941 -128.500995) (xy 11.002492 -128.507238)
			(xy 10.995406 -128.512824) (xy 10.995152 -128.513078) (xy 10.974219 -128.530719) (xy 10.928251 -128.560443)
			(xy 10.878505 -128.583289) (xy 10.826003 -128.598785) (xy 10.771825 -128.606614) (xy 10.717083 -128.606614)
			(xy 10.662905 -128.598785) (xy 10.610403 -128.583289) (xy 10.560657 -128.560443) (xy 10.514689 -128.530719)
			(xy 10.493756 -128.513078) (xy 10.493502 -128.512824) (xy 10.486425 -128.507223) (xy 10.469501 -128.500987)
			(xy 10.460482 -128.500632) (xy 10.393426 -128.500632) (xy 10.38441 -128.500995) (xy 10.367492 -128.507238)
			(xy 10.360406 -128.512824) (xy 10.360406 -128.513078) (xy 10.360152 -128.513078) (xy 10.339208 -128.530703)
			(xy 10.293239 -128.560418) (xy 10.243495 -128.583257) (xy 10.190996 -128.598751) (xy 10.136822 -128.606582)
			(xy 10.109454 -128.607058) (xy 10.082201 -128.606595) (xy 10.02825 -128.598838) (xy 9.975951 -128.583483)
			(xy 9.926371 -128.56084) (xy 9.880517 -128.531373) (xy 9.839324 -128.495679) (xy 9.80363 -128.454486)
			(xy 9.774161 -128.408633) (xy 9.751519 -128.359052) (xy 9.736162 -128.306754) (xy 9.728405 -128.252803)
			(xy 4.38404 -128.252803) (xy 4.38404 -131.447101) (xy 9.713452 -131.447101) (xy 9.713452 -131.392599)
			(xy 9.721208 -131.338652) (xy 9.736563 -131.286358) (xy 9.759204 -131.236782) (xy 9.78867 -131.190932)
			(xy 9.824361 -131.149742) (xy 9.86555 -131.114051) (xy 9.9114 -131.084585) (xy 9.960976 -131.061944)
			(xy 10.01327 -131.046589) (xy 10.067217 -131.038832) (xy 10.094468 -131.038346) (xy 10.121838 -131.03882)
			(xy 10.176017 -131.046634) (xy 10.228521 -131.062121) (xy 10.278268 -131.084961) (xy 10.324235 -131.114685)
			(xy 10.345166 -131.132326) (xy 10.34542 -131.13258) (xy 10.35249 -131.13819) (xy 10.36942 -131.144421)
			(xy 10.37844 -131.144772) (xy 10.445496 -131.144772) (xy 10.454513 -131.144419) (xy 10.471431 -131.13817)
			(xy 10.478516 -131.13258) (xy 10.478516 -131.132326) (xy 10.47877 -131.132326) (xy 10.499703 -131.114685)
			(xy 10.545671 -131.084961) (xy 10.595417 -131.062115) (xy 10.647919 -131.046619) (xy 10.702097 -131.03879)
			(xy 10.756839 -131.03879) (xy 10.811017 -131.046619) (xy 10.863519 -131.062115) (xy 10.913265 -131.084961)
			(xy 10.959233 -131.114685) (xy 10.980166 -131.132326) (xy 10.98042 -131.13258) (xy 10.98749 -131.13819)
			(xy 11.00442 -131.144421) (xy 11.01344 -131.144772) (xy 11.080496 -131.144772) (xy 11.089513 -131.144419)
			(xy 11.106431 -131.13817) (xy 11.113516 -131.13258) (xy 11.113516 -131.132326) (xy 11.11377 -131.132326)
			(xy 11.134706 -131.114692) (xy 11.180677 -131.084978) (xy 11.230424 -131.062141) (xy 11.282924 -131.046649)
			(xy 11.337099 -131.03882) (xy 11.364468 -131.038346) (xy 11.391721 -131.038801) (xy 11.445673 -131.046558)
			(xy 11.497972 -131.061914) (xy 11.547552 -131.084557) (xy 11.593406 -131.114025) (xy 11.6346 -131.149719)
			(xy 11.670294 -131.190912) (xy 11.699762 -131.236766) (xy 11.722405 -131.286347) (xy 11.725807 -131.297934)
			(xy 34.667952 -131.297934) (xy 34.667952 -130.434334) (xy 34.668442 -130.404366) (xy 34.676265 -130.344944)
			(xy 34.691778 -130.287051) (xy 34.714714 -130.231678) (xy 34.744681 -130.179772) (xy 34.781168 -130.132222)
			(xy 34.823548 -130.089842) (xy 34.871098 -130.053355) (xy 34.923004 -130.023388) (xy 34.978377 -130.000452)
			(xy 35.03627 -129.984939) (xy 35.095692 -129.977116) (xy 35.155628 -129.977116) (xy 35.21505 -129.984939)
			(xy 35.272943 -130.000452) (xy 35.328316 -130.023388) (xy 35.380222 -130.053355) (xy 35.427772 -130.089842)
			(xy 35.470152 -130.132222) (xy 35.506639 -130.179772) (xy 35.536606 -130.231678) (xy 35.559542 -130.287051)
			(xy 35.575055 -130.344944) (xy 35.582878 -130.404366) (xy 35.583368 -130.434334) (xy 35.583368 -131.29641)
			(xy 53.639212 -131.29641) (xy 53.639212 -130.43281) (xy 53.639702 -130.402842) (xy 53.647525 -130.34342)
			(xy 53.663038 -130.285527) (xy 53.685974 -130.230154) (xy 53.715941 -130.178248) (xy 53.752428 -130.130698)
			(xy 53.794808 -130.088318) (xy 53.842358 -130.051831) (xy 53.894264 -130.021864) (xy 53.949637 -129.998928)
			(xy 54.00753 -129.983415) (xy 54.066952 -129.975592) (xy 54.126888 -129.975592) (xy 54.18631 -129.983415)
			(xy 54.244203 -129.998928) (xy 54.299576 -130.021864) (xy 54.351482 -130.051831) (xy 54.399032 -130.088318)
			(xy 54.441412 -130.130698) (xy 54.477899 -130.178248) (xy 54.507866 -130.230154) (xy 54.530802 -130.285527)
			(xy 54.546315 -130.34342) (xy 54.554138 -130.402842) (xy 54.554628 -130.43281) (xy 54.554628 -130.777234)
			(xy 66.599308 -130.777234) (xy 66.599308 -129.913634) (xy 66.599798 -129.88365) (xy 66.607626 -129.824194)
			(xy 66.623147 -129.766269) (xy 66.646096 -129.710865) (xy 66.67608 -129.658931) (xy 66.712586 -129.611355)
			(xy 66.754991 -129.56895) (xy 66.802567 -129.532444) (xy 66.854501 -129.50246) (xy 66.909905 -129.479511)
			(xy 66.96783 -129.46399) (xy 67.027286 -129.456162) (xy 67.087254 -129.456162) (xy 67.14671 -129.46399)
			(xy 67.204635 -129.479511) (xy 67.260039 -129.50246) (xy 67.311973 -129.532444) (xy 67.359549 -129.56895)
			(xy 67.401954 -129.611355) (xy 67.43846 -129.658931) (xy 67.468444 -129.710865) (xy 67.491393 -129.766269)
			(xy 67.506914 -129.824194) (xy 67.514742 -129.88365) (xy 67.515232 -129.913634) (xy 67.515232 -130.769106)
			(xy 81.07426 -130.769106) (xy 81.07426 -129.905506) (xy 81.07475 -129.875522) (xy 81.082578 -129.816066)
			(xy 81.098099 -129.758141) (xy 81.121048 -129.702737) (xy 81.151032 -129.650803) (xy 81.187538 -129.603227)
			(xy 81.229943 -129.560822) (xy 81.277519 -129.524316) (xy 81.329453 -129.494332) (xy 81.384857 -129.471383)
			(xy 81.442782 -129.455862) (xy 81.502238 -129.448034) (xy 81.562206 -129.448034) (xy 81.621662 -129.455862)
			(xy 81.679587 -129.471383) (xy 81.734991 -129.494332) (xy 81.786925 -129.524316) (xy 81.834501 -129.560822)
			(xy 81.876906 -129.603227) (xy 81.913412 -129.650803) (xy 81.943396 -129.702737) (xy 81.966345 -129.758141)
			(xy 81.981866 -129.816066) (xy 81.989694 -129.875522) (xy 81.990184 -129.905506) (xy 81.990184 -130.769106)
			(xy 81.989694 -130.79909) (xy 81.981866 -130.858546) (xy 81.966345 -130.916471) (xy 81.943396 -130.971875)
			(xy 81.913412 -131.023809) (xy 81.876906 -131.071385) (xy 81.834501 -131.11379) (xy 81.786925 -131.150296)
			(xy 81.734991 -131.18028) (xy 81.679587 -131.203229) (xy 81.621662 -131.21875) (xy 81.562206 -131.226578)
			(xy 81.502238 -131.226578) (xy 81.442782 -131.21875) (xy 81.384857 -131.203229) (xy 81.329453 -131.18028)
			(xy 81.277519 -131.150296) (xy 81.229943 -131.11379) (xy 81.187538 -131.071385) (xy 81.151032 -131.023809)
			(xy 81.121048 -130.971875) (xy 81.098099 -130.916471) (xy 81.082578 -130.858546) (xy 81.07475 -130.79909)
			(xy 81.07426 -130.769106) (xy 67.515232 -130.769106) (xy 67.515232 -130.777234) (xy 67.514742 -130.807218)
			(xy 67.506914 -130.866674) (xy 67.491393 -130.924599) (xy 67.468444 -130.980003) (xy 67.43846 -131.031937)
			(xy 67.401954 -131.079513) (xy 67.359549 -131.121918) (xy 67.311973 -131.158424) (xy 67.260039 -131.188408)
			(xy 67.204635 -131.211357) (xy 67.14671 -131.226878) (xy 67.087254 -131.234706) (xy 67.027286 -131.234706)
			(xy 66.96783 -131.226878) (xy 66.909905 -131.211357) (xy 66.854501 -131.188408) (xy 66.802567 -131.158424)
			(xy 66.754991 -131.121918) (xy 66.712586 -131.079513) (xy 66.67608 -131.031937) (xy 66.646096 -130.980003)
			(xy 66.623147 -130.924599) (xy 66.607626 -130.866674) (xy 66.599798 -130.807218) (xy 66.599308 -130.777234)
			(xy 54.554628 -130.777234) (xy 54.554628 -131.29641) (xy 54.554138 -131.326378) (xy 54.546315 -131.3858)
			(xy 54.530802 -131.443693) (xy 54.507866 -131.499066) (xy 54.477899 -131.550972) (xy 54.441412 -131.598522)
			(xy 54.399032 -131.640902) (xy 54.351482 -131.677389) (xy 54.299576 -131.707356) (xy 54.244203 -131.730292)
			(xy 54.18631 -131.745805) (xy 54.126888 -131.753628) (xy 54.066952 -131.753628) (xy 54.00753 -131.745805)
			(xy 53.949637 -131.730292) (xy 53.894264 -131.707356) (xy 53.842358 -131.677389) (xy 53.794808 -131.640902)
			(xy 53.752428 -131.598522) (xy 53.715941 -131.550972) (xy 53.685974 -131.499066) (xy 53.663038 -131.443693)
			(xy 53.647525 -131.3858) (xy 53.639702 -131.326378) (xy 53.639212 -131.29641) (xy 35.583368 -131.29641)
			(xy 35.583368 -131.297934) (xy 35.582878 -131.327902) (xy 35.575055 -131.387324) (xy 35.559542 -131.445217)
			(xy 35.536606 -131.50059) (xy 35.506639 -131.552496) (xy 35.470152 -131.600046) (xy 35.427772 -131.642426)
			(xy 35.380222 -131.678913) (xy 35.328316 -131.70888) (xy 35.272943 -131.731816) (xy 35.21505 -131.747329)
			(xy 35.155628 -131.755152) (xy 35.095692 -131.755152) (xy 35.03627 -131.747329) (xy 34.978377 -131.731816)
			(xy 34.923004 -131.70888) (xy 34.871098 -131.678913) (xy 34.823548 -131.642426) (xy 34.781168 -131.600046)
			(xy 34.744681 -131.552496) (xy 34.714714 -131.50059) (xy 34.691778 -131.445217) (xy 34.676265 -131.387324)
			(xy 34.668442 -131.327902) (xy 34.667952 -131.297934) (xy 11.725807 -131.297934) (xy 11.737762 -131.338645)
			(xy 11.745519 -131.392597) (xy 11.745519 -131.447103) (xy 11.737762 -131.501055) (xy 11.722405 -131.553353)
			(xy 11.699762 -131.602934) (xy 11.670294 -131.648788) (xy 11.6346 -131.689981) (xy 11.593406 -131.725675)
			(xy 11.547552 -131.755143) (xy 11.497972 -131.777786) (xy 11.445673 -131.793142) (xy 11.391721 -131.800899)
			(xy 11.364468 -131.801362) (xy 11.337097 -131.800924) (xy 11.282916 -131.793101) (xy 11.230412 -131.777606)
			(xy 11.180666 -131.754757) (xy 11.1347 -131.725026) (xy 11.11377 -131.707382) (xy 11.113516 -131.707128)
			(xy 11.106435 -131.701534) (xy 11.089514 -131.695294) (xy 11.080496 -131.694936) (xy 11.01344 -131.694936)
			(xy 11.004424 -131.695304) (xy 10.987507 -131.701543) (xy 10.98042 -131.707128) (xy 10.980166 -131.707382)
			(xy 10.959233 -131.725023) (xy 10.913265 -131.754747) (xy 10.863519 -131.777593) (xy 10.811017 -131.793089)
			(xy 10.756839 -131.800918) (xy 10.702097 -131.800918) (xy 10.647919 -131.793089) (xy 10.595417 -131.777593)
			(xy 10.545671 -131.754747) (xy 10.499703 -131.725023) (xy 10.47877 -131.707382) (xy 10.478516 -131.707128)
			(xy 10.471435 -131.701534) (xy 10.454514 -131.695294) (xy 10.445496 -131.694936) (xy 10.37844 -131.694936)
			(xy 10.369424 -131.695304) (xy 10.352507 -131.701543) (xy 10.34542 -131.707128) (xy 10.34542 -131.707382)
			(xy 10.345166 -131.707382) (xy 10.324218 -131.725001) (xy 10.27825 -131.754716) (xy 10.228506 -131.777556)
			(xy 10.176009 -131.793052) (xy 10.121836 -131.800885) (xy 10.094468 -131.801362) (xy 10.067217 -131.800868)
			(xy 10.01327 -131.793111) (xy 9.960976 -131.777756) (xy 9.9114 -131.755115) (xy 9.86555 -131.725649)
			(xy 9.824361 -131.689958) (xy 9.78867 -131.648768) (xy 9.759204 -131.602918) (xy 9.736563 -131.553342)
			(xy 9.721208 -131.501048) (xy 9.713452 -131.447101) (xy 4.38404 -131.447101) (xy 4.38404 -133.443726)
			(xy 11.122914 -133.443726) (xy 11.123394 -133.417412) (xy 11.130626 -133.365284) (xy 11.144942 -133.314642)
			(xy 11.166072 -133.266442) (xy 11.193616 -133.221599) (xy 11.227053 -133.180959) (xy 11.246104 -133.162802)
			(xy 11.253507 -133.155282) (xy 11.26203 -133.136001) (xy 11.262614 -133.125464) (xy 11.262614 -133.050788)
			(xy 11.262101 -133.040237) (xy 11.253554 -133.020942) (xy 11.246104 -133.01345) (xy 11.227032 -132.995311)
			(xy 11.193576 -132.954678) (xy 11.166019 -132.909834) (xy 11.144884 -132.86163) (xy 11.13057 -132.81098)
			(xy 11.12335 -132.758843) (xy 11.122914 -132.732526) (xy 11.1234 -132.705275) (xy 11.131156 -132.651327)
			(xy 11.146511 -132.599032) (xy 11.169153 -132.549455) (xy 11.198619 -132.503605) (xy 11.23431 -132.462414)
			(xy 11.275501 -132.426723) (xy 11.321351 -132.397257) (xy 11.370928 -132.374615) (xy 11.423223 -132.35926)
			(xy 11.477171 -132.351504) (xy 11.531673 -132.351504) (xy 11.585621 -132.35926) (xy 11.637916 -132.374615)
			(xy 11.687493 -132.397257) (xy 11.733343 -132.426723) (xy 11.774534 -132.462414) (xy 11.810225 -132.503605)
			(xy 11.839691 -132.549455) (xy 11.862333 -132.599032) (xy 11.877688 -132.651327) (xy 11.885444 -132.705275)
			(xy 11.88593 -132.732526) (xy 11.88547 -132.75884) (xy 11.878233 -132.810969) (xy 11.863911 -132.861611)
			(xy 11.842777 -132.90981) (xy 11.81523 -132.954653) (xy 11.781791 -132.995293) (xy 11.76274 -133.01345)
			(xy 11.75532 -133.020957) (xy 11.746805 -133.040248) (xy 11.74623 -133.050788) (xy 11.74623 -133.104382)
			(xy 37.31006 -133.104382) (xy 37.31006 -132.240782) (xy 37.31055 -132.210814) (xy 37.318373 -132.151392)
			(xy 37.333886 -132.093499) (xy 37.356822 -132.038126) (xy 37.386789 -131.98622) (xy 37.423276 -131.93867)
			(xy 37.465656 -131.89629) (xy 37.513206 -131.859803) (xy 37.565112 -131.829836) (xy 37.620485 -131.8069)
			(xy 37.678378 -131.791387) (xy 37.7378 -131.783564) (xy 37.797736 -131.783564) (xy 37.857158 -131.791387)
			(xy 37.915051 -131.8069) (xy 37.970424 -131.829836) (xy 38.02233 -131.859803) (xy 38.06988 -131.89629)
			(xy 38.11226 -131.93867) (xy 38.148747 -131.98622) (xy 38.178714 -132.038126) (xy 38.20165 -132.093499)
			(xy 38.217163 -132.151392) (xy 38.224986 -132.210814) (xy 38.225476 -132.240782) (xy 38.225476 -133.096508)
			(xy 51.785012 -133.096508) (xy 51.785012 -132.232908) (xy 51.785502 -132.20294) (xy 51.793325 -132.143518)
			(xy 51.808838 -132.085625) (xy 51.831774 -132.030252) (xy 51.861741 -131.978346) (xy 51.898228 -131.930796)
			(xy 51.940608 -131.888416) (xy 51.988158 -131.851929) (xy 52.040064 -131.821962) (xy 52.095437 -131.799026)
			(xy 52.15333 -131.783513) (xy 52.212752 -131.77569) (xy 52.272688 -131.77569) (xy 52.33211 -131.783513)
			(xy 52.390003 -131.799026) (xy 52.445376 -131.821962) (xy 52.497282 -131.851929) (xy 52.544832 -131.888416)
			(xy 52.587212 -131.930796) (xy 52.623699 -131.978346) (xy 52.653666 -132.030252) (xy 52.676602 -132.085625)
			(xy 52.692115 -132.143518) (xy 52.699938 -132.20294) (xy 52.700428 -132.232908) (xy 52.700428 -132.577332)
			(xy 64.745108 -132.577332) (xy 64.745108 -131.713732) (xy 64.745598 -131.683748) (xy 64.753426 -131.624292)
			(xy 64.768947 -131.566367) (xy 64.791896 -131.510963) (xy 64.82188 -131.459029) (xy 64.858386 -131.411453)
			(xy 64.900791 -131.369048) (xy 64.948367 -131.332542) (xy 65.000301 -131.302558) (xy 65.055705 -131.279609)
			(xy 65.11363 -131.264088) (xy 65.173086 -131.25626) (xy 65.233054 -131.25626) (xy 65.29251 -131.264088)
			(xy 65.350435 -131.279609) (xy 65.405839 -131.302558) (xy 65.457773 -131.332542) (xy 65.505349 -131.369048)
			(xy 65.547754 -131.411453) (xy 65.58426 -131.459029) (xy 65.614244 -131.510963) (xy 65.637193 -131.566367)
			(xy 65.652714 -131.624292) (xy 65.660542 -131.683748) (xy 65.661032 -131.713732) (xy 65.661032 -132.575808)
			(xy 83.716368 -132.575808) (xy 83.716368 -131.712208) (xy 83.716858 -131.682224) (xy 83.724686 -131.622768)
			(xy 83.740207 -131.564843) (xy 83.763156 -131.509439) (xy 83.79314 -131.457505) (xy 83.829646 -131.409929)
			(xy 83.872051 -131.367524) (xy 83.919627 -131.331018) (xy 83.971561 -131.301034) (xy 84.026965 -131.278085)
			(xy 84.08489 -131.262564) (xy 84.144346 -131.254736) (xy 84.204314 -131.254736) (xy 84.26377 -131.262564)
			(xy 84.321695 -131.278085) (xy 84.377099 -131.301034) (xy 84.429033 -131.331018) (xy 84.476609 -131.367524)
			(xy 84.519014 -131.409929) (xy 84.55552 -131.457505) (xy 84.585504 -131.509439) (xy 84.608453 -131.564843)
			(xy 84.623974 -131.622768) (xy 84.631802 -131.682224) (xy 84.632292 -131.712208) (xy 84.632292 -132.575808)
			(xy 84.631802 -132.605792) (xy 84.623974 -132.665248) (xy 84.608453 -132.723173) (xy 84.585504 -132.778577)
			(xy 84.55552 -132.830511) (xy 84.519014 -132.878087) (xy 84.476609 -132.920492) (xy 84.429033 -132.956998)
			(xy 84.377099 -132.986982) (xy 84.321695 -133.009931) (xy 84.26377 -133.025452) (xy 84.204314 -133.03328)
			(xy 84.144346 -133.03328) (xy 84.08489 -133.025452) (xy 84.026965 -133.009931) (xy 83.971561 -132.986982)
			(xy 83.919627 -132.956998) (xy 83.872051 -132.920492) (xy 83.829646 -132.878087) (xy 83.79314 -132.830511)
			(xy 83.763156 -132.778577) (xy 83.740207 -132.723173) (xy 83.724686 -132.665248) (xy 83.716858 -132.605792)
			(xy 83.716368 -132.575808) (xy 65.661032 -132.575808) (xy 65.661032 -132.577332) (xy 65.660542 -132.607316)
			(xy 65.652714 -132.666772) (xy 65.637193 -132.724697) (xy 65.614244 -132.780101) (xy 65.58426 -132.832035)
			(xy 65.547754 -132.879611) (xy 65.505349 -132.922016) (xy 65.457773 -132.958522) (xy 65.405839 -132.988506)
			(xy 65.350435 -133.011455) (xy 65.29251 -133.026976) (xy 65.233054 -133.034804) (xy 65.173086 -133.034804)
			(xy 65.11363 -133.026976) (xy 65.055705 -133.011455) (xy 65.000301 -132.988506) (xy 64.948367 -132.958522)
			(xy 64.900791 -132.922016) (xy 64.858386 -132.879611) (xy 64.82188 -132.832035) (xy 64.791896 -132.780101)
			(xy 64.768947 -132.724697) (xy 64.753426 -132.666772) (xy 64.745598 -132.607316) (xy 64.745108 -132.577332)
			(xy 52.700428 -132.577332) (xy 52.700428 -133.096508) (xy 52.699938 -133.126476) (xy 52.692115 -133.185898)
			(xy 52.676602 -133.243791) (xy 52.653666 -133.299164) (xy 52.623699 -133.35107) (xy 52.587212 -133.39862)
			(xy 52.544832 -133.441) (xy 52.497282 -133.477487) (xy 52.445376 -133.507454) (xy 52.390003 -133.53039)
			(xy 52.33211 -133.545903) (xy 52.272688 -133.553726) (xy 52.212752 -133.553726) (xy 52.15333 -133.545903)
			(xy 52.095437 -133.53039) (xy 52.040064 -133.507454) (xy 51.988158 -133.477487) (xy 51.940608 -133.441)
			(xy 51.898228 -133.39862) (xy 51.861741 -133.35107) (xy 51.831774 -133.299164) (xy 51.808838 -133.243791)
			(xy 51.793325 -133.185898) (xy 51.785502 -133.126476) (xy 51.785012 -133.096508) (xy 38.225476 -133.096508)
			(xy 38.225476 -133.104382) (xy 38.224986 -133.13435) (xy 38.217163 -133.193772) (xy 38.20165 -133.251665)
			(xy 38.178714 -133.307038) (xy 38.148747 -133.358944) (xy 38.11226 -133.406494) (xy 38.06988 -133.448874)
			(xy 38.02233 -133.485361) (xy 37.970424 -133.515328) (xy 37.915051 -133.538264) (xy 37.857158 -133.553777)
			(xy 37.797736 -133.5616) (xy 37.7378 -133.5616) (xy 37.678378 -133.553777) (xy 37.620485 -133.538264)
			(xy 37.565112 -133.515328) (xy 37.513206 -133.485361) (xy 37.465656 -133.448874) (xy 37.423276 -133.406494)
			(xy 37.386789 -133.358944) (xy 37.356822 -133.307038) (xy 37.333886 -133.251665) (xy 37.318373 -133.193772)
			(xy 37.31055 -133.13435) (xy 37.31006 -133.104382) (xy 11.74623 -133.104382) (xy 11.74623 -133.125464)
			(xy 11.746756 -133.136014) (xy 11.755293 -133.15531) (xy 11.76274 -133.162802) (xy 11.781797 -133.180956)
			(xy 11.815253 -133.221587) (xy 11.84281 -133.266428) (xy 11.863948 -133.314629) (xy 11.878266 -133.365276)
			(xy 11.885491 -133.41741) (xy 11.88593 -133.443726) (xy 11.885444 -133.470977) (xy 11.877688 -133.524925)
			(xy 11.862333 -133.57722) (xy 11.839691 -133.626797) (xy 11.810225 -133.672647) (xy 11.774534 -133.713838)
			(xy 11.733343 -133.749529) (xy 11.687493 -133.778995) (xy 11.637916 -133.801637) (xy 11.585621 -133.816992)
			(xy 11.531673 -133.824748) (xy 11.477171 -133.824748) (xy 11.423223 -133.816992) (xy 11.370928 -133.801637)
			(xy 11.321351 -133.778995) (xy 11.275501 -133.749529) (xy 11.23431 -133.713838) (xy 11.198619 -133.672647)
			(xy 11.169153 -133.626797) (xy 11.146511 -133.57722) (xy 11.131156 -133.524925) (xy 11.1234 -133.470977)
			(xy 11.122914 -133.443726) (xy 4.38404 -133.443726) (xy 4.38404 -134.042404) (xy 6.176008 -134.042404)
			(xy 6.180079 -133.986782) (xy 6.192205 -133.932345) (xy 6.212128 -133.880254) (xy 6.239424 -133.831619)
			(xy 6.27351 -133.787476) (xy 6.313659 -133.748767) (xy 6.359017 -133.716316) (xy 6.408617 -133.690815)
			(xy 6.461401 -133.672808) (xy 6.516244 -133.662678) (xy 6.571978 -133.660641) (xy 6.627415 -133.666741)
			(xy 6.681372 -133.680847) (xy 6.732701 -133.702659) (xy 6.780307 -133.731713) (xy 6.823175 -133.767388)
			(xy 6.860392 -133.808925) (xy 6.891165 -133.855438) (xy 6.914837 -133.905935) (xy 6.930905 -133.959342)
			(xy 6.939025 -134.014518) (xy 6.939534 -134.042404) (xy 6.939025 -134.07029) (xy 6.930905 -134.125466)
			(xy 6.914837 -134.178873) (xy 6.891165 -134.22937) (xy 6.860392 -134.275883) (xy 6.823175 -134.31742)
			(xy 6.780307 -134.353095) (xy 6.732701 -134.382149) (xy 6.681372 -134.403961) (xy 6.627415 -134.418067)
			(xy 6.571978 -134.424167) (xy 6.516244 -134.42213) (xy 6.461401 -134.412) (xy 6.408617 -134.393993)
			(xy 6.359017 -134.368492) (xy 6.313659 -134.336041) (xy 6.27351 -134.297332) (xy 6.239424 -134.253189)
			(xy 6.212128 -134.204554) (xy 6.192205 -134.152463) (xy 6.180079 -134.098026) (xy 6.176008 -134.042404)
			(xy 4.38404 -134.042404) (xy 4.38404 -135.142043) (xy 9.361887 -135.142043) (xy 9.361887 -135.087537)
			(xy 9.369644 -135.033586) (xy 9.385 -134.981289) (xy 9.407643 -134.931709) (xy 9.437111 -134.885856)
			(xy 9.472805 -134.844663) (xy 9.513997 -134.80897) (xy 9.55985 -134.779502) (xy 9.609431 -134.75686)
			(xy 9.661728 -134.741504) (xy 9.715679 -134.733747) (xy 9.742932 -134.733284) (xy 9.771849 -134.733819)
			(xy 9.82902 -134.74254) (xy 9.88422 -134.759793) (xy 9.936183 -134.785181) (xy 9.983717 -134.818123)
			(xy 10.025733 -134.857864) (xy 10.043922 -134.88035) (xy 10.051733 -134.889318) (xy 10.073184 -134.899517)
			(xy 10.08507 -134.899908) (xy 10.178542 -134.897876) (xy 10.199878 -134.8867) (xy 10.206736 -134.876794)
			(xy 10.22216 -134.855904) (xy 10.257734 -134.818076) (xy 10.298108 -134.785422) (xy 10.342538 -134.758545)
			(xy 10.390203 -134.737942) (xy 10.440221 -134.723993) (xy 10.491669 -134.716955) (xy 10.517632 -134.71652)
			(xy 10.545003 -134.716962) (xy 10.599183 -134.724785) (xy 10.651687 -134.74028) (xy 10.701433 -134.763127)
			(xy 10.747399 -134.792856) (xy 10.76833 -134.8105) (xy 10.768584 -134.810754) (xy 10.775666 -134.816346)
			(xy 10.792587 -134.822588) (xy 10.801604 -134.822946) (xy 10.86866 -134.822946) (xy 10.877676 -134.822582)
			(xy 10.894594 -134.81634) (xy 10.90168 -134.810754) (xy 10.90168 -134.8105) (xy 10.901934 -134.8105)
			(xy 10.922867 -134.792859) (xy 10.968835 -134.763135) (xy 11.018581 -134.740289) (xy 11.071083 -134.724793)
			(xy 11.125261 -134.716964) (xy 11.180003 -134.716964) (xy 11.234181 -134.724793) (xy 11.286683 -134.740289)
			(xy 11.336429 -134.763135) (xy 11.382397 -134.792859) (xy 11.40333 -134.8105) (xy 11.403584 -134.810754)
			(xy 11.410666 -134.816346) (xy 11.427587 -134.822588) (xy 11.436604 -134.822946) (xy 11.50366 -134.822946)
			(xy 11.512676 -134.822582) (xy 11.529594 -134.81634) (xy 11.53668 -134.810754) (xy 11.537188 -134.8105)
			(xy 11.549922 -134.799555) (xy 11.577013 -134.779714) (xy 11.59129 -134.770876) (xy 11.60018 -134.765542)
			(xy 11.612372 -134.748524) (xy 11.632692 -134.655306) (xy 11.628374 -134.634732) (xy 11.622532 -134.626096)
			(xy 11.606532 -134.602032) (xy 11.581188 -134.550101) (xy 11.563962 -134.494943) (xy 11.555248 -134.437819)
			(xy 11.554714 -134.408926) (xy 11.5552 -134.381675) (xy 11.562956 -134.327727) (xy 11.578311 -134.275432)
			(xy 11.600953 -134.225855) (xy 11.630419 -134.180005) (xy 11.66611 -134.138814) (xy 11.707301 -134.103123)
			(xy 11.753151 -134.073657) (xy 11.802728 -134.051015) (xy 11.855023 -134.03566) (xy 11.908971 -134.027904)
			(xy 11.963473 -134.027904) (xy 12.017421 -134.03566) (xy 12.069716 -134.051015) (xy 12.119293 -134.073657)
			(xy 12.165143 -134.103123) (xy 12.206334 -134.138814) (xy 12.242025 -134.180005) (xy 12.271491 -134.225855)
			(xy 12.294133 -134.275432) (xy 12.309488 -134.327727) (xy 12.317244 -134.381675) (xy 12.31773 -134.408926)
			(xy 12.31725 -134.437018) (xy 12.309019 -134.492596) (xy 12.292725 -134.546365) (xy 12.26872 -134.597162)
			(xy 12.237523 -134.643889) (xy 12.19981 -134.685533) (xy 12.156395 -134.721196) (xy 12.132564 -134.736078)
			(xy 12.123674 -134.741412) (xy 12.111482 -134.75843) (xy 12.091162 -134.851648) (xy 12.09548 -134.872222)
			(xy 12.101322 -134.880858) (xy 12.112624 -134.897876) (xy 34.667952 -134.897876) (xy 34.667952 -134.034276)
			(xy 34.668442 -134.004308) (xy 34.676265 -133.944886) (xy 34.691778 -133.886993) (xy 34.714714 -133.83162)
			(xy 34.744681 -133.779714) (xy 34.781168 -133.732164) (xy 34.823548 -133.689784) (xy 34.871098 -133.653297)
			(xy 34.923004 -133.62333) (xy 34.978377 -133.600394) (xy 35.03627 -133.584881) (xy 35.095692 -133.577058)
			(xy 35.155628 -133.577058) (xy 35.21505 -133.584881) (xy 35.272943 -133.600394) (xy 35.328316 -133.62333)
			(xy 35.380222 -133.653297) (xy 35.427772 -133.689784) (xy 35.470152 -133.732164) (xy 35.506639 -133.779714)
			(xy 35.536606 -133.83162) (xy 35.559542 -133.886993) (xy 35.575055 -133.944886) (xy 35.582878 -134.004308)
			(xy 35.583368 -134.034276) (xy 35.583368 -134.896352) (xy 53.639212 -134.896352) (xy 53.639212 -134.032752)
			(xy 53.639702 -134.002784) (xy 53.647525 -133.943362) (xy 53.663038 -133.885469) (xy 53.685974 -133.830096)
			(xy 53.715941 -133.77819) (xy 53.752428 -133.73064) (xy 53.794808 -133.68826) (xy 53.842358 -133.651773)
			(xy 53.894264 -133.621806) (xy 53.949637 -133.59887) (xy 54.00753 -133.583357) (xy 54.066952 -133.575534)
			(xy 54.126888 -133.575534) (xy 54.18631 -133.583357) (xy 54.244203 -133.59887) (xy 54.299576 -133.621806)
			(xy 54.351482 -133.651773) (xy 54.399032 -133.68826) (xy 54.441412 -133.73064) (xy 54.477899 -133.77819)
			(xy 54.507866 -133.830096) (xy 54.530802 -133.885469) (xy 54.546315 -133.943362) (xy 54.554138 -134.002784)
			(xy 54.554628 -134.032752) (xy 54.554628 -134.62) (xy 56.894982 -134.62) (xy 56.899053 -134.564378)
			(xy 56.911179 -134.509941) (xy 56.931102 -134.45785) (xy 56.958398 -134.409215) (xy 56.992484 -134.365072)
			(xy 57.032633 -134.326363) (xy 57.077991 -134.293912) (xy 57.127591 -134.268411) (xy 57.180375 -134.250404)
			(xy 57.235218 -134.240274) (xy 57.290952 -134.238237) (xy 57.346389 -134.244337) (xy 57.400346 -134.258443)
			(xy 57.451675 -134.280255) (xy 57.499281 -134.309309) (xy 57.542149 -134.344984) (xy 57.570993 -134.377176)
			(xy 66.599308 -134.377176) (xy 66.599308 -133.513576) (xy 66.599798 -133.483592) (xy 66.607626 -133.424136)
			(xy 66.623147 -133.366211) (xy 66.646096 -133.310807) (xy 66.67608 -133.258873) (xy 66.712586 -133.211297)
			(xy 66.754991 -133.168892) (xy 66.802567 -133.132386) (xy 66.854501 -133.102402) (xy 66.909905 -133.079453)
			(xy 66.96783 -133.063932) (xy 67.027286 -133.056104) (xy 67.087254 -133.056104) (xy 67.14671 -133.063932)
			(xy 67.204635 -133.079453) (xy 67.260039 -133.102402) (xy 67.311973 -133.132386) (xy 67.359549 -133.168892)
			(xy 67.401954 -133.211297) (xy 67.43846 -133.258873) (xy 67.468444 -133.310807) (xy 67.491393 -133.366211)
			(xy 67.506914 -133.424136) (xy 67.514742 -133.483592) (xy 67.515232 -133.513576) (xy 67.515232 -134.369302)
			(xy 81.07426 -134.369302) (xy 81.07426 -133.505702) (xy 81.07475 -133.475718) (xy 81.082578 -133.416262)
			(xy 81.098099 -133.358337) (xy 81.121048 -133.302933) (xy 81.151032 -133.250999) (xy 81.187538 -133.203423)
			(xy 81.229943 -133.161018) (xy 81.277519 -133.124512) (xy 81.329453 -133.094528) (xy 81.384857 -133.071579)
			(xy 81.442782 -133.056058) (xy 81.502238 -133.04823) (xy 81.562206 -133.04823) (xy 81.621662 -133.056058)
			(xy 81.679587 -133.071579) (xy 81.734991 -133.094528) (xy 81.786925 -133.124512) (xy 81.834501 -133.161018)
			(xy 81.876906 -133.203423) (xy 81.913412 -133.250999) (xy 81.943396 -133.302933) (xy 81.966345 -133.358337)
			(xy 81.981866 -133.416262) (xy 81.989694 -133.475718) (xy 81.990184 -133.505702) (xy 81.990184 -134.369302)
			(xy 81.989694 -134.399286) (xy 81.981866 -134.458742) (xy 81.966345 -134.516667) (xy 81.943396 -134.572071)
			(xy 81.913412 -134.624005) (xy 81.876906 -134.671581) (xy 81.834501 -134.713986) (xy 81.786925 -134.750492)
			(xy 81.734991 -134.780476) (xy 81.679587 -134.803425) (xy 81.621662 -134.818946) (xy 81.562206 -134.826774)
			(xy 81.502238 -134.826774) (xy 81.442782 -134.818946) (xy 81.384857 -134.803425) (xy 81.329453 -134.780476)
			(xy 81.277519 -134.750492) (xy 81.229943 -134.713986) (xy 81.187538 -134.671581) (xy 81.151032 -134.624005)
			(xy 81.121048 -134.572071) (xy 81.098099 -134.516667) (xy 81.082578 -134.458742) (xy 81.07475 -134.399286)
			(xy 81.07426 -134.369302) (xy 67.515232 -134.369302) (xy 67.515232 -134.377176) (xy 67.514742 -134.40716)
			(xy 67.506914 -134.466616) (xy 67.491393 -134.524541) (xy 67.468444 -134.579945) (xy 67.43846 -134.631879)
			(xy 67.401954 -134.679455) (xy 67.359549 -134.72186) (xy 67.311973 -134.758366) (xy 67.260039 -134.78835)
			(xy 67.204635 -134.811299) (xy 67.14671 -134.82682) (xy 67.087254 -134.834648) (xy 67.027286 -134.834648)
			(xy 66.96783 -134.82682) (xy 66.909905 -134.811299) (xy 66.854501 -134.78835) (xy 66.802567 -134.758366)
			(xy 66.754991 -134.72186) (xy 66.712586 -134.679455) (xy 66.67608 -134.631879) (xy 66.646096 -134.579945)
			(xy 66.623147 -134.524541) (xy 66.607626 -134.466616) (xy 66.599798 -134.40716) (xy 66.599308 -134.377176)
			(xy 57.570993 -134.377176) (xy 57.579366 -134.386521) (xy 57.610139 -134.433034) (xy 57.633811 -134.483531)
			(xy 57.649879 -134.536938) (xy 57.657999 -134.592114) (xy 57.658508 -134.62) (xy 57.657999 -134.647886)
			(xy 57.649879 -134.703062) (xy 57.633811 -134.756469) (xy 57.610139 -134.806966) (xy 57.579366 -134.853479)
			(xy 57.542149 -134.895016) (xy 57.499281 -134.930691) (xy 57.451675 -134.959745) (xy 57.400346 -134.981557)
			(xy 57.346389 -134.995663) (xy 57.290952 -135.001763) (xy 57.235218 -134.999726) (xy 57.180375 -134.989596)
			(xy 57.127591 -134.971589) (xy 57.077991 -134.946088) (xy 57.032633 -134.913637) (xy 56.992484 -134.874928)
			(xy 56.958398 -134.830785) (xy 56.931102 -134.78215) (xy 56.911179 -134.730059) (xy 56.899053 -134.675622)
			(xy 56.894982 -134.62) (xy 54.554628 -134.62) (xy 54.554628 -134.896352) (xy 54.554138 -134.92632)
			(xy 54.546315 -134.985742) (xy 54.530802 -135.043635) (xy 54.507866 -135.099008) (xy 54.477899 -135.150914)
			(xy 54.441412 -135.198464) (xy 54.399032 -135.240844) (xy 54.351482 -135.277331) (xy 54.299576 -135.307298)
			(xy 54.244203 -135.330234) (xy 54.18631 -135.345747) (xy 54.126888 -135.35357) (xy 54.066952 -135.35357)
			(xy 54.00753 -135.345747) (xy 53.949637 -135.330234) (xy 53.894264 -135.307298) (xy 53.842358 -135.277331)
			(xy 53.794808 -135.240844) (xy 53.752428 -135.198464) (xy 53.715941 -135.150914) (xy 53.685974 -135.099008)
			(xy 53.663038 -135.043635) (xy 53.647525 -134.985742) (xy 53.639702 -134.92632) (xy 53.639212 -134.896352)
			(xy 35.583368 -134.896352) (xy 35.583368 -134.897876) (xy 35.582878 -134.927844) (xy 35.575055 -134.987266)
			(xy 35.559542 -135.045159) (xy 35.536606 -135.100532) (xy 35.506639 -135.152438) (xy 35.470152 -135.199988)
			(xy 35.427772 -135.242368) (xy 35.380222 -135.278855) (xy 35.328316 -135.308822) (xy 35.272943 -135.331758)
			(xy 35.21505 -135.347271) (xy 35.155628 -135.355094) (xy 35.095692 -135.355094) (xy 35.03627 -135.347271)
			(xy 34.978377 -135.331758) (xy 34.923004 -135.308822) (xy 34.871098 -135.278855) (xy 34.823548 -135.242368)
			(xy 34.781168 -135.199988) (xy 34.744681 -135.152438) (xy 34.714714 -135.100532) (xy 34.691778 -135.045159)
			(xy 34.676265 -134.987266) (xy 34.668442 -134.927844) (xy 34.667952 -134.897876) (xy 12.112624 -134.897876)
			(xy 12.117309 -134.90493) (xy 12.142654 -134.956859) (xy 12.159883 -135.012014) (xy 12.168603 -135.069136)
			(xy 12.16914 -135.098028) (xy 12.168648 -135.125278) (xy 12.160889 -135.179224) (xy 12.145532 -135.231517)
			(xy 12.12289 -135.281092) (xy 12.093423 -135.326941) (xy 12.057733 -135.36813) (xy 12.016544 -135.403821)
			(xy 11.970696 -135.433288) (xy 11.921121 -135.45593) (xy 11.868828 -135.471288) (xy 11.814882 -135.479048)
			(xy 11.787632 -135.479536) (xy 11.760262 -135.479067) (xy 11.706082 -135.471252) (xy 11.653578 -135.455765)
			(xy 11.603831 -135.432923) (xy 11.557865 -135.403198) (xy 11.536934 -135.385556) (xy 11.53668 -135.385302)
			(xy 11.529603 -135.379701) (xy 11.512679 -135.373463) (xy 11.50366 -135.37311) (xy 11.436604 -135.37311)
			(xy 11.427587 -135.373467) (xy 11.41067 -135.379714) (xy 11.403584 -135.385302) (xy 11.403584 -135.385556)
			(xy 11.40333 -135.385556) (xy 11.382397 -135.403197) (xy 11.336429 -135.432921) (xy 11.286683 -135.455767)
			(xy 11.234181 -135.471263) (xy 11.180003 -135.479092) (xy 11.125261 -135.479092) (xy 11.071083 -135.471263)
			(xy 11.018581 -135.455767) (xy 10.968835 -135.432921) (xy 10.922867 -135.403197) (xy 10.901934 -135.385556)
			(xy 10.90168 -135.385302) (xy 10.894603 -135.379701) (xy 10.877679 -135.373463) (xy 10.86866 -135.37311)
			(xy 10.801604 -135.37311) (xy 10.792587 -135.373467) (xy 10.77567 -135.379714) (xy 10.768584 -135.385302)
			(xy 10.768584 -135.385556) (xy 10.76833 -135.385556) (xy 10.747392 -135.403188) (xy 10.701421 -135.432902)
			(xy 10.651676 -135.45574) (xy 10.599176 -135.471233) (xy 10.545001 -135.479062) (xy 10.517632 -135.479536)
			(xy 10.488715 -135.479019) (xy 10.431542 -135.470293) (xy 10.376342 -135.453037) (xy 10.32438 -135.427645)
			(xy 10.276847 -135.3947) (xy 10.234831 -135.354957) (xy 10.216642 -135.33247) (xy 10.208844 -135.323489)
			(xy 10.187383 -135.313296) (xy 10.175494 -135.312912) (xy 10.082022 -135.314944) (xy 10.060686 -135.32612)
			(xy 10.053828 -135.336026) (xy 10.038432 -135.356938) (xy 10.002853 -135.394764) (xy 9.962473 -135.427415)
			(xy 9.918038 -135.454289) (xy 9.87037 -135.474889) (xy 9.820348 -135.488834) (xy 9.768897 -135.495867)
			(xy 9.742932 -135.4963) (xy 9.715679 -135.495833) (xy 9.661728 -135.488076) (xy 9.609431 -135.47272)
			(xy 9.55985 -135.450078) (xy 9.513997 -135.42061) (xy 9.472805 -135.384917) (xy 9.437111 -135.343724)
			(xy 9.407643 -135.297871) (xy 9.385 -135.248291) (xy 9.369644 -135.195994) (xy 9.361887 -135.142043)
			(xy 4.38404 -135.142043) (xy 4.38404 -135.689594) (xy 7.28294 -135.689594) (xy 7.287011 -135.633972)
			(xy 7.299137 -135.579535) (xy 7.31906 -135.527444) (xy 7.346356 -135.478809) (xy 7.380442 -135.434666)
			(xy 7.420591 -135.395957) (xy 7.465949 -135.363506) (xy 7.515549 -135.338005) (xy 7.568333 -135.319998)
			(xy 7.623176 -135.309868) (xy 7.67891 -135.307831) (xy 7.734347 -135.313931) (xy 7.788304 -135.328037)
			(xy 7.839633 -135.349849) (xy 7.887239 -135.378903) (xy 7.930107 -135.414578) (xy 7.967324 -135.456115)
			(xy 7.998097 -135.502628) (xy 8.021769 -135.553125) (xy 8.037837 -135.606532) (xy 8.045957 -135.661708)
			(xy 8.046466 -135.689594) (xy 8.045957 -135.71748) (xy 8.037837 -135.772656) (xy 8.021769 -135.826063)
			(xy 8.002632 -135.866886) (xy 8.43991 -135.866886) (xy 8.443981 -135.811264) (xy 8.456107 -135.756827)
			(xy 8.47603 -135.704736) (xy 8.503326 -135.656101) (xy 8.537412 -135.611958) (xy 8.577561 -135.573249)
			(xy 8.622919 -135.540798) (xy 8.672519 -135.515297) (xy 8.725303 -135.49729) (xy 8.780146 -135.48716)
			(xy 8.83588 -135.485123) (xy 8.891317 -135.491223) (xy 8.945274 -135.505329) (xy 8.996603 -135.527141)
			(xy 9.044209 -135.556195) (xy 9.087077 -135.59187) (xy 9.124294 -135.633407) (xy 9.155067 -135.67992)
			(xy 9.178739 -135.730417) (xy 9.194807 -135.783824) (xy 9.202927 -135.839) (xy 9.203436 -135.866886)
			(xy 9.202927 -135.894772) (xy 9.194807 -135.949948) (xy 9.178739 -136.003355) (xy 9.155067 -136.053852)
			(xy 9.124294 -136.100365) (xy 9.087077 -136.141902) (xy 9.044209 -136.177577) (xy 8.996603 -136.206631)
			(xy 8.945274 -136.228443) (xy 8.891317 -136.242549) (xy 8.83588 -136.248649) (xy 8.780146 -136.246612)
			(xy 8.725303 -136.236482) (xy 8.672519 -136.218475) (xy 8.622919 -136.192974) (xy 8.577561 -136.160523)
			(xy 8.537412 -136.121814) (xy 8.503326 -136.077671) (xy 8.47603 -136.029036) (xy 8.456107 -135.976945)
			(xy 8.443981 -135.922508) (xy 8.43991 -135.866886) (xy 8.002632 -135.866886) (xy 7.998097 -135.87656)
			(xy 7.967324 -135.923073) (xy 7.930107 -135.96461) (xy 7.887239 -136.000285) (xy 7.839633 -136.029339)
			(xy 7.788304 -136.051151) (xy 7.734347 -136.065257) (xy 7.67891 -136.071357) (xy 7.623176 -136.06932)
			(xy 7.568333 -136.05919) (xy 7.515549 -136.041183) (xy 7.465949 -136.015682) (xy 7.420591 -135.983231)
			(xy 7.380442 -135.944522) (xy 7.346356 -135.900379) (xy 7.31906 -135.851744) (xy 7.299137 -135.799653)
			(xy 7.287011 -135.745216) (xy 7.28294 -135.689594) (xy 4.38404 -135.689594) (xy 4.38404 -137.44829)
			(xy 8.345168 -137.44829) (xy 8.349239 -137.392668) (xy 8.361365 -137.338231) (xy 8.381288 -137.28614)
			(xy 8.408584 -137.237505) (xy 8.44267 -137.193362) (xy 8.482819 -137.154653) (xy 8.528177 -137.122202)
			(xy 8.577777 -137.096701) (xy 8.630561 -137.078694) (xy 8.685404 -137.068564) (xy 8.741138 -137.066527)
			(xy 8.796575 -137.072627) (xy 8.850532 -137.086733) (xy 8.901861 -137.108545) (xy 8.949467 -137.137599)
			(xy 8.992335 -137.173274) (xy 9.029552 -137.214811) (xy 9.060325 -137.261324) (xy 9.06736 -137.276332)
			(xy 13.047218 -137.276332) (xy 13.047698 -137.248962) (xy 13.055512 -137.194784) (xy 13.070998 -137.14228)
			(xy 13.093836 -137.092533) (xy 13.123558 -137.046566) (xy 13.141198 -137.025634) (xy 13.141452 -137.02538)
			(xy 13.147059 -137.018308) (xy 13.153292 -137.00138) (xy 13.153644 -136.99236) (xy 13.153644 -136.925304)
			(xy 13.153297 -136.916286) (xy 13.147044 -136.899368) (xy 13.141452 -136.892284) (xy 13.141198 -136.892284)
			(xy 13.141198 -136.89203) (xy 13.123559 -136.871098) (xy 13.093847 -136.825125) (xy 13.071011 -136.775377)
			(xy 13.05552 -136.722877) (xy 13.047692 -136.668701) (xy 13.047218 -136.641332) (xy 13.047704 -136.614081)
			(xy 13.05546 -136.560133) (xy 13.070815 -136.507838) (xy 13.093457 -136.458261) (xy 13.122923 -136.412411)
			(xy 13.158614 -136.37122) (xy 13.199805 -136.335529) (xy 13.245655 -136.306063) (xy 13.295232 -136.283421)
			(xy 13.347527 -136.268066) (xy 13.401475 -136.26031) (xy 13.455977 -136.26031) (xy 13.509925 -136.268066)
			(xy 13.56222 -136.283421) (xy 13.611797 -136.306063) (xy 13.657647 -136.335529) (xy 13.698838 -136.37122)
			(xy 13.734529 -136.412411) (xy 13.763995 -136.458261) (xy 13.786637 -136.507838) (xy 13.801992 -136.560133)
			(xy 13.809748 -136.614081) (xy 13.810234 -136.641332) (xy 13.809803 -136.668704) (xy 13.801979 -136.722885)
			(xy 13.786483 -136.775389) (xy 13.763633 -136.825135) (xy 13.7339 -136.8711) (xy 13.716254 -136.89203)
			(xy 13.716 -136.892284) (xy 13.710414 -136.899371) (xy 13.704167 -136.916287) (xy 13.703808 -136.925304)
			(xy 13.703808 -136.99236) (xy 13.704183 -137.001375) (xy 13.710418 -137.018292) (xy 13.716 -137.02538)
			(xy 13.716254 -137.02538) (xy 13.716254 -137.025634) (xy 13.733868 -137.046586) (xy 13.763586 -137.092553)
			(xy 13.786427 -137.142295) (xy 13.801924 -137.194792) (xy 13.809757 -137.248964) (xy 13.810234 -137.276332)
			(xy 13.809748 -137.303583) (xy 13.801992 -137.357531) (xy 13.786637 -137.409826) (xy 13.763995 -137.459403)
			(xy 13.734529 -137.505253) (xy 13.698838 -137.546444) (xy 13.657647 -137.582135) (xy 13.611797 -137.611601)
			(xy 13.56222 -137.634243) (xy 13.509925 -137.649598) (xy 13.455977 -137.657354) (xy 13.401475 -137.657354)
			(xy 13.347527 -137.649598) (xy 13.295232 -137.634243) (xy 13.245655 -137.611601) (xy 13.199805 -137.582135)
			(xy 13.158614 -137.546444) (xy 13.122923 -137.505253) (xy 13.093457 -137.459403) (xy 13.070815 -137.409826)
			(xy 13.05546 -137.357531) (xy 13.047704 -137.303583) (xy 13.047218 -137.276332) (xy 9.06736 -137.276332)
			(xy 9.083997 -137.311821) (xy 9.100065 -137.365228) (xy 9.108185 -137.420404) (xy 9.108694 -137.44829)
			(xy 9.108185 -137.476176) (xy 9.100065 -137.531352) (xy 9.083997 -137.584759) (xy 9.060325 -137.635256)
			(xy 9.029552 -137.681769) (xy 8.992335 -137.723306) (xy 8.988288 -137.726674) (xy 13.98778 -137.726674)
			(xy 13.988211 -137.699302) (xy 13.996035 -137.645121) (xy 14.011531 -137.592617) (xy 14.034381 -137.54287)
			(xy 14.064114 -137.496906) (xy 14.08176 -137.475976) (xy 14.082014 -137.475722) (xy 14.087599 -137.468634)
			(xy 14.093846 -137.451718) (xy 14.094206 -137.442702) (xy 14.094206 -137.375646) (xy 14.093826 -137.366631)
			(xy 14.087594 -137.349714) (xy 14.082014 -137.342626) (xy 14.08176 -137.342626) (xy 14.08176 -137.342372)
			(xy 14.064135 -137.321429) (xy 14.034422 -137.275459) (xy 14.011584 -137.225714) (xy 13.996089 -137.173216)
			(xy 13.988256 -137.119042) (xy 13.98778 -137.091674) (xy 13.988266 -137.064423) (xy 13.996022 -137.010475)
			(xy 14.011377 -136.95818) (xy 14.034019 -136.908603) (xy 14.063485 -136.862753) (xy 14.099176 -136.821562)
			(xy 14.140367 -136.785871) (xy 14.186217 -136.756405) (xy 14.235794 -136.733763) (xy 14.288089 -136.718408)
			(xy 14.342037 -136.710652) (xy 14.396539 -136.710652) (xy 14.450487 -136.718408) (xy 14.502782 -136.733763)
			(xy 14.552359 -136.756405) (xy 14.598209 -136.785871) (xy 14.6394 -136.821562) (xy 14.675091 -136.862753)
			(xy 14.704557 -136.908603) (xy 14.727199 -136.95818) (xy 14.742554 -137.010475) (xy 14.75031 -137.064423)
			(xy 14.750796 -137.091674) (xy 14.750316 -137.119044) (xy 14.742501 -137.173222) (xy 14.727016 -137.225725)
			(xy 14.704177 -137.275472) (xy 14.674456 -137.32144) (xy 14.656816 -137.342372) (xy 14.656562 -137.342626)
			(xy 14.650996 -137.349726) (xy 14.644738 -137.366633) (xy 14.64437 -137.375646) (xy 14.64437 -137.442702)
			(xy 14.644733 -137.451718) (xy 14.650977 -137.468635) (xy 14.656562 -137.475722) (xy 14.656816 -137.475722)
			(xy 14.656816 -137.475976) (xy 14.67446 -137.496904) (xy 14.70417 -137.542878) (xy 14.727005 -137.592627)
			(xy 14.742495 -137.645128) (xy 14.750322 -137.699305) (xy 14.750796 -137.726674) (xy 14.75031 -137.753925)
			(xy 14.742554 -137.807873) (xy 14.727199 -137.860168) (xy 14.704557 -137.909745) (xy 14.675091 -137.955595)
			(xy 14.6394 -137.996786) (xy 14.598209 -138.032477) (xy 14.552359 -138.061943) (xy 14.502782 -138.084585)
			(xy 14.450487 -138.09994) (xy 14.396539 -138.107696) (xy 14.342037 -138.107696) (xy 14.288089 -138.09994)
			(xy 14.235794 -138.084585) (xy 14.186217 -138.061943) (xy 14.140367 -138.032477) (xy 14.099176 -137.996786)
			(xy 14.063485 -137.955595) (xy 14.034019 -137.909745) (xy 14.011377 -137.860168) (xy 13.996022 -137.807873)
			(xy 13.988266 -137.753925) (xy 13.98778 -137.726674) (xy 8.988288 -137.726674) (xy 8.949467 -137.758981)
			(xy 8.901861 -137.788035) (xy 8.850532 -137.809847) (xy 8.796575 -137.823953) (xy 8.741138 -137.830053)
			(xy 8.685404 -137.828016) (xy 8.630561 -137.817886) (xy 8.577777 -137.799879) (xy 8.528177 -137.774378)
			(xy 8.482819 -137.741927) (xy 8.44267 -137.703218) (xy 8.408584 -137.659075) (xy 8.381288 -137.61044)
			(xy 8.361365 -137.558349) (xy 8.349239 -137.503912) (xy 8.345168 -137.44829) (xy 4.38404 -137.44829)
			(xy 4.38404 -138.360404) (xy 6.176008 -138.360404) (xy 6.180079 -138.304782) (xy 6.192205 -138.250345)
			(xy 6.212128 -138.198254) (xy 6.239424 -138.149619) (xy 6.27351 -138.105476) (xy 6.313659 -138.066767)
			(xy 6.359017 -138.034316) (xy 6.408617 -138.008815) (xy 6.461401 -137.990808) (xy 6.516244 -137.980678)
			(xy 6.571978 -137.978641) (xy 6.627415 -137.984741) (xy 6.681372 -137.998847) (xy 6.732701 -138.020659)
			(xy 6.780307 -138.049713) (xy 6.823175 -138.085388) (xy 6.860392 -138.126925) (xy 6.891165 -138.173438)
			(xy 6.914837 -138.223935) (xy 6.930905 -138.277342) (xy 6.939025 -138.332518) (xy 6.939534 -138.360404)
			(xy 6.939025 -138.38829) (xy 6.936812 -138.40333) (xy 15.196312 -138.40333) (xy 15.196842 -138.375665)
			(xy 15.204838 -138.320917) (xy 15.220651 -138.267895) (xy 15.243951 -138.217711) (xy 15.274249 -138.171415)
			(xy 15.310912 -138.129977) (xy 15.353172 -138.094264) (xy 15.376398 -138.079226) (xy 15.386055 -138.072565)
			(xy 15.398512 -138.052722) (xy 15.400274 -138.041126) (xy 15.408148 -137.961116) (xy 15.408763 -137.949478)
			(xy 15.400695 -137.927642) (xy 15.392654 -137.919206) (xy 15.3924 -137.918952) (xy 15.373813 -137.900876)
			(xy 15.341235 -137.860543) (xy 15.314423 -137.816168) (xy 15.293871 -137.768568) (xy 15.279959 -137.718623)
			(xy 15.272943 -137.667253) (xy 15.272512 -137.64133) (xy 15.272983 -137.614077) (xy 15.280737 -137.560125)
			(xy 15.29609 -137.507826) (xy 15.31873 -137.458245) (xy 15.348197 -137.412391) (xy 15.38389 -137.371197)
			(xy 15.425083 -137.335503) (xy 15.470936 -137.306035) (xy 15.520517 -137.283393) (xy 15.572816 -137.268039)
			(xy 15.626767 -137.260284) (xy 15.65402 -137.259822) (xy 15.681391 -137.260271) (xy 15.735571 -137.268092)
			(xy 15.788074 -137.283585) (xy 15.837821 -137.306431) (xy 15.883787 -137.336159) (xy 15.904718 -137.353802)
			(xy 15.904972 -137.354056) (xy 15.912058 -137.359644) (xy 15.928975 -137.365888) (xy 15.937992 -137.366248)
			(xy 16.005048 -137.366248) (xy 16.014064 -137.365877) (xy 16.030981 -137.359641) (xy 16.038068 -137.354056)
			(xy 16.038068 -137.353802) (xy 16.038322 -137.353802) (xy 16.059273 -137.336186) (xy 16.105241 -137.306471)
			(xy 16.154983 -137.28363) (xy 16.20748 -137.268134) (xy 16.261652 -137.260299) (xy 16.28902 -137.259822)
			(xy 16.316275 -137.260236) (xy 16.370229 -137.267997) (xy 16.42253 -137.283357) (xy 16.472112 -137.306004)
			(xy 16.517966 -137.335477) (xy 16.55916 -137.371176) (xy 16.594853 -137.412374) (xy 16.62432 -137.458232)
			(xy 16.646961 -137.507817) (xy 16.662314 -137.56012) (xy 16.670067 -137.614075) (xy 16.670528 -137.64133)
			(xy 16.669987 -137.670246) (xy 16.661266 -137.727418) (xy 16.644015 -137.782617) (xy 16.618627 -137.83458)
			(xy 16.585686 -137.882114) (xy 16.545947 -137.92413) (xy 16.523462 -137.94232) (xy 16.514649 -137.949922)
			(xy 16.50447 -137.970827) (xy 16.503904 -137.982452) (xy 16.503904 -138.062208) (xy 16.504451 -138.073839)
			(xy 16.514634 -138.094749) (xy 16.523462 -138.10234) (xy 16.545957 -138.120518) (xy 16.585693 -138.162539)
			(xy 16.618632 -138.210077) (xy 16.644019 -138.262041) (xy 16.661272 -138.317241) (xy 16.669996 -138.374413)
			(xy 16.670528 -138.40333) (xy 16.67005 -138.430581) (xy 16.66229 -138.484528) (xy 16.646932 -138.536822)
			(xy 16.624289 -138.586398) (xy 16.594821 -138.632247) (xy 16.559129 -138.673436) (xy 16.517939 -138.709127)
			(xy 16.472089 -138.738594) (xy 16.422512 -138.761236) (xy 16.370218 -138.776592) (xy 16.316271 -138.784351)
			(xy 16.28902 -138.784838) (xy 16.262706 -138.784377) (xy 16.210576 -138.777144) (xy 16.159932 -138.762825)
			(xy 16.111733 -138.741691) (xy 16.06689 -138.714143) (xy 16.026251 -138.680701) (xy 16.008096 -138.661648)
			(xy 16.000571 -138.65425) (xy 15.981294 -138.645722) (xy 15.970758 -138.645138) (xy 15.896082 -138.645138)
			(xy 15.885534 -138.645687) (xy 15.866238 -138.654207) (xy 15.858744 -138.661648) (xy 15.840618 -138.680733)
			(xy 15.799981 -138.714185) (xy 15.755134 -138.741739) (xy 15.706928 -138.762872) (xy 15.656276 -138.777184)
			(xy 15.604138 -138.784403) (xy 15.57782 -138.784838) (xy 15.550571 -138.784303) (xy 15.496626 -138.77655)
			(xy 15.444334 -138.761199) (xy 15.394759 -138.738563) (xy 15.34891 -138.709101) (xy 15.307721 -138.673415)
			(xy 15.272029 -138.63223) (xy 15.242561 -138.586385) (xy 15.219918 -138.536813) (xy 15.20456 -138.484523)
			(xy 15.1968 -138.430579) (xy 15.196312 -138.40333) (xy 6.936812 -138.40333) (xy 6.930905 -138.443466)
			(xy 6.914837 -138.496873) (xy 6.891165 -138.54737) (xy 6.860392 -138.593883) (xy 6.823175 -138.63542)
			(xy 6.780307 -138.671095) (xy 6.732701 -138.700149) (xy 6.681372 -138.721961) (xy 6.627415 -138.736067)
			(xy 6.571978 -138.742167) (xy 6.516244 -138.74013) (xy 6.461401 -138.73) (xy 6.408617 -138.711993)
			(xy 6.359017 -138.686492) (xy 6.313659 -138.654041) (xy 6.27351 -138.615332) (xy 6.239424 -138.571189)
			(xy 6.212128 -138.522554) (xy 6.192205 -138.470463) (xy 6.180079 -138.416026) (xy 6.176008 -138.360404)
			(xy 4.38404 -138.360404) (xy 4.38404 -138.824462) (xy 8.361932 -138.824462) (xy 8.366003 -138.76884)
			(xy 8.378129 -138.714403) (xy 8.398052 -138.662312) (xy 8.425348 -138.613677) (xy 8.459434 -138.569534)
			(xy 8.499583 -138.530825) (xy 8.544941 -138.498374) (xy 8.594541 -138.472873) (xy 8.647325 -138.454866)
			(xy 8.702168 -138.444736) (xy 8.757902 -138.442699) (xy 8.813339 -138.448799) (xy 8.867296 -138.462905)
			(xy 8.918625 -138.484717) (xy 8.966231 -138.513771) (xy 9.009099 -138.549446) (xy 9.046316 -138.590983)
			(xy 9.077089 -138.637496) (xy 9.100761 -138.687993) (xy 9.116829 -138.7414) (xy 9.124949 -138.796576)
			(xy 9.125458 -138.824462) (xy 9.124949 -138.852348) (xy 9.116829 -138.907524) (xy 9.100761 -138.960931)
			(xy 9.077089 -139.011428) (xy 9.046316 -139.057941) (xy 9.009099 -139.099478) (xy 8.966231 -139.135153)
			(xy 8.918625 -139.164207) (xy 8.867296 -139.186019) (xy 8.813339 -139.200125) (xy 8.757902 -139.206225)
			(xy 8.702168 -139.204188) (xy 8.647325 -139.194058) (xy 8.594541 -139.176051) (xy 8.544941 -139.15055)
			(xy 8.499583 -139.118099) (xy 8.459434 -139.07939) (xy 8.425348 -139.035247) (xy 8.398052 -138.986612)
			(xy 8.378129 -138.934521) (xy 8.366003 -138.880084) (xy 8.361932 -138.824462) (xy 4.38404 -138.824462)
			(xy 4.38404 -139.376404) (xy 6.176008 -139.376404) (xy 6.180079 -139.320782) (xy 6.192205 -139.266345)
			(xy 6.212128 -139.214254) (xy 6.239424 -139.165619) (xy 6.27351 -139.121476) (xy 6.313659 -139.082767)
			(xy 6.359017 -139.050316) (xy 6.408617 -139.024815) (xy 6.461401 -139.006808) (xy 6.516244 -138.996678)
			(xy 6.571978 -138.994641) (xy 6.627415 -139.000741) (xy 6.681372 -139.014847) (xy 6.732701 -139.036659)
			(xy 6.780307 -139.065713) (xy 6.823175 -139.101388) (xy 6.860392 -139.142925) (xy 6.891165 -139.189438)
			(xy 6.914837 -139.239935) (xy 6.927773 -139.282932) (xy 16.938244 -139.282932) (xy 16.938754 -139.25414)
			(xy 16.947436 -139.197214) (xy 16.964578 -139.14224) (xy 16.989789 -139.090467) (xy 17.022498 -139.043074)
			(xy 17.061959 -139.001136) (xy 17.084294 -138.982958) (xy 17.092898 -138.975378) (xy 17.102912 -138.954782)
			(xy 17.103598 -138.943334) (xy 17.104106 -138.851894) (xy 17.093946 -138.830812) (xy 17.084802 -138.8237)
			(xy 17.062892 -138.805501) (xy 17.024216 -138.763691) (xy 16.992191 -138.716591) (xy 16.967531 -138.665251)
			(xy 16.950784 -138.610813) (xy 16.942323 -138.55449) (xy 16.9418 -138.526012) (xy 16.9418 -138.525758)
			(xy 16.9423 -138.498389) (xy 16.95011 -138.444211) (xy 16.965591 -138.391709) (xy 16.988425 -138.341961)
			(xy 17.018142 -138.295993) (xy 17.03578 -138.27506) (xy 17.036034 -138.274806) (xy 17.041628 -138.267725)
			(xy 17.047869 -138.250804) (xy 17.048226 -138.241786) (xy 17.048226 -138.17473) (xy 17.047849 -138.165715)
			(xy 17.041615 -138.148798) (xy 17.036034 -138.14171) (xy 17.03578 -138.14171) (xy 17.03578 -138.141456)
			(xy 17.018137 -138.120525) (xy 16.988412 -138.074557) (xy 16.965567 -138.02481) (xy 16.950071 -137.972308)
			(xy 16.942242 -137.918129) (xy 16.942242 -137.863388) (xy 16.950071 -137.809209) (xy 16.965568 -137.756707)
			(xy 16.988414 -137.70696) (xy 17.018139 -137.660993) (xy 17.03578 -137.64006) (xy 17.036034 -137.639806)
			(xy 17.041628 -137.632725) (xy 17.047869 -137.615804) (xy 17.048226 -137.606786) (xy 17.048226 -137.53973)
			(xy 17.047849 -137.530715) (xy 17.041615 -137.513798) (xy 17.036034 -137.50671) (xy 17.03578 -137.50671)
			(xy 17.03578 -137.506456) (xy 17.018137 -137.485525) (xy 16.988412 -137.439557) (xy 16.965567 -137.38981)
			(xy 16.950071 -137.337308) (xy 16.942242 -137.283129) (xy 16.942242 -137.228388) (xy 16.950071 -137.174209)
			(xy 16.965568 -137.121707) (xy 16.988414 -137.07196) (xy 17.018139 -137.025993) (xy 17.03578 -137.00506)
			(xy 17.036034 -137.004806) (xy 17.041628 -136.997725) (xy 17.047869 -136.980804) (xy 17.048226 -136.971786)
			(xy 17.048226 -136.90473) (xy 17.047849 -136.895715) (xy 17.041615 -136.878798) (xy 17.036034 -136.87171)
			(xy 17.03578 -136.87171) (xy 17.03578 -136.871456) (xy 17.018151 -136.850516) (xy 16.988438 -136.804545)
			(xy 16.9656 -136.7548) (xy 16.950107 -136.702301) (xy 16.942276 -136.648127) (xy 16.9418 -136.620758)
			(xy 16.942286 -136.593507) (xy 16.950042 -136.539559) (xy 16.965397 -136.487264) (xy 16.988039 -136.437687)
			(xy 17.017505 -136.391837) (xy 17.053196 -136.350646) (xy 17.094387 -136.314955) (xy 17.140237 -136.285489)
			(xy 17.189814 -136.262847) (xy 17.242109 -136.247492) (xy 17.296057 -136.239736) (xy 17.350559 -136.239736)
			(xy 17.404507 -136.247492) (xy 17.456802 -136.262847) (xy 17.506379 -136.285489) (xy 17.552229 -136.314955)
			(xy 17.59342 -136.350646) (xy 17.629111 -136.391837) (xy 17.658577 -136.437687) (xy 17.681219 -136.487264)
			(xy 17.696574 -136.539559) (xy 17.70433 -136.593507) (xy 17.704816 -136.620758) (xy 17.704346 -136.648128)
			(xy 17.696532 -136.702308) (xy 17.695937 -136.704324) (xy 37.31006 -136.704324) (xy 37.31006 -135.840724)
			(xy 37.31055 -135.810756) (xy 37.318373 -135.751334) (xy 37.333886 -135.693441) (xy 37.356822 -135.638068)
			(xy 37.386789 -135.586162) (xy 37.423276 -135.538612) (xy 37.465656 -135.496232) (xy 37.513206 -135.459745)
			(xy 37.565112 -135.429778) (xy 37.620485 -135.406842) (xy 37.678378 -135.391329) (xy 37.7378 -135.383506)
			(xy 37.797736 -135.383506) (xy 37.857158 -135.391329) (xy 37.915051 -135.406842) (xy 37.970424 -135.429778)
			(xy 38.02233 -135.459745) (xy 38.06988 -135.496232) (xy 38.11226 -135.538612) (xy 38.148747 -135.586162)
			(xy 38.178714 -135.638068) (xy 38.20165 -135.693441) (xy 38.217163 -135.751334) (xy 38.224986 -135.810756)
			(xy 38.225476 -135.840724) (xy 38.225476 -136.69645) (xy 51.785012 -136.69645) (xy 51.785012 -135.83285)
			(xy 51.785502 -135.802882) (xy 51.793325 -135.74346) (xy 51.808838 -135.685567) (xy 51.831774 -135.630194)
			(xy 51.861741 -135.578288) (xy 51.898228 -135.530738) (xy 51.940608 -135.488358) (xy 51.988158 -135.451871)
			(xy 52.040064 -135.421904) (xy 52.095437 -135.398968) (xy 52.15333 -135.383455) (xy 52.212752 -135.375632)
			(xy 52.272688 -135.375632) (xy 52.33211 -135.383455) (xy 52.390003 -135.398968) (xy 52.445376 -135.421904)
			(xy 52.497282 -135.451871) (xy 52.544832 -135.488358) (xy 52.587212 -135.530738) (xy 52.623699 -135.578288)
			(xy 52.653666 -135.630194) (xy 52.676602 -135.685567) (xy 52.692115 -135.74346) (xy 52.699938 -135.802882)
			(xy 52.700428 -135.83285) (xy 52.700428 -136.177274) (xy 64.745108 -136.177274) (xy 64.745108 -135.313674)
			(xy 64.745598 -135.28369) (xy 64.753426 -135.224234) (xy 64.768947 -135.166309) (xy 64.791896 -135.110905)
			(xy 64.82188 -135.058971) (xy 64.858386 -135.011395) (xy 64.900791 -134.96899) (xy 64.948367 -134.932484)
			(xy 65.000301 -134.9025) (xy 65.055705 -134.879551) (xy 65.11363 -134.86403) (xy 65.173086 -134.856202)
			(xy 65.233054 -134.856202) (xy 65.29251 -134.86403) (xy 65.350435 -134.879551) (xy 65.405839 -134.9025)
			(xy 65.457773 -134.932484) (xy 65.505349 -134.96899) (xy 65.547754 -135.011395) (xy 65.58426 -135.058971)
			(xy 65.614244 -135.110905) (xy 65.637193 -135.166309) (xy 65.652714 -135.224234) (xy 65.660542 -135.28369)
			(xy 65.661032 -135.313674) (xy 65.661032 -136.17575) (xy 83.716368 -136.17575) (xy 83.716368 -135.31215)
			(xy 83.716858 -135.282166) (xy 83.724686 -135.22271) (xy 83.740207 -135.164785) (xy 83.763156 -135.109381)
			(xy 83.79314 -135.057447) (xy 83.829646 -135.009871) (xy 83.872051 -134.967466) (xy 83.919627 -134.93096)
			(xy 83.971561 -134.900976) (xy 84.026965 -134.878027) (xy 84.08489 -134.862506) (xy 84.144346 -134.854678)
			(xy 84.204314 -134.854678) (xy 84.26377 -134.862506) (xy 84.321695 -134.878027) (xy 84.377099 -134.900976)
			(xy 84.429033 -134.93096) (xy 84.476609 -134.967466) (xy 84.519014 -135.009871) (xy 84.55552 -135.057447)
			(xy 84.585504 -135.109381) (xy 84.608453 -135.164785) (xy 84.623974 -135.22271) (xy 84.631802 -135.282166)
			(xy 84.632292 -135.31215) (xy 84.632292 -136.17575) (xy 84.631802 -136.205734) (xy 84.623974 -136.26519)
			(xy 84.608453 -136.323115) (xy 84.585504 -136.378519) (xy 84.55552 -136.430453) (xy 84.519014 -136.478029)
			(xy 84.476609 -136.520434) (xy 84.429033 -136.55694) (xy 84.377099 -136.586924) (xy 84.321695 -136.609873)
			(xy 84.26377 -136.625394) (xy 84.204314 -136.633222) (xy 84.144346 -136.633222) (xy 84.08489 -136.625394)
			(xy 84.026965 -136.609873) (xy 83.971561 -136.586924) (xy 83.919627 -136.55694) (xy 83.872051 -136.520434)
			(xy 83.829646 -136.478029) (xy 83.79314 -136.430453) (xy 83.763156 -136.378519) (xy 83.740207 -136.323115)
			(xy 83.724686 -136.26519) (xy 83.716858 -136.205734) (xy 83.716368 -136.17575) (xy 65.661032 -136.17575)
			(xy 65.661032 -136.177274) (xy 65.660542 -136.207258) (xy 65.652714 -136.266714) (xy 65.637193 -136.324639)
			(xy 65.614244 -136.380043) (xy 65.58426 -136.431977) (xy 65.547754 -136.479553) (xy 65.505349 -136.521958)
			(xy 65.457773 -136.558464) (xy 65.405839 -136.588448) (xy 65.350435 -136.611397) (xy 65.29251 -136.626918)
			(xy 65.233054 -136.634746) (xy 65.173086 -136.634746) (xy 65.11363 -136.626918) (xy 65.055705 -136.611397)
			(xy 65.000301 -136.588448) (xy 64.948367 -136.558464) (xy 64.900791 -136.521958) (xy 64.858386 -136.479553)
			(xy 64.82188 -136.431977) (xy 64.791896 -136.380043) (xy 64.768947 -136.324639) (xy 64.753426 -136.266714)
			(xy 64.745598 -136.207258) (xy 64.745108 -136.177274) (xy 52.700428 -136.177274) (xy 52.700428 -136.69645)
			(xy 52.699938 -136.726418) (xy 52.692115 -136.78584) (xy 52.676602 -136.843733) (xy 52.653666 -136.899106)
			(xy 52.623699 -136.951012) (xy 52.587212 -136.998562) (xy 52.544832 -137.040942) (xy 52.497282 -137.077429)
			(xy 52.445376 -137.107396) (xy 52.390003 -137.130332) (xy 52.33211 -137.145845) (xy 52.272688 -137.153668)
			(xy 52.212752 -137.153668) (xy 52.15333 -137.145845) (xy 52.095437 -137.130332) (xy 52.040064 -137.107396)
			(xy 51.988158 -137.077429) (xy 51.940608 -137.040942) (xy 51.898228 -136.998562) (xy 51.861741 -136.951012)
			(xy 51.831774 -136.899106) (xy 51.808838 -136.843733) (xy 51.793325 -136.78584) (xy 51.785502 -136.726418)
			(xy 51.785012 -136.69645) (xy 38.225476 -136.69645) (xy 38.225476 -136.704324) (xy 38.224986 -136.734292)
			(xy 38.217163 -136.793714) (xy 38.20165 -136.851607) (xy 38.178714 -136.90698) (xy 38.148747 -136.958886)
			(xy 38.11226 -137.006436) (xy 38.06988 -137.048816) (xy 38.02233 -137.085303) (xy 37.970424 -137.11527)
			(xy 37.915051 -137.138206) (xy 37.857158 -137.153719) (xy 37.797736 -137.161542) (xy 37.7378 -137.161542)
			(xy 37.678378 -137.153719) (xy 37.620485 -137.138206) (xy 37.565112 -137.11527) (xy 37.513206 -137.085303)
			(xy 37.465656 -137.048816) (xy 37.423276 -137.006436) (xy 37.386789 -136.958886) (xy 37.356822 -136.90698)
			(xy 37.333886 -136.851607) (xy 37.318373 -136.793714) (xy 37.31055 -136.734292) (xy 37.31006 -136.704324)
			(xy 17.695937 -136.704324) (xy 17.681045 -136.754812) (xy 17.658204 -136.804559) (xy 17.628478 -136.850525)
			(xy 17.610836 -136.871456) (xy 17.610582 -136.87171) (xy 17.604983 -136.878788) (xy 17.598744 -136.895711)
			(xy 17.59839 -136.90473) (xy 17.59839 -136.971786) (xy 17.598756 -136.980802) (xy 17.604998 -136.997719)
			(xy 17.610582 -137.004806) (xy 17.610836 -137.004806) (xy 17.610836 -137.00506) (xy 17.628475 -137.025994)
			(xy 17.658199 -137.071962) (xy 17.681045 -137.121708) (xy 17.696541 -137.17421) (xy 17.70437 -137.228388)
			(xy 17.70437 -137.283129) (xy 17.696541 -137.337307) (xy 17.681046 -137.389809) (xy 17.658201 -137.439555)
			(xy 17.628476 -137.485523) (xy 17.610836 -137.506456) (xy 17.610582 -137.50671) (xy 17.604983 -137.513788)
			(xy 17.598744 -137.530711) (xy 17.59839 -137.53973) (xy 17.59839 -137.606786) (xy 17.598756 -137.615802)
			(xy 17.604998 -137.632719) (xy 17.610582 -137.639806) (xy 17.610836 -137.639806) (xy 17.610836 -137.64006)
			(xy 17.628475 -137.660994) (xy 17.658199 -137.706962) (xy 17.681045 -137.756708) (xy 17.696541 -137.80921)
			(xy 17.70437 -137.863388) (xy 17.70437 -137.918129) (xy 17.696541 -137.972307) (xy 17.681046 -138.024809)
			(xy 17.658201 -138.074555) (xy 17.628476 -138.120523) (xy 17.610836 -138.141456) (xy 17.610582 -138.14171)
			(xy 17.604983 -138.148788) (xy 17.598744 -138.165711) (xy 17.59839 -138.17473) (xy 17.59839 -138.241786)
			(xy 17.598756 -138.250802) (xy 17.604998 -138.267719) (xy 17.610582 -138.274806) (xy 17.610836 -138.274806)
			(xy 17.610836 -138.27506) (xy 17.628475 -138.295992) (xy 17.658186 -138.341965) (xy 17.681021 -138.391713)
			(xy 17.696512 -138.444213) (xy 17.704075 -138.496548) (xy 43.97248 -138.496548) (xy 43.97248 -137.632948)
			(xy 43.97297 -137.602964) (xy 43.980798 -137.543508) (xy 43.996319 -137.485583) (xy 44.019268 -137.430179)
			(xy 44.049252 -137.378245) (xy 44.085758 -137.330669) (xy 44.128163 -137.288264) (xy 44.175739 -137.251758)
			(xy 44.227673 -137.221774) (xy 44.283077 -137.198825) (xy 44.341002 -137.183304) (xy 44.400458 -137.175476)
			(xy 44.460426 -137.175476) (xy 44.519882 -137.183304) (xy 44.577807 -137.198825) (xy 44.633211 -137.221774)
			(xy 44.685145 -137.251758) (xy 44.731074 -137.287) (xy 56.767982 -137.287) (xy 56.772053 -137.231378)
			(xy 56.784179 -137.176941) (xy 56.804102 -137.12485) (xy 56.831398 -137.076215) (xy 56.865484 -137.032072)
			(xy 56.905633 -136.993363) (xy 56.950991 -136.960912) (xy 57.000591 -136.935411) (xy 57.053375 -136.917404)
			(xy 57.108218 -136.907274) (xy 57.163952 -136.905237) (xy 57.219389 -136.911337) (xy 57.273346 -136.925443)
			(xy 57.324675 -136.947255) (xy 57.372281 -136.976309) (xy 57.383938 -136.98601) (xy 80.557622 -136.98601)
			(xy 80.561693 -136.930388) (xy 80.573819 -136.875951) (xy 80.593742 -136.82386) (xy 80.621038 -136.775225)
			(xy 80.655124 -136.731082) (xy 80.695273 -136.692373) (xy 80.740631 -136.659922) (xy 80.790231 -136.634421)
			(xy 80.843015 -136.616414) (xy 80.897858 -136.606284) (xy 80.953592 -136.604247) (xy 81.009029 -136.610347)
			(xy 81.062986 -136.624453) (xy 81.114315 -136.646265) (xy 81.161921 -136.675319) (xy 81.204789 -136.710994)
			(xy 81.242006 -136.752531) (xy 81.272779 -136.799044) (xy 81.296451 -136.849541) (xy 81.312519 -136.902948)
			(xy 81.320639 -136.958124) (xy 81.321148 -136.98601) (xy 81.320639 -137.013896) (xy 81.312519 -137.069072)
			(xy 81.296451 -137.122479) (xy 81.272779 -137.172976) (xy 81.242006 -137.219489) (xy 81.204789 -137.261026)
			(xy 81.161921 -137.296701) (xy 81.114315 -137.325755) (xy 81.062986 -137.347567) (xy 81.009029 -137.361673)
			(xy 80.953592 -137.367773) (xy 80.897858 -137.365736) (xy 80.843015 -137.355606) (xy 80.790231 -137.337599)
			(xy 80.740631 -137.312098) (xy 80.695273 -137.279647) (xy 80.655124 -137.240938) (xy 80.621038 -137.196795)
			(xy 80.593742 -137.14816) (xy 80.573819 -137.096069) (xy 80.561693 -137.041632) (xy 80.557622 -136.98601)
			(xy 57.383938 -136.98601) (xy 57.415149 -137.011984) (xy 57.452366 -137.053521) (xy 57.483139 -137.100034)
			(xy 57.506811 -137.150531) (xy 57.522879 -137.203938) (xy 57.530999 -137.259114) (xy 57.531508 -137.287)
			(xy 57.530999 -137.314886) (xy 57.522879 -137.370062) (xy 57.506811 -137.423469) (xy 57.483139 -137.473966)
			(xy 57.452366 -137.520479) (xy 57.415149 -137.562016) (xy 57.372281 -137.597691) (xy 57.324675 -137.626745)
			(xy 57.273346 -137.648557) (xy 57.219389 -137.662663) (xy 57.163952 -137.668763) (xy 57.108218 -137.666726)
			(xy 57.053375 -137.656596) (xy 57.000591 -137.638589) (xy 56.950991 -137.613088) (xy 56.905633 -137.580637)
			(xy 56.865484 -137.541928) (xy 56.831398 -137.497785) (xy 56.804102 -137.44915) (xy 56.784179 -137.397059)
			(xy 56.772053 -137.342622) (xy 56.767982 -137.287) (xy 44.731074 -137.287) (xy 44.732721 -137.288264)
			(xy 44.775126 -137.330669) (xy 44.811632 -137.378245) (xy 44.841616 -137.430179) (xy 44.864565 -137.485583)
			(xy 44.880086 -137.543508) (xy 44.887914 -137.602964) (xy 44.888404 -137.632948) (xy 44.888404 -137.848848)
			(xy 61.93993 -137.848848) (xy 61.944001 -137.793226) (xy 61.956127 -137.738789) (xy 61.97605 -137.686698)
			(xy 62.003346 -137.638063) (xy 62.037432 -137.59392) (xy 62.077581 -137.555211) (xy 62.122939 -137.52276)
			(xy 62.172539 -137.497259) (xy 62.225323 -137.479252) (xy 62.280166 -137.469122) (xy 62.3359 -137.467085)
			(xy 62.391337 -137.473185) (xy 62.445294 -137.487291) (xy 62.496623 -137.509103) (xy 62.544229 -137.538157)
			(xy 62.587097 -137.573832) (xy 62.624314 -137.615369) (xy 62.655087 -137.661882) (xy 62.678759 -137.712379)
			(xy 62.694827 -137.765786) (xy 62.702947 -137.820962) (xy 62.703456 -137.848848) (xy 62.702947 -137.876734)
			(xy 62.694827 -137.93191) (xy 62.678759 -137.985317) (xy 62.655087 -138.035814) (xy 62.624314 -138.082327)
			(xy 62.587097 -138.123864) (xy 62.544229 -138.159539) (xy 62.496623 -138.188593) (xy 62.445294 -138.210405)
			(xy 62.391337 -138.224511) (xy 62.3359 -138.230611) (xy 62.280166 -138.228574) (xy 62.225323 -138.218444)
			(xy 62.172539 -138.200437) (xy 62.122939 -138.174936) (xy 62.077581 -138.142485) (xy 62.037432 -138.103776)
			(xy 62.003346 -138.059633) (xy 61.97605 -138.010998) (xy 61.956127 -137.958907) (xy 61.944001 -137.90447)
			(xy 61.93993 -137.848848) (xy 44.888404 -137.848848) (xy 44.888404 -138.496548) (xy 44.887914 -138.526532)
			(xy 44.882966 -138.564112) (xy 46.691294 -138.564112) (xy 46.695365 -138.50849) (xy 46.707491 -138.454053)
			(xy 46.727414 -138.401962) (xy 46.75471 -138.353327) (xy 46.788796 -138.309184) (xy 46.828945 -138.270475)
			(xy 46.874303 -138.238024) (xy 46.923903 -138.212523) (xy 46.976687 -138.194516) (xy 47.03153 -138.184386)
			(xy 47.087264 -138.182349) (xy 47.142701 -138.188449) (xy 47.196658 -138.202555) (xy 47.247987 -138.224367)
			(xy 47.295593 -138.253421) (xy 47.338461 -138.289096) (xy 47.375678 -138.330633) (xy 47.39403 -138.358372)
			(xy 84.809328 -138.358372) (xy 84.813399 -138.30275) (xy 84.825525 -138.248313) (xy 84.845448 -138.196222)
			(xy 84.872744 -138.147587) (xy 84.90683 -138.103444) (xy 84.946979 -138.064735) (xy 84.992337 -138.032284)
			(xy 85.041937 -138.006783) (xy 85.094721 -137.988776) (xy 85.149564 -137.978646) (xy 85.205298 -137.976609)
			(xy 85.260735 -137.982709) (xy 85.314692 -137.996815) (xy 85.366021 -138.018627) (xy 85.413627 -138.047681)
			(xy 85.456495 -138.083356) (xy 85.493712 -138.124893) (xy 85.524485 -138.171406) (xy 85.548157 -138.221903)
			(xy 85.564225 -138.27531) (xy 85.572345 -138.330486) (xy 85.572854 -138.358372) (xy 85.572345 -138.386258)
			(xy 85.564225 -138.441434) (xy 85.548157 -138.494841) (xy 85.524485 -138.545338) (xy 85.493712 -138.591851)
			(xy 85.456495 -138.633388) (xy 85.413627 -138.669063) (xy 85.366021 -138.698117) (xy 85.314692 -138.719929)
			(xy 85.260735 -138.734035) (xy 85.205298 -138.740135) (xy 85.149564 -138.738098) (xy 85.094721 -138.727968)
			(xy 85.041937 -138.709961) (xy 84.992337 -138.68446) (xy 84.946979 -138.652009) (xy 84.90683 -138.6133)
			(xy 84.872744 -138.569157) (xy 84.845448 -138.520522) (xy 84.825525 -138.468431) (xy 84.813399 -138.413994)
			(xy 84.809328 -138.358372) (xy 47.39403 -138.358372) (xy 47.406451 -138.377146) (xy 47.430123 -138.427643)
			(xy 47.446191 -138.48105) (xy 47.454311 -138.536226) (xy 47.45482 -138.564112) (xy 47.454311 -138.591998)
			(xy 47.446191 -138.647174) (xy 47.430123 -138.700581) (xy 47.406451 -138.751078) (xy 47.375678 -138.797591)
			(xy 47.338461 -138.839128) (xy 47.295593 -138.874803) (xy 47.247987 -138.903857) (xy 47.196658 -138.925669)
			(xy 47.142701 -138.939775) (xy 47.087264 -138.945875) (xy 47.03153 -138.943838) (xy 46.976687 -138.933708)
			(xy 46.923903 -138.915701) (xy 46.874303 -138.8902) (xy 46.828945 -138.857749) (xy 46.788796 -138.81904)
			(xy 46.75471 -138.774897) (xy 46.727414 -138.726262) (xy 46.707491 -138.674171) (xy 46.695365 -138.619734)
			(xy 46.691294 -138.564112) (xy 44.882966 -138.564112) (xy 44.880086 -138.585988) (xy 44.864565 -138.643913)
			(xy 44.841616 -138.699317) (xy 44.811632 -138.751251) (xy 44.775126 -138.798827) (xy 44.732721 -138.841232)
			(xy 44.685145 -138.877738) (xy 44.633211 -138.907722) (xy 44.577807 -138.930671) (xy 44.519882 -138.946192)
			(xy 44.460426 -138.95402) (xy 44.400458 -138.95402) (xy 44.341002 -138.946192) (xy 44.283077 -138.930671)
			(xy 44.227673 -138.907722) (xy 44.175739 -138.877738) (xy 44.128163 -138.841232) (xy 44.085758 -138.798827)
			(xy 44.049252 -138.751251) (xy 44.019268 -138.699317) (xy 43.996319 -138.643913) (xy 43.980798 -138.585988)
			(xy 43.97297 -138.526532) (xy 43.97248 -138.496548) (xy 17.704075 -138.496548) (xy 17.704341 -138.498389)
			(xy 17.704816 -138.525758) (xy 17.704314 -138.554551) (xy 17.695632 -138.611478) (xy 17.67849 -138.666453)
			(xy 17.653277 -138.718225) (xy 17.620567 -138.765619) (xy 17.581102 -138.807555) (xy 17.558766 -138.825732)
			(xy 17.550177 -138.833327) (xy 17.540152 -138.853911) (xy 17.539462 -138.865356) (xy 17.538954 -138.956796)
			(xy 17.549114 -138.977878) (xy 17.558258 -138.98499) (xy 17.57045 -138.995404) (xy 17.570704 -138.995658)
			(xy 17.57778 -139.001259) (xy 17.594705 -139.007496) (xy 17.603724 -139.00785) (xy 17.67078 -139.00785)
			(xy 17.679797 -139.007494) (xy 17.696715 -139.001247) (xy 17.7038 -138.995658) (xy 17.7038 -138.995404)
			(xy 17.704054 -138.995404) (xy 17.724987 -138.977763) (xy 17.770955 -138.948039) (xy 17.820701 -138.925193)
			(xy 17.873203 -138.909697) (xy 17.927381 -138.901868) (xy 17.982123 -138.901868) (xy 18.036301 -138.909697)
			(xy 18.088803 -138.925193) (xy 18.138549 -138.948039) (xy 18.184517 -138.977763) (xy 18.20545 -138.995404)
			(xy 18.205704 -138.995658) (xy 18.21278 -139.001259) (xy 18.229705 -139.007496) (xy 18.238724 -139.00785)
			(xy 18.30578 -139.00785) (xy 18.314797 -139.007494) (xy 18.331715 -139.001247) (xy 18.3388 -138.995658)
			(xy 18.3388 -138.995404) (xy 18.339054 -138.995404) (xy 18.359987 -138.977763) (xy 18.405955 -138.948039)
			(xy 18.455701 -138.925193) (xy 18.508203 -138.909697) (xy 18.562381 -138.901868) (xy 18.617123 -138.901868)
			(xy 18.671301 -138.909697) (xy 18.723803 -138.925193) (xy 18.773549 -138.948039) (xy 18.819517 -138.977763)
			(xy 18.84045 -138.995404) (xy 18.840704 -138.995658) (xy 18.84778 -139.001259) (xy 18.864705 -139.007496)
			(xy 18.873724 -139.00785) (xy 18.94078 -139.00785) (xy 18.949797 -139.007494) (xy 18.966715 -139.001247)
			(xy 18.9738 -138.995658) (xy 18.9738 -138.995404) (xy 18.974054 -138.995404) (xy 18.994993 -138.977774)
			(xy 19.040964 -138.94806) (xy 19.09071 -138.925223) (xy 19.143209 -138.90973) (xy 19.197383 -138.901899)
			(xy 19.224752 -138.901424) (xy 19.252003 -138.901906) (xy 19.305951 -138.909663) (xy 19.358246 -138.925018)
			(xy 19.407823 -138.947659) (xy 19.422436 -138.95705) (xy 56.514492 -138.95705) (xy 56.514978 -138.929799)
			(xy 56.522734 -138.875851) (xy 56.538089 -138.823556) (xy 56.560731 -138.773979) (xy 56.590197 -138.728129)
			(xy 56.625888 -138.686938) (xy 56.667079 -138.651247) (xy 56.712929 -138.621781) (xy 56.762506 -138.599139)
			(xy 56.814801 -138.583784) (xy 56.868749 -138.576028) (xy 56.923251 -138.576028) (xy 56.977199 -138.583784)
			(xy 57.029494 -138.599139) (xy 57.079071 -138.621781) (xy 57.124921 -138.651247) (xy 57.166112 -138.686938)
			(xy 57.201803 -138.728129) (xy 57.231269 -138.773979) (xy 57.253911 -138.823556) (xy 57.266035 -138.864848)
			(xy 61.93993 -138.864848) (xy 61.944001 -138.809226) (xy 61.956127 -138.754789) (xy 61.97605 -138.702698)
			(xy 62.003346 -138.654063) (xy 62.037432 -138.60992) (xy 62.077581 -138.571211) (xy 62.122939 -138.53876)
			(xy 62.172539 -138.513259) (xy 62.225323 -138.495252) (xy 62.280166 -138.485122) (xy 62.3359 -138.483085)
			(xy 62.391337 -138.489185) (xy 62.445294 -138.503291) (xy 62.496623 -138.525103) (xy 62.544229 -138.554157)
			(xy 62.587097 -138.589832) (xy 62.624314 -138.631369) (xy 62.655087 -138.677882) (xy 62.678759 -138.728379)
			(xy 62.694827 -138.781786) (xy 62.702947 -138.836962) (xy 62.703456 -138.864848) (xy 62.702947 -138.892734)
			(xy 62.694827 -138.94791) (xy 62.678759 -139.001317) (xy 62.655087 -139.051814) (xy 62.624314 -139.098327)
			(xy 62.587097 -139.139864) (xy 62.544229 -139.175539) (xy 62.496623 -139.204593) (xy 62.445294 -139.226405)
			(xy 62.391337 -139.240511) (xy 62.3359 -139.246611) (xy 62.280166 -139.244574) (xy 62.225323 -139.234444)
			(xy 62.172539 -139.216437) (xy 62.122939 -139.190936) (xy 62.077581 -139.158485) (xy 62.037432 -139.119776)
			(xy 62.003346 -139.075633) (xy 61.97605 -139.026998) (xy 61.956127 -138.974907) (xy 61.944001 -138.92047)
			(xy 61.93993 -138.864848) (xy 57.266035 -138.864848) (xy 57.269266 -138.875851) (xy 57.277022 -138.929799)
			(xy 57.277508 -138.95705) (xy 57.277021 -138.984831) (xy 57.268946 -139.039802) (xy 57.252975 -139.093019)
			(xy 57.229446 -139.143352) (xy 57.198858 -139.189736) (xy 57.180734 -139.210796) (xy 57.18048 -139.21105)
			(xy 57.174172 -139.218927) (xy 57.167759 -139.238046) (xy 57.168034 -139.248134) (xy 57.173368 -139.321286)
			(xy 57.17455 -139.33136) (xy 57.183715 -139.349437) (xy 57.191148 -139.356338) (xy 57.191402 -139.356592)
			(xy 57.212402 -139.374834) (xy 57.249478 -139.416297) (xy 57.280132 -139.46271) (xy 57.303711 -139.513087)
			(xy 57.319715 -139.566358) (xy 57.327802 -139.621389) (xy 57.328308 -139.6492) (xy 57.327822 -139.676451)
			(xy 57.322063 -139.71651) (xy 82.791806 -139.71651) (xy 82.795877 -139.660888) (xy 82.808003 -139.606451)
			(xy 82.827926 -139.55436) (xy 82.855222 -139.505725) (xy 82.889308 -139.461582) (xy 82.929457 -139.422873)
			(xy 82.974815 -139.390422) (xy 83.024415 -139.364921) (xy 83.077199 -139.346914) (xy 83.132042 -139.336784)
			(xy 83.187776 -139.334747) (xy 83.243213 -139.340847) (xy 83.29717 -139.354953) (xy 83.348499 -139.376765)
			(xy 83.396105 -139.405819) (xy 83.438973 -139.441494) (xy 83.47619 -139.483031) (xy 83.506963 -139.529544)
			(xy 83.530635 -139.580041) (xy 83.546703 -139.633448) (xy 83.554823 -139.688624) (xy 83.555332 -139.71651)
			(xy 83.554823 -139.744396) (xy 83.546703 -139.799572) (xy 83.530635 -139.852979) (xy 83.506963 -139.903476)
			(xy 83.47619 -139.949989) (xy 83.438973 -139.991526) (xy 83.396105 -140.027201) (xy 83.35748 -140.050774)
			(xy 85.235794 -140.050774) (xy 85.239865 -139.995152) (xy 85.251991 -139.940715) (xy 85.271914 -139.888624)
			(xy 85.29921 -139.839989) (xy 85.333296 -139.795846) (xy 85.373445 -139.757137) (xy 85.418803 -139.724686)
			(xy 85.468403 -139.699185) (xy 85.521187 -139.681178) (xy 85.57603 -139.671048) (xy 85.631764 -139.669011)
			(xy 85.687201 -139.675111) (xy 85.741158 -139.689217) (xy 85.792487 -139.711029) (xy 85.840093 -139.740083)
			(xy 85.882961 -139.775758) (xy 85.920178 -139.817295) (xy 85.950951 -139.863808) (xy 85.974623 -139.914305)
			(xy 85.990691 -139.967712) (xy 85.998811 -140.022888) (xy 85.99932 -140.050774) (xy 85.998811 -140.07866)
			(xy 85.990691 -140.133836) (xy 85.974623 -140.187243) (xy 85.950951 -140.23774) (xy 85.920178 -140.284253)
			(xy 85.882961 -140.32579) (xy 85.840093 -140.361465) (xy 85.792487 -140.390519) (xy 85.741158 -140.412331)
			(xy 85.687201 -140.426437) (xy 85.631764 -140.432537) (xy 85.57603 -140.4305) (xy 85.521187 -140.42037)
			(xy 85.468403 -140.402363) (xy 85.418803 -140.376862) (xy 85.373445 -140.344411) (xy 85.333296 -140.305702)
			(xy 85.29921 -140.261559) (xy 85.271914 -140.212924) (xy 85.251991 -140.160833) (xy 85.239865 -140.106396)
			(xy 85.235794 -140.050774) (xy 83.35748 -140.050774) (xy 83.348499 -140.056255) (xy 83.29717 -140.078067)
			(xy 83.243213 -140.092173) (xy 83.187776 -140.098273) (xy 83.132042 -140.096236) (xy 83.077199 -140.086106)
			(xy 83.024415 -140.068099) (xy 82.974815 -140.042598) (xy 82.929457 -140.010147) (xy 82.889308 -139.971438)
			(xy 82.855222 -139.927295) (xy 82.827926 -139.87866) (xy 82.808003 -139.826569) (xy 82.795877 -139.772132)
			(xy 82.791806 -139.71651) (xy 57.322063 -139.71651) (xy 57.320066 -139.730399) (xy 57.304711 -139.782694)
			(xy 57.282069 -139.832271) (xy 57.252603 -139.878121) (xy 57.216912 -139.919312) (xy 57.175721 -139.955003)
			(xy 57.129871 -139.984469) (xy 57.080294 -140.007111) (xy 57.027999 -140.022466) (xy 56.974051 -140.030222)
			(xy 56.919549 -140.030222) (xy 56.865601 -140.022466) (xy 56.813306 -140.007111) (xy 56.763729 -139.984469)
			(xy 56.717879 -139.955003) (xy 56.676688 -139.919312) (xy 56.640997 -139.878121) (xy 56.611531 -139.832271)
			(xy 56.588889 -139.782694) (xy 56.573534 -139.730399) (xy 56.565778 -139.676451) (xy 56.565292 -139.6492)
			(xy 56.565809 -139.62142) (xy 56.573876 -139.56645) (xy 56.58984 -139.513234) (xy 56.613363 -139.4629)
			(xy 56.643945 -139.416515) (xy 56.662066 -139.395454) (xy 56.66232 -139.3952) (xy 56.668651 -139.387339)
			(xy 56.675051 -139.368207) (xy 56.674766 -139.358116) (xy 56.669432 -139.284964) (xy 56.668275 -139.274885)
			(xy 56.659093 -139.25681) (xy 56.651652 -139.249912) (xy 56.651398 -139.249658) (xy 56.630374 -139.231443)
			(xy 56.593299 -139.189974) (xy 56.562649 -139.143555) (xy 56.539074 -139.093173) (xy 56.523075 -139.039898)
			(xy 56.514994 -138.984863) (xy 56.514492 -138.95705) (xy 19.422436 -138.95705) (xy 19.453674 -138.977126)
			(xy 19.494864 -139.012818) (xy 19.530555 -139.054008) (xy 19.560021 -139.099859) (xy 19.582663 -139.149436)
			(xy 19.598018 -139.201731) (xy 19.605774 -139.255679) (xy 19.605774 -139.310181) (xy 19.598018 -139.364129)
			(xy 19.582663 -139.416424) (xy 19.560021 -139.466001) (xy 19.530555 -139.511852) (xy 19.494864 -139.553042)
			(xy 19.453674 -139.588734) (xy 19.407823 -139.618201) (xy 19.358246 -139.640842) (xy 19.305951 -139.656197)
			(xy 19.252003 -139.663954) (xy 19.224752 -139.66444) (xy 19.197382 -139.663958) (xy 19.143203 -139.656146)
			(xy 19.0907 -139.640662) (xy 19.040952 -139.617823) (xy 18.994986 -139.588101) (xy 18.974054 -139.57046)
			(xy 18.9738 -139.570206) (xy 18.966717 -139.564614) (xy 18.949798 -139.55837) (xy 18.94078 -139.558014)
			(xy 18.873724 -139.558014) (xy 18.864708 -139.558379) (xy 18.847791 -139.564621) (xy 18.840704 -139.570206)
			(xy 18.84045 -139.57046) (xy 18.819517 -139.588101) (xy 18.773549 -139.617825) (xy 18.723803 -139.640671)
			(xy 18.671301 -139.656167) (xy 18.617123 -139.663996) (xy 18.562381 -139.663996) (xy 18.508203 -139.656167)
			(xy 18.455701 -139.640671) (xy 18.405955 -139.617825) (xy 18.359987 -139.588101) (xy 18.339054 -139.57046)
			(xy 18.3388 -139.570206) (xy 18.331717 -139.564614) (xy 18.314798 -139.55837) (xy 18.30578 -139.558014)
			(xy 18.238724 -139.558014) (xy 18.229708 -139.558379) (xy 18.212791 -139.564621) (xy 18.205704 -139.570206)
			(xy 18.205704 -139.57046) (xy 18.20545 -139.57046) (xy 18.184517 -139.588101) (xy 18.138549 -139.617825)
			(xy 18.088803 -139.640671) (xy 18.036301 -139.656167) (xy 17.982123 -139.663996) (xy 17.927381 -139.663996)
			(xy 17.873203 -139.656167) (xy 17.820701 -139.640671) (xy 17.770955 -139.617825) (xy 17.724987 -139.588101)
			(xy 17.704054 -139.57046) (xy 17.7038 -139.570206) (xy 17.696717 -139.564614) (xy 17.679798 -139.55837)
			(xy 17.67078 -139.558014) (xy 17.603724 -139.558014) (xy 17.594708 -139.558379) (xy 17.577791 -139.564621)
			(xy 17.570704 -139.570206) (xy 17.570704 -139.57046) (xy 17.57045 -139.57046) (xy 17.549505 -139.588083)
			(xy 17.503536 -139.617799) (xy 17.453792 -139.640638) (xy 17.401294 -139.656133) (xy 17.34712 -139.663964)
			(xy 17.319752 -139.66444) (xy 17.292501 -139.663967) (xy 17.238555 -139.656205) (xy 17.186262 -139.640845)
			(xy 17.136686 -139.618201) (xy 17.090838 -139.588732) (xy 17.049649 -139.55304) (xy 17.013958 -139.51185)
			(xy 16.984492 -139.466) (xy 16.961849 -139.416423) (xy 16.946492 -139.36413) (xy 16.938732 -139.310183)
			(xy 16.938244 -139.282932) (xy 6.927773 -139.282932) (xy 6.930905 -139.293342) (xy 6.939025 -139.348518)
			(xy 6.939534 -139.376404) (xy 6.939025 -139.40429) (xy 6.930905 -139.459466) (xy 6.914837 -139.512873)
			(xy 6.891165 -139.56337) (xy 6.860392 -139.609883) (xy 6.823175 -139.65142) (xy 6.780307 -139.687095)
			(xy 6.732701 -139.716149) (xy 6.681372 -139.737961) (xy 6.627415 -139.752067) (xy 6.571978 -139.758167)
			(xy 6.516244 -139.75613) (xy 6.461401 -139.746) (xy 6.408617 -139.727993) (xy 6.359017 -139.702492)
			(xy 6.313659 -139.670041) (xy 6.27351 -139.631332) (xy 6.239424 -139.587189) (xy 6.212128 -139.538554)
			(xy 6.192205 -139.486463) (xy 6.180079 -139.432026) (xy 6.176008 -139.376404) (xy 4.38404 -139.376404)
			(xy 4.38404 -140.392404) (xy 8.367774 -140.392404) (xy 8.371845 -140.336782) (xy 8.383971 -140.282345)
			(xy 8.403894 -140.230254) (xy 8.43119 -140.181619) (xy 8.465276 -140.137476) (xy 8.505425 -140.098767)
			(xy 8.550783 -140.066316) (xy 8.600383 -140.040815) (xy 8.653167 -140.022808) (xy 8.70801 -140.012678)
			(xy 8.763744 -140.010641) (xy 8.819181 -140.016741) (xy 8.873138 -140.030847) (xy 8.924467 -140.052659)
			(xy 8.972073 -140.081713) (xy 9.014941 -140.117388) (xy 9.052158 -140.158925) (xy 9.082931 -140.205438)
			(xy 9.106603 -140.255935) (xy 9.122671 -140.309342) (xy 9.130791 -140.364518) (xy 9.1313 -140.392404)
			(xy 9.130791 -140.42029) (xy 9.122671 -140.475466) (xy 9.106603 -140.528873) (xy 9.082931 -140.57937)
			(xy 9.052158 -140.625883) (xy 9.014941 -140.66742) (xy 8.972073 -140.703095) (xy 8.924467 -140.732149)
			(xy 8.873138 -140.753961) (xy 8.819181 -140.768067) (xy 8.763744 -140.774167) (xy 8.70801 -140.77213)
			(xy 8.653167 -140.762) (xy 8.600383 -140.743993) (xy 8.550783 -140.718492) (xy 8.505425 -140.686041)
			(xy 8.465276 -140.647332) (xy 8.43119 -140.603189) (xy 8.403894 -140.554554) (xy 8.383971 -140.502463)
			(xy 8.371845 -140.448026) (xy 8.367774 -140.392404) (xy 4.38404 -140.392404) (xy 4.38404 -141.046533)
			(xy 10.755071 -141.046533) (xy 10.755071 -140.992027) (xy 10.762828 -140.938075) (xy 10.778185 -140.885777)
			(xy 10.800828 -140.836196) (xy 10.830296 -140.790342) (xy 10.86599 -140.749149) (xy 10.907184 -140.713455)
			(xy 10.953038 -140.683987) (xy 11.002618 -140.661344) (xy 11.054917 -140.645988) (xy 11.108869 -140.638231)
			(xy 11.136122 -140.637768) (xy 11.162436 -140.638231) (xy 11.214564 -140.645468) (xy 11.265207 -140.659789)
			(xy 11.313405 -140.680922) (xy 11.358249 -140.708469) (xy 11.398889 -140.741907) (xy 11.417046 -140.760958)
			(xy 11.424554 -140.768376) (xy 11.443844 -140.776892) (xy 11.454384 -140.777468) (xy 11.52906 -140.777468)
			(xy 11.53961 -140.77694) (xy 11.558906 -140.768405) (xy 11.566398 -140.760958) (xy 11.584553 -140.741902)
			(xy 11.625184 -140.708447) (xy 11.670025 -140.680889) (xy 11.718225 -140.659751) (xy 11.768872 -140.645433)
			(xy 11.821006 -140.638207) (xy 11.847322 -140.637768) (xy 11.874573 -140.638262) (xy 11.92852 -140.646019)
			(xy 11.980814 -140.661374) (xy 12.03039 -140.684015) (xy 12.07624 -140.713481) (xy 12.117429 -140.749172)
			(xy 12.15312 -140.790362) (xy 12.182586 -140.836212) (xy 12.205227 -140.885788) (xy 12.220582 -140.938082)
			(xy 12.228338 -140.992029) (xy 12.228338 -141.046531) (xy 12.220582 -141.100478) (xy 12.205227 -141.152772)
			(xy 12.182586 -141.202348) (xy 12.15312 -141.248198) (xy 12.117429 -141.289388) (xy 12.07624 -141.325079)
			(xy 12.03039 -141.354545) (xy 11.980814 -141.377186) (xy 11.92852 -141.392541) (xy 11.874573 -141.400298)
			(xy 11.847322 -141.400784) (xy 11.821008 -141.400307) (xy 11.76888 -141.393075) (xy 11.718237 -141.378758)
			(xy 11.670038 -141.357627) (xy 11.625194 -141.330083) (xy 11.584555 -141.296645) (xy 11.566398 -141.277594)
			(xy 11.55888 -141.270189) (xy 11.539597 -141.261667) (xy 11.52906 -141.261084) (xy 11.454384 -141.261084)
			(xy 11.443832 -141.261596) (xy 11.424538 -141.270144) (xy 11.417046 -141.277594) (xy 11.398909 -141.296668)
			(xy 11.358275 -141.330123) (xy 11.313431 -141.35768) (xy 11.265227 -141.378815) (xy 11.214576 -141.393129)
			(xy 11.162439 -141.400348) (xy 11.136122 -141.400784) (xy 11.108869 -141.400329) (xy 11.054917 -141.392572)
			(xy 11.002618 -141.377216) (xy 10.953038 -141.354573) (xy 10.907184 -141.325105) (xy 10.86599 -141.289411)
			(xy 10.830296 -141.248218) (xy 10.800828 -141.202364) (xy 10.778185 -141.152783) (xy 10.762828 -141.100485)
			(xy 10.755071 -141.046533) (xy 4.38404 -141.046533) (xy 4.38404 -143.078533) (xy 10.755071 -143.078533)
			(xy 10.755071 -143.024027) (xy 10.762828 -142.970075) (xy 10.778185 -142.917777) (xy 10.800828 -142.868196)
			(xy 10.830296 -142.822342) (xy 10.86599 -142.781149) (xy 10.907184 -142.745455) (xy 10.953038 -142.715987)
			(xy 11.002618 -142.693344) (xy 11.054917 -142.677988) (xy 11.108869 -142.670231) (xy 11.136122 -142.669768)
			(xy 11.162436 -142.670231) (xy 11.214564 -142.677468) (xy 11.265207 -142.691789) (xy 11.313405 -142.712922)
			(xy 11.358249 -142.740469) (xy 11.398889 -142.773907) (xy 11.417046 -142.792958) (xy 11.424554 -142.800376)
			(xy 11.443844 -142.808892) (xy 11.454384 -142.809468) (xy 11.52906 -142.809468) (xy 11.53961 -142.80894)
			(xy 11.558906 -142.800405) (xy 11.566398 -142.792958) (xy 11.584553 -142.773902) (xy 11.625184 -142.740447)
			(xy 11.670025 -142.712889) (xy 11.718225 -142.691751) (xy 11.768872 -142.677433) (xy 11.821006 -142.670207)
			(xy 11.847322 -142.669768) (xy 11.874573 -142.670262) (xy 11.92852 -142.678019) (xy 11.980814 -142.693374)
			(xy 12.03039 -142.716015) (xy 12.07624 -142.745481) (xy 12.117429 -142.781172) (xy 12.15312 -142.822362)
			(xy 12.182586 -142.868212) (xy 12.205227 -142.917788) (xy 12.220582 -142.970082) (xy 12.228338 -143.024029)
			(xy 12.228338 -143.078531) (xy 12.220582 -143.132478) (xy 12.205227 -143.184772) (xy 12.182586 -143.234348)
			(xy 12.15312 -143.280198) (xy 12.117429 -143.321388) (xy 12.07624 -143.357079) (xy 12.03039 -143.386545)
			(xy 11.980814 -143.409186) (xy 11.92852 -143.424541) (xy 11.874573 -143.432298) (xy 11.847322 -143.432784)
			(xy 11.821008 -143.432307) (xy 11.76888 -143.425075) (xy 11.718237 -143.410758) (xy 11.670038 -143.389627)
			(xy 11.625194 -143.362083) (xy 11.584555 -143.328645) (xy 11.566398 -143.309594) (xy 11.55888 -143.302189)
			(xy 11.539597 -143.293667) (xy 11.52906 -143.293084) (xy 11.454384 -143.293084) (xy 11.443832 -143.293596)
			(xy 11.424538 -143.302144) (xy 11.417046 -143.309594) (xy 11.398909 -143.328668) (xy 11.358275 -143.362123)
			(xy 11.313431 -143.38968) (xy 11.265227 -143.410815) (xy 11.214576 -143.425129) (xy 11.162439 -143.432348)
			(xy 11.136122 -143.432784) (xy 11.108869 -143.432329) (xy 11.054917 -143.424572) (xy 11.002618 -143.409216)
			(xy 10.953038 -143.386573) (xy 10.907184 -143.357105) (xy 10.86599 -143.321411) (xy 10.830296 -143.280218)
			(xy 10.800828 -143.234364) (xy 10.778185 -143.184783) (xy 10.762828 -143.132485) (xy 10.755071 -143.078533)
			(xy 4.38404 -143.078533) (xy 4.38404 -143.915638) (xy 19.464274 -143.915638) (xy 19.464775 -143.888065)
			(xy 19.472722 -143.833494) (xy 19.48844 -143.780635) (xy 19.511604 -143.730589) (xy 19.541729 -143.684399)
			(xy 19.57819 -143.643025) (xy 19.598894 -143.624808) (xy 19.606965 -143.617249) (xy 19.616322 -143.597241)
			(xy 19.616928 -143.5862) (xy 19.616928 -143.508476) (xy 19.616341 -143.497428) (xy 19.606991 -143.477406)
			(xy 19.598894 -143.469868) (xy 19.578163 -143.451679) (xy 19.541694 -143.410305) (xy 19.511565 -143.364111)
			(xy 19.488403 -143.314058) (xy 19.472691 -143.261192) (xy 19.464756 -143.206614) (xy 19.464274 -143.179038)
			(xy 19.464767 -143.150298) (xy 19.473398 -143.09347) (xy 19.490456 -143.038579) (xy 19.515554 -142.986868)
			(xy 19.548125 -142.939506) (xy 19.567398 -142.91818) (xy 19.574002 -142.911322) (xy 19.581114 -142.893288)
			(xy 19.581114 -142.804388) (xy 19.574002 -142.786354) (xy 19.567398 -142.779496) (xy 19.548166 -142.758136)
			(xy 19.515602 -142.710778) (xy 19.49051 -142.659072) (xy 19.473458 -142.604187) (xy 19.464833 -142.547364)
			(xy 19.464829 -142.489891) (xy 19.473446 -142.433068) (xy 19.490489 -142.37818) (xy 19.515574 -142.32647)
			(xy 19.548131 -142.279107) (xy 19.567398 -142.25778) (xy 19.574002 -142.250922) (xy 19.581114 -142.232888)
			(xy 19.581114 -142.143988) (xy 19.574002 -142.125954) (xy 19.567398 -142.119096) (xy 19.548166 -142.097736)
			(xy 19.515602 -142.050378) (xy 19.49051 -141.998672) (xy 19.473458 -141.943787) (xy 19.464833 -141.886964)
			(xy 19.464829 -141.829491) (xy 19.473446 -141.772668) (xy 19.490489 -141.71778) (xy 19.515574 -141.66607)
			(xy 19.548131 -141.618707) (xy 19.567398 -141.59738) (xy 19.574002 -141.590522) (xy 19.581114 -141.572488)
			(xy 19.581114 -141.483588) (xy 19.574002 -141.465554) (xy 19.567398 -141.458696) (xy 19.548166 -141.437336)
			(xy 19.515602 -141.389978) (xy 19.49051 -141.338272) (xy 19.473458 -141.283387) (xy 19.464833 -141.226564)
			(xy 19.464829 -141.169091) (xy 19.473446 -141.112268) (xy 19.490489 -141.05738) (xy 19.515574 -141.00567)
			(xy 19.548131 -140.958307) (xy 19.567398 -140.93698) (xy 19.574002 -140.930122) (xy 19.581114 -140.912088)
			(xy 19.581114 -140.823188) (xy 19.574002 -140.805154) (xy 19.567398 -140.798296) (xy 19.548156 -140.776944)
			(xy 19.515583 -140.72959) (xy 19.490484 -140.677885) (xy 19.473427 -140.622999) (xy 19.464798 -140.566175)
			(xy 19.464274 -140.537438) (xy 19.46476 -140.510187) (xy 19.472516 -140.456239) (xy 19.487871 -140.403944)
			(xy 19.510513 -140.354367) (xy 19.539979 -140.308517) (xy 19.57567 -140.267326) (xy 19.616861 -140.231635)
			(xy 19.662711 -140.202169) (xy 19.712288 -140.179527) (xy 19.764583 -140.164172) (xy 19.818531 -140.156416)
			(xy 19.873033 -140.156416) (xy 19.926981 -140.164172) (xy 19.979276 -140.179527) (xy 20.028853 -140.202169)
			(xy 20.074703 -140.231635) (xy 20.115894 -140.267326) (xy 20.151585 -140.308517) (xy 20.163055 -140.326364)
			(xy 35.692078 -140.326364) (xy 35.696149 -140.270742) (xy 35.708275 -140.216305) (xy 35.728198 -140.164214)
			(xy 35.755494 -140.115579) (xy 35.78958 -140.071436) (xy 35.829729 -140.032727) (xy 35.875087 -140.000276)
			(xy 35.924687 -139.974775) (xy 35.977471 -139.956768) (xy 36.032314 -139.946638) (xy 36.088048 -139.944601)
			(xy 36.143485 -139.950701) (xy 36.197442 -139.964807) (xy 36.248771 -139.986619) (xy 36.296377 -140.015673)
			(xy 36.339245 -140.051348) (xy 36.376462 -140.092885) (xy 36.407235 -140.139398) (xy 36.430907 -140.189895)
			(xy 36.446975 -140.243302) (xy 36.455095 -140.298478) (xy 36.455604 -140.326364) (xy 36.455095 -140.35425)
			(xy 36.446975 -140.409426) (xy 36.430907 -140.462833) (xy 36.407235 -140.51333) (xy 36.376462 -140.559843)
			(xy 36.339245 -140.60138) (xy 36.296377 -140.637055) (xy 36.248771 -140.666109) (xy 36.197442 -140.687921)
			(xy 36.143485 -140.702027) (xy 36.088048 -140.708127) (xy 36.032314 -140.70609) (xy 35.977471 -140.69596)
			(xy 35.924687 -140.677953) (xy 35.875087 -140.652452) (xy 35.829729 -140.620001) (xy 35.78958 -140.581292)
			(xy 35.755494 -140.537149) (xy 35.728198 -140.488514) (xy 35.708275 -140.436423) (xy 35.696149 -140.381986)
			(xy 35.692078 -140.326364) (xy 20.163055 -140.326364) (xy 20.181051 -140.354367) (xy 20.203693 -140.403944)
			(xy 20.219048 -140.456239) (xy 20.226804 -140.510187) (xy 20.22729 -140.537438) (xy 20.226792 -140.566178)
			(xy 20.218164 -140.623007) (xy 20.201108 -140.677898) (xy 20.17601 -140.729609) (xy 20.143439 -140.77697)
			(xy 20.124166 -140.798296) (xy 20.117562 -140.805154) (xy 20.11045 -140.823188) (xy 20.11045 -140.912088)
			(xy 20.117562 -140.930122) (xy 20.124166 -140.93698) (xy 20.143475 -140.958274) (xy 20.17604 -141.005642)
			(xy 20.20113 -141.057359) (xy 20.218178 -141.112255) (xy 20.226797 -141.169087) (xy 20.226793 -141.226569)
			(xy 20.218165 -141.283399) (xy 20.20111 -141.338293) (xy 20.176012 -141.390006) (xy 20.14344 -141.437369)
			(xy 20.124166 -141.458696) (xy 20.117562 -141.465554) (xy 20.11045 -141.483588) (xy 20.11045 -141.572488)
			(xy 20.117562 -141.590522) (xy 20.124166 -141.59738) (xy 20.143475 -141.618674) (xy 20.17604 -141.666042)
			(xy 20.20113 -141.717759) (xy 20.218178 -141.772655) (xy 20.226797 -141.829487) (xy 20.226793 -141.886969)
			(xy 20.218165 -141.943799) (xy 20.20111 -141.998693) (xy 20.176012 -142.050406) (xy 20.14344 -142.097769)
			(xy 20.124166 -142.119096) (xy 20.117562 -142.125954) (xy 20.11045 -142.143988) (xy 20.11045 -142.232888)
			(xy 20.117562 -142.250922) (xy 20.124166 -142.25778) (xy 20.143475 -142.279074) (xy 20.17604 -142.326442)
			(xy 20.20113 -142.378159) (xy 20.218178 -142.433055) (xy 20.226797 -142.489887) (xy 20.226793 -142.547369)
			(xy 20.218165 -142.604199) (xy 20.20111 -142.659093) (xy 20.176012 -142.710806) (xy 20.14344 -142.758169)
			(xy 20.124166 -142.779496) (xy 20.117562 -142.786354) (xy 20.11045 -142.804388) (xy 20.11045 -142.893288)
			(xy 20.117562 -142.911322) (xy 20.124166 -142.91818) (xy 20.143455 -142.939491) (xy 20.176019 -142.986857)
			(xy 20.201108 -143.038573) (xy 20.218154 -143.093467) (xy 20.226772 -143.150298) (xy 20.22729 -143.179038)
			(xy 20.226785 -143.206611) (xy 20.218841 -143.261182) (xy 20.203124 -143.314042) (xy 20.179961 -143.364088)
			(xy 20.149836 -143.410279) (xy 20.113374 -143.451651) (xy 20.09267 -143.469868) (xy 20.084604 -143.477431)
			(xy 20.075246 -143.497437) (xy 20.074636 -143.508476) (xy 20.074636 -143.5862) (xy 20.075248 -143.597244)
			(xy 20.084581 -143.617266) (xy 20.09267 -143.624808) (xy 20.113382 -143.643018) (xy 20.149854 -143.684386)
			(xy 20.179987 -143.730576) (xy 20.203152 -143.780625) (xy 20.218868 -143.833488) (xy 20.226806 -143.888063)
			(xy 20.22729 -143.915638) (xy 20.226804 -143.942889) (xy 20.219048 -143.996837) (xy 20.203693 -144.049132)
			(xy 20.181051 -144.098709) (xy 20.151585 -144.144559) (xy 20.115894 -144.18575) (xy 20.074703 -144.221441)
			(xy 20.028853 -144.250907) (xy 19.979276 -144.273549) (xy 19.926981 -144.288904) (xy 19.873033 -144.29666)
			(xy 19.818531 -144.29666) (xy 19.764583 -144.288904) (xy 19.712288 -144.273549) (xy 19.662711 -144.250907)
			(xy 19.616861 -144.221441) (xy 19.57567 -144.18575) (xy 19.539979 -144.144559) (xy 19.510513 -144.098709)
			(xy 19.487871 -144.049132) (xy 19.472516 -143.996837) (xy 19.46476 -143.942889) (xy 19.464274 -143.915638)
			(xy 4.38404 -143.915638) (xy 4.38404 -145.110533) (xy 10.755071 -145.110533) (xy 10.755071 -145.056027)
			(xy 10.762828 -145.002075) (xy 10.778185 -144.949777) (xy 10.800828 -144.900196) (xy 10.830296 -144.854342)
			(xy 10.86599 -144.813149) (xy 10.907184 -144.777455) (xy 10.953038 -144.747987) (xy 11.002618 -144.725344)
			(xy 11.054917 -144.709988) (xy 11.108869 -144.702231) (xy 11.136122 -144.701768) (xy 11.162436 -144.702231)
			(xy 11.214564 -144.709468) (xy 11.265207 -144.723789) (xy 11.313405 -144.744922) (xy 11.358249 -144.772469)
			(xy 11.398889 -144.805907) (xy 11.417046 -144.824958) (xy 11.424554 -144.832376) (xy 11.443844 -144.840892)
			(xy 11.454384 -144.841468) (xy 11.52906 -144.841468) (xy 11.53961 -144.84094) (xy 11.558906 -144.832405)
			(xy 11.566398 -144.824958) (xy 11.584553 -144.805902) (xy 11.625184 -144.772447) (xy 11.670025 -144.744889)
			(xy 11.718225 -144.723751) (xy 11.768872 -144.709433) (xy 11.821006 -144.702207) (xy 11.847322 -144.701768)
			(xy 11.874573 -144.702262) (xy 11.92852 -144.710019) (xy 11.980814 -144.725374) (xy 12.03039 -144.748015)
			(xy 12.07624 -144.777481) (xy 12.117429 -144.813172) (xy 12.15312 -144.854362) (xy 12.182586 -144.900212)
			(xy 12.205227 -144.949788) (xy 12.206535 -144.954244) (xy 17.939004 -144.954244) (xy 17.939496 -144.926992)
			(xy 17.947248 -144.873041) (xy 17.962599 -144.820743) (xy 17.985237 -144.771162) (xy 18.014701 -144.725308)
			(xy 18.050392 -144.684115) (xy 18.091583 -144.648421) (xy 18.137434 -144.618952) (xy 18.187013 -144.59631)
			(xy 18.23931 -144.580954) (xy 18.29326 -144.573199) (xy 18.320512 -144.572736) (xy 18.349288 -144.573223)
			(xy 18.406184 -144.581882) (xy 18.461135 -144.598986) (xy 18.512895 -144.624148) (xy 18.560289 -144.656798)
			(xy 18.581624 -144.676114) (xy 18.589498 -144.68348) (xy 18.60931 -144.690592) (xy 18.705576 -144.683226)
			(xy 18.724372 -144.67332) (xy 18.730976 -144.664938) (xy 18.749179 -144.642735) (xy 18.791119 -144.603525)
			(xy 18.838459 -144.571041) (xy 18.890131 -144.546016) (xy 18.944969 -144.529014) (xy 19.001735 -144.520419)
			(xy 19.030442 -144.519904) (xy 19.057695 -144.520339) (xy 19.111645 -144.528101) (xy 19.163941 -144.543462)
			(xy 19.21352 -144.566109) (xy 19.25937 -144.595581) (xy 19.30056 -144.631278) (xy 19.336251 -144.672473)
			(xy 19.365717 -144.718328) (xy 19.388357 -144.767909) (xy 19.40371 -144.820208) (xy 19.411465 -144.874159)
			(xy 19.41195 -144.901412) (xy 19.411476 -144.928314) (xy 19.403904 -144.981583) (xy 19.388925 -145.03326)
			(xy 19.366836 -145.082321) (xy 19.338076 -145.127793) (xy 19.303214 -145.168775) (xy 19.262942 -145.204455)
			(xy 19.240754 -145.219674) (xy 19.229832 -145.226786) (xy 19.217894 -145.249646) (xy 19.219926 -145.361914)
			(xy 19.23288 -145.384266) (xy 19.244056 -145.391124) (xy 19.267647 -145.406062) (xy 19.310602 -145.441736)
			(xy 19.347897 -145.483291) (xy 19.378737 -145.529838) (xy 19.402462 -145.580383) (xy 19.418566 -145.633847)
			(xy 19.426704 -145.689088) (xy 19.42719 -145.717006) (xy 19.426721 -145.743999) (xy 19.419116 -145.797446)
			(xy 19.404057 -145.849289) (xy 19.381845 -145.898494) (xy 19.352923 -145.944079) (xy 19.33575 -145.96491)
			(xy 19.328638 -145.973038) (xy 19.322542 -145.993612) (xy 19.333464 -146.078956) (xy 19.335269 -146.089493)
			(xy 19.346303 -146.107777) (xy 19.3548 -146.114262) (xy 19.376018 -146.129632) (xy 19.414469 -146.165218)
			(xy 19.447687 -146.205732) (xy 19.475047 -146.250413) (xy 19.496032 -146.298418) (xy 19.510249 -146.348843)
			(xy 19.517429 -146.40074) (xy 19.517868 -146.426936) (xy 19.517382 -146.454187) (xy 19.509626 -146.508135)
			(xy 19.494271 -146.56043) (xy 19.471629 -146.610007) (xy 19.442163 -146.655857) (xy 19.406472 -146.697048)
			(xy 19.365281 -146.732739) (xy 19.319431 -146.762205) (xy 19.269854 -146.784847) (xy 19.217559 -146.800202)
			(xy 19.163611 -146.807958) (xy 19.109109 -146.807958) (xy 19.055161 -146.800202) (xy 19.002866 -146.784847)
			(xy 18.953289 -146.762205) (xy 18.907439 -146.732739) (xy 18.866248 -146.697048) (xy 18.830557 -146.655857)
			(xy 18.801091 -146.610007) (xy 18.778449 -146.56043) (xy 18.763094 -146.508135) (xy 18.755338 -146.454187)
			(xy 18.754852 -146.426936) (xy 18.755335 -146.399943) (xy 18.762936 -146.346496) (xy 18.777991 -146.294653)
			(xy 18.8002 -146.245448) (xy 18.82912 -146.199863) (xy 18.846292 -146.179032) (xy 18.853404 -146.170904)
			(xy 18.8595 -146.15033) (xy 18.848578 -146.064986) (xy 18.846822 -146.054437) (xy 18.835755 -146.036156)
			(xy 18.827242 -146.02968) (xy 18.802936 -146.012074) (xy 18.75968 -145.970474) (xy 18.741136 -145.946876)
			(xy 18.735294 -145.939002) (xy 18.717768 -145.928588) (xy 18.627344 -145.91538) (xy 18.60804 -145.920206)
			(xy 18.600166 -145.926048) (xy 18.599912 -145.926048) (xy 18.575181 -145.943571) (xy 18.521324 -145.97137)
			(xy 18.463748 -145.990301) (xy 18.403902 -145.999887) (xy 18.373598 -146.00047) (xy 18.346343 -146.000046)
			(xy 18.292389 -145.992288) (xy 18.240088 -145.97693) (xy 18.190505 -145.954284) (xy 18.144651 -145.924813)
			(xy 18.103457 -145.889115) (xy 18.067763 -145.847917) (xy 18.038296 -145.802059) (xy 18.015656 -145.752474)
			(xy 18.000303 -145.700172) (xy 17.992551 -145.646217) (xy 17.99209 -145.618962) (xy 17.992513 -145.592928)
			(xy 17.999606 -145.541344) (xy 18.01364 -145.491201) (xy 18.034357 -145.443431) (xy 18.061371 -145.398917)
			(xy 18.077434 -145.378424) (xy 18.08318 -145.37067) (xy 18.088917 -145.352257) (xy 18.08861 -145.34261)
			(xy 18.08226 -145.262854) (xy 18.073624 -145.245074) (xy 18.066258 -145.238724) (xy 18.046611 -145.220544)
			(xy 18.012087 -145.179638) (xy 17.983617 -145.134309) (xy 17.961759 -145.085447) (xy 17.946943 -145.03401)
			(xy 17.939458 -144.981008) (xy 17.939004 -144.954244) (xy 12.206535 -144.954244) (xy 12.220582 -145.002082)
			(xy 12.228338 -145.056029) (xy 12.228338 -145.110531) (xy 12.220582 -145.164478) (xy 12.205227 -145.216772)
			(xy 12.182586 -145.266348) (xy 12.15312 -145.312198) (xy 12.117429 -145.353388) (xy 12.07624 -145.389079)
			(xy 12.03039 -145.418545) (xy 11.980814 -145.441186) (xy 11.92852 -145.456541) (xy 11.874573 -145.464298)
			(xy 11.847322 -145.464784) (xy 11.821008 -145.464307) (xy 11.76888 -145.457075) (xy 11.718237 -145.442758)
			(xy 11.670038 -145.421627) (xy 11.625194 -145.394083) (xy 11.584555 -145.360645) (xy 11.566398 -145.341594)
			(xy 11.55888 -145.334189) (xy 11.539597 -145.325667) (xy 11.52906 -145.325084) (xy 11.454384 -145.325084)
			(xy 11.443832 -145.325596) (xy 11.424538 -145.334144) (xy 11.417046 -145.341594) (xy 11.398909 -145.360668)
			(xy 11.358275 -145.394123) (xy 11.313431 -145.42168) (xy 11.265227 -145.442815) (xy 11.214576 -145.457129)
			(xy 11.162439 -145.464348) (xy 11.136122 -145.464784) (xy 11.108869 -145.464329) (xy 11.054917 -145.456572)
			(xy 11.002618 -145.441216) (xy 10.953038 -145.418573) (xy 10.907184 -145.389105) (xy 10.86599 -145.353411)
			(xy 10.830296 -145.312218) (xy 10.800828 -145.266364) (xy 10.778185 -145.216783) (xy 10.762828 -145.164485)
			(xy 10.755071 -145.110533) (xy 4.38404 -145.110533) (xy 4.38404 -146.91487) (xy 19.616164 -146.91487)
			(xy 19.620235 -146.859248) (xy 19.632361 -146.804811) (xy 19.652284 -146.75272) (xy 19.67958 -146.704085)
			(xy 19.713666 -146.659942) (xy 19.753815 -146.621233) (xy 19.799173 -146.588782) (xy 19.848773 -146.563281)
			(xy 19.901557 -146.545274) (xy 19.9564 -146.535144) (xy 20.012134 -146.533107) (xy 20.067571 -146.539207)
			(xy 20.121528 -146.553313) (xy 20.172857 -146.575125) (xy 20.220463 -146.604179) (xy 20.263331 -146.639854)
			(xy 20.300548 -146.681391) (xy 20.331321 -146.727904) (xy 20.354993 -146.778401) (xy 20.371061 -146.831808)
			(xy 20.379181 -146.886984) (xy 20.37969 -146.91487) (xy 20.379181 -146.942756) (xy 20.371061 -146.997932)
			(xy 20.354993 -147.051339) (xy 20.349787 -147.062444) (xy 20.994368 -147.062444) (xy 20.998439 -147.006822)
			(xy 21.010565 -146.952385) (xy 21.030488 -146.900294) (xy 21.057784 -146.851659) (xy 21.09187 -146.807516)
			(xy 21.132019 -146.768807) (xy 21.177377 -146.736356) (xy 21.226977 -146.710855) (xy 21.279761 -146.692848)
			(xy 21.334604 -146.682718) (xy 21.390338 -146.680681) (xy 21.445775 -146.686781) (xy 21.499732 -146.700887)
			(xy 21.551061 -146.722699) (xy 21.598667 -146.751753) (xy 21.641535 -146.787428) (xy 21.678752 -146.828965)
			(xy 21.709525 -146.875478) (xy 21.733197 -146.925975) (xy 21.749265 -146.979382) (xy 21.757385 -147.034558)
			(xy 21.757894 -147.062444) (xy 21.757385 -147.09033) (xy 21.749265 -147.145506) (xy 21.733197 -147.198913)
			(xy 21.709525 -147.24941) (xy 21.678752 -147.295923) (xy 21.641535 -147.33746) (xy 21.598667 -147.373135)
			(xy 21.551061 -147.402189) (xy 21.499732 -147.424001) (xy 21.445775 -147.438107) (xy 21.390338 -147.444207)
			(xy 21.334604 -147.44217) (xy 21.279761 -147.43204) (xy 21.226977 -147.414033) (xy 21.177377 -147.388532)
			(xy 21.132019 -147.356081) (xy 21.09187 -147.317372) (xy 21.057784 -147.273229) (xy 21.030488 -147.224594)
			(xy 21.010565 -147.172503) (xy 20.998439 -147.118066) (xy 20.994368 -147.062444) (xy 20.349787 -147.062444)
			(xy 20.331321 -147.101836) (xy 20.300548 -147.148349) (xy 20.263331 -147.189886) (xy 20.220463 -147.225561)
			(xy 20.172857 -147.254615) (xy 20.121528 -147.276427) (xy 20.067571 -147.290533) (xy 20.012134 -147.296633)
			(xy 19.9564 -147.294596) (xy 19.901557 -147.284466) (xy 19.848773 -147.266459) (xy 19.799173 -147.240958)
			(xy 19.753815 -147.208507) (xy 19.713666 -147.169798) (xy 19.67958 -147.125655) (xy 19.652284 -147.07702)
			(xy 19.632361 -147.024929) (xy 19.620235 -146.970492) (xy 19.616164 -146.91487) (xy 4.38404 -146.91487)
			(xy 4.38404 -147.657652) (xy 11.150566 -147.657652) (xy 11.150566 -147.603148) (xy 11.158323 -147.549198)
			(xy 11.173678 -147.496902) (xy 11.19632 -147.447323) (xy 11.225787 -147.401471) (xy 11.26148 -147.36028)
			(xy 11.302671 -147.324587) (xy 11.348523 -147.29512) (xy 11.398102 -147.272478) (xy 11.450398 -147.257123)
			(xy 11.504348 -147.249366) (xy 11.5316 -147.24888) (xy 11.557914 -147.249354) (xy 11.610042 -147.256588)
			(xy 11.660684 -147.270907) (xy 11.708883 -147.292038) (xy 11.753727 -147.319582) (xy 11.794367 -147.353019)
			(xy 11.812524 -147.37207) (xy 11.820039 -147.37948) (xy 11.839324 -147.388001) (xy 11.849862 -147.38858)
			(xy 11.924538 -147.38858) (xy 11.935086 -147.388037) (xy 11.954382 -147.379512) (xy 11.961876 -147.37207)
			(xy 11.981696 -147.351282) (xy 12.026468 -147.315307) (xy 12.076126 -147.286447) (xy 12.129548 -147.265354)
			(xy 12.185527 -147.252505) (xy 12.2428 -147.24819) (xy 12.300073 -147.252505) (xy 12.356052 -147.265354)
			(xy 12.409474 -147.286447) (xy 12.459132 -147.315307) (xy 12.503904 -147.351282) (xy 12.523724 -147.37207)
			(xy 12.531239 -147.37948) (xy 12.550524 -147.388001) (xy 12.561062 -147.38858) (xy 12.635738 -147.38858)
			(xy 12.646286 -147.388037) (xy 12.665582 -147.379512) (xy 12.673076 -147.37207) (xy 12.691244 -147.353027)
			(xy 12.731872 -147.31957) (xy 12.77671 -147.29201) (xy 12.824908 -147.27087) (xy 12.875553 -147.256549)
			(xy 12.927685 -147.249321) (xy 12.954 -147.24888) (xy 12.98125 -147.24939) (xy 13.035196 -147.257147)
			(xy 13.087489 -147.272501) (xy 13.137065 -147.295142) (xy 13.182914 -147.324607) (xy 13.224103 -147.360297)
			(xy 13.259793 -147.401486) (xy 13.289258 -147.447335) (xy 13.311899 -147.496911) (xy 13.327253 -147.549204)
			(xy 13.33501 -147.60315) (xy 13.33501 -147.65765) (xy 13.327253 -147.711596) (xy 13.311899 -147.763889)
			(xy 13.289258 -147.813465) (xy 13.259793 -147.859314) (xy 13.224103 -147.900503) (xy 13.182914 -147.936193)
			(xy 13.137065 -147.965658) (xy 13.087489 -147.988299) (xy 13.035196 -148.003653) (xy 12.98125 -148.01141)
			(xy 12.954 -148.011896) (xy 12.927686 -148.01143) (xy 12.875557 -148.004195) (xy 12.824915 -147.989876)
			(xy 12.776716 -147.968743) (xy 12.731872 -147.941197) (xy 12.691233 -147.907758) (xy 12.673076 -147.888706)
			(xy 12.665564 -147.881293) (xy 12.646277 -147.872775) (xy 12.635738 -147.872196) (xy 12.561062 -147.872196)
			(xy 12.550515 -147.872746) (xy 12.531219 -147.881267) (xy 12.523724 -147.888706) (xy 12.503904 -147.909494)
			(xy 12.459132 -147.945469) (xy 12.409474 -147.974329) (xy 12.356052 -147.995422) (xy 12.300073 -148.008271)
			(xy 12.2428 -148.012586) (xy 12.185527 -148.008271) (xy 12.129548 -147.995422) (xy 12.076126 -147.974329)
			(xy 12.026468 -147.945469) (xy 11.981696 -147.909494) (xy 11.961876 -147.888706) (xy 11.954364 -147.881293)
			(xy 11.935077 -147.872775) (xy 11.924538 -147.872196) (xy 11.849862 -147.872196) (xy 11.839315 -147.872746)
			(xy 11.820019 -147.881267) (xy 11.812524 -147.888706) (xy 11.794351 -147.907744) (xy 11.753725 -147.941203)
			(xy 11.708888 -147.968764) (xy 11.660691 -147.989905) (xy 11.610047 -148.004226) (xy 11.557915 -148.011455)
			(xy 11.5316 -148.011896) (xy 11.504348 -148.011434) (xy 11.450398 -148.003677) (xy 11.398102 -147.988322)
			(xy 11.348523 -147.96568) (xy 11.302671 -147.936213) (xy 11.26148 -147.90052) (xy 11.225787 -147.859329)
			(xy 11.19632 -147.813477) (xy 11.173678 -147.763898) (xy 11.158323 -147.711602) (xy 11.150566 -147.657652)
			(xy 4.38404 -147.657652) (xy 4.38404 -148.017738) (xy 15.977614 -148.017738) (xy 15.981685 -147.962116)
			(xy 15.993811 -147.907679) (xy 16.013734 -147.855588) (xy 16.04103 -147.806953) (xy 16.075116 -147.76281)
			(xy 16.115265 -147.724101) (xy 16.160623 -147.69165) (xy 16.210223 -147.666149) (xy 16.263007 -147.648142)
			(xy 16.31785 -147.638012) (xy 16.373584 -147.635975) (xy 16.429021 -147.642075) (xy 16.482978 -147.656181)
			(xy 16.534307 -147.677993) (xy 16.581913 -147.707047) (xy 16.623176 -147.741386) (xy 21.662134 -147.741386)
			(xy 21.666205 -147.685764) (xy 21.678331 -147.631327) (xy 21.698254 -147.579236) (xy 21.72555 -147.530601)
			(xy 21.759636 -147.486458) (xy 21.799785 -147.447749) (xy 21.845143 -147.415298) (xy 21.894743 -147.389797)
			(xy 21.947527 -147.37179) (xy 22.00237 -147.36166) (xy 22.058104 -147.359623) (xy 22.113541 -147.365723)
			(xy 22.167498 -147.379829) (xy 22.218827 -147.401641) (xy 22.266433 -147.430695) (xy 22.309301 -147.46637)
			(xy 22.346518 -147.507907) (xy 22.377291 -147.55442) (xy 22.400963 -147.604917) (xy 22.417031 -147.658324)
			(xy 22.425151 -147.7135) (xy 22.42566 -147.741386) (xy 22.425151 -147.769272) (xy 22.417031 -147.824448)
			(xy 22.400963 -147.877855) (xy 22.377291 -147.928352) (xy 22.346518 -147.974865) (xy 22.309301 -148.016402)
			(xy 22.266433 -148.052077) (xy 22.218827 -148.081131) (xy 22.167498 -148.102943) (xy 22.113541 -148.117049)
			(xy 22.058104 -148.123149) (xy 22.00237 -148.121112) (xy 21.947527 -148.110982) (xy 21.894743 -148.092975)
			(xy 21.845143 -148.067474) (xy 21.799785 -148.035023) (xy 21.759636 -147.996314) (xy 21.72555 -147.952171)
			(xy 21.698254 -147.903536) (xy 21.678331 -147.851445) (xy 21.666205 -147.797008) (xy 21.662134 -147.741386)
			(xy 16.623176 -147.741386) (xy 16.624781 -147.742722) (xy 16.661998 -147.784259) (xy 16.692771 -147.830772)
			(xy 16.716443 -147.881269) (xy 16.732511 -147.934676) (xy 16.740631 -147.989852) (xy 16.74114 -148.017738)
			(xy 16.740631 -148.045624) (xy 16.732511 -148.1008) (xy 16.716443 -148.154207) (xy 16.692771 -148.204704)
			(xy 16.661998 -148.251217) (xy 16.624781 -148.292754) (xy 16.581913 -148.328429) (xy 16.534307 -148.357483)
			(xy 16.482978 -148.379295) (xy 16.429021 -148.393401) (xy 16.373584 -148.399501) (xy 16.31785 -148.397464)
			(xy 16.263007 -148.387334) (xy 16.210223 -148.369327) (xy 16.160623 -148.343826) (xy 16.115265 -148.311375)
			(xy 16.075116 -148.272666) (xy 16.04103 -148.228523) (xy 16.013734 -148.179888) (xy 15.993811 -148.127797)
			(xy 15.981685 -148.07336) (xy 15.977614 -148.017738) (xy 4.38404 -148.017738) (xy 4.38404 -150.19585)
			(xy 11.150588 -150.19585) (xy 11.150588 -150.14135) (xy 11.158345 -150.087403) (xy 11.173699 -150.03511)
			(xy 11.19634 -149.985534) (xy 11.225805 -149.939685) (xy 11.261496 -149.898496) (xy 11.302685 -149.862805)
			(xy 11.348534 -149.83334) (xy 11.39811 -149.810699) (xy 11.450403 -149.795345) (xy 11.50435 -149.787588)
			(xy 11.5316 -149.787102) (xy 11.557914 -149.787569) (xy 11.610043 -149.794804) (xy 11.660685 -149.809123)
			(xy 11.708884 -149.830255) (xy 11.753728 -149.857802) (xy 11.794367 -149.89124) (xy 11.812524 -149.910292)
			(xy 11.820036 -149.917705) (xy 11.839323 -149.926223) (xy 11.849862 -149.926802) (xy 11.924538 -149.926802)
			(xy 11.935085 -149.926252) (xy 11.954381 -149.917732) (xy 11.961876 -149.910292) (xy 11.981696 -149.889504)
			(xy 12.026468 -149.853529) (xy 12.076126 -149.824669) (xy 12.129548 -149.803576) (xy 12.185527 -149.790727)
			(xy 12.2428 -149.786412) (xy 12.300073 -149.790727) (xy 12.356052 -149.803576) (xy 12.409474 -149.824669)
			(xy 12.459132 -149.853529) (xy 12.503904 -149.889504) (xy 12.523724 -149.910292) (xy 12.531236 -149.917705)
			(xy 12.550523 -149.926223) (xy 12.561062 -149.926802) (xy 12.635738 -149.926802) (xy 12.646285 -149.926252)
			(xy 12.665581 -149.917732) (xy 12.673076 -149.910292) (xy 12.691249 -149.891254) (xy 12.731875 -149.857795)
			(xy 12.776712 -149.830234) (xy 12.824909 -149.809093) (xy 12.875553 -149.794772) (xy 12.927685 -149.787543)
			(xy 12.954 -149.787102) (xy 12.981252 -149.787568) (xy 13.035201 -149.795325) (xy 13.087497 -149.81068)
			(xy 13.137076 -149.833322) (xy 13.182927 -149.862789) (xy 13.224119 -149.898481) (xy 13.259811 -149.939673)
			(xy 13.289278 -149.985524) (xy 13.31192 -150.035103) (xy 13.320244 -150.063454) (xy 15.838168 -150.063454)
			(xy 15.842239 -150.007832) (xy 15.854365 -149.953395) (xy 15.874288 -149.901304) (xy 15.901584 -149.852669)
			(xy 15.93567 -149.808526) (xy 15.975819 -149.769817) (xy 16.021177 -149.737366) (xy 16.070777 -149.711865)
			(xy 16.123561 -149.693858) (xy 16.178404 -149.683728) (xy 16.234138 -149.681691) (xy 16.289575 -149.687791)
			(xy 16.343532 -149.701897) (xy 16.394861 -149.723709) (xy 16.442467 -149.752763) (xy 16.485335 -149.788438)
			(xy 16.522552 -149.829975) (xy 16.553325 -149.876488) (xy 16.576997 -149.926985) (xy 16.593065 -149.980392)
			(xy 16.601185 -150.035568) (xy 16.601694 -150.063454) (xy 16.601185 -150.09134) (xy 16.593065 -150.146516)
			(xy 16.576997 -150.199923) (xy 16.553325 -150.25042) (xy 16.522552 -150.296933) (xy 16.485335 -150.33847)
			(xy 16.442467 -150.374145) (xy 16.394861 -150.403199) (xy 16.343532 -150.425011) (xy 16.289575 -150.439117)
			(xy 16.234138 -150.445217) (xy 16.178404 -150.44318) (xy 16.123561 -150.43305) (xy 16.070777 -150.415043)
			(xy 16.021177 -150.389542) (xy 15.975819 -150.357091) (xy 15.93567 -150.318382) (xy 15.901584 -150.274239)
			(xy 15.874288 -150.225604) (xy 15.854365 -150.173513) (xy 15.842239 -150.119076) (xy 15.838168 -150.063454)
			(xy 13.320244 -150.063454) (xy 13.327275 -150.087399) (xy 13.335032 -150.141348) (xy 13.335032 -150.195852)
			(xy 13.327275 -150.249801) (xy 13.31192 -150.302097) (xy 13.289278 -150.351676) (xy 13.259811 -150.397527)
			(xy 13.224119 -150.438719) (xy 13.182927 -150.474411) (xy 13.137076 -150.503878) (xy 13.087497 -150.52652)
			(xy 13.035201 -150.541875) (xy 12.981252 -150.549632) (xy 12.954 -150.550118) (xy 12.927686 -150.549645)
			(xy 12.875558 -150.54241) (xy 12.824916 -150.528092) (xy 12.776717 -150.506961) (xy 12.731873 -150.479416)
			(xy 12.691233 -150.445979) (xy 12.673076 -150.426928) (xy 12.665562 -150.419518) (xy 12.646276 -150.410997)
			(xy 12.635738 -150.410418) (xy 12.561062 -150.410418) (xy 12.550514 -150.410962) (xy 12.531218 -150.419486)
			(xy 12.523724 -150.426928) (xy 12.503904 -150.447716) (xy 12.459132 -150.483691) (xy 12.409474 -150.512551)
			(xy 12.356052 -150.533644) (xy 12.300073 -150.546493) (xy 12.2428 -150.550808) (xy 12.185527 -150.546493)
			(xy 12.129548 -150.533644) (xy 12.076126 -150.512551) (xy 12.026468 -150.483691) (xy 11.981696 -150.447716)
			(xy 11.961876 -150.426928) (xy 11.954362 -150.419518) (xy 11.935076 -150.410997) (xy 11.924538 -150.410418)
			(xy 11.849862 -150.410418) (xy 11.839314 -150.410962) (xy 11.820018 -150.419486) (xy 11.812524 -150.426928)
			(xy 11.794355 -150.44597) (xy 11.753728 -150.479428) (xy 11.70889 -150.506988) (xy 11.660692 -150.528128)
			(xy 11.610047 -150.542449) (xy 11.557915 -150.549677) (xy 11.5316 -150.550118) (xy 11.50435 -150.549612)
			(xy 11.450403 -150.541855) (xy 11.39811 -150.526501) (xy 11.348534 -150.50386) (xy 11.302685 -150.474395)
			(xy 11.261496 -150.438704) (xy 11.225805 -150.397515) (xy 11.19634 -150.351666) (xy 11.173699 -150.30209)
			(xy 11.158345 -150.249797) (xy 11.150588 -150.19585) (xy 4.38404 -150.19585) (xy 4.38404 -151.67102)
			(xy 15.793718 -151.67102) (xy 15.797789 -151.615398) (xy 15.809915 -151.560961) (xy 15.829838 -151.50887)
			(xy 15.857134 -151.460235) (xy 15.89122 -151.416092) (xy 15.931369 -151.377383) (xy 15.976727 -151.344932)
			(xy 16.026327 -151.319431) (xy 16.079111 -151.301424) (xy 16.133954 -151.291294) (xy 16.189688 -151.289257)
			(xy 16.245125 -151.295357) (xy 16.299082 -151.309463) (xy 16.350411 -151.331275) (xy 16.398017 -151.360329)
			(xy 16.440885 -151.396004) (xy 16.478102 -151.437541) (xy 16.508875 -151.484054) (xy 16.532547 -151.534551)
			(xy 16.548615 -151.587958) (xy 16.556735 -151.643134) (xy 16.557244 -151.67102) (xy 16.556771 -151.696928)
			(xy 16.809718 -151.696928) (xy 16.813789 -151.641306) (xy 16.825915 -151.586869) (xy 16.845838 -151.534778)
			(xy 16.873134 -151.486143) (xy 16.90722 -151.442) (xy 16.947369 -151.403291) (xy 16.992727 -151.37084)
			(xy 17.042327 -151.345339) (xy 17.095111 -151.327332) (xy 17.149954 -151.317202) (xy 17.205688 -151.315165)
			(xy 17.261125 -151.321265) (xy 17.315082 -151.335371) (xy 17.366411 -151.357183) (xy 17.414017 -151.386237)
			(xy 17.438493 -151.406606) (xy 18.036792 -151.406606) (xy 18.040863 -151.350984) (xy 18.052989 -151.296547)
			(xy 18.072912 -151.244456) (xy 18.100208 -151.195821) (xy 18.134294 -151.151678) (xy 18.174443 -151.112969)
			(xy 18.219801 -151.080518) (xy 18.269401 -151.055017) (xy 18.322185 -151.03701) (xy 18.377028 -151.02688)
			(xy 18.432762 -151.024843) (xy 18.488199 -151.030943) (xy 18.542156 -151.045049) (xy 18.593485 -151.066861)
			(xy 18.641091 -151.095915) (xy 18.683959 -151.13159) (xy 18.721176 -151.173127) (xy 18.751949 -151.21964)
			(xy 18.775621 -151.270137) (xy 18.791689 -151.323544) (xy 18.799809 -151.37872) (xy 18.800318 -151.406606)
			(xy 18.799809 -151.434492) (xy 18.791689 -151.489668) (xy 18.775621 -151.543075) (xy 18.757079 -151.582628)
			(xy 19.362418 -151.582628) (xy 19.366489 -151.527006) (xy 19.378615 -151.472569) (xy 19.398538 -151.420478)
			(xy 19.425834 -151.371843) (xy 19.45992 -151.3277) (xy 19.500069 -151.288991) (xy 19.545427 -151.25654)
			(xy 19.595027 -151.231039) (xy 19.647811 -151.213032) (xy 19.702654 -151.202902) (xy 19.758388 -151.200865)
			(xy 19.813825 -151.206965) (xy 19.867782 -151.221071) (xy 19.919111 -151.242883) (xy 19.966717 -151.271937)
			(xy 20.009585 -151.307612) (xy 20.046802 -151.349149) (xy 20.077575 -151.395662) (xy 20.101247 -151.446159)
			(xy 20.117315 -151.499566) (xy 20.125435 -151.554742) (xy 20.125698 -151.569166) (xy 20.873718 -151.569166)
			(xy 20.877789 -151.513544) (xy 20.889915 -151.459107) (xy 20.909838 -151.407016) (xy 20.937134 -151.358381)
			(xy 20.97122 -151.314238) (xy 21.011369 -151.275529) (xy 21.056727 -151.243078) (xy 21.106327 -151.217577)
			(xy 21.159111 -151.19957) (xy 21.213954 -151.18944) (xy 21.269688 -151.187403) (xy 21.325125 -151.193503)
			(xy 21.379082 -151.207609) (xy 21.430411 -151.229421) (xy 21.478017 -151.258475) (xy 21.520885 -151.29415)
			(xy 21.558102 -151.335687) (xy 21.588875 -151.3822) (xy 21.612547 -151.432697) (xy 21.628615 -151.486104)
			(xy 21.636735 -151.54128) (xy 21.637244 -151.569166) (xy 21.636735 -151.597052) (xy 21.628615 -151.652228)
			(xy 21.612547 -151.705635) (xy 21.588875 -151.756132) (xy 21.558102 -151.802645) (xy 21.520885 -151.844182)
			(xy 21.478017 -151.879857) (xy 21.430411 -151.908911) (xy 21.379082 -151.930723) (xy 21.325125 -151.944829)
			(xy 21.269688 -151.950929) (xy 21.213954 -151.948892) (xy 21.159111 -151.938762) (xy 21.106327 -151.920755)
			(xy 21.056727 -151.895254) (xy 21.011369 -151.862803) (xy 20.97122 -151.824094) (xy 20.937134 -151.779951)
			(xy 20.909838 -151.731316) (xy 20.889915 -151.679225) (xy 20.877789 -151.624788) (xy 20.873718 -151.569166)
			(xy 20.125698 -151.569166) (xy 20.125944 -151.582628) (xy 20.125435 -151.610514) (xy 20.117315 -151.66569)
			(xy 20.101247 -151.719097) (xy 20.077575 -151.769594) (xy 20.046802 -151.816107) (xy 20.009585 -151.857644)
			(xy 19.966717 -151.893319) (xy 19.919111 -151.922373) (xy 19.867782 -151.944185) (xy 19.813825 -151.958291)
			(xy 19.758388 -151.964391) (xy 19.702654 -151.962354) (xy 19.647811 -151.952224) (xy 19.595027 -151.934217)
			(xy 19.545427 -151.908716) (xy 19.500069 -151.876265) (xy 19.45992 -151.837556) (xy 19.425834 -151.793413)
			(xy 19.398538 -151.744778) (xy 19.378615 -151.692687) (xy 19.366489 -151.63825) (xy 19.362418 -151.582628)
			(xy 18.757079 -151.582628) (xy 18.751949 -151.593572) (xy 18.721176 -151.640085) (xy 18.683959 -151.681622)
			(xy 18.641091 -151.717297) (xy 18.593485 -151.746351) (xy 18.542156 -151.768163) (xy 18.488199 -151.782269)
			(xy 18.432762 -151.788369) (xy 18.377028 -151.786332) (xy 18.322185 -151.776202) (xy 18.269401 -151.758195)
			(xy 18.219801 -151.732694) (xy 18.174443 -151.700243) (xy 18.134294 -151.661534) (xy 18.100208 -151.617391)
			(xy 18.072912 -151.568756) (xy 18.052989 -151.516665) (xy 18.040863 -151.462228) (xy 18.036792 -151.406606)
			(xy 17.438493 -151.406606) (xy 17.456885 -151.421912) (xy 17.494102 -151.463449) (xy 17.524875 -151.509962)
			(xy 17.548547 -151.560459) (xy 17.564615 -151.613866) (xy 17.572735 -151.669042) (xy 17.573244 -151.696928)
			(xy 17.572735 -151.724814) (xy 17.564615 -151.77999) (xy 17.548547 -151.833397) (xy 17.524875 -151.883894)
			(xy 17.494102 -151.930407) (xy 17.456885 -151.971944) (xy 17.414017 -152.007619) (xy 17.366411 -152.036673)
			(xy 17.315082 -152.058485) (xy 17.261125 -152.072591) (xy 17.205688 -152.078691) (xy 17.149954 -152.076654)
			(xy 17.095111 -152.066524) (xy 17.042327 -152.048517) (xy 16.992727 -152.023016) (xy 16.947369 -151.990565)
			(xy 16.90722 -151.951856) (xy 16.873134 -151.907713) (xy 16.845838 -151.859078) (xy 16.825915 -151.806987)
			(xy 16.813789 -151.75255) (xy 16.809718 -151.696928) (xy 16.556771 -151.696928) (xy 16.556735 -151.698906)
			(xy 16.548615 -151.754082) (xy 16.532547 -151.807489) (xy 16.508875 -151.857986) (xy 16.478102 -151.904499)
			(xy 16.440885 -151.946036) (xy 16.398017 -151.981711) (xy 16.350411 -152.010765) (xy 16.299082 -152.032577)
			(xy 16.245125 -152.046683) (xy 16.189688 -152.052783) (xy 16.133954 -152.050746) (xy 16.079111 -152.040616)
			(xy 16.026327 -152.022609) (xy 15.976727 -151.997108) (xy 15.931369 -151.964657) (xy 15.89122 -151.925948)
			(xy 15.857134 -151.881805) (xy 15.829838 -151.83317) (xy 15.809915 -151.781079) (xy 15.797789 -151.726642)
			(xy 15.793718 -151.67102) (xy 4.38404 -151.67102) (xy 4.38404 -153.782522) (xy 14.777718 -153.782522)
			(xy 14.781789 -153.7269) (xy 14.793915 -153.672463) (xy 14.813838 -153.620372) (xy 14.841134 -153.571737)
			(xy 14.87522 -153.527594) (xy 14.915369 -153.488885) (xy 14.960727 -153.456434) (xy 15.010327 -153.430933)
			(xy 15.063111 -153.412926) (xy 15.117954 -153.402796) (xy 15.173688 -153.400759) (xy 15.229125 -153.406859)
			(xy 15.283082 -153.420965) (xy 15.334411 -153.442777) (xy 15.382017 -153.471831) (xy 15.424885 -153.507506)
			(xy 15.462102 -153.549043) (xy 15.492875 -153.595556) (xy 15.516547 -153.646053) (xy 15.532615 -153.69946)
			(xy 15.540735 -153.754636) (xy 15.541244 -153.782522) (xy 15.793718 -153.782522) (xy 15.797789 -153.7269)
			(xy 15.809915 -153.672463) (xy 15.829838 -153.620372) (xy 15.857134 -153.571737) (xy 15.89122 -153.527594)
			(xy 15.931369 -153.488885) (xy 15.976727 -153.456434) (xy 16.026327 -153.430933) (xy 16.079111 -153.412926)
			(xy 16.133954 -153.402796) (xy 16.189688 -153.400759) (xy 16.245125 -153.406859) (xy 16.299082 -153.420965)
			(xy 16.350411 -153.442777) (xy 16.398017 -153.471831) (xy 16.440885 -153.507506) (xy 16.478102 -153.549043)
			(xy 16.508875 -153.595556) (xy 16.532547 -153.646053) (xy 16.548615 -153.69946) (xy 16.556735 -153.754636)
			(xy 16.557244 -153.782522) (xy 16.556735 -153.810408) (xy 16.553587 -153.831798) (xy 16.809718 -153.831798)
			(xy 16.813789 -153.776176) (xy 16.825915 -153.721739) (xy 16.845838 -153.669648) (xy 16.873134 -153.621013)
			(xy 16.90722 -153.57687) (xy 16.947369 -153.538161) (xy 16.992727 -153.50571) (xy 17.042327 -153.480209)
			(xy 17.095111 -153.462202) (xy 17.149954 -153.452072) (xy 17.205688 -153.450035) (xy 17.261125 -153.456135)
			(xy 17.315082 -153.470241) (xy 17.366411 -153.492053) (xy 17.414017 -153.521107) (xy 17.456885 -153.556782)
			(xy 17.494102 -153.598319) (xy 17.524875 -153.644832) (xy 17.548547 -153.695329) (xy 17.564615 -153.748736)
			(xy 17.569587 -153.782522) (xy 19.857718 -153.782522) (xy 19.861789 -153.7269) (xy 19.873915 -153.672463)
			(xy 19.893838 -153.620372) (xy 19.921134 -153.571737) (xy 19.95522 -153.527594) (xy 19.995369 -153.488885)
			(xy 20.040727 -153.456434) (xy 20.090327 -153.430933) (xy 20.143111 -153.412926) (xy 20.197954 -153.402796)
			(xy 20.253688 -153.400759) (xy 20.309125 -153.406859) (xy 20.363082 -153.420965) (xy 20.414411 -153.442777)
			(xy 20.462017 -153.471831) (xy 20.504885 -153.507506) (xy 20.542102 -153.549043) (xy 20.572875 -153.595556)
			(xy 20.596547 -153.646053) (xy 20.612615 -153.69946) (xy 20.620735 -153.754636) (xy 20.621244 -153.782522)
			(xy 21.889718 -153.782522) (xy 21.893789 -153.7269) (xy 21.905915 -153.672463) (xy 21.925838 -153.620372)
			(xy 21.953134 -153.571737) (xy 21.98722 -153.527594) (xy 22.027369 -153.488885) (xy 22.072727 -153.456434)
			(xy 22.122327 -153.430933) (xy 22.175111 -153.412926) (xy 22.229954 -153.402796) (xy 22.285688 -153.400759)
			(xy 22.341125 -153.406859) (xy 22.395082 -153.420965) (xy 22.446411 -153.442777) (xy 22.494017 -153.471831)
			(xy 22.536885 -153.507506) (xy 22.574102 -153.549043) (xy 22.604875 -153.595556) (xy 22.628547 -153.646053)
			(xy 22.644615 -153.69946) (xy 22.652735 -153.754636) (xy 22.653244 -153.782522) (xy 22.652735 -153.810408)
			(xy 22.644615 -153.865584) (xy 22.628547 -153.918991) (xy 22.604875 -153.969488) (xy 22.574102 -154.016001)
			(xy 22.536885 -154.057538) (xy 22.494017 -154.093213) (xy 22.446411 -154.122267) (xy 22.395082 -154.144079)
			(xy 22.341125 -154.158185) (xy 22.285688 -154.164285) (xy 22.229954 -154.162248) (xy 22.175111 -154.152118)
			(xy 22.122327 -154.134111) (xy 22.072727 -154.10861) (xy 22.027369 -154.076159) (xy 21.98722 -154.03745)
			(xy 21.953134 -153.993307) (xy 21.925838 -153.944672) (xy 21.905915 -153.892581) (xy 21.893789 -153.838144)
			(xy 21.889718 -153.782522) (xy 20.621244 -153.782522) (xy 20.620735 -153.810408) (xy 20.612615 -153.865584)
			(xy 20.596547 -153.918991) (xy 20.572875 -153.969488) (xy 20.542102 -154.016001) (xy 20.504885 -154.057538)
			(xy 20.462017 -154.093213) (xy 20.414411 -154.122267) (xy 20.363082 -154.144079) (xy 20.309125 -154.158185)
			(xy 20.253688 -154.164285) (xy 20.197954 -154.162248) (xy 20.143111 -154.152118) (xy 20.090327 -154.134111)
			(xy 20.040727 -154.10861) (xy 19.995369 -154.076159) (xy 19.95522 -154.03745) (xy 19.921134 -153.993307)
			(xy 19.893838 -153.944672) (xy 19.873915 -153.892581) (xy 19.861789 -153.838144) (xy 19.857718 -153.782522)
			(xy 17.569587 -153.782522) (xy 17.572735 -153.803912) (xy 17.573244 -153.831798) (xy 17.572735 -153.859684)
			(xy 17.564615 -153.91486) (xy 17.548547 -153.968267) (xy 17.524875 -154.018764) (xy 17.494102 -154.065277)
			(xy 17.456885 -154.106814) (xy 17.414017 -154.142489) (xy 17.366411 -154.171543) (xy 17.315082 -154.193355)
			(xy 17.261125 -154.207461) (xy 17.205688 -154.213561) (xy 17.149954 -154.211524) (xy 17.095111 -154.201394)
			(xy 17.042327 -154.183387) (xy 16.992727 -154.157886) (xy 16.947369 -154.125435) (xy 16.90722 -154.086726)
			(xy 16.873134 -154.042583) (xy 16.845838 -153.993948) (xy 16.825915 -153.941857) (xy 16.813789 -153.88742)
			(xy 16.809718 -153.831798) (xy 16.553587 -153.831798) (xy 16.548615 -153.865584) (xy 16.532547 -153.918991)
			(xy 16.508875 -153.969488) (xy 16.478102 -154.016001) (xy 16.440885 -154.057538) (xy 16.398017 -154.093213)
			(xy 16.350411 -154.122267) (xy 16.299082 -154.144079) (xy 16.245125 -154.158185) (xy 16.189688 -154.164285)
			(xy 16.133954 -154.162248) (xy 16.079111 -154.152118) (xy 16.026327 -154.134111) (xy 15.976727 -154.10861)
			(xy 15.931369 -154.076159) (xy 15.89122 -154.03745) (xy 15.857134 -153.993307) (xy 15.829838 -153.944672)
			(xy 15.809915 -153.892581) (xy 15.797789 -153.838144) (xy 15.793718 -153.782522) (xy 15.541244 -153.782522)
			(xy 15.540735 -153.810408) (xy 15.532615 -153.865584) (xy 15.516547 -153.918991) (xy 15.492875 -153.969488)
			(xy 15.462102 -154.016001) (xy 15.424885 -154.057538) (xy 15.382017 -154.093213) (xy 15.334411 -154.122267)
			(xy 15.283082 -154.144079) (xy 15.229125 -154.158185) (xy 15.173688 -154.164285) (xy 15.117954 -154.162248)
			(xy 15.063111 -154.152118) (xy 15.010327 -154.134111) (xy 14.960727 -154.10861) (xy 14.915369 -154.076159)
			(xy 14.87522 -154.03745) (xy 14.841134 -153.993307) (xy 14.813838 -153.944672) (xy 14.793915 -153.892581)
			(xy 14.781789 -153.838144) (xy 14.777718 -153.782522) (xy 4.38404 -153.782522) (xy 4.38404 -155.212034)
			(xy 7.269224 -155.212034) (xy 7.273295 -155.156412) (xy 7.285421 -155.101975) (xy 7.305344 -155.049884)
			(xy 7.33264 -155.001249) (xy 7.366726 -154.957106) (xy 7.406875 -154.918397) (xy 7.452233 -154.885946)
			(xy 7.501833 -154.860445) (xy 7.554617 -154.842438) (xy 7.60946 -154.832308) (xy 7.665194 -154.830271)
			(xy 7.720631 -154.836371) (xy 7.774588 -154.850477) (xy 7.825917 -154.872289) (xy 7.873523 -154.901343)
			(xy 7.916391 -154.937018) (xy 7.953608 -154.978555) (xy 7.984381 -155.025068) (xy 8.008053 -155.075565)
			(xy 8.009144 -155.079192) (xy 9.86993 -155.079192) (xy 9.874001 -155.02357) (xy 9.886127 -154.969133)
			(xy 9.90605 -154.917042) (xy 9.933346 -154.868407) (xy 9.967432 -154.824264) (xy 10.007581 -154.785555)
			(xy 10.052939 -154.753104) (xy 10.102539 -154.727603) (xy 10.155323 -154.709596) (xy 10.210166 -154.699466)
			(xy 10.2659 -154.697429) (xy 10.321337 -154.703529) (xy 10.375294 -154.717635) (xy 10.426623 -154.739447)
			(xy 10.474229 -154.768501) (xy 10.517097 -154.804176) (xy 10.554314 -154.845713) (xy 10.585087 -154.892226)
			(xy 10.608759 -154.942723) (xy 10.624827 -154.99613) (xy 10.632947 -155.051306) (xy 10.633456 -155.079192)
			(xy 10.633391 -155.082748) (xy 11.19378 -155.082748) (xy 11.194219 -155.056433) (xy 11.201461 -155.004304)
			(xy 11.215786 -154.953661) (xy 11.236924 -154.905462) (xy 11.264474 -154.860619) (xy 11.297917 -154.81998)
			(xy 11.31697 -154.801824) (xy 11.324359 -154.794291) (xy 11.332892 -154.77502) (xy 11.33348 -154.764486)
			(xy 11.33348 -154.68981) (xy 11.332965 -154.679259) (xy 11.32442 -154.659963) (xy 11.31697 -154.652472)
			(xy 11.297902 -154.634329) (xy 11.264447 -154.593696) (xy 11.236891 -154.548853) (xy 11.215755 -154.50065)
			(xy 11.20144 -154.45) (xy 11.194217 -154.397865) (xy 11.19378 -154.371548) (xy 11.1943 -154.344297)
			(xy 11.20205 -154.290349) (xy 11.217399 -154.238053) (xy 11.240035 -154.188473) (xy 11.269497 -154.142621)
			(xy 11.305185 -154.101428) (xy 11.346372 -154.065733) (xy 11.392221 -154.036264) (xy 11.441796 -154.01362)
			(xy 11.49409 -153.998263) (xy 11.548037 -153.990504) (xy 11.575288 -153.99004) (xy 11.601602 -153.990503)
			(xy 11.653731 -153.997737) (xy 11.704375 -154.012056) (xy 11.752574 -154.033189) (xy 11.797417 -154.060737)
			(xy 11.838056 -154.094177) (xy 11.856212 -154.11323) (xy 11.863737 -154.120629) (xy 11.883014 -154.129157)
			(xy 11.89355 -154.12974) (xy 11.968226 -154.12974) (xy 11.978771 -154.129173) (xy 11.998066 -154.120663)
			(xy 12.005564 -154.11323) (xy 12.025384 -154.092442) (xy 12.070156 -154.056467) (xy 12.119814 -154.027607)
			(xy 12.173236 -154.006514) (xy 12.229215 -153.993665) (xy 12.286488 -153.98935) (xy 12.343761 -153.993665)
			(xy 12.39974 -154.006514) (xy 12.453162 -154.027607) (xy 12.50282 -154.056467) (xy 12.547592 -154.092442)
			(xy 12.567412 -154.11323) (xy 12.574937 -154.120629) (xy 12.594214 -154.129157) (xy 12.60475 -154.12974)
			(xy 12.679426 -154.12974) (xy 12.689971 -154.129173) (xy 12.709266 -154.120663) (xy 12.716764 -154.11323)
			(xy 12.736584 -154.092442) (xy 12.781356 -154.056467) (xy 12.831014 -154.027607) (xy 12.884436 -154.006514)
			(xy 12.940415 -153.993665) (xy 12.997688 -153.98935) (xy 13.054961 -153.993665) (xy 13.11094 -154.006514)
			(xy 13.164362 -154.027607) (xy 13.21402 -154.056467) (xy 13.258792 -154.092442) (xy 13.278612 -154.11323)
			(xy 13.286137 -154.120629) (xy 13.305414 -154.129157) (xy 13.31595 -154.12974) (xy 13.390626 -154.12974)
			(xy 13.401171 -154.129173) (xy 13.420466 -154.120663) (xy 13.427964 -154.11323) (xy 13.446101 -154.094156)
			(xy 13.486734 -154.060699) (xy 13.531578 -154.033142) (xy 13.579783 -154.012007) (xy 13.630434 -153.997694)
			(xy 13.682571 -153.990475) (xy 13.708888 -153.99004) (xy 13.736143 -153.990467) (xy 13.790097 -153.998223)
			(xy 13.842399 -154.01358) (xy 13.891982 -154.036225) (xy 13.937838 -154.065696) (xy 13.979032 -154.101394)
			(xy 14.014726 -154.142591) (xy 14.044193 -154.188449) (xy 14.066832 -154.238035) (xy 14.082184 -154.290338)
			(xy 14.089936 -154.344293) (xy 14.090396 -154.371548) (xy 14.089962 -154.397863) (xy 14.08272 -154.449993)
			(xy 14.068395 -154.500637) (xy 14.047256 -154.548835) (xy 14.019704 -154.593678) (xy 13.98626 -154.634316)
			(xy 13.967206 -154.652472) (xy 13.959816 -154.660003) (xy 13.951285 -154.679276) (xy 13.950696 -154.68981)
			(xy 13.950696 -154.764486) (xy 13.951221 -154.775036) (xy 13.959759 -154.794331) (xy 13.967206 -154.801824)
			(xy 13.986267 -154.819974) (xy 14.019724 -154.860605) (xy 14.047282 -154.905446) (xy 14.068419 -154.953648)
			(xy 14.082735 -155.004297) (xy 14.089958 -155.056432) (xy 14.090396 -155.082748) (xy 14.089967 -155.110001)
			(xy 14.082203 -155.163951) (xy 14.066842 -155.216248) (xy 14.044194 -155.265826) (xy 14.014722 -155.311677)
			(xy 13.979024 -155.352867) (xy 13.937829 -155.388558) (xy 13.891973 -155.418023) (xy 13.842392 -155.440663)
			(xy 13.790093 -155.456016) (xy 13.736141 -155.463771) (xy 13.708888 -155.464256) (xy 13.682573 -155.463811)
			(xy 13.630443 -155.456573) (xy 13.579799 -155.442251) (xy 13.5316 -155.421114) (xy 13.486757 -155.393564)
			(xy 13.446119 -155.36012) (xy 13.427964 -155.341066) (xy 13.420449 -155.333656) (xy 13.401164 -155.325134)
			(xy 13.390626 -155.324556) (xy 13.31595 -155.324556) (xy 13.305404 -155.325112) (xy 13.286109 -155.33363)
			(xy 13.278612 -155.341066) (xy 13.258792 -155.361854) (xy 13.21402 -155.397829) (xy 13.164362 -155.426689)
			(xy 13.11094 -155.447782) (xy 13.054961 -155.460631) (xy 12.997688 -155.464946) (xy 12.940415 -155.460631)
			(xy 12.884436 -155.447782) (xy 12.831014 -155.426689) (xy 12.781356 -155.397829) (xy 12.736584 -155.361854)
			(xy 12.716764 -155.341066) (xy 12.709249 -155.333656) (xy 12.689964 -155.325134) (xy 12.679426 -155.324556)
			(xy 12.60475 -155.324556) (xy 12.594204 -155.325112) (xy 12.574909 -155.33363) (xy 12.567412 -155.341066)
			(xy 12.547592 -155.361854) (xy 12.50282 -155.397829) (xy 12.453162 -155.426689) (xy 12.39974 -155.447782)
			(xy 12.343761 -155.460631) (xy 12.286488 -155.464946) (xy 12.229215 -155.460631) (xy 12.173236 -155.447782)
			(xy 12.119814 -155.426689) (xy 12.070156 -155.397829) (xy 12.025384 -155.361854) (xy 12.005564 -155.341066)
			(xy 11.998049 -155.333656) (xy 11.978764 -155.325134) (xy 11.968226 -155.324556) (xy 11.89355 -155.324556)
			(xy 11.883004 -155.325112) (xy 11.863709 -155.33363) (xy 11.856212 -155.341066) (xy 11.838057 -155.360121)
			(xy 11.797425 -155.393576) (xy 11.752585 -155.421133) (xy 11.704384 -155.442271) (xy 11.653737 -155.456589)
			(xy 11.601604 -155.463816) (xy 11.575288 -155.464256) (xy 11.548037 -155.463774) (xy 11.494089 -155.456017)
			(xy 11.441794 -155.440662) (xy 11.392216 -155.41802) (xy 11.346366 -155.388554) (xy 11.305176 -155.352862)
			(xy 11.269484 -155.311671) (xy 11.240018 -155.26582) (xy 11.217377 -155.216243) (xy 11.202022 -155.163947)
			(xy 11.194266 -155.109999) (xy 11.19378 -155.082748) (xy 10.633391 -155.082748) (xy 10.632947 -155.107078)
			(xy 10.624827 -155.162254) (xy 10.608759 -155.215661) (xy 10.585087 -155.266158) (xy 10.554314 -155.312671)
			(xy 10.517097 -155.354208) (xy 10.474229 -155.389883) (xy 10.426623 -155.418937) (xy 10.375294 -155.440749)
			(xy 10.321337 -155.454855) (xy 10.2659 -155.460955) (xy 10.210166 -155.458918) (xy 10.155323 -155.448788)
			(xy 10.102539 -155.430781) (xy 10.052939 -155.40528) (xy 10.007581 -155.372829) (xy 9.967432 -155.33412)
			(xy 9.933346 -155.289977) (xy 9.90605 -155.241342) (xy 9.886127 -155.189251) (xy 9.874001 -155.134814)
			(xy 9.86993 -155.079192) (xy 8.009144 -155.079192) (xy 8.024121 -155.128972) (xy 8.032241 -155.184148)
			(xy 8.03275 -155.212034) (xy 8.032241 -155.23992) (xy 8.024121 -155.295096) (xy 8.008053 -155.348503)
			(xy 7.984381 -155.399) (xy 7.953608 -155.445513) (xy 7.916391 -155.48705) (xy 7.873523 -155.522725)
			(xy 7.825917 -155.551779) (xy 7.774588 -155.573591) (xy 7.720631 -155.587697) (xy 7.665194 -155.593797)
			(xy 7.60946 -155.59176) (xy 7.554617 -155.58163) (xy 7.501833 -155.563623) (xy 7.452233 -155.538122)
			(xy 7.406875 -155.505671) (xy 7.366726 -155.466962) (xy 7.33264 -155.422819) (xy 7.305344 -155.374184)
			(xy 7.285421 -155.322093) (xy 7.273295 -155.267656) (xy 7.269224 -155.212034) (xy 4.38404 -155.212034)
			(xy 4.38404 -156.69387) (xy 8.887458 -156.69387) (xy 8.891529 -156.638248) (xy 8.903655 -156.583811)
			(xy 8.923578 -156.53172) (xy 8.950874 -156.483085) (xy 8.98496 -156.438942) (xy 9.025109 -156.400233)
			(xy 9.070467 -156.367782) (xy 9.120067 -156.342281) (xy 9.172851 -156.324274) (xy 9.227694 -156.314144)
			(xy 9.283428 -156.312107) (xy 9.338865 -156.318207) (xy 9.392822 -156.332313) (xy 9.444151 -156.354125)
			(xy 9.491757 -156.383179) (xy 9.534625 -156.418854) (xy 9.571842 -156.460391) (xy 9.602615 -156.506904)
			(xy 9.626287 -156.557401) (xy 9.642355 -156.610808) (xy 9.650475 -156.665984) (xy 9.650984 -156.69387)
			(xy 9.650475 -156.721756) (xy 9.642355 -156.776932) (xy 9.626287 -156.830339) (xy 9.602615 -156.880836)
			(xy 9.571842 -156.927349) (xy 9.534625 -156.968886) (xy 9.491757 -157.004561) (xy 9.444151 -157.033615)
			(xy 9.392822 -157.055427) (xy 9.338865 -157.069533) (xy 9.283428 -157.075633) (xy 9.227694 -157.073596)
			(xy 9.172851 -157.063466) (xy 9.120067 -157.045459) (xy 9.070467 -157.019958) (xy 9.025109 -156.987507)
			(xy 8.98496 -156.948798) (xy 8.950874 -156.904655) (xy 8.923578 -156.85602) (xy 8.903655 -156.803929)
			(xy 8.891529 -156.749492) (xy 8.887458 -156.69387) (xy 4.38404 -156.69387) (xy 4.38404 -157.812994)
			(xy 6.650226 -157.812994) (xy 6.654297 -157.757372) (xy 6.666423 -157.702935) (xy 6.686346 -157.650844)
			(xy 6.713642 -157.602209) (xy 6.747728 -157.558066) (xy 6.787877 -157.519357) (xy 6.833235 -157.486906)
			(xy 6.882835 -157.461405) (xy 6.935619 -157.443398) (xy 6.990462 -157.433268) (xy 7.046196 -157.431231)
			(xy 7.101633 -157.437331) (xy 7.15559 -157.451437) (xy 7.206919 -157.473249) (xy 7.254525 -157.502303)
			(xy 7.297393 -157.537978) (xy 7.33461 -157.579515) (xy 7.365383 -157.626028) (xy 7.375633 -157.647894)
			(xy 11.013948 -157.647894) (xy 11.014459 -157.62125) (xy 11.022984 -157.568649) (xy 11.039844 -157.518099)
			(xy 11.064602 -157.470913) (xy 11.096615 -157.428313) (xy 11.135053 -157.391407) (xy 11.156696 -157.37586)
			(xy 11.167989 -157.367504) (xy 11.185848 -157.34583) (xy 11.197132 -157.320114) (xy 11.20099 -157.292297)
			(xy 11.19713 -157.26448) (xy 11.185844 -157.238764) (xy 11.167984 -157.217092) (xy 11.156696 -157.208728)
			(xy 11.135107 -157.193114) (xy 11.096689 -157.156206) (xy 11.064685 -157.113615) (xy 11.039924 -157.066445)
			(xy 11.023047 -157.015914) (xy 11.014491 -156.963331) (xy 11.013948 -156.936694) (xy 11.014458 -156.910707)
			(xy 11.022588 -156.859372) (xy 11.038649 -156.809942) (xy 11.062245 -156.763632) (xy 11.092795 -156.721584)
			(xy 11.129546 -156.684833) (xy 11.171594 -156.654283) (xy 11.217904 -156.630687) (xy 11.267334 -156.614626)
			(xy 11.318669 -156.606496) (xy 11.370643 -156.606496) (xy 11.421978 -156.614626) (xy 11.471408 -156.630687)
			(xy 11.517718 -156.654283) (xy 11.559766 -156.684833) (xy 11.596517 -156.721584) (xy 11.627067 -156.763632)
			(xy 11.650663 -156.809942) (xy 11.666724 -156.859372) (xy 11.674854 -156.910707) (xy 11.675364 -156.936694)
			(xy 11.674839 -156.963337) (xy 11.666316 -157.015937) (xy 11.649459 -157.066487) (xy 11.624703 -157.113673)
			(xy 11.592693 -157.156273) (xy 11.554258 -157.193181) (xy 11.532616 -157.208728) (xy 11.521334 -157.217098)
			(xy 11.503473 -157.238768) (xy 11.492187 -157.264482) (xy 11.488327 -157.292297) (xy 11.492185 -157.320112)
			(xy 11.50347 -157.345826) (xy 11.521328 -157.367497) (xy 11.532616 -157.37586) (xy 11.554202 -157.391478)
			(xy 11.59262 -157.428386) (xy 11.624623 -157.470975) (xy 11.649384 -157.518145) (xy 11.666262 -157.568675)
			(xy 11.674821 -157.621257) (xy 11.675364 -157.647894) (xy 11.91387 -157.647894) (xy 11.914371 -157.62125)
			(xy 11.922897 -157.568648) (xy 11.939758 -157.518097) (xy 11.964518 -157.47091) (xy 11.996533 -157.428311)
			(xy 12.034973 -157.391406) (xy 12.056618 -157.37586) (xy 12.067909 -157.367503) (xy 12.085764 -157.345828)
			(xy 12.097046 -157.320112) (xy 12.100903 -157.292297) (xy 12.097044 -157.264481) (xy 12.08576 -157.238766)
			(xy 12.067904 -157.217092) (xy 12.056618 -157.208728) (xy 12.035012 -157.193137) (xy 11.996598 -157.156222)
			(xy 11.964599 -157.113625) (xy 11.939842 -157.066451) (xy 11.922968 -157.015917) (xy 11.914412 -156.963332)
			(xy 11.91387 -156.936694) (xy 11.91438 -156.910707) (xy 11.92251 -156.859372) (xy 11.938571 -156.809942)
			(xy 11.962167 -156.763632) (xy 11.992717 -156.721584) (xy 12.029468 -156.684833) (xy 12.071516 -156.654283)
			(xy 12.117826 -156.630687) (xy 12.167256 -156.614626) (xy 12.218591 -156.606496) (xy 12.270565 -156.606496)
			(xy 12.3219 -156.614626) (xy 12.37133 -156.630687) (xy 12.41764 -156.654283) (xy 12.459688 -156.684833)
			(xy 12.496439 -156.721584) (xy 12.526989 -156.763632) (xy 12.550585 -156.809942) (xy 12.566646 -156.859372)
			(xy 12.574776 -156.910707) (xy 12.575286 -156.936694) (xy 12.574752 -156.963337) (xy 12.56623 -157.015936)
			(xy 12.549373 -157.066485) (xy 12.52462 -157.113671) (xy 12.492611 -157.156271) (xy 12.454179 -157.19318)
			(xy 12.432538 -157.208728) (xy 12.421262 -157.217102) (xy 12.403416 -157.238776) (xy 12.392139 -157.264487)
			(xy 12.388282 -157.292297) (xy 12.392137 -157.320106) (xy 12.403412 -157.345818) (xy 12.421257 -157.367493)
			(xy 12.432538 -157.37586) (xy 12.454129 -157.391471) (xy 12.492545 -157.428381) (xy 12.524548 -157.470973)
			(xy 12.549308 -157.518144) (xy 12.566185 -157.568674) (xy 12.574743 -157.621257) (xy 12.575286 -157.647894)
			(xy 12.813792 -157.647894) (xy 12.814327 -157.621251) (xy 12.82285 -157.568653) (xy 12.839707 -157.518105)
			(xy 12.864461 -157.470918) (xy 12.896468 -157.428318) (xy 12.9349 -157.391409) (xy 12.95654 -157.37586)
			(xy 12.967829 -157.367502) (xy 12.98568 -157.345826) (xy 12.996959 -157.320111) (xy 13.000815 -157.292297)
			(xy 12.996957 -157.264483) (xy 12.985677 -157.238768) (xy 12.967824 -157.217094) (xy 12.95654 -157.208728)
			(xy 12.934939 -157.193131) (xy 12.896524 -157.156217) (xy 12.864523 -157.113623) (xy 12.839765 -157.066449)
			(xy 12.82289 -157.015916) (xy 12.814334 -156.963332) (xy 12.813792 -156.936694) (xy 12.814302 -156.910707)
			(xy 12.822432 -156.859372) (xy 12.838493 -156.809942) (xy 12.862089 -156.763632) (xy 12.892639 -156.721584)
			(xy 12.92939 -156.684833) (xy 12.971438 -156.654283) (xy 13.017748 -156.630687) (xy 13.067178 -156.614626)
			(xy 13.118513 -156.606496) (xy 13.170487 -156.606496) (xy 13.221822 -156.614626) (xy 13.271252 -156.630687)
			(xy 13.317562 -156.654283) (xy 13.35961 -156.684833) (xy 13.396361 -156.721584) (xy 13.426911 -156.763632)
			(xy 13.450507 -156.809942) (xy 13.466568 -156.859372) (xy 13.474698 -156.910707) (xy 13.475208 -156.936694)
			(xy 13.474664 -156.963336) (xy 13.466143 -157.015935) (xy 13.449288 -157.066482) (xy 13.424536 -157.113669)
			(xy 13.39253 -157.156269) (xy 13.3541 -157.193179) (xy 13.33246 -157.208728) (xy 13.321182 -157.217101)
			(xy 13.303332 -157.238773) (xy 13.292052 -157.264485) (xy 13.288195 -157.292297) (xy 13.29205 -157.320108)
			(xy 13.303328 -157.345821) (xy 13.321177 -157.367494) (xy 13.33246 -157.37586) (xy 13.354056 -157.391465)
			(xy 13.392471 -157.428377) (xy 13.424472 -157.47097) (xy 13.449231 -157.518142) (xy 13.466107 -157.568673)
			(xy 13.474665 -157.621257) (xy 13.475208 -157.647894) (xy 13.713968 -157.647894) (xy 13.71447 -157.62125)
			(xy 13.722996 -157.568648) (xy 13.739857 -157.518098) (xy 13.764617 -157.470911) (xy 13.796632 -157.428312)
			(xy 13.835071 -157.391406) (xy 13.856716 -157.37586) (xy 13.868008 -157.367503) (xy 13.885863 -157.345828)
			(xy 13.897145 -157.320112) (xy 13.901002 -157.292297) (xy 13.897143 -157.264481) (xy 13.885859 -157.238766)
			(xy 13.868002 -157.217092) (xy 13.856716 -157.208728) (xy 13.83511 -157.193138) (xy 13.796696 -157.156222)
			(xy 13.764697 -157.113626) (xy 13.73994 -157.066451) (xy 13.723066 -157.015917) (xy 13.71451 -156.963332)
			(xy 13.713968 -156.936694) (xy 13.714478 -156.910707) (xy 13.722608 -156.859372) (xy 13.738669 -156.809942)
			(xy 13.762265 -156.763632) (xy 13.792815 -156.721584) (xy 13.829566 -156.684833) (xy 13.871614 -156.654283)
			(xy 13.917924 -156.630687) (xy 13.967354 -156.614626) (xy 14.018689 -156.606496) (xy 14.070663 -156.606496)
			(xy 14.121998 -156.614626) (xy 14.171428 -156.630687) (xy 14.217738 -156.654283) (xy 14.259786 -156.684833)
			(xy 14.296537 -156.721584) (xy 14.327087 -156.763632) (xy 14.350683 -156.809942) (xy 14.366744 -156.859372)
			(xy 14.374874 -156.910707) (xy 14.375384 -156.936694) (xy 14.374851 -156.963337) (xy 14.366328 -157.015936)
			(xy 14.349472 -157.066485) (xy 14.324718 -157.113671) (xy 14.29271 -157.156271) (xy 14.254277 -157.19318)
			(xy 14.232636 -157.208728) (xy 14.221352 -157.217097) (xy 14.203488 -157.238766) (xy 14.192199 -157.26448)
			(xy 14.188338 -157.292297) (xy 14.192197 -157.320113) (xy 14.203484 -157.345828) (xy 14.221347 -157.367498)
			(xy 14.232636 -157.37586) (xy 14.254226 -157.391472) (xy 14.292643 -157.428382) (xy 14.324645 -157.470973)
			(xy 14.349405 -157.518144) (xy 14.366283 -157.568674) (xy 14.374841 -157.621257) (xy 14.375343 -157.645862)
			(xy 15.329408 -157.645862) (xy 15.329848 -157.619547) (xy 15.337088 -157.567417) (xy 15.351412 -157.516774)
			(xy 15.37255 -157.468575) (xy 15.400101 -157.423732) (xy 15.433544 -157.383094) (xy 15.452598 -157.364938)
			(xy 15.459984 -157.357404) (xy 15.468517 -157.338133) (xy 15.469108 -157.3276) (xy 15.469108 -157.252924)
			(xy 15.468577 -157.242375) (xy 15.460043 -157.223079) (xy 15.452598 -157.215586) (xy 15.433542 -157.197431)
			(xy 15.400085 -157.156801) (xy 15.372526 -157.111961) (xy 15.351388 -157.06376) (xy 15.337071 -157.013112)
			(xy 15.329846 -156.960978) (xy 15.329408 -156.934662) (xy 15.329894 -156.907411) (xy 15.33765 -156.853463)
			(xy 15.353005 -156.801168) (xy 15.375647 -156.751591) (xy 15.405113 -156.705741) (xy 15.440804 -156.66455)
			(xy 15.481995 -156.628859) (xy 15.527845 -156.599393) (xy 15.577422 -156.576751) (xy 15.629717 -156.561396)
			(xy 15.683665 -156.55364) (xy 15.738167 -156.55364) (xy 15.792115 -156.561396) (xy 15.84441 -156.576751)
			(xy 15.893987 -156.599393) (xy 15.939837 -156.628859) (xy 15.958582 -156.645101) (xy 17.31399 -156.645101)
			(xy 17.318305 -156.587829) (xy 17.331153 -156.531851) (xy 17.352244 -156.478429) (xy 17.381102 -156.428772)
			(xy 17.417075 -156.383999) (xy 17.437862 -156.364178) (xy 17.445269 -156.356661) (xy 17.453792 -156.337378)
			(xy 17.454372 -156.32684) (xy 17.454372 -156.252164) (xy 17.45383 -156.241616) (xy 17.445305 -156.22232)
			(xy 17.437862 -156.214826) (xy 17.418819 -156.196658) (xy 17.385362 -156.15603) (xy 17.357802 -156.111192)
			(xy 17.336662 -156.062994) (xy 17.322342 -156.012349) (xy 17.315113 -155.960217) (xy 17.314672 -155.933902)
			(xy 17.315158 -155.906651) (xy 17.322914 -155.852703) (xy 17.338269 -155.800408) (xy 17.360911 -155.750831)
			(xy 17.390377 -155.704981) (xy 17.426068 -155.66379) (xy 17.467259 -155.628099) (xy 17.513109 -155.598633)
			(xy 17.562686 -155.575991) (xy 17.614981 -155.560636) (xy 17.668929 -155.55288) (xy 17.723431 -155.55288)
			(xy 17.777379 -155.560636) (xy 17.829674 -155.575991) (xy 17.879251 -155.598633) (xy 17.925101 -155.628099)
			(xy 17.966292 -155.66379) (xy 18.001983 -155.704981) (xy 18.031449 -155.750831) (xy 18.054091 -155.800408)
			(xy 18.069446 -155.852703) (xy 18.077202 -155.906651) (xy 18.077688 -155.933902) (xy 18.077226 -155.960216)
			(xy 18.06999 -156.012345) (xy 18.055671 -156.062988) (xy 18.034537 -156.111187) (xy 18.00699 -156.15603)
			(xy 17.97355 -156.19667) (xy 17.954498 -156.214826) (xy 17.947083 -156.222336) (xy 17.938566 -156.241625)
			(xy 17.937988 -156.252164) (xy 17.937988 -156.32684) (xy 17.938539 -156.337387) (xy 17.947059 -156.356682)
			(xy 17.954498 -156.364178) (xy 17.975289 -156.383995) (xy 18.011266 -156.428768) (xy 18.040127 -156.478425)
			(xy 18.061221 -156.531848) (xy 18.07407 -156.587828) (xy 18.078386 -156.645101) (xy 18.07407 -156.702375)
			(xy 18.072934 -156.707322) (xy 20.379798 -156.707322) (xy 20.38411 -156.650054) (xy 20.396954 -156.594078)
			(xy 20.41804 -156.540659) (xy 20.446892 -156.491002) (xy 20.482858 -156.446229) (xy 20.503642 -156.426408)
			(xy 20.511034 -156.418878) (xy 20.519566 -156.399605) (xy 20.520152 -156.38907) (xy 20.520152 -156.314394)
			(xy 20.519654 -156.30384) (xy 20.511098 -156.284544) (xy 20.503642 -156.277056) (xy 20.484561 -156.258926)
			(xy 20.451108 -156.21829) (xy 20.423554 -156.173444) (xy 20.402421 -156.125238) (xy 20.388108 -156.074587)
			(xy 20.380888 -156.022449) (xy 20.380452 -155.996132) (xy 20.380938 -155.968881) (xy 20.388694 -155.914933)
			(xy 20.404049 -155.862638) (xy 20.426691 -155.813061) (xy 20.456157 -155.767211) (xy 20.491848 -155.72602)
			(xy 20.533039 -155.690329) (xy 20.578889 -155.660863) (xy 20.628466 -155.638221) (xy 20.680761 -155.622866)
			(xy 20.734709 -155.61511) (xy 20.789211 -155.61511) (xy 20.843159 -155.622866) (xy 20.895454 -155.638221)
			(xy 20.945031 -155.660863) (xy 20.990881 -155.690329) (xy 21.032072 -155.72602) (xy 21.067763 -155.767211)
			(xy 21.097229 -155.813061) (xy 21.119871 -155.862638) (xy 21.135226 -155.914933) (xy 21.142982 -155.968881)
			(xy 21.143468 -155.996132) (xy 21.143032 -156.022447) (xy 21.135792 -156.074577) (xy 21.121468 -156.125221)
			(xy 21.100329 -156.17342) (xy 21.072777 -156.218263) (xy 21.039333 -156.258901) (xy 21.020278 -156.277056)
			(xy 21.01289 -156.284589) (xy 21.004359 -156.303861) (xy 21.003768 -156.314394) (xy 21.003768 -156.38907)
			(xy 21.004309 -156.399618) (xy 21.012837 -156.418913) (xy 21.020278 -156.426408) (xy 21.0411 -156.446195)
			(xy 21.077078 -156.490971) (xy 21.10594 -156.540633) (xy 21.127033 -156.59406) (xy 21.139882 -156.650044)
			(xy 21.144195 -156.707322) (xy 21.139875 -156.764599) (xy 21.12702 -156.820582) (xy 21.105921 -156.874006)
			(xy 21.077054 -156.923665) (xy 21.04107 -156.968437) (xy 21.020278 -156.988256) (xy 21.01289 -156.995789)
			(xy 21.004359 -157.015061) (xy 21.003768 -157.025594) (xy 21.003768 -157.10027) (xy 21.004309 -157.110818)
			(xy 21.012837 -157.130113) (xy 21.020278 -157.137608) (xy 21.039326 -157.155771) (xy 21.072785 -157.196399)
			(xy 21.100345 -157.241237) (xy 21.121485 -157.289437) (xy 21.135804 -157.340083) (xy 21.143029 -157.392216)
			(xy 21.143468 -157.418532) (xy 21.142982 -157.445783) (xy 21.135226 -157.499731) (xy 21.119871 -157.552026)
			(xy 21.097229 -157.601603) (xy 21.067763 -157.647453) (xy 21.032072 -157.688644) (xy 20.990881 -157.724335)
			(xy 20.945031 -157.753801) (xy 20.895454 -157.776443) (xy 20.843159 -157.791798) (xy 20.789211 -157.799554)
			(xy 20.734709 -157.799554) (xy 20.680761 -157.791798) (xy 20.628466 -157.776443) (xy 20.578889 -157.753801)
			(xy 20.533039 -157.724335) (xy 20.491848 -157.688644) (xy 20.456157 -157.647453) (xy 20.426691 -157.601603)
			(xy 20.404049 -157.552026) (xy 20.388694 -157.499731) (xy 20.380938 -157.445783) (xy 20.380452 -157.418532)
			(xy 20.380857 -157.392216) (xy 20.388103 -157.340084) (xy 20.402433 -157.289439) (xy 20.423577 -157.24124)
			(xy 20.451135 -157.196398) (xy 20.484585 -157.155762) (xy 20.503642 -157.137608) (xy 20.511034 -157.130078)
			(xy 20.519566 -157.110805) (xy 20.520152 -157.10027) (xy 20.520152 -157.025594) (xy 20.519654 -157.01504)
			(xy 20.511098 -156.995744) (xy 20.503642 -156.988256) (xy 20.482888 -156.968403) (xy 20.446916 -156.923634)
			(xy 20.418059 -156.87398) (xy 20.396967 -156.820564) (xy 20.384116 -156.764589) (xy 20.379798 -156.707322)
			(xy 18.072934 -156.707322) (xy 18.06122 -156.758355) (xy 18.040126 -156.811777) (xy 18.011264 -156.861435)
			(xy 17.975287 -156.906207) (xy 17.954498 -156.926026) (xy 17.947083 -156.933536) (xy 17.938566 -156.952825)
			(xy 17.937988 -156.963364) (xy 17.937988 -157.03804) (xy 17.938539 -157.048587) (xy 17.947059 -157.067882)
			(xy 17.954498 -157.075378) (xy 17.973536 -157.093552) (xy 18.006994 -157.134177) (xy 18.034556 -157.179014)
			(xy 18.055697 -157.227211) (xy 18.070018 -157.277855) (xy 18.077247 -157.329987) (xy 18.077688 -157.356302)
			(xy 18.077202 -157.383553) (xy 18.069446 -157.437501) (xy 18.054091 -157.489796) (xy 18.031449 -157.539373)
			(xy 18.001983 -157.585223) (xy 17.966292 -157.626414) (xy 17.925101 -157.662105) (xy 17.879251 -157.691571)
			(xy 17.829674 -157.714213) (xy 17.777379 -157.729568) (xy 17.723431 -157.737324) (xy 17.668929 -157.737324)
			(xy 17.614981 -157.729568) (xy 17.562686 -157.714213) (xy 17.513109 -157.691571) (xy 17.467259 -157.662105)
			(xy 17.426068 -157.626414) (xy 17.390377 -157.585223) (xy 17.360911 -157.539373) (xy 17.338269 -157.489796)
			(xy 17.322914 -157.437501) (xy 17.315158 -157.383553) (xy 17.314672 -157.356302) (xy 17.31515 -157.329988)
			(xy 17.322384 -157.277861) (xy 17.336701 -157.227219) (xy 17.357832 -157.17902) (xy 17.385376 -157.134176)
			(xy 17.418812 -157.093535) (xy 17.437862 -157.075378) (xy 17.445269 -157.067861) (xy 17.453792 -157.048578)
			(xy 17.454372 -157.03804) (xy 17.454372 -156.963364) (xy 17.45383 -156.952816) (xy 17.445305 -156.93352)
			(xy 17.437862 -156.926026) (xy 17.417077 -156.906203) (xy 17.381104 -156.861431) (xy 17.352245 -156.811773)
			(xy 17.331154 -156.758352) (xy 17.318305 -156.702373) (xy 17.31399 -156.645101) (xy 15.958582 -156.645101)
			(xy 15.981028 -156.66455) (xy 16.016719 -156.705741) (xy 16.046185 -156.751591) (xy 16.068827 -156.801168)
			(xy 16.084182 -156.853463) (xy 16.091938 -156.907411) (xy 16.092424 -156.934662) (xy 16.09199 -156.960977)
			(xy 16.084747 -157.013107) (xy 16.070421 -157.06375) (xy 16.049282 -157.111948) (xy 16.021731 -157.156791)
			(xy 15.988288 -157.19743) (xy 15.969234 -157.215586) (xy 15.961841 -157.223115) (xy 15.953311 -157.242389)
			(xy 15.952724 -157.252924) (xy 15.952724 -157.3276) (xy 15.953233 -157.338152) (xy 15.961781 -157.357448)
			(xy 15.969234 -157.364938) (xy 15.988307 -157.383075) (xy 16.021762 -157.42371) (xy 16.049317 -157.468554)
			(xy 16.070453 -157.516758) (xy 16.084766 -157.567409) (xy 16.091987 -157.619545) (xy 16.092424 -157.645862)
			(xy 16.091938 -157.673113) (xy 16.084182 -157.727061) (xy 16.068827 -157.779356) (xy 16.046185 -157.828933)
			(xy 16.016719 -157.874783) (xy 15.981028 -157.915974) (xy 15.939837 -157.951665) (xy 15.893987 -157.981131)
			(xy 15.84441 -158.003773) (xy 15.792115 -158.019128) (xy 15.738167 -158.026884) (xy 15.683665 -158.026884)
			(xy 15.629717 -158.019128) (xy 15.577422 -158.003773) (xy 15.527845 -157.981131) (xy 15.481995 -157.951665)
			(xy 15.440804 -157.915974) (xy 15.405113 -157.874783) (xy 15.375647 -157.828933) (xy 15.353005 -157.779356)
			(xy 15.33765 -157.727061) (xy 15.329894 -157.673113) (xy 15.329408 -157.645862) (xy 14.375343 -157.645862)
			(xy 14.375384 -157.647894) (xy 14.374874 -157.673881) (xy 14.366744 -157.725216) (xy 14.350683 -157.774646)
			(xy 14.327087 -157.820956) (xy 14.296537 -157.863004) (xy 14.259786 -157.899755) (xy 14.217738 -157.930305)
			(xy 14.171428 -157.953901) (xy 14.121998 -157.969962) (xy 14.070663 -157.978092) (xy 14.018689 -157.978092)
			(xy 13.967354 -157.969962) (xy 13.917924 -157.953901) (xy 13.871614 -157.930305) (xy 13.829566 -157.899755)
			(xy 13.792815 -157.863004) (xy 13.762265 -157.820956) (xy 13.738669 -157.774646) (xy 13.722608 -157.725216)
			(xy 13.714478 -157.673881) (xy 13.713968 -157.647894) (xy 13.475208 -157.647894) (xy 13.474698 -157.673881)
			(xy 13.466568 -157.725216) (xy 13.450507 -157.774646) (xy 13.426911 -157.820956) (xy 13.396361 -157.863004)
			(xy 13.35961 -157.899755) (xy 13.317562 -157.930305) (xy 13.271252 -157.953901) (xy 13.221822 -157.969962)
			(xy 13.170487 -157.978092) (xy 13.118513 -157.978092) (xy 13.067178 -157.969962) (xy 13.017748 -157.953901)
			(xy 12.971438 -157.930305) (xy 12.92939 -157.899755) (xy 12.892639 -157.863004) (xy 12.862089 -157.820956)
			(xy 12.838493 -157.774646) (xy 12.822432 -157.725216) (xy 12.814302 -157.673881) (xy 12.813792 -157.647894)
			(xy 12.575286 -157.647894) (xy 12.574776 -157.673881) (xy 12.566646 -157.725216) (xy 12.550585 -157.774646)
			(xy 12.526989 -157.820956) (xy 12.496439 -157.863004) (xy 12.459688 -157.899755) (xy 12.41764 -157.930305)
			(xy 12.37133 -157.953901) (xy 12.3219 -157.969962) (xy 12.270565 -157.978092) (xy 12.218591 -157.978092)
			(xy 12.167256 -157.969962) (xy 12.117826 -157.953901) (xy 12.071516 -157.930305) (xy 12.029468 -157.899755)
			(xy 11.992717 -157.863004) (xy 11.962167 -157.820956) (xy 11.938571 -157.774646) (xy 11.92251 -157.725216)
			(xy 11.91438 -157.673881) (xy 11.91387 -157.647894) (xy 11.675364 -157.647894) (xy 11.674854 -157.673881)
			(xy 11.666724 -157.725216) (xy 11.650663 -157.774646) (xy 11.627067 -157.820956) (xy 11.596517 -157.863004)
			(xy 11.559766 -157.899755) (xy 11.517718 -157.930305) (xy 11.471408 -157.953901) (xy 11.421978 -157.969962)
			(xy 11.370643 -157.978092) (xy 11.318669 -157.978092) (xy 11.267334 -157.969962) (xy 11.217904 -157.953901)
			(xy 11.171594 -157.930305) (xy 11.129546 -157.899755) (xy 11.092795 -157.863004) (xy 11.062245 -157.820956)
			(xy 11.038649 -157.774646) (xy 11.022588 -157.725216) (xy 11.014458 -157.673881) (xy 11.013948 -157.647894)
			(xy 7.375633 -157.647894) (xy 7.389055 -157.676525) (xy 7.405123 -157.729932) (xy 7.413243 -157.785108)
			(xy 7.413752 -157.812994) (xy 7.413243 -157.84088) (xy 7.405123 -157.896056) (xy 7.389055 -157.949463)
			(xy 7.365383 -157.99996) (xy 7.33461 -158.046473) (xy 7.32214 -158.06039) (xy 8.839706 -158.06039)
			(xy 8.843777 -158.004768) (xy 8.855903 -157.950331) (xy 8.875826 -157.89824) (xy 8.903122 -157.849605)
			(xy 8.937208 -157.805462) (xy 8.977357 -157.766753) (xy 9.022715 -157.734302) (xy 9.072315 -157.708801)
			(xy 9.125099 -157.690794) (xy 9.179942 -157.680664) (xy 9.235676 -157.678627) (xy 9.291113 -157.684727)
			(xy 9.34507 -157.698833) (xy 9.396399 -157.720645) (xy 9.444005 -157.749699) (xy 9.486873 -157.785374)
			(xy 9.52409 -157.826911) (xy 9.554863 -157.873424) (xy 9.578535 -157.923921) (xy 9.594603 -157.977328)
			(xy 9.602723 -158.032504) (xy 9.603232 -158.06039) (xy 9.602723 -158.088276) (xy 9.594603 -158.143452)
			(xy 9.578535 -158.196859) (xy 9.554863 -158.247356) (xy 9.536224 -158.275528) (xy 36.0934 -158.275528)
			(xy 36.0934 -142.513304) (xy 36.093851 -142.489299) (xy 36.101399 -142.441885) (xy 36.116276 -142.396237)
			(xy 36.138116 -142.353482) (xy 36.166382 -142.314673) (xy 36.183062 -142.297404) (xy 39.012368 -139.468098)
			(xy 39.029676 -139.451464) (xy 39.068482 -139.42321) (xy 39.111229 -139.401373) (xy 39.156865 -139.386492)
			(xy 39.204268 -139.378932) (xy 39.228268 -139.378436) (xy 46.70425 -139.378436) (xy 46.728085 -139.378907)
			(xy 46.775165 -139.386388) (xy 46.820509 -139.401099) (xy 46.863014 -139.422681) (xy 46.901647 -139.45061)
			(xy 46.91888 -139.467082) (xy 47.006002 -139.553442) (xy 47.009414 -139.557077) (xy 47.014915 -139.565389)
			(xy 47.016924 -139.569952) (xy 47.05604 -139.663424) (xy 47.057924 -139.668093) (xy 47.059966 -139.677949)
			(xy 47.060104 -139.682982) (xy 47.060104 -139.732766) (xy 47.060762 -139.748586) (xy 47.068919 -139.779171)
			(xy 47.084363 -139.806801) (xy 47.094902 -139.818618) (xy 47.09541 -139.819126) (xy 47.146972 -139.872466)
			(xy 47.154096 -139.879215) (xy 47.171988 -139.887225) (xy 47.191579 -139.887933) (xy 47.210003 -139.881235)
			(xy 47.217584 -139.875006) (xy 47.269146 -139.82827) (xy 47.27067 -139.827) (xy 47.283617 -139.814831)
			(xy 47.302885 -139.784997) (xy 47.313219 -139.751019) (xy 47.314104 -139.733274) (xy 47.314104 -139.732512)
			(xy 47.314104 -139.682982) (xy 47.314289 -139.677955) (xy 47.316328 -139.668106) (xy 47.318168 -139.663424)
			(xy 47.357284 -139.569952) (xy 47.359267 -139.565376) (xy 47.364771 -139.557059) (xy 47.368206 -139.553442)
			(xy 47.455328 -139.467082) (xy 47.472567 -139.450619) (xy 47.511206 -139.422705) (xy 47.553711 -139.401132)
			(xy 47.599051 -139.386423) (xy 47.646126 -139.378936) (xy 47.669958 -139.378436) (xy 55.801768 -139.378436)
			(xy 55.825773 -139.378895) (xy 55.873187 -139.386438) (xy 55.918835 -139.401313) (xy 55.961591 -139.423153)
			(xy 56.000399 -139.451418) (xy 56.017668 -139.468098) (xy 56.929528 -140.379958) (xy 56.946098 -140.397208)
			(xy 56.974226 -140.435893) (xy 56.99598 -140.47849) (xy 57.010829 -140.523957) (xy 57.012585 -140.534898)
			(xy 81.097372 -140.534898) (xy 81.101443 -140.479276) (xy 81.113569 -140.424839) (xy 81.133492 -140.372748)
			(xy 81.160788 -140.324113) (xy 81.194874 -140.27997) (xy 81.235023 -140.241261) (xy 81.280381 -140.20881)
			(xy 81.329981 -140.183309) (xy 81.382765 -140.165302) (xy 81.437608 -140.155172) (xy 81.493342 -140.153135)
			(xy 81.548779 -140.159235) (xy 81.602736 -140.173341) (xy 81.654065 -140.195153) (xy 81.701671 -140.224207)
			(xy 81.744539 -140.259882) (xy 81.781756 -140.301419) (xy 81.812529 -140.347932) (xy 81.836201 -140.398429)
			(xy 81.852269 -140.451836) (xy 81.860389 -140.507012) (xy 81.860898 -140.534898) (xy 81.860389 -140.562784)
			(xy 81.852269 -140.61796) (xy 81.836201 -140.671367) (xy 81.812529 -140.721864) (xy 81.781756 -140.768377)
			(xy 81.744539 -140.809914) (xy 81.701671 -140.845589) (xy 81.654065 -140.874643) (xy 81.602736 -140.896455)
			(xy 81.548779 -140.910561) (xy 81.493342 -140.916661) (xy 81.437608 -140.914624) (xy 81.382765 -140.904494)
			(xy 81.329981 -140.886487) (xy 81.280381 -140.860986) (xy 81.235023 -140.828535) (xy 81.194874 -140.789826)
			(xy 81.160788 -140.745683) (xy 81.133492 -140.697048) (xy 81.113569 -140.644957) (xy 81.101443 -140.59052)
			(xy 81.097372 -140.534898) (xy 57.012585 -140.534898) (xy 57.018409 -140.571182) (xy 57.018936 -140.595096)
			(xy 57.019444 -140.716508) (xy 57.019291 -140.721398) (xy 57.017383 -140.73099) (xy 57.015634 -140.735558)
			(xy 56.978804 -140.827506) (xy 56.97685 -140.831997) (xy 56.97148 -140.840184) (xy 56.968136 -140.843762)
			(xy 56.93283 -140.880338) (xy 56.932068 -140.8811) (xy 56.921011 -140.893139) (xy 56.904892 -140.921564)
			(xy 56.896531 -140.953154) (xy 56.896 -140.969492) (xy 56.896 -140.97) (xy 56.896543 -140.986648)
			(xy 56.905161 -141.018811) (xy 56.921809 -141.047646) (xy 56.945354 -141.071191) (xy 56.974189 -141.087839)
			(xy 57.006352 -141.096457) (xy 57.023 -141.097) (xy 57.023508 -141.097) (xy 57.039846 -141.096486)
			(xy 57.071432 -141.088108) (xy 57.099853 -141.071981) (xy 57.1119 -141.060932) (xy 57.112662 -141.06017)
			(xy 57.149238 -141.024864) (xy 57.152835 -141.021544) (xy 57.161015 -141.01617) (xy 57.165494 -141.014196)
			(xy 57.257442 -140.977366) (xy 57.262004 -140.975597) (xy 57.2716 -140.973688) (xy 57.276492 -140.973556)
			(xy 57.397904 -140.974064) (xy 57.421819 -140.974584) (xy 57.469049 -140.982154) (xy 57.51452 -140.996999)
			(xy 57.557119 -141.018755) (xy 57.595802 -141.046889) (xy 57.613042 -141.063472) (xy 60.03671 -143.48714)
			(xy 66.599308 -143.48714) (xy 66.599308 -142.62354) (xy 66.599798 -142.593556) (xy 66.607626 -142.5341)
			(xy 66.623147 -142.476175) (xy 66.646096 -142.420771) (xy 66.67608 -142.368837) (xy 66.712586 -142.321261)
			(xy 66.754991 -142.278856) (xy 66.802567 -142.24235) (xy 66.854501 -142.212366) (xy 66.909905 -142.189417)
			(xy 66.96783 -142.173896) (xy 67.027286 -142.166068) (xy 67.087254 -142.166068) (xy 67.14671 -142.173896)
			(xy 67.204635 -142.189417) (xy 67.260039 -142.212366) (xy 67.311973 -142.24235) (xy 67.359549 -142.278856)
			(xy 67.401954 -142.321261) (xy 67.43846 -142.368837) (xy 67.468444 -142.420771) (xy 67.491393 -142.476175)
			(xy 67.506914 -142.5341) (xy 67.514742 -142.593556) (xy 67.515232 -142.62354) (xy 67.515232 -143.479266)
			(xy 81.07426 -143.479266) (xy 81.07426 -142.615666) (xy 81.07475 -142.585682) (xy 81.082578 -142.526226)
			(xy 81.098099 -142.468301) (xy 81.121048 -142.412897) (xy 81.151032 -142.360963) (xy 81.187538 -142.313387)
			(xy 81.229943 -142.270982) (xy 81.277519 -142.234476) (xy 81.329453 -142.204492) (xy 81.384857 -142.181543)
			(xy 81.442782 -142.166022) (xy 81.502238 -142.158194) (xy 81.562206 -142.158194) (xy 81.621662 -142.166022)
			(xy 81.679587 -142.181543) (xy 81.734991 -142.204492) (xy 81.786925 -142.234476) (xy 81.834501 -142.270982)
			(xy 81.876906 -142.313387) (xy 81.913412 -142.360963) (xy 81.943396 -142.412897) (xy 81.966345 -142.468301)
			(xy 81.981866 -142.526226) (xy 81.989694 -142.585682) (xy 81.990184 -142.615666) (xy 81.990184 -143.479266)
			(xy 81.989694 -143.50925) (xy 81.981866 -143.568706) (xy 81.966345 -143.626631) (xy 81.943396 -143.682035)
			(xy 81.913412 -143.733969) (xy 81.876906 -143.781545) (xy 81.834501 -143.82395) (xy 81.786925 -143.860456)
			(xy 81.734991 -143.89044) (xy 81.679587 -143.913389) (xy 81.621662 -143.92891) (xy 81.562206 -143.936738)
			(xy 81.502238 -143.936738) (xy 81.442782 -143.92891) (xy 81.384857 -143.913389) (xy 81.329453 -143.89044)
			(xy 81.277519 -143.860456) (xy 81.229943 -143.82395) (xy 81.187538 -143.781545) (xy 81.151032 -143.733969)
			(xy 81.121048 -143.682035) (xy 81.098099 -143.626631) (xy 81.082578 -143.568706) (xy 81.07475 -143.50925)
			(xy 81.07426 -143.479266) (xy 67.515232 -143.479266) (xy 67.515232 -143.48714) (xy 67.514742 -143.517124)
			(xy 67.506914 -143.57658) (xy 67.491393 -143.634505) (xy 67.468444 -143.689909) (xy 67.43846 -143.741843)
			(xy 67.401954 -143.789419) (xy 67.359549 -143.831824) (xy 67.311973 -143.86833) (xy 67.260039 -143.898314)
			(xy 67.204635 -143.921263) (xy 67.14671 -143.936784) (xy 67.087254 -143.944612) (xy 67.027286 -143.944612)
			(xy 66.96783 -143.936784) (xy 66.909905 -143.921263) (xy 66.854501 -143.898314) (xy 66.802567 -143.86833)
			(xy 66.754991 -143.831824) (xy 66.712586 -143.789419) (xy 66.67608 -143.741843) (xy 66.646096 -143.689909)
			(xy 66.623147 -143.634505) (xy 66.607626 -143.57658) (xy 66.599798 -143.517124) (xy 66.599308 -143.48714)
			(xy 60.03671 -143.48714) (xy 61.836808 -145.287238) (xy 64.745108 -145.287238) (xy 64.745108 -144.423638)
			(xy 64.745598 -144.393654) (xy 64.753426 -144.334198) (xy 64.768947 -144.276273) (xy 64.791896 -144.220869)
			(xy 64.82188 -144.168935) (xy 64.858386 -144.121359) (xy 64.900791 -144.078954) (xy 64.948367 -144.042448)
			(xy 65.000301 -144.012464) (xy 65.055705 -143.989515) (xy 65.11363 -143.973994) (xy 65.173086 -143.966166)
			(xy 65.233054 -143.966166) (xy 65.29251 -143.973994) (xy 65.350435 -143.989515) (xy 65.405839 -144.012464)
			(xy 65.457773 -144.042448) (xy 65.505349 -144.078954) (xy 65.547754 -144.121359) (xy 65.58426 -144.168935)
			(xy 65.614244 -144.220869) (xy 65.637193 -144.276273) (xy 65.652714 -144.334198) (xy 65.660542 -144.393654)
			(xy 65.661032 -144.423638) (xy 65.661032 -145.285714) (xy 83.716368 -145.285714) (xy 83.716368 -144.422114)
			(xy 83.716858 -144.39213) (xy 83.724686 -144.332674) (xy 83.740207 -144.274749) (xy 83.763156 -144.219345)
			(xy 83.79314 -144.167411) (xy 83.829646 -144.119835) (xy 83.872051 -144.07743) (xy 83.919627 -144.040924)
			(xy 83.971561 -144.01094) (xy 84.026965 -143.987991) (xy 84.08489 -143.97247) (xy 84.144346 -143.964642)
			(xy 84.204314 -143.964642) (xy 84.26377 -143.97247) (xy 84.321695 -143.987991) (xy 84.377099 -144.01094)
			(xy 84.429033 -144.040924) (xy 84.476609 -144.07743) (xy 84.519014 -144.119835) (xy 84.55552 -144.167411)
			(xy 84.585504 -144.219345) (xy 84.608453 -144.274749) (xy 84.623974 -144.332674) (xy 84.631802 -144.39213)
			(xy 84.632292 -144.422114) (xy 84.632292 -145.285714) (xy 84.631802 -145.315698) (xy 84.623974 -145.375154)
			(xy 84.608453 -145.433079) (xy 84.585504 -145.488483) (xy 84.55552 -145.540417) (xy 84.519014 -145.587993)
			(xy 84.476609 -145.630398) (xy 84.429033 -145.666904) (xy 84.377099 -145.696888) (xy 84.321695 -145.719837)
			(xy 84.26377 -145.735358) (xy 84.204314 -145.743186) (xy 84.144346 -145.743186) (xy 84.08489 -145.735358)
			(xy 84.026965 -145.719837) (xy 83.971561 -145.696888) (xy 83.919627 -145.666904) (xy 83.872051 -145.630398)
			(xy 83.829646 -145.587993) (xy 83.79314 -145.540417) (xy 83.763156 -145.488483) (xy 83.740207 -145.433079)
			(xy 83.724686 -145.375154) (xy 83.716858 -145.315698) (xy 83.716368 -145.285714) (xy 65.661032 -145.285714)
			(xy 65.661032 -145.287238) (xy 65.660542 -145.317222) (xy 65.652714 -145.376678) (xy 65.637193 -145.434603)
			(xy 65.614244 -145.490007) (xy 65.58426 -145.541941) (xy 65.547754 -145.589517) (xy 65.505349 -145.631922)
			(xy 65.457773 -145.668428) (xy 65.405839 -145.698412) (xy 65.350435 -145.721361) (xy 65.29251 -145.736882)
			(xy 65.233054 -145.74471) (xy 65.173086 -145.74471) (xy 65.11363 -145.736882) (xy 65.055705 -145.721361)
			(xy 65.000301 -145.698412) (xy 64.948367 -145.668428) (xy 64.900791 -145.631922) (xy 64.858386 -145.589517)
			(xy 64.82188 -145.541941) (xy 64.791896 -145.490007) (xy 64.768947 -145.434603) (xy 64.753426 -145.376678)
			(xy 64.745598 -145.317222) (xy 64.745108 -145.287238) (xy 61.836808 -145.287238) (xy 63.636906 -147.087336)
			(xy 66.599308 -147.087336) (xy 66.599308 -146.223736) (xy 66.599798 -146.193752) (xy 66.607626 -146.134296)
			(xy 66.623147 -146.076371) (xy 66.646096 -146.020967) (xy 66.67608 -145.969033) (xy 66.712586 -145.921457)
			(xy 66.754991 -145.879052) (xy 66.802567 -145.842546) (xy 66.854501 -145.812562) (xy 66.909905 -145.789613)
			(xy 66.96783 -145.774092) (xy 67.027286 -145.766264) (xy 67.087254 -145.766264) (xy 67.14671 -145.774092)
			(xy 67.204635 -145.789613) (xy 67.260039 -145.812562) (xy 67.311973 -145.842546) (xy 67.359549 -145.879052)
			(xy 67.401954 -145.921457) (xy 67.43846 -145.969033) (xy 67.468444 -146.020967) (xy 67.491393 -146.076371)
			(xy 67.506914 -146.134296) (xy 67.514742 -146.193752) (xy 67.515232 -146.223736) (xy 67.515232 -147.079208)
			(xy 81.07426 -147.079208) (xy 81.07426 -146.215608) (xy 81.07475 -146.185624) (xy 81.082578 -146.126168)
			(xy 81.098099 -146.068243) (xy 81.121048 -146.012839) (xy 81.151032 -145.960905) (xy 81.187538 -145.913329)
			(xy 81.229943 -145.870924) (xy 81.277519 -145.834418) (xy 81.329453 -145.804434) (xy 81.384857 -145.781485)
			(xy 81.442782 -145.765964) (xy 81.502238 -145.758136) (xy 81.562206 -145.758136) (xy 81.621662 -145.765964)
			(xy 81.679587 -145.781485) (xy 81.734991 -145.804434) (xy 81.786925 -145.834418) (xy 81.834501 -145.870924)
			(xy 81.876906 -145.913329) (xy 81.913412 -145.960905) (xy 81.943396 -146.012839) (xy 81.966345 -146.068243)
			(xy 81.981866 -146.126168) (xy 81.989694 -146.185624) (xy 81.990184 -146.215608) (xy 81.990184 -147.079208)
			(xy 81.989694 -147.109192) (xy 81.981866 -147.168648) (xy 81.966345 -147.226573) (xy 81.943396 -147.281977)
			(xy 81.913412 -147.333911) (xy 81.876906 -147.381487) (xy 81.834501 -147.423892) (xy 81.786925 -147.460398)
			(xy 81.734991 -147.490382) (xy 81.679587 -147.513331) (xy 81.621662 -147.528852) (xy 81.562206 -147.53668)
			(xy 81.502238 -147.53668) (xy 81.442782 -147.528852) (xy 81.384857 -147.513331) (xy 81.329453 -147.490382)
			(xy 81.277519 -147.460398) (xy 81.229943 -147.423892) (xy 81.187538 -147.381487) (xy 81.151032 -147.333911)
			(xy 81.121048 -147.281977) (xy 81.098099 -147.226573) (xy 81.082578 -147.168648) (xy 81.07475 -147.109192)
			(xy 81.07426 -147.079208) (xy 67.515232 -147.079208) (xy 67.515232 -147.087336) (xy 67.514742 -147.11732)
			(xy 67.506914 -147.176776) (xy 67.491393 -147.234701) (xy 67.468444 -147.290105) (xy 67.43846 -147.342039)
			(xy 67.401954 -147.389615) (xy 67.359549 -147.43202) (xy 67.311973 -147.468526) (xy 67.260039 -147.49851)
			(xy 67.204635 -147.521459) (xy 67.14671 -147.53698) (xy 67.087254 -147.544808) (xy 67.027286 -147.544808)
			(xy 66.96783 -147.53698) (xy 66.909905 -147.521459) (xy 66.854501 -147.49851) (xy 66.802567 -147.468526)
			(xy 66.754991 -147.43202) (xy 66.712586 -147.389615) (xy 66.67608 -147.342039) (xy 66.646096 -147.290105)
			(xy 66.623147 -147.234701) (xy 66.607626 -147.176776) (xy 66.599798 -147.11732) (xy 66.599308 -147.087336)
			(xy 63.636906 -147.087336) (xy 64.178942 -147.629372) (xy 64.195586 -147.646673) (xy 64.223846 -147.685478)
			(xy 64.245687 -147.728226) (xy 64.260571 -147.773865) (xy 64.268132 -147.82127) (xy 64.268604 -147.845272)
			(xy 64.268604 -148.887434) (xy 64.745108 -148.887434) (xy 64.745108 -148.023834) (xy 64.745598 -147.99385)
			(xy 64.753426 -147.934394) (xy 64.768947 -147.876469) (xy 64.791896 -147.821065) (xy 64.82188 -147.769131)
			(xy 64.858386 -147.721555) (xy 64.900791 -147.67915) (xy 64.948367 -147.642644) (xy 65.000301 -147.61266)
			(xy 65.055705 -147.589711) (xy 65.11363 -147.57419) (xy 65.173086 -147.566362) (xy 65.233054 -147.566362)
			(xy 65.29251 -147.57419) (xy 65.350435 -147.589711) (xy 65.405839 -147.61266) (xy 65.457773 -147.642644)
			(xy 65.505349 -147.67915) (xy 65.547754 -147.721555) (xy 65.58426 -147.769131) (xy 65.614244 -147.821065)
			(xy 65.637193 -147.876469) (xy 65.652714 -147.934394) (xy 65.660542 -147.99385) (xy 65.661032 -148.023834)
			(xy 65.661032 -148.88591) (xy 83.716368 -148.88591) (xy 83.716368 -148.02231) (xy 83.716858 -147.992326)
			(xy 83.724686 -147.93287) (xy 83.740207 -147.874945) (xy 83.763156 -147.819541) (xy 83.79314 -147.767607)
			(xy 83.829646 -147.720031) (xy 83.872051 -147.677626) (xy 83.919627 -147.64112) (xy 83.971561 -147.611136)
			(xy 84.026965 -147.588187) (xy 84.08489 -147.572666) (xy 84.144346 -147.564838) (xy 84.204314 -147.564838)
			(xy 84.26377 -147.572666) (xy 84.321695 -147.588187) (xy 84.377099 -147.611136) (xy 84.429033 -147.64112)
			(xy 84.476609 -147.677626) (xy 84.519014 -147.720031) (xy 84.55552 -147.767607) (xy 84.585504 -147.819541)
			(xy 84.608453 -147.874945) (xy 84.623974 -147.93287) (xy 84.631802 -147.992326) (xy 84.632292 -148.02231)
			(xy 84.632292 -148.88591) (xy 84.631802 -148.915894) (xy 84.623974 -148.97535) (xy 84.608453 -149.033275)
			(xy 84.585504 -149.088679) (xy 84.55552 -149.140613) (xy 84.519014 -149.188189) (xy 84.476609 -149.230594)
			(xy 84.429033 -149.2671) (xy 84.377099 -149.297084) (xy 84.321695 -149.320033) (xy 84.26377 -149.335554)
			(xy 84.204314 -149.343382) (xy 84.144346 -149.343382) (xy 84.08489 -149.335554) (xy 84.026965 -149.320033)
			(xy 83.971561 -149.297084) (xy 83.919627 -149.2671) (xy 83.872051 -149.230594) (xy 83.829646 -149.188189)
			(xy 83.79314 -149.140613) (xy 83.763156 -149.088679) (xy 83.740207 -149.033275) (xy 83.724686 -148.97535)
			(xy 83.716858 -148.915894) (xy 83.716368 -148.88591) (xy 65.661032 -148.88591) (xy 65.661032 -148.887434)
			(xy 65.660542 -148.917418) (xy 65.652714 -148.976874) (xy 65.637193 -149.034799) (xy 65.614244 -149.090203)
			(xy 65.58426 -149.142137) (xy 65.547754 -149.189713) (xy 65.505349 -149.232118) (xy 65.457773 -149.268624)
			(xy 65.405839 -149.298608) (xy 65.350435 -149.321557) (xy 65.29251 -149.337078) (xy 65.233054 -149.344906)
			(xy 65.173086 -149.344906) (xy 65.11363 -149.337078) (xy 65.055705 -149.321557) (xy 65.000301 -149.298608)
			(xy 64.948367 -149.268624) (xy 64.900791 -149.232118) (xy 64.858386 -149.189713) (xy 64.82188 -149.142137)
			(xy 64.791896 -149.090203) (xy 64.768947 -149.034799) (xy 64.753426 -148.976874) (xy 64.745598 -148.917418)
			(xy 64.745108 -148.887434) (xy 64.268604 -148.887434) (xy 64.268604 -150.687278) (xy 66.599308 -150.687278)
			(xy 66.599308 -149.823678) (xy 66.599798 -149.793694) (xy 66.607626 -149.734238) (xy 66.623147 -149.676313)
			(xy 66.646096 -149.620909) (xy 66.67608 -149.568975) (xy 66.712586 -149.521399) (xy 66.754991 -149.478994)
			(xy 66.802567 -149.442488) (xy 66.854501 -149.412504) (xy 66.909905 -149.389555) (xy 66.96783 -149.374034)
			(xy 67.027286 -149.366206) (xy 67.087254 -149.366206) (xy 67.14671 -149.374034) (xy 67.204635 -149.389555)
			(xy 67.260039 -149.412504) (xy 67.311973 -149.442488) (xy 67.359549 -149.478994) (xy 67.401954 -149.521399)
			(xy 67.43846 -149.568975) (xy 67.468444 -149.620909) (xy 67.491393 -149.676313) (xy 67.506914 -149.734238)
			(xy 67.514742 -149.793694) (xy 67.515232 -149.823678) (xy 67.515232 -150.67915) (xy 81.07426 -150.67915)
			(xy 81.07426 -149.81555) (xy 81.07475 -149.785566) (xy 81.082578 -149.72611) (xy 81.098099 -149.668185)
			(xy 81.121048 -149.612781) (xy 81.151032 -149.560847) (xy 81.187538 -149.513271) (xy 81.229943 -149.470866)
			(xy 81.277519 -149.43436) (xy 81.329453 -149.404376) (xy 81.384857 -149.381427) (xy 81.442782 -149.365906)
			(xy 81.502238 -149.358078) (xy 81.562206 -149.358078) (xy 81.621662 -149.365906) (xy 81.679587 -149.381427)
			(xy 81.734991 -149.404376) (xy 81.786925 -149.43436) (xy 81.834501 -149.470866) (xy 81.876906 -149.513271)
			(xy 81.913412 -149.560847) (xy 81.943396 -149.612781) (xy 81.966345 -149.668185) (xy 81.981866 -149.72611)
			(xy 81.989694 -149.785566) (xy 81.990184 -149.81555) (xy 81.990184 -150.67915) (xy 81.989694 -150.709134)
			(xy 81.981866 -150.76859) (xy 81.966345 -150.826515) (xy 81.943396 -150.881919) (xy 81.913412 -150.933853)
			(xy 81.876906 -150.981429) (xy 81.834501 -151.023834) (xy 81.786925 -151.06034) (xy 81.734991 -151.090324)
			(xy 81.679587 -151.113273) (xy 81.621662 -151.128794) (xy 81.562206 -151.136622) (xy 81.502238 -151.136622)
			(xy 81.442782 -151.128794) (xy 81.384857 -151.113273) (xy 81.329453 -151.090324) (xy 81.277519 -151.06034)
			(xy 81.229943 -151.023834) (xy 81.187538 -150.981429) (xy 81.151032 -150.933853) (xy 81.121048 -150.881919)
			(xy 81.098099 -150.826515) (xy 81.082578 -150.76859) (xy 81.07475 -150.709134) (xy 81.07426 -150.67915)
			(xy 67.515232 -150.67915) (xy 67.515232 -150.687278) (xy 67.514742 -150.717262) (xy 67.506914 -150.776718)
			(xy 67.491393 -150.834643) (xy 67.468444 -150.890047) (xy 67.43846 -150.941981) (xy 67.401954 -150.989557)
			(xy 67.359549 -151.031962) (xy 67.311973 -151.068468) (xy 67.260039 -151.098452) (xy 67.204635 -151.121401)
			(xy 67.14671 -151.136922) (xy 67.087254 -151.14475) (xy 67.027286 -151.14475) (xy 66.96783 -151.136922)
			(xy 66.909905 -151.121401) (xy 66.854501 -151.098452) (xy 66.802567 -151.068468) (xy 66.754991 -151.031962)
			(xy 66.712586 -150.989557) (xy 66.67608 -150.941981) (xy 66.646096 -150.890047) (xy 66.623147 -150.834643)
			(xy 66.607626 -150.776718) (xy 66.599798 -150.717262) (xy 66.599308 -150.687278) (xy 64.268604 -150.687278)
			(xy 64.268604 -152.487376) (xy 64.745108 -152.487376) (xy 64.745108 -151.623776) (xy 64.745598 -151.593792)
			(xy 64.753426 -151.534336) (xy 64.768947 -151.476411) (xy 64.791896 -151.421007) (xy 64.82188 -151.369073)
			(xy 64.858386 -151.321497) (xy 64.900791 -151.279092) (xy 64.948367 -151.242586) (xy 65.000301 -151.212602)
			(xy 65.055705 -151.189653) (xy 65.11363 -151.174132) (xy 65.173086 -151.166304) (xy 65.233054 -151.166304)
			(xy 65.29251 -151.174132) (xy 65.350435 -151.189653) (xy 65.405839 -151.212602) (xy 65.457773 -151.242586)
			(xy 65.505349 -151.279092) (xy 65.547754 -151.321497) (xy 65.58426 -151.369073) (xy 65.614244 -151.421007)
			(xy 65.637193 -151.476411) (xy 65.652714 -151.534336) (xy 65.660542 -151.593792) (xy 65.661032 -151.623776)
			(xy 65.661032 -152.485852) (xy 83.716368 -152.485852) (xy 83.716368 -151.622252) (xy 83.716858 -151.592268)
			(xy 83.724686 -151.532812) (xy 83.740207 -151.474887) (xy 83.763156 -151.419483) (xy 83.79314 -151.367549)
			(xy 83.829646 -151.319973) (xy 83.872051 -151.277568) (xy 83.919627 -151.241062) (xy 83.971561 -151.211078)
			(xy 84.026965 -151.188129) (xy 84.08489 -151.172608) (xy 84.144346 -151.16478) (xy 84.204314 -151.16478)
			(xy 84.26377 -151.172608) (xy 84.321695 -151.188129) (xy 84.377099 -151.211078) (xy 84.429033 -151.241062)
			(xy 84.476609 -151.277568) (xy 84.519014 -151.319973) (xy 84.55552 -151.367549) (xy 84.585504 -151.419483)
			(xy 84.608453 -151.474887) (xy 84.623974 -151.532812) (xy 84.631802 -151.592268) (xy 84.632292 -151.622252)
			(xy 84.632292 -152.485852) (xy 84.631802 -152.515836) (xy 84.623974 -152.575292) (xy 84.608453 -152.633217)
			(xy 84.585504 -152.688621) (xy 84.55552 -152.740555) (xy 84.519014 -152.788131) (xy 84.476609 -152.830536)
			(xy 84.429033 -152.867042) (xy 84.377099 -152.897026) (xy 84.321695 -152.919975) (xy 84.26377 -152.935496)
			(xy 84.204314 -152.943324) (xy 84.144346 -152.943324) (xy 84.08489 -152.935496) (xy 84.026965 -152.919975)
			(xy 83.971561 -152.897026) (xy 83.919627 -152.867042) (xy 83.872051 -152.830536) (xy 83.829646 -152.788131)
			(xy 83.79314 -152.740555) (xy 83.763156 -152.688621) (xy 83.740207 -152.633217) (xy 83.724686 -152.575292)
			(xy 83.716858 -152.515836) (xy 83.716368 -152.485852) (xy 65.661032 -152.485852) (xy 65.661032 -152.487376)
			(xy 65.660542 -152.51736) (xy 65.652714 -152.576816) (xy 65.637193 -152.634741) (xy 65.614244 -152.690145)
			(xy 65.58426 -152.742079) (xy 65.547754 -152.789655) (xy 65.505349 -152.83206) (xy 65.457773 -152.868566)
			(xy 65.405839 -152.89855) (xy 65.350435 -152.921499) (xy 65.29251 -152.93702) (xy 65.233054 -152.944848)
			(xy 65.173086 -152.944848) (xy 65.11363 -152.93702) (xy 65.055705 -152.921499) (xy 65.000301 -152.89855)
			(xy 64.948367 -152.868566) (xy 64.900791 -152.83206) (xy 64.858386 -152.789655) (xy 64.82188 -152.742079)
			(xy 64.791896 -152.690145) (xy 64.768947 -152.634741) (xy 64.753426 -152.576816) (xy 64.745598 -152.51736)
			(xy 64.745108 -152.487376) (xy 64.268604 -152.487376) (xy 64.268604 -154.28722) (xy 66.599308 -154.28722)
			(xy 66.599308 -153.42362) (xy 66.599798 -153.393636) (xy 66.607626 -153.33418) (xy 66.623147 -153.276255)
			(xy 66.646096 -153.220851) (xy 66.67608 -153.168917) (xy 66.712586 -153.121341) (xy 66.754991 -153.078936)
			(xy 66.802567 -153.04243) (xy 66.854501 -153.012446) (xy 66.909905 -152.989497) (xy 66.96783 -152.973976)
			(xy 67.027286 -152.966148) (xy 67.087254 -152.966148) (xy 67.14671 -152.973976) (xy 67.204635 -152.989497)
			(xy 67.260039 -153.012446) (xy 67.311973 -153.04243) (xy 67.359549 -153.078936) (xy 67.401954 -153.121341)
			(xy 67.43846 -153.168917) (xy 67.468444 -153.220851) (xy 67.491393 -153.276255) (xy 67.506914 -153.33418)
			(xy 67.514742 -153.393636) (xy 67.515232 -153.42362) (xy 67.515232 -154.279346) (xy 81.07426 -154.279346)
			(xy 81.07426 -153.415746) (xy 81.07475 -153.385762) (xy 81.082578 -153.326306) (xy 81.098099 -153.268381)
			(xy 81.121048 -153.212977) (xy 81.151032 -153.161043) (xy 81.187538 -153.113467) (xy 81.229943 -153.071062)
			(xy 81.277519 -153.034556) (xy 81.329453 -153.004572) (xy 81.384857 -152.981623) (xy 81.442782 -152.966102)
			(xy 81.502238 -152.958274) (xy 81.562206 -152.958274) (xy 81.621662 -152.966102) (xy 81.679587 -152.981623)
			(xy 81.734991 -153.004572) (xy 81.786925 -153.034556) (xy 81.834501 -153.071062) (xy 81.876906 -153.113467)
			(xy 81.913412 -153.161043) (xy 81.943396 -153.212977) (xy 81.966345 -153.268381) (xy 81.981866 -153.326306)
			(xy 81.989694 -153.385762) (xy 81.990184 -153.415746) (xy 81.990184 -154.279346) (xy 81.989694 -154.30933)
			(xy 81.981866 -154.368786) (xy 81.966345 -154.426711) (xy 81.943396 -154.482115) (xy 81.913412 -154.534049)
			(xy 81.876906 -154.581625) (xy 81.834501 -154.62403) (xy 81.786925 -154.660536) (xy 81.734991 -154.69052)
			(xy 81.679587 -154.713469) (xy 81.621662 -154.72899) (xy 81.562206 -154.736818) (xy 81.502238 -154.736818)
			(xy 81.442782 -154.72899) (xy 81.384857 -154.713469) (xy 81.329453 -154.69052) (xy 81.277519 -154.660536)
			(xy 81.229943 -154.62403) (xy 81.187538 -154.581625) (xy 81.151032 -154.534049) (xy 81.121048 -154.482115)
			(xy 81.098099 -154.426711) (xy 81.082578 -154.368786) (xy 81.07475 -154.30933) (xy 81.07426 -154.279346)
			(xy 67.515232 -154.279346) (xy 67.515232 -154.28722) (xy 67.514742 -154.317204) (xy 67.506914 -154.37666)
			(xy 67.491393 -154.434585) (xy 67.468444 -154.489989) (xy 67.43846 -154.541923) (xy 67.401954 -154.589499)
			(xy 67.359549 -154.631904) (xy 67.311973 -154.66841) (xy 67.260039 -154.698394) (xy 67.204635 -154.721343)
			(xy 67.14671 -154.736864) (xy 67.087254 -154.744692) (xy 67.027286 -154.744692) (xy 66.96783 -154.736864)
			(xy 66.909905 -154.721343) (xy 66.854501 -154.698394) (xy 66.802567 -154.66841) (xy 66.754991 -154.631904)
			(xy 66.712586 -154.589499) (xy 66.67608 -154.541923) (xy 66.646096 -154.489989) (xy 66.623147 -154.434585)
			(xy 66.607626 -154.37666) (xy 66.599798 -154.317204) (xy 66.599308 -154.28722) (xy 64.268604 -154.28722)
			(xy 64.268604 -156.087318) (xy 64.745108 -156.087318) (xy 64.745108 -155.223718) (xy 64.745598 -155.193734)
			(xy 64.753426 -155.134278) (xy 64.768947 -155.076353) (xy 64.791896 -155.020949) (xy 64.82188 -154.969015)
			(xy 64.858386 -154.921439) (xy 64.900791 -154.879034) (xy 64.948367 -154.842528) (xy 65.000301 -154.812544)
			(xy 65.055705 -154.789595) (xy 65.11363 -154.774074) (xy 65.173086 -154.766246) (xy 65.233054 -154.766246)
			(xy 65.29251 -154.774074) (xy 65.350435 -154.789595) (xy 65.405839 -154.812544) (xy 65.457773 -154.842528)
			(xy 65.505349 -154.879034) (xy 65.547754 -154.921439) (xy 65.58426 -154.969015) (xy 65.614244 -155.020949)
			(xy 65.637193 -155.076353) (xy 65.652714 -155.134278) (xy 65.660542 -155.193734) (xy 65.661032 -155.223718)
			(xy 65.661032 -156.085794) (xy 83.716368 -156.085794) (xy 83.716368 -155.222194) (xy 83.716858 -155.19221)
			(xy 83.724686 -155.132754) (xy 83.740207 -155.074829) (xy 83.763156 -155.019425) (xy 83.79314 -154.967491)
			(xy 83.829646 -154.919915) (xy 83.872051 -154.87751) (xy 83.919627 -154.841004) (xy 83.971561 -154.81102)
			(xy 84.026965 -154.788071) (xy 84.08489 -154.77255) (xy 84.144346 -154.764722) (xy 84.204314 -154.764722)
			(xy 84.26377 -154.77255) (xy 84.321695 -154.788071) (xy 84.377099 -154.81102) (xy 84.429033 -154.841004)
			(xy 84.476609 -154.87751) (xy 84.519014 -154.919915) (xy 84.55552 -154.967491) (xy 84.585504 -155.019425)
			(xy 84.608453 -155.074829) (xy 84.623974 -155.132754) (xy 84.631802 -155.19221) (xy 84.632292 -155.222194)
			(xy 84.632292 -156.085794) (xy 84.631802 -156.115778) (xy 84.623974 -156.175234) (xy 84.608453 -156.233159)
			(xy 84.585504 -156.288563) (xy 84.55552 -156.340497) (xy 84.519014 -156.388073) (xy 84.476609 -156.430478)
			(xy 84.429033 -156.466984) (xy 84.377099 -156.496968) (xy 84.321695 -156.519917) (xy 84.26377 -156.535438)
			(xy 84.204314 -156.543266) (xy 84.144346 -156.543266) (xy 84.08489 -156.535438) (xy 84.026965 -156.519917)
			(xy 83.971561 -156.496968) (xy 83.919627 -156.466984) (xy 83.872051 -156.430478) (xy 83.829646 -156.388073)
			(xy 83.79314 -156.340497) (xy 83.763156 -156.288563) (xy 83.740207 -156.233159) (xy 83.724686 -156.175234)
			(xy 83.716858 -156.115778) (xy 83.716368 -156.085794) (xy 65.661032 -156.085794) (xy 65.661032 -156.087318)
			(xy 65.660542 -156.117302) (xy 65.652714 -156.176758) (xy 65.637193 -156.234683) (xy 65.614244 -156.290087)
			(xy 65.58426 -156.342021) (xy 65.547754 -156.389597) (xy 65.505349 -156.432002) (xy 65.457773 -156.468508)
			(xy 65.405839 -156.498492) (xy 65.350435 -156.521441) (xy 65.29251 -156.536962) (xy 65.233054 -156.54479)
			(xy 65.173086 -156.54479) (xy 65.11363 -156.536962) (xy 65.055705 -156.521441) (xy 65.000301 -156.498492)
			(xy 64.948367 -156.468508) (xy 64.900791 -156.432002) (xy 64.858386 -156.389597) (xy 64.82188 -156.342021)
			(xy 64.791896 -156.290087) (xy 64.768947 -156.234683) (xy 64.753426 -156.176758) (xy 64.745598 -156.117302)
			(xy 64.745108 -156.087318) (xy 64.268604 -156.087318) (xy 64.268604 -158.219648) (xy 81.182208 -158.219648)
			(xy 81.186279 -158.164026) (xy 81.198405 -158.109589) (xy 81.218328 -158.057498) (xy 81.245624 -158.008863)
			(xy 81.27971 -157.96472) (xy 81.319859 -157.926011) (xy 81.365217 -157.89356) (xy 81.414817 -157.868059)
			(xy 81.467601 -157.850052) (xy 81.522444 -157.839922) (xy 81.578178 -157.837885) (xy 81.633615 -157.843985)
			(xy 81.687572 -157.858091) (xy 81.738901 -157.879903) (xy 81.786507 -157.908957) (xy 81.829375 -157.944632)
			(xy 81.866592 -157.986169) (xy 81.897365 -158.032682) (xy 81.921037 -158.083179) (xy 81.937105 -158.136586)
			(xy 81.945225 -158.191762) (xy 81.945734 -158.219648) (xy 81.945225 -158.247534) (xy 81.937105 -158.30271)
			(xy 81.921037 -158.356117) (xy 81.897365 -158.406614) (xy 81.866592 -158.453127) (xy 81.829375 -158.494664)
			(xy 81.786507 -158.530339) (xy 81.738901 -158.559393) (xy 81.687572 -158.581205) (xy 81.633615 -158.595311)
			(xy 81.578178 -158.601411) (xy 81.522444 -158.599374) (xy 81.467601 -158.589244) (xy 81.414817 -158.571237)
			(xy 81.365217 -158.545736) (xy 81.319859 -158.513285) (xy 81.27971 -158.474576) (xy 81.245624 -158.430433)
			(xy 81.218328 -158.381798) (xy 81.198405 -158.329707) (xy 81.186279 -158.27527) (xy 81.182208 -158.219648)
			(xy 64.268604 -158.219648) (xy 64.268604 -160.1851) (xy 69.888875 -160.1851) (xy 69.892831 -160.093241)
			(xy 69.904668 -160.002062) (xy 69.9243 -159.912238) (xy 69.951581 -159.824435) (xy 69.986309 -159.739302)
			(xy 70.028227 -159.657469) (xy 70.077025 -159.579542) (xy 70.13234 -159.506099) (xy 70.193765 -159.437683)
			(xy 70.260844 -159.374801) (xy 70.333079 -159.317918) (xy 70.409938 -159.267455) (xy 70.49085 -159.223786)
			(xy 70.575216 -159.187234) (xy 70.662412 -159.15807) (xy 70.751793 -159.13651) (xy 70.842696 -159.122714)
			(xy 70.934449 -159.116782) (xy 71.026371 -159.118761) (xy 71.117784 -159.128634) (xy 71.208009 -159.146329)
			(xy 71.29638 -159.171714) (xy 71.38224 -159.204602) (xy 71.464956 -159.24475) (xy 71.543914 -159.291859)
			(xy 71.618531 -159.345582) (xy 71.688252 -159.40552) (xy 71.752563 -159.47123) (xy 71.810988 -159.542226)
			(xy 71.863093 -159.61798) (xy 71.908492 -159.697934) (xy 71.946851 -159.781494) (xy 71.977884 -159.868043)
			(xy 72.001362 -159.956939) (xy 72.017112 -160.047524) (xy 72.025016 -160.139128) (xy 72.02551 -160.1851)
			(xy 72.025016 -160.231072) (xy 72.017112 -160.322676) (xy 72.001362 -160.413261) (xy 71.977884 -160.502157)
			(xy 71.946851 -160.588706) (xy 71.908492 -160.672266) (xy 71.863093 -160.75222) (xy 71.810988 -160.827974)
			(xy 71.752563 -160.89897) (xy 71.688252 -160.96468) (xy 71.618531 -161.024618) (xy 71.543914 -161.078341)
			(xy 71.464956 -161.12545) (xy 71.38224 -161.165598) (xy 71.29638 -161.198486) (xy 71.208009 -161.223871)
			(xy 71.117784 -161.241566) (xy 71.026371 -161.251439) (xy 70.934449 -161.253418) (xy 70.842696 -161.247486)
			(xy 70.751793 -161.23369) (xy 70.662412 -161.21213) (xy 70.575216 -161.182966) (xy 70.49085 -161.146414)
			(xy 70.409938 -161.102745) (xy 70.333079 -161.052282) (xy 70.260844 -160.995399) (xy 70.193765 -160.932517)
			(xy 70.13234 -160.864101) (xy 70.077025 -160.790658) (xy 70.028227 -160.712731) (xy 69.986309 -160.630898)
			(xy 69.951581 -160.545765) (xy 69.9243 -160.457962) (xy 69.904668 -160.368138) (xy 69.892831 -160.276959)
			(xy 69.888875 -160.1851) (xy 64.268604 -160.1851) (xy 64.268604 -161.242756) (xy 64.287654 -161.269172)
			(xy 64.303148 -161.274506) (xy 64.329585 -161.283907) (xy 64.379658 -161.309217) (xy 64.425483 -161.341589)
			(xy 64.466071 -161.380325) (xy 64.500545 -161.42459) (xy 64.528162 -161.473428) (xy 64.548327 -161.525785)
			(xy 64.560603 -161.580532) (xy 64.564726 -161.636486) (xy 64.560607 -161.692441) (xy 64.548335 -161.747188)
			(xy 64.528174 -161.799547) (xy 64.50056 -161.848387) (xy 64.466089 -161.892654) (xy 64.425504 -161.931393)
			(xy 64.379682 -161.963769) (xy 64.329611 -161.989082) (xy 64.303148 -161.998406) (xy 64.293283 -162.002247)
			(xy 64.277648 -162.016486) (xy 64.269123 -162.035838) (xy 64.268604 -162.046412) (xy 64.268604 -172.804074)
			(xy 64.268138 -172.828079) (xy 64.260594 -172.875492) (xy 64.24572 -172.921139) (xy 64.223883 -172.963895)
			(xy 64.195621 -173.002704) (xy 64.178942 -173.019974) (xy 63.938658 -173.260258) (xy 63.921391 -173.276939)
			(xy 63.882576 -173.305193) (xy 63.83982 -173.327027) (xy 63.794173 -173.341902) (xy 63.746762 -173.349453)
			(xy 63.722758 -173.34992) (xy 61.330332 -173.34992) (xy 61.306328 -173.349445) (xy 61.258915 -173.341903)
			(xy 61.213268 -173.327031) (xy 61.170512 -173.305196) (xy 61.131702 -173.276936) (xy 61.114432 -173.260258)
			(xy 60.333128 -172.478954) (xy 60.316536 -172.461656) (xy 60.288369 -172.422877) (xy 60.2666 -172.380177)
			(xy 60.251762 -172.334603) (xy 60.244219 -172.287272) (xy 60.24372 -172.263308) (xy 60.24372 -151.313134)
			(xy 60.243298 -151.303064) (xy 60.235577 -151.284465) (xy 60.228734 -151.277066) (xy 52.6796 -143.728186)
			(xy 52.672196 -143.721352) (xy 52.6536 -143.713629) (xy 52.643532 -143.7132) (xy 52.128928 -143.7132)
			(xy 52.105597 -143.712693) (xy 52.059489 -143.70552) (xy 52.015009 -143.691414) (xy 51.973194 -143.670702)
			(xy 51.935018 -143.643868) (xy 51.901371 -143.611537) (xy 51.873036 -143.574462) (xy 51.861466 -143.554196)
			(xy 51.853824 -143.541124) (xy 51.833454 -143.518733) (xy 51.808381 -143.501773) (xy 51.780017 -143.4912)
			(xy 51.74996 -143.487607) (xy 51.719903 -143.4912) (xy 51.691539 -143.501773) (xy 51.666466 -143.518733)
			(xy 51.646096 -143.541124) (xy 51.638454 -143.554196) (xy 51.626894 -143.574468) (xy 51.598558 -143.611547)
			(xy 51.56491 -143.643882) (xy 51.526733 -143.670719) (xy 51.484917 -143.691434) (xy 51.440435 -143.705544)
			(xy 51.394324 -143.71272) (xy 51.370992 -143.7132) (xy 45.502068 -143.7132) (xy 45.489532 -143.71391)
			(xy 45.467425 -143.725752) (xy 45.459904 -143.735806) (xy 45.412914 -143.80591) (xy 45.406438 -143.816721)
			(xy 45.403917 -143.841769) (xy 45.408088 -143.853662) (xy 45.417331 -143.876934) (xy 45.430345 -143.925287)
			(xy 45.436905 -143.974929) (xy 45.437298 -143.999966) (xy 45.436835 -144.026547) (xy 45.429452 -144.079195)
			(xy 45.414826 -144.130306) (xy 45.393239 -144.178888) (xy 45.365111 -144.224) (xy 45.330987 -144.264765)
			(xy 45.311568 -144.282922) (xy 45.304979 -144.289398) (xy 45.296513 -144.305803) (xy 45.295058 -144.314926)
			(xy 45.287692 -144.381474) (xy 45.286951 -144.39065) (xy 45.291393 -144.4085) (xy 45.296328 -144.416272)
			(xy 45.312439 -144.4404) (xy 45.337976 -144.492493) (xy 45.355334 -144.54785) (xy 45.364113 -144.605197)
			(xy 45.364654 -144.634204) (xy 45.364126 -144.661453) (xy 45.35637 -144.715397) (xy 45.341017 -144.767688)
			(xy 45.318379 -144.817262) (xy 45.288916 -144.863111) (xy 45.253229 -144.9043) (xy 45.212044 -144.939991)
			(xy 45.166199 -144.969458) (xy 45.116628 -144.992102) (xy 45.064338 -145.007461) (xy 45.010395 -145.015223)
			(xy 44.983146 -145.015712) (xy 44.982638 -145.015712) (xy 44.972841 -145.015644) (xy 44.953273 -145.014629)
			(xy 44.943522 -145.01368) (xy 44.943268 -145.01368) (xy 44.933878 -145.013094) (xy 44.915742 -145.018044)
			(xy 44.907962 -145.023332) (xy 44.84497 -145.070068) (xy 44.835064 -145.08607) (xy 44.833286 -145.095722)
			(xy 44.827837 -145.121546) (xy 44.81091 -145.171534) (xy 44.787254 -145.218711) (xy 44.757323 -145.262178)
			(xy 44.721687 -145.301105) (xy 44.681025 -145.334749) (xy 44.636115 -145.362469) (xy 44.587814 -145.383734)
			(xy 44.537042 -145.39814) (xy 44.48477 -145.405411) (xy 44.458382 -145.405856) (xy 44.430833 -145.40536)
			(xy 44.376305 -145.397444) (xy 44.323485 -145.381765) (xy 44.273469 -145.35865) (xy 44.227301 -145.328578)
			(xy 44.185939 -145.292177) (xy 44.150245 -145.250203) (xy 44.120961 -145.20353) (xy 44.109386 -145.178526)
			(xy 44.105576 -145.16989) (xy 44.092114 -145.156428) (xy 44.01185 -145.121122) (xy 43.993308 -145.120106)
			(xy 43.984418 -145.1229) (xy 43.983402 -145.123408) (xy 43.968416 -145.128234) (xy 43.959545 -145.131213)
			(xy 43.944569 -145.142409) (xy 43.939206 -145.150078) (xy 43.898312 -145.215356) (xy 43.894756 -145.233136)
			(xy 43.89628 -145.24228) (xy 43.89628 -145.242788) (xy 43.898764 -145.258418) (xy 43.901433 -145.289955)
			(xy 43.901614 -145.30578) (xy 43.901128 -145.333031) (xy 43.893372 -145.386979) (xy 43.878017 -145.439274)
			(xy 43.855375 -145.488851) (xy 43.825909 -145.534701) (xy 43.790218 -145.575892) (xy 43.749027 -145.611583)
			(xy 43.703177 -145.641049) (xy 43.6536 -145.663691) (xy 43.601305 -145.679046) (xy 43.547357 -145.686802)
			(xy 43.492855 -145.686802) (xy 43.438907 -145.679046) (xy 43.386612 -145.663691) (xy 43.337035 -145.641049)
			(xy 43.291185 -145.611583) (xy 43.249994 -145.575892) (xy 43.214303 -145.534701) (xy 43.184837 -145.488851)
			(xy 43.162195 -145.439274) (xy 43.14684 -145.386979) (xy 43.139084 -145.333031) (xy 43.138598 -145.30578)
			(xy 43.139069 -145.278446) (xy 43.146849 -145.224334) (xy 43.162276 -145.171887) (xy 43.185033 -145.12218)
			(xy 43.214654 -145.076232) (xy 43.250532 -145.034984) (xy 43.291932 -144.999282) (xy 43.338006 -144.969856)
			(xy 43.387809 -144.947311) (xy 43.413934 -144.939258) (xy 43.422799 -144.936263) (xy 43.437779 -144.925079)
			(xy 43.443144 -144.917414) (xy 43.484038 -144.852136) (xy 43.487594 -144.834356) (xy 43.48607 -144.825212)
			(xy 43.48607 -144.824704) (xy 43.483585 -144.809074) (xy 43.480916 -144.777537) (xy 43.480736 -144.761712)
			(xy 43.481167 -144.734457) (xy 43.488923 -144.680503) (xy 43.50428 -144.628202) (xy 43.526924 -144.578619)
			(xy 43.556395 -144.532764) (xy 43.592092 -144.49157) (xy 43.633289 -144.455876) (xy 43.679147 -144.426409)
			(xy 43.728732 -144.403769) (xy 43.781034 -144.388416) (xy 43.834989 -144.380664) (xy 43.862244 -144.380204)
			(xy 43.874215 -144.380314) (xy 43.898108 -144.381841) (xy 43.909996 -144.383252) (xy 43.91025 -144.383252)
			(xy 43.919424 -144.383939) (xy 43.937265 -144.37952) (xy 43.945048 -144.374616) (xy 44.001182 -144.3355)
			(xy 44.008599 -144.32993) (xy 44.019139 -144.314682) (xy 44.021756 -144.305782) (xy 44.021756 -144.305528)
			(xy 44.028689 -144.277959) (xy 44.049728 -144.225149) (xy 44.078374 -144.176046) (xy 44.113991 -144.13174)
			(xy 44.15579 -144.093212) (xy 44.202845 -144.061316) (xy 44.254114 -144.036758) (xy 44.308461 -144.020082)
			(xy 44.36468 -144.011659) (xy 44.393104 -144.011142) (xy 44.417775 -144.011568) (xy 44.466701 -144.017963)
			(xy 44.514395 -144.030607) (xy 44.537376 -144.03959) (xy 44.548486 -144.043465) (xy 44.571921 -144.041763)
			(xy 44.582334 -144.036288) (xy 44.652184 -143.994632) (xy 44.661971 -143.988174) (xy 44.674817 -143.968592)
			(xy 44.676822 -143.95704) (xy 44.676822 -143.956532) (xy 44.680296 -143.930088) (xy 44.693676 -143.878461)
			(xy 44.703492 -143.853662) (xy 44.70773 -143.841781) (xy 44.705179 -143.816715) (xy 44.698666 -143.80591)
			(xy 44.651676 -143.735806) (xy 44.644199 -143.725701) (xy 44.622067 -143.713845) (xy 44.609512 -143.7132)
			(xy 41.57472 -143.7132) (xy 41.564648 -143.71361) (xy 41.546049 -143.721339) (xy 41.538652 -143.728186)
			(xy 39.321994 -145.94459) (xy 39.315165 -145.951999) (xy 39.307439 -145.970591) (xy 39.307008 -145.980658)
			(xy 39.307008 -146.739864) (xy 48.909984 -146.739864) (xy 48.914055 -146.684242) (xy 48.926181 -146.629805)
			(xy 48.946104 -146.577714) (xy 48.9734 -146.529079) (xy 49.007486 -146.484936) (xy 49.047635 -146.446227)
			(xy 49.092993 -146.413776) (xy 49.142593 -146.388275) (xy 49.195377 -146.370268) (xy 49.25022 -146.360138)
			(xy 49.305954 -146.358101) (xy 49.361391 -146.364201) (xy 49.415348 -146.378307) (xy 49.466677 -146.400119)
			(xy 49.514283 -146.429173) (xy 49.557151 -146.464848) (xy 49.594368 -146.506385) (xy 49.625141 -146.552898)
			(xy 49.648813 -146.603395) (xy 49.664881 -146.656802) (xy 49.673001 -146.711978) (xy 49.67351 -146.739864)
			(xy 49.673001 -146.76775) (xy 49.668844 -146.795998) (xy 50.543712 -146.795998) (xy 50.547783 -146.740376)
			(xy 50.559909 -146.685939) (xy 50.579832 -146.633848) (xy 50.607128 -146.585213) (xy 50.641214 -146.54107)
			(xy 50.681363 -146.502361) (xy 50.726721 -146.46991) (xy 50.776321 -146.444409) (xy 50.829105 -146.426402)
			(xy 50.883948 -146.416272) (xy 50.939682 -146.414235) (xy 50.995119 -146.420335) (xy 51.049076 -146.434441)
			(xy 51.100405 -146.456253) (xy 51.148011 -146.485307) (xy 51.190879 -146.520982) (xy 51.228096 -146.562519)
			(xy 51.258869 -146.609032) (xy 51.282541 -146.659529) (xy 51.298609 -146.712936) (xy 51.306729 -146.768112)
			(xy 51.307238 -146.795998) (xy 51.306729 -146.823884) (xy 51.298609 -146.87906) (xy 51.282541 -146.932467)
			(xy 51.258869 -146.982964) (xy 51.228096 -147.029477) (xy 51.190879 -147.071014) (xy 51.148011 -147.106689)
			(xy 51.100405 -147.135743) (xy 51.049076 -147.157555) (xy 50.995119 -147.171661) (xy 50.939682 -147.177761)
			(xy 50.883948 -147.175724) (xy 50.829105 -147.165594) (xy 50.776321 -147.147587) (xy 50.726721 -147.122086)
			(xy 50.681363 -147.089635) (xy 50.641214 -147.050926) (xy 50.607128 -147.006783) (xy 50.579832 -146.958148)
			(xy 50.559909 -146.906057) (xy 50.547783 -146.85162) (xy 50.543712 -146.795998) (xy 49.668844 -146.795998)
			(xy 49.664881 -146.822926) (xy 49.648813 -146.876333) (xy 49.625141 -146.92683) (xy 49.594368 -146.973343)
			(xy 49.557151 -147.01488) (xy 49.514283 -147.050555) (xy 49.466677 -147.079609) (xy 49.415348 -147.101421)
			(xy 49.361391 -147.115527) (xy 49.305954 -147.121627) (xy 49.25022 -147.11959) (xy 49.195377 -147.10946)
			(xy 49.142593 -147.091453) (xy 49.092993 -147.065952) (xy 49.047635 -147.033501) (xy 49.007486 -146.994792)
			(xy 48.9734 -146.950649) (xy 48.946104 -146.902014) (xy 48.926181 -146.849923) (xy 48.914055 -146.795486)
			(xy 48.909984 -146.739864) (xy 39.307008 -146.739864) (xy 39.307008 -150.08733) (xy 56.079388 -150.08733)
			(xy 56.083459 -150.031708) (xy 56.095585 -149.977271) (xy 56.115508 -149.92518) (xy 56.142804 -149.876545)
			(xy 56.17689 -149.832402) (xy 56.217039 -149.793693) (xy 56.262397 -149.761242) (xy 56.311997 -149.735741)
			(xy 56.364781 -149.717734) (xy 56.419624 -149.707604) (xy 56.475358 -149.705567) (xy 56.530795 -149.711667)
			(xy 56.584752 -149.725773) (xy 56.636081 -149.747585) (xy 56.683687 -149.776639) (xy 56.726555 -149.812314)
			(xy 56.763772 -149.853851) (xy 56.794545 -149.900364) (xy 56.818217 -149.950861) (xy 56.834285 -150.004268)
			(xy 56.842405 -150.059444) (xy 56.842914 -150.08733) (xy 56.842405 -150.115216) (xy 56.834285 -150.170392)
			(xy 56.818217 -150.223799) (xy 56.794545 -150.274296) (xy 56.763772 -150.320809) (xy 56.726555 -150.362346)
			(xy 56.683687 -150.398021) (xy 56.636081 -150.427075) (xy 56.584752 -150.448887) (xy 56.530795 -150.462993)
			(xy 56.475358 -150.469093) (xy 56.419624 -150.467056) (xy 56.364781 -150.456926) (xy 56.311997 -150.438919)
			(xy 56.262397 -150.413418) (xy 56.217039 -150.380967) (xy 56.17689 -150.342258) (xy 56.142804 -150.298115)
			(xy 56.115508 -150.24948) (xy 56.095585 -150.197389) (xy 56.083459 -150.142952) (xy 56.079388 -150.08733)
			(xy 39.307008 -150.08733) (xy 39.307008 -151.257) (xy 52.576982 -151.257) (xy 52.581053 -151.201378)
			(xy 52.593179 -151.146941) (xy 52.613102 -151.09485) (xy 52.640398 -151.046215) (xy 52.674484 -151.002072)
			(xy 52.714633 -150.963363) (xy 52.759991 -150.930912) (xy 52.809591 -150.905411) (xy 52.862375 -150.887404)
			(xy 52.917218 -150.877274) (xy 52.972952 -150.875237) (xy 53.028389 -150.881337) (xy 53.082346 -150.895443)
			(xy 53.133675 -150.917255) (xy 53.181281 -150.946309) (xy 53.224149 -150.981984) (xy 53.261366 -151.023521)
			(xy 53.292139 -151.070034) (xy 53.315811 -151.120531) (xy 53.317284 -151.125428) (xy 55.928004 -151.125428)
			(xy 55.932075 -151.069806) (xy 55.944201 -151.015369) (xy 55.964124 -150.963278) (xy 55.99142 -150.914643)
			(xy 56.025506 -150.8705) (xy 56.065655 -150.831791) (xy 56.111013 -150.79934) (xy 56.160613 -150.773839)
			(xy 56.213397 -150.755832) (xy 56.26824 -150.745702) (xy 56.323974 -150.743665) (xy 56.379411 -150.749765)
			(xy 56.433368 -150.763871) (xy 56.484697 -150.785683) (xy 56.532303 -150.814737) (xy 56.575171 -150.850412)
			(xy 56.612388 -150.891949) (xy 56.643161 -150.938462) (xy 56.666833 -150.988959) (xy 56.682901 -151.042366)
			(xy 56.691021 -151.097542) (xy 56.69153 -151.125428) (xy 56.691021 -151.153314) (xy 56.682901 -151.20849)
			(xy 56.666833 -151.261897) (xy 56.643161 -151.312394) (xy 56.612388 -151.358907) (xy 56.575171 -151.400444)
			(xy 56.532303 -151.436119) (xy 56.484697 -151.465173) (xy 56.433368 -151.486985) (xy 56.379411 -151.501091)
			(xy 56.323974 -151.507191) (xy 56.26824 -151.505154) (xy 56.213397 -151.495024) (xy 56.160613 -151.477017)
			(xy 56.111013 -151.451516) (xy 56.065655 -151.419065) (xy 56.025506 -151.380356) (xy 55.99142 -151.336213)
			(xy 55.964124 -151.287578) (xy 55.944201 -151.235487) (xy 55.932075 -151.18105) (xy 55.928004 -151.125428)
			(xy 53.317284 -151.125428) (xy 53.331879 -151.173938) (xy 53.339999 -151.229114) (xy 53.340508 -151.257)
			(xy 53.339999 -151.284886) (xy 53.331879 -151.340062) (xy 53.315811 -151.393469) (xy 53.292139 -151.443966)
			(xy 53.261366 -151.490479) (xy 53.224149 -151.532016) (xy 53.181281 -151.567691) (xy 53.133675 -151.596745)
			(xy 53.082346 -151.618557) (xy 53.028389 -151.632663) (xy 52.972952 -151.638763) (xy 52.917218 -151.636726)
			(xy 52.862375 -151.626596) (xy 52.809591 -151.608589) (xy 52.759991 -151.583088) (xy 52.714633 -151.550637)
			(xy 52.674484 -151.511928) (xy 52.640398 -151.467785) (xy 52.613102 -151.41915) (xy 52.593179 -151.367059)
			(xy 52.581053 -151.312622) (xy 52.576982 -151.257) (xy 39.307008 -151.257) (xy 39.307008 -153.108152)
			(xy 39.307457 -153.118219) (xy 39.315161 -153.136817) (xy 39.321994 -153.14422) (xy 39.737882 -153.560018)
			(xy 52.449982 -153.560018) (xy 52.454053 -153.504396) (xy 52.466179 -153.449959) (xy 52.486102 -153.397868)
			(xy 52.513398 -153.349233) (xy 52.547484 -153.30509) (xy 52.587633 -153.266381) (xy 52.632991 -153.23393)
			(xy 52.682591 -153.208429) (xy 52.735375 -153.190422) (xy 52.790218 -153.180292) (xy 52.845952 -153.178255)
			(xy 52.901389 -153.184355) (xy 52.955346 -153.198461) (xy 53.006675 -153.220273) (xy 53.054281 -153.249327)
			(xy 53.097149 -153.285002) (xy 53.134366 -153.326539) (xy 53.165139 -153.373052) (xy 53.188811 -153.423549)
			(xy 53.204879 -153.476956) (xy 53.212999 -153.532132) (xy 53.213508 -153.560018) (xy 53.212999 -153.587904)
			(xy 53.204879 -153.64308) (xy 53.188811 -153.696487) (xy 53.165139 -153.746984) (xy 53.134366 -153.793497)
			(xy 53.097149 -153.835034) (xy 53.054281 -153.870709) (xy 53.006675 -153.899763) (xy 52.955346 -153.921575)
			(xy 52.901389 -153.935681) (xy 52.845952 -153.941781) (xy 52.790218 -153.939744) (xy 52.735375 -153.929614)
			(xy 52.682591 -153.911607) (xy 52.632991 -153.886106) (xy 52.587633 -153.853655) (xy 52.547484 -153.814946)
			(xy 52.513398 -153.770803) (xy 52.486102 -153.722168) (xy 52.466179 -153.670077) (xy 52.454053 -153.61564)
			(xy 52.449982 -153.560018) (xy 39.737882 -153.560018) (xy 40.33796 -154.159966) (xy 51.306982 -154.159966)
			(xy 51.311053 -154.104344) (xy 51.323179 -154.049907) (xy 51.343102 -153.997816) (xy 51.370398 -153.949181)
			(xy 51.404484 -153.905038) (xy 51.444633 -153.866329) (xy 51.489991 -153.833878) (xy 51.539591 -153.808377)
			(xy 51.592375 -153.79037) (xy 51.647218 -153.78024) (xy 51.702952 -153.778203) (xy 51.758389 -153.784303)
			(xy 51.812346 -153.798409) (xy 51.863675 -153.820221) (xy 51.911281 -153.849275) (xy 51.954149 -153.88495)
			(xy 51.991366 -153.926487) (xy 52.022139 -153.973) (xy 52.045811 -154.023497) (xy 52.061879 -154.076904)
			(xy 52.069999 -154.13208) (xy 52.070508 -154.159966) (xy 52.069999 -154.187852) (xy 52.061879 -154.243028)
			(xy 52.045811 -154.296435) (xy 52.022139 -154.346932) (xy 51.991366 -154.393445) (xy 51.954149 -154.434982)
			(xy 51.911281 -154.470657) (xy 51.863675 -154.499711) (xy 51.812346 -154.521523) (xy 51.758389 -154.535629)
			(xy 51.702952 -154.541729) (xy 51.647218 -154.539692) (xy 51.592375 -154.529562) (xy 51.539591 -154.511555)
			(xy 51.489991 -154.486054) (xy 51.444633 -154.453603) (xy 51.404484 -154.414894) (xy 51.370398 -154.370751)
			(xy 51.343102 -154.322116) (xy 51.323179 -154.270025) (xy 51.311053 -154.215588) (xy 51.306982 -154.159966)
			(xy 40.33796 -154.159966) (xy 40.495474 -154.317446) (xy 40.502923 -154.324215) (xy 40.52149 -154.33193)
			(xy 40.531542 -154.332432) (xy 48.769016 -154.332432) (xy 48.793022 -154.332861) (xy 48.840437 -154.340413)
			(xy 48.886086 -154.355295) (xy 48.928841 -154.37714) (xy 48.967648 -154.405411) (xy 48.984916 -154.422094)
			(xy 49.52111 -154.958288) (xy 52.744114 -154.958288) (xy 52.748185 -154.902666) (xy 52.760311 -154.848229)
			(xy 52.780234 -154.796138) (xy 52.80753 -154.747503) (xy 52.841616 -154.70336) (xy 52.881765 -154.664651)
			(xy 52.927123 -154.6322) (xy 52.976723 -154.606699) (xy 53.029507 -154.588692) (xy 53.08435 -154.578562)
			(xy 53.140084 -154.576525) (xy 53.195521 -154.582625) (xy 53.249478 -154.596731) (xy 53.300807 -154.618543)
			(xy 53.348413 -154.647597) (xy 53.391281 -154.683272) (xy 53.428498 -154.724809) (xy 53.459271 -154.771322)
			(xy 53.482943 -154.821819) (xy 53.499011 -154.875226) (xy 53.507131 -154.930402) (xy 53.50764 -154.958288)
			(xy 53.507131 -154.986174) (xy 53.499011 -155.04135) (xy 53.482943 -155.094757) (xy 53.459271 -155.145254)
			(xy 53.428498 -155.191767) (xy 53.391281 -155.233304) (xy 53.348413 -155.268979) (xy 53.300807 -155.298033)
			(xy 53.249478 -155.319845) (xy 53.195521 -155.333951) (xy 53.140084 -155.340051) (xy 53.08435 -155.338014)
			(xy 53.029507 -155.327884) (xy 52.976723 -155.309877) (xy 52.927123 -155.284376) (xy 52.881765 -155.251925)
			(xy 52.841616 -155.213216) (xy 52.80753 -155.169073) (xy 52.780234 -155.120438) (xy 52.760311 -155.068347)
			(xy 52.748185 -155.01391) (xy 52.744114 -154.958288) (xy 49.52111 -154.958288) (xy 49.76622 -155.203398)
			(xy 49.782845 -155.220666) (xy 49.811006 -155.259454) (xy 49.832767 -155.302161) (xy 49.847598 -155.347742)
			(xy 49.855133 -155.395078) (xy 49.855628 -155.419044) (xy 49.855628 -155.598368) (xy 51.368196 -155.598368)
			(xy 51.372267 -155.542746) (xy 51.384393 -155.488309) (xy 51.404316 -155.436218) (xy 51.431612 -155.387583)
			(xy 51.465698 -155.34344) (xy 51.505847 -155.304731) (xy 51.551205 -155.27228) (xy 51.600805 -155.246779)
			(xy 51.653589 -155.228772) (xy 51.708432 -155.218642) (xy 51.764166 -155.216605) (xy 51.819603 -155.222705)
			(xy 51.87356 -155.236811) (xy 51.924889 -155.258623) (xy 51.972495 -155.287677) (xy 52.015363 -155.323352)
			(xy 52.05258 -155.364889) (xy 52.083353 -155.411402) (xy 52.107025 -155.461899) (xy 52.123093 -155.515306)
			(xy 52.131213 -155.570482) (xy 52.131722 -155.598368) (xy 52.131213 -155.626254) (xy 52.123093 -155.68143)
			(xy 52.107025 -155.734837) (xy 52.083353 -155.785334) (xy 52.05258 -155.831847) (xy 52.015363 -155.873384)
			(xy 51.972495 -155.909059) (xy 51.924889 -155.938113) (xy 51.87356 -155.959925) (xy 51.819603 -155.974031)
			(xy 51.764166 -155.980131) (xy 51.708432 -155.978094) (xy 51.653589 -155.967964) (xy 51.600805 -155.949957)
			(xy 51.551205 -155.924456) (xy 51.505847 -155.892005) (xy 51.465698 -155.853296) (xy 51.431612 -155.809153)
			(xy 51.404316 -155.760518) (xy 51.384393 -155.708427) (xy 51.372267 -155.65399) (xy 51.368196 -155.598368)
			(xy 49.855628 -155.598368) (xy 49.855628 -156.544518) (xy 52.727858 -156.544518) (xy 52.731929 -156.488896)
			(xy 52.744055 -156.434459) (xy 52.763978 -156.382368) (xy 52.791274 -156.333733) (xy 52.82536 -156.28959)
			(xy 52.865509 -156.250881) (xy 52.910867 -156.21843) (xy 52.960467 -156.192929) (xy 53.013251 -156.174922)
			(xy 53.068094 -156.164792) (xy 53.123828 -156.162755) (xy 53.179265 -156.168855) (xy 53.233222 -156.182961)
			(xy 53.284551 -156.204773) (xy 53.332157 -156.233827) (xy 53.375025 -156.269502) (xy 53.412242 -156.311039)
			(xy 53.443015 -156.357552) (xy 53.466687 -156.408049) (xy 53.482755 -156.461456) (xy 53.490875 -156.516632)
			(xy 53.491384 -156.544518) (xy 53.490875 -156.572404) (xy 53.482755 -156.62758) (xy 53.466687 -156.680987)
			(xy 53.443015 -156.731484) (xy 53.412242 -156.777997) (xy 53.375025 -156.819534) (xy 53.332157 -156.855209)
			(xy 53.284551 -156.884263) (xy 53.233222 -156.906075) (xy 53.179265 -156.920181) (xy 53.123828 -156.926281)
			(xy 53.068094 -156.924244) (xy 53.013251 -156.914114) (xy 52.960467 -156.896107) (xy 52.910867 -156.870606)
			(xy 52.865509 -156.838155) (xy 52.82536 -156.799446) (xy 52.791274 -156.755303) (xy 52.763978 -156.706668)
			(xy 52.744055 -156.654577) (xy 52.731929 -156.60014) (xy 52.727858 -156.544518) (xy 49.855628 -156.544518)
			(xy 49.855628 -157.0736) (xy 51.296822 -157.0736) (xy 51.300893 -157.017978) (xy 51.313019 -156.963541)
			(xy 51.332942 -156.91145) (xy 51.360238 -156.862815) (xy 51.394324 -156.818672) (xy 51.434473 -156.779963)
			(xy 51.479831 -156.747512) (xy 51.529431 -156.722011) (xy 51.582215 -156.704004) (xy 51.637058 -156.693874)
			(xy 51.692792 -156.691837) (xy 51.748229 -156.697937) (xy 51.802186 -156.712043) (xy 51.853515 -156.733855)
			(xy 51.901121 -156.762909) (xy 51.943989 -156.798584) (xy 51.981206 -156.840121) (xy 52.011979 -156.886634)
			(xy 52.035651 -156.937131) (xy 52.040792 -156.95422) (xy 55.582564 -156.95422) (xy 55.586635 -156.898598)
			(xy 55.598761 -156.844161) (xy 55.618684 -156.79207) (xy 55.64598 -156.743435) (xy 55.680066 -156.699292)
			(xy 55.720215 -156.660583) (xy 55.765573 -156.628132) (xy 55.815173 -156.602631) (xy 55.867957 -156.584624)
			(xy 55.9228 -156.574494) (xy 55.978534 -156.572457) (xy 56.033971 -156.578557) (xy 56.087928 -156.592663)
			(xy 56.139257 -156.614475) (xy 56.186863 -156.643529) (xy 56.229731 -156.679204) (xy 56.266948 -156.720741)
			(xy 56.297721 -156.767254) (xy 56.321393 -156.817751) (xy 56.337461 -156.871158) (xy 56.345581 -156.926334)
			(xy 56.34609 -156.95422) (xy 56.345581 -156.982106) (xy 56.337461 -157.037282) (xy 56.321393 -157.090689)
			(xy 56.297721 -157.141186) (xy 56.266948 -157.187699) (xy 56.229731 -157.229236) (xy 56.186863 -157.264911)
			(xy 56.139257 -157.293965) (xy 56.087928 -157.315777) (xy 56.033971 -157.329883) (xy 55.978534 -157.335983)
			(xy 55.9228 -157.333946) (xy 55.867957 -157.323816) (xy 55.815173 -157.305809) (xy 55.765573 -157.280308)
			(xy 55.720215 -157.247857) (xy 55.680066 -157.209148) (xy 55.64598 -157.165005) (xy 55.618684 -157.11637)
			(xy 55.598761 -157.064279) (xy 55.586635 -157.009842) (xy 55.582564 -156.95422) (xy 52.040792 -156.95422)
			(xy 52.051719 -156.990538) (xy 52.059839 -157.045714) (xy 52.060348 -157.0736) (xy 52.059839 -157.101486)
			(xy 52.051719 -157.156662) (xy 52.035651 -157.210069) (xy 52.011979 -157.260566) (xy 51.981206 -157.307079)
			(xy 51.943989 -157.348616) (xy 51.901121 -157.384291) (xy 51.853515 -157.413345) (xy 51.802186 -157.435157)
			(xy 51.748229 -157.449263) (xy 51.692792 -157.455363) (xy 51.637058 -157.453326) (xy 51.582215 -157.443196)
			(xy 51.529431 -157.425189) (xy 51.479831 -157.399688) (xy 51.434473 -157.367237) (xy 51.394324 -157.328528)
			(xy 51.360238 -157.284385) (xy 51.332942 -157.23575) (xy 51.313019 -157.183659) (xy 51.300893 -157.129222)
			(xy 51.296822 -157.0736) (xy 49.855628 -157.0736) (xy 49.855628 -157.735016) (xy 49.855197 -157.758988)
			(xy 49.847698 -157.806343) (xy 49.832871 -157.851937) (xy 49.816456 -157.884114) (xy 52.587142 -157.884114)
			(xy 52.591213 -157.828492) (xy 52.603339 -157.774055) (xy 52.623262 -157.721964) (xy 52.650558 -157.673329)
			(xy 52.684644 -157.629186) (xy 52.724793 -157.590477) (xy 52.770151 -157.558026) (xy 52.819751 -157.532525)
			(xy 52.872535 -157.514518) (xy 52.927378 -157.504388) (xy 52.983112 -157.502351) (xy 53.038549 -157.508451)
			(xy 53.092506 -157.522557) (xy 53.143835 -157.544369) (xy 53.191441 -157.573423) (xy 53.234309 -157.609098)
			(xy 53.271526 -157.650635) (xy 53.302299 -157.697148) (xy 53.325971 -157.747645) (xy 53.342039 -157.801052)
			(xy 53.350159 -157.856228) (xy 53.350668 -157.884114) (xy 53.350159 -157.912) (xy 53.342039 -157.967176)
			(xy 53.325971 -158.020583) (xy 53.302299 -158.07108) (xy 53.271526 -158.117593) (xy 53.234309 -158.15913)
			(xy 53.191441 -158.194805) (xy 53.143835 -158.223859) (xy 53.092506 -158.245671) (xy 53.038549 -158.259777)
			(xy 52.983112 -158.265877) (xy 52.927378 -158.26384) (xy 52.872535 -158.25371) (xy 52.819751 -158.235703)
			(xy 52.770151 -158.210202) (xy 52.724793 -158.177751) (xy 52.684644 -158.139042) (xy 52.650558 -158.094899)
			(xy 52.623262 -158.046264) (xy 52.603339 -157.994173) (xy 52.591213 -157.939736) (xy 52.587142 -157.884114)
			(xy 49.816456 -157.884114) (xy 49.811083 -157.894645) (xy 49.782872 -157.933411) (xy 49.76622 -157.950662)
			(xy 48.560228 -159.156654) (xy 48.542929 -159.173301) (xy 48.504123 -159.201559) (xy 48.461375 -159.2234)
			(xy 48.415736 -159.238283) (xy 48.36833 -159.245844) (xy 48.344328 -159.246316) (xy 47.408592 -159.246316)
			(xy 47.398478 -159.246716) (xy 47.379805 -159.254498) (xy 47.365561 -159.268861) (xy 47.361348 -159.278066)
			(xy 47.3202 -159.379412) (xy 47.326296 -159.409638) (xy 47.337472 -159.42056) (xy 47.370074 -159.453001)
			(xy 47.430183 -159.522623) (xy 47.484079 -159.597159) (xy 47.531361 -159.676055) (xy 47.57168 -159.758728)
			(xy 47.604735 -159.844563) (xy 47.630282 -159.932924) (xy 47.634896 -159.956246) (xy 55.562752 -159.956246)
			(xy 55.566823 -159.900624) (xy 55.578949 -159.846187) (xy 55.598872 -159.794096) (xy 55.626168 -159.745461)
			(xy 55.660254 -159.701318) (xy 55.700403 -159.662609) (xy 55.745761 -159.630158) (xy 55.795361 -159.604657)
			(xy 55.848145 -159.58665) (xy 55.902988 -159.57652) (xy 55.958722 -159.574483) (xy 56.014159 -159.580583)
			(xy 56.068116 -159.594689) (xy 56.119445 -159.616501) (xy 56.167051 -159.645555) (xy 56.209919 -159.68123)
			(xy 56.247136 -159.722767) (xy 56.277909 -159.76928) (xy 56.301581 -159.819777) (xy 56.317649 -159.873184)
			(xy 56.325769 -159.92836) (xy 56.326278 -159.956246) (xy 56.325769 -159.984132) (xy 56.317649 -160.039308)
			(xy 56.301581 -160.092715) (xy 56.277909 -160.143212) (xy 56.247136 -160.189725) (xy 56.209919 -160.231262)
			(xy 56.167051 -160.266937) (xy 56.119445 -160.295991) (xy 56.068116 -160.317803) (xy 56.014159 -160.331909)
			(xy 55.958722 -160.338009) (xy 55.902988 -160.335972) (xy 55.848145 -160.325842) (xy 55.795361 -160.307835)
			(xy 55.745761 -160.282334) (xy 55.700403 -160.249883) (xy 55.660254 -160.211174) (xy 55.626168 -160.167031)
			(xy 55.598872 -160.118396) (xy 55.578949 -160.066305) (xy 55.566823 -160.011868) (xy 55.562752 -159.956246)
			(xy 47.634896 -159.956246) (xy 47.648132 -160.023155) (xy 47.658151 -160.114588) (xy 47.660266 -160.206544)
			(xy 47.654461 -160.29834) (xy 47.640779 -160.389297) (xy 47.619321 -160.478739) (xy 47.590247 -160.566003)
			(xy 47.553772 -160.650442) (xy 47.510167 -160.731429) (xy 47.459755 -160.808364) (xy 47.40291 -160.880675)
			(xy 47.340054 -160.947828) (xy 47.271653 -161.009323) (xy 47.198215 -161.064704) (xy 47.120283 -161.113561)
			(xy 47.038437 -161.155531) (xy 46.953283 -161.190303) (xy 46.865453 -161.21762) (xy 46.775598 -161.237277)
			(xy 46.684385 -161.24913) (xy 46.59249 -161.253091) (xy 46.500595 -161.24913) (xy 46.409382 -161.237277)
			(xy 46.319527 -161.21762) (xy 46.231697 -161.190303) (xy 46.146543 -161.155531) (xy 46.064697 -161.113561)
			(xy 45.986765 -161.064704) (xy 45.913327 -161.009323) (xy 45.844926 -160.947828) (xy 45.78207 -160.880675)
			(xy 45.725225 -160.808364) (xy 45.674813 -160.731429) (xy 45.631208 -160.650442) (xy 45.594733 -160.566003)
			(xy 45.565659 -160.478739) (xy 45.544201 -160.389297) (xy 45.530519 -160.29834) (xy 45.524714 -160.206544)
			(xy 45.526829 -160.114588) (xy 45.536848 -160.023155) (xy 45.554698 -159.932924) (xy 45.580245 -159.844563)
			(xy 45.6133 -159.758728) (xy 45.653619 -159.676055) (xy 45.700901 -159.597159) (xy 45.754797 -159.522623)
			(xy 45.814906 -159.453001) (xy 45.847508 -159.42056) (xy 45.854303 -159.413178) (xy 45.862089 -159.394707)
			(xy 45.862242 -159.374663) (xy 45.858938 -159.365188) (xy 45.823632 -159.278066) (xy 45.819419 -159.268853)
			(xy 45.805204 -159.25445) (xy 45.786509 -159.246702) (xy 45.776388 -159.246316) (xy 37.064188 -159.246316)
			(xy 37.040183 -159.24587) (xy 36.992769 -159.238321) (xy 36.947121 -159.223442) (xy 36.904366 -159.2016)
			(xy 36.865557 -159.173334) (xy 36.848288 -159.156654) (xy 36.183062 -158.491428) (xy 36.166418 -158.474127)
			(xy 36.138158 -158.435322) (xy 36.116317 -158.392574) (xy 36.101433 -158.346935) (xy 36.093872 -158.29953)
			(xy 36.0934 -158.275528) (xy 9.536224 -158.275528) (xy 9.52409 -158.293869) (xy 9.486873 -158.335406)
			(xy 9.444005 -158.371081) (xy 9.396399 -158.400135) (xy 9.34507 -158.421947) (xy 9.291113 -158.436053)
			(xy 9.235676 -158.442153) (xy 9.179942 -158.440116) (xy 9.125099 -158.429986) (xy 9.072315 -158.411979)
			(xy 9.022715 -158.386478) (xy 8.977357 -158.354027) (xy 8.937208 -158.315318) (xy 8.903122 -158.271175)
			(xy 8.875826 -158.22254) (xy 8.855903 -158.170449) (xy 8.843777 -158.116012) (xy 8.839706 -158.06039)
			(xy 7.32214 -158.06039) (xy 7.297393 -158.08801) (xy 7.254525 -158.123685) (xy 7.206919 -158.152739)
			(xy 7.15559 -158.174551) (xy 7.101633 -158.188657) (xy 7.046196 -158.194757) (xy 6.990462 -158.19272)
			(xy 6.935619 -158.18259) (xy 6.882835 -158.164583) (xy 6.833235 -158.139082) (xy 6.787877 -158.106631)
			(xy 6.747728 -158.067922) (xy 6.713642 -158.023779) (xy 6.686346 -157.975144) (xy 6.666423 -157.923053)
			(xy 6.654297 -157.868616) (xy 6.650226 -157.812994) (xy 4.38404 -157.812994) (xy 4.38404 -158.828994)
			(xy 6.650226 -158.828994) (xy 6.654297 -158.773372) (xy 6.666423 -158.718935) (xy 6.686346 -158.666844)
			(xy 6.713642 -158.618209) (xy 6.747728 -158.574066) (xy 6.787877 -158.535357) (xy 6.833235 -158.502906)
			(xy 6.882835 -158.477405) (xy 6.935619 -158.459398) (xy 6.990462 -158.449268) (xy 7.046196 -158.447231)
			(xy 7.101633 -158.453331) (xy 7.15559 -158.467437) (xy 7.206919 -158.489249) (xy 7.254525 -158.518303)
			(xy 7.297393 -158.553978) (xy 7.33461 -158.595515) (xy 7.365383 -158.642028) (xy 7.389055 -158.692525)
			(xy 7.405123 -158.745932) (xy 7.406208 -158.753302) (xy 16.516602 -158.753302) (xy 16.520673 -158.69768)
			(xy 16.532799 -158.643243) (xy 16.552722 -158.591152) (xy 16.580018 -158.542517) (xy 16.614104 -158.498374)
			(xy 16.654253 -158.459665) (xy 16.699611 -158.427214) (xy 16.749211 -158.401713) (xy 16.801995 -158.383706)
			(xy 16.856838 -158.373576) (xy 16.912572 -158.371539) (xy 16.968009 -158.377639) (xy 17.021966 -158.391745)
			(xy 17.073295 -158.413557) (xy 17.120901 -158.442611) (xy 17.163769 -158.478286) (xy 17.200986 -158.519823)
			(xy 17.231759 -158.566336) (xy 17.255431 -158.616833) (xy 17.271499 -158.67024) (xy 17.279619 -158.725416)
			(xy 17.280128 -158.753302) (xy 17.279619 -158.781188) (xy 17.271499 -158.836364) (xy 17.255431 -158.889771)
			(xy 17.231759 -158.940268) (xy 17.200986 -158.986781) (xy 17.163769 -159.028318) (xy 17.120901 -159.063993)
			(xy 17.073295 -159.093047) (xy 17.021966 -159.114859) (xy 16.968009 -159.128965) (xy 16.912572 -159.135065)
			(xy 16.856838 -159.133028) (xy 16.801995 -159.122898) (xy 16.749211 -159.104891) (xy 16.699611 -159.07939)
			(xy 16.654253 -159.046939) (xy 16.614104 -159.00823) (xy 16.580018 -158.964087) (xy 16.552722 -158.915452)
			(xy 16.532799 -158.863361) (xy 16.520673 -158.808924) (xy 16.516602 -158.753302) (xy 7.406208 -158.753302)
			(xy 7.413243 -158.801108) (xy 7.413752 -158.828994) (xy 7.413243 -158.85688) (xy 7.405123 -158.912056)
			(xy 7.389055 -158.965463) (xy 7.365383 -159.01596) (xy 7.33461 -159.062473) (xy 7.297393 -159.10401)
			(xy 7.254525 -159.139685) (xy 7.206919 -159.168739) (xy 7.15559 -159.190551) (xy 7.101633 -159.204657)
			(xy 7.046196 -159.210757) (xy 6.990462 -159.20872) (xy 6.935619 -159.19859) (xy 6.882835 -159.180583)
			(xy 6.833235 -159.155082) (xy 6.787877 -159.122631) (xy 6.747728 -159.083922) (xy 6.713642 -159.039779)
			(xy 6.686346 -158.991144) (xy 6.666423 -158.939053) (xy 6.654297 -158.884616) (xy 6.650226 -158.828994)
			(xy 4.38404 -158.828994) (xy 4.38404 -159.439102) (xy 8.908032 -159.439102) (xy 8.912103 -159.38348)
			(xy 8.924229 -159.329043) (xy 8.944152 -159.276952) (xy 8.971448 -159.228317) (xy 9.005534 -159.184174)
			(xy 9.045683 -159.145465) (xy 9.091041 -159.113014) (xy 9.140641 -159.087513) (xy 9.193425 -159.069506)
			(xy 9.248268 -159.059376) (xy 9.304002 -159.057339) (xy 9.359439 -159.063439) (xy 9.413396 -159.077545)
			(xy 9.464725 -159.099357) (xy 9.512331 -159.128411) (xy 9.555199 -159.164086) (xy 9.592416 -159.205623)
			(xy 9.623189 -159.252136) (xy 9.646861 -159.302633) (xy 9.662929 -159.35604) (xy 9.671049 -159.411216)
			(xy 9.671558 -159.439102) (xy 9.671049 -159.466988) (xy 9.662929 -159.522164) (xy 9.660026 -159.531812)
			(xy 12.11275 -159.531812) (xy 12.116821 -159.47619) (xy 12.128947 -159.421753) (xy 12.14887 -159.369662)
			(xy 12.176166 -159.321027) (xy 12.210252 -159.276884) (xy 12.250401 -159.238175) (xy 12.295759 -159.205724)
			(xy 12.345359 -159.180223) (xy 12.398143 -159.162216) (xy 12.452986 -159.152086) (xy 12.50872 -159.150049)
			(xy 12.564157 -159.156149) (xy 12.618114 -159.170255) (xy 12.669443 -159.192067) (xy 12.717049 -159.221121)
			(xy 12.759917 -159.256796) (xy 12.797134 -159.298333) (xy 12.827907 -159.344846) (xy 12.851579 -159.395343)
			(xy 12.867647 -159.44875) (xy 12.873516 -159.488632) (xy 14.395956 -159.488632) (xy 14.400027 -159.43301)
			(xy 14.412153 -159.378573) (xy 14.432076 -159.326482) (xy 14.459372 -159.277847) (xy 14.493458 -159.233704)
			(xy 14.533607 -159.194995) (xy 14.578965 -159.162544) (xy 14.628565 -159.137043) (xy 14.681349 -159.119036)
			(xy 14.736192 -159.108906) (xy 14.791926 -159.106869) (xy 14.847363 -159.112969) (xy 14.90132 -159.127075)
			(xy 14.952649 -159.148887) (xy 15.000255 -159.177941) (xy 15.043123 -159.213616) (xy 15.08034 -159.255153)
			(xy 15.111113 -159.301666) (xy 15.134785 -159.352163) (xy 15.150853 -159.40557) (xy 15.158973 -159.460746)
			(xy 15.159482 -159.488632) (xy 15.158973 -159.516518) (xy 15.150853 -159.571694) (xy 15.134785 -159.625101)
			(xy 15.111113 -159.675598) (xy 15.08034 -159.722111) (xy 15.043123 -159.763648) (xy 15.000255 -159.799323)
			(xy 14.952649 -159.828377) (xy 14.90132 -159.850189) (xy 14.847363 -159.864295) (xy 14.791926 -159.870395)
			(xy 14.736192 -159.868358) (xy 14.681349 -159.858228) (xy 14.628565 -159.840221) (xy 14.578965 -159.81472)
			(xy 14.533607 -159.782269) (xy 14.493458 -159.74356) (xy 14.459372 -159.699417) (xy 14.432076 -159.650782)
			(xy 14.412153 -159.598691) (xy 14.400027 -159.544254) (xy 14.395956 -159.488632) (xy 12.873516 -159.488632)
			(xy 12.875767 -159.503926) (xy 12.876276 -159.531812) (xy 12.875767 -159.559698) (xy 12.867647 -159.614874)
			(xy 12.851579 -159.668281) (xy 12.827907 -159.718778) (xy 12.797134 -159.765291) (xy 12.759917 -159.806828)
			(xy 12.717049 -159.842503) (xy 12.669443 -159.871557) (xy 12.618114 -159.893369) (xy 12.564157 -159.907475)
			(xy 12.50872 -159.913575) (xy 12.452986 -159.911538) (xy 12.398143 -159.901408) (xy 12.345359 -159.883401)
			(xy 12.295759 -159.8579) (xy 12.250401 -159.825449) (xy 12.210252 -159.78674) (xy 12.176166 -159.742597)
			(xy 12.14887 -159.693962) (xy 12.128947 -159.641871) (xy 12.116821 -159.587434) (xy 12.11275 -159.531812)
			(xy 9.660026 -159.531812) (xy 9.646861 -159.575571) (xy 9.623189 -159.626068) (xy 9.592416 -159.672581)
			(xy 9.555199 -159.714118) (xy 9.512331 -159.749793) (xy 9.464725 -159.778847) (xy 9.413396 -159.800659)
			(xy 9.359439 -159.814765) (xy 9.304002 -159.820865) (xy 9.248268 -159.818828) (xy 9.193425 -159.808698)
			(xy 9.140641 -159.790691) (xy 9.091041 -159.76519) (xy 9.045683 -159.732739) (xy 9.005534 -159.69403)
			(xy 8.971448 -159.649887) (xy 8.944152 -159.601252) (xy 8.924229 -159.549161) (xy 8.912103 -159.494724)
			(xy 8.908032 -159.439102) (xy 4.38404 -159.439102) (xy 4.38404 -159.844994) (xy 6.650226 -159.844994)
			(xy 6.654297 -159.789372) (xy 6.666423 -159.734935) (xy 6.686346 -159.682844) (xy 6.713642 -159.634209)
			(xy 6.747728 -159.590066) (xy 6.787877 -159.551357) (xy 6.833235 -159.518906) (xy 6.882835 -159.493405)
			(xy 6.935619 -159.475398) (xy 6.990462 -159.465268) (xy 7.046196 -159.463231) (xy 7.101633 -159.469331)
			(xy 7.15559 -159.483437) (xy 7.206919 -159.505249) (xy 7.254525 -159.534303) (xy 7.297393 -159.569978)
			(xy 7.33461 -159.611515) (xy 7.365383 -159.658028) (xy 7.389055 -159.708525) (xy 7.405123 -159.761932)
			(xy 7.413243 -159.817108) (xy 7.413752 -159.844994) (xy 7.413243 -159.87288) (xy 7.405123 -159.928056)
			(xy 7.389055 -159.981463) (xy 7.365383 -160.03196) (xy 7.33461 -160.078473) (xy 7.297393 -160.12001)
			(xy 7.254525 -160.155685) (xy 7.206919 -160.184739) (xy 7.15559 -160.206551) (xy 7.101633 -160.220657)
			(xy 7.046196 -160.226757) (xy 6.990462 -160.22472) (xy 6.935619 -160.21459) (xy 6.882835 -160.196583)
			(xy 6.833235 -160.171082) (xy 6.787877 -160.138631) (xy 6.747728 -160.099922) (xy 6.713642 -160.055779)
			(xy 6.686346 -160.007144) (xy 6.666423 -159.955053) (xy 6.654297 -159.900616) (xy 6.650226 -159.844994)
			(xy 4.38404 -159.844994) (xy 4.38404 -160.965896) (xy 8.93775 -160.965896) (xy 8.941821 -160.910274)
			(xy 8.953947 -160.855837) (xy 8.97387 -160.803746) (xy 9.001166 -160.755111) (xy 9.035252 -160.710968)
			(xy 9.075401 -160.672259) (xy 9.120759 -160.639808) (xy 9.170359 -160.614307) (xy 9.223143 -160.5963)
			(xy 9.277986 -160.58617) (xy 9.33372 -160.584133) (xy 9.389157 -160.590233) (xy 9.443114 -160.604339)
			(xy 9.494443 -160.626151) (xy 9.542049 -160.655205) (xy 9.584917 -160.69088) (xy 9.622134 -160.732417)
			(xy 9.652907 -160.77893) (xy 9.676579 -160.829427) (xy 9.692647 -160.882834) (xy 9.700767 -160.93801)
			(xy 9.701239 -160.963864) (xy 10.32967 -160.963864) (xy 10.333741 -160.908242) (xy 10.345867 -160.853805)
			(xy 10.36579 -160.801714) (xy 10.393086 -160.753079) (xy 10.427172 -160.708936) (xy 10.467321 -160.670227)
			(xy 10.512679 -160.637776) (xy 10.562279 -160.612275) (xy 10.615063 -160.594268) (xy 10.669906 -160.584138)
			(xy 10.72564 -160.582101) (xy 10.781077 -160.588201) (xy 10.835034 -160.602307) (xy 10.886363 -160.624119)
			(xy 10.933969 -160.653173) (xy 10.976837 -160.688848) (xy 11.014054 -160.730385) (xy 11.044827 -160.776898)
			(xy 11.068499 -160.827395) (xy 11.084567 -160.880802) (xy 11.092687 -160.935978) (xy 11.093196 -160.963864)
			(xy 11.093103 -160.968944) (xy 11.601448 -160.968944) (xy 11.605519 -160.913322) (xy 11.617645 -160.858885)
			(xy 11.637568 -160.806794) (xy 11.664864 -160.758159) (xy 11.69895 -160.714016) (xy 11.739099 -160.675307)
			(xy 11.784457 -160.642856) (xy 11.834057 -160.617355) (xy 11.886841 -160.599348) (xy 11.941684 -160.589218)
			(xy 11.997418 -160.587181) (xy 12.052855 -160.593281) (xy 12.106812 -160.607387) (xy 12.158141 -160.629199)
			(xy 12.205747 -160.658253) (xy 12.248615 -160.693928) (xy 12.285832 -160.735465) (xy 12.316605 -160.781978)
			(xy 12.340277 -160.832475) (xy 12.356345 -160.885882) (xy 12.358738 -160.902142) (xy 13.38275 -160.902142)
			(xy 13.386821 -160.84652) (xy 13.398947 -160.792083) (xy 13.41887 -160.739992) (xy 13.446166 -160.691357)
			(xy 13.480252 -160.647214) (xy 13.520401 -160.608505) (xy 13.565759 -160.576054) (xy 13.615359 -160.550553)
			(xy 13.668143 -160.532546) (xy 13.722986 -160.522416) (xy 13.77872 -160.520379) (xy 13.834157 -160.526479)
			(xy 13.888114 -160.540585) (xy 13.939443 -160.562397) (xy 13.987049 -160.591451) (xy 14.029917 -160.627126)
			(xy 14.067134 -160.668663) (xy 14.097907 -160.715176) (xy 14.121579 -160.765673) (xy 14.137647 -160.81908)
			(xy 14.145767 -160.874256) (xy 14.146276 -160.902142) (xy 14.145767 -160.930028) (xy 14.137647 -160.985204)
			(xy 14.121579 -161.038611) (xy 14.10018 -161.08426) (xy 37.583108 -161.08426) (xy 37.587179 -161.028638)
			(xy 37.599305 -160.974201) (xy 37.619228 -160.92211) (xy 37.646524 -160.873475) (xy 37.68061 -160.829332)
			(xy 37.720759 -160.790623) (xy 37.766117 -160.758172) (xy 37.815717 -160.732671) (xy 37.868501 -160.714664)
			(xy 37.923344 -160.704534) (xy 37.979078 -160.702497) (xy 38.034515 -160.708597) (xy 38.088472 -160.722703)
			(xy 38.139801 -160.744515) (xy 38.187407 -160.773569) (xy 38.230275 -160.809244) (xy 38.267492 -160.850781)
			(xy 38.298265 -160.897294) (xy 38.321937 -160.947791) (xy 38.338005 -161.001198) (xy 38.346125 -161.056374)
			(xy 38.346634 -161.08426) (xy 38.346125 -161.112146) (xy 38.338005 -161.167322) (xy 38.321937 -161.220729)
			(xy 38.298265 -161.271226) (xy 38.267492 -161.317739) (xy 38.230275 -161.359276) (xy 38.187407 -161.394951)
			(xy 38.139801 -161.424005) (xy 38.088472 -161.445817) (xy 38.034515 -161.459923) (xy 37.979078 -161.466023)
			(xy 37.923344 -161.463986) (xy 37.868501 -161.453856) (xy 37.815717 -161.435849) (xy 37.766117 -161.410348)
			(xy 37.720759 -161.377897) (xy 37.68061 -161.339188) (xy 37.646524 -161.295045) (xy 37.619228 -161.24641)
			(xy 37.599305 -161.194319) (xy 37.587179 -161.139882) (xy 37.583108 -161.08426) (xy 14.10018 -161.08426)
			(xy 14.097907 -161.089108) (xy 14.067134 -161.135621) (xy 14.029917 -161.177158) (xy 13.987049 -161.212833)
			(xy 13.939443 -161.241887) (xy 13.888114 -161.263699) (xy 13.834157 -161.277805) (xy 13.77872 -161.283905)
			(xy 13.722986 -161.281868) (xy 13.668143 -161.271738) (xy 13.615359 -161.253731) (xy 13.565759 -161.22823)
			(xy 13.520401 -161.195779) (xy 13.480252 -161.15707) (xy 13.446166 -161.112927) (xy 13.41887 -161.064292)
			(xy 13.398947 -161.012201) (xy 13.386821 -160.957764) (xy 13.38275 -160.902142) (xy 12.358738 -160.902142)
			(xy 12.364465 -160.941058) (xy 12.364974 -160.968944) (xy 12.364465 -160.99683) (xy 12.356345 -161.052006)
			(xy 12.340277 -161.105413) (xy 12.316605 -161.15591) (xy 12.285832 -161.202423) (xy 12.248615 -161.24396)
			(xy 12.205747 -161.279635) (xy 12.158141 -161.308689) (xy 12.106812 -161.330501) (xy 12.052855 -161.344607)
			(xy 11.997418 -161.350707) (xy 11.941684 -161.34867) (xy 11.886841 -161.33854) (xy 11.834057 -161.320533)
			(xy 11.784457 -161.295032) (xy 11.739099 -161.262581) (xy 11.69895 -161.223872) (xy 11.664864 -161.179729)
			(xy 11.637568 -161.131094) (xy 11.617645 -161.079003) (xy 11.605519 -161.024566) (xy 11.601448 -160.968944)
			(xy 11.093103 -160.968944) (xy 11.092687 -160.99175) (xy 11.084567 -161.046926) (xy 11.068499 -161.100333)
			(xy 11.044827 -161.15083) (xy 11.014054 -161.197343) (xy 10.976837 -161.23888) (xy 10.933969 -161.274555)
			(xy 10.886363 -161.303609) (xy 10.835034 -161.325421) (xy 10.781077 -161.339527) (xy 10.72564 -161.345627)
			(xy 10.669906 -161.34359) (xy 10.615063 -161.33346) (xy 10.562279 -161.315453) (xy 10.512679 -161.289952)
			(xy 10.467321 -161.257501) (xy 10.427172 -161.218792) (xy 10.393086 -161.174649) (xy 10.36579 -161.126014)
			(xy 10.345867 -161.073923) (xy 10.333741 -161.019486) (xy 10.32967 -160.963864) (xy 9.701239 -160.963864)
			(xy 9.701276 -160.965896) (xy 9.700767 -160.993782) (xy 9.692647 -161.048958) (xy 9.676579 -161.102365)
			(xy 9.652907 -161.152862) (xy 9.622134 -161.199375) (xy 9.584917 -161.240912) (xy 9.542049 -161.276587)
			(xy 9.494443 -161.305641) (xy 9.443114 -161.327453) (xy 9.389157 -161.341559) (xy 9.33372 -161.347659)
			(xy 9.277986 -161.345622) (xy 9.223143 -161.335492) (xy 9.170359 -161.317485) (xy 9.120759 -161.291984)
			(xy 9.075401 -161.259533) (xy 9.035252 -161.220824) (xy 9.001166 -161.176681) (xy 8.97387 -161.128046)
			(xy 8.953947 -161.075955) (xy 8.941821 -161.021518) (xy 8.93775 -160.965896) (xy 4.38404 -160.965896)
			(xy 4.38404 -163.114736) (xy 16.04975 -163.114736) (xy 16.053821 -163.059114) (xy 16.065947 -163.004677)
			(xy 16.08587 -162.952586) (xy 16.113166 -162.903951) (xy 16.147252 -162.859808) (xy 16.187401 -162.821099)
			(xy 16.232759 -162.788648) (xy 16.282359 -162.763147) (xy 16.335143 -162.74514) (xy 16.389986 -162.73501)
			(xy 16.44572 -162.732973) (xy 16.501157 -162.739073) (xy 16.555114 -162.753179) (xy 16.606443 -162.774991)
			(xy 16.654049 -162.804045) (xy 16.696917 -162.83972) (xy 16.734134 -162.881257) (xy 16.764907 -162.92777)
			(xy 16.788579 -162.978267) (xy 16.804647 -163.031674) (xy 16.812767 -163.08685) (xy 16.813276 -163.114736)
			(xy 16.812767 -163.142622) (xy 16.804647 -163.197798) (xy 16.788579 -163.251205) (xy 16.764907 -163.301702)
			(xy 16.734134 -163.348215) (xy 16.696917 -163.389752) (xy 16.654049 -163.425427) (xy 16.606443 -163.454481)
			(xy 16.555114 -163.476293) (xy 16.501157 -163.490399) (xy 16.44572 -163.496499) (xy 16.389986 -163.494462)
			(xy 16.335143 -163.484332) (xy 16.282359 -163.466325) (xy 16.232759 -163.440824) (xy 16.187401 -163.408373)
			(xy 16.147252 -163.369664) (xy 16.113166 -163.325521) (xy 16.08587 -163.276886) (xy 16.065947 -163.224795)
			(xy 16.053821 -163.170358) (xy 16.04975 -163.114736) (xy 4.38404 -163.114736) (xy 4.38404 -163.928806)
			(xy 38.393114 -163.928806) (xy 38.397185 -163.873184) (xy 38.409311 -163.818747) (xy 38.429234 -163.766656)
			(xy 38.45653 -163.718021) (xy 38.490616 -163.673878) (xy 38.530765 -163.635169) (xy 38.576123 -163.602718)
			(xy 38.625723 -163.577217) (xy 38.678507 -163.55921) (xy 38.73335 -163.54908) (xy 38.789084 -163.547043)
			(xy 38.844521 -163.553143) (xy 38.898478 -163.567249) (xy 38.949807 -163.589061) (xy 38.997413 -163.618115)
			(xy 39.040281 -163.65379) (xy 39.077498 -163.695327) (xy 39.108271 -163.74184) (xy 39.131943 -163.792337)
			(xy 39.148011 -163.845744) (xy 39.156131 -163.90092) (xy 39.15664 -163.928806) (xy 39.156131 -163.956692)
			(xy 39.148011 -164.011868) (xy 39.131943 -164.065275) (xy 39.108271 -164.115772) (xy 39.077498 -164.162285)
			(xy 39.040281 -164.203822) (xy 38.997413 -164.239497) (xy 38.949807 -164.268551) (xy 38.898478 -164.290363)
			(xy 38.844521 -164.304469) (xy 38.789084 -164.310569) (xy 38.73335 -164.308532) (xy 38.678507 -164.298402)
			(xy 38.625723 -164.280395) (xy 38.576123 -164.254894) (xy 38.530765 -164.222443) (xy 38.490616 -164.183734)
			(xy 38.45653 -164.139591) (xy 38.429234 -164.090956) (xy 38.409311 -164.038865) (xy 38.397185 -163.984428)
			(xy 38.393114 -163.928806) (xy 4.38404 -163.928806) (xy 4.38404 -167.667178) (xy 18.392138 -167.667178)
			(xy 18.396209 -167.611556) (xy 18.408335 -167.557119) (xy 18.428258 -167.505028) (xy 18.455554 -167.456393)
			(xy 18.48964 -167.41225) (xy 18.529789 -167.373541) (xy 18.575147 -167.34109) (xy 18.624747 -167.315589)
			(xy 18.677531 -167.297582) (xy 18.732374 -167.287452) (xy 18.788108 -167.285415) (xy 18.843545 -167.291515)
			(xy 18.897502 -167.305621) (xy 18.948831 -167.327433) (xy 18.996437 -167.356487) (xy 19.039305 -167.392162)
			(xy 19.076522 -167.433699) (xy 19.107295 -167.480212) (xy 19.130967 -167.530709) (xy 19.147035 -167.584116)
			(xy 19.149914 -167.603678) (xy 21.168612 -167.603678) (xy 21.172683 -167.548056) (xy 21.184809 -167.493619)
			(xy 21.204732 -167.441528) (xy 21.232028 -167.392893) (xy 21.266114 -167.34875) (xy 21.306263 -167.310041)
			(xy 21.351621 -167.27759) (xy 21.401221 -167.252089) (xy 21.454005 -167.234082) (xy 21.508848 -167.223952)
			(xy 21.564582 -167.221915) (xy 21.620019 -167.228015) (xy 21.673976 -167.242121) (xy 21.69359 -167.250456)
			(xy 23.214741 -167.250456) (xy 23.214741 -167.195944) (xy 23.222499 -167.141988) (xy 23.237858 -167.089685)
			(xy 23.260504 -167.040101) (xy 23.289977 -166.994244) (xy 23.325676 -166.953049) (xy 23.366874 -166.917354)
			(xy 23.412734 -166.887886) (xy 23.462321 -166.865244) (xy 23.514625 -166.849891) (xy 23.568582 -166.842138)
			(xy 23.595838 -166.841678) (xy 23.625175 -166.842247) (xy 23.683154 -166.851246) (xy 23.739073 -166.869012)
			(xy 23.791615 -166.895126) (xy 23.839542 -166.928972) (xy 23.881725 -166.969754) (xy 23.899876 -166.992808)
			(xy 23.899876 -166.993062) (xy 23.907479 -167.001907) (xy 23.928364 -167.012232) (xy 23.940008 -167.012874)
			(xy 24.032718 -167.013382) (xy 24.054054 -167.002968) (xy 24.061166 -166.99357) (xy 24.070432 -166.981847)
			(xy 24.090519 -166.959723) (xy 24.101298 -166.949374) (xy 24.101552 -166.94912) (xy 24.108437 -166.941841)
			(xy 24.116552 -166.923549) (xy 24.1173 -166.91356) (xy 24.119078 -166.830502) (xy 24.111712 -166.811706)
			(xy 24.104346 -166.80434) (xy 24.08411 -166.782802) (xy 24.049802 -166.734686) (xy 24.023324 -166.681855)
			(xy 24.005311 -166.625574) (xy 23.996191 -166.567187) (xy 23.995634 -166.53764) (xy 23.99612 -166.510389)
			(xy 24.003876 -166.456441) (xy 24.019231 -166.404146) (xy 24.041873 -166.354569) (xy 24.071339 -166.308719)
			(xy 24.10703 -166.267528) (xy 24.148221 -166.231837) (xy 24.194071 -166.202371) (xy 24.243648 -166.179729)
			(xy 24.295943 -166.164374) (xy 24.349891 -166.156618) (xy 24.404393 -166.156618) (xy 24.458341 -166.164374)
			(xy 24.510636 -166.179729) (xy 24.560213 -166.202371) (xy 24.606063 -166.231837) (xy 24.647254 -166.267528)
			(xy 24.682945 -166.308719) (xy 24.712411 -166.354569) (xy 24.735053 -166.404146) (xy 24.750408 -166.456441)
			(xy 24.758164 -166.510389) (xy 24.75865 -166.53764) (xy 24.758194 -166.56356) (xy 24.751159 -166.614922)
			(xy 24.737239 -166.664858) (xy 24.716688 -166.712452) (xy 24.689886 -166.756826) (xy 24.657325 -166.797165)
			(xy 24.638762 -166.815262) (xy 24.638508 -166.815516) (xy 24.631617 -166.82279) (xy 24.623503 -166.841085)
			(xy 24.62276 -166.851076) (xy 24.620982 -166.934134) (xy 24.628348 -166.95293) (xy 24.635714 -166.960296)
			(xy 24.655977 -166.981809) (xy 24.690279 -167.029933) (xy 24.716751 -167.08277) (xy 24.734758 -167.139057)
			(xy 24.743871 -167.197447) (xy 24.744426 -167.226996) (xy 24.743919 -167.254246) (xy 24.736163 -167.308192)
			(xy 24.720809 -167.360486) (xy 24.69817 -167.410062) (xy 24.668706 -167.455911) (xy 24.633017 -167.497101)
			(xy 24.591829 -167.532793) (xy 24.545981 -167.562259) (xy 24.496406 -167.584902) (xy 24.444114 -167.600258)
			(xy 24.390168 -167.608017) (xy 24.362918 -167.608504) (xy 24.33358 -167.607974) (xy 24.275599 -167.598967)
			(xy 24.219678 -167.581194) (xy 24.167136 -167.555073) (xy 24.119211 -167.52122) (xy 24.07703 -167.480431)
			(xy 24.05888 -167.457374) (xy 24.05888 -167.45712) (xy 24.0513 -167.448252) (xy 24.030398 -167.437941)
			(xy 24.018748 -167.437308) (xy 23.926038 -167.4368) (xy 23.904702 -167.447214) (xy 23.89759 -167.456612)
			(xy 23.879385 -167.479219) (xy 23.837332 -167.519221) (xy 23.789705 -167.552392) (xy 23.737602 -167.577965)
			(xy 23.682228 -167.595351) (xy 23.624858 -167.604149) (xy 23.595838 -167.604694) (xy 23.568582 -167.604262)
			(xy 23.514625 -167.596509) (xy 23.462321 -167.581156) (xy 23.412734 -167.558514) (xy 23.366874 -167.529046)
			(xy 23.325676 -167.493351) (xy 23.289977 -167.452156) (xy 23.260504 -167.406299) (xy 23.237858 -167.356715)
			(xy 23.222499 -167.304412) (xy 23.214741 -167.250456) (xy 21.69359 -167.250456) (xy 21.725305 -167.263933)
			(xy 21.772911 -167.292987) (xy 21.815779 -167.328662) (xy 21.852996 -167.370199) (xy 21.883769 -167.416712)
			(xy 21.907441 -167.467209) (xy 21.923509 -167.520616) (xy 21.931629 -167.575792) (xy 21.932138 -167.603678)
			(xy 21.931629 -167.631564) (xy 21.923509 -167.68674) (xy 21.907441 -167.740147) (xy 21.883769 -167.790644)
			(xy 21.852996 -167.837157) (xy 21.815779 -167.878694) (xy 21.772911 -167.914369) (xy 21.725305 -167.943423)
			(xy 21.673976 -167.965235) (xy 21.620019 -167.979341) (xy 21.564582 -167.985441) (xy 21.508848 -167.983404)
			(xy 21.454005 -167.973274) (xy 21.401221 -167.955267) (xy 21.351621 -167.929766) (xy 21.306263 -167.897315)
			(xy 21.266114 -167.858606) (xy 21.232028 -167.814463) (xy 21.204732 -167.765828) (xy 21.184809 -167.713737)
			(xy 21.172683 -167.6593) (xy 21.168612 -167.603678) (xy 19.149914 -167.603678) (xy 19.155155 -167.639292)
			(xy 19.155664 -167.667178) (xy 19.155155 -167.695064) (xy 19.147035 -167.75024) (xy 19.130967 -167.803647)
			(xy 19.107295 -167.854144) (xy 19.076522 -167.900657) (xy 19.039305 -167.942194) (xy 18.996437 -167.977869)
			(xy 18.948831 -168.006923) (xy 18.897502 -168.028735) (xy 18.843545 -168.042841) (xy 18.788108 -168.048941)
			(xy 18.732374 -168.046904) (xy 18.677531 -168.036774) (xy 18.624747 -168.018767) (xy 18.575147 -167.993266)
			(xy 18.529789 -167.960815) (xy 18.48964 -167.922106) (xy 18.455554 -167.877963) (xy 18.428258 -167.829328)
			(xy 18.408335 -167.777237) (xy 18.396209 -167.7228) (xy 18.392138 -167.667178) (xy 4.38404 -167.667178)
			(xy 4.38404 -168.417063) (xy 8.583373 -168.417063) (xy 8.583373 -168.362557) (xy 8.59113 -168.308606)
			(xy 8.606487 -168.256307) (xy 8.629129 -168.206727) (xy 8.658598 -168.160873) (xy 8.694292 -168.11968)
			(xy 8.735485 -168.083987) (xy 8.781339 -168.054518) (xy 8.830919 -168.031876) (xy 8.883217 -168.01652)
			(xy 8.937169 -168.008763) (xy 8.964422 -168.0083) (xy 8.991897 -168.008773) (xy 9.046277 -168.016668)
			(xy 9.09896 -168.032292) (xy 9.148852 -168.055319) (xy 9.19492 -168.085273) (xy 9.215882 -168.103042)
			(xy 9.223155 -168.108845) (xy 9.240617 -168.115223) (xy 9.249918 -168.115488) (xy 9.32815 -168.114218)
			(xy 9.345422 -168.107106) (xy 9.35228 -168.100756) (xy 9.373594 -168.08147) (xy 9.420959 -168.048905)
			(xy 9.472674 -168.023815) (xy 9.527568 -168.006768) (xy 9.584398 -167.99815) (xy 9.613138 -167.997632)
			(xy 9.640391 -167.998095) (xy 9.694342 -168.005852) (xy 9.74664 -168.021208) (xy 9.796221 -168.04385)
			(xy 9.842074 -168.073318) (xy 9.883267 -168.109012) (xy 9.918961 -168.150204) (xy 9.948429 -168.196058)
			(xy 9.971072 -168.245638) (xy 9.986428 -168.297936) (xy 9.994185 -168.351887) (xy 9.994185 -168.406393)
			(xy 9.986428 -168.460344) (xy 9.971072 -168.512642) (xy 9.948429 -168.562222) (xy 9.918961 -168.608076)
			(xy 9.883267 -168.649268) (xy 9.842074 -168.684962) (xy 9.796221 -168.71443) (xy 9.74664 -168.737072)
			(xy 9.694342 -168.752428) (xy 9.640391 -168.760185) (xy 9.613138 -168.760648) (xy 9.585664 -168.760152)
			(xy 9.531284 -168.752264) (xy 9.478601 -168.736647) (xy 9.428708 -168.713624) (xy 9.38264 -168.683673)
			(xy 9.361678 -168.665906) (xy 9.354383 -168.660134) (xy 9.336938 -168.653736) (xy 9.327642 -168.65346)
			(xy 9.24941 -168.65473) (xy 9.232138 -168.661842) (xy 9.22528 -168.668192) (xy 9.203948 -168.687457)
			(xy 9.156587 -168.720023) (xy 9.104877 -168.745116) (xy 9.049987 -168.762168) (xy 9.008124 -168.768522)
			(xy 23.884888 -168.768522) (xy 23.888959 -168.7129) (xy 23.901085 -168.658463) (xy 23.921008 -168.606372)
			(xy 23.948304 -168.557737) (xy 23.98239 -168.513594) (xy 24.022539 -168.474885) (xy 24.067897 -168.442434)
			(xy 24.117497 -168.416933) (xy 24.170281 -168.398926) (xy 24.225124 -168.388796) (xy 24.280858 -168.386759)
			(xy 24.336295 -168.392859) (xy 24.390252 -168.406965) (xy 24.441581 -168.428777) (xy 24.489187 -168.457831)
			(xy 24.532055 -168.493506) (xy 24.569272 -168.535043) (xy 24.600045 -168.581556) (xy 24.623717 -168.632053)
			(xy 24.639785 -168.68546) (xy 24.647905 -168.740636) (xy 24.648414 -168.768522) (xy 24.647905 -168.796408)
			(xy 24.639785 -168.851584) (xy 24.623717 -168.904991) (xy 24.600045 -168.955488) (xy 24.569272 -169.002001)
			(xy 24.532055 -169.043538) (xy 24.489187 -169.079213) (xy 24.441581 -169.108267) (xy 24.390252 -169.130079)
			(xy 24.336295 -169.144185) (xy 24.280858 -169.150285) (xy 24.225124 -169.148248) (xy 24.170281 -169.138118)
			(xy 24.117497 -169.120111) (xy 24.067897 -169.09461) (xy 24.022539 -169.062159) (xy 23.98239 -169.02345)
			(xy 23.948304 -168.979307) (xy 23.921008 -168.930672) (xy 23.901085 -168.878581) (xy 23.888959 -168.824144)
			(xy 23.884888 -168.768522) (xy 9.008124 -168.768522) (xy 8.993161 -168.770793) (xy 8.964422 -168.771316)
			(xy 8.937169 -168.770857) (xy 8.883217 -168.7631) (xy 8.830919 -168.747744) (xy 8.781339 -168.725102)
			(xy 8.735485 -168.695633) (xy 8.694292 -168.65994) (xy 8.658598 -168.618747) (xy 8.629129 -168.572893)
			(xy 8.606487 -168.523313) (xy 8.59113 -168.471014) (xy 8.583373 -168.417063) (xy 4.38404 -168.417063)
			(xy 4.38404 -169.517314) (xy 19.694904 -169.517314) (xy 19.698975 -169.461692) (xy 19.711101 -169.407255)
			(xy 19.731024 -169.355164) (xy 19.75832 -169.306529) (xy 19.792406 -169.262386) (xy 19.832555 -169.223677)
			(xy 19.877913 -169.191226) (xy 19.927513 -169.165725) (xy 19.980297 -169.147718) (xy 20.03514 -169.137588)
			(xy 20.090874 -169.135551) (xy 20.146311 -169.141651) (xy 20.200268 -169.155757) (xy 20.251597 -169.177569)
			(xy 20.299203 -169.206623) (xy 20.342071 -169.242298) (xy 20.379288 -169.283835) (xy 20.410061 -169.330348)
			(xy 20.433733 -169.380845) (xy 20.449801 -169.434252) (xy 20.457921 -169.489428) (xy 20.45843 -169.517314)
			(xy 20.457921 -169.5452) (xy 20.449801 -169.600376) (xy 20.433733 -169.653783) (xy 20.410061 -169.70428)
			(xy 20.379288 -169.750793) (xy 20.342071 -169.79233) (xy 20.299203 -169.828005) (xy 20.251597 -169.857059)
			(xy 20.200268 -169.878871) (xy 20.146311 -169.892977) (xy 20.090874 -169.899077) (xy 20.03514 -169.89704)
			(xy 19.980297 -169.88691) (xy 19.927513 -169.868903) (xy 19.877913 -169.843402) (xy 19.832555 -169.810951)
			(xy 19.792406 -169.772242) (xy 19.75832 -169.728099) (xy 19.731024 -169.679464) (xy 19.711101 -169.627373)
			(xy 19.698975 -169.572936) (xy 19.694904 -169.517314) (xy 4.38404 -169.517314) (xy 4.38404 -169.909236)
			(xy 51.926996 -169.909236) (xy 51.931067 -169.853614) (xy 51.943193 -169.799177) (xy 51.963116 -169.747086)
			(xy 51.990412 -169.698451) (xy 52.024498 -169.654308) (xy 52.064647 -169.615599) (xy 52.110005 -169.583148)
			(xy 52.159605 -169.557647) (xy 52.212389 -169.53964) (xy 52.267232 -169.52951) (xy 52.322966 -169.527473)
			(xy 52.378403 -169.533573) (xy 52.43236 -169.547679) (xy 52.483689 -169.569491) (xy 52.531295 -169.598545)
			(xy 52.574163 -169.63422) (xy 52.61138 -169.675757) (xy 52.642153 -169.72227) (xy 52.665825 -169.772767)
			(xy 52.681893 -169.826174) (xy 52.690013 -169.88135) (xy 52.690522 -169.909236) (xy 52.690013 -169.937122)
			(xy 52.681893 -169.992298) (xy 52.665825 -170.045705) (xy 52.642153 -170.096202) (xy 52.61138 -170.142715)
			(xy 52.574163 -170.184252) (xy 52.531295 -170.219927) (xy 52.483689 -170.248981) (xy 52.43236 -170.270793)
			(xy 52.378403 -170.284899) (xy 52.322966 -170.290999) (xy 52.267232 -170.288962) (xy 52.212389 -170.278832)
			(xy 52.159605 -170.260825) (xy 52.110005 -170.235324) (xy 52.064647 -170.202873) (xy 52.024498 -170.164164)
			(xy 51.990412 -170.120021) (xy 51.963116 -170.071386) (xy 51.943193 -170.019295) (xy 51.931067 -169.964858)
			(xy 51.926996 -169.909236) (xy 4.38404 -169.909236) (xy 4.38404 -170.590281) (xy 8.57248 -170.590281)
			(xy 8.57248 -170.535779) (xy 8.580236 -170.481831) (xy 8.595591 -170.429537) (xy 8.618232 -170.37996)
			(xy 8.647698 -170.33411) (xy 8.68339 -170.29292) (xy 8.72458 -170.257228) (xy 8.77043 -170.227762)
			(xy 8.820007 -170.205121) (xy 8.872301 -170.189766) (xy 8.926249 -170.18201) (xy 8.9535 -170.181524)
			(xy 8.981589 -170.182012) (xy 9.037157 -170.190259) (xy 9.090913 -170.206574) (xy 9.141691 -170.230605)
			(xy 9.188391 -170.26183) (xy 9.209532 -170.28033) (xy 9.209786 -170.280584) (xy 9.216994 -170.286556)
			(xy 9.234468 -170.293221) (xy 9.243822 -170.293538) (xy 9.311894 -170.293538) (xy 9.32123 -170.293116)
			(xy 9.338682 -170.286482) (xy 9.34593 -170.280584) (xy 9.346184 -170.28033) (xy 9.367346 -170.26186)
			(xy 9.414058 -170.230668) (xy 9.464833 -170.206652) (xy 9.518577 -170.190328) (xy 9.574132 -170.182049)
			(xy 9.602216 -170.181524) (xy 9.629469 -170.181983) (xy 9.683421 -170.18974) (xy 9.735719 -170.205095)
			(xy 9.7853 -170.227738) (xy 9.831154 -170.257206) (xy 9.872348 -170.2929) (xy 9.908042 -170.334093)
			(xy 9.91985 -170.352466) (xy 20.610574 -170.352466) (xy 20.614645 -170.296844) (xy 20.626771 -170.242407)
			(xy 20.646694 -170.190316) (xy 20.67399 -170.141681) (xy 20.708076 -170.097538) (xy 20.748225 -170.058829)
			(xy 20.793583 -170.026378) (xy 20.843183 -170.000877) (xy 20.895967 -169.98287) (xy 20.95081 -169.97274)
			(xy 21.006544 -169.970703) (xy 21.061981 -169.976803) (xy 21.115938 -169.990909) (xy 21.167267 -170.012721)
			(xy 21.214873 -170.041775) (xy 21.257741 -170.07745) (xy 21.294958 -170.118987) (xy 21.325731 -170.1655)
			(xy 21.349403 -170.215997) (xy 21.365471 -170.269404) (xy 21.373591 -170.32458) (xy 21.3741 -170.352466)
			(xy 21.373591 -170.380352) (xy 21.365471 -170.435528) (xy 21.349403 -170.488935) (xy 21.325731 -170.539432)
			(xy 21.294958 -170.585945) (xy 21.257741 -170.627482) (xy 21.214873 -170.663157) (xy 21.167267 -170.692211)
			(xy 21.115938 -170.714023) (xy 21.061981 -170.728129) (xy 21.006544 -170.734229) (xy 20.95081 -170.732192)
			(xy 20.895967 -170.722062) (xy 20.843183 -170.704055) (xy 20.793583 -170.678554) (xy 20.748225 -170.646103)
			(xy 20.708076 -170.607394) (xy 20.67399 -170.563251) (xy 20.646694 -170.514616) (xy 20.626771 -170.462525)
			(xy 20.614645 -170.408088) (xy 20.610574 -170.352466) (xy 9.91985 -170.352466) (xy 9.93751 -170.379946)
			(xy 9.960153 -170.429527) (xy 9.97551 -170.481825) (xy 9.983267 -170.535777) (xy 9.983267 -170.590283)
			(xy 9.97551 -170.644235) (xy 9.960153 -170.696533) (xy 9.93751 -170.746114) (xy 9.908042 -170.791967)
			(xy 9.872348 -170.83316) (xy 9.831154 -170.868854) (xy 9.7853 -170.898322) (xy 9.735719 -170.920965)
			(xy 9.683421 -170.93632) (xy 9.629469 -170.944077) (xy 9.602216 -170.94454) (xy 9.574127 -170.944051)
			(xy 9.518559 -170.935806) (xy 9.464803 -170.919491) (xy 9.414025 -170.89546) (xy 9.367325 -170.864235)
			(xy 9.346184 -170.845734) (xy 9.34593 -170.84548) (xy 9.338721 -170.839511) (xy 9.321247 -170.832845)
			(xy 9.311894 -170.832526) (xy 9.243822 -170.832526) (xy 9.234488 -170.832963) (xy 9.217036 -170.839587)
			(xy 9.209786 -170.84548) (xy 9.209532 -170.845734) (xy 9.188359 -170.864191) (xy 9.141651 -170.895386)
			(xy 9.090878 -170.919405) (xy 9.037136 -170.935732) (xy 8.981583 -170.944014) (xy 8.9535 -170.94454)
			(xy 8.926249 -170.94405) (xy 8.872301 -170.936294) (xy 8.820007 -170.920939) (xy 8.77043 -170.898298)
			(xy 8.72458 -170.868832) (xy 8.68339 -170.83314) (xy 8.647698 -170.79195) (xy 8.618232 -170.7461)
			(xy 8.595591 -170.696523) (xy 8.580236 -170.644229) (xy 8.57248 -170.590281) (xy 4.38404 -170.590281)
			(xy 4.38404 -172.729398) (xy 20.58873 -172.729398) (xy 20.592801 -172.673776) (xy 20.604927 -172.619339)
			(xy 20.62485 -172.567248) (xy 20.652146 -172.518613) (xy 20.686232 -172.47447) (xy 20.726381 -172.435761)
			(xy 20.771739 -172.40331) (xy 20.821339 -172.377809) (xy 20.874123 -172.359802) (xy 20.928966 -172.349672)
			(xy 20.9847 -172.347635) (xy 21.040137 -172.353735) (xy 21.094094 -172.367841) (xy 21.145423 -172.389653)
			(xy 21.193029 -172.418707) (xy 21.235897 -172.454382) (xy 21.273114 -172.495919) (xy 21.303887 -172.542432)
			(xy 21.327559 -172.592929) (xy 21.343627 -172.646336) (xy 21.351747 -172.701512) (xy 21.352256 -172.729398)
			(xy 21.351747 -172.757284) (xy 21.343627 -172.81246) (xy 21.327559 -172.865867) (xy 21.303887 -172.916364)
			(xy 21.273114 -172.962877) (xy 21.235897 -173.004414) (xy 21.193029 -173.040089) (xy 21.145423 -173.069143)
			(xy 21.094094 -173.090955) (xy 21.040137 -173.105061) (xy 20.9847 -173.111161) (xy 20.928966 -173.109124)
			(xy 20.874123 -173.098994) (xy 20.821339 -173.080987) (xy 20.771739 -173.055486) (xy 20.726381 -173.023035)
			(xy 20.686232 -172.984326) (xy 20.652146 -172.940183) (xy 20.62485 -172.891548) (xy 20.604927 -172.839457)
			(xy 20.592801 -172.78502) (xy 20.58873 -172.729398) (xy 4.38404 -172.729398) (xy 4.38404 -173.282681)
			(xy 8.99412 -173.282681) (xy 8.99412 -173.228179) (xy 9.001876 -173.174231) (xy 9.017231 -173.121937)
			(xy 9.039872 -173.07236) (xy 9.069338 -173.02651) (xy 9.10503 -172.98532) (xy 9.14622 -172.949628)
			(xy 9.19207 -172.920162) (xy 9.241647 -172.897521) (xy 9.293941 -172.882166) (xy 9.347889 -172.87441)
			(xy 9.37514 -172.873924) (xy 9.404399 -172.874486) (xy 9.462231 -172.883433) (xy 9.518021 -172.901096)
			(xy 9.570464 -172.927062) (xy 9.618333 -172.960722) (xy 9.639808 -172.980604) (xy 9.647174 -172.987716)
			(xy 9.664954 -172.994828) (xy 9.755632 -172.994828) (xy 9.773412 -172.987716) (xy 9.780778 -172.980604)
			(xy 9.802223 -172.960685) (xy 9.850091 -172.92701) (xy 9.902541 -172.90104) (xy 9.958341 -172.883382)
			(xy 10.016182 -172.874453) (xy 10.045446 -172.873924) (xy 10.072699 -172.874383) (xy 10.126651 -172.88214)
			(xy 10.178949 -172.897495) (xy 10.22853 -172.920138) (xy 10.274384 -172.949606) (xy 10.315578 -172.9853)
			(xy 10.351272 -173.026493) (xy 10.38074 -173.072346) (xy 10.403383 -173.121927) (xy 10.41874 -173.174225)
			(xy 10.426497 -173.228177) (xy 10.426497 -173.282683) (xy 10.41874 -173.336635) (xy 10.403383 -173.388933)
			(xy 10.38074 -173.438514) (xy 10.351272 -173.484367) (xy 10.315578 -173.52556) (xy 10.274384 -173.561254)
			(xy 10.229336 -173.590204) (xy 19.616672 -173.590204) (xy 19.620743 -173.534582) (xy 19.632869 -173.480145)
			(xy 19.652792 -173.428054) (xy 19.680088 -173.379419) (xy 19.714174 -173.335276) (xy 19.754323 -173.296567)
			(xy 19.799681 -173.264116) (xy 19.849281 -173.238615) (xy 19.902065 -173.220608) (xy 19.956908 -173.210478)
			(xy 20.012642 -173.208441) (xy 20.068079 -173.214541) (xy 20.122036 -173.228647) (xy 20.173365 -173.250459)
			(xy 20.220971 -173.279513) (xy 20.263839 -173.315188) (xy 20.301056 -173.356725) (xy 20.331829 -173.403238)
			(xy 20.355501 -173.453735) (xy 20.371569 -173.507142) (xy 20.379689 -173.562318) (xy 20.380198 -173.590204)
			(xy 20.379689 -173.61809) (xy 20.371569 -173.673266) (xy 20.355501 -173.726673) (xy 20.331829 -173.77717)
			(xy 20.301056 -173.823683) (xy 20.263839 -173.86522) (xy 20.220971 -173.900895) (xy 20.173365 -173.929949)
			(xy 20.122036 -173.951761) (xy 20.068079 -173.965867) (xy 20.012642 -173.971967) (xy 19.956908 -173.96993)
			(xy 19.902065 -173.9598) (xy 19.849281 -173.941793) (xy 19.799681 -173.916292) (xy 19.754323 -173.883841)
			(xy 19.714174 -173.845132) (xy 19.680088 -173.800989) (xy 19.652792 -173.752354) (xy 19.632869 -173.700263)
			(xy 19.620743 -173.645826) (xy 19.616672 -173.590204) (xy 10.229336 -173.590204) (xy 10.22853 -173.590722)
			(xy 10.178949 -173.613365) (xy 10.126651 -173.62872) (xy 10.072699 -173.636477) (xy 10.045446 -173.63694)
			(xy 10.016186 -173.636396) (xy 9.958353 -173.627446) (xy 9.902562 -173.60978) (xy 9.85012 -173.58381)
			(xy 9.802252 -173.550144) (xy 9.780778 -173.53026) (xy 9.773412 -173.523148) (xy 9.755632 -173.516036)
			(xy 9.664954 -173.516036) (xy 9.647174 -173.523148) (xy 9.639808 -173.53026) (xy 9.618364 -173.550179)
			(xy 9.570496 -173.583855) (xy 9.518046 -173.609827) (xy 9.462246 -173.627484) (xy 9.404404 -173.636412)
			(xy 9.37514 -173.63694) (xy 9.347889 -173.63645) (xy 9.293941 -173.628694) (xy 9.241647 -173.613339)
			(xy 9.19207 -173.590698) (xy 9.14622 -173.561232) (xy 9.10503 -173.52554) (xy 9.069338 -173.48435)
			(xy 9.039872 -173.4385) (xy 9.017231 -173.388923) (xy 9.001876 -173.336629) (xy 8.99412 -173.282681)
			(xy 4.38404 -173.282681) (xy 4.38404 -174.271178) (xy 21.033738 -174.271178) (xy 21.037809 -174.215556)
			(xy 21.049935 -174.161119) (xy 21.069858 -174.109028) (xy 21.097154 -174.060393) (xy 21.13124 -174.01625)
			(xy 21.171389 -173.977541) (xy 21.216747 -173.94509) (xy 21.266347 -173.919589) (xy 21.319131 -173.901582)
			(xy 21.373974 -173.891452) (xy 21.429708 -173.889415) (xy 21.485145 -173.895515) (xy 21.539102 -173.909621)
			(xy 21.590431 -173.931433) (xy 21.638037 -173.960487) (xy 21.680905 -173.996162) (xy 21.718122 -174.037699)
			(xy 21.748895 -174.084212) (xy 21.772567 -174.134709) (xy 21.788635 -174.188116) (xy 21.796755 -174.243292)
			(xy 21.797264 -174.271178) (xy 21.796755 -174.299064) (xy 21.788635 -174.35424) (xy 21.772567 -174.407647)
			(xy 21.748895 -174.458144) (xy 21.718122 -174.504657) (xy 21.680905 -174.546194) (xy 21.638037 -174.581869)
			(xy 21.590431 -174.610923) (xy 21.539102 -174.632735) (xy 21.485145 -174.646841) (xy 21.429708 -174.652941)
			(xy 21.373974 -174.650904) (xy 21.319131 -174.640774) (xy 21.266347 -174.622767) (xy 21.216747 -174.597266)
			(xy 21.171389 -174.564815) (xy 21.13124 -174.526106) (xy 21.097154 -174.481963) (xy 21.069858 -174.433328)
			(xy 21.049935 -174.381237) (xy 21.037809 -174.3268) (xy 21.033738 -174.271178) (xy 4.38404 -174.271178)
			(xy 4.38404 -175.542956) (xy 62.632842 -175.542956) (xy 62.636913 -175.487334) (xy 62.649039 -175.432897)
			(xy 62.668962 -175.380806) (xy 62.696258 -175.332171) (xy 62.730344 -175.288028) (xy 62.770493 -175.249319)
			(xy 62.815851 -175.216868) (xy 62.865451 -175.191367) (xy 62.918235 -175.17336) (xy 62.973078 -175.16323)
			(xy 63.028812 -175.161193) (xy 63.084249 -175.167293) (xy 63.138206 -175.181399) (xy 63.189535 -175.203211)
			(xy 63.237141 -175.232265) (xy 63.280009 -175.26794) (xy 63.317226 -175.309477) (xy 63.347999 -175.35599)
			(xy 63.371671 -175.406487) (xy 63.387739 -175.459894) (xy 63.395859 -175.51507) (xy 63.396368 -175.542956)
			(xy 63.395859 -175.570842) (xy 63.387739 -175.626018) (xy 63.371671 -175.679425) (xy 63.347999 -175.729922)
			(xy 63.317226 -175.776435) (xy 63.280009 -175.817972) (xy 63.237141 -175.853647) (xy 63.189535 -175.882701)
			(xy 63.138206 -175.904513) (xy 63.084249 -175.918619) (xy 63.028812 -175.924719) (xy 62.973078 -175.922682)
			(xy 62.918235 -175.912552) (xy 62.865451 -175.894545) (xy 62.815851 -175.869044) (xy 62.770493 -175.836593)
			(xy 62.730344 -175.797884) (xy 62.696258 -175.753741) (xy 62.668962 -175.705106) (xy 62.649039 -175.653015)
			(xy 62.636913 -175.598578) (xy 62.632842 -175.542956) (xy 4.38404 -175.542956) (xy 4.38404 -176.704855)
			(xy 50.702129 -176.704855) (xy 50.702129 -176.650345) (xy 50.709887 -176.596389) (xy 50.725244 -176.544087)
			(xy 50.747889 -176.494503) (xy 50.77736 -176.448646) (xy 50.813057 -176.40745) (xy 50.854254 -176.371754)
			(xy 50.900112 -176.342284) (xy 50.949696 -176.319641) (xy 51.001999 -176.304285) (xy 51.055955 -176.296528)
			(xy 51.08321 -176.296066) (xy 51.089052 -176.296066) (xy 51.102338 -176.295857) (xy 51.128101 -176.289393)
			(xy 51.151322 -176.276498) (xy 51.170429 -176.258047) (xy 51.184126 -176.23529) (xy 51.191485 -176.209768)
			(xy 51.192176 -176.196498) (xy 51.193121 -176.169592) (xy 51.201734 -176.116446) (xy 51.217731 -176.065038)
			(xy 51.240794 -176.016389) (xy 51.270465 -175.971464) (xy 51.306156 -175.931155) (xy 51.347157 -175.896262)
			(xy 51.392656 -175.867477) (xy 51.441748 -175.845373) (xy 51.49346 -175.830388) (xy 51.546764 -175.822819)
			(xy 51.573684 -175.822356) (xy 51.600935 -175.82289) (xy 51.654883 -175.830645) (xy 51.707177 -175.845998)
			(xy 51.756755 -175.868637) (xy 51.802606 -175.898102) (xy 51.843796 -175.933792) (xy 51.879488 -175.974981)
			(xy 51.908955 -176.020831) (xy 51.931597 -176.070408) (xy 51.946952 -176.122702) (xy 51.954709 -176.176649)
			(xy 51.954709 -176.231151) (xy 51.946952 -176.285098) (xy 51.931597 -176.337392) (xy 51.908955 -176.386969)
			(xy 51.879488 -176.432819) (xy 51.843796 -176.474008) (xy 51.802606 -176.509698) (xy 51.756755 -176.539163)
			(xy 51.707177 -176.561802) (xy 51.654883 -176.577155) (xy 51.600935 -176.58491) (xy 51.573684 -176.585372)
			(xy 51.567842 -176.585372) (xy 51.55456 -176.585636) (xy 51.528806 -176.592097) (xy 51.505591 -176.604983)
			(xy 51.486486 -176.623422) (xy 51.472785 -176.646166) (xy 51.465416 -176.671675) (xy 51.464718 -176.68494)
			(xy 51.463814 -176.711848) (xy 51.455195 -176.764996) (xy 51.439193 -176.816404) (xy 51.416126 -176.865054)
			(xy 51.38645 -176.909979) (xy 51.350755 -176.950288) (xy 51.30975 -176.98518) (xy 51.264248 -177.013964)
			(xy 51.261072 -177.015394) (xy 61.6618 -177.015394) (xy 61.665871 -176.959772) (xy 61.677997 -176.905335)
			(xy 61.69792 -176.853244) (xy 61.725216 -176.804609) (xy 61.759302 -176.760466) (xy 61.799451 -176.721757)
			(xy 61.844809 -176.689306) (xy 61.894409 -176.663805) (xy 61.947193 -176.645798) (xy 62.002036 -176.635668)
			(xy 62.05777 -176.633631) (xy 62.113207 -176.639731) (xy 62.167164 -176.653837) (xy 62.218493 -176.675649)
			(xy 62.266099 -176.704703) (xy 62.308967 -176.740378) (xy 62.346184 -176.781915) (xy 62.376957 -176.828428)
			(xy 62.400629 -176.878925) (xy 62.416697 -176.932332) (xy 62.424817 -176.987508) (xy 62.425326 -177.015394)
			(xy 62.424817 -177.04328) (xy 62.416697 -177.098456) (xy 62.400629 -177.151863) (xy 62.376957 -177.20236)
			(xy 62.346184 -177.248873) (xy 62.308967 -177.29041) (xy 62.266099 -177.326085) (xy 62.221647 -177.353214)
			(xy 64.295018 -177.353214) (xy 64.299089 -177.297592) (xy 64.311215 -177.243155) (xy 64.331138 -177.191064)
			(xy 64.358434 -177.142429) (xy 64.39252 -177.098286) (xy 64.432669 -177.059577) (xy 64.478027 -177.027126)
			(xy 64.527627 -177.001625) (xy 64.580411 -176.983618) (xy 64.635254 -176.973488) (xy 64.690988 -176.971451)
			(xy 64.746425 -176.977551) (xy 64.800382 -176.991657) (xy 64.851711 -177.013469) (xy 64.899317 -177.042523)
			(xy 64.942185 -177.078198) (xy 64.979402 -177.119735) (xy 65.010175 -177.166248) (xy 65.033847 -177.216745)
			(xy 65.049915 -177.270152) (xy 65.058035 -177.325328) (xy 65.058544 -177.353214) (xy 65.058035 -177.3811)
			(xy 65.049915 -177.436276) (xy 65.033847 -177.489683) (xy 65.010175 -177.54018) (xy 64.979402 -177.586693)
			(xy 64.942185 -177.62823) (xy 64.899317 -177.663905) (xy 64.851711 -177.692959) (xy 64.800382 -177.714771)
			(xy 64.746425 -177.728877) (xy 64.690988 -177.734977) (xy 64.635254 -177.73294) (xy 64.580411 -177.72281)
			(xy 64.527627 -177.704803) (xy 64.478027 -177.679302) (xy 64.432669 -177.646851) (xy 64.39252 -177.608142)
			(xy 64.358434 -177.563999) (xy 64.331138 -177.515364) (xy 64.311215 -177.463273) (xy 64.299089 -177.408836)
			(xy 64.295018 -177.353214) (xy 62.221647 -177.353214) (xy 62.218493 -177.355139) (xy 62.167164 -177.376951)
			(xy 62.113207 -177.391057) (xy 62.05777 -177.397157) (xy 62.002036 -177.39512) (xy 61.947193 -177.38499)
			(xy 61.894409 -177.366983) (xy 61.844809 -177.341482) (xy 61.799451 -177.309031) (xy 61.759302 -177.270322)
			(xy 61.725216 -177.226179) (xy 61.69792 -177.177544) (xy 61.677997 -177.125453) (xy 61.665871 -177.071016)
			(xy 61.6618 -177.015394) (xy 51.261072 -177.015394) (xy 51.215152 -177.036067) (xy 51.163438 -177.051051)
			(xy 51.110131 -177.058619) (xy 51.08321 -177.059082) (xy 51.055955 -177.058672) (xy 51.001999 -177.050915)
			(xy 50.949696 -177.035559) (xy 50.900112 -177.012916) (xy 50.854254 -176.983446) (xy 50.813057 -176.94775)
			(xy 50.77736 -176.906554) (xy 50.747889 -176.860697) (xy 50.725244 -176.811113) (xy 50.709887 -176.758811)
			(xy 50.702129 -176.704855) (xy 4.38404 -176.704855) (xy 4.38404 -206.51978) (xy 6.532372 -206.51978)
			(xy 6.532372 -179.330858) (xy 6.532886 -179.299225) (xy 6.541128 -179.236498) (xy 6.557489 -179.175385)
			(xy 6.581691 -179.116931) (xy 6.613319 -179.062139) (xy 6.651832 -179.011946) (xy 6.67385 -178.989228)
			(xy 8.43788 -177.225198) (xy 8.460599 -177.203183) (xy 8.510798 -177.164681) (xy 8.565593 -177.133059)
			(xy 8.624044 -177.108857) (xy 8.685155 -177.09249) (xy 8.747878 -177.084236) (xy 8.77951 -177.08372)
			(xy 8.812965 -177.084263) (xy 8.87923 -177.093539) (xy 8.943581 -177.11187) (xy 9.004786 -177.138906)
			(xy 9.061675 -177.17413) (xy 9.113159 -177.216867) (xy 9.136126 -177.2412) (xy 9.142632 -177.247715)
			(xy 9.159031 -177.256052) (xy 9.16813 -177.257456) (xy 9.235186 -177.264822) (xy 9.2444 -177.265382)
			(xy 9.262239 -177.260699) (xy 9.269984 -177.255678) (xy 9.294317 -177.239098) (xy 9.346996 -177.212801)
			(xy 9.403092 -177.194916) (xy 9.461271 -177.185866) (xy 9.49071 -177.18532) (xy 9.517024 -177.185774)
			(xy 9.569154 -177.193011) (xy 9.619797 -177.207332) (xy 9.667996 -177.228467) (xy 9.712839 -177.256016)
			(xy 9.753478 -177.289457) (xy 9.771634 -177.30851) (xy 9.77914 -177.31593) (xy 9.798432 -177.324444)
			(xy 9.808972 -177.32502) (xy 9.883648 -177.32502) (xy 9.894195 -177.32447) (xy 9.91349 -177.315949)
			(xy 9.920986 -177.30851) (xy 9.939157 -177.28947) (xy 9.979783 -177.256011) (xy 10.02462 -177.22845)
			(xy 10.072818 -177.207309) (xy 10.123463 -177.192988) (xy 10.175595 -177.18576) (xy 10.20191 -177.18532)
			(xy 10.229161 -177.18581) (xy 10.283109 -177.193566) (xy 10.335403 -177.208921) (xy 10.38498 -177.231562)
			(xy 10.43083 -177.261028) (xy 10.47202 -177.29672) (xy 10.507712 -177.33791) (xy 10.537178 -177.38376)
			(xy 10.559819 -177.433337) (xy 10.575174 -177.485631) (xy 10.58293 -177.539579) (xy 10.58293 -177.594081)
			(xy 10.575174 -177.648029) (xy 10.559819 -177.700323) (xy 10.537178 -177.7499) (xy 10.507712 -177.79575)
			(xy 10.47202 -177.83694) (xy 10.43083 -177.872632) (xy 10.38498 -177.902098) (xy 10.335403 -177.924739)
			(xy 10.283109 -177.940094) (xy 10.229161 -177.94785) (xy 10.20191 -177.948336) (xy 10.175597 -177.94785)
			(xy 10.12347 -177.940618) (xy 10.072828 -177.926301) (xy 10.024629 -177.905172) (xy 9.979785 -177.87763)
			(xy 9.939144 -177.844195) (xy 9.920986 -177.825146) (xy 9.913465 -177.817743) (xy 9.894185 -177.809218)
			(xy 9.883648 -177.808636) (xy 9.808972 -177.808636) (xy 9.798424 -177.80918) (xy 9.779127 -177.817703)
			(xy 9.771634 -177.825146) (xy 9.753513 -177.844235) (xy 9.712874 -177.877688) (xy 9.668027 -177.905241)
			(xy 9.619819 -177.926373) (xy 9.569166 -177.940684) (xy 9.517028 -177.947901) (xy 9.49071 -177.948336)
			(xy 9.461271 -177.947794) (xy 9.403093 -177.938737) (xy 9.346996 -177.920854) (xy 9.294311 -177.894566)
			(xy 9.269984 -177.877978) (xy 9.262236 -177.87296) (xy 9.244399 -177.868264) (xy 9.235186 -177.868834)
			(xy 9.158986 -177.877216) (xy 9.142476 -177.885598) (xy 9.13638 -177.892202) (xy 9.135872 -177.89271)
			(xy 9.12114 -177.908458) (xy 7.513574 -179.516024) (xy 7.506727 -179.523419) (xy 7.499012 -179.542022)
			(xy 7.498588 -179.552092) (xy 7.498588 -202.41387) (xy 27.454096 -202.41387) (xy 27.458167 -202.358248)
			(xy 27.470293 -202.303811) (xy 27.490216 -202.25172) (xy 27.517512 -202.203085) (xy 27.551598 -202.158942)
			(xy 27.591747 -202.120233) (xy 27.637105 -202.087782) (xy 27.686705 -202.062281) (xy 27.739489 -202.044274)
			(xy 27.794332 -202.034144) (xy 27.850066 -202.032107) (xy 27.905503 -202.038207) (xy 27.95946 -202.052313)
			(xy 28.010789 -202.074125) (xy 28.058395 -202.103179) (xy 28.101263 -202.138854) (xy 28.13848 -202.180391)
			(xy 28.169253 -202.226904) (xy 28.192925 -202.277401) (xy 28.208993 -202.330808) (xy 28.217113 -202.385984)
			(xy 28.217395 -202.401424) (xy 28.448252 -202.401424) (xy 28.452323 -202.345802) (xy 28.464449 -202.291365)
			(xy 28.484372 -202.239274) (xy 28.511668 -202.190639) (xy 28.545754 -202.146496) (xy 28.585903 -202.107787)
			(xy 28.631261 -202.075336) (xy 28.680861 -202.049835) (xy 28.733645 -202.031828) (xy 28.788488 -202.021698)
			(xy 28.844222 -202.019661) (xy 28.899659 -202.025761) (xy 28.953616 -202.039867) (xy 29.004945 -202.061679)
			(xy 29.052551 -202.090733) (xy 29.095419 -202.126408) (xy 29.132636 -202.167945) (xy 29.163409 -202.214458)
			(xy 29.187081 -202.264955) (xy 29.203149 -202.318362) (xy 29.211269 -202.373538) (xy 29.211449 -202.38339)
			(xy 29.7086 -202.38339) (xy 29.712671 -202.327768) (xy 29.724797 -202.273331) (xy 29.74472 -202.22124)
			(xy 29.772016 -202.172605) (xy 29.806102 -202.128462) (xy 29.846251 -202.089753) (xy 29.891609 -202.057302)
			(xy 29.941209 -202.031801) (xy 29.993993 -202.013794) (xy 30.048836 -202.003664) (xy 30.10457 -202.001627)
			(xy 30.160007 -202.007727) (xy 30.213964 -202.021833) (xy 30.265293 -202.043645) (xy 30.312899 -202.072699)
			(xy 30.355767 -202.108374) (xy 30.392984 -202.149911) (xy 30.423757 -202.196424) (xy 30.447429 -202.246921)
			(xy 30.463497 -202.300328) (xy 30.471617 -202.355504) (xy 30.472126 -202.38339) (xy 30.471617 -202.411276)
			(xy 30.463497 -202.466452) (xy 30.447429 -202.519859) (xy 30.423757 -202.570356) (xy 30.392984 -202.616869)
			(xy 30.355767 -202.658406) (xy 30.312899 -202.694081) (xy 30.265293 -202.723135) (xy 30.213964 -202.744947)
			(xy 30.160007 -202.759053) (xy 30.10457 -202.765153) (xy 30.048836 -202.763116) (xy 29.993993 -202.752986)
			(xy 29.941209 -202.734979) (xy 29.891609 -202.709478) (xy 29.846251 -202.677027) (xy 29.806102 -202.638318)
			(xy 29.772016 -202.594175) (xy 29.74472 -202.54554) (xy 29.724797 -202.493449) (xy 29.712671 -202.439012)
			(xy 29.7086 -202.38339) (xy 29.211449 -202.38339) (xy 29.211778 -202.401424) (xy 29.211269 -202.42931)
			(xy 29.203149 -202.484486) (xy 29.187081 -202.537893) (xy 29.163409 -202.58839) (xy 29.132636 -202.634903)
			(xy 29.095419 -202.67644) (xy 29.052551 -202.712115) (xy 29.004945 -202.741169) (xy 28.953616 -202.762981)
			(xy 28.899659 -202.777087) (xy 28.844222 -202.783187) (xy 28.788488 -202.78115) (xy 28.733645 -202.77102)
			(xy 28.680861 -202.753013) (xy 28.631261 -202.727512) (xy 28.585903 -202.695061) (xy 28.545754 -202.656352)
			(xy 28.511668 -202.612209) (xy 28.484372 -202.563574) (xy 28.464449 -202.511483) (xy 28.452323 -202.457046)
			(xy 28.448252 -202.401424) (xy 28.217395 -202.401424) (xy 28.217622 -202.41387) (xy 28.217113 -202.441756)
			(xy 28.208993 -202.496932) (xy 28.192925 -202.550339) (xy 28.169253 -202.600836) (xy 28.13848 -202.647349)
			(xy 28.101263 -202.688886) (xy 28.058395 -202.724561) (xy 28.010789 -202.753615) (xy 27.95946 -202.775427)
			(xy 27.905503 -202.789533) (xy 27.850066 -202.795633) (xy 27.794332 -202.793596) (xy 27.739489 -202.783466)
			(xy 27.686705 -202.765459) (xy 27.637105 -202.739958) (xy 27.591747 -202.707507) (xy 27.551598 -202.668798)
			(xy 27.517512 -202.624655) (xy 27.490216 -202.57602) (xy 27.470293 -202.523929) (xy 27.458167 -202.469492)
			(xy 27.454096 -202.41387) (xy 7.498588 -202.41387) (xy 7.498588 -206.298546) (xy 7.499018 -206.308615)
			(xy 7.506733 -206.327214) (xy 7.513574 -206.334614) (xy 10.657332 -209.478372) (xy 18.503138 -209.478372)
			(xy 18.503575 -209.452057) (xy 18.510814 -209.399927) (xy 18.525138 -209.349283) (xy 18.546277 -209.301084)
			(xy 18.573829 -209.256241) (xy 18.607273 -209.215603) (xy 18.626328 -209.197448) (xy 18.633744 -209.189938)
			(xy 18.642263 -209.17065) (xy 18.642838 -209.16011) (xy 18.642838 -209.085434) (xy 18.642293 -209.074886)
			(xy 18.633768 -209.055592) (xy 18.626328 -209.048096) (xy 18.607283 -209.02993) (xy 18.573824 -208.989303)
			(xy 18.546263 -208.944465) (xy 18.525122 -208.896266) (xy 18.510803 -208.84562) (xy 18.503577 -208.793488)
			(xy 18.503138 -208.767172) (xy 18.503624 -208.739921) (xy 18.51138 -208.685973) (xy 18.526735 -208.633678)
			(xy 18.549377 -208.584101) (xy 18.578843 -208.538251) (xy 18.614534 -208.49706) (xy 18.655725 -208.461369)
			(xy 18.701575 -208.431903) (xy 18.751152 -208.409261) (xy 18.803447 -208.393906) (xy 18.857395 -208.38615)
			(xy 18.911897 -208.38615) (xy 18.965845 -208.393906) (xy 19.01814 -208.409261) (xy 19.067717 -208.431903)
			(xy 19.113567 -208.461369) (xy 19.154758 -208.49706) (xy 19.190449 -208.538251) (xy 19.219915 -208.584101)
			(xy 19.242557 -208.633678) (xy 19.257912 -208.685973) (xy 19.265668 -208.739921) (xy 19.266154 -208.767172)
			(xy 19.265749 -208.793488) (xy 19.263405 -208.810352) (xy 21.535388 -208.810352) (xy 21.539459 -208.75473)
			(xy 21.551585 -208.700293) (xy 21.571508 -208.648202) (xy 21.598804 -208.599567) (xy 21.63289 -208.555424)
			(xy 21.673039 -208.516715) (xy 21.718397 -208.484264) (xy 21.767997 -208.458763) (xy 21.820781 -208.440756)
			(xy 21.875624 -208.430626) (xy 21.931358 -208.428589) (xy 21.986795 -208.434689) (xy 22.040752 -208.448795)
			(xy 22.092081 -208.470607) (xy 22.139687 -208.499661) (xy 22.182555 -208.535336) (xy 22.219772 -208.576873)
			(xy 22.250545 -208.623386) (xy 22.274217 -208.673883) (xy 22.290285 -208.72729) (xy 22.298405 -208.782466)
			(xy 22.298914 -208.810352) (xy 22.298405 -208.838238) (xy 22.290285 -208.893414) (xy 22.274217 -208.946821)
			(xy 22.250545 -208.997318) (xy 22.219772 -209.043831) (xy 22.182555 -209.085368) (xy 22.139687 -209.121043)
			(xy 22.092081 -209.150097) (xy 22.040752 -209.171909) (xy 21.986795 -209.186015) (xy 21.931358 -209.192115)
			(xy 21.875624 -209.190078) (xy 21.820781 -209.179948) (xy 21.767997 -209.161941) (xy 21.718397 -209.13644)
			(xy 21.673039 -209.103989) (xy 21.63289 -209.06528) (xy 21.598804 -209.021137) (xy 21.571508 -208.972502)
			(xy 21.551585 -208.920411) (xy 21.539459 -208.865974) (xy 21.535388 -208.810352) (xy 19.263405 -208.810352)
			(xy 19.258504 -208.84562) (xy 19.244173 -208.896265) (xy 19.223029 -208.944464) (xy 19.195471 -208.989305)
			(xy 19.162021 -209.029942) (xy 19.142964 -209.048096) (xy 19.135572 -209.055626) (xy 19.12704 -209.074899)
			(xy 19.126454 -209.085434) (xy 19.126454 -209.16011) (xy 19.126978 -209.17066) (xy 19.135518 -209.189954)
			(xy 19.142964 -209.197448) (xy 19.162048 -209.215575) (xy 19.1955 -209.256212) (xy 19.223054 -209.301059)
			(xy 19.244187 -209.349265) (xy 19.258499 -209.399917) (xy 19.265718 -209.452054) (xy 19.266154 -209.478372)
			(xy 19.265668 -209.505623) (xy 19.257912 -209.559571) (xy 19.242557 -209.611866) (xy 19.219915 -209.661443)
			(xy 19.190449 -209.707293) (xy 19.154758 -209.748484) (xy 19.113567 -209.784175) (xy 19.067717 -209.813641)
			(xy 19.01814 -209.836283) (xy 18.965845 -209.851638) (xy 18.911897 -209.859394) (xy 18.857395 -209.859394)
			(xy 18.803447 -209.851638) (xy 18.751152 -209.836283) (xy 18.701575 -209.813641) (xy 18.655725 -209.784175)
			(xy 18.614534 -209.748484) (xy 18.578843 -209.707293) (xy 18.549377 -209.661443) (xy 18.526735 -209.611866)
			(xy 18.51138 -209.559571) (xy 18.503624 -209.505623) (xy 18.503138 -209.478372) (xy 10.657332 -209.478372)
			(xy 10.794238 -209.615278) (xy 10.801633 -209.622124) (xy 10.820236 -209.629841) (xy 10.830306 -209.630264)
			(xy 14.236446 -209.630264) (xy 14.268078 -209.630755) (xy 14.330802 -209.639012) (xy 14.391911 -209.655386)
			(xy 14.450361 -209.679596) (xy 14.50515 -209.711228) (xy 14.555341 -209.749741) (xy 14.600076 -209.794476)
			(xy 14.63859 -209.844667) (xy 14.670222 -209.899456) (xy 14.694433 -209.957905) (xy 14.710807 -210.019014)
			(xy 14.719065 -210.081738) (xy 14.719065 -210.113372) (xy 17.054828 -210.113372) (xy 17.058899 -210.05775)
			(xy 17.071025 -210.003313) (xy 17.090948 -209.951222) (xy 17.118244 -209.902587) (xy 17.15233 -209.858444)
			(xy 17.192479 -209.819735) (xy 17.237837 -209.787284) (xy 17.287437 -209.761783) (xy 17.340221 -209.743776)
			(xy 17.395064 -209.733646) (xy 17.450798 -209.731609) (xy 17.506235 -209.737709) (xy 17.560192 -209.751815)
			(xy 17.611521 -209.773627) (xy 17.659127 -209.802681) (xy 17.701995 -209.838356) (xy 17.739212 -209.879893)
			(xy 17.769985 -209.926406) (xy 17.793657 -209.976903) (xy 17.809725 -210.03031) (xy 17.817845 -210.085486)
			(xy 17.818354 -210.113372) (xy 17.81789 -210.138772) (xy 17.943828 -210.138772) (xy 17.947899 -210.08315)
			(xy 17.960025 -210.028713) (xy 17.979948 -209.976622) (xy 18.007244 -209.927987) (xy 18.04133 -209.883844)
			(xy 18.081479 -209.845135) (xy 18.126837 -209.812684) (xy 18.176437 -209.787183) (xy 18.229221 -209.769176)
			(xy 18.284064 -209.759046) (xy 18.339798 -209.757009) (xy 18.395235 -209.763109) (xy 18.449192 -209.777215)
			(xy 18.500521 -209.799027) (xy 18.548127 -209.828081) (xy 18.590995 -209.863756) (xy 18.628212 -209.905293)
			(xy 18.658985 -209.951806) (xy 18.682657 -210.002303) (xy 18.698725 -210.05571) (xy 18.706845 -210.110886)
			(xy 18.707354 -210.138772) (xy 18.706845 -210.166658) (xy 18.698725 -210.221834) (xy 18.682657 -210.275241)
			(xy 18.658985 -210.325738) (xy 18.628212 -210.372251) (xy 18.590995 -210.413788) (xy 18.548127 -210.449463)
			(xy 18.500521 -210.478517) (xy 18.449192 -210.500329) (xy 18.395235 -210.514435) (xy 18.339798 -210.520535)
			(xy 18.284064 -210.518498) (xy 18.229221 -210.508368) (xy 18.176437 -210.490361) (xy 18.126837 -210.46486)
			(xy 18.081479 -210.432409) (xy 18.04133 -210.3937) (xy 18.007244 -210.349557) (xy 17.979948 -210.300922)
			(xy 17.960025 -210.248831) (xy 17.947899 -210.194394) (xy 17.943828 -210.138772) (xy 17.81789 -210.138772)
			(xy 17.817845 -210.141258) (xy 17.809725 -210.196434) (xy 17.793657 -210.249841) (xy 17.769985 -210.300338)
			(xy 17.739212 -210.346851) (xy 17.701995 -210.388388) (xy 17.659127 -210.424063) (xy 17.611521 -210.453117)
			(xy 17.560192 -210.474929) (xy 17.506235 -210.489035) (xy 17.450798 -210.495135) (xy 17.395064 -210.493098)
			(xy 17.340221 -210.482968) (xy 17.287437 -210.464961) (xy 17.237837 -210.43946) (xy 17.192479 -210.407009)
			(xy 17.15233 -210.3683) (xy 17.118244 -210.324157) (xy 17.090948 -210.275522) (xy 17.071025 -210.223431)
			(xy 17.058899 -210.168994) (xy 17.054828 -210.113372) (xy 14.719065 -210.113372) (xy 14.719065 -210.145002)
			(xy 14.710807 -210.207726) (xy 14.694433 -210.268835) (xy 14.670222 -210.327284) (xy 14.63859 -210.382073)
			(xy 14.600076 -210.432264) (xy 14.555341 -210.476999) (xy 14.50515 -210.515512) (xy 14.450361 -210.547144)
			(xy 14.391911 -210.571354) (xy 14.330802 -210.587728) (xy 14.268078 -210.595985) (xy 14.236446 -210.59648)
			(xy 10.609072 -210.59648) (xy 10.577438 -210.596006) (xy 10.51471 -210.587754) (xy 10.453596 -210.571384)
			(xy 10.395143 -210.547174) (xy 10.340352 -210.51554) (xy 10.290159 -210.477022) (xy 10.267442 -210.455002)
			(xy 6.67385 -206.86141) (xy 6.651856 -206.838672) (xy 6.613353 -206.788476) (xy 6.581728 -206.733686)
			(xy 6.557523 -206.675238) (xy 6.541151 -206.614131) (xy 6.532891 -206.551411) (xy 6.532372 -206.51978)
			(xy 4.38404 -206.51978) (xy 4.38404 -212.807621) (xy 11.31543 -212.807621) (xy 11.31543 -212.753119)
			(xy 11.323186 -212.699172) (xy 11.338541 -212.646878) (xy 11.361182 -212.597301) (xy 11.390647 -212.551451)
			(xy 11.426338 -212.510261) (xy 11.467528 -212.47457) (xy 11.513378 -212.445104) (xy 11.562954 -212.422462)
			(xy 11.615248 -212.407107) (xy 11.669195 -212.39935) (xy 11.696446 -212.398864) (xy 11.723692 -212.399293)
			(xy 11.777628 -212.407058) (xy 11.82991 -212.422422) (xy 11.879471 -212.445072) (xy 11.925303 -212.474548)
			(xy 11.966472 -212.510248) (xy 12.002139 -212.551446) (xy 12.017248 -212.574124) (xy 12.022086 -212.581157)
			(xy 12.035497 -212.591704) (xy 12.051641 -212.597224) (xy 12.060174 -212.597492) (xy 12.145518 -212.597492)
			(xy 12.154038 -212.597173) (xy 12.17015 -212.591625) (xy 12.18356 -212.581112) (xy 12.188444 -212.574124)
			(xy 12.203523 -212.551427) (xy 12.239196 -212.510233) (xy 12.280371 -212.474539) (xy 12.326209 -212.445071)
			(xy 12.375776 -212.42243) (xy 12.428061 -212.407077) (xy 12.482 -212.399324) (xy 12.509246 -212.398864)
			(xy 12.535223 -212.399266) (xy 12.586696 -212.406315) (xy 12.636734 -212.42029) (xy 12.684411 -212.440933)
			(xy 12.728842 -212.467859) (xy 12.769204 -212.500572) (xy 12.804749 -212.538463) (xy 12.820142 -212.559392)
			(xy 12.827792 -212.568866) (xy 12.84939 -212.580023) (xy 12.861544 -212.580728) (xy 12.944348 -212.580728)
			(xy 12.956512 -212.580046) (xy 12.978134 -212.568901) (xy 12.98575 -212.559392) (xy 13.001177 -212.538491)
			(xy 13.036724 -212.500612) (xy 13.077084 -212.467909) (xy 13.121509 -212.440987) (xy 13.169179 -212.420345)
			(xy 13.219208 -212.406366) (xy 13.270673 -212.399307) (xy 13.296646 -212.398864) (xy 13.323899 -212.399323)
			(xy 13.377851 -212.40708) (xy 13.430149 -212.422435) (xy 13.47973 -212.445078) (xy 13.525584 -212.474546)
			(xy 13.566778 -212.51024) (xy 13.602472 -212.551433) (xy 13.63194 -212.597286) (xy 13.654583 -212.646867)
			(xy 13.66994 -212.699165) (xy 13.677697 -212.753117) (xy 13.677697 -212.807623) (xy 13.66994 -212.861575)
			(xy 13.654583 -212.913873) (xy 13.63194 -212.963454) (xy 13.602472 -213.009307) (xy 13.566778 -213.0505)
			(xy 13.525584 -213.086194) (xy 13.47973 -213.115662) (xy 13.430149 -213.138305) (xy 13.377851 -213.15366)
			(xy 13.323899 -213.161417) (xy 13.296646 -213.16188) (xy 13.27067 -213.161466) (xy 13.219198 -213.154416)
			(xy 13.169161 -213.140442) (xy 13.121485 -213.119801) (xy 13.077054 -213.092877) (xy 13.036691 -213.060167)
			(xy 13.001144 -213.02228) (xy 12.98575 -213.001352) (xy 12.978115 -212.991864) (xy 12.956505 -212.980717)
			(xy 12.944348 -212.980016) (xy 12.861544 -212.980016) (xy 12.849383 -212.980715) (xy 12.827762 -212.99185)
			(xy 12.820142 -213.001352) (xy 12.804733 -213.022266) (xy 12.769182 -213.060143) (xy 12.728818 -213.092844)
			(xy 12.684389 -213.119763) (xy 12.636718 -213.140403) (xy 12.586686 -213.154381) (xy 12.53522 -213.161438)
			(xy 12.509246 -213.16188) (xy 12.482001 -213.161437) (xy 12.428066 -213.153672) (xy 12.375786 -213.138309)
			(xy 12.326225 -213.115661) (xy 12.280393 -213.086187) (xy 12.239223 -213.05049) (xy 12.203555 -213.009296)
			(xy 12.188444 -212.98662) (xy 12.183567 -212.979618) (xy 12.170172 -212.96907) (xy 12.154045 -212.963533)
			(xy 12.145518 -212.963252) (xy 12.060174 -212.963252) (xy 12.051656 -212.96359) (xy 12.035548 -212.969134)
			(xy 12.022136 -212.979637) (xy 12.017248 -212.98662) (xy 12.002156 -213.009308) (xy 11.966487 -213.050504)
			(xy 11.925315 -213.086201) (xy 11.879479 -213.115671) (xy 11.829914 -213.138314) (xy 11.77763 -213.153668)
			(xy 11.723692 -213.16142) (xy 11.696446 -213.16188) (xy 11.669195 -213.16139) (xy 11.615248 -213.153633)
			(xy 11.562954 -213.138278) (xy 11.513378 -213.115636) (xy 11.467528 -213.08617) (xy 11.426338 -213.050479)
			(xy 11.390647 -213.009289) (xy 11.361182 -212.963439) (xy 11.338541 -212.913862) (xy 11.323186 -212.861568)
			(xy 11.31543 -212.807621) (xy 4.38404 -212.807621) (xy 4.38404 -214.151972) (xy 13.219428 -214.151972)
			(xy 13.223499 -214.09635) (xy 13.235625 -214.041913) (xy 13.255548 -213.989822) (xy 13.282844 -213.941187)
			(xy 13.31693 -213.897044) (xy 13.357079 -213.858335) (xy 13.402437 -213.825884) (xy 13.452037 -213.800383)
			(xy 13.504821 -213.782376) (xy 13.559664 -213.772246) (xy 13.615398 -213.770209) (xy 13.670835 -213.776309)
			(xy 13.724792 -213.790415) (xy 13.776121 -213.812227) (xy 13.823727 -213.841281) (xy 13.866595 -213.876956)
			(xy 13.903812 -213.918493) (xy 13.934585 -213.965006) (xy 13.958257 -214.015503) (xy 13.974325 -214.06891)
			(xy 13.978026 -214.09406) (xy 18.591782 -214.09406) (xy 18.595853 -214.038438) (xy 18.607979 -213.984001)
			(xy 18.627902 -213.93191) (xy 18.655198 -213.883275) (xy 18.689284 -213.839132) (xy 18.729433 -213.800423)
			(xy 18.774791 -213.767972) (xy 18.824391 -213.742471) (xy 18.877175 -213.724464) (xy 18.932018 -213.714334)
			(xy 18.987752 -213.712297) (xy 19.043189 -213.718397) (xy 19.097146 -213.732503) (xy 19.148475 -213.754315)
			(xy 19.196081 -213.783369) (xy 19.238949 -213.819044) (xy 19.276166 -213.860581) (xy 19.306939 -213.907094)
			(xy 19.330611 -213.957591) (xy 19.346679 -214.010998) (xy 19.354799 -214.066174) (xy 19.355308 -214.09406)
			(xy 19.354799 -214.121946) (xy 19.346679 -214.177122) (xy 19.330611 -214.230529) (xy 19.306939 -214.281026)
			(xy 19.276166 -214.327539) (xy 19.238949 -214.369076) (xy 19.196081 -214.404751) (xy 19.148475 -214.433805)
			(xy 19.097146 -214.455617) (xy 19.043189 -214.469723) (xy 18.987752 -214.475823) (xy 18.932018 -214.473786)
			(xy 18.877175 -214.463656) (xy 18.824391 -214.445649) (xy 18.774791 -214.420148) (xy 18.729433 -214.387697)
			(xy 18.689284 -214.348988) (xy 18.655198 -214.304845) (xy 18.627902 -214.25621) (xy 18.607979 -214.204119)
			(xy 18.595853 -214.149682) (xy 18.591782 -214.09406) (xy 13.978026 -214.09406) (xy 13.982445 -214.124086)
			(xy 13.982954 -214.151972) (xy 13.982445 -214.179858) (xy 13.974325 -214.235034) (xy 13.958257 -214.288441)
			(xy 13.934585 -214.338938) (xy 13.903812 -214.385451) (xy 13.866595 -214.426988) (xy 13.823727 -214.462663)
			(xy 13.776121 -214.491717) (xy 13.724792 -214.513529) (xy 13.670835 -214.527635) (xy 13.615398 -214.533735)
			(xy 13.559664 -214.531698) (xy 13.504821 -214.521568) (xy 13.452037 -214.503561) (xy 13.402437 -214.47806)
			(xy 13.357079 -214.445609) (xy 13.31693 -214.4069) (xy 13.282844 -214.362757) (xy 13.255548 -214.314122)
			(xy 13.235625 -214.262031) (xy 13.223499 -214.207594) (xy 13.219428 -214.151972) (xy 4.38404 -214.151972)
			(xy 4.38404 -215.320372) (xy 17.156428 -215.320372) (xy 17.160499 -215.26475) (xy 17.172625 -215.210313)
			(xy 17.192548 -215.158222) (xy 17.219844 -215.109587) (xy 17.25393 -215.065444) (xy 17.294079 -215.026735)
			(xy 17.339437 -214.994284) (xy 17.389037 -214.968783) (xy 17.441821 -214.950776) (xy 17.496664 -214.940646)
			(xy 17.552398 -214.938609) (xy 17.607835 -214.944709) (xy 17.661792 -214.958815) (xy 17.713121 -214.980627)
			(xy 17.760727 -215.009681) (xy 17.803595 -215.045356) (xy 17.840812 -215.086893) (xy 17.871585 -215.133406)
			(xy 17.895257 -215.183903) (xy 17.911325 -215.23731) (xy 17.919445 -215.292486) (xy 17.919954 -215.320372)
			(xy 17.919445 -215.348258) (xy 17.911325 -215.403434) (xy 17.895257 -215.456841) (xy 17.871585 -215.507338)
			(xy 17.840812 -215.553851) (xy 17.803595 -215.595388) (xy 17.760727 -215.631063) (xy 17.713121 -215.660117)
			(xy 17.661792 -215.681929) (xy 17.607835 -215.696035) (xy 17.552398 -215.702135) (xy 17.496664 -215.700098)
			(xy 17.441821 -215.689968) (xy 17.389037 -215.671961) (xy 17.339437 -215.64646) (xy 17.294079 -215.614009)
			(xy 17.25393 -215.5753) (xy 17.219844 -215.531157) (xy 17.192548 -215.482522) (xy 17.172625 -215.430431)
			(xy 17.160499 -215.375994) (xy 17.156428 -215.320372) (xy 4.38404 -215.320372) (xy 4.38404 -216.082372)
			(xy 16.267428 -216.082372) (xy 16.271499 -216.02675) (xy 16.283625 -215.972313) (xy 16.303548 -215.920222)
			(xy 16.330844 -215.871587) (xy 16.36493 -215.827444) (xy 16.405079 -215.788735) (xy 16.450437 -215.756284)
			(xy 16.500037 -215.730783) (xy 16.552821 -215.712776) (xy 16.607664 -215.702646) (xy 16.663398 -215.700609)
			(xy 16.718835 -215.706709) (xy 16.772792 -215.720815) (xy 16.824121 -215.742627) (xy 16.871727 -215.771681)
			(xy 16.914595 -215.807356) (xy 16.951812 -215.848893) (xy 16.982585 -215.895406) (xy 17.006257 -215.945903)
			(xy 17.022325 -215.99931) (xy 17.030445 -216.054486) (xy 17.030954 -216.082372) (xy 17.030445 -216.110258)
			(xy 17.022325 -216.165434) (xy 17.006257 -216.218841) (xy 16.982585 -216.269338) (xy 16.951812 -216.315851)
			(xy 16.914595 -216.357388) (xy 16.871727 -216.393063) (xy 16.824121 -216.422117) (xy 16.772792 -216.443929)
			(xy 16.718835 -216.458035) (xy 16.663398 -216.464135) (xy 16.607664 -216.462098) (xy 16.552821 -216.451968)
			(xy 16.500037 -216.433961) (xy 16.450437 -216.40846) (xy 16.405079 -216.376009) (xy 16.36493 -216.3373)
			(xy 16.330844 -216.293157) (xy 16.303548 -216.244522) (xy 16.283625 -216.192431) (xy 16.271499 -216.137994)
			(xy 16.267428 -216.082372) (xy 4.38404 -216.082372) (xy 4.38404 -218.29141) (xy 17.041874 -218.29141)
			(xy 17.045945 -218.235788) (xy 17.058071 -218.181351) (xy 17.077994 -218.12926) (xy 17.10529 -218.080625)
			(xy 17.139376 -218.036482) (xy 17.179525 -217.997773) (xy 17.224883 -217.965322) (xy 17.274483 -217.939821)
			(xy 17.327267 -217.921814) (xy 17.38211 -217.911684) (xy 17.437844 -217.909647) (xy 17.493281 -217.915747)
			(xy 17.547238 -217.929853) (xy 17.598567 -217.951665) (xy 17.646173 -217.980719) (xy 17.689041 -218.016394)
			(xy 17.726258 -218.057931) (xy 17.757031 -218.104444) (xy 17.780703 -218.154941) (xy 17.796771 -218.208348)
			(xy 17.804891 -218.263524) (xy 17.8054 -218.29141) (xy 17.804891 -218.319296) (xy 17.796771 -218.374472)
			(xy 17.780703 -218.427879) (xy 17.757031 -218.478376) (xy 17.726258 -218.524889) (xy 17.689041 -218.566426)
			(xy 17.646173 -218.602101) (xy 17.598567 -218.631155) (xy 17.547238 -218.652967) (xy 17.493281 -218.667073)
			(xy 17.437844 -218.673173) (xy 17.38211 -218.671136) (xy 17.327267 -218.661006) (xy 17.274483 -218.642999)
			(xy 17.224883 -218.617498) (xy 17.179525 -218.585047) (xy 17.139376 -218.546338) (xy 17.10529 -218.502195)
			(xy 17.077994 -218.45356) (xy 17.058071 -218.401469) (xy 17.045945 -218.347032) (xy 17.041874 -218.29141)
			(xy 4.38404 -218.29141) (xy 4.38404 -220.84665) (xy 15.866108 -220.84665) (xy 15.870179 -220.791028)
			(xy 15.882305 -220.736591) (xy 15.902228 -220.6845) (xy 15.929524 -220.635865) (xy 15.96361 -220.591722)
			(xy 16.003759 -220.553013) (xy 16.049117 -220.520562) (xy 16.098717 -220.495061) (xy 16.151501 -220.477054)
			(xy 16.206344 -220.466924) (xy 16.262078 -220.464887) (xy 16.317515 -220.470987) (xy 16.371472 -220.485093)
			(xy 16.422801 -220.506905) (xy 16.470407 -220.535959) (xy 16.513275 -220.571634) (xy 16.550492 -220.613171)
			(xy 16.581265 -220.659684) (xy 16.604937 -220.710181) (xy 16.621005 -220.763588) (xy 16.629125 -220.818764)
			(xy 16.629634 -220.84665) (xy 16.629125 -220.874536) (xy 16.621005 -220.929712) (xy 16.604937 -220.983119)
			(xy 16.581265 -221.033616) (xy 16.550492 -221.080129) (xy 16.513275 -221.121666) (xy 16.470407 -221.157341)
			(xy 16.422801 -221.186395) (xy 16.371472 -221.208207) (xy 16.317515 -221.222313) (xy 16.262078 -221.228413)
			(xy 16.206344 -221.226376) (xy 16.151501 -221.216246) (xy 16.098717 -221.198239) (xy 16.049117 -221.172738)
			(xy 16.003759 -221.140287) (xy 15.96361 -221.101578) (xy 15.929524 -221.057435) (xy 15.902228 -221.0088)
			(xy 15.882305 -220.956709) (xy 15.870179 -220.902272) (xy 15.866108 -220.84665) (xy 4.38404 -220.84665)
			(xy 4.38404 -222.172276) (xy 15.856202 -222.172276) (xy 15.860273 -222.116654) (xy 15.872399 -222.062217)
			(xy 15.892322 -222.010126) (xy 15.919618 -221.961491) (xy 15.953704 -221.917348) (xy 15.993853 -221.878639)
			(xy 16.039211 -221.846188) (xy 16.088811 -221.820687) (xy 16.141595 -221.80268) (xy 16.196438 -221.79255)
			(xy 16.252172 -221.790513) (xy 16.307609 -221.796613) (xy 16.361566 -221.810719) (xy 16.412895 -221.832531)
			(xy 16.460501 -221.861585) (xy 16.503369 -221.89726) (xy 16.540586 -221.938797) (xy 16.548351 -221.950534)
			(xy 17.087594 -221.950534) (xy 17.091665 -221.894912) (xy 17.103791 -221.840475) (xy 17.123714 -221.788384)
			(xy 17.15101 -221.739749) (xy 17.185096 -221.695606) (xy 17.225245 -221.656897) (xy 17.270603 -221.624446)
			(xy 17.320203 -221.598945) (xy 17.372987 -221.580938) (xy 17.42783 -221.570808) (xy 17.483564 -221.568771)
			(xy 17.539001 -221.574871) (xy 17.592958 -221.588977) (xy 17.644287 -221.610789) (xy 17.691893 -221.639843)
			(xy 17.734761 -221.675518) (xy 17.771978 -221.717055) (xy 17.802751 -221.763568) (xy 17.826423 -221.814065)
			(xy 17.842491 -221.867472) (xy 17.850611 -221.922648) (xy 17.85112 -221.950534) (xy 17.850611 -221.97842)
			(xy 17.842491 -222.033596) (xy 17.826423 -222.087003) (xy 17.802751 -222.1375) (xy 17.771978 -222.184013)
			(xy 17.734761 -222.22555) (xy 17.691893 -222.261225) (xy 17.644287 -222.290279) (xy 17.592958 -222.312091)
			(xy 17.539001 -222.326197) (xy 17.483564 -222.332297) (xy 17.42783 -222.33026) (xy 17.372987 -222.32013)
			(xy 17.320203 -222.302123) (xy 17.270603 -222.276622) (xy 17.225245 -222.244171) (xy 17.185096 -222.205462)
			(xy 17.15101 -222.161319) (xy 17.123714 -222.112684) (xy 17.103791 -222.060593) (xy 17.091665 -222.006156)
			(xy 17.087594 -221.950534) (xy 16.548351 -221.950534) (xy 16.571359 -221.98531) (xy 16.595031 -222.035807)
			(xy 16.611099 -222.089214) (xy 16.619219 -222.14439) (xy 16.619728 -222.172276) (xy 16.619219 -222.200162)
			(xy 16.611099 -222.255338) (xy 16.595031 -222.308745) (xy 16.571359 -222.359242) (xy 16.540586 -222.405755)
			(xy 16.503369 -222.447292) (xy 16.460501 -222.482967) (xy 16.412895 -222.512021) (xy 16.361566 -222.533833)
			(xy 16.307609 -222.547939) (xy 16.252172 -222.554039) (xy 16.196438 -222.552002) (xy 16.141595 -222.541872)
			(xy 16.088811 -222.523865) (xy 16.039211 -222.498364) (xy 15.993853 -222.465913) (xy 15.953704 -222.427204)
			(xy 15.919618 -222.383061) (xy 15.892322 -222.334426) (xy 15.872399 -222.282335) (xy 15.860273 -222.227898)
			(xy 15.856202 -222.172276) (xy 4.38404 -222.172276) (xy 4.38404 -228.981) (xy 16.03451 -228.981)
			(xy 16.038581 -228.925378) (xy 16.050707 -228.870941) (xy 16.07063 -228.81885) (xy 16.097926 -228.770215)
			(xy 16.132012 -228.726072) (xy 16.172161 -228.687363) (xy 16.217519 -228.654912) (xy 16.267119 -228.629411)
			(xy 16.319903 -228.611404) (xy 16.374746 -228.601274) (xy 16.43048 -228.599237) (xy 16.485917 -228.605337)
			(xy 16.539874 -228.619443) (xy 16.591203 -228.641255) (xy 16.638809 -228.670309) (xy 16.681677 -228.705984)
			(xy 16.718894 -228.747521) (xy 16.749667 -228.794034) (xy 16.773339 -228.844531) (xy 16.789407 -228.897938)
			(xy 16.797527 -228.953114) (xy 16.798036 -228.981) (xy 16.797527 -229.008886) (xy 16.789407 -229.064062)
			(xy 16.773339 -229.117469) (xy 16.749667 -229.167966) (xy 16.718894 -229.214479) (xy 16.681677 -229.256016)
			(xy 16.638809 -229.291691) (xy 16.591203 -229.320745) (xy 16.539874 -229.342557) (xy 16.485917 -229.356663)
			(xy 16.43048 -229.362763) (xy 16.374746 -229.360726) (xy 16.319903 -229.350596) (xy 16.267119 -229.332589)
			(xy 16.217519 -229.307088) (xy 16.172161 -229.274637) (xy 16.132012 -229.235928) (xy 16.097926 -229.191785)
			(xy 16.07063 -229.14315) (xy 16.050707 -229.091059) (xy 16.038581 -229.036622) (xy 16.03451 -228.981)
			(xy 4.38404 -228.981) (xy 4.38404 -229.94493) (xy 12.84554 -229.94493) (xy 12.849611 -229.889308)
			(xy 12.861737 -229.834871) (xy 12.88166 -229.78278) (xy 12.908956 -229.734145) (xy 12.943042 -229.690002)
			(xy 12.983191 -229.651293) (xy 13.028549 -229.618842) (xy 13.078149 -229.593341) (xy 13.130933 -229.575334)
			(xy 13.185776 -229.565204) (xy 13.24151 -229.563167) (xy 13.296947 -229.569267) (xy 13.350904 -229.583373)
			(xy 13.402233 -229.605185) (xy 13.449839 -229.634239) (xy 13.492707 -229.669914) (xy 13.529924 -229.711451)
			(xy 13.560697 -229.757964) (xy 13.584369 -229.808461) (xy 13.600437 -229.861868) (xy 13.608557 -229.917044)
			(xy 13.609066 -229.94493) (xy 13.608557 -229.972816) (xy 13.600437 -230.027992) (xy 13.584369 -230.081399)
			(xy 13.560697 -230.131896) (xy 13.529924 -230.178409) (xy 13.492707 -230.219946) (xy 13.449839 -230.255621)
			(xy 13.402233 -230.284675) (xy 13.350904 -230.306487) (xy 13.296947 -230.320593) (xy 13.24151 -230.326693)
			(xy 13.185776 -230.324656) (xy 13.130933 -230.314526) (xy 13.078149 -230.296519) (xy 13.028549 -230.271018)
			(xy 12.983191 -230.238567) (xy 12.943042 -230.199858) (xy 12.908956 -230.155715) (xy 12.88166 -230.10708)
			(xy 12.861737 -230.054989) (xy 12.849611 -230.000552) (xy 12.84554 -229.94493) (xy 4.38404 -229.94493)
			(xy 4.38404 -231.203754) (xy 14.84833 -231.203754) (xy 14.852401 -231.148132) (xy 14.864527 -231.093695)
			(xy 14.88445 -231.041604) (xy 14.911746 -230.992969) (xy 14.945832 -230.948826) (xy 14.985981 -230.910117)
			(xy 15.031339 -230.877666) (xy 15.080939 -230.852165) (xy 15.133723 -230.834158) (xy 15.188566 -230.824028)
			(xy 15.2443 -230.821991) (xy 15.299737 -230.828091) (xy 15.353694 -230.842197) (xy 15.405023 -230.864009)
			(xy 15.452629 -230.893063) (xy 15.495497 -230.928738) (xy 15.532714 -230.970275) (xy 15.563487 -231.016788)
			(xy 15.587159 -231.067285) (xy 15.603227 -231.120692) (xy 15.610629 -231.170988) (xy 16.915382 -231.170988)
			(xy 16.919453 -231.115366) (xy 16.931579 -231.060929) (xy 16.951502 -231.008838) (xy 16.978798 -230.960203)
			(xy 17.012884 -230.91606) (xy 17.053033 -230.877351) (xy 17.098391 -230.8449) (xy 17.147991 -230.819399)
			(xy 17.200775 -230.801392) (xy 17.255618 -230.791262) (xy 17.311352 -230.789225) (xy 17.366789 -230.795325)
			(xy 17.420746 -230.809431) (xy 17.472075 -230.831243) (xy 17.519681 -230.860297) (xy 17.562549 -230.895972)
			(xy 17.599766 -230.937509) (xy 17.630539 -230.984022) (xy 17.654211 -231.034519) (xy 17.670279 -231.087926)
			(xy 17.678399 -231.143102) (xy 17.678908 -231.170988) (xy 17.678399 -231.198874) (xy 17.670279 -231.25405)
			(xy 17.654211 -231.307457) (xy 17.630539 -231.357954) (xy 17.599766 -231.404467) (xy 17.562549 -231.446004)
			(xy 17.519681 -231.481679) (xy 17.472075 -231.510733) (xy 17.420746 -231.532545) (xy 17.366789 -231.546651)
			(xy 17.311352 -231.552751) (xy 17.255618 -231.550714) (xy 17.200775 -231.540584) (xy 17.147991 -231.522577)
			(xy 17.098391 -231.497076) (xy 17.053033 -231.464625) (xy 17.012884 -231.425916) (xy 16.978798 -231.381773)
			(xy 16.951502 -231.333138) (xy 16.931579 -231.281047) (xy 16.919453 -231.22661) (xy 16.915382 -231.170988)
			(xy 15.610629 -231.170988) (xy 15.611347 -231.175868) (xy 15.611856 -231.203754) (xy 15.611347 -231.23164)
			(xy 15.603227 -231.286816) (xy 15.587159 -231.340223) (xy 15.563487 -231.39072) (xy 15.532714 -231.437233)
			(xy 15.495497 -231.47877) (xy 15.452629 -231.514445) (xy 15.405023 -231.543499) (xy 15.353694 -231.565311)
			(xy 15.299737 -231.579417) (xy 15.2443 -231.585517) (xy 15.188566 -231.58348) (xy 15.133723 -231.57335)
			(xy 15.080939 -231.555343) (xy 15.031339 -231.529842) (xy 14.985981 -231.497391) (xy 14.945832 -231.458682)
			(xy 14.911746 -231.414539) (xy 14.88445 -231.365904) (xy 14.864527 -231.313813) (xy 14.852401 -231.259376)
			(xy 14.84833 -231.203754) (xy 4.38404 -231.203754) (xy 4.38404 -231.95026) (xy 17.786094 -231.95026)
			(xy 17.790165 -231.894638) (xy 17.802291 -231.840201) (xy 17.822214 -231.78811) (xy 17.84951 -231.739475)
			(xy 17.883596 -231.695332) (xy 17.923745 -231.656623) (xy 17.969103 -231.624172) (xy 18.018703 -231.598671)
			(xy 18.071487 -231.580664) (xy 18.12633 -231.570534) (xy 18.182064 -231.568497) (xy 18.237501 -231.574597)
			(xy 18.291458 -231.588703) (xy 18.342787 -231.610515) (xy 18.390393 -231.639569) (xy 18.433261 -231.675244)
			(xy 18.470478 -231.716781) (xy 18.501251 -231.763294) (xy 18.524923 -231.813791) (xy 18.540991 -231.867198)
			(xy 18.549111 -231.922374) (xy 18.54962 -231.95026) (xy 18.549111 -231.978146) (xy 18.540991 -232.033322)
			(xy 18.524923 -232.086729) (xy 18.501251 -232.137226) (xy 18.470478 -232.183739) (xy 18.433261 -232.225276)
			(xy 18.390393 -232.260951) (xy 18.342787 -232.290005) (xy 18.291458 -232.311817) (xy 18.237501 -232.325923)
			(xy 18.182064 -232.332023) (xy 18.12633 -232.329986) (xy 18.071487 -232.319856) (xy 18.018703 -232.301849)
			(xy 17.969103 -232.276348) (xy 17.923745 -232.243897) (xy 17.883596 -232.205188) (xy 17.84951 -232.161045)
			(xy 17.822214 -232.11241) (xy 17.802291 -232.060319) (xy 17.790165 -232.005882) (xy 17.786094 -231.95026)
			(xy 4.38404 -231.95026) (xy 4.38404 -233.590846) (xy 11.623038 -233.590846) (xy 11.627109 -233.535224)
			(xy 11.639235 -233.480787) (xy 11.659158 -233.428696) (xy 11.686454 -233.380061) (xy 11.72054 -233.335918)
			(xy 11.760689 -233.297209) (xy 11.806047 -233.264758) (xy 11.855647 -233.239257) (xy 11.908431 -233.22125)
			(xy 11.963274 -233.21112) (xy 12.019008 -233.209083) (xy 12.074445 -233.215183) (xy 12.128402 -233.229289)
			(xy 12.179731 -233.251101) (xy 12.227337 -233.280155) (xy 12.270205 -233.31583) (xy 12.307422 -233.357367)
			(xy 12.338195 -233.40388) (xy 12.361867 -233.454377) (xy 12.377935 -233.507784) (xy 12.386055 -233.56296)
			(xy 12.386564 -233.590846) (xy 12.386055 -233.618732) (xy 12.377935 -233.673908) (xy 12.361867 -233.727315)
			(xy 12.338195 -233.777812) (xy 12.307422 -233.824325) (xy 12.270205 -233.865862) (xy 12.227337 -233.901537)
			(xy 12.179731 -233.930591) (xy 12.128402 -233.952403) (xy 12.074445 -233.966509) (xy 12.019008 -233.972609)
			(xy 11.963274 -233.970572) (xy 11.908431 -233.960442) (xy 11.855647 -233.942435) (xy 11.806047 -233.916934)
			(xy 11.760689 -233.884483) (xy 11.72054 -233.845774) (xy 11.686454 -233.801631) (xy 11.659158 -233.752996)
			(xy 11.639235 -233.700905) (xy 11.627109 -233.646468) (xy 11.623038 -233.590846) (xy 4.38404 -233.590846)
			(xy 4.38404 -235.290106) (xy 70.550276 -235.290106) (xy 70.554347 -235.234484) (xy 70.566473 -235.180047)
			(xy 70.586396 -235.127956) (xy 70.613692 -235.079321) (xy 70.647778 -235.035178) (xy 70.687927 -234.996469)
			(xy 70.733285 -234.964018) (xy 70.782885 -234.938517) (xy 70.835669 -234.92051) (xy 70.890512 -234.91038)
			(xy 70.946246 -234.908343) (xy 71.001683 -234.914443) (xy 71.05564 -234.928549) (xy 71.106969 -234.950361)
			(xy 71.154575 -234.979415) (xy 71.160738 -234.984544) (xy 93.107 -234.984544) (xy 93.111071 -234.928922)
			(xy 93.123197 -234.874485) (xy 93.14312 -234.822394) (xy 93.170416 -234.773759) (xy 93.204502 -234.729616)
			(xy 93.244651 -234.690907) (xy 93.290009 -234.658456) (xy 93.339609 -234.632955) (xy 93.392393 -234.614948)
			(xy 93.447236 -234.604818) (xy 93.50297 -234.602781) (xy 93.558407 -234.608881) (xy 93.612364 -234.622987)
			(xy 93.663693 -234.644799) (xy 93.711299 -234.673853) (xy 93.754167 -234.709528) (xy 93.791384 -234.751065)
			(xy 93.822157 -234.797578) (xy 93.845829 -234.848075) (xy 93.861897 -234.901482) (xy 93.870017 -234.956658)
			(xy 93.870526 -234.984544) (xy 93.870017 -235.01243) (xy 93.861897 -235.067606) (xy 93.845829 -235.121013)
			(xy 93.822157 -235.17151) (xy 93.791384 -235.218023) (xy 93.754167 -235.25956) (xy 93.711299 -235.295235)
			(xy 93.663693 -235.324289) (xy 93.612364 -235.346101) (xy 93.558407 -235.360207) (xy 93.50297 -235.366307)
			(xy 93.447236 -235.36427) (xy 93.392393 -235.35414) (xy 93.339609 -235.336133) (xy 93.290009 -235.310632)
			(xy 93.244651 -235.278181) (xy 93.204502 -235.239472) (xy 93.170416 -235.195329) (xy 93.14312 -235.146694)
			(xy 93.123197 -235.094603) (xy 93.111071 -235.040166) (xy 93.107 -234.984544) (xy 71.160738 -234.984544)
			(xy 71.197443 -235.01509) (xy 71.23466 -235.056627) (xy 71.265433 -235.10314) (xy 71.289105 -235.153637)
			(xy 71.305173 -235.207044) (xy 71.313293 -235.26222) (xy 71.313802 -235.290106) (xy 71.313293 -235.317992)
			(xy 71.305173 -235.373168) (xy 71.289105 -235.426575) (xy 71.265433 -235.477072) (xy 71.23466 -235.523585)
			(xy 71.197443 -235.565122) (xy 71.154575 -235.600797) (xy 71.106969 -235.629851) (xy 71.05564 -235.651663)
			(xy 71.001683 -235.665769) (xy 70.946246 -235.671869) (xy 70.890512 -235.669832) (xy 70.835669 -235.659702)
			(xy 70.782885 -235.641695) (xy 70.733285 -235.616194) (xy 70.687927 -235.583743) (xy 70.647778 -235.545034)
			(xy 70.613692 -235.500891) (xy 70.586396 -235.452256) (xy 70.566473 -235.400165) (xy 70.554347 -235.345728)
			(xy 70.550276 -235.290106) (xy 4.38404 -235.290106) (xy 4.38404 -236.561884) (xy 93.248986 -236.561884)
			(xy 93.253057 -236.506262) (xy 93.265183 -236.451825) (xy 93.285106 -236.399734) (xy 93.312402 -236.351099)
			(xy 93.346488 -236.306956) (xy 93.386637 -236.268247) (xy 93.431995 -236.235796) (xy 93.481595 -236.210295)
			(xy 93.534379 -236.192288) (xy 93.589222 -236.182158) (xy 93.644956 -236.180121) (xy 93.700393 -236.186221)
			(xy 93.75435 -236.200327) (xy 93.805679 -236.222139) (xy 93.853285 -236.251193) (xy 93.896153 -236.286868)
			(xy 93.93337 -236.328405) (xy 93.964143 -236.374918) (xy 93.987815 -236.425415) (xy 94.003883 -236.478822)
			(xy 94.012003 -236.533998) (xy 94.012512 -236.561884) (xy 94.012003 -236.58977) (xy 94.003883 -236.644946)
			(xy 93.987815 -236.698353) (xy 93.964143 -236.74885) (xy 93.93337 -236.795363) (xy 93.896153 -236.8369)
			(xy 93.853285 -236.872575) (xy 93.805679 -236.901629) (xy 93.75435 -236.923441) (xy 93.700393 -236.937547)
			(xy 93.644956 -236.943647) (xy 93.589222 -236.94161) (xy 93.534379 -236.93148) (xy 93.481595 -236.913473)
			(xy 93.431995 -236.887972) (xy 93.386637 -236.855521) (xy 93.346488 -236.816812) (xy 93.312402 -236.772669)
			(xy 93.285106 -236.724034) (xy 93.265183 -236.671943) (xy 93.253057 -236.617506) (xy 93.248986 -236.561884)
			(xy 4.38404 -236.561884) (xy 4.38404 -242.016026) (xy 4.383611 -242.026093) (xy 4.375883 -242.044685)
			(xy 4.369054 -242.052094) (xy 0.886206 -245.534942) (xy 0.883503 -245.537795) (xy 0.878917 -245.544177)
			(xy 0.877062 -245.547642) (xy 0.874476 -245.553068) (xy 0.871648 -245.564748) (xy 0.871474 -245.570756)
			(xy 0.871474 -246.444516) (xy 0.871047 -246.454584) (xy 0.863326 -246.473182) (xy 0.856488 -246.480584)
			(xy 0.544576 -246.792496) (xy 0.541868 -246.795346) (xy 0.537271 -246.801722) (xy 0.535432 -246.805196)
			(xy 0.532853 -246.810624) (xy 0.53004 -246.822303) (xy 0.529844 -246.82831) (xy 0.529844 -255.732026)
			(xy 3.944364 -255.732026) (xy 3.948435 -255.676404) (xy 3.960561 -255.621967) (xy 3.980484 -255.569876)
			(xy 4.00778 -255.521241) (xy 4.041866 -255.477098) (xy 4.082015 -255.438389) (xy 4.127373 -255.405938)
			(xy 4.176973 -255.380437) (xy 4.229757 -255.36243) (xy 4.2846 -255.3523) (xy 4.340334 -255.350263)
			(xy 4.395771 -255.356363) (xy 4.449728 -255.370469) (xy 4.501057 -255.392281) (xy 4.548663 -255.421335)
			(xy 4.591531 -255.45701) (xy 4.628748 -255.498547) (xy 4.659521 -255.54506) (xy 4.683193 -255.595557)
			(xy 4.692308 -255.625854) (xy 5.829806 -255.625854) (xy 5.833877 -255.570232) (xy 5.846003 -255.515795)
			(xy 5.865926 -255.463704) (xy 5.893222 -255.415069) (xy 5.927308 -255.370926) (xy 5.967457 -255.332217)
			(xy 6.012815 -255.299766) (xy 6.062415 -255.274265) (xy 6.115199 -255.256258) (xy 6.170042 -255.246128)
			(xy 6.225776 -255.244091) (xy 6.281213 -255.250191) (xy 6.33517 -255.264297) (xy 6.386499 -255.286109)
			(xy 6.434105 -255.315163) (xy 6.476973 -255.350838) (xy 6.51419 -255.392375) (xy 6.544963 -255.438888)
			(xy 6.568635 -255.489385) (xy 6.584703 -255.542792) (xy 6.592823 -255.597968) (xy 6.593332 -255.625854)
			(xy 6.592831 -255.653286) (xy 7.359648 -255.653286) (xy 7.363719 -255.597664) (xy 7.375845 -255.543227)
			(xy 7.395768 -255.491136) (xy 7.423064 -255.442501) (xy 7.45715 -255.398358) (xy 7.497299 -255.359649)
			(xy 7.542657 -255.327198) (xy 7.592257 -255.301697) (xy 7.645041 -255.28369) (xy 7.699884 -255.27356)
			(xy 7.755618 -255.271523) (xy 7.811055 -255.277623) (xy 7.865012 -255.291729) (xy 7.916341 -255.313541)
			(xy 7.963947 -255.342595) (xy 8.006815 -255.37827) (xy 8.044032 -255.419807) (xy 8.074805 -255.46632)
			(xy 8.098477 -255.516817) (xy 8.114545 -255.570224) (xy 8.119741 -255.605534) (xy 8.896348 -255.605534)
			(xy 8.900419 -255.549912) (xy 8.912545 -255.495475) (xy 8.932468 -255.443384) (xy 8.959764 -255.394749)
			(xy 8.99385 -255.350606) (xy 9.033999 -255.311897) (xy 9.079357 -255.279446) (xy 9.128957 -255.253945)
			(xy 9.181741 -255.235938) (xy 9.236584 -255.225808) (xy 9.292318 -255.223771) (xy 9.347755 -255.229871)
			(xy 9.401712 -255.243977) (xy 9.453041 -255.265789) (xy 9.500647 -255.294843) (xy 9.543515 -255.330518)
			(xy 9.580732 -255.372055) (xy 9.611505 -255.418568) (xy 9.635177 -255.469065) (xy 9.651245 -255.522472)
			(xy 9.659365 -255.577648) (xy 9.659874 -255.605534) (xy 9.659365 -255.63342) (xy 9.651245 -255.688596)
			(xy 9.644369 -255.711452) (xy 10.405362 -255.711452) (xy 10.409433 -255.65583) (xy 10.421559 -255.601393)
			(xy 10.441482 -255.549302) (xy 10.468778 -255.500667) (xy 10.502864 -255.456524) (xy 10.543013 -255.417815)
			(xy 10.588371 -255.385364) (xy 10.637971 -255.359863) (xy 10.690755 -255.341856) (xy 10.745598 -255.331726)
			(xy 10.801332 -255.329689) (xy 10.856769 -255.335789) (xy 10.910726 -255.349895) (xy 10.962055 -255.371707)
			(xy 11.009661 -255.400761) (xy 11.052529 -255.436436) (xy 11.089746 -255.477973) (xy 11.120519 -255.524486)
			(xy 11.144191 -255.574983) (xy 11.160259 -255.62839) (xy 11.16396 -255.65354) (xy 11.983464 -255.65354)
			(xy 11.987535 -255.597918) (xy 11.999661 -255.543481) (xy 12.019584 -255.49139) (xy 12.04688 -255.442755)
			(xy 12.080966 -255.398612) (xy 12.121115 -255.359903) (xy 12.166473 -255.327452) (xy 12.216073 -255.301951)
			(xy 12.268857 -255.283944) (xy 12.3237 -255.273814) (xy 12.379434 -255.271777) (xy 12.434871 -255.277877)
			(xy 12.488828 -255.291983) (xy 12.540157 -255.313795) (xy 12.587763 -255.342849) (xy 12.630631 -255.378524)
			(xy 12.667848 -255.420061) (xy 12.698621 -255.466574) (xy 12.722293 -255.517071) (xy 12.738361 -255.570478)
			(xy 12.746481 -255.625654) (xy 12.74699 -255.65354) (xy 12.746481 -255.681426) (xy 12.738361 -255.736602)
			(xy 12.722293 -255.790009) (xy 12.698621 -255.840506) (xy 12.667848 -255.887019) (xy 12.630631 -255.928556)
			(xy 12.587763 -255.964231) (xy 12.540157 -255.993285) (xy 12.488828 -256.015097) (xy 12.434871 -256.029203)
			(xy 12.379434 -256.035303) (xy 12.3237 -256.033266) (xy 12.268857 -256.023136) (xy 12.216073 -256.005129)
			(xy 12.166473 -255.979628) (xy 12.121115 -255.947177) (xy 12.080966 -255.908468) (xy 12.04688 -255.864325)
			(xy 12.019584 -255.81569) (xy 11.999661 -255.763599) (xy 11.987535 -255.709162) (xy 11.983464 -255.65354)
			(xy 11.16396 -255.65354) (xy 11.168379 -255.683566) (xy 11.168888 -255.711452) (xy 11.168379 -255.739338)
			(xy 11.160259 -255.794514) (xy 11.144191 -255.847921) (xy 11.120519 -255.898418) (xy 11.089746 -255.944931)
			(xy 11.052529 -255.986468) (xy 11.009661 -256.022143) (xy 10.962055 -256.051197) (xy 10.910726 -256.073009)
			(xy 10.856769 -256.087115) (xy 10.801332 -256.093215) (xy 10.745598 -256.091178) (xy 10.690755 -256.081048)
			(xy 10.637971 -256.063041) (xy 10.588371 -256.03754) (xy 10.543013 -256.005089) (xy 10.502864 -255.96638)
			(xy 10.468778 -255.922237) (xy 10.441482 -255.873602) (xy 10.421559 -255.821511) (xy 10.409433 -255.767074)
			(xy 10.405362 -255.711452) (xy 9.644369 -255.711452) (xy 9.635177 -255.742003) (xy 9.611505 -255.7925)
			(xy 9.580732 -255.839013) (xy 9.543515 -255.88055) (xy 9.500647 -255.916225) (xy 9.453041 -255.945279)
			(xy 9.401712 -255.967091) (xy 9.347755 -255.981197) (xy 9.292318 -255.987297) (xy 9.236584 -255.98526)
			(xy 9.181741 -255.97513) (xy 9.128957 -255.957123) (xy 9.079357 -255.931622) (xy 9.033999 -255.899171)
			(xy 8.99385 -255.860462) (xy 8.959764 -255.816319) (xy 8.932468 -255.767684) (xy 8.912545 -255.715593)
			(xy 8.900419 -255.661156) (xy 8.896348 -255.605534) (xy 8.119741 -255.605534) (xy 8.122665 -255.6254)
			(xy 8.123174 -255.653286) (xy 8.122665 -255.681172) (xy 8.114545 -255.736348) (xy 8.098477 -255.789755)
			(xy 8.074805 -255.840252) (xy 8.044032 -255.886765) (xy 8.006815 -255.928302) (xy 7.963947 -255.963977)
			(xy 7.916341 -255.993031) (xy 7.865012 -256.014843) (xy 7.811055 -256.028949) (xy 7.755618 -256.035049)
			(xy 7.699884 -256.033012) (xy 7.645041 -256.022882) (xy 7.592257 -256.004875) (xy 7.542657 -255.979374)
			(xy 7.497299 -255.946923) (xy 7.45715 -255.908214) (xy 7.423064 -255.864071) (xy 7.395768 -255.815436)
			(xy 7.375845 -255.763345) (xy 7.363719 -255.708908) (xy 7.359648 -255.653286) (xy 6.592831 -255.653286)
			(xy 6.592823 -255.65374) (xy 6.584703 -255.708916) (xy 6.568635 -255.762323) (xy 6.544963 -255.81282)
			(xy 6.51419 -255.859333) (xy 6.476973 -255.90087) (xy 6.434105 -255.936545) (xy 6.386499 -255.965599)
			(xy 6.33517 -255.987411) (xy 6.281213 -256.001517) (xy 6.225776 -256.007617) (xy 6.170042 -256.00558)
			(xy 6.115199 -255.99545) (xy 6.062415 -255.977443) (xy 6.012815 -255.951942) (xy 5.967457 -255.919491)
			(xy 5.927308 -255.880782) (xy 5.893222 -255.836639) (xy 5.865926 -255.788004) (xy 5.846003 -255.735913)
			(xy 5.833877 -255.681476) (xy 5.829806 -255.625854) (xy 4.692308 -255.625854) (xy 4.699261 -255.648964)
			(xy 4.707381 -255.70414) (xy 4.70789 -255.732026) (xy 4.707381 -255.759912) (xy 4.699261 -255.815088)
			(xy 4.683193 -255.868495) (xy 4.659521 -255.918992) (xy 4.628748 -255.965505) (xy 4.591531 -256.007042)
			(xy 4.548663 -256.042717) (xy 4.501057 -256.071771) (xy 4.449728 -256.093583) (xy 4.395771 -256.107689)
			(xy 4.340334 -256.113789) (xy 4.2846 -256.111752) (xy 4.229757 -256.101622) (xy 4.176973 -256.083615)
			(xy 4.127373 -256.058114) (xy 4.082015 -256.025663) (xy 4.041866 -255.986954) (xy 4.00778 -255.942811)
			(xy 3.980484 -255.894176) (xy 3.960561 -255.842085) (xy 3.948435 -255.787648) (xy 3.944364 -255.732026)
			(xy 0.529844 -255.732026) (xy 0.529844 -256.516124) (xy 3.26466 -256.516124) (xy 3.268731 -256.460502)
			(xy 3.280857 -256.406065) (xy 3.30078 -256.353974) (xy 3.328076 -256.305339) (xy 3.362162 -256.261196)
			(xy 3.402311 -256.222487) (xy 3.447669 -256.190036) (xy 3.497269 -256.164535) (xy 3.550053 -256.146528)
			(xy 3.604896 -256.136398) (xy 3.66063 -256.134361) (xy 3.716067 -256.140461) (xy 3.770024 -256.154567)
			(xy 3.821353 -256.176379) (xy 3.868959 -256.205433) (xy 3.911827 -256.241108) (xy 3.949044 -256.282645)
			(xy 3.979817 -256.329158) (xy 4.003489 -256.379655) (xy 4.019557 -256.433062) (xy 4.025875 -256.475992)
			(xy 4.752846 -256.475992) (xy 4.756917 -256.42037) (xy 4.769043 -256.365933) (xy 4.788966 -256.313842)
			(xy 4.816262 -256.265207) (xy 4.850348 -256.221064) (xy 4.890497 -256.182355) (xy 4.935855 -256.149904)
			(xy 4.985455 -256.124403) (xy 5.038239 -256.106396) (xy 5.093082 -256.096266) (xy 5.148816 -256.094229)
			(xy 5.204253 -256.100329) (xy 5.25821 -256.114435) (xy 5.309539 -256.136247) (xy 5.357145 -256.165301)
			(xy 5.400013 -256.200976) (xy 5.43723 -256.242513) (xy 5.468003 -256.289026) (xy 5.491675 -256.339523)
			(xy 5.507743 -256.39293) (xy 5.515863 -256.448106) (xy 5.516372 -256.475992) (xy 5.515863 -256.503878)
			(xy 5.511108 -256.53619) (xy 6.261352 -256.53619) (xy 6.265423 -256.480568) (xy 6.277549 -256.426131)
			(xy 6.297472 -256.37404) (xy 6.324768 -256.325405) (xy 6.358854 -256.281262) (xy 6.399003 -256.242553)
			(xy 6.444361 -256.210102) (xy 6.493961 -256.184601) (xy 6.546745 -256.166594) (xy 6.601588 -256.156464)
			(xy 6.657322 -256.154427) (xy 6.712759 -256.160527) (xy 6.766716 -256.174633) (xy 6.818045 -256.196445)
			(xy 6.865651 -256.225499) (xy 6.908519 -256.261174) (xy 6.945736 -256.302711) (xy 6.976509 -256.349224)
			(xy 7.000181 -256.399721) (xy 7.016249 -256.453128) (xy 7.019614 -256.475992) (xy 7.769604 -256.475992)
			(xy 7.773675 -256.42037) (xy 7.785801 -256.365933) (xy 7.805724 -256.313842) (xy 7.83302 -256.265207)
			(xy 7.867106 -256.221064) (xy 7.907255 -256.182355) (xy 7.952613 -256.149904) (xy 8.002213 -256.124403)
			(xy 8.054997 -256.106396) (xy 8.10984 -256.096266) (xy 8.165574 -256.094229) (xy 8.221011 -256.100329)
			(xy 8.274968 -256.114435) (xy 8.326297 -256.136247) (xy 8.373903 -256.165301) (xy 8.416771 -256.200976)
			(xy 8.453988 -256.242513) (xy 8.484761 -256.289026) (xy 8.508433 -256.339523) (xy 8.513192 -256.355342)
			(xy 9.479024 -256.355342) (xy 9.483095 -256.29972) (xy 9.495221 -256.245283) (xy 9.515144 -256.193192)
			(xy 9.54244 -256.144557) (xy 9.576526 -256.100414) (xy 9.616675 -256.061705) (xy 9.662033 -256.029254)
			(xy 9.711633 -256.003753) (xy 9.764417 -255.985746) (xy 9.81926 -255.975616) (xy 9.874994 -255.973579)
			(xy 9.930431 -255.979679) (xy 9.984388 -255.993785) (xy 10.035717 -256.015597) (xy 10.083323 -256.044651)
			(xy 10.126191 -256.080326) (xy 10.163408 -256.121863) (xy 10.194181 -256.168376) (xy 10.217853 -256.218873)
			(xy 10.233921 -256.27228) (xy 10.242041 -256.327456) (xy 10.24255 -256.355342) (xy 10.242041 -256.383228)
			(xy 10.237286 -256.41554) (xy 11.047728 -256.41554) (xy 11.051799 -256.359918) (xy 11.063925 -256.305481)
			(xy 11.083848 -256.25339) (xy 11.111144 -256.204755) (xy 11.14523 -256.160612) (xy 11.185379 -256.121903)
			(xy 11.230737 -256.089452) (xy 11.280337 -256.063951) (xy 11.333121 -256.045944) (xy 11.387964 -256.035814)
			(xy 11.443698 -256.033777) (xy 11.499135 -256.039877) (xy 11.553092 -256.053983) (xy 11.604421 -256.075795)
			(xy 11.652027 -256.104849) (xy 11.694895 -256.140524) (xy 11.732112 -256.182061) (xy 11.762885 -256.228574)
			(xy 11.786557 -256.279071) (xy 11.802625 -256.332478) (xy 11.810745 -256.387654) (xy 11.811254 -256.41554)
			(xy 11.810888 -256.435606) (xy 12.455396 -256.435606) (xy 12.459467 -256.379984) (xy 12.471593 -256.325547)
			(xy 12.491516 -256.273456) (xy 12.518812 -256.224821) (xy 12.552898 -256.180678) (xy 12.593047 -256.141969)
			(xy 12.638405 -256.109518) (xy 12.688005 -256.084017) (xy 12.740789 -256.06601) (xy 12.795632 -256.05588)
			(xy 12.851366 -256.053843) (xy 12.906803 -256.059943) (xy 12.96076 -256.074049) (xy 13.012089 -256.095861)
			(xy 13.059695 -256.124915) (xy 13.102563 -256.16059) (xy 13.13978 -256.202127) (xy 13.170553 -256.24864)
			(xy 13.194225 -256.299137) (xy 13.210293 -256.352544) (xy 13.218413 -256.40772) (xy 13.218922 -256.435606)
			(xy 13.218413 -256.463492) (xy 13.210293 -256.518668) (xy 13.194225 -256.572075) (xy 13.170553 -256.622572)
			(xy 13.13978 -256.669085) (xy 13.102563 -256.710622) (xy 13.059695 -256.746297) (xy 13.012089 -256.775351)
			(xy 12.96076 -256.797163) (xy 12.906803 -256.811269) (xy 12.851366 -256.817369) (xy 12.795632 -256.815332)
			(xy 12.740789 -256.805202) (xy 12.688005 -256.787195) (xy 12.638405 -256.761694) (xy 12.593047 -256.729243)
			(xy 12.552898 -256.690534) (xy 12.518812 -256.646391) (xy 12.491516 -256.597756) (xy 12.471593 -256.545665)
			(xy 12.459467 -256.491228) (xy 12.455396 -256.435606) (xy 11.810888 -256.435606) (xy 11.810745 -256.443426)
			(xy 11.802625 -256.498602) (xy 11.786557 -256.552009) (xy 11.762885 -256.602506) (xy 11.732112 -256.649019)
			(xy 11.694895 -256.690556) (xy 11.652027 -256.726231) (xy 11.604421 -256.755285) (xy 11.553092 -256.777097)
			(xy 11.499135 -256.791203) (xy 11.443698 -256.797303) (xy 11.387964 -256.795266) (xy 11.333121 -256.785136)
			(xy 11.280337 -256.767129) (xy 11.230737 -256.741628) (xy 11.185379 -256.709177) (xy 11.14523 -256.670468)
			(xy 11.111144 -256.626325) (xy 11.083848 -256.57769) (xy 11.063925 -256.525599) (xy 11.051799 -256.471162)
			(xy 11.047728 -256.41554) (xy 10.237286 -256.41554) (xy 10.233921 -256.438404) (xy 10.217853 -256.491811)
			(xy 10.194181 -256.542308) (xy 10.163408 -256.588821) (xy 10.126191 -256.630358) (xy 10.083323 -256.666033)
			(xy 10.035717 -256.695087) (xy 9.984388 -256.716899) (xy 9.930431 -256.731005) (xy 9.874994 -256.737105)
			(xy 9.81926 -256.735068) (xy 9.764417 -256.724938) (xy 9.711633 -256.706931) (xy 9.662033 -256.68143)
			(xy 9.616675 -256.648979) (xy 9.576526 -256.61027) (xy 9.54244 -256.566127) (xy 9.515144 -256.517492)
			(xy 9.495221 -256.465401) (xy 9.483095 -256.410964) (xy 9.479024 -256.355342) (xy 8.513192 -256.355342)
			(xy 8.524501 -256.39293) (xy 8.532621 -256.448106) (xy 8.53313 -256.475992) (xy 8.532621 -256.503878)
			(xy 8.524501 -256.559054) (xy 8.508433 -256.612461) (xy 8.484761 -256.662958) (xy 8.453988 -256.709471)
			(xy 8.416771 -256.751008) (xy 8.373903 -256.786683) (xy 8.326297 -256.815737) (xy 8.274968 -256.837549)
			(xy 8.221011 -256.851655) (xy 8.165574 -256.857755) (xy 8.10984 -256.855718) (xy 8.054997 -256.845588)
			(xy 8.002213 -256.827581) (xy 7.952613 -256.80208) (xy 7.907255 -256.769629) (xy 7.867106 -256.73092)
			(xy 7.83302 -256.686777) (xy 7.805724 -256.638142) (xy 7.785801 -256.586051) (xy 7.773675 -256.531614)
			(xy 7.769604 -256.475992) (xy 7.019614 -256.475992) (xy 7.024369 -256.508304) (xy 7.024878 -256.53619)
			(xy 7.024369 -256.564076) (xy 7.016249 -256.619252) (xy 7.000181 -256.672659) (xy 6.976509 -256.723156)
			(xy 6.945736 -256.769669) (xy 6.908519 -256.811206) (xy 6.865651 -256.846881) (xy 6.818045 -256.875935)
			(xy 6.766716 -256.897747) (xy 6.712759 -256.911853) (xy 6.657322 -256.917953) (xy 6.601588 -256.915916)
			(xy 6.546745 -256.905786) (xy 6.493961 -256.887779) (xy 6.444361 -256.862278) (xy 6.399003 -256.829827)
			(xy 6.358854 -256.791118) (xy 6.324768 -256.746975) (xy 6.297472 -256.69834) (xy 6.277549 -256.646249)
			(xy 6.265423 -256.591812) (xy 6.261352 -256.53619) (xy 5.511108 -256.53619) (xy 5.507743 -256.559054)
			(xy 5.491675 -256.612461) (xy 5.468003 -256.662958) (xy 5.43723 -256.709471) (xy 5.400013 -256.751008)
			(xy 5.357145 -256.786683) (xy 5.309539 -256.815737) (xy 5.25821 -256.837549) (xy 5.204253 -256.851655)
			(xy 5.148816 -256.857755) (xy 5.093082 -256.855718) (xy 5.038239 -256.845588) (xy 4.985455 -256.827581)
			(xy 4.935855 -256.80208) (xy 4.890497 -256.769629) (xy 4.850348 -256.73092) (xy 4.816262 -256.686777)
			(xy 4.788966 -256.638142) (xy 4.769043 -256.586051) (xy 4.756917 -256.531614) (xy 4.752846 -256.475992)
			(xy 4.025875 -256.475992) (xy 4.027677 -256.488238) (xy 4.028186 -256.516124) (xy 4.027677 -256.54401)
			(xy 4.019557 -256.599186) (xy 4.003489 -256.652593) (xy 3.979817 -256.70309) (xy 3.949044 -256.749603)
			(xy 3.911827 -256.79114) (xy 3.868959 -256.826815) (xy 3.821353 -256.855869) (xy 3.770024 -256.877681)
			(xy 3.716067 -256.891787) (xy 3.66063 -256.897887) (xy 3.604896 -256.89585) (xy 3.550053 -256.88572)
			(xy 3.497269 -256.867713) (xy 3.447669 -256.842212) (xy 3.402311 -256.809761) (xy 3.362162 -256.771052)
			(xy 3.328076 -256.726909) (xy 3.30078 -256.678274) (xy 3.280857 -256.626183) (xy 3.268731 -256.571746)
			(xy 3.26466 -256.516124) (xy 0.529844 -256.516124) (xy 0.529844 -257.60807) (xy 3.22402 -257.60807)
			(xy 3.228091 -257.552448) (xy 3.240217 -257.498011) (xy 3.26014 -257.44592) (xy 3.287436 -257.397285)
			(xy 3.321522 -257.353142) (xy 3.361671 -257.314433) (xy 3.407029 -257.281982) (xy 3.456629 -257.256481)
			(xy 3.509413 -257.238474) (xy 3.564256 -257.228344) (xy 3.61999 -257.226307) (xy 3.675427 -257.232407)
			(xy 3.729384 -257.246513) (xy 3.780713 -257.268325) (xy 3.828319 -257.297379) (xy 3.871187 -257.333054)
			(xy 3.908404 -257.374591) (xy 3.939177 -257.421104) (xy 3.962849 -257.471601) (xy 3.978917 -257.525008)
			(xy 3.987037 -257.580184) (xy 3.987546 -257.60807) (xy 4.74802 -257.60807) (xy 4.752091 -257.552448)
			(xy 4.764217 -257.498011) (xy 4.78414 -257.44592) (xy 4.811436 -257.397285) (xy 4.845522 -257.353142)
			(xy 4.885671 -257.314433) (xy 4.931029 -257.281982) (xy 4.980629 -257.256481) (xy 5.033413 -257.238474)
			(xy 5.088256 -257.228344) (xy 5.14399 -257.226307) (xy 5.199427 -257.232407) (xy 5.253384 -257.246513)
			(xy 5.304713 -257.268325) (xy 5.352319 -257.297379) (xy 5.395187 -257.333054) (xy 5.432404 -257.374591)
			(xy 5.463177 -257.421104) (xy 5.486849 -257.471601) (xy 5.502917 -257.525008) (xy 5.511037 -257.580184)
			(xy 5.511546 -257.60807) (xy 7.03402 -257.60807) (xy 7.038091 -257.552448) (xy 7.050217 -257.498011)
			(xy 7.07014 -257.44592) (xy 7.097436 -257.397285) (xy 7.131522 -257.353142) (xy 7.171671 -257.314433)
			(xy 7.217029 -257.281982) (xy 7.266629 -257.256481) (xy 7.319413 -257.238474) (xy 7.374256 -257.228344)
			(xy 7.42999 -257.226307) (xy 7.485427 -257.232407) (xy 7.539384 -257.246513) (xy 7.590713 -257.268325)
			(xy 7.638319 -257.297379) (xy 7.681187 -257.333054) (xy 7.718404 -257.374591) (xy 7.749177 -257.421104)
			(xy 7.772849 -257.471601) (xy 7.788917 -257.525008) (xy 7.797037 -257.580184) (xy 7.797546 -257.60807)
			(xy 8.55802 -257.60807) (xy 8.562091 -257.552448) (xy 8.574217 -257.498011) (xy 8.59414 -257.44592)
			(xy 8.621436 -257.397285) (xy 8.655522 -257.353142) (xy 8.695671 -257.314433) (xy 8.741029 -257.281982)
			(xy 8.790629 -257.256481) (xy 8.843413 -257.238474) (xy 8.898256 -257.228344) (xy 8.95399 -257.226307)
			(xy 9.009427 -257.232407) (xy 9.063384 -257.246513) (xy 9.114713 -257.268325) (xy 9.162319 -257.297379)
			(xy 9.205187 -257.333054) (xy 9.242404 -257.374591) (xy 9.273177 -257.421104) (xy 9.296849 -257.471601)
			(xy 9.312917 -257.525008) (xy 9.321037 -257.580184) (xy 9.321546 -257.60807) (xy 10.08202 -257.60807)
			(xy 10.086091 -257.552448) (xy 10.098217 -257.498011) (xy 10.11814 -257.44592) (xy 10.145436 -257.397285)
			(xy 10.179522 -257.353142) (xy 10.219671 -257.314433) (xy 10.265029 -257.281982) (xy 10.314629 -257.256481)
			(xy 10.367413 -257.238474) (xy 10.422256 -257.228344) (xy 10.47799 -257.226307) (xy 10.533427 -257.232407)
			(xy 10.587384 -257.246513) (xy 10.638713 -257.268325) (xy 10.686319 -257.297379) (xy 10.729187 -257.333054)
			(xy 10.766404 -257.374591) (xy 10.797177 -257.421104) (xy 10.820849 -257.471601) (xy 10.836917 -257.525008)
			(xy 10.845037 -257.580184) (xy 10.845546 -257.60807) (xy 11.60602 -257.60807) (xy 11.610091 -257.552448)
			(xy 11.622217 -257.498011) (xy 11.64214 -257.44592) (xy 11.669436 -257.397285) (xy 11.703522 -257.353142)
			(xy 11.743671 -257.314433) (xy 11.789029 -257.281982) (xy 11.838629 -257.256481) (xy 11.891413 -257.238474)
			(xy 11.946256 -257.228344) (xy 12.00199 -257.226307) (xy 12.057427 -257.232407) (xy 12.111384 -257.246513)
			(xy 12.162713 -257.268325) (xy 12.210319 -257.297379) (xy 12.253187 -257.333054) (xy 12.290404 -257.374591)
			(xy 12.321177 -257.421104) (xy 12.344849 -257.471601) (xy 12.360917 -257.525008) (xy 12.369037 -257.580184)
			(xy 12.369546 -257.60807) (xy 13.13002 -257.60807) (xy 13.134091 -257.552448) (xy 13.146217 -257.498011)
			(xy 13.16614 -257.44592) (xy 13.193436 -257.397285) (xy 13.227522 -257.353142) (xy 13.267671 -257.314433)
			(xy 13.313029 -257.281982) (xy 13.362629 -257.256481) (xy 13.415413 -257.238474) (xy 13.470256 -257.228344)
			(xy 13.52599 -257.226307) (xy 13.581427 -257.232407) (xy 13.635384 -257.246513) (xy 13.686713 -257.268325)
			(xy 13.734319 -257.297379) (xy 13.777187 -257.333054) (xy 13.814404 -257.374591) (xy 13.845177 -257.421104)
			(xy 13.868849 -257.471601) (xy 13.884917 -257.525008) (xy 13.893037 -257.580184) (xy 13.893546 -257.60807)
			(xy 13.893037 -257.635956) (xy 13.884917 -257.691132) (xy 13.868849 -257.744539) (xy 13.845177 -257.795036)
			(xy 13.814404 -257.841549) (xy 13.777187 -257.883086) (xy 13.734319 -257.918761) (xy 13.686713 -257.947815)
			(xy 13.635384 -257.969627) (xy 13.581427 -257.983733) (xy 13.52599 -257.989833) (xy 13.470256 -257.987796)
			(xy 13.415413 -257.977666) (xy 13.362629 -257.959659) (xy 13.313029 -257.934158) (xy 13.267671 -257.901707)
			(xy 13.227522 -257.862998) (xy 13.193436 -257.818855) (xy 13.16614 -257.77022) (xy 13.146217 -257.718129)
			(xy 13.134091 -257.663692) (xy 13.13002 -257.60807) (xy 12.369546 -257.60807) (xy 12.369037 -257.635956)
			(xy 12.360917 -257.691132) (xy 12.344849 -257.744539) (xy 12.321177 -257.795036) (xy 12.290404 -257.841549)
			(xy 12.253187 -257.883086) (xy 12.210319 -257.918761) (xy 12.162713 -257.947815) (xy 12.111384 -257.969627)
			(xy 12.057427 -257.983733) (xy 12.00199 -257.989833) (xy 11.946256 -257.987796) (xy 11.891413 -257.977666)
			(xy 11.838629 -257.959659) (xy 11.789029 -257.934158) (xy 11.743671 -257.901707) (xy 11.703522 -257.862998)
			(xy 11.669436 -257.818855) (xy 11.64214 -257.77022) (xy 11.622217 -257.718129) (xy 11.610091 -257.663692)
			(xy 11.60602 -257.60807) (xy 10.845546 -257.60807) (xy 10.845037 -257.635956) (xy 10.836917 -257.691132)
			(xy 10.820849 -257.744539) (xy 10.797177 -257.795036) (xy 10.766404 -257.841549) (xy 10.729187 -257.883086)
			(xy 10.686319 -257.918761) (xy 10.638713 -257.947815) (xy 10.587384 -257.969627) (xy 10.533427 -257.983733)
			(xy 10.47799 -257.989833) (xy 10.422256 -257.987796) (xy 10.367413 -257.977666) (xy 10.314629 -257.959659)
			(xy 10.265029 -257.934158) (xy 10.219671 -257.901707) (xy 10.179522 -257.862998) (xy 10.145436 -257.818855)
			(xy 10.11814 -257.77022) (xy 10.098217 -257.718129) (xy 10.086091 -257.663692) (xy 10.08202 -257.60807)
			(xy 9.321546 -257.60807) (xy 9.321037 -257.635956) (xy 9.312917 -257.691132) (xy 9.296849 -257.744539)
			(xy 9.273177 -257.795036) (xy 9.242404 -257.841549) (xy 9.205187 -257.883086) (xy 9.162319 -257.918761)
			(xy 9.114713 -257.947815) (xy 9.063384 -257.969627) (xy 9.009427 -257.983733) (xy 8.95399 -257.989833)
			(xy 8.898256 -257.987796) (xy 8.843413 -257.977666) (xy 8.790629 -257.959659) (xy 8.741029 -257.934158)
			(xy 8.695671 -257.901707) (xy 8.655522 -257.862998) (xy 8.621436 -257.818855) (xy 8.59414 -257.77022)
			(xy 8.574217 -257.718129) (xy 8.562091 -257.663692) (xy 8.55802 -257.60807) (xy 7.797546 -257.60807)
			(xy 7.797037 -257.635956) (xy 7.788917 -257.691132) (xy 7.772849 -257.744539) (xy 7.749177 -257.795036)
			(xy 7.718404 -257.841549) (xy 7.681187 -257.883086) (xy 7.638319 -257.918761) (xy 7.590713 -257.947815)
			(xy 7.539384 -257.969627) (xy 7.485427 -257.983733) (xy 7.42999 -257.989833) (xy 7.374256 -257.987796)
			(xy 7.319413 -257.977666) (xy 7.266629 -257.959659) (xy 7.217029 -257.934158) (xy 7.171671 -257.901707)
			(xy 7.131522 -257.862998) (xy 7.097436 -257.818855) (xy 7.07014 -257.77022) (xy 7.050217 -257.718129)
			(xy 7.038091 -257.663692) (xy 7.03402 -257.60807) (xy 5.511546 -257.60807) (xy 5.511037 -257.635956)
			(xy 5.502917 -257.691132) (xy 5.486849 -257.744539) (xy 5.463177 -257.795036) (xy 5.432404 -257.841549)
			(xy 5.395187 -257.883086) (xy 5.352319 -257.918761) (xy 5.304713 -257.947815) (xy 5.253384 -257.969627)
			(xy 5.199427 -257.983733) (xy 5.14399 -257.989833) (xy 5.088256 -257.987796) (xy 5.033413 -257.977666)
			(xy 4.980629 -257.959659) (xy 4.931029 -257.934158) (xy 4.885671 -257.901707) (xy 4.845522 -257.862998)
			(xy 4.811436 -257.818855) (xy 4.78414 -257.77022) (xy 4.764217 -257.718129) (xy 4.752091 -257.663692)
			(xy 4.74802 -257.60807) (xy 3.987546 -257.60807) (xy 3.987037 -257.635956) (xy 3.978917 -257.691132)
			(xy 3.962849 -257.744539) (xy 3.939177 -257.795036) (xy 3.908404 -257.841549) (xy 3.871187 -257.883086)
			(xy 3.828319 -257.918761) (xy 3.780713 -257.947815) (xy 3.729384 -257.969627) (xy 3.675427 -257.983733)
			(xy 3.61999 -257.989833) (xy 3.564256 -257.987796) (xy 3.509413 -257.977666) (xy 3.456629 -257.959659)
			(xy 3.407029 -257.934158) (xy 3.361671 -257.901707) (xy 3.321522 -257.862998) (xy 3.287436 -257.818855)
			(xy 3.26014 -257.77022) (xy 3.240217 -257.718129) (xy 3.228091 -257.663692) (xy 3.22402 -257.60807)
			(xy 0.529844 -257.60807) (xy 0.529844 -258.510786) (xy 3.22402 -258.510786) (xy 3.228091 -258.455164)
			(xy 3.240217 -258.400727) (xy 3.26014 -258.348636) (xy 3.287436 -258.300001) (xy 3.321522 -258.255858)
			(xy 3.361671 -258.217149) (xy 3.407029 -258.184698) (xy 3.456629 -258.159197) (xy 3.509413 -258.14119)
			(xy 3.564256 -258.13106) (xy 3.61999 -258.129023) (xy 3.675427 -258.135123) (xy 3.729384 -258.149229)
			(xy 3.780713 -258.171041) (xy 3.828319 -258.200095) (xy 3.871187 -258.23577) (xy 3.908404 -258.277307)
			(xy 3.939177 -258.32382) (xy 3.962849 -258.374317) (xy 3.978917 -258.427724) (xy 3.987037 -258.4829)
			(xy 3.987546 -258.510786) (xy 4.74802 -258.510786) (xy 4.752091 -258.455164) (xy 4.764217 -258.400727)
			(xy 4.78414 -258.348636) (xy 4.811436 -258.300001) (xy 4.845522 -258.255858) (xy 4.885671 -258.217149)
			(xy 4.931029 -258.184698) (xy 4.980629 -258.159197) (xy 5.033413 -258.14119) (xy 5.088256 -258.13106)
			(xy 5.14399 -258.129023) (xy 5.199427 -258.135123) (xy 5.253384 -258.149229) (xy 5.304713 -258.171041)
			(xy 5.352319 -258.200095) (xy 5.395187 -258.23577) (xy 5.432404 -258.277307) (xy 5.463177 -258.32382)
			(xy 5.486849 -258.374317) (xy 5.502917 -258.427724) (xy 5.511037 -258.4829) (xy 5.511546 -258.510786)
			(xy 6.27202 -258.510786) (xy 6.276091 -258.455164) (xy 6.288217 -258.400727) (xy 6.30814 -258.348636)
			(xy 6.335436 -258.300001) (xy 6.369522 -258.255858) (xy 6.409671 -258.217149) (xy 6.455029 -258.184698)
			(xy 6.504629 -258.159197) (xy 6.557413 -258.14119) (xy 6.612256 -258.13106) (xy 6.66799 -258.129023)
			(xy 6.723427 -258.135123) (xy 6.777384 -258.149229) (xy 6.828713 -258.171041) (xy 6.876319 -258.200095)
			(xy 6.919187 -258.23577) (xy 6.956404 -258.277307) (xy 6.987177 -258.32382) (xy 7.010849 -258.374317)
			(xy 7.026917 -258.427724) (xy 7.035037 -258.4829) (xy 7.035546 -258.510786) (xy 7.79602 -258.510786)
			(xy 7.800091 -258.455164) (xy 7.812217 -258.400727) (xy 7.83214 -258.348636) (xy 7.859436 -258.300001)
			(xy 7.893522 -258.255858) (xy 7.933671 -258.217149) (xy 7.979029 -258.184698) (xy 8.028629 -258.159197)
			(xy 8.081413 -258.14119) (xy 8.136256 -258.13106) (xy 8.19199 -258.129023) (xy 8.247427 -258.135123)
			(xy 8.301384 -258.149229) (xy 8.352713 -258.171041) (xy 8.400319 -258.200095) (xy 8.443187 -258.23577)
			(xy 8.480404 -258.277307) (xy 8.511177 -258.32382) (xy 8.534849 -258.374317) (xy 8.550917 -258.427724)
			(xy 8.559037 -258.4829) (xy 8.559546 -258.510786) (xy 9.32002 -258.510786) (xy 9.324091 -258.455164)
			(xy 9.336217 -258.400727) (xy 9.35614 -258.348636) (xy 9.383436 -258.300001) (xy 9.417522 -258.255858)
			(xy 9.457671 -258.217149) (xy 9.503029 -258.184698) (xy 9.552629 -258.159197) (xy 9.605413 -258.14119)
			(xy 9.660256 -258.13106) (xy 9.71599 -258.129023) (xy 9.771427 -258.135123) (xy 9.825384 -258.149229)
			(xy 9.876713 -258.171041) (xy 9.924319 -258.200095) (xy 9.967187 -258.23577) (xy 10.004404 -258.277307)
			(xy 10.035177 -258.32382) (xy 10.058849 -258.374317) (xy 10.074917 -258.427724) (xy 10.083037 -258.4829)
			(xy 10.083546 -258.510786) (xy 10.84402 -258.510786) (xy 10.848091 -258.455164) (xy 10.860217 -258.400727)
			(xy 10.88014 -258.348636) (xy 10.907436 -258.300001) (xy 10.941522 -258.255858) (xy 10.981671 -258.217149)
			(xy 11.027029 -258.184698) (xy 11.076629 -258.159197) (xy 11.129413 -258.14119) (xy 11.184256 -258.13106)
			(xy 11.23999 -258.129023) (xy 11.295427 -258.135123) (xy 11.349384 -258.149229) (xy 11.400713 -258.171041)
			(xy 11.448319 -258.200095) (xy 11.491187 -258.23577) (xy 11.528404 -258.277307) (xy 11.559177 -258.32382)
			(xy 11.582849 -258.374317) (xy 11.598917 -258.427724) (xy 11.607037 -258.4829) (xy 11.607546 -258.510786)
			(xy 11.607037 -258.538672) (xy 11.602805 -258.567428) (xy 11.988798 -258.567428) (xy 11.992869 -258.511806)
			(xy 12.004995 -258.457369) (xy 12.024918 -258.405278) (xy 12.052214 -258.356643) (xy 12.0863 -258.3125)
			(xy 12.126449 -258.273791) (xy 12.171807 -258.24134) (xy 12.221407 -258.215839) (xy 12.274191 -258.197832)
			(xy 12.329034 -258.187702) (xy 12.384768 -258.185665) (xy 12.440205 -258.191765) (xy 12.494162 -258.205871)
			(xy 12.545491 -258.227683) (xy 12.593097 -258.256737) (xy 12.635965 -258.292412) (xy 12.673182 -258.333949)
			(xy 12.703955 -258.380462) (xy 12.727627 -258.430959) (xy 12.743695 -258.484366) (xy 12.747583 -258.510786)
			(xy 13.13002 -258.510786) (xy 13.134091 -258.455164) (xy 13.146217 -258.400727) (xy 13.16614 -258.348636)
			(xy 13.193436 -258.300001) (xy 13.227522 -258.255858) (xy 13.267671 -258.217149) (xy 13.313029 -258.184698)
			(xy 13.362629 -258.159197) (xy 13.415413 -258.14119) (xy 13.470256 -258.13106) (xy 13.52599 -258.129023)
			(xy 13.581427 -258.135123) (xy 13.635384 -258.149229) (xy 13.686713 -258.171041) (xy 13.734319 -258.200095)
			(xy 13.777187 -258.23577) (xy 13.814404 -258.277307) (xy 13.845177 -258.32382) (xy 13.868849 -258.374317)
			(xy 13.884917 -258.427724) (xy 13.893037 -258.4829) (xy 13.893546 -258.510786) (xy 13.893037 -258.538672)
			(xy 13.884917 -258.593848) (xy 13.868849 -258.647255) (xy 13.845177 -258.697752) (xy 13.814404 -258.744265)
			(xy 13.777187 -258.785802) (xy 13.734319 -258.821477) (xy 13.686713 -258.850531) (xy 13.635384 -258.872343)
			(xy 13.581427 -258.886449) (xy 13.52599 -258.892549) (xy 13.470256 -258.890512) (xy 13.415413 -258.880382)
			(xy 13.362629 -258.862375) (xy 13.313029 -258.836874) (xy 13.267671 -258.804423) (xy 13.227522 -258.765714)
			(xy 13.193436 -258.721571) (xy 13.16614 -258.672936) (xy 13.146217 -258.620845) (xy 13.134091 -258.566408)
			(xy 13.13002 -258.510786) (xy 12.747583 -258.510786) (xy 12.751815 -258.539542) (xy 12.752324 -258.567428)
			(xy 12.751815 -258.595314) (xy 12.743695 -258.65049) (xy 12.727627 -258.703897) (xy 12.703955 -258.754394)
			(xy 12.673182 -258.800907) (xy 12.635965 -258.842444) (xy 12.593097 -258.878119) (xy 12.545491 -258.907173)
			(xy 12.494162 -258.928985) (xy 12.440205 -258.943091) (xy 12.384768 -258.949191) (xy 12.329034 -258.947154)
			(xy 12.274191 -258.937024) (xy 12.221407 -258.919017) (xy 12.171807 -258.893516) (xy 12.126449 -258.861065)
			(xy 12.0863 -258.822356) (xy 12.052214 -258.778213) (xy 12.024918 -258.729578) (xy 12.004995 -258.677487)
			(xy 11.992869 -258.62305) (xy 11.988798 -258.567428) (xy 11.602805 -258.567428) (xy 11.598917 -258.593848)
			(xy 11.582849 -258.647255) (xy 11.559177 -258.697752) (xy 11.528404 -258.744265) (xy 11.491187 -258.785802)
			(xy 11.448319 -258.821477) (xy 11.400713 -258.850531) (xy 11.349384 -258.872343) (xy 11.295427 -258.886449)
			(xy 11.23999 -258.892549) (xy 11.184256 -258.890512) (xy 11.129413 -258.880382) (xy 11.076629 -258.862375)
			(xy 11.027029 -258.836874) (xy 10.981671 -258.804423) (xy 10.941522 -258.765714) (xy 10.907436 -258.721571)
			(xy 10.88014 -258.672936) (xy 10.860217 -258.620845) (xy 10.848091 -258.566408) (xy 10.84402 -258.510786)
			(xy 10.083546 -258.510786) (xy 10.083037 -258.538672) (xy 10.074917 -258.593848) (xy 10.058849 -258.647255)
			(xy 10.035177 -258.697752) (xy 10.004404 -258.744265) (xy 9.967187 -258.785802) (xy 9.924319 -258.821477)
			(xy 9.876713 -258.850531) (xy 9.825384 -258.872343) (xy 9.771427 -258.886449) (xy 9.71599 -258.892549)
			(xy 9.660256 -258.890512) (xy 9.605413 -258.880382) (xy 9.552629 -258.862375) (xy 9.503029 -258.836874)
			(xy 9.457671 -258.804423) (xy 9.417522 -258.765714) (xy 9.383436 -258.721571) (xy 9.35614 -258.672936)
			(xy 9.336217 -258.620845) (xy 9.324091 -258.566408) (xy 9.32002 -258.510786) (xy 8.559546 -258.510786)
			(xy 8.559037 -258.538672) (xy 8.550917 -258.593848) (xy 8.534849 -258.647255) (xy 8.511177 -258.697752)
			(xy 8.480404 -258.744265) (xy 8.443187 -258.785802) (xy 8.400319 -258.821477) (xy 8.352713 -258.850531)
			(xy 8.301384 -258.872343) (xy 8.247427 -258.886449) (xy 8.19199 -258.892549) (xy 8.136256 -258.890512)
			(xy 8.081413 -258.880382) (xy 8.028629 -258.862375) (xy 7.979029 -258.836874) (xy 7.933671 -258.804423)
			(xy 7.893522 -258.765714) (xy 7.859436 -258.721571) (xy 7.83214 -258.672936) (xy 7.812217 -258.620845)
			(xy 7.800091 -258.566408) (xy 7.79602 -258.510786) (xy 7.035546 -258.510786) (xy 7.035037 -258.538672)
			(xy 7.026917 -258.593848) (xy 7.010849 -258.647255) (xy 6.987177 -258.697752) (xy 6.956404 -258.744265)
			(xy 6.919187 -258.785802) (xy 6.876319 -258.821477) (xy 6.828713 -258.850531) (xy 6.777384 -258.872343)
			(xy 6.723427 -258.886449) (xy 6.66799 -258.892549) (xy 6.612256 -258.890512) (xy 6.557413 -258.880382)
			(xy 6.504629 -258.862375) (xy 6.455029 -258.836874) (xy 6.409671 -258.804423) (xy 6.369522 -258.765714)
			(xy 6.335436 -258.721571) (xy 6.30814 -258.672936) (xy 6.288217 -258.620845) (xy 6.276091 -258.566408)
			(xy 6.27202 -258.510786) (xy 5.511546 -258.510786) (xy 5.511037 -258.538672) (xy 5.502917 -258.593848)
			(xy 5.486849 -258.647255) (xy 5.463177 -258.697752) (xy 5.432404 -258.744265) (xy 5.395187 -258.785802)
			(xy 5.352319 -258.821477) (xy 5.304713 -258.850531) (xy 5.253384 -258.872343) (xy 5.199427 -258.886449)
			(xy 5.14399 -258.892549) (xy 5.088256 -258.890512) (xy 5.033413 -258.880382) (xy 4.980629 -258.862375)
			(xy 4.931029 -258.836874) (xy 4.885671 -258.804423) (xy 4.845522 -258.765714) (xy 4.811436 -258.721571)
			(xy 4.78414 -258.672936) (xy 4.764217 -258.620845) (xy 4.752091 -258.566408) (xy 4.74802 -258.510786)
			(xy 3.987546 -258.510786) (xy 3.987037 -258.538672) (xy 3.978917 -258.593848) (xy 3.962849 -258.647255)
			(xy 3.939177 -258.697752) (xy 3.908404 -258.744265) (xy 3.871187 -258.785802) (xy 3.828319 -258.821477)
			(xy 3.780713 -258.850531) (xy 3.729384 -258.872343) (xy 3.675427 -258.886449) (xy 3.61999 -258.892549)
			(xy 3.564256 -258.890512) (xy 3.509413 -258.880382) (xy 3.456629 -258.862375) (xy 3.407029 -258.836874)
			(xy 3.361671 -258.804423) (xy 3.321522 -258.765714) (xy 3.287436 -258.721571) (xy 3.26014 -258.672936)
			(xy 3.240217 -258.620845) (xy 3.228091 -258.566408) (xy 3.22402 -258.510786) (xy 0.529844 -258.510786)
			(xy 0.529844 -270.644366) (xy 5.002276 -270.644366) (xy 5.002704 -270.616994) (xy 5.010528 -270.562813)
			(xy 5.026025 -270.510308) (xy 5.048876 -270.460562) (xy 5.07861 -270.414598) (xy 5.096256 -270.393668)
			(xy 5.09651 -270.393414) (xy 5.102098 -270.386328) (xy 5.108344 -270.369411) (xy 5.108702 -270.360394)
			(xy 5.108702 -270.293338) (xy 5.108327 -270.284323) (xy 5.102092 -270.267406) (xy 5.09651 -270.260318)
			(xy 5.096256 -270.260318) (xy 5.096256 -270.260064) (xy 5.078626 -270.239125) (xy 5.048914 -270.193153)
			(xy 5.026077 -270.143407) (xy 5.010584 -270.090909) (xy 5.002752 -270.036735) (xy 5.002276 -270.009366)
			(xy 5.002746 -269.982115) (xy 5.010507 -269.928167) (xy 5.025865 -269.875873) (xy 5.048509 -269.826297)
			(xy 5.077978 -269.780447) (xy 5.113671 -269.739258) (xy 5.154862 -269.703567) (xy 5.200713 -269.674101)
			(xy 5.25029 -269.651459) (xy 5.302585 -269.636103) (xy 5.356533 -269.628345) (xy 5.383784 -269.627858)
			(xy 5.412522 -269.628403) (xy 5.469348 -269.637022) (xy 5.524238 -269.654068) (xy 5.57595 -269.679154)
			(xy 5.623314 -269.711714) (xy 5.644642 -269.730982) (xy 5.6515 -269.737586) (xy 5.669534 -269.744698)
			(xy 5.758434 -269.744698) (xy 5.776468 -269.737586) (xy 5.783326 -269.730982) (xy 5.804653 -269.711712)
			(xy 5.852016 -269.679147) (xy 5.903727 -269.654056) (xy 5.958618 -269.637006) (xy 6.015445 -269.628384)
			(xy 6.072923 -269.628384) (xy 6.12975 -269.637006) (xy 6.184641 -269.654056) (xy 6.236352 -269.679147)
			(xy 6.283715 -269.711712) (xy 6.305042 -269.730982) (xy 6.3119 -269.737586) (xy 6.329934 -269.744698)
			(xy 6.418834 -269.744698) (xy 6.436868 -269.737586) (xy 6.443726 -269.730982) (xy 6.465053 -269.711712)
			(xy 6.512416 -269.679147) (xy 6.564127 -269.654056) (xy 6.619018 -269.637006) (xy 6.675845 -269.628384)
			(xy 6.733323 -269.628384) (xy 6.79015 -269.637006) (xy 6.845041 -269.654056) (xy 6.896752 -269.679147)
			(xy 6.944115 -269.711712) (xy 6.965442 -269.730982) (xy 6.9723 -269.737586) (xy 6.990334 -269.744698)
			(xy 7.079234 -269.744698) (xy 7.097268 -269.737586) (xy 7.104126 -269.730982) (xy 7.125466 -269.711726)
			(xy 7.172824 -269.679156) (xy 7.224532 -269.65406) (xy 7.27942 -269.637006) (xy 7.336246 -269.62838)
			(xy 7.364984 -269.627858) (xy 7.392235 -269.628344) (xy 7.446183 -269.636101) (xy 7.498477 -269.651456)
			(xy 7.548054 -269.674098) (xy 7.593904 -269.703564) (xy 7.635094 -269.739256) (xy 7.670786 -269.780446)
			(xy 7.700252 -269.826296) (xy 7.722894 -269.875873) (xy 7.738249 -269.928167) (xy 7.746006 -269.982115)
			(xy 7.746492 -270.009366) (xy 7.746008 -270.036736) (xy 7.738195 -270.090914) (xy 7.72271 -270.143417)
			(xy 7.699872 -270.193164) (xy 7.670151 -270.239132) (xy 7.652512 -270.260064) (xy 7.652258 -270.260318)
			(xy 7.646653 -270.267392) (xy 7.640418 -270.284318) (xy 7.640066 -270.293338) (xy 7.640066 -270.360394)
			(xy 7.640433 -270.36941) (xy 7.646675 -270.386326) (xy 7.652258 -270.393414) (xy 7.652512 -270.393414)
			(xy 7.652512 -270.393668) (xy 7.670151 -270.4146) (xy 7.699863 -270.460573) (xy 7.722698 -270.51032)
			(xy 7.730174 -270.535654) (xy 8.785098 -270.535654) (xy 8.785596 -270.508285) (xy 8.793406 -270.454107)
			(xy 8.808888 -270.401605) (xy 8.831723 -270.351857) (xy 8.86144 -270.305889) (xy 8.879078 -270.284956)
			(xy 8.879332 -270.284702) (xy 8.884927 -270.277622) (xy 8.891168 -270.2607) (xy 8.891524 -270.251682)
			(xy 8.891524 -270.184626) (xy 8.891149 -270.175611) (xy 8.884913 -270.158694) (xy 8.879332 -270.151606)
			(xy 8.879078 -270.151606) (xy 8.879078 -270.151352) (xy 8.861446 -270.130414) (xy 8.831734 -270.084442)
			(xy 8.808897 -270.034696) (xy 8.793404 -269.982197) (xy 8.785574 -269.928023) (xy 8.785098 -269.900654)
			(xy 8.785535 -269.873401) (xy 8.793298 -269.819452) (xy 8.808659 -269.767156) (xy 8.831306 -269.717578)
			(xy 8.860778 -269.671727) (xy 8.896474 -269.630537) (xy 8.937669 -269.594847) (xy 8.983523 -269.565381)
			(xy 9.033104 -269.542741) (xy 9.085402 -269.527387) (xy 9.139353 -269.519631) (xy 9.166606 -269.519146)
			(xy 9.195344 -269.519681) (xy 9.252171 -269.528303) (xy 9.307061 -269.545351) (xy 9.358772 -269.57044)
			(xy 9.406136 -269.603001) (xy 9.427464 -269.62227) (xy 9.434322 -269.628874) (xy 9.452356 -269.635986)
			(xy 9.541256 -269.635986) (xy 9.55929 -269.628874) (xy 9.566148 -269.62227) (xy 9.587475 -269.603)
			(xy 9.634838 -269.570435) (xy 9.686549 -269.545344) (xy 9.74144 -269.528294) (xy 9.798267 -269.519672)
			(xy 9.855745 -269.519672) (xy 9.912572 -269.528294) (xy 9.967463 -269.545344) (xy 10.019174 -269.570435)
			(xy 10.066537 -269.603) (xy 10.087864 -269.62227) (xy 10.094722 -269.628874) (xy 10.112756 -269.635986)
			(xy 10.201656 -269.635986) (xy 10.21969 -269.628874) (xy 10.226548 -269.62227) (xy 10.247875 -269.603)
			(xy 10.295238 -269.570435) (xy 10.346949 -269.545344) (xy 10.40184 -269.528294) (xy 10.458667 -269.519672)
			(xy 10.516145 -269.519672) (xy 10.572972 -269.528294) (xy 10.627863 -269.545344) (xy 10.679574 -269.570435)
			(xy 10.726937 -269.603) (xy 10.748264 -269.62227) (xy 10.755122 -269.628874) (xy 10.773156 -269.635986)
			(xy 10.862056 -269.635986) (xy 10.88009 -269.628874) (xy 10.886948 -269.62227) (xy 10.908277 -269.603002)
			(xy 10.955638 -269.570434) (xy 11.007349 -269.54534) (xy 11.06224 -269.528289) (xy 11.119067 -269.519667)
			(xy 11.147806 -269.519146) (xy 11.175059 -269.519609) (xy 11.22901 -269.527366) (xy 11.281308 -269.542721)
			(xy 11.330889 -269.565364) (xy 11.376742 -269.594832) (xy 11.417935 -269.630525) (xy 11.453628 -269.671718)
			(xy 11.483096 -269.717571) (xy 11.505739 -269.767152) (xy 11.521094 -269.81945) (xy 11.528851 -269.873401)
			(xy 11.529314 -269.900654) (xy 11.528818 -269.928023) (xy 11.521007 -269.982201) (xy 11.505524 -270.034703)
			(xy 11.48269 -270.084451) (xy 11.452972 -270.130419) (xy 11.435334 -270.151352) (xy 11.43508 -270.151606)
			(xy 11.429483 -270.158685) (xy 11.423243 -270.175608) (xy 11.422888 -270.184626) (xy 11.422888 -270.251682)
			(xy 11.423256 -270.260698) (xy 11.429496 -270.277615) (xy 11.43508 -270.284702) (xy 11.435334 -270.284702)
			(xy 11.435334 -270.284956) (xy 11.452971 -270.305889) (xy 11.482682 -270.351862) (xy 11.505518 -270.40161)
			(xy 11.52101 -270.45411) (xy 11.528839 -270.508285) (xy 11.529314 -270.535654) (xy 11.528802 -270.562905)
			(xy 11.521051 -270.616854) (xy 11.505701 -270.669151) (xy 11.483065 -270.71873) (xy 11.453602 -270.764584)
			(xy 11.417913 -270.805777) (xy 11.376725 -270.841471) (xy 11.330876 -270.87094) (xy 11.2813 -270.893583)
			(xy 11.229005 -270.90894) (xy 11.175057 -270.916698) (xy 11.147806 -270.917162) (xy 11.119068 -270.916618)
			(xy 11.062242 -270.907998) (xy 11.007352 -270.890952) (xy 10.95564 -270.865865) (xy 10.908276 -270.833306)
			(xy 10.886948 -270.814038) (xy 10.88009 -270.807434) (xy 10.862056 -270.800322) (xy 10.773156 -270.800322)
			(xy 10.755122 -270.807434) (xy 10.748264 -270.814038) (xy 10.726937 -270.833308) (xy 10.679574 -270.865873)
			(xy 10.627863 -270.890964) (xy 10.572972 -270.908014) (xy 10.516145 -270.916636) (xy 10.458667 -270.916636)
			(xy 10.40184 -270.908014) (xy 10.346949 -270.890964) (xy 10.295238 -270.865873) (xy 10.247875 -270.833308)
			(xy 10.226548 -270.814038) (xy 10.21969 -270.807434) (xy 10.201656 -270.800322) (xy 10.112756 -270.800322)
			(xy 10.094722 -270.807434) (xy 10.087864 -270.814038) (xy 10.066537 -270.833308) (xy 10.019174 -270.865873)
			(xy 9.967463 -270.890964) (xy 9.912572 -270.908014) (xy 9.855745 -270.916636) (xy 9.798267 -270.916636)
			(xy 9.74144 -270.908014) (xy 9.686549 -270.890964) (xy 9.634838 -270.865873) (xy 9.587475 -270.833308)
			(xy 9.566148 -270.814038) (xy 9.55929 -270.807434) (xy 9.541256 -270.800322) (xy 9.452356 -270.800322)
			(xy 9.434322 -270.807434) (xy 9.427464 -270.814038) (xy 9.406131 -270.833302) (xy 9.358771 -270.86587)
			(xy 9.307061 -270.890964) (xy 9.252171 -270.908016) (xy 9.195345 -270.916641) (xy 9.166606 -270.917162)
			(xy 9.139355 -270.916676) (xy 9.085407 -270.908919) (xy 9.033113 -270.893564) (xy 8.983536 -270.870922)
			(xy 8.937686 -270.841456) (xy 8.896496 -270.805764) (xy 8.860804 -270.764574) (xy 8.831338 -270.718724)
			(xy 8.808696 -270.669147) (xy 8.793341 -270.616853) (xy 8.785584 -270.562905) (xy 8.785098 -270.535654)
			(xy 7.730174 -270.535654) (xy 7.73819 -270.562821) (xy 7.746018 -270.616997) (xy 7.746492 -270.644366)
			(xy 7.746013 -270.671619) (xy 7.73826 -270.72557) (xy 7.722908 -270.777868) (xy 7.700268 -270.82745)
			(xy 7.670802 -270.873304) (xy 7.63511 -270.914497) (xy 7.593918 -270.950191) (xy 7.548065 -270.979659)
			(xy 7.498485 -271.002301) (xy 7.446188 -271.017656) (xy 7.392237 -271.025412) (xy 7.364984 -271.025874)
			(xy 7.336246 -271.02534) (xy 7.27942 -271.016717) (xy 7.22453 -270.999668) (xy 7.172818 -270.974579)
			(xy 7.125454 -270.942018) (xy 7.104126 -270.92275) (xy 7.097268 -270.916146) (xy 7.079234 -270.909034)
			(xy 6.990334 -270.909034) (xy 6.9723 -270.916146) (xy 6.965442 -270.92275) (xy 6.944115 -270.94202)
			(xy 6.896752 -270.974585) (xy 6.845041 -270.999676) (xy 6.79015 -271.016726) (xy 6.733323 -271.025348)
			(xy 6.675845 -271.025348) (xy 6.619018 -271.016726) (xy 6.564127 -270.999676) (xy 6.512416 -270.974585)
			(xy 6.465053 -270.94202) (xy 6.443726 -270.92275) (xy 6.436868 -270.916146) (xy 6.418834 -270.909034)
			(xy 6.329934 -270.909034) (xy 6.3119 -270.916146) (xy 6.305042 -270.92275) (xy 6.283715 -270.94202)
			(xy 6.236352 -270.974585) (xy 6.184641 -270.999676) (xy 6.12975 -271.016726) (xy 6.072923 -271.025348)
			(xy 6.015445 -271.025348) (xy 5.958618 -271.016726) (xy 5.903727 -270.999676) (xy 5.852016 -270.974585)
			(xy 5.804653 -270.94202) (xy 5.783326 -270.92275) (xy 5.776468 -270.916146) (xy 5.758434 -270.909034)
			(xy 5.669534 -270.909034) (xy 5.6515 -270.916146) (xy 5.644642 -270.92275) (xy 5.62332 -270.942026)
			(xy 5.575957 -270.974592) (xy 5.524244 -270.999684) (xy 5.469352 -271.016733) (xy 5.412523 -271.025354)
			(xy 5.383784 -271.025874) (xy 5.356531 -271.025411) (xy 5.30258 -271.017654) (xy 5.250282 -271.002299)
			(xy 5.200701 -270.979656) (xy 5.154848 -270.950188) (xy 5.113655 -270.914495) (xy 5.077962 -270.873302)
			(xy 5.048494 -270.827449) (xy 5.025851 -270.777868) (xy 5.010496 -270.72557) (xy 5.002739 -270.671619)
			(xy 5.002276 -270.644366) (xy 0.529844 -270.644366) (xy 0.529844 -272.345912) (xy 11.635738 -272.345912)
			(xy 11.639809 -272.29029) (xy 11.651935 -272.235853) (xy 11.671858 -272.183762) (xy 11.699154 -272.135127)
			(xy 11.73324 -272.090984) (xy 11.773389 -272.052275) (xy 11.818747 -272.019824) (xy 11.868347 -271.994323)
			(xy 11.921131 -271.976316) (xy 11.975974 -271.966186) (xy 12.031708 -271.964149) (xy 12.087145 -271.970249)
			(xy 12.141102 -271.984355) (xy 12.192431 -272.006167) (xy 12.240037 -272.035221) (xy 12.282905 -272.070896)
			(xy 12.320122 -272.112433) (xy 12.350895 -272.158946) (xy 12.374567 -272.209443) (xy 12.390635 -272.26285)
			(xy 12.398755 -272.318026) (xy 12.399264 -272.345912) (xy 12.398755 -272.373798) (xy 12.390635 -272.428974)
			(xy 12.374894 -272.481294) (xy 13.765528 -272.481294) (xy 13.769599 -272.425672) (xy 13.781725 -272.371235)
			(xy 13.801648 -272.319144) (xy 13.828944 -272.270509) (xy 13.86303 -272.226366) (xy 13.903179 -272.187657)
			(xy 13.948537 -272.155206) (xy 13.998137 -272.129705) (xy 14.050921 -272.111698) (xy 14.105764 -272.101568)
			(xy 14.161498 -272.099531) (xy 14.216935 -272.105631) (xy 14.270892 -272.119737) (xy 14.322221 -272.141549)
			(xy 14.369827 -272.170603) (xy 14.412695 -272.206278) (xy 14.449912 -272.247815) (xy 14.480685 -272.294328)
			(xy 14.504357 -272.344825) (xy 14.520425 -272.398232) (xy 14.528545 -272.453408) (xy 14.529054 -272.481294)
			(xy 14.528545 -272.50918) (xy 14.520425 -272.564356) (xy 14.504357 -272.617763) (xy 14.480685 -272.66826)
			(xy 14.449912 -272.714773) (xy 14.412695 -272.75631) (xy 14.369827 -272.791985) (xy 14.322221 -272.821039)
			(xy 14.270892 -272.842851) (xy 14.216935 -272.856957) (xy 14.161498 -272.863057) (xy 14.105764 -272.86102)
			(xy 14.050921 -272.85089) (xy 13.998137 -272.832883) (xy 13.948537 -272.807382) (xy 13.903179 -272.774931)
			(xy 13.86303 -272.736222) (xy 13.828944 -272.692079) (xy 13.801648 -272.643444) (xy 13.781725 -272.591353)
			(xy 13.769599 -272.536916) (xy 13.765528 -272.481294) (xy 12.374894 -272.481294) (xy 12.374567 -272.482381)
			(xy 12.350895 -272.532878) (xy 12.320122 -272.579391) (xy 12.282905 -272.620928) (xy 12.240037 -272.656603)
			(xy 12.192431 -272.685657) (xy 12.141102 -272.707469) (xy 12.087145 -272.721575) (xy 12.031708 -272.727675)
			(xy 11.975974 -272.725638) (xy 11.921131 -272.715508) (xy 11.868347 -272.697501) (xy 11.818747 -272.672)
			(xy 11.773389 -272.639549) (xy 11.73324 -272.60084) (xy 11.699154 -272.556697) (xy 11.671858 -272.508062)
			(xy 11.651935 -272.455971) (xy 11.639809 -272.401534) (xy 11.635738 -272.345912) (xy 0.529844 -272.345912)
			(xy 0.529844 -273.245651) (xy 8.10893 -273.245651) (xy 8.10893 -273.191149) (xy 8.116686 -273.137201)
			(xy 8.132041 -273.084907) (xy 8.154682 -273.03533) (xy 8.184148 -272.98948) (xy 8.21984 -272.94829)
			(xy 8.26103 -272.912598) (xy 8.30688 -272.883132) (xy 8.356457 -272.860491) (xy 8.408751 -272.845136)
			(xy 8.462699 -272.83738) (xy 8.48995 -272.836894) (xy 8.517319 -272.837391) (xy 8.571497 -272.845201)
			(xy 8.624 -272.860683) (xy 8.673747 -272.883518) (xy 8.719715 -272.913236) (xy 8.740648 -272.930874)
			(xy 8.740902 -272.931128) (xy 8.747982 -272.936725) (xy 8.764904 -272.942964) (xy 8.773922 -272.94332)
			(xy 8.840978 -272.94332) (xy 8.849993 -272.942948) (xy 8.86691 -272.93671) (xy 8.873998 -272.931128)
			(xy 8.873998 -272.930874) (xy 8.874252 -272.930874) (xy 8.895188 -272.91324) (xy 8.94116 -272.883528)
			(xy 8.990907 -272.860692) (xy 9.043406 -272.845199) (xy 9.097581 -272.837369) (xy 9.12495 -272.836894)
			(xy 9.152201 -272.837376) (xy 9.206149 -272.845132) (xy 9.258444 -272.860488) (xy 9.308022 -272.883129)
			(xy 9.353873 -272.912595) (xy 9.360311 -272.918174) (xy 15.261334 -272.918174) (xy 15.265405 -272.862552)
			(xy 15.277531 -272.808115) (xy 15.297454 -272.756024) (xy 15.32475 -272.707389) (xy 15.358836 -272.663246)
			(xy 15.398985 -272.624537) (xy 15.444343 -272.592086) (xy 15.493943 -272.566585) (xy 15.546727 -272.548578)
			(xy 15.60157 -272.538448) (xy 15.657304 -272.536411) (xy 15.712741 -272.542511) (xy 15.766698 -272.556617)
			(xy 15.818027 -272.578429) (xy 15.865633 -272.607483) (xy 15.908501 -272.643158) (xy 15.945718 -272.684695)
			(xy 15.976491 -272.731208) (xy 16.000163 -272.781705) (xy 16.016231 -272.835112) (xy 16.024351 -272.890288)
			(xy 16.02486 -272.918174) (xy 16.024351 -272.94606) (xy 16.016231 -273.001236) (xy 16.000163 -273.054643)
			(xy 15.976491 -273.10514) (xy 15.945718 -273.151653) (xy 15.908501 -273.19319) (xy 15.865633 -273.228865)
			(xy 15.818027 -273.257919) (xy 15.766698 -273.279731) (xy 15.712741 -273.293837) (xy 15.657304 -273.299937)
			(xy 15.60157 -273.2979) (xy 15.546727 -273.28777) (xy 15.493943 -273.269763) (xy 15.444343 -273.244262)
			(xy 15.398985 -273.211811) (xy 15.358836 -273.173102) (xy 15.32475 -273.128959) (xy 15.297454 -273.080324)
			(xy 15.277531 -273.028233) (xy 15.265405 -272.973796) (xy 15.261334 -272.918174) (xy 9.360311 -272.918174)
			(xy 9.395063 -272.948287) (xy 9.430755 -272.989477) (xy 9.460221 -273.035328) (xy 9.482862 -273.084906)
			(xy 9.498218 -273.137201) (xy 9.505974 -273.191149) (xy 9.505974 -273.245651) (xy 9.498218 -273.299599)
			(xy 9.482862 -273.351894) (xy 9.460221 -273.401472) (xy 9.430755 -273.447323) (xy 9.395063 -273.488513)
			(xy 9.353873 -273.524205) (xy 9.308022 -273.553671) (xy 9.258444 -273.576312) (xy 9.206149 -273.591668)
			(xy 9.152201 -273.599424) (xy 9.12495 -273.59991) (xy 9.097581 -273.599412) (xy 9.043403 -273.591602)
			(xy 8.990901 -273.57612) (xy 8.941153 -273.553285) (xy 8.895185 -273.523568) (xy 8.874252 -273.50593)
			(xy 8.873998 -273.505676) (xy 8.866918 -273.50008) (xy 8.849996 -273.49384) (xy 8.840978 -273.493484)
			(xy 8.773922 -273.493484) (xy 8.764907 -273.493855) (xy 8.74799 -273.500093) (xy 8.740902 -273.505676)
			(xy 8.740902 -273.50593) (xy 8.740648 -273.50593) (xy 8.719713 -273.523565) (xy 8.67374 -273.553276)
			(xy 8.623993 -273.576112) (xy 8.571494 -273.591605) (xy 8.517319 -273.599435) (xy 8.48995 -273.59991)
			(xy 8.462699 -273.59942) (xy 8.408751 -273.591664) (xy 8.356457 -273.576309) (xy 8.30688 -273.553668)
			(xy 8.26103 -273.524202) (xy 8.21984 -273.48851) (xy 8.184148 -273.44732) (xy 8.154682 -273.40147)
			(xy 8.132041 -273.351893) (xy 8.116686 -273.299599) (xy 8.10893 -273.245651) (xy 0.529844 -273.245651)
			(xy 0.529844 -275.000212) (xy 4.903216 -275.000212) (xy 4.903685 -274.972842) (xy 4.911502 -274.918663)
			(xy 4.92699 -274.866159) (xy 4.949831 -274.816413) (xy 4.979555 -274.770446) (xy 4.997196 -274.749514)
			(xy 4.99745 -274.74926) (xy 5.003024 -274.742165) (xy 5.009277 -274.725254) (xy 5.009642 -274.71624)
			(xy 5.009642 -274.649184) (xy 5.009305 -274.640165) (xy 5.003045 -274.623247) (xy 4.99745 -274.616164)
			(xy 4.997196 -274.616164) (xy 4.997196 -274.61591) (xy 4.979548 -274.594986) (xy 4.949837 -274.549011)
			(xy 4.927003 -274.499261) (xy 4.911514 -274.446759) (xy 4.903689 -274.392582) (xy 4.903216 -274.365212)
			(xy 4.903667 -274.337958) (xy 4.911423 -274.284006) (xy 4.926778 -274.231706) (xy 4.949421 -274.182124)
			(xy 4.97889 -274.13627) (xy 5.014585 -274.095077) (xy 5.05578 -274.059383) (xy 5.101635 -274.029915)
			(xy 5.151217 -274.007274) (xy 5.203517 -273.99192) (xy 5.25747 -273.984166) (xy 5.284724 -273.983704)
			(xy 5.313464 -273.984212) (xy 5.370292 -273.992838) (xy 5.425183 -274.009892) (xy 5.476894 -274.034987)
			(xy 5.524256 -274.067556) (xy 5.545582 -274.086828) (xy 5.55244 -274.093432) (xy 5.570474 -274.100544)
			(xy 5.659374 -274.100544) (xy 5.677408 -274.093432) (xy 5.684266 -274.086828) (xy 5.705593 -274.067558)
			(xy 5.752956 -274.034993) (xy 5.804667 -274.009902) (xy 5.859558 -273.992852) (xy 5.916385 -273.98423)
			(xy 5.973863 -273.98423) (xy 6.03069 -273.992852) (xy 6.085581 -274.009902) (xy 6.137292 -274.034993)
			(xy 6.184655 -274.067558) (xy 6.205982 -274.086828) (xy 6.21284 -274.093432) (xy 6.230874 -274.100544)
			(xy 6.319774 -274.100544) (xy 6.337808 -274.093432) (xy 6.344666 -274.086828) (xy 6.365993 -274.067558)
			(xy 6.413356 -274.034993) (xy 6.465067 -274.009902) (xy 6.519958 -273.992852) (xy 6.576785 -273.98423)
			(xy 6.634263 -273.98423) (xy 6.69109 -273.992852) (xy 6.745981 -274.009902) (xy 6.797692 -274.034993)
			(xy 6.845055 -274.067558) (xy 6.866382 -274.086828) (xy 6.87324 -274.093432) (xy 6.891274 -274.100544)
			(xy 6.980174 -274.100544) (xy 6.998208 -274.093432) (xy 7.005066 -274.086828) (xy 7.026382 -274.067544)
			(xy 7.073747 -274.03498) (xy 7.125462 -274.00989) (xy 7.180355 -273.992843) (xy 7.237184 -273.984223)
			(xy 7.265924 -273.983704) (xy 7.293176 -273.984156) (xy 7.347126 -273.991916) (xy 7.399422 -274.007274)
			(xy 7.449 -274.029919) (xy 7.494851 -274.059389) (xy 7.521238 -274.082256) (xy 10.07567 -274.082256)
			(xy 10.079741 -274.026634) (xy 10.091867 -273.972197) (xy 10.11179 -273.920106) (xy 10.139086 -273.871471)
			(xy 10.173172 -273.827328) (xy 10.213321 -273.788619) (xy 10.258679 -273.756168) (xy 10.308279 -273.730667)
			(xy 10.361063 -273.71266) (xy 10.415906 -273.70253) (xy 10.47164 -273.700493) (xy 10.527077 -273.706593)
			(xy 10.581034 -273.720699) (xy 10.632363 -273.742511) (xy 10.679969 -273.771565) (xy 10.722837 -273.80724)
			(xy 10.760054 -273.848777) (xy 10.790827 -273.89529) (xy 10.814499 -273.945787) (xy 10.830567 -273.999194)
			(xy 10.838687 -274.05437) (xy 10.839196 -274.082256) (xy 10.838687 -274.110142) (xy 10.830567 -274.165318)
			(xy 10.814499 -274.218725) (xy 10.790827 -274.269222) (xy 10.760054 -274.315735) (xy 10.722837 -274.357272)
			(xy 10.679969 -274.392947) (xy 10.632363 -274.422001) (xy 10.581034 -274.443813) (xy 10.527077 -274.457919)
			(xy 10.47164 -274.464019) (xy 10.415906 -274.461982) (xy 10.361063 -274.451852) (xy 10.308279 -274.433845)
			(xy 10.258679 -274.408344) (xy 10.213321 -274.375893) (xy 10.173172 -274.337184) (xy 10.139086 -274.293041)
			(xy 10.11179 -274.244406) (xy 10.091867 -274.192315) (xy 10.079741 -274.137878) (xy 10.07567 -274.082256)
			(xy 7.521238 -274.082256) (xy 7.536041 -274.095084) (xy 7.571733 -274.136278) (xy 7.601198 -274.182131)
			(xy 7.623838 -274.231712) (xy 7.639192 -274.284009) (xy 7.646947 -274.33796) (xy 7.647432 -274.365212)
			(xy 7.64699 -274.392583) (xy 7.639169 -274.446764) (xy 7.623675 -274.499268) (xy 7.600827 -274.549015)
			(xy 7.571097 -274.59498) (xy 7.553452 -274.61591) (xy 7.553198 -274.616164) (xy 7.54762 -274.623257)
			(xy 7.541368 -274.640169) (xy 7.541006 -274.649184) (xy 7.541006 -274.71624) (xy 7.541343 -274.725259)
			(xy 7.547604 -274.742176) (xy 7.553198 -274.74926) (xy 7.553452 -274.74926) (xy 7.553452 -274.749514)
			(xy 7.571057 -274.770474) (xy 7.600775 -274.816438) (xy 7.623619 -274.866179) (xy 7.639118 -274.918673)
			(xy 7.646954 -274.972845) (xy 7.647432 -275.000212) (xy 7.646933 -275.027462) (xy 7.639176 -275.081408)
			(xy 7.62382 -275.133702) (xy 7.60118 -275.183277) (xy 7.571714 -275.229126) (xy 7.536024 -275.270316)
			(xy 7.494836 -275.306007) (xy 7.448988 -275.335474) (xy 7.399413 -275.358116) (xy 7.34712 -275.373473)
			(xy 7.293174 -275.381233) (xy 7.265924 -275.38172) (xy 7.237186 -275.381176) (xy 7.18036 -275.372558)
			(xy 7.125469 -275.355512) (xy 7.073757 -275.330425) (xy 7.026394 -275.297865) (xy 7.005066 -275.278596)
			(xy 6.998208 -275.271992) (xy 6.980174 -275.26488) (xy 6.891274 -275.26488) (xy 6.87324 -275.271992)
			(xy 6.866382 -275.278596) (xy 6.845055 -275.297866) (xy 6.797692 -275.330431) (xy 6.745981 -275.355522)
			(xy 6.69109 -275.372572) (xy 6.634263 -275.381194) (xy 6.576785 -275.381194) (xy 6.519958 -275.372572)
			(xy 6.465067 -275.355522) (xy 6.413356 -275.330431) (xy 6.365993 -275.297866) (xy 6.344666 -275.278596)
			(xy 6.337808 -275.271992) (xy 6.319774 -275.26488) (xy 6.230874 -275.26488) (xy 6.21284 -275.271992)
			(xy 6.205982 -275.278596) (xy 6.184655 -275.297866) (xy 6.137292 -275.330431) (xy 6.085581 -275.355522)
			(xy 6.03069 -275.372572) (xy 5.973863 -275.381194) (xy 5.916385 -275.381194) (xy 5.859558 -275.372572)
			(xy 5.804667 -275.355522) (xy 5.752956 -275.330431) (xy 5.705593 -275.297866) (xy 5.684266 -275.278596)
			(xy 5.677408 -275.271992) (xy 5.659374 -275.26488) (xy 5.570474 -275.26488) (xy 5.55244 -275.271992)
			(xy 5.545582 -275.278596) (xy 5.524235 -275.297844) (xy 5.47688 -275.330416) (xy 5.425173 -275.355514)
			(xy 5.370286 -275.372569) (xy 5.313462 -275.381197) (xy 5.284724 -275.38172) (xy 5.257472 -275.381222)
			(xy 5.203523 -275.373469) (xy 5.151227 -275.358117) (xy 5.101647 -275.335478) (xy 5.055795 -275.306013)
			(xy 5.014602 -275.270323) (xy 4.978908 -275.229134) (xy 4.949439 -275.183284) (xy 4.926796 -275.133707)
			(xy 4.911439 -275.081412) (xy 4.90368 -275.027464) (xy 4.903216 -275.000212) (xy 0.529844 -275.000212)
			(xy 0.529844 -279.73909) (xy 5.034026 -279.73909) (xy 5.034518 -279.710836) (xy 5.042855 -279.654948)
			(xy 5.059345 -279.6009) (xy 5.083626 -279.549876) (xy 5.115169 -279.502992) (xy 5.133848 -279.481788)
			(xy 5.140452 -279.474676) (xy 5.14731 -279.45715) (xy 5.14731 -279.369266) (xy 5.140452 -279.35174)
			(xy 5.133848 -279.344628) (xy 5.115176 -279.32342) (xy 5.083639 -279.276534) (xy 5.059362 -279.22551)
			(xy 5.042875 -279.171465) (xy 5.034539 -279.115578) (xy 5.034026 -279.087326) (xy 5.03448 -279.060072)
			(xy 5.042234 -279.006119) (xy 5.057588 -278.953819) (xy 5.08023 -278.904237) (xy 5.109699 -278.858382)
			(xy 5.145394 -278.817188) (xy 5.186588 -278.781494) (xy 5.232444 -278.752026) (xy 5.282027 -278.729386)
			(xy 5.334327 -278.714032) (xy 5.38828 -278.706279) (xy 5.415534 -278.705818) (xy 5.444273 -278.706343)
			(xy 5.501099 -278.714969) (xy 5.555989 -278.73202) (xy 5.6077 -278.75711) (xy 5.655064 -278.789673)
			(xy 5.676392 -278.808942) (xy 5.68325 -278.815546) (xy 5.701284 -278.822658) (xy 5.790184 -278.822658)
			(xy 5.808218 -278.815546) (xy 5.815076 -278.808942) (xy 5.836403 -278.789672) (xy 5.883766 -278.757107)
			(xy 5.935477 -278.732016) (xy 5.990368 -278.714966) (xy 6.047195 -278.706344) (xy 6.104673 -278.706344)
			(xy 6.1615 -278.714966) (xy 6.216391 -278.732016) (xy 6.268102 -278.757107) (xy 6.315465 -278.789672)
			(xy 6.336792 -278.808942) (xy 6.34365 -278.815546) (xy 6.361684 -278.822658) (xy 6.450584 -278.822658)
			(xy 6.468618 -278.815546) (xy 6.475476 -278.808942) (xy 6.496803 -278.789672) (xy 6.544166 -278.757107)
			(xy 6.595877 -278.732016) (xy 6.650768 -278.714966) (xy 6.707595 -278.706344) (xy 6.765073 -278.706344)
			(xy 6.8219 -278.714966) (xy 6.876791 -278.732016) (xy 6.928502 -278.757107) (xy 6.975865 -278.789672)
			(xy 6.997192 -278.808942) (xy 7.00405 -278.815546) (xy 7.022084 -278.822658) (xy 7.110984 -278.822658)
			(xy 7.129018 -278.815546) (xy 7.135876 -278.808942) (xy 7.15719 -278.789656) (xy 7.204555 -278.757092)
			(xy 7.25627 -278.732002) (xy 7.311164 -278.714955) (xy 7.367994 -278.706336) (xy 7.396734 -278.705818)
			(xy 7.423987 -278.706246) (xy 7.477938 -278.714008) (xy 7.530236 -278.729369) (xy 7.579815 -278.752016)
			(xy 7.625666 -278.781488) (xy 7.666857 -278.817186) (xy 7.702548 -278.858382) (xy 7.732013 -278.904238)
			(xy 7.754652 -278.95382) (xy 7.770005 -279.00612) (xy 7.777758 -279.060073) (xy 7.778242 -279.087326)
			(xy 7.777767 -279.11558) (xy 7.769428 -279.17147) (xy 7.752934 -279.225518) (xy 7.728649 -279.276542)
			(xy 7.697102 -279.323425) (xy 7.67842 -279.344628) (xy 7.671816 -279.35174) (xy 7.664958 -279.369266)
			(xy 7.664958 -279.45715) (xy 7.671816 -279.474676) (xy 7.67842 -279.481788) (xy 7.697095 -279.502995)
			(xy 7.728632 -279.54988) (xy 7.752909 -279.600904) (xy 7.769395 -279.654951) (xy 7.77773 -279.710837)
			(xy 7.778242 -279.73909) (xy 7.777713 -279.766339) (xy 7.769958 -279.820284) (xy 7.754606 -279.872576)
			(xy 7.731969 -279.92215) (xy 7.702507 -279.967999) (xy 7.66682 -280.009189) (xy 7.625634 -280.04488)
			(xy 7.579789 -280.074348) (xy 7.530217 -280.096991) (xy 7.477927 -280.112349) (xy 7.423983 -280.120109)
			(xy 7.396734 -280.120598) (xy 7.367994 -280.120115) (xy 7.311164 -280.111483) (xy 7.256273 -280.094423)
			(xy 7.204562 -280.069322) (xy 7.157201 -280.036749) (xy 7.135876 -280.017474) (xy 7.129018 -280.01087)
			(xy 7.110984 -280.003758) (xy 7.022084 -280.003758) (xy 7.00405 -280.01087) (xy 6.997192 -280.017474)
			(xy 6.975865 -280.036744) (xy 6.928502 -280.069309) (xy 6.876791 -280.0944) (xy 6.8219 -280.11145)
			(xy 6.765073 -280.120072) (xy 6.707595 -280.120072) (xy 6.650768 -280.11145) (xy 6.595877 -280.0944)
			(xy 6.544166 -280.069309) (xy 6.496803 -280.036744) (xy 6.475476 -280.017474) (xy 6.468618 -280.01087)
			(xy 6.450584 -280.003758) (xy 6.361684 -280.003758) (xy 6.34365 -280.01087) (xy 6.336792 -280.017474)
			(xy 6.315465 -280.036744) (xy 6.268102 -280.069309) (xy 6.216391 -280.0944) (xy 6.1615 -280.11145)
			(xy 6.104673 -280.120072) (xy 6.047195 -280.120072) (xy 5.990368 -280.11145) (xy 5.935477 -280.0944)
			(xy 5.883766 -280.069309) (xy 5.836403 -280.036744) (xy 5.815076 -280.017474) (xy 5.808218 -280.01087)
			(xy 5.790184 -280.003758) (xy 5.701284 -280.003758) (xy 5.68325 -280.01087) (xy 5.676392 -280.017474)
			(xy 5.655053 -280.036731) (xy 5.607694 -280.069298) (xy 5.555985 -280.094393) (xy 5.501097 -280.111447)
			(xy 5.444272 -280.120075) (xy 5.415534 -280.120598) (xy 5.388282 -280.120113) (xy 5.334331 -280.11236)
			(xy 5.282033 -280.097008) (xy 5.232452 -280.074369) (xy 5.186598 -280.044904) (xy 5.145405 -280.009212)
			(xy 5.109711 -279.968021) (xy 5.080243 -279.922169) (xy 5.0576 -279.87259) (xy 5.042245 -279.820293)
			(xy 5.034489 -279.766342) (xy 5.034026 -279.73909) (xy 0.529844 -279.73909) (xy 0.529844 -280.722651)
			(xy 9.692378 -280.722651) (xy 9.692378 -280.668149) (xy 9.700134 -280.614203) (xy 9.715488 -280.561909)
			(xy 9.738128 -280.512333) (xy 9.767593 -280.466483) (xy 9.803283 -280.425293) (xy 9.844472 -280.389602)
			(xy 9.890321 -280.360135) (xy 9.939896 -280.337493) (xy 9.992189 -280.322137) (xy 10.046135 -280.314379)
			(xy 10.073386 -280.313892) (xy 10.102124 -280.314426) (xy 10.158951 -280.323047) (xy 10.213842 -280.340094)
			(xy 10.265554 -280.365184) (xy 10.312917 -280.397746) (xy 10.334244 -280.417016) (xy 10.341102 -280.42362)
			(xy 10.359136 -280.430732) (xy 10.448036 -280.430732) (xy 10.46607 -280.42362) (xy 10.472928 -280.417016)
			(xy 10.494255 -280.397746) (xy 10.541618 -280.365181) (xy 10.593329 -280.34009) (xy 10.64822 -280.32304)
			(xy 10.705047 -280.314418) (xy 10.762525 -280.314418) (xy 10.819352 -280.32304) (xy 10.874243 -280.34009)
			(xy 10.925954 -280.365181) (xy 10.973317 -280.397746) (xy 10.994644 -280.417016) (xy 11.001502 -280.42362)
			(xy 11.019536 -280.430732) (xy 11.108436 -280.430732) (xy 11.12647 -280.42362) (xy 11.133328 -280.417016)
			(xy 11.154658 -280.397748) (xy 11.202019 -280.365182) (xy 11.25373 -280.34009) (xy 11.30862 -280.323038)
			(xy 11.365447 -280.314414) (xy 11.394186 -280.313892) (xy 11.42431 -280.31446) (xy 11.483807 -280.32394)
			(xy 11.541075 -280.342651) (xy 11.594692 -280.370128) (xy 11.643326 -280.405688) (xy 11.66495 -280.426668)
			(xy 11.672377 -280.433474) (xy 11.690955 -280.441215) (xy 11.701018 -280.441654) (xy 11.773154 -280.441654)
			(xy 11.783222 -280.441217) (xy 11.801821 -280.433506) (xy 11.809222 -280.426668) (xy 11.83087 -280.405712)
			(xy 11.879491 -280.370138) (xy 11.933102 -280.342652) (xy 11.990367 -280.323939) (xy 12.049863 -280.314463)
			(xy 12.079986 -280.313892) (xy 12.10724 -280.314354) (xy 12.161192 -280.32211) (xy 12.213491 -280.337465)
			(xy 12.263073 -280.360106) (xy 12.308928 -280.389574) (xy 12.350123 -280.425268) (xy 12.385818 -280.466461)
			(xy 12.415287 -280.512314) (xy 12.437931 -280.561895) (xy 12.453287 -280.614194) (xy 12.461045 -280.668147)
			(xy 12.461045 -280.722653) (xy 12.453287 -280.776606) (xy 12.437931 -280.828905) (xy 12.415287 -280.878486)
			(xy 12.385818 -280.924339) (xy 12.350123 -280.965532) (xy 12.308928 -281.001226) (xy 12.263073 -281.030694)
			(xy 12.213491 -281.053335) (xy 12.161192 -281.06869) (xy 12.10724 -281.076446) (xy 12.079986 -281.076908)
			(xy 12.049862 -281.076358) (xy 11.990364 -281.066874) (xy 11.933095 -281.048159) (xy 11.879478 -281.020678)
			(xy 11.830845 -280.985114) (xy 11.809222 -280.964132) (xy 11.801805 -280.957314) (xy 11.783219 -280.94958)
			(xy 11.773154 -280.949146) (xy 11.701018 -280.949146) (xy 11.690948 -280.949569) (xy 11.67235 -280.95729)
			(xy 11.66495 -280.964132) (xy 11.643315 -280.985101) (xy 11.59469 -281.020673) (xy 11.541076 -281.048157)
			(xy 11.483808 -281.066867) (xy 11.42431 -281.076339) (xy 11.394186 -281.076908) (xy 11.365447 -281.076391)
			(xy 11.308619 -281.067766) (xy 11.253729 -281.050715) (xy 11.202017 -281.025622) (xy 11.154655 -280.993055)
			(xy 11.133328 -280.973784) (xy 11.12647 -280.96718) (xy 11.108436 -280.960068) (xy 11.019536 -280.960068)
			(xy 11.001502 -280.96718) (xy 10.994644 -280.973784) (xy 10.973317 -280.993054) (xy 10.925954 -281.025619)
			(xy 10.874243 -281.05071) (xy 10.819352 -281.06776) (xy 10.762525 -281.076382) (xy 10.705047 -281.076382)
			(xy 10.64822 -281.06776) (xy 10.593329 -281.05071) (xy 10.541618 -281.025619) (xy 10.494255 -280.993054)
			(xy 10.472928 -280.973784) (xy 10.46607 -280.96718) (xy 10.448036 -280.960068) (xy 10.359136 -280.960068)
			(xy 10.341102 -280.96718) (xy 10.334244 -280.973784) (xy 10.312926 -280.993065) (xy 10.265561 -281.025629)
			(xy 10.213847 -281.050719) (xy 10.158955 -281.067767) (xy 10.102126 -281.076388) (xy 10.073386 -281.076908)
			(xy 10.046135 -281.076421) (xy 9.992189 -281.068663) (xy 9.939896 -281.053307) (xy 9.890321 -281.030665)
			(xy 9.844472 -281.001198) (xy 9.803283 -280.965507) (xy 9.767593 -280.924317) (xy 9.738128 -280.878467)
			(xy 9.715488 -280.828891) (xy 9.700134 -280.776597) (xy 9.692378 -280.722651) (xy 0.529844 -280.722651)
			(xy 0.529844 -282.382031) (xy 5.88618 -282.382031) (xy 5.88618 -282.327529) (xy 5.893936 -282.273582)
			(xy 5.909291 -282.221288) (xy 5.931932 -282.171711) (xy 5.961397 -282.125861) (xy 5.997088 -282.084671)
			(xy 6.038278 -282.04898) (xy 6.084128 -282.019514) (xy 6.133704 -281.996872) (xy 6.185998 -281.981517)
			(xy 6.239945 -281.97376) (xy 6.267196 -281.973274) (xy 6.295934 -281.973807) (xy 6.352761 -281.982428)
			(xy 6.407651 -281.999477) (xy 6.459363 -282.024566) (xy 6.506727 -282.057129) (xy 6.528054 -282.076398)
			(xy 6.534912 -282.083002) (xy 6.552946 -282.090114) (xy 6.641846 -282.090114) (xy 6.65988 -282.083002)
			(xy 6.666738 -282.076398) (xy 6.688065 -282.057128) (xy 6.735428 -282.024563) (xy 6.787139 -281.999472)
			(xy 6.84203 -281.982422) (xy 6.898857 -281.9738) (xy 6.956335 -281.9738) (xy 7.013162 -281.982422)
			(xy 7.068053 -281.999472) (xy 7.119764 -282.024563) (xy 7.167127 -282.057128) (xy 7.188454 -282.076398)
			(xy 7.195312 -282.083002) (xy 7.213346 -282.090114) (xy 7.302246 -282.090114) (xy 7.32028 -282.083002)
			(xy 7.327138 -282.076398) (xy 7.348476 -282.05714) (xy 7.395834 -282.024569) (xy 7.447543 -281.999474)
			(xy 7.502431 -281.98242) (xy 7.559258 -281.973796) (xy 7.587996 -281.973274) (xy 7.61812 -281.97384)
			(xy 7.677617 -281.983321) (xy 7.734885 -282.002033) (xy 7.788502 -282.02951) (xy 7.837136 -282.06507)
			(xy 7.85876 -282.08605) (xy 7.866186 -282.092858) (xy 7.884765 -282.100598) (xy 7.894828 -282.101036)
			(xy 7.966964 -282.101036) (xy 7.977033 -282.100609) (xy 7.995632 -282.092891) (xy 8.003032 -282.08605)
			(xy 8.024672 -282.065086) (xy 8.073296 -282.029514) (xy 8.126908 -282.00203) (xy 8.184175 -281.983318)
			(xy 8.243673 -281.973844) (xy 8.273796 -281.973274) (xy 8.301049 -281.973733) (xy 8.355001 -281.98149)
			(xy 8.407299 -281.996845) (xy 8.45688 -282.019488) (xy 8.502734 -282.048956) (xy 8.543928 -282.08465)
			(xy 8.579622 -282.125843) (xy 8.60909 -282.171696) (xy 8.631733 -282.221277) (xy 8.64709 -282.273575)
			(xy 8.654847 -282.327527) (xy 8.654847 -282.382033) (xy 8.64709 -282.435985) (xy 8.631733 -282.488283)
			(xy 8.60909 -282.537864) (xy 8.579622 -282.583717) (xy 8.543928 -282.62491) (xy 8.502734 -282.660604)
			(xy 8.45688 -282.690072) (xy 8.407299 -282.712715) (xy 8.355001 -282.72807) (xy 8.301049 -282.735827)
			(xy 8.273796 -282.73629) (xy 8.243672 -282.735739) (xy 8.184174 -282.726256) (xy 8.126905 -282.707541)
			(xy 8.073288 -282.68006) (xy 8.024656 -282.644496) (xy 8.003032 -282.623514) (xy 7.995613 -282.616697)
			(xy 7.977028 -282.608963) (xy 7.966964 -282.608528) (xy 7.894828 -282.608528) (xy 7.884759 -282.608961)
			(xy 7.866161 -282.616676) (xy 7.85876 -282.623514) (xy 7.837134 -282.644493) (xy 7.788505 -282.680061)
			(xy 7.734889 -282.707541) (xy 7.677619 -282.726249) (xy 7.61812 -282.735721) (xy 7.587996 -282.73629)
			(xy 7.559257 -282.735771) (xy 7.502429 -282.727148) (xy 7.447538 -282.710097) (xy 7.395827 -282.685004)
			(xy 7.348464 -282.652437) (xy 7.327138 -282.633166) (xy 7.32028 -282.626562) (xy 7.302246 -282.61945)
			(xy 7.213346 -282.61945) (xy 7.195312 -282.626562) (xy 7.188454 -282.633166) (xy 7.167127 -282.652436)
			(xy 7.119764 -282.685001) (xy 7.068053 -282.710092) (xy 7.013162 -282.727142) (xy 6.956335 -282.735764)
			(xy 6.898857 -282.735764) (xy 6.84203 -282.727142) (xy 6.787139 -282.710092) (xy 6.735428 -282.685001)
			(xy 6.688065 -282.652436) (xy 6.666738 -282.633166) (xy 6.65988 -282.626562) (xy 6.641846 -282.61945)
			(xy 6.552946 -282.61945) (xy 6.534912 -282.626562) (xy 6.528054 -282.633166) (xy 6.506729 -282.652439)
			(xy 6.459366 -282.685005) (xy 6.407654 -282.710097) (xy 6.352763 -282.727147) (xy 6.295935 -282.735769)
			(xy 6.267196 -282.73629) (xy 6.239945 -282.7358) (xy 6.185998 -282.728043) (xy 6.133704 -282.712688)
			(xy 6.084128 -282.690046) (xy 6.038278 -282.66058) (xy 5.997088 -282.624889) (xy 5.961397 -282.583699)
			(xy 5.931932 -282.537849) (xy 5.909291 -282.488272) (xy 5.893936 -282.435978) (xy 5.88618 -282.382031)
			(xy 0.529844 -282.382031) (xy 0.529844 -283.186451) (xy 9.692378 -283.186451) (xy 9.692378 -283.131949)
			(xy 9.700134 -283.078003) (xy 9.715488 -283.025709) (xy 9.738128 -282.976133) (xy 9.767593 -282.930283)
			(xy 9.803283 -282.889093) (xy 9.844472 -282.853402) (xy 9.890321 -282.823935) (xy 9.939896 -282.801293)
			(xy 9.992189 -282.785937) (xy 10.046135 -282.778179) (xy 10.073386 -282.777692) (xy 10.102124 -282.778226)
			(xy 10.158951 -282.786847) (xy 10.213842 -282.803894) (xy 10.265554 -282.828984) (xy 10.312917 -282.861546)
			(xy 10.334244 -282.880816) (xy 10.341102 -282.88742) (xy 10.359136 -282.894532) (xy 10.448036 -282.894532)
			(xy 10.46607 -282.88742) (xy 10.472928 -282.880816) (xy 10.494255 -282.861546) (xy 10.541618 -282.828981)
			(xy 10.593329 -282.80389) (xy 10.64822 -282.78684) (xy 10.705047 -282.778218) (xy 10.762525 -282.778218)
			(xy 10.819352 -282.78684) (xy 10.874243 -282.80389) (xy 10.925954 -282.828981) (xy 10.973317 -282.861546)
			(xy 10.994644 -282.880816) (xy 11.001502 -282.88742) (xy 11.019536 -282.894532) (xy 11.108436 -282.894532)
			(xy 11.12647 -282.88742) (xy 11.133328 -282.880816) (xy 11.154658 -282.861548) (xy 11.202019 -282.828982)
			(xy 11.25373 -282.80389) (xy 11.30862 -282.786838) (xy 11.365447 -282.778214) (xy 11.394186 -282.777692)
			(xy 11.42431 -282.77826) (xy 11.483807 -282.78774) (xy 11.541075 -282.806451) (xy 11.594692 -282.833928)
			(xy 11.643326 -282.869488) (xy 11.66495 -282.890468) (xy 11.672377 -282.897274) (xy 11.690955 -282.905015)
			(xy 11.701018 -282.905454) (xy 11.773154 -282.905454) (xy 11.783222 -282.905017) (xy 11.801821 -282.897306)
			(xy 11.809222 -282.890468) (xy 11.83087 -282.869512) (xy 11.879491 -282.833938) (xy 11.933102 -282.806452)
			(xy 11.990367 -282.787739) (xy 12.049863 -282.778263) (xy 12.079986 -282.777692) (xy 12.10724 -282.778154)
			(xy 12.161192 -282.78591) (xy 12.213491 -282.801265) (xy 12.263073 -282.823906) (xy 12.308928 -282.853374)
			(xy 12.350123 -282.889068) (xy 12.385818 -282.930261) (xy 12.415287 -282.976114) (xy 12.437931 -283.025695)
			(xy 12.453287 -283.077994) (xy 12.461045 -283.131947) (xy 12.461045 -283.186453) (xy 12.453287 -283.240406)
			(xy 12.437931 -283.292705) (xy 12.415287 -283.342286) (xy 12.385818 -283.388139) (xy 12.350123 -283.429332)
			(xy 12.308928 -283.465026) (xy 12.263073 -283.494494) (xy 12.213491 -283.517135) (xy 12.161192 -283.53249)
			(xy 12.10724 -283.540246) (xy 12.079986 -283.540708) (xy 12.049862 -283.540158) (xy 11.990364 -283.530674)
			(xy 11.933095 -283.511959) (xy 11.879478 -283.484478) (xy 11.830845 -283.448914) (xy 11.809222 -283.427932)
			(xy 11.801805 -283.421114) (xy 11.783219 -283.41338) (xy 11.773154 -283.412946) (xy 11.701018 -283.412946)
			(xy 11.690948 -283.413369) (xy 11.67235 -283.42109) (xy 11.66495 -283.427932) (xy 11.643315 -283.448901)
			(xy 11.59469 -283.484473) (xy 11.541076 -283.511957) (xy 11.483808 -283.530667) (xy 11.42431 -283.540139)
			(xy 11.394186 -283.540708) (xy 11.365447 -283.540191) (xy 11.308619 -283.531566) (xy 11.253729 -283.514515)
			(xy 11.202017 -283.489422) (xy 11.154655 -283.456855) (xy 11.133328 -283.437584) (xy 11.12647 -283.43098)
			(xy 11.108436 -283.423868) (xy 11.019536 -283.423868) (xy 11.001502 -283.43098) (xy 10.994644 -283.437584)
			(xy 10.973317 -283.456854) (xy 10.925954 -283.489419) (xy 10.874243 -283.51451) (xy 10.819352 -283.53156)
			(xy 10.762525 -283.540182) (xy 10.705047 -283.540182) (xy 10.64822 -283.53156) (xy 10.593329 -283.51451)
			(xy 10.541618 -283.489419) (xy 10.494255 -283.456854) (xy 10.472928 -283.437584) (xy 10.46607 -283.43098)
			(xy 10.448036 -283.423868) (xy 10.359136 -283.423868) (xy 10.341102 -283.43098) (xy 10.334244 -283.437584)
			(xy 10.312926 -283.456865) (xy 10.265561 -283.489429) (xy 10.213847 -283.514519) (xy 10.158955 -283.531567)
			(xy 10.102126 -283.540188) (xy 10.073386 -283.540708) (xy 10.046135 -283.540221) (xy 9.992189 -283.532463)
			(xy 9.939896 -283.517107) (xy 9.890321 -283.494465) (xy 9.844472 -283.464998) (xy 9.803283 -283.429307)
			(xy 9.767593 -283.388117) (xy 9.738128 -283.342267) (xy 9.715488 -283.292691) (xy 9.700134 -283.240397)
			(xy 9.692378 -283.186451) (xy 0.529844 -283.186451) (xy 0.529844 -284.845831) (xy 5.88618 -284.845831)
			(xy 5.88618 -284.791329) (xy 5.893936 -284.737382) (xy 5.909291 -284.685088) (xy 5.931932 -284.635511)
			(xy 5.961397 -284.589661) (xy 5.997088 -284.548471) (xy 6.038278 -284.51278) (xy 6.084128 -284.483314)
			(xy 6.133704 -284.460672) (xy 6.185998 -284.445317) (xy 6.239945 -284.43756) (xy 6.267196 -284.437074)
			(xy 6.295934 -284.437607) (xy 6.352761 -284.446228) (xy 6.407651 -284.463277) (xy 6.459363 -284.488366)
			(xy 6.506727 -284.520929) (xy 6.528054 -284.540198) (xy 6.534912 -284.546802) (xy 6.552946 -284.553914)
			(xy 6.641846 -284.553914) (xy 6.65988 -284.546802) (xy 6.666738 -284.540198) (xy 6.688065 -284.520928)
			(xy 6.735428 -284.488363) (xy 6.787139 -284.463272) (xy 6.84203 -284.446222) (xy 6.898857 -284.4376)
			(xy 6.956335 -284.4376) (xy 7.013162 -284.446222) (xy 7.068053 -284.463272) (xy 7.119764 -284.488363)
			(xy 7.167127 -284.520928) (xy 7.188454 -284.540198) (xy 7.195312 -284.546802) (xy 7.213346 -284.553914)
			(xy 7.302246 -284.553914) (xy 7.32028 -284.546802) (xy 7.327138 -284.540198) (xy 7.348476 -284.52094)
			(xy 7.395834 -284.488369) (xy 7.447543 -284.463274) (xy 7.502431 -284.44622) (xy 7.559258 -284.437596)
			(xy 7.587996 -284.437074) (xy 7.61812 -284.43764) (xy 7.677617 -284.447121) (xy 7.734885 -284.465833)
			(xy 7.788502 -284.49331) (xy 7.837136 -284.52887) (xy 7.85876 -284.54985) (xy 7.866186 -284.556658)
			(xy 7.884765 -284.564398) (xy 7.894828 -284.564836) (xy 7.966964 -284.564836) (xy 7.977033 -284.564409)
			(xy 7.995632 -284.556691) (xy 8.003032 -284.54985) (xy 8.024672 -284.528886) (xy 8.073296 -284.493314)
			(xy 8.126908 -284.46583) (xy 8.184175 -284.447118) (xy 8.243673 -284.437644) (xy 8.273796 -284.437074)
			(xy 8.301049 -284.437533) (xy 8.355001 -284.44529) (xy 8.407299 -284.460645) (xy 8.45688 -284.483288)
			(xy 8.502734 -284.512756) (xy 8.543928 -284.54845) (xy 8.579622 -284.589643) (xy 8.60909 -284.635496)
			(xy 8.631733 -284.685077) (xy 8.64709 -284.737375) (xy 8.654847 -284.791327) (xy 8.654847 -284.845833)
			(xy 8.64709 -284.899785) (xy 8.631733 -284.952083) (xy 8.60909 -285.001664) (xy 8.579622 -285.047517)
			(xy 8.543928 -285.08871) (xy 8.502734 -285.124404) (xy 8.45688 -285.153872) (xy 8.407299 -285.176515)
			(xy 8.355001 -285.19187) (xy 8.301049 -285.199627) (xy 8.273796 -285.20009) (xy 8.243672 -285.199539)
			(xy 8.184174 -285.190056) (xy 8.126905 -285.171341) (xy 8.073288 -285.14386) (xy 8.024656 -285.108296)
			(xy 8.003032 -285.087314) (xy 7.995613 -285.080497) (xy 7.977028 -285.072763) (xy 7.966964 -285.072328)
			(xy 7.894828 -285.072328) (xy 7.884759 -285.072761) (xy 7.866161 -285.080476) (xy 7.85876 -285.087314)
			(xy 7.837134 -285.108293) (xy 7.788505 -285.143861) (xy 7.734889 -285.171341) (xy 7.677619 -285.190049)
			(xy 7.61812 -285.199521) (xy 7.587996 -285.20009) (xy 7.559257 -285.199571) (xy 7.502429 -285.190948)
			(xy 7.447538 -285.173897) (xy 7.395827 -285.148804) (xy 7.348464 -285.116237) (xy 7.327138 -285.096966)
			(xy 7.32028 -285.090362) (xy 7.302246 -285.08325) (xy 7.213346 -285.08325) (xy 7.195312 -285.090362)
			(xy 7.188454 -285.096966) (xy 7.167127 -285.116236) (xy 7.119764 -285.148801) (xy 7.068053 -285.173892)
			(xy 7.013162 -285.190942) (xy 6.956335 -285.199564) (xy 6.898857 -285.199564) (xy 6.84203 -285.190942)
			(xy 6.787139 -285.173892) (xy 6.735428 -285.148801) (xy 6.688065 -285.116236) (xy 6.666738 -285.096966)
			(xy 6.65988 -285.090362) (xy 6.641846 -285.08325) (xy 6.552946 -285.08325) (xy 6.534912 -285.090362)
			(xy 6.528054 -285.096966) (xy 6.506729 -285.116239) (xy 6.459366 -285.148805) (xy 6.407654 -285.173897)
			(xy 6.352763 -285.190947) (xy 6.295935 -285.199569) (xy 6.267196 -285.20009) (xy 6.239945 -285.1996)
			(xy 6.185998 -285.191843) (xy 6.133704 -285.176488) (xy 6.084128 -285.153846) (xy 6.038278 -285.12438)
			(xy 5.997088 -285.088689) (xy 5.961397 -285.047499) (xy 5.931932 -285.001649) (xy 5.909291 -284.952072)
			(xy 5.893936 -284.899778) (xy 5.88618 -284.845831) (xy 0.529844 -284.845831) (xy 0.529844 -285.462218)
			(xy 11.958572 -285.462218) (xy 11.962643 -285.406596) (xy 11.974769 -285.352159) (xy 11.994692 -285.300068)
			(xy 12.021988 -285.251433) (xy 12.056074 -285.20729) (xy 12.096223 -285.168581) (xy 12.141581 -285.13613)
			(xy 12.191181 -285.110629) (xy 12.243965 -285.092622) (xy 12.298808 -285.082492) (xy 12.354542 -285.080455)
			(xy 12.409979 -285.086555) (xy 12.463936 -285.100661) (xy 12.515265 -285.122473) (xy 12.562871 -285.151527)
			(xy 12.605739 -285.187202) (xy 12.642956 -285.228739) (xy 12.673729 -285.275252) (xy 12.697401 -285.325749)
			(xy 12.713469 -285.379156) (xy 12.721589 -285.434332) (xy 12.722098 -285.462218) (xy 12.721589 -285.490104)
			(xy 12.713469 -285.54528) (xy 12.697401 -285.598687) (xy 12.673729 -285.649184) (xy 12.642956 -285.695697)
			(xy 12.605739 -285.737234) (xy 12.562871 -285.772909) (xy 12.515265 -285.801963) (xy 12.463936 -285.823775)
			(xy 12.409979 -285.837881) (xy 12.354542 -285.843981) (xy 12.298808 -285.841944) (xy 12.243965 -285.831814)
			(xy 12.191181 -285.813807) (xy 12.141581 -285.788306) (xy 12.096223 -285.755855) (xy 12.056074 -285.717146)
			(xy 12.021988 -285.673003) (xy 11.994692 -285.624368) (xy 11.974769 -285.572277) (xy 11.962643 -285.51784)
			(xy 11.958572 -285.462218) (xy 0.529844 -285.462218) (xy 0.529844 -287.131831) (xy 5.20038 -287.131831)
			(xy 5.20038 -287.077329) (xy 5.208136 -287.023382) (xy 5.223491 -286.971088) (xy 5.246132 -286.921511)
			(xy 5.275597 -286.875661) (xy 5.311288 -286.834471) (xy 5.352478 -286.79878) (xy 5.398328 -286.769314)
			(xy 5.447904 -286.746672) (xy 5.500198 -286.731317) (xy 5.554145 -286.72356) (xy 5.581396 -286.723074)
			(xy 5.61152 -286.72364) (xy 5.671017 -286.733121) (xy 5.728285 -286.751833) (xy 5.781902 -286.77931)
			(xy 5.830536 -286.81487) (xy 5.85216 -286.83585) (xy 5.859586 -286.842658) (xy 5.878165 -286.850398)
			(xy 5.888228 -286.850836) (xy 5.960364 -286.850836) (xy 5.970433 -286.850409) (xy 5.989032 -286.842691)
			(xy 5.996432 -286.83585) (xy 6.018072 -286.814886) (xy 6.066696 -286.779314) (xy 6.120308 -286.75183)
			(xy 6.177575 -286.733118) (xy 6.237073 -286.723644) (xy 6.267196 -286.723074) (xy 6.294449 -286.723533)
			(xy 6.348401 -286.73129) (xy 6.400699 -286.746645) (xy 6.45028 -286.769288) (xy 6.496134 -286.798756)
			(xy 6.537328 -286.83445) (xy 6.573022 -286.875643) (xy 6.60249 -286.921496) (xy 6.625133 -286.971077)
			(xy 6.64049 -287.023375) (xy 6.648247 -287.077327) (xy 6.648247 -287.131833) (xy 6.64049 -287.185785)
			(xy 6.625133 -287.238083) (xy 6.60249 -287.287664) (xy 6.573022 -287.333517) (xy 6.537328 -287.37471)
			(xy 6.496134 -287.410404) (xy 6.45028 -287.439872) (xy 6.400699 -287.462515) (xy 6.348401 -287.47787)
			(xy 6.294449 -287.485627) (xy 6.267196 -287.48609) (xy 6.237072 -287.485539) (xy 6.177574 -287.476056)
			(xy 6.120305 -287.457341) (xy 6.066688 -287.42986) (xy 6.018056 -287.394296) (xy 5.996432 -287.373314)
			(xy 5.989013 -287.366497) (xy 5.970428 -287.358763) (xy 5.960364 -287.358328) (xy 5.888228 -287.358328)
			(xy 5.878159 -287.358761) (xy 5.859561 -287.366476) (xy 5.85216 -287.373314) (xy 5.830534 -287.394293)
			(xy 5.781905 -287.429861) (xy 5.728289 -287.457341) (xy 5.671019 -287.476049) (xy 5.61152 -287.485521)
			(xy 5.581396 -287.48609) (xy 5.554145 -287.4856) (xy 5.500198 -287.477843) (xy 5.447904 -287.462488)
			(xy 5.398328 -287.439846) (xy 5.352478 -287.41038) (xy 5.311288 -287.374689) (xy 5.275597 -287.333499)
			(xy 5.246132 -287.287649) (xy 5.223491 -287.238072) (xy 5.208136 -287.185778) (xy 5.20038 -287.131831)
			(xy 0.529844 -287.131831) (xy 0.529844 -287.984001) (xy 11.94992 -287.984001) (xy 11.94992 -287.929499)
			(xy 11.957676 -287.875552) (xy 11.973031 -287.823257) (xy 11.995672 -287.773681) (xy 12.025138 -287.72783)
			(xy 12.060829 -287.686641) (xy 12.102019 -287.650949) (xy 12.147869 -287.621483) (xy 12.197446 -287.598842)
			(xy 12.24974 -287.583487) (xy 12.303687 -287.57573) (xy 12.330938 -287.575244) (xy 12.358307 -287.575736)
			(xy 12.412486 -287.583546) (xy 12.464989 -287.599028) (xy 12.514736 -287.621865) (xy 12.560704 -287.651585)
			(xy 12.581636 -287.669224) (xy 12.58189 -287.669478) (xy 12.588969 -287.675076) (xy 12.605892 -287.681314)
			(xy 12.61491 -287.68167) (xy 12.681966 -287.68167) (xy 12.690982 -287.681303) (xy 12.707899 -287.675063)
			(xy 12.714986 -287.669478) (xy 12.714986 -287.669224) (xy 12.71524 -287.669224) (xy 12.736187 -287.651603)
			(xy 12.782155 -287.621888) (xy 12.831899 -287.599048) (xy 12.884396 -287.583553) (xy 12.93857 -287.57572)
			(xy 12.965938 -287.575244) (xy 12.993191 -287.575703) (xy 13.047143 -287.58346) (xy 13.099441 -287.598816)
			(xy 13.149021 -287.621458) (xy 13.194875 -287.650927) (xy 13.236068 -287.68662) (xy 13.271762 -287.727813)
			(xy 13.301231 -287.773667) (xy 13.323873 -287.823247) (xy 13.33923 -287.875546) (xy 13.346987 -287.929497)
			(xy 13.346987 -287.984003) (xy 13.33923 -288.037954) (xy 13.323873 -288.090253) (xy 13.301231 -288.139833)
			(xy 13.271762 -288.185687) (xy 13.236068 -288.22688) (xy 13.194875 -288.262573) (xy 13.149021 -288.292042)
			(xy 13.099441 -288.314684) (xy 13.047143 -288.33004) (xy 12.993191 -288.337797) (xy 12.965938 -288.33826)
			(xy 12.938568 -288.337781) (xy 12.884389 -288.329968) (xy 12.831886 -288.314482) (xy 12.782139 -288.291643)
			(xy 12.736172 -288.261921) (xy 12.71524 -288.24428) (xy 12.714986 -288.244026) (xy 12.707914 -288.238419)
			(xy 12.690986 -288.232186) (xy 12.681966 -288.231834) (xy 12.61491 -288.231834) (xy 12.605893 -288.232189)
			(xy 12.588976 -288.238437) (xy 12.58189 -288.244026) (xy 12.58189 -288.24428) (xy 12.581636 -288.24428)
			(xy 12.560699 -288.261913) (xy 12.514728 -288.291626) (xy 12.464981 -288.314464) (xy 12.412482 -288.329956)
			(xy 12.358307 -288.337785) (xy 12.330938 -288.33826) (xy 12.303687 -288.33777) (xy 12.24974 -288.330013)
			(xy 12.197446 -288.314658) (xy 12.147869 -288.292017) (xy 12.102019 -288.262551) (xy 12.060829 -288.226859)
			(xy 12.025138 -288.18567) (xy 11.995672 -288.139819) (xy 11.973031 -288.090243) (xy 11.957676 -288.037948)
			(xy 11.94992 -287.984001) (xy 0.529844 -287.984001) (xy 0.529844 -289.258321) (xy 5.006068 -289.258321)
			(xy 5.006068 -289.203819) (xy 5.013824 -289.149872) (xy 5.029179 -289.097577) (xy 5.05182 -289.048)
			(xy 5.081286 -289.00215) (xy 5.116977 -288.96096) (xy 5.158167 -288.925268) (xy 5.204017 -288.895802)
			(xy 5.253593 -288.873161) (xy 5.305888 -288.857805) (xy 5.359835 -288.850048) (xy 5.387086 -288.849562)
			(xy 5.414457 -288.850021) (xy 5.468637 -288.857838) (xy 5.52114 -288.873328) (xy 5.570887 -288.896172)
			(xy 5.616853 -288.925899) (xy 5.637784 -288.943542) (xy 5.638038 -288.943796) (xy 5.645139 -288.949362)
			(xy 5.662045 -288.955621) (xy 5.671058 -288.955988) (xy 5.738114 -288.955988) (xy 5.747132 -288.95564)
			(xy 5.764049 -288.949387) (xy 5.771134 -288.943796) (xy 5.771134 -288.943542) (xy 5.771388 -288.943542)
			(xy 5.792319 -288.925902) (xy 5.838292 -288.896189) (xy 5.888039 -288.873352) (xy 5.94054 -288.857862)
			(xy 5.994717 -288.850035) (xy 6.022086 -288.849562) (xy 6.049339 -288.850025) (xy 6.10329 -288.857782)
			(xy 6.155589 -288.873137) (xy 6.205169 -288.89578) (xy 6.251023 -288.925247) (xy 6.292216 -288.960941)
			(xy 6.32791 -289.002134) (xy 6.357379 -289.047987) (xy 6.380021 -289.097568) (xy 6.395378 -289.149866)
			(xy 6.403135 -289.203817) (xy 6.403135 -289.258323) (xy 6.395378 -289.312274) (xy 6.380021 -289.364572)
			(xy 6.357379 -289.414153) (xy 6.32791 -289.460006) (xy 6.292216 -289.501199) (xy 6.251023 -289.536893)
			(xy 6.205169 -289.56636) (xy 6.155589 -289.589003) (xy 6.10329 -289.604358) (xy 6.049339 -289.612115)
			(xy 6.022086 -289.612578) (xy 5.994715 -289.612125) (xy 5.940535 -289.604305) (xy 5.888032 -289.588813)
			(xy 5.838285 -289.565968) (xy 5.792319 -289.536241) (xy 5.771388 -289.518598) (xy 5.771134 -289.518344)
			(xy 5.764047 -289.512759) (xy 5.74713 -289.506513) (xy 5.738114 -289.506152) (xy 5.671058 -289.506152)
			(xy 5.662043 -289.506525) (xy 5.645125 -289.51276) (xy 5.638038 -289.518344) (xy 5.638038 -289.518598)
			(xy 5.637784 -289.518598) (xy 5.616831 -289.536211) (xy 5.570864 -289.565927) (xy 5.521122 -289.588768)
			(xy 5.468626 -289.604265) (xy 5.414454 -289.6121) (xy 5.387086 -289.612578) (xy 5.359835 -289.612092)
			(xy 5.305888 -289.604335) (xy 5.253593 -289.588979) (xy 5.204017 -289.566338) (xy 5.158167 -289.536872)
			(xy 5.116977 -289.50118) (xy 5.081286 -289.45999) (xy 5.05182 -289.41414) (xy 5.029179 -289.364563)
			(xy 5.013824 -289.312268) (xy 5.006068 -289.258321) (xy 0.529844 -289.258321) (xy 0.529844 -304.457354)
			(xy 7.652256 -304.457354) (xy 7.656327 -304.401732) (xy 7.668453 -304.347295) (xy 7.688376 -304.295204)
			(xy 7.715672 -304.246569) (xy 7.749758 -304.202426) (xy 7.789907 -304.163717) (xy 7.835265 -304.131266)
			(xy 7.884865 -304.105765) (xy 7.937649 -304.087758) (xy 7.992492 -304.077628) (xy 8.048226 -304.075591)
			(xy 8.103663 -304.081691) (xy 8.15762 -304.095797) (xy 8.208949 -304.117609) (xy 8.256555 -304.146663)
			(xy 8.299423 -304.182338) (xy 8.33664 -304.223875) (xy 8.367413 -304.270388) (xy 8.391085 -304.320885)
			(xy 8.407153 -304.374292) (xy 8.415273 -304.429468) (xy 8.415782 -304.457354) (xy 8.415273 -304.48524)
			(xy 8.41306 -304.50028) (xy 14.926308 -304.50028) (xy 14.930379 -304.444658) (xy 14.942505 -304.390221)
			(xy 14.962428 -304.33813) (xy 14.989724 -304.289495) (xy 15.02381 -304.245352) (xy 15.063959 -304.206643)
			(xy 15.109317 -304.174192) (xy 15.158917 -304.148691) (xy 15.211701 -304.130684) (xy 15.266544 -304.120554)
			(xy 15.322278 -304.118517) (xy 15.377715 -304.124617) (xy 15.431672 -304.138723) (xy 15.483001 -304.160535)
			(xy 15.530607 -304.189589) (xy 15.573475 -304.225264) (xy 15.610692 -304.266801) (xy 15.641465 -304.313314)
			(xy 15.665137 -304.363811) (xy 15.681205 -304.417218) (xy 15.689325 -304.472394) (xy 15.689834 -304.50028)
			(xy 15.689325 -304.528166) (xy 15.681205 -304.583342) (xy 15.665137 -304.636749) (xy 15.641465 -304.687246)
			(xy 15.610692 -304.733759) (xy 15.573475 -304.775296) (xy 15.530607 -304.810971) (xy 15.483001 -304.840025)
			(xy 15.431672 -304.861837) (xy 15.377715 -304.875943) (xy 15.322278 -304.882043) (xy 15.266544 -304.880006)
			(xy 15.211701 -304.869876) (xy 15.158917 -304.851869) (xy 15.109317 -304.826368) (xy 15.063959 -304.793917)
			(xy 15.02381 -304.755208) (xy 14.989724 -304.711065) (xy 14.962428 -304.66243) (xy 14.942505 -304.610339)
			(xy 14.930379 -304.555902) (xy 14.926308 -304.50028) (xy 8.41306 -304.50028) (xy 8.407153 -304.540416)
			(xy 8.391085 -304.593823) (xy 8.367413 -304.64432) (xy 8.33664 -304.690833) (xy 8.299423 -304.73237)
			(xy 8.256555 -304.768045) (xy 8.208949 -304.797099) (xy 8.15762 -304.818911) (xy 8.103663 -304.833017)
			(xy 8.048226 -304.839117) (xy 7.992492 -304.83708) (xy 7.937649 -304.82695) (xy 7.884865 -304.808943)
			(xy 7.835265 -304.783442) (xy 7.789907 -304.750991) (xy 7.749758 -304.712282) (xy 7.715672 -304.668139)
			(xy 7.688376 -304.619504) (xy 7.668453 -304.567413) (xy 7.656327 -304.512976) (xy 7.652256 -304.457354)
			(xy 0.529844 -304.457354) (xy 0.529844 -305.159664) (xy 12.577824 -305.159664) (xy 12.581895 -305.104042)
			(xy 12.594021 -305.049605) (xy 12.613944 -304.997514) (xy 12.64124 -304.948879) (xy 12.675326 -304.904736)
			(xy 12.715475 -304.866027) (xy 12.760833 -304.833576) (xy 12.810433 -304.808075) (xy 12.863217 -304.790068)
			(xy 12.91806 -304.779938) (xy 12.973794 -304.777901) (xy 13.029231 -304.784001) (xy 13.083188 -304.798107)
			(xy 13.134517 -304.819919) (xy 13.182123 -304.848973) (xy 13.224991 -304.884648) (xy 13.262208 -304.926185)
			(xy 13.292981 -304.972698) (xy 13.316653 -305.023195) (xy 13.332721 -305.076602) (xy 13.340841 -305.131778)
			(xy 13.34135 -305.159664) (xy 13.340841 -305.18755) (xy 13.332721 -305.242726) (xy 13.316653 -305.296133)
			(xy 13.292981 -305.34663) (xy 13.262208 -305.393143) (xy 13.224991 -305.43468) (xy 13.182123 -305.470355)
			(xy 13.134517 -305.499409) (xy 13.083188 -305.521221) (xy 13.029231 -305.535327) (xy 12.973794 -305.541427)
			(xy 12.91806 -305.53939) (xy 12.863217 -305.52926) (xy 12.810433 -305.511253) (xy 12.760833 -305.485752)
			(xy 12.715475 -305.453301) (xy 12.675326 -305.414592) (xy 12.64124 -305.370449) (xy 12.613944 -305.321814)
			(xy 12.594021 -305.269723) (xy 12.581895 -305.215286) (xy 12.577824 -305.159664) (xy 0.529844 -305.159664)
			(xy 0.529844 -306.115466) (xy 13.635734 -306.115466) (xy 13.639805 -306.059844) (xy 13.651931 -306.005407)
			(xy 13.671854 -305.953316) (xy 13.69915 -305.904681) (xy 13.733236 -305.860538) (xy 13.773385 -305.821829)
			(xy 13.818743 -305.789378) (xy 13.868343 -305.763877) (xy 13.921127 -305.74587) (xy 13.97597 -305.73574)
			(xy 14.031704 -305.733703) (xy 14.087141 -305.739803) (xy 14.141098 -305.753909) (xy 14.192427 -305.775721)
			(xy 14.240033 -305.804775) (xy 14.282901 -305.84045) (xy 14.320118 -305.881987) (xy 14.350891 -305.9285)
			(xy 14.374563 -305.978997) (xy 14.390631 -306.032404) (xy 14.398751 -306.08758) (xy 14.39926 -306.115466)
			(xy 14.398751 -306.143352) (xy 14.390631 -306.198528) (xy 14.374563 -306.251935) (xy 14.350891 -306.302432)
			(xy 14.320118 -306.348945) (xy 14.282901 -306.390482) (xy 14.240033 -306.426157) (xy 14.192427 -306.455211)
			(xy 14.141098 -306.477023) (xy 14.087141 -306.491129) (xy 14.031704 -306.497229) (xy 13.97597 -306.495192)
			(xy 13.921127 -306.485062) (xy 13.868343 -306.467055) (xy 13.818743 -306.441554) (xy 13.773385 -306.409103)
			(xy 13.733236 -306.370394) (xy 13.69915 -306.326251) (xy 13.671854 -306.277616) (xy 13.651931 -306.225525)
			(xy 13.639805 -306.171088) (xy 13.635734 -306.115466) (xy 0.529844 -306.115466) (xy 0.529844 -306.731416)
			(xy 15.643858 -306.731416) (xy 15.647929 -306.675794) (xy 15.660055 -306.621357) (xy 15.679978 -306.569266)
			(xy 15.707274 -306.520631) (xy 15.74136 -306.476488) (xy 15.781509 -306.437779) (xy 15.826867 -306.405328)
			(xy 15.876467 -306.379827) (xy 15.929251 -306.36182) (xy 15.984094 -306.35169) (xy 16.039828 -306.349653)
			(xy 16.095265 -306.355753) (xy 16.149222 -306.369859) (xy 16.200551 -306.391671) (xy 16.248157 -306.420725)
			(xy 16.291025 -306.4564) (xy 16.328242 -306.497937) (xy 16.359015 -306.54445) (xy 16.382687 -306.594947)
			(xy 16.398755 -306.648354) (xy 16.406875 -306.70353) (xy 16.407384 -306.731416) (xy 16.406875 -306.759302)
			(xy 16.398755 -306.814478) (xy 16.382687 -306.867885) (xy 16.359015 -306.918382) (xy 16.328242 -306.964895)
			(xy 16.291025 -307.006432) (xy 16.248157 -307.042107) (xy 16.200551 -307.071161) (xy 16.149222 -307.092973)
			(xy 16.095265 -307.107079) (xy 16.039828 -307.113179) (xy 15.984094 -307.111142) (xy 15.929251 -307.101012)
			(xy 15.876467 -307.083005) (xy 15.826867 -307.057504) (xy 15.781509 -307.025053) (xy 15.74136 -306.986344)
			(xy 15.707274 -306.942201) (xy 15.679978 -306.893566) (xy 15.660055 -306.841475) (xy 15.647929 -306.787038)
			(xy 15.643858 -306.731416) (xy 0.529844 -306.731416) (xy 0.529844 -307.621686) (xy 12.02385 -307.621686)
			(xy 12.027921 -307.566064) (xy 12.040047 -307.511627) (xy 12.05997 -307.459536) (xy 12.087266 -307.410901)
			(xy 12.121352 -307.366758) (xy 12.161501 -307.328049) (xy 12.206859 -307.295598) (xy 12.256459 -307.270097)
			(xy 12.309243 -307.25209) (xy 12.364086 -307.24196) (xy 12.41982 -307.239923) (xy 12.475257 -307.246023)
			(xy 12.529214 -307.260129) (xy 12.580543 -307.281941) (xy 12.628149 -307.310995) (xy 12.671017 -307.34667)
			(xy 12.708234 -307.388207) (xy 12.739007 -307.43472) (xy 12.750091 -307.458364) (xy 13.739366 -307.458364)
			(xy 13.743437 -307.402742) (xy 13.755563 -307.348305) (xy 13.775486 -307.296214) (xy 13.802782 -307.247579)
			(xy 13.836868 -307.203436) (xy 13.877017 -307.164727) (xy 13.922375 -307.132276) (xy 13.971975 -307.106775)
			(xy 14.024759 -307.088768) (xy 14.079602 -307.078638) (xy 14.135336 -307.076601) (xy 14.190773 -307.082701)
			(xy 14.24473 -307.096807) (xy 14.296059 -307.118619) (xy 14.343665 -307.147673) (xy 14.386533 -307.183348)
			(xy 14.42375 -307.224885) (xy 14.454523 -307.271398) (xy 14.478195 -307.321895) (xy 14.494263 -307.375302)
			(xy 14.502383 -307.430478) (xy 14.502892 -307.458364) (xy 14.502383 -307.48625) (xy 14.494263 -307.541426)
			(xy 14.478195 -307.594833) (xy 14.454523 -307.64533) (xy 14.42375 -307.691843) (xy 14.386533 -307.73338)
			(xy 14.343665 -307.769055) (xy 14.296059 -307.798109) (xy 14.24473 -307.819921) (xy 14.190773 -307.834027)
			(xy 14.135336 -307.840127) (xy 14.079602 -307.83809) (xy 14.024759 -307.82796) (xy 13.971975 -307.809953)
			(xy 13.922375 -307.784452) (xy 13.877017 -307.752001) (xy 13.836868 -307.713292) (xy 13.802782 -307.669149)
			(xy 13.775486 -307.620514) (xy 13.755563 -307.568423) (xy 13.743437 -307.513986) (xy 13.739366 -307.458364)
			(xy 12.750091 -307.458364) (xy 12.762679 -307.485217) (xy 12.778747 -307.538624) (xy 12.786867 -307.5938)
			(xy 12.787376 -307.621686) (xy 12.786867 -307.649572) (xy 12.778747 -307.704748) (xy 12.762679 -307.758155)
			(xy 12.739007 -307.808652) (xy 12.708234 -307.855165) (xy 12.671017 -307.896702) (xy 12.628149 -307.932377)
			(xy 12.580543 -307.961431) (xy 12.529214 -307.983243) (xy 12.475257 -307.997349) (xy 12.41982 -308.003449)
			(xy 12.364086 -308.001412) (xy 12.309243 -307.991282) (xy 12.256459 -307.973275) (xy 12.206859 -307.947774)
			(xy 12.161501 -307.915323) (xy 12.121352 -307.876614) (xy 12.087266 -307.832471) (xy 12.05997 -307.783836)
			(xy 12.040047 -307.731745) (xy 12.027921 -307.677308) (xy 12.02385 -307.621686) (xy 0.529844 -307.621686)
			(xy 0.529844 -308.929024) (xy 13.201648 -308.929024) (xy 13.205719 -308.873402) (xy 13.217845 -308.818965)
			(xy 13.237768 -308.766874) (xy 13.265064 -308.718239) (xy 13.29915 -308.674096) (xy 13.339299 -308.635387)
			(xy 13.384657 -308.602936) (xy 13.434257 -308.577435) (xy 13.487041 -308.559428) (xy 13.541884 -308.549298)
			(xy 13.597618 -308.547261) (xy 13.653055 -308.553361) (xy 13.707012 -308.567467) (xy 13.758341 -308.589279)
			(xy 13.805947 -308.618333) (xy 13.848815 -308.654008) (xy 13.886032 -308.695545) (xy 13.916805 -308.742058)
			(xy 13.940477 -308.792555) (xy 13.956545 -308.845962) (xy 13.964665 -308.901138) (xy 13.965174 -308.929024)
			(xy 13.964665 -308.95691) (xy 13.956545 -309.012086) (xy 13.940477 -309.065493) (xy 13.916805 -309.11599)
			(xy 13.886032 -309.162503) (xy 13.848815 -309.20404) (xy 13.805947 -309.239715) (xy 13.758341 -309.268769)
			(xy 13.707012 -309.290581) (xy 13.653055 -309.304687) (xy 13.597618 -309.310787) (xy 13.541884 -309.30875)
			(xy 13.487041 -309.29862) (xy 13.434257 -309.280613) (xy 13.384657 -309.255112) (xy 13.339299 -309.222661)
			(xy 13.29915 -309.183952) (xy 13.265064 -309.139809) (xy 13.237768 -309.091174) (xy 13.217845 -309.039083)
			(xy 13.205719 -308.984646) (xy 13.201648 -308.929024) (xy 0.529844 -308.929024) (xy 0.529844 -318.52997)
			(xy 10.590784 -318.52997) (xy 10.591212 -318.502598) (xy 10.599036 -318.448417) (xy 10.614533 -318.395912)
			(xy 10.637383 -318.346166) (xy 10.667118 -318.300202) (xy 10.684764 -318.279272) (xy 10.685018 -318.279018)
			(xy 10.690605 -318.271932) (xy 10.696851 -318.255015) (xy 10.69721 -318.245998) (xy 10.69721 -318.178942)
			(xy 10.696831 -318.169927) (xy 10.690598 -318.15301) (xy 10.685018 -318.145922) (xy 10.684764 -318.145922)
			(xy 10.684764 -318.145668) (xy 10.667138 -318.124726) (xy 10.637425 -318.078755) (xy 10.614587 -318.02901)
			(xy 10.599093 -317.976512) (xy 10.591261 -317.922338) (xy 10.590784 -317.89497) (xy 10.59125 -317.867718)
			(xy 10.59901 -317.81377) (xy 10.614369 -317.761476) (xy 10.637013 -317.711899) (xy 10.666482 -317.666049)
			(xy 10.702175 -317.624859) (xy 10.743367 -317.589168) (xy 10.789218 -317.559702) (xy 10.838796 -317.537061)
			(xy 10.891092 -317.521706) (xy 10.94504 -317.513948) (xy 10.972292 -317.513462) (xy 10.999663 -317.513918)
			(xy 11.053843 -317.521736) (xy 11.106347 -317.537226) (xy 11.156093 -317.560071) (xy 11.202059 -317.589799)
			(xy 11.22299 -317.607442) (xy 11.223244 -317.607696) (xy 11.230343 -317.613265) (xy 11.24725 -317.619522)
			(xy 11.256264 -317.619888) (xy 11.32332 -317.619888) (xy 11.332338 -317.619543) (xy 11.349255 -317.613287)
			(xy 11.35634 -317.607696) (xy 11.35634 -317.607442) (xy 11.356594 -317.607442) (xy 11.377527 -317.589801)
			(xy 11.423495 -317.560077) (xy 11.473241 -317.537231) (xy 11.525743 -317.521735) (xy 11.579921 -317.513906)
			(xy 11.634663 -317.513906) (xy 11.688841 -317.521735) (xy 11.741343 -317.537231) (xy 11.791089 -317.560077)
			(xy 11.837057 -317.589801) (xy 11.85799 -317.607442) (xy 11.858244 -317.607696) (xy 11.865343 -317.613265)
			(xy 11.88225 -317.619522) (xy 11.891264 -317.619888) (xy 11.95832 -317.619888) (xy 11.967338 -317.619543)
			(xy 11.984255 -317.613287) (xy 11.99134 -317.607696) (xy 11.99134 -317.607442) (xy 11.991594 -317.607442)
			(xy 12.012523 -317.589799) (xy 12.058496 -317.560086) (xy 12.108244 -317.53725) (xy 12.160746 -317.52176)
			(xy 12.214922 -317.513934) (xy 12.242292 -317.513462) (xy 12.269542 -317.513985) (xy 12.323487 -317.52174)
			(xy 12.375779 -317.537092) (xy 12.425354 -317.55973) (xy 12.471203 -317.589193) (xy 12.512393 -317.624881)
			(xy 12.548084 -317.666067) (xy 12.577551 -317.711913) (xy 12.600194 -317.761486) (xy 12.615552 -317.813776)
			(xy 12.623312 -317.86772) (xy 12.6238 -317.89497) (xy 12.623316 -317.92234) (xy 12.615503 -317.976518)
			(xy 12.600018 -318.029021) (xy 12.57718 -318.078768) (xy 12.547459 -318.124736) (xy 12.52982 -318.145668)
			(xy 12.529566 -318.145922) (xy 12.52396 -318.152995) (xy 12.517726 -318.169922) (xy 12.517374 -318.178942)
			(xy 12.517374 -318.245998) (xy 12.517738 -318.255014) (xy 12.523981 -318.271931) (xy 12.529566 -318.279018)
			(xy 12.52982 -318.279018) (xy 12.52982 -318.279272) (xy 12.547463 -318.300201) (xy 12.577173 -318.346175)
			(xy 12.600008 -318.395923) (xy 12.615498 -318.448425) (xy 12.623326 -318.502601) (xy 12.6238 -318.52997)
			(xy 12.623317 -318.557222) (xy 12.615564 -318.611173) (xy 12.600211 -318.663471) (xy 12.577571 -318.713052)
			(xy 12.548106 -318.758905) (xy 12.512414 -318.800099) (xy 12.471223 -318.835793) (xy 12.425371 -318.865261)
			(xy 12.375792 -318.887903) (xy 12.323495 -318.903259) (xy 12.269544 -318.911015) (xy 12.242292 -318.911478)
			(xy 12.214921 -318.911022) (xy 12.160742 -318.903203) (xy 12.108238 -318.887711) (xy 12.058491 -318.864867)
			(xy 12.012525 -318.83514) (xy 11.991594 -318.817498) (xy 11.99134 -318.817244) (xy 11.984251 -318.811661)
			(xy 11.967336 -318.805414) (xy 11.95832 -318.805052) (xy 11.891264 -318.805052) (xy 11.882244 -318.80538)
			(xy 11.865327 -318.811646) (xy 11.858244 -318.817244) (xy 11.85799 -318.817498) (xy 11.837057 -318.835139)
			(xy 11.791089 -318.864863) (xy 11.741343 -318.887709) (xy 11.688841 -318.903205) (xy 11.634663 -318.911034)
			(xy 11.579921 -318.911034) (xy 11.525743 -318.903205) (xy 11.473241 -318.887709) (xy 11.423495 -318.864863)
			(xy 11.377527 -318.835139) (xy 11.356594 -318.817498) (xy 11.35634 -318.817244) (xy 11.349251 -318.811661)
			(xy 11.332336 -318.805414) (xy 11.32332 -318.805052) (xy 11.256264 -318.805052) (xy 11.247244 -318.80538)
			(xy 11.230327 -318.811646) (xy 11.223244 -318.817244) (xy 11.223244 -318.817498) (xy 11.22299 -318.817498)
			(xy 11.202072 -318.835155) (xy 11.156096 -318.864864) (xy 11.106344 -318.887697) (xy 11.053841 -318.903184)
			(xy 10.999662 -318.911007) (xy 10.972292 -318.911478) (xy 10.945038 -318.911052) (xy 10.891084 -318.903293)
			(xy 10.838783 -318.887935) (xy 10.789201 -318.865289) (xy 10.743347 -318.835817) (xy 10.702153 -318.80012)
			(xy 10.66646 -318.758923) (xy 10.636993 -318.713065) (xy 10.614352 -318.663481) (xy 10.598999 -318.611179)
			(xy 10.591245 -318.557224) (xy 10.590784 -318.52997) (xy 0.529844 -318.52997) (xy 0.529844 -323.153278)
			(xy 14.462504 -323.153278) (xy 14.466575 -323.097656) (xy 14.478701 -323.043219) (xy 14.498624 -322.991128)
			(xy 14.52592 -322.942493) (xy 14.560006 -322.89835) (xy 14.600155 -322.859641) (xy 14.645513 -322.82719)
			(xy 14.695113 -322.801689) (xy 14.747897 -322.783682) (xy 14.80274 -322.773552) (xy 14.858474 -322.771515)
			(xy 14.913911 -322.777615) (xy 14.967868 -322.791721) (xy 15.019197 -322.813533) (xy 15.066803 -322.842587)
			(xy 15.109671 -322.878262) (xy 15.146888 -322.919799) (xy 15.177661 -322.966312) (xy 15.201333 -323.016809)
			(xy 15.217401 -323.070216) (xy 15.225521 -323.125392) (xy 15.22603 -323.153278) (xy 15.225521 -323.181164)
			(xy 15.217401 -323.23634) (xy 15.201333 -323.289747) (xy 15.177661 -323.340244) (xy 15.146888 -323.386757)
			(xy 15.109671 -323.428294) (xy 15.066803 -323.463969) (xy 15.019197 -323.493023) (xy 14.967868 -323.514835)
			(xy 14.913911 -323.528941) (xy 14.858474 -323.535041) (xy 14.80274 -323.533004) (xy 14.747897 -323.522874)
			(xy 14.695113 -323.504867) (xy 14.645513 -323.479366) (xy 14.600155 -323.446915) (xy 14.560006 -323.408206)
			(xy 14.52592 -323.364063) (xy 14.498624 -323.315428) (xy 14.478701 -323.263337) (xy 14.466575 -323.2089)
			(xy 14.462504 -323.153278) (xy 0.529844 -323.153278) (xy 0.529844 -341.292688) (xy 11.713716 -341.292688)
			(xy 11.717787 -341.237066) (xy 11.729913 -341.182629) (xy 11.749836 -341.130538) (xy 11.777132 -341.081903)
			(xy 11.811218 -341.03776) (xy 11.851367 -340.999051) (xy 11.896725 -340.9666) (xy 11.946325 -340.941099)
			(xy 11.999109 -340.923092) (xy 12.053952 -340.912962) (xy 12.109686 -340.910925) (xy 12.165123 -340.917025)
			(xy 12.21908 -340.931131) (xy 12.270409 -340.952943) (xy 12.318015 -340.981997) (xy 12.360883 -341.017672)
			(xy 12.3981 -341.059209) (xy 12.428873 -341.105722) (xy 12.452545 -341.156219) (xy 12.468613 -341.209626)
			(xy 12.476733 -341.264802) (xy 12.477242 -341.292688) (xy 12.476733 -341.320574) (xy 12.468613 -341.37575)
			(xy 12.452545 -341.429157) (xy 12.428873 -341.479654) (xy 12.3981 -341.526167) (xy 12.360883 -341.567704)
			(xy 12.318015 -341.603379) (xy 12.270409 -341.632433) (xy 12.21908 -341.654245) (xy 12.165123 -341.668351)
			(xy 12.109686 -341.674451) (xy 12.053952 -341.672414) (xy 11.999109 -341.662284) (xy 11.946325 -341.644277)
			(xy 11.896725 -341.618776) (xy 11.851367 -341.586325) (xy 11.811218 -341.547616) (xy 11.777132 -341.503473)
			(xy 11.749836 -341.454838) (xy 11.729913 -341.402747) (xy 11.717787 -341.34831) (xy 11.713716 -341.292688)
			(xy 0.529844 -341.292688) (xy 0.529844 -342.466769) (xy 18.951172 -342.466769) (xy 18.951172 -342.412231)
			(xy 18.958934 -342.358247) (xy 18.974299 -342.305917) (xy 18.996956 -342.256307) (xy 19.026441 -342.210426)
			(xy 19.062157 -342.169208) (xy 19.103374 -342.133493) (xy 19.149255 -342.104007) (xy 19.198865 -342.08135)
			(xy 19.251195 -342.065985) (xy 19.305179 -342.058223) (xy 19.332448 -342.057736) (xy 20.196048 -342.057736)
			(xy 20.223319 -342.058203) (xy 20.277306 -342.065965) (xy 20.329638 -342.081331) (xy 20.379252 -342.103989)
			(xy 20.425135 -342.133476) (xy 20.466355 -342.169193) (xy 20.502073 -342.210413) (xy 20.53156 -342.256297)
			(xy 20.554218 -342.30591) (xy 20.569584 -342.358242) (xy 20.577347 -342.412229) (xy 20.577347 -342.466771)
			(xy 20.577347 -342.466772) (xy 22.0601 -342.466772) (xy 22.0601 -342.412228) (xy 22.067862 -342.358241)
			(xy 22.083229 -342.305907) (xy 22.105887 -342.256293) (xy 22.135375 -342.210409) (xy 22.171094 -342.169188)
			(xy 22.212315 -342.133471) (xy 22.2582 -342.103983) (xy 22.307815 -342.081326) (xy 22.360148 -342.06596)
			(xy 22.414136 -342.058199) (xy 22.441408 -342.057736) (xy 23.305008 -342.057736) (xy 23.332277 -342.058227)
			(xy 23.386259 -342.06599) (xy 23.438588 -342.081355) (xy 23.488197 -342.104012) (xy 23.534076 -342.133498)
			(xy 23.575293 -342.169213) (xy 23.611007 -342.21043) (xy 23.640492 -342.256311) (xy 23.663147 -342.30592)
			(xy 23.678512 -342.358249) (xy 23.686274 -342.412231) (xy 23.686274 -342.466768) (xy 25.169122 -342.466768)
			(xy 25.169122 -342.412232) (xy 25.176883 -342.358251) (xy 25.192247 -342.305924) (xy 25.214901 -342.256315)
			(xy 25.244384 -342.210436) (xy 25.280096 -342.169219) (xy 25.32131 -342.133503) (xy 25.367187 -342.104016)
			(xy 25.416794 -342.081358) (xy 25.46912 -342.06599) (xy 25.5231 -342.058225) (xy 25.550368 -342.057736)
			(xy 26.413968 -342.057736) (xy 26.44124 -342.058201) (xy 26.49523 -342.06596) (xy 26.547567 -342.081323)
			(xy 26.597184 -342.103979) (xy 26.643071 -342.133465) (xy 26.684295 -342.169183) (xy 26.720015 -342.210403)
			(xy 26.749506 -342.256288) (xy 26.772166 -342.305903) (xy 26.787533 -342.358238) (xy 26.795296 -342.412228)
			(xy 26.795296 -342.466772) (xy 28.278 -342.466772) (xy 28.278 -342.412228) (xy 28.285762 -342.358238)
			(xy 28.30113 -342.305903) (xy 28.32379 -342.256288) (xy 28.35328 -342.210402) (xy 28.389001 -342.169181)
			(xy 28.430225 -342.133464) (xy 28.476112 -342.103977) (xy 28.525729 -342.08132) (xy 28.578065 -342.065957)
			(xy 28.632056 -342.058198) (xy 28.659328 -342.057736) (xy 29.522928 -342.057736) (xy 29.550196 -342.058228)
			(xy 29.604176 -342.065993) (xy 29.656502 -342.081361) (xy 29.706109 -342.104019) (xy 29.751986 -342.133505)
			(xy 29.7932 -342.16922) (xy 29.828912 -342.210437) (xy 29.858395 -342.256316) (xy 29.881049 -342.305924)
			(xy 29.896413 -342.358251) (xy 29.904174 -342.412232) (xy 29.904174 -342.466768) (xy 29.904174 -342.466769)
			(xy 31.387022 -342.466769) (xy 31.387022 -342.412231) (xy 31.394784 -342.358248) (xy 31.410149 -342.305919)
			(xy 31.432804 -342.25631) (xy 31.462289 -342.210429) (xy 31.498003 -342.169212) (xy 31.53922 -342.133496)
			(xy 31.585099 -342.10401) (xy 31.634708 -342.081353) (xy 31.687036 -342.065986) (xy 31.741019 -342.058223)
			(xy 31.768288 -342.057736) (xy 32.631888 -342.057736) (xy 32.659159 -342.058203) (xy 32.713147 -342.065963)
			(xy 32.765481 -342.081329) (xy 32.815096 -342.103985) (xy 32.86098 -342.133472) (xy 32.902202 -342.16919)
			(xy 32.93792 -342.21041) (xy 32.967409 -342.256294) (xy 32.990067 -342.305908) (xy 33.005434 -342.358241)
			(xy 33.013196 -342.412229) (xy 33.013196 -342.466771) (xy 33.013196 -342.466773) (xy 34.4959 -342.466773)
			(xy 34.4959 -342.412227) (xy 34.503663 -342.358235) (xy 34.519032 -342.305899) (xy 34.541693 -342.256282)
			(xy 34.571185 -342.210396) (xy 34.606908 -342.169174) (xy 34.648134 -342.133456) (xy 34.694024 -342.10397)
			(xy 34.743644 -342.081315) (xy 34.795982 -342.065953) (xy 34.849975 -342.058196) (xy 34.877248 -342.057736)
			(xy 35.740848 -342.057736) (xy 35.768115 -342.05823) (xy 35.822093 -342.065997) (xy 35.874417 -342.081366)
			(xy 35.92402 -342.104025) (xy 35.969895 -342.133512) (xy 36.011107 -342.169227) (xy 36.046817 -342.210443)
			(xy 36.076298 -342.256322) (xy 36.098951 -342.305928) (xy 36.114313 -342.358254) (xy 36.122074 -342.412233)
			(xy 36.122074 -342.466767) (xy 36.122073 -342.466772) (xy 37.6049 -342.466772) (xy 37.6049 -342.412228)
			(xy 37.612662 -342.358241) (xy 37.628029 -342.305907) (xy 37.650687 -342.256293) (xy 37.680175 -342.210409)
			(xy 37.715894 -342.169188) (xy 37.757115 -342.133471) (xy 37.803 -342.103983) (xy 37.852615 -342.081326)
			(xy 37.904948 -342.06596) (xy 37.958936 -342.058199) (xy 37.986208 -342.057736) (xy 38.849808 -342.057736)
			(xy 38.877077 -342.058227) (xy 38.931059 -342.06599) (xy 38.983388 -342.081355) (xy 39.032997 -342.104012)
			(xy 39.078876 -342.133498) (xy 39.120093 -342.169213) (xy 39.155807 -342.21043) (xy 39.185292 -342.256311)
			(xy 39.207947 -342.30592) (xy 39.223312 -342.358249) (xy 39.231074 -342.412231) (xy 39.231074 -342.466768)
			(xy 40.713922 -342.466768) (xy 40.713922 -342.412232) (xy 40.721683 -342.358251) (xy 40.737047 -342.305924)
			(xy 40.759701 -342.256315) (xy 40.789184 -342.210436) (xy 40.824896 -342.169219) (xy 40.86611 -342.133503)
			(xy 40.911987 -342.104016) (xy 40.961594 -342.081358) (xy 41.01392 -342.06599) (xy 41.0679 -342.058225)
			(xy 41.095168 -342.057736) (xy 41.958768 -342.057736) (xy 41.98604 -342.058201) (xy 42.04003 -342.06596)
			(xy 42.092367 -342.081323) (xy 42.141984 -342.103979) (xy 42.187871 -342.133465) (xy 42.229095 -342.169183)
			(xy 42.264815 -342.210403) (xy 42.294306 -342.256288) (xy 42.316966 -342.305903) (xy 42.332333 -342.358238)
			(xy 42.340096 -342.412228) (xy 42.340096 -342.466772) (xy 43.8228 -342.466772) (xy 43.8228 -342.412228)
			(xy 43.830562 -342.358238) (xy 43.84593 -342.305903) (xy 43.86859 -342.256288) (xy 43.89808 -342.210402)
			(xy 43.933801 -342.169181) (xy 43.975025 -342.133464) (xy 44.020912 -342.103977) (xy 44.070529 -342.08132)
			(xy 44.122865 -342.065957) (xy 44.176856 -342.058198) (xy 44.204128 -342.057736) (xy 45.067728 -342.057736)
			(xy 45.094996 -342.058228) (xy 45.148976 -342.065993) (xy 45.201302 -342.081361) (xy 45.250909 -342.104019)
			(xy 45.296786 -342.133505) (xy 45.338 -342.16922) (xy 45.373712 -342.210437) (xy 45.403195 -342.256316)
			(xy 45.425849 -342.305924) (xy 45.441213 -342.358251) (xy 45.448974 -342.412232) (xy 45.448974 -342.466768)
			(xy 45.448974 -342.466769) (xy 46.931822 -342.466769) (xy 46.931822 -342.412231) (xy 46.939584 -342.358248)
			(xy 46.954949 -342.305919) (xy 46.977604 -342.25631) (xy 47.007089 -342.210429) (xy 47.042803 -342.169212)
			(xy 47.08402 -342.133496) (xy 47.129899 -342.10401) (xy 47.179508 -342.081353) (xy 47.231836 -342.065986)
			(xy 47.285819 -342.058223) (xy 47.313088 -342.057736) (xy 48.176688 -342.057736) (xy 48.203959 -342.058203)
			(xy 48.257947 -342.065963) (xy 48.310281 -342.081329) (xy 48.359896 -342.103985) (xy 48.40578 -342.133472)
			(xy 48.447002 -342.16919) (xy 48.48272 -342.21041) (xy 48.512209 -342.256294) (xy 48.534867 -342.305908)
			(xy 48.550234 -342.358241) (xy 48.557996 -342.412229) (xy 48.557996 -342.466771) (xy 48.550234 -342.520759)
			(xy 48.534867 -342.573092) (xy 48.512209 -342.622706) (xy 48.48272 -342.66859) (xy 48.447002 -342.70981)
			(xy 48.40578 -342.745528) (xy 48.359896 -342.775015) (xy 48.310281 -342.797671) (xy 48.257947 -342.813037)
			(xy 48.203959 -342.820797) (xy 48.176688 -342.82126) (xy 47.313088 -342.82126) (xy 47.285819 -342.820777)
			(xy 47.231836 -342.813014) (xy 47.179508 -342.797647) (xy 47.129899 -342.77499) (xy 47.08402 -342.745504)
			(xy 47.042803 -342.709788) (xy 47.007089 -342.668571) (xy 46.977604 -342.62269) (xy 46.954949 -342.573081)
			(xy 46.939584 -342.520752) (xy 46.931822 -342.466769) (xy 45.448974 -342.466769) (xy 45.441213 -342.520749)
			(xy 45.425849 -342.573076) (xy 45.403195 -342.622684) (xy 45.373712 -342.668563) (xy 45.338 -342.70978)
			(xy 45.296786 -342.745495) (xy 45.250909 -342.774981) (xy 45.201302 -342.797639) (xy 45.148976 -342.813007)
			(xy 45.094996 -342.820772) (xy 45.067728 -342.82126) (xy 44.204128 -342.82126) (xy 44.176856 -342.820802)
			(xy 44.122865 -342.813043) (xy 44.070529 -342.79768) (xy 44.020912 -342.775023) (xy 43.975025 -342.745536)
			(xy 43.933801 -342.709819) (xy 43.89808 -342.668598) (xy 43.86859 -342.622712) (xy 43.84593 -342.573097)
			(xy 43.830562 -342.520762) (xy 43.8228 -342.466772) (xy 42.340096 -342.466772) (xy 42.332333 -342.520762)
			(xy 42.316966 -342.573097) (xy 42.294306 -342.622712) (xy 42.264815 -342.668597) (xy 42.229095 -342.709817)
			(xy 42.187871 -342.745535) (xy 42.141984 -342.775021) (xy 42.092367 -342.797677) (xy 42.04003 -342.81304)
			(xy 41.98604 -342.820799) (xy 41.958768 -342.82126) (xy 41.095168 -342.82126) (xy 41.0679 -342.820775)
			(xy 41.01392 -342.81301) (xy 40.961594 -342.797642) (xy 40.911987 -342.774984) (xy 40.86611 -342.745497)
			(xy 40.824896 -342.709781) (xy 40.789184 -342.668564) (xy 40.759701 -342.622685) (xy 40.737047 -342.573076)
			(xy 40.721683 -342.520749) (xy 40.713922 -342.466768) (xy 39.231074 -342.466768) (xy 39.231074 -342.466769)
			(xy 39.223312 -342.520751) (xy 39.207947 -342.57308) (xy 39.185292 -342.622689) (xy 39.155807 -342.66857)
			(xy 39.120093 -342.709787) (xy 39.078876 -342.745502) (xy 39.032997 -342.774988) (xy 38.983388 -342.797645)
			(xy 38.931059 -342.81301) (xy 38.877077 -342.820773) (xy 38.849808 -342.82126) (xy 37.986208 -342.82126)
			(xy 37.958936 -342.820801) (xy 37.904948 -342.81304) (xy 37.852615 -342.797674) (xy 37.803 -342.775017)
			(xy 37.757115 -342.745529) (xy 37.715894 -342.709812) (xy 37.680175 -342.668591) (xy 37.650687 -342.622707)
			(xy 37.628029 -342.573093) (xy 37.612662 -342.520759) (xy 37.6049 -342.466772) (xy 36.122073 -342.466772)
			(xy 36.114313 -342.520746) (xy 36.098951 -342.573072) (xy 36.076298 -342.622678) (xy 36.046817 -342.668557)
			(xy 36.011107 -342.709773) (xy 35.969895 -342.745488) (xy 35.92402 -342.774975) (xy 35.874417 -342.797634)
			(xy 35.822093 -342.813003) (xy 35.768115 -342.82077) (xy 35.740848 -342.82126) (xy 34.877248 -342.82126)
			(xy 34.849975 -342.820804) (xy 34.795982 -342.813047) (xy 34.743644 -342.797685) (xy 34.694024 -342.77503)
			(xy 34.648134 -342.745544) (xy 34.606908 -342.709826) (xy 34.571185 -342.668604) (xy 34.541693 -342.622718)
			(xy 34.519032 -342.573101) (xy 34.503663 -342.520765) (xy 34.4959 -342.466773) (xy 33.013196 -342.466773)
			(xy 33.005434 -342.520759) (xy 32.990067 -342.573092) (xy 32.967409 -342.622706) (xy 32.93792 -342.66859)
			(xy 32.902202 -342.70981) (xy 32.86098 -342.745528) (xy 32.815096 -342.775015) (xy 32.765481 -342.797671)
			(xy 32.713147 -342.813037) (xy 32.659159 -342.820797) (xy 32.631888 -342.82126) (xy 31.768288 -342.82126)
			(xy 31.741019 -342.820777) (xy 31.687036 -342.813014) (xy 31.634708 -342.797647) (xy 31.585099 -342.77499)
			(xy 31.53922 -342.745504) (xy 31.498003 -342.709788) (xy 31.462289 -342.668571) (xy 31.432804 -342.62269)
			(xy 31.410149 -342.573081) (xy 31.394784 -342.520752) (xy 31.387022 -342.466769) (xy 29.904174 -342.466769)
			(xy 29.896413 -342.520749) (xy 29.881049 -342.573076) (xy 29.858395 -342.622684) (xy 29.828912 -342.668563)
			(xy 29.7932 -342.70978) (xy 29.751986 -342.745495) (xy 29.706109 -342.774981) (xy 29.656502 -342.797639)
			(xy 29.604176 -342.813007) (xy 29.550196 -342.820772) (xy 29.522928 -342.82126) (xy 28.659328 -342.82126)
			(xy 28.632056 -342.820802) (xy 28.578065 -342.813043) (xy 28.525729 -342.79768) (xy 28.476112 -342.775023)
			(xy 28.430225 -342.745536) (xy 28.389001 -342.709819) (xy 28.35328 -342.668598) (xy 28.32379 -342.622712)
			(xy 28.30113 -342.573097) (xy 28.285762 -342.520762) (xy 28.278 -342.466772) (xy 26.795296 -342.466772)
			(xy 26.787533 -342.520762) (xy 26.772166 -342.573097) (xy 26.749506 -342.622712) (xy 26.720015 -342.668597)
			(xy 26.684295 -342.709817) (xy 26.643071 -342.745535) (xy 26.597184 -342.775021) (xy 26.547567 -342.797677)
			(xy 26.49523 -342.81304) (xy 26.44124 -342.820799) (xy 26.413968 -342.82126) (xy 25.550368 -342.82126)
			(xy 25.5231 -342.820775) (xy 25.46912 -342.81301) (xy 25.416794 -342.797642) (xy 25.367187 -342.774984)
			(xy 25.32131 -342.745497) (xy 25.280096 -342.709781) (xy 25.244384 -342.668564) (xy 25.214901 -342.622685)
			(xy 25.192247 -342.573076) (xy 25.176883 -342.520749) (xy 25.169122 -342.466768) (xy 23.686274 -342.466768)
			(xy 23.686274 -342.466769) (xy 23.678512 -342.520751) (xy 23.663147 -342.57308) (xy 23.640492 -342.622689)
			(xy 23.611007 -342.66857) (xy 23.575293 -342.709787) (xy 23.534076 -342.745502) (xy 23.488197 -342.774988)
			(xy 23.438588 -342.797645) (xy 23.386259 -342.81301) (xy 23.332277 -342.820773) (xy 23.305008 -342.82126)
			(xy 22.441408 -342.82126) (xy 22.414136 -342.820801) (xy 22.360148 -342.81304) (xy 22.307815 -342.797674)
			(xy 22.2582 -342.775017) (xy 22.212315 -342.745529) (xy 22.171094 -342.709812) (xy 22.135375 -342.668591)
			(xy 22.105887 -342.622707) (xy 22.083229 -342.573093) (xy 22.067862 -342.520759) (xy 22.0601 -342.466772)
			(xy 20.577347 -342.466772) (xy 20.569584 -342.520758) (xy 20.554218 -342.57309) (xy 20.53156 -342.622703)
			(xy 20.502073 -342.668587) (xy 20.466355 -342.709807) (xy 20.425135 -342.745524) (xy 20.379252 -342.775011)
			(xy 20.329638 -342.797669) (xy 20.277306 -342.813035) (xy 20.223319 -342.820797) (xy 20.196048 -342.82126)
			(xy 19.332448 -342.82126) (xy 19.305179 -342.820777) (xy 19.251195 -342.813015) (xy 19.198865 -342.79765)
			(xy 19.149255 -342.774993) (xy 19.103374 -342.745507) (xy 19.062157 -342.709792) (xy 19.026441 -342.668574)
			(xy 18.996956 -342.622693) (xy 18.974299 -342.573083) (xy 18.958934 -342.520753) (xy 18.951172 -342.466769)
			(xy 0.529844 -342.466769) (xy 0.529844 -345.49242) (xy 18.95117 -345.49242) (xy 18.95117 -345.43788)
			(xy 18.958932 -345.383896) (xy 18.974298 -345.331567) (xy 18.996954 -345.281956) (xy 19.02644 -345.236075)
			(xy 19.062155 -345.194857) (xy 19.103373 -345.159141) (xy 19.149254 -345.129655) (xy 19.198865 -345.106998)
			(xy 19.251194 -345.091633) (xy 19.305178 -345.083871) (xy 19.332448 -345.083384) (xy 20.196048 -345.083384)
			(xy 20.223319 -345.083855) (xy 20.277305 -345.091617) (xy 20.329638 -345.106983) (xy 20.379251 -345.12964)
			(xy 20.425134 -345.159128) (xy 20.466354 -345.194845) (xy 20.502071 -345.236064) (xy 20.531559 -345.281948)
			(xy 20.554216 -345.33156) (xy 20.569582 -345.383893) (xy 20.577345 -345.437879) (xy 20.577345 -345.49242)
			(xy 22.06013 -345.49242) (xy 22.06013 -345.43788) (xy 22.067892 -345.383896) (xy 22.083258 -345.331567)
			(xy 22.105914 -345.281956) (xy 22.1354 -345.236075) (xy 22.171115 -345.194857) (xy 22.212333 -345.159141)
			(xy 22.258214 -345.129655) (xy 22.307825 -345.106998) (xy 22.360154 -345.091633) (xy 22.414138 -345.083871)
			(xy 22.441408 -345.083384) (xy 23.305008 -345.083384) (xy 23.332279 -345.083855) (xy 23.386265 -345.091617)
			(xy 23.438598 -345.106983) (xy 23.488211 -345.12964) (xy 23.534094 -345.159128) (xy 23.575314 -345.194845)
			(xy 23.611031 -345.236064) (xy 23.640519 -345.281948) (xy 23.663176 -345.33156) (xy 23.678542 -345.383893)
			(xy 23.686305 -345.437879) (xy 23.686305 -345.492365) (xy 25.16917 -345.492365) (xy 25.16917 -345.437835)
			(xy 25.17693 -345.383861) (xy 25.192292 -345.33154) (xy 25.214943 -345.281938) (xy 25.244422 -345.236064)
			(xy 25.28013 -345.194853) (xy 25.321339 -345.159142) (xy 25.36721 -345.129658) (xy 25.41681 -345.107003)
			(xy 25.46913 -345.091637) (xy 25.523103 -345.083872) (xy 25.550368 -345.083384) (xy 26.413968 -345.083384)
			(xy 26.441244 -345.083753) (xy 26.495241 -345.091513) (xy 26.547583 -345.106878) (xy 26.597207 -345.129537)
			(xy 26.6431 -345.159027) (xy 26.684329 -345.194749) (xy 26.720054 -345.235975) (xy 26.749548 -345.281865)
			(xy 26.772211 -345.331487) (xy 26.78758 -345.383828) (xy 26.795344 -345.437824) (xy 26.795344 -345.492369)
			(xy 28.278047 -345.492369) (xy 28.278047 -345.437831) (xy 28.285809 -345.383848) (xy 28.301175 -345.33152)
			(xy 28.323832 -345.281911) (xy 28.353319 -345.236031) (xy 28.389035 -345.194815) (xy 28.430253 -345.159102)
			(xy 28.476135 -345.129619) (xy 28.525746 -345.106965) (xy 28.578076 -345.091603) (xy 28.632059 -345.083845)
			(xy 28.659328 -345.083384) (xy 29.522928 -345.083384) (xy 29.550199 -345.08378) (xy 29.604186 -345.091546)
			(xy 29.656519 -345.106916) (xy 29.706132 -345.129576) (xy 29.752014 -345.159067) (xy 29.793234 -345.194786)
			(xy 29.82895 -345.236008) (xy 29.858437 -345.281893) (xy 29.881094 -345.331507) (xy 29.89646 -345.383841)
			(xy 29.904222 -345.437829) (xy 29.904222 -345.492366) (xy 31.38707 -345.492366) (xy 31.38707 -345.437834)
			(xy 31.394831 -345.383858) (xy 31.410194 -345.331536) (xy 31.432846 -345.281933) (xy 31.462327 -345.236058)
			(xy 31.498037 -345.194846) (xy 31.539248 -345.159135) (xy 31.585122 -345.129652) (xy 31.634725 -345.106998)
			(xy 31.687047 -345.091633) (xy 31.741022 -345.083871) (xy 31.768288 -345.083384) (xy 32.631888 -345.083384)
			(xy 32.659163 -345.083755) (xy 32.713157 -345.091516) (xy 32.765498 -345.106884) (xy 32.815119 -345.129543)
			(xy 32.861009 -345.159034) (xy 32.902236 -345.194756) (xy 32.937959 -345.235981) (xy 32.967451 -345.281871)
			(xy 32.990112 -345.331491) (xy 33.005481 -345.383831) (xy 33.013244 -345.437825) (xy 33.013244 -345.49237)
			(xy 34.495948 -345.49237) (xy 34.495948 -345.43783) (xy 34.50371 -345.383846) (xy 34.519077 -345.331515)
			(xy 34.541735 -345.281905) (xy 34.571224 -345.236024) (xy 34.606942 -345.194808) (xy 34.648163 -345.159095)
			(xy 34.694047 -345.129612) (xy 34.74366 -345.10696) (xy 34.795992 -345.0916) (xy 34.849978 -345.083844)
			(xy 34.877248 -345.083384) (xy 35.740848 -345.083384) (xy 35.768118 -345.083782) (xy 35.822103 -345.09155)
			(xy 35.874433 -345.106921) (xy 35.924044 -345.129583) (xy 35.969924 -345.159074) (xy 36.011141 -345.194793)
			(xy 36.046855 -345.236015) (xy 36.07634 -345.281899) (xy 36.098995 -345.331512) (xy 36.11436 -345.383844)
			(xy 36.122122 -345.43783) (xy 36.122122 -345.492368) (xy 37.604947 -345.492368) (xy 37.604947 -345.437832)
			(xy 37.612709 -345.383851) (xy 37.628074 -345.331524) (xy 37.650729 -345.281916) (xy 37.680214 -345.236038)
			(xy 37.715928 -345.194822) (xy 37.757144 -345.159109) (xy 37.803023 -345.129625) (xy 37.852631 -345.106971)
			(xy 37.904959 -345.091607) (xy 37.95894 -345.083847) (xy 37.986208 -345.083384) (xy 38.849808 -345.083384)
			(xy 38.87708 -345.083779) (xy 38.93107 -345.091543) (xy 38.983404 -345.106911) (xy 39.03302 -345.12957)
			(xy 39.078905 -345.15906) (xy 39.120127 -345.194779) (xy 39.155845 -345.236001) (xy 39.185334 -345.281888)
			(xy 39.207992 -345.331503) (xy 39.223359 -345.383838) (xy 39.231121 -345.437828) (xy 39.231121 -345.492365)
			(xy 40.71397 -345.492365) (xy 40.71397 -345.437835) (xy 40.72173 -345.383861) (xy 40.737092 -345.33154)
			(xy 40.759743 -345.281938) (xy 40.789222 -345.236064) (xy 40.82493 -345.194853) (xy 40.866139 -345.159142)
			(xy 40.91201 -345.129658) (xy 40.96161 -345.107003) (xy 41.01393 -345.091637) (xy 41.067903 -345.083872)
			(xy 41.095168 -345.083384) (xy 41.958768 -345.083384) (xy 41.986044 -345.083753) (xy 42.040041 -345.091513)
			(xy 42.092383 -345.106878) (xy 42.142007 -345.129537) (xy 42.1879 -345.159027) (xy 42.229129 -345.194749)
			(xy 42.264854 -345.235975) (xy 42.294348 -345.281865) (xy 42.317011 -345.331487) (xy 42.33238 -345.383828)
			(xy 42.340144 -345.437824) (xy 42.340144 -345.492369) (xy 43.822847 -345.492369) (xy 43.822847 -345.437831)
			(xy 43.830609 -345.383848) (xy 43.845975 -345.33152) (xy 43.868632 -345.281911) (xy 43.898119 -345.236031)
			(xy 43.933835 -345.194815) (xy 43.975053 -345.159102) (xy 44.020935 -345.129619) (xy 44.070546 -345.106965)
			(xy 44.122876 -345.091603) (xy 44.176859 -345.083845) (xy 44.204128 -345.083384) (xy 45.067728 -345.083384)
			(xy 45.094999 -345.08378) (xy 45.148986 -345.091546) (xy 45.201319 -345.106916) (xy 45.250932 -345.129576)
			(xy 45.296814 -345.159067) (xy 45.338034 -345.194786) (xy 45.37375 -345.236008) (xy 45.403237 -345.281893)
			(xy 45.425894 -345.331507) (xy 45.44126 -345.383841) (xy 45.449022 -345.437829) (xy 45.449022 -345.492366)
			(xy 46.93187 -345.492366) (xy 46.93187 -345.437834) (xy 46.939631 -345.383858) (xy 46.954994 -345.331536)
			(xy 46.977646 -345.281933) (xy 47.007127 -345.236058) (xy 47.042837 -345.194846) (xy 47.084048 -345.159135)
			(xy 47.129922 -345.129652) (xy 47.179525 -345.106998) (xy 47.231847 -345.091633) (xy 47.285822 -345.083871)
			(xy 47.313088 -345.083384) (xy 48.176688 -345.083384) (xy 48.203963 -345.083755) (xy 48.257957 -345.091516)
			(xy 48.310298 -345.106884) (xy 48.359919 -345.129543) (xy 48.405809 -345.159034) (xy 48.447036 -345.194756)
			(xy 48.482759 -345.235981) (xy 48.512251 -345.281871) (xy 48.534912 -345.331491) (xy 48.550281 -345.383831)
			(xy 48.558044 -345.437825) (xy 48.558044 -345.49237) (xy 50.040748 -345.49237) (xy 50.040748 -345.43783)
			(xy 50.04851 -345.383846) (xy 50.063877 -345.331515) (xy 50.086535 -345.281905) (xy 50.116024 -345.236024)
			(xy 50.151742 -345.194808) (xy 50.192963 -345.159095) (xy 50.238847 -345.129612) (xy 50.28846 -345.10696)
			(xy 50.340792 -345.0916) (xy 50.394778 -345.083844) (xy 50.422048 -345.083384) (xy 51.285648 -345.083384)
			(xy 51.312918 -345.083782) (xy 51.366903 -345.09155) (xy 51.419233 -345.106921) (xy 51.468844 -345.129583)
			(xy 51.514724 -345.159074) (xy 51.555941 -345.194793) (xy 51.591655 -345.236015) (xy 51.62114 -345.281899)
			(xy 51.643795 -345.331512) (xy 51.65916 -345.383844) (xy 51.666922 -345.43783) (xy 51.666922 -345.49237)
			(xy 51.65916 -345.546356) (xy 51.643795 -345.598688) (xy 51.62114 -345.648301) (xy 51.591655 -345.694185)
			(xy 51.555941 -345.735407) (xy 51.514724 -345.771126) (xy 51.468843 -345.800617) (xy 51.419233 -345.823279)
			(xy 51.366903 -345.83865) (xy 51.312918 -345.846418) (xy 51.285648 -345.846908) (xy 50.422048 -345.846908)
			(xy 50.394778 -345.846356) (xy 50.340792 -345.8386) (xy 50.28846 -345.82324) (xy 50.238847 -345.800588)
			(xy 50.192963 -345.771105) (xy 50.151742 -345.735392) (xy 50.116024 -345.694176) (xy 50.086535 -345.648295)
			(xy 50.063877 -345.598685) (xy 50.04851 -345.546354) (xy 50.040748 -345.49237) (xy 48.558044 -345.49237)
			(xy 48.558044 -345.492375) (xy 48.550281 -345.546369) (xy 48.534912 -345.598709) (xy 48.512251 -345.648329)
			(xy 48.482759 -345.694219) (xy 48.447036 -345.735444) (xy 48.405809 -345.771166) (xy 48.359919 -345.800657)
			(xy 48.310298 -345.823316) (xy 48.257958 -345.838684) (xy 48.203963 -345.846445) (xy 48.176688 -345.846908)
			(xy 47.313088 -345.846908) (xy 47.285822 -345.846329) (xy 47.231847 -345.838567) (xy 47.179525 -345.823202)
			(xy 47.129922 -345.800548) (xy 47.084048 -345.771065) (xy 47.042837 -345.735354) (xy 47.007127 -345.694142)
			(xy 46.977646 -345.648267) (xy 46.954994 -345.598664) (xy 46.939631 -345.546342) (xy 46.93187 -345.492366)
			(xy 45.449022 -345.492366) (xy 45.449022 -345.492371) (xy 45.44126 -345.546359) (xy 45.425894 -345.598693)
			(xy 45.403237 -345.648307) (xy 45.37375 -345.694192) (xy 45.338034 -345.735414) (xy 45.296814 -345.771133)
			(xy 45.250932 -345.800624) (xy 45.201319 -345.823284) (xy 45.148986 -345.838654) (xy 45.094999 -345.84642)
			(xy 45.067728 -345.846908) (xy 44.204128 -345.846908) (xy 44.176859 -345.846355) (xy 44.122876 -345.838597)
			(xy 44.070546 -345.823235) (xy 44.020935 -345.800581) (xy 43.975053 -345.771098) (xy 43.933835 -345.735385)
			(xy 43.898119 -345.694169) (xy 43.868632 -345.648289) (xy 43.845975 -345.59868) (xy 43.830609 -345.546352)
			(xy 43.822847 -345.492369) (xy 42.340144 -345.492369) (xy 42.340144 -345.492376) (xy 42.33238 -345.546372)
			(xy 42.317011 -345.598713) (xy 42.294348 -345.648335) (xy 42.264854 -345.694225) (xy 42.229129 -345.735451)
			(xy 42.1879 -345.771173) (xy 42.142007 -345.800663) (xy 42.092383 -345.823322) (xy 42.040041 -345.838687)
			(xy 41.986044 -345.846447) (xy 41.958768 -345.846908) (xy 41.095168 -345.846908) (xy 41.067903 -345.846328)
			(xy 41.01393 -345.838563) (xy 40.96161 -345.823197) (xy 40.91201 -345.800542) (xy 40.866139 -345.771058)
			(xy 40.82493 -345.735347) (xy 40.789222 -345.694136) (xy 40.759743 -345.648262) (xy 40.737092 -345.59866)
			(xy 40.72173 -345.546339) (xy 40.71397 -345.492365) (xy 39.231121 -345.492365) (xy 39.231121 -345.492372)
			(xy 39.223359 -345.546362) (xy 39.207992 -345.598697) (xy 39.185334 -345.648312) (xy 39.155845 -345.694199)
			(xy 39.120127 -345.735421) (xy 39.078905 -345.77114) (xy 39.03302 -345.80063) (xy 38.983404 -345.82329)
			(xy 38.93107 -345.838657) (xy 38.87708 -345.846421) (xy 38.849808 -345.846908) (xy 37.986208 -345.846908)
			(xy 37.95894 -345.846353) (xy 37.904959 -345.838593) (xy 37.852631 -345.823229) (xy 37.803023 -345.800575)
			(xy 37.757144 -345.771091) (xy 37.715928 -345.735378) (xy 37.680214 -345.694162) (xy 37.650729 -345.648284)
			(xy 37.628074 -345.598676) (xy 37.612709 -345.546349) (xy 37.604947 -345.492368) (xy 36.122122 -345.492368)
			(xy 36.122122 -345.49237) (xy 36.11436 -345.546356) (xy 36.098995 -345.598688) (xy 36.07634 -345.648301)
			(xy 36.046855 -345.694185) (xy 36.011141 -345.735407) (xy 35.969924 -345.771126) (xy 35.924043 -345.800617)
			(xy 35.874433 -345.823279) (xy 35.822103 -345.83865) (xy 35.768118 -345.846418) (xy 35.740848 -345.846908)
			(xy 34.877248 -345.846908) (xy 34.849978 -345.846356) (xy 34.795992 -345.8386) (xy 34.74366 -345.82324)
			(xy 34.694047 -345.800588) (xy 34.648163 -345.771105) (xy 34.606942 -345.735392) (xy 34.571224 -345.694176)
			(xy 34.541735 -345.648295) (xy 34.519077 -345.598685) (xy 34.50371 -345.546354) (xy 34.495948 -345.49237)
			(xy 33.013244 -345.49237) (xy 33.013244 -345.492375) (xy 33.005481 -345.546369) (xy 32.990112 -345.598709)
			(xy 32.967451 -345.648329) (xy 32.937959 -345.694219) (xy 32.902236 -345.735444) (xy 32.861009 -345.771166)
			(xy 32.815119 -345.800657) (xy 32.765498 -345.823316) (xy 32.713158 -345.838684) (xy 32.659163 -345.846445)
			(xy 32.631888 -345.846908) (xy 31.768288 -345.846908) (xy 31.741022 -345.846329) (xy 31.687047 -345.838567)
			(xy 31.634725 -345.823202) (xy 31.585122 -345.800548) (xy 31.539248 -345.771065) (xy 31.498037 -345.735354)
			(xy 31.462327 -345.694142) (xy 31.432846 -345.648267) (xy 31.410194 -345.598664) (xy 31.394831 -345.546342)
			(xy 31.38707 -345.492366) (xy 29.904222 -345.492366) (xy 29.904222 -345.492371) (xy 29.89646 -345.546359)
			(xy 29.881094 -345.598693) (xy 29.858437 -345.648307) (xy 29.82895 -345.694192) (xy 29.793234 -345.735414)
			(xy 29.752014 -345.771133) (xy 29.706132 -345.800624) (xy 29.656519 -345.823284) (xy 29.604186 -345.838654)
			(xy 29.550199 -345.84642) (xy 29.522928 -345.846908) (xy 28.659328 -345.846908) (xy 28.632059 -345.846355)
			(xy 28.578076 -345.838597) (xy 28.525746 -345.823235) (xy 28.476135 -345.800581) (xy 28.430253 -345.771098)
			(xy 28.389035 -345.735385) (xy 28.353319 -345.694169) (xy 28.323832 -345.648289) (xy 28.301175 -345.59868)
			(xy 28.285809 -345.546352) (xy 28.278047 -345.492369) (xy 26.795344 -345.492369) (xy 26.795344 -345.492376)
			(xy 26.78758 -345.546372) (xy 26.772211 -345.598713) (xy 26.749548 -345.648335) (xy 26.720054 -345.694225)
			(xy 26.684329 -345.735451) (xy 26.6431 -345.771173) (xy 26.597207 -345.800663) (xy 26.547583 -345.823322)
			(xy 26.495241 -345.838687) (xy 26.441244 -345.846447) (xy 26.413968 -345.846908) (xy 25.550368 -345.846908)
			(xy 25.523103 -345.846328) (xy 25.46913 -345.838563) (xy 25.41681 -345.823197) (xy 25.36721 -345.800542)
			(xy 25.321339 -345.771058) (xy 25.28013 -345.735347) (xy 25.244422 -345.694136) (xy 25.214943 -345.648262)
			(xy 25.192292 -345.59866) (xy 25.17693 -345.546339) (xy 25.16917 -345.492365) (xy 23.686305 -345.492365)
			(xy 23.686305 -345.492421) (xy 23.678542 -345.546407) (xy 23.663176 -345.59874) (xy 23.640519 -345.648352)
			(xy 23.611031 -345.694236) (xy 23.575314 -345.735455) (xy 23.534094 -345.771172) (xy 23.488211 -345.80066)
			(xy 23.438598 -345.823317) (xy 23.386265 -345.838683) (xy 23.332279 -345.846445) (xy 23.305008 -345.846908)
			(xy 22.441408 -345.846908) (xy 22.414138 -345.846429) (xy 22.360154 -345.838667) (xy 22.307825 -345.823302)
			(xy 22.258214 -345.800645) (xy 22.212333 -345.771159) (xy 22.171115 -345.735443) (xy 22.1354 -345.694225)
			(xy 22.105914 -345.648344) (xy 22.083258 -345.598733) (xy 22.067892 -345.546404) (xy 22.06013 -345.49242)
			(xy 20.577345 -345.49242) (xy 20.577345 -345.492421) (xy 20.569582 -345.546407) (xy 20.554216 -345.59874)
			(xy 20.531559 -345.648352) (xy 20.502071 -345.694236) (xy 20.466354 -345.735455) (xy 20.425134 -345.771172)
			(xy 20.379251 -345.80066) (xy 20.329638 -345.823317) (xy 20.277305 -345.838683) (xy 20.223319 -345.846445)
			(xy 20.196048 -345.846908) (xy 19.332448 -345.846908) (xy 19.305178 -345.846429) (xy 19.251194 -345.838667)
			(xy 19.198865 -345.823302) (xy 19.149254 -345.800645) (xy 19.103373 -345.771159) (xy 19.062155 -345.735443)
			(xy 19.02644 -345.694225) (xy 18.996954 -345.648344) (xy 18.974298 -345.598733) (xy 18.958932 -345.546404)
			(xy 18.95117 -345.49242) (xy 0.529844 -345.49242) (xy 0.529844 -348.976496) (xy 4.708641 -348.976496)
			(xy 4.708641 -348.847356) (xy 4.716591 -348.718461) (xy 4.732461 -348.590301) (xy 4.75619 -348.46336)
			(xy 4.787689 -348.338121) (xy 4.826838 -348.215058) (xy 4.873489 -348.094639) (xy 4.927464 -347.97732)
			(xy 4.988559 -347.863546) (xy 5.056542 -347.753749) (xy 5.131156 -347.648346) (xy 5.212117 -347.547736)
			(xy 5.299117 -347.452301) (xy 5.391828 -347.362402) (xy 5.489898 -347.278381) (xy 5.592953 -347.200557)
			(xy 5.700604 -347.129225) (xy 5.812443 -347.064655) (xy 5.928044 -347.007093) (xy 6.046969 -346.956756)
			(xy 6.168768 -346.913836) (xy 6.292978 -346.878495) (xy 6.419127 -346.850868) (xy 6.546739 -346.831059)
			(xy 6.675328 -346.819143) (xy 6.804406 -346.815167) (xy 6.933484 -346.819143) (xy 7.062073 -346.831059)
			(xy 7.189685 -346.850868) (xy 7.315834 -346.878495) (xy 7.440044 -346.913836) (xy 7.561843 -346.956756)
			(xy 7.680768 -347.007093) (xy 7.796369 -347.064655) (xy 7.908208 -347.129225) (xy 8.015859 -347.200557)
			(xy 8.118914 -347.278381) (xy 8.216984 -347.362402) (xy 8.309695 -347.452301) (xy 8.396695 -347.547736)
			(xy 8.477656 -347.648346) (xy 8.55227 -347.753749) (xy 8.620253 -347.863546) (xy 8.681348 -347.97732)
			(xy 8.735323 -348.094639) (xy 8.781974 -348.215058) (xy 8.821123 -348.338121) (xy 8.852622 -348.46336)
			(xy 8.876351 -348.590301) (xy 8.879169 -348.613059) (xy 18.951174 -348.613059) (xy 18.951174 -348.558521)
			(xy 18.958936 -348.504537) (xy 18.974301 -348.452208) (xy 18.996957 -348.402598) (xy 19.026443 -348.356717)
			(xy 19.062158 -348.315499) (xy 19.103375 -348.279784) (xy 19.149256 -348.250298) (xy 19.198866 -348.227642)
			(xy 19.251195 -348.212276) (xy 19.305179 -348.204515) (xy 19.332448 -348.204028) (xy 20.196048 -348.204028)
			(xy 20.223319 -348.204491) (xy 20.277306 -348.212253) (xy 20.329639 -348.227619) (xy 20.379253 -348.250277)
			(xy 20.425136 -348.279764) (xy 20.466357 -348.315482) (xy 20.502074 -348.356702) (xy 20.531562 -348.402586)
			(xy 20.55422 -348.452199) (xy 20.569586 -348.504532) (xy 20.577349 -348.558519) (xy 20.577349 -348.613061)
			(xy 20.577347 -348.613072) (xy 22.060092 -348.613072) (xy 22.060092 -348.558528) (xy 22.067854 -348.504539)
			(xy 22.083221 -348.452204) (xy 22.10588 -348.402589) (xy 22.135369 -348.356704) (xy 22.171088 -348.315483)
			(xy 22.21231 -348.279764) (xy 22.258196 -348.250276) (xy 22.307812 -348.227618) (xy 22.360147 -348.212252)
			(xy 22.414136 -348.204491) (xy 22.441408 -348.204028) (xy 23.305008 -348.204028) (xy 23.332276 -348.204535)
			(xy 23.386258 -348.212297) (xy 23.438585 -348.227663) (xy 23.488193 -348.250319) (xy 23.534071 -348.279804)
			(xy 23.575287 -348.315519) (xy 23.611 -348.356735) (xy 23.640485 -348.402614) (xy 23.66314 -348.452223)
			(xy 23.678504 -348.50455) (xy 23.686266 -348.558532) (xy 23.686266 -348.613068) (xy 23.686266 -348.613069)
			(xy 25.169114 -348.613069) (xy 25.169114 -348.558531) (xy 25.176875 -348.504549) (xy 25.19224 -348.452221)
			(xy 25.214894 -348.402611) (xy 25.244378 -348.356731) (xy 25.28009 -348.315513) (xy 25.321305 -348.279797)
			(xy 25.367183 -348.250309) (xy 25.416791 -348.227651) (xy 25.469118 -348.212282) (xy 25.523099 -348.204517)
			(xy 25.550368 -348.204028) (xy 26.413968 -348.204028) (xy 26.44124 -348.204509) (xy 26.495229 -348.212268)
			(xy 26.547564 -348.227631) (xy 26.59718 -348.250286) (xy 26.643066 -348.279772) (xy 26.684289 -348.315488)
			(xy 26.720009 -348.356708) (xy 26.749499 -348.402592) (xy 26.772158 -348.452206) (xy 26.787526 -348.50454)
			(xy 26.795288 -348.558528) (xy 26.795288 -348.613072) (xy 26.795288 -348.613073) (xy 28.277992 -348.613073)
			(xy 28.277992 -348.558527) (xy 28.285755 -348.504536) (xy 28.301123 -348.4522) (xy 28.323783 -348.402584)
			(xy 28.353274 -348.356697) (xy 28.388995 -348.315476) (xy 28.43022 -348.279757) (xy 28.476108 -348.25027)
			(xy 28.525726 -348.227613) (xy 28.578064 -348.212249) (xy 28.632055 -348.20449) (xy 28.659328 -348.204028)
			(xy 29.522928 -348.204028) (xy 29.550195 -348.204536) (xy 29.604175 -348.212301) (xy 29.656499 -348.227668)
			(xy 29.706105 -348.250326) (xy 29.751981 -348.279811) (xy 29.793194 -348.315526) (xy 29.828905 -348.356742)
			(xy 29.858388 -348.40262) (xy 29.881041 -348.452227) (xy 29.896405 -348.504553) (xy 29.904166 -348.558533)
			(xy 29.904166 -348.613067) (xy 29.904166 -348.61307) (xy 31.387014 -348.61307) (xy 31.387014 -348.55853)
			(xy 31.394776 -348.504546) (xy 31.410141 -348.452217) (xy 31.432797 -348.402606) (xy 31.462283 -348.356724)
			(xy 31.497997 -348.315506) (xy 31.539215 -348.27979) (xy 31.585095 -348.250303) (xy 31.634705 -348.227645)
			(xy 31.687035 -348.212279) (xy 31.741018 -348.204515) (xy 31.768288 -348.204028) (xy 32.631888 -348.204028)
			(xy 32.659159 -348.204511) (xy 32.713146 -348.212271) (xy 32.765478 -348.227636) (xy 32.815092 -348.250292)
			(xy 32.860976 -348.279779) (xy 32.902196 -348.315495) (xy 32.937914 -348.356715) (xy 32.967402 -348.402598)
			(xy 32.99006 -348.45221) (xy 33.005426 -348.504543) (xy 33.013189 -348.558529) (xy 33.013189 -348.613071)
			(xy 33.013189 -348.613074) (xy 34.495892 -348.613074) (xy 34.495892 -348.558526) (xy 34.503655 -348.504534)
			(xy 34.519024 -348.452196) (xy 34.541686 -348.402578) (xy 34.571179 -348.356691) (xy 34.606902 -348.315468)
			(xy 34.648129 -348.27975) (xy 34.69402 -348.250263) (xy 34.743641 -348.227608) (xy 34.795981 -348.212245)
			(xy 34.849974 -348.204488) (xy 34.877248 -348.204028) (xy 35.740848 -348.204028) (xy 35.768114 -348.204538)
			(xy 35.822091 -348.212305) (xy 35.874414 -348.227674) (xy 35.924017 -348.250332) (xy 35.96989 -348.279819)
			(xy 36.011101 -348.315533) (xy 36.04681 -348.356748) (xy 36.076291 -348.402626) (xy 36.098943 -348.452231)
			(xy 36.114306 -348.504556) (xy 36.122066 -348.558534) (xy 36.122066 -348.613066) (xy 36.122065 -348.613072)
			(xy 37.604892 -348.613072) (xy 37.604892 -348.558528) (xy 37.612654 -348.504539) (xy 37.628021 -348.452204)
			(xy 37.65068 -348.402589) (xy 37.680169 -348.356704) (xy 37.715888 -348.315483) (xy 37.75711 -348.279764)
			(xy 37.802996 -348.250276) (xy 37.852612 -348.227618) (xy 37.904947 -348.212252) (xy 37.958936 -348.204491)
			(xy 37.986208 -348.204028) (xy 38.849808 -348.204028) (xy 38.877076 -348.204535) (xy 38.931058 -348.212297)
			(xy 38.983385 -348.227663) (xy 39.032993 -348.250319) (xy 39.078871 -348.279804) (xy 39.120087 -348.315519)
			(xy 39.1558 -348.356735) (xy 39.185285 -348.402614) (xy 39.20794 -348.452223) (xy 39.223304 -348.50455)
			(xy 39.231066 -348.558532) (xy 39.231066 -348.613068) (xy 39.231066 -348.613069) (xy 40.713914 -348.613069)
			(xy 40.713914 -348.558531) (xy 40.721675 -348.504549) (xy 40.73704 -348.452221) (xy 40.759694 -348.402611)
			(xy 40.789178 -348.356731) (xy 40.82489 -348.315513) (xy 40.866105 -348.279797) (xy 40.911983 -348.250309)
			(xy 40.961591 -348.227651) (xy 41.013918 -348.212282) (xy 41.067899 -348.204517) (xy 41.095168 -348.204028)
			(xy 41.958768 -348.204028) (xy 41.98604 -348.204509) (xy 42.040029 -348.212268) (xy 42.092364 -348.227631)
			(xy 42.14198 -348.250286) (xy 42.187866 -348.279772) (xy 42.229089 -348.315488) (xy 42.264809 -348.356708)
			(xy 42.294299 -348.402592) (xy 42.316958 -348.452206) (xy 42.332326 -348.50454) (xy 42.340088 -348.558528)
			(xy 42.340088 -348.613072) (xy 42.340088 -348.613073) (xy 43.822792 -348.613073) (xy 43.822792 -348.558527)
			(xy 43.830555 -348.504536) (xy 43.845923 -348.4522) (xy 43.868583 -348.402584) (xy 43.898074 -348.356697)
			(xy 43.933795 -348.315476) (xy 43.97502 -348.279757) (xy 44.020908 -348.25027) (xy 44.070526 -348.227613)
			(xy 44.122864 -348.212249) (xy 44.176855 -348.20449) (xy 44.204128 -348.204028) (xy 45.067728 -348.204028)
			(xy 45.094995 -348.204536) (xy 45.148975 -348.212301) (xy 45.201299 -348.227668) (xy 45.250905 -348.250326)
			(xy 45.296781 -348.279811) (xy 45.337994 -348.315526) (xy 45.373705 -348.356742) (xy 45.403188 -348.40262)
			(xy 45.425841 -348.452227) (xy 45.441205 -348.504553) (xy 45.448966 -348.558533) (xy 45.448966 -348.613067)
			(xy 45.448966 -348.61307) (xy 46.931814 -348.61307) (xy 46.931814 -348.55853) (xy 46.939576 -348.504546)
			(xy 46.954941 -348.452217) (xy 46.977597 -348.402606) (xy 47.007083 -348.356724) (xy 47.042797 -348.315506)
			(xy 47.084015 -348.27979) (xy 47.129895 -348.250303) (xy 47.179505 -348.227645) (xy 47.231835 -348.212279)
			(xy 47.285818 -348.204515) (xy 47.313088 -348.204028) (xy 48.176688 -348.204028) (xy 48.203959 -348.204511)
			(xy 48.257946 -348.212271) (xy 48.310278 -348.227636) (xy 48.359892 -348.250292) (xy 48.405776 -348.279779)
			(xy 48.446996 -348.315495) (xy 48.482714 -348.356715) (xy 48.512202 -348.402598) (xy 48.53486 -348.45221)
			(xy 48.550226 -348.504543) (xy 48.557989 -348.558529) (xy 48.557989 -348.613071) (xy 48.557989 -348.613074)
			(xy 50.040692 -348.613074) (xy 50.040692 -348.558526) (xy 50.048455 -348.504534) (xy 50.063824 -348.452196)
			(xy 50.086486 -348.402578) (xy 50.115979 -348.356691) (xy 50.151702 -348.315468) (xy 50.192929 -348.27975)
			(xy 50.23882 -348.250263) (xy 50.288441 -348.227608) (xy 50.340781 -348.212245) (xy 50.394774 -348.204488)
			(xy 50.422048 -348.204028) (xy 51.285648 -348.204028) (xy 51.312914 -348.204538) (xy 51.366891 -348.212305)
			(xy 51.419214 -348.227674) (xy 51.468817 -348.250332) (xy 51.51469 -348.279819) (xy 51.555901 -348.315533)
			(xy 51.59161 -348.356748) (xy 51.621091 -348.402626) (xy 51.643743 -348.452231) (xy 51.659106 -348.504556)
			(xy 51.666866 -348.558534) (xy 51.666866 -348.613066) (xy 51.659106 -348.667044) (xy 51.643743 -348.719369)
			(xy 51.621091 -348.768974) (xy 51.59161 -348.814852) (xy 51.555901 -348.856067) (xy 51.51469 -348.891781)
			(xy 51.468817 -348.921268) (xy 51.419214 -348.943926) (xy 51.366891 -348.959295) (xy 51.312914 -348.967062)
			(xy 51.285648 -348.967552) (xy 50.422048 -348.967552) (xy 50.394774 -348.967112) (xy 50.340781 -348.959355)
			(xy 50.288441 -348.943992) (xy 50.23882 -348.921337) (xy 50.192929 -348.89185) (xy 50.151702 -348.856132)
			(xy 50.115979 -348.814909) (xy 50.086486 -348.769022) (xy 50.063824 -348.719404) (xy 50.048455 -348.667066)
			(xy 50.040692 -348.613074) (xy 48.557989 -348.613074) (xy 48.550226 -348.667057) (xy 48.53486 -348.71939)
			(xy 48.512202 -348.769002) (xy 48.482714 -348.814885) (xy 48.446996 -348.856105) (xy 48.405776 -348.891821)
			(xy 48.359892 -348.921308) (xy 48.310278 -348.943964) (xy 48.257946 -348.959329) (xy 48.203959 -348.967089)
			(xy 48.176688 -348.967552) (xy 47.313088 -348.967552) (xy 47.285818 -348.967085) (xy 47.231835 -348.959321)
			(xy 47.179505 -348.943955) (xy 47.129895 -348.921297) (xy 47.084015 -348.89181) (xy 47.042797 -348.856094)
			(xy 47.007083 -348.814876) (xy 46.977597 -348.768994) (xy 46.954941 -348.719383) (xy 46.939576 -348.667053)
			(xy 46.931814 -348.61307) (xy 45.448966 -348.61307) (xy 45.441205 -348.667047) (xy 45.425841 -348.719373)
			(xy 45.403188 -348.76898) (xy 45.373705 -348.814858) (xy 45.337994 -348.856074) (xy 45.296781 -348.891789)
			(xy 45.250905 -348.921274) (xy 45.201299 -348.943932) (xy 45.148975 -348.959299) (xy 45.094995 -348.967064)
			(xy 45.067728 -348.967552) (xy 44.204128 -348.967552) (xy 44.176855 -348.96711) (xy 44.122864 -348.959351)
			(xy 44.070526 -348.943987) (xy 44.020908 -348.92133) (xy 43.97502 -348.891843) (xy 43.933795 -348.856124)
			(xy 43.898074 -348.814903) (xy 43.868583 -348.769016) (xy 43.845923 -348.7194) (xy 43.830555 -348.667064)
			(xy 43.822792 -348.613073) (xy 42.340088 -348.613073) (xy 42.332326 -348.66706) (xy 42.316958 -348.719394)
			(xy 42.294299 -348.769008) (xy 42.264809 -348.814892) (xy 42.229089 -348.856112) (xy 42.187866 -348.891828)
			(xy 42.14198 -348.921314) (xy 42.092364 -348.943969) (xy 42.040029 -348.959332) (xy 41.98604 -348.967091)
			(xy 41.958768 -348.967552) (xy 41.095168 -348.967552) (xy 41.067899 -348.967083) (xy 41.013918 -348.959318)
			(xy 40.961591 -348.943949) (xy 40.911983 -348.921291) (xy 40.866105 -348.891803) (xy 40.82489 -348.856087)
			(xy 40.789178 -348.814869) (xy 40.759694 -348.768989) (xy 40.73704 -348.719379) (xy 40.721675 -348.667051)
			(xy 40.713914 -348.613069) (xy 39.231066 -348.613069) (xy 39.223304 -348.66705) (xy 39.20794 -348.719377)
			(xy 39.185285 -348.768986) (xy 39.1558 -348.814865) (xy 39.120087 -348.856081) (xy 39.078871 -348.891796)
			(xy 39.032993 -348.921281) (xy 38.983385 -348.943937) (xy 38.931058 -348.959303) (xy 38.877076 -348.967065)
			(xy 38.849808 -348.967552) (xy 37.986208 -348.967552) (xy 37.958936 -348.967109) (xy 37.904947 -348.959348)
			(xy 37.852612 -348.943982) (xy 37.802996 -348.921324) (xy 37.75711 -348.891836) (xy 37.715888 -348.856117)
			(xy 37.680169 -348.814896) (xy 37.65068 -348.769011) (xy 37.628021 -348.719396) (xy 37.612654 -348.667061)
			(xy 37.604892 -348.613072) (xy 36.122065 -348.613072) (xy 36.114306 -348.667044) (xy 36.098943 -348.719369)
			(xy 36.076291 -348.768974) (xy 36.04681 -348.814852) (xy 36.011101 -348.856067) (xy 35.96989 -348.891781)
			(xy 35.924017 -348.921268) (xy 35.874414 -348.943926) (xy 35.822091 -348.959295) (xy 35.768114 -348.967062)
			(xy 35.740848 -348.967552) (xy 34.877248 -348.967552) (xy 34.849974 -348.967112) (xy 34.795981 -348.959355)
			(xy 34.743641 -348.943992) (xy 34.69402 -348.921337) (xy 34.648129 -348.89185) (xy 34.606902 -348.856132)
			(xy 34.571179 -348.814909) (xy 34.541686 -348.769022) (xy 34.519024 -348.719404) (xy 34.503655 -348.667066)
			(xy 34.495892 -348.613074) (xy 33.013189 -348.613074) (xy 33.005426 -348.667057) (xy 32.99006 -348.71939)
			(xy 32.967402 -348.769002) (xy 32.937914 -348.814885) (xy 32.902196 -348.856105) (xy 32.860976 -348.891821)
			(xy 32.815092 -348.921308) (xy 32.765478 -348.943964) (xy 32.713146 -348.959329) (xy 32.659159 -348.967089)
			(xy 32.631888 -348.967552) (xy 31.768288 -348.967552) (xy 31.741018 -348.967085) (xy 31.687035 -348.959321)
			(xy 31.634705 -348.943955) (xy 31.585095 -348.921297) (xy 31.539215 -348.89181) (xy 31.497997 -348.856094)
			(xy 31.462283 -348.814876) (xy 31.432797 -348.768994) (xy 31.410141 -348.719383) (xy 31.394776 -348.667053)
			(xy 31.387014 -348.61307) (xy 29.904166 -348.61307) (xy 29.896405 -348.667047) (xy 29.881041 -348.719373)
			(xy 29.858388 -348.76898) (xy 29.828905 -348.814858) (xy 29.793194 -348.856074) (xy 29.751981 -348.891789)
			(xy 29.706105 -348.921274) (xy 29.656499 -348.943932) (xy 29.604175 -348.959299) (xy 29.550195 -348.967064)
			(xy 29.522928 -348.967552) (xy 28.659328 -348.967552) (xy 28.632055 -348.96711) (xy 28.578064 -348.959351)
			(xy 28.525726 -348.943987) (xy 28.476108 -348.92133) (xy 28.43022 -348.891843) (xy 28.388995 -348.856124)
			(xy 28.353274 -348.814903) (xy 28.323783 -348.769016) (xy 28.301123 -348.7194) (xy 28.285755 -348.667064)
			(xy 28.277992 -348.613073) (xy 26.795288 -348.613073) (xy 26.787526 -348.66706) (xy 26.772158 -348.719394)
			(xy 26.749499 -348.769008) (xy 26.720009 -348.814892) (xy 26.684289 -348.856112) (xy 26.643066 -348.891828)
			(xy 26.59718 -348.921314) (xy 26.547564 -348.943969) (xy 26.495229 -348.959332) (xy 26.44124 -348.967091)
			(xy 26.413968 -348.967552) (xy 25.550368 -348.967552) (xy 25.523099 -348.967083) (xy 25.469118 -348.959318)
			(xy 25.416791 -348.943949) (xy 25.367183 -348.921291) (xy 25.321305 -348.891803) (xy 25.28009 -348.856087)
			(xy 25.244378 -348.814869) (xy 25.214894 -348.768989) (xy 25.19224 -348.719379) (xy 25.176875 -348.667051)
			(xy 25.169114 -348.613069) (xy 23.686266 -348.613069) (xy 23.678504 -348.66705) (xy 23.66314 -348.719377)
			(xy 23.640485 -348.768986) (xy 23.611 -348.814865) (xy 23.575287 -348.856081) (xy 23.534071 -348.891796)
			(xy 23.488193 -348.921281) (xy 23.438585 -348.943937) (xy 23.386258 -348.959303) (xy 23.332276 -348.967065)
			(xy 23.305008 -348.967552) (xy 22.441408 -348.967552) (xy 22.414136 -348.967109) (xy 22.360147 -348.959348)
			(xy 22.307812 -348.943982) (xy 22.258196 -348.921324) (xy 22.21231 -348.891836) (xy 22.171088 -348.856117)
			(xy 22.135369 -348.814896) (xy 22.10588 -348.769011) (xy 22.083221 -348.719396) (xy 22.067854 -348.667061)
			(xy 22.060092 -348.613072) (xy 20.577347 -348.613072) (xy 20.569586 -348.667048) (xy 20.55422 -348.719381)
			(xy 20.531562 -348.768994) (xy 20.502074 -348.814878) (xy 20.466357 -348.856098) (xy 20.425136 -348.891816)
			(xy 20.379253 -348.921303) (xy 20.329639 -348.943961) (xy 20.277306 -348.959327) (xy 20.223319 -348.967089)
			(xy 20.196048 -348.967552) (xy 19.332448 -348.967552) (xy 19.305179 -348.967065) (xy 19.251195 -348.959304)
			(xy 19.198866 -348.943938) (xy 19.149256 -348.921282) (xy 19.103375 -348.891796) (xy 19.062158 -348.856081)
			(xy 19.026443 -348.814863) (xy 18.996957 -348.768982) (xy 18.974301 -348.719372) (xy 18.958936 -348.667043)
			(xy 18.951174 -348.613059) (xy 8.879169 -348.613059) (xy 8.892221 -348.718461) (xy 8.900171 -348.847356)
			(xy 8.900668 -348.911926) (xy 8.900171 -348.976496) (xy 8.892221 -349.105391) (xy 8.876351 -349.233551)
			(xy 8.852622 -349.360492) (xy 8.821123 -349.485731) (xy 8.781974 -349.608794) (xy 8.735323 -349.729213)
			(xy 8.681348 -349.846532) (xy 8.620253 -349.960306) (xy 8.55227 -350.070103) (xy 8.477656 -350.175506)
			(xy 8.396695 -350.276116) (xy 8.309695 -350.371551) (xy 8.216984 -350.46145) (xy 8.118914 -350.545471)
			(xy 8.015859 -350.623295) (xy 7.908208 -350.694627) (xy 7.796369 -350.759197) (xy 7.680768 -350.816759)
			(xy 7.561843 -350.867096) (xy 7.440044 -350.910016) (xy 7.315834 -350.945357) (xy 7.189685 -350.972984)
			(xy 7.062073 -350.992793) (xy 6.933484 -351.004709) (xy 6.804406 -351.008686) (xy 6.675328 -351.004709)
			(xy 6.546739 -350.992793) (xy 6.419127 -350.972984) (xy 6.292978 -350.945357) (xy 6.168768 -350.910016)
			(xy 6.046969 -350.867096) (xy 5.928044 -350.816759) (xy 5.812443 -350.759197) (xy 5.700604 -350.694627)
			(xy 5.592953 -350.623295) (xy 5.489898 -350.545471) (xy 5.391828 -350.46145) (xy 5.299117 -350.371551)
			(xy 5.212117 -350.276116) (xy 5.131156 -350.175506) (xy 5.056542 -350.070103) (xy 4.988559 -349.960306)
			(xy 4.927464 -349.846532) (xy 4.873489 -349.729213) (xy 4.826838 -349.608794) (xy 4.787689 -349.485731)
			(xy 4.75619 -349.360492) (xy 4.732461 -349.233551) (xy 4.716591 -349.105391) (xy 4.708641 -348.976496)
			(xy 0.529844 -348.976496) (xy 0.529844 -351.638709) (xy 18.951172 -351.638709) (xy 18.951172 -351.584171)
			(xy 18.958934 -351.530187) (xy 18.974299 -351.477857) (xy 18.996956 -351.428247) (xy 19.026441 -351.382366)
			(xy 19.062157 -351.341148) (xy 19.103374 -351.305433) (xy 19.149255 -351.275947) (xy 19.198865 -351.25329)
			(xy 19.251195 -351.237925) (xy 19.305179 -351.230163) (xy 19.332448 -351.229676) (xy 20.196048 -351.229676)
			(xy 20.223319 -351.230143) (xy 20.277306 -351.237905) (xy 20.329638 -351.253271) (xy 20.379252 -351.275929)
			(xy 20.425135 -351.305416) (xy 20.466355 -351.341133) (xy 20.502073 -351.382353) (xy 20.53156 -351.428237)
			(xy 20.554218 -351.47785) (xy 20.569584 -351.530182) (xy 20.577347 -351.584169) (xy 20.577347 -351.638669)
			(xy 22.060139 -351.638669) (xy 22.060139 -351.584131) (xy 22.067901 -351.530149) (xy 22.083266 -351.477821)
			(xy 22.105922 -351.428212) (xy 22.135407 -351.382333) (xy 22.171122 -351.341117) (xy 22.212339 -351.305403)
			(xy 22.258219 -351.275918) (xy 22.307829 -351.253263) (xy 22.360157 -351.237899) (xy 22.414139 -351.230139)
			(xy 22.441408 -351.229676) (xy 23.305008 -351.229676) (xy 23.33228 -351.230087) (xy 23.386268 -351.23785)
			(xy 23.438602 -351.253218) (xy 23.488216 -351.275877) (xy 23.5341 -351.305366) (xy 23.575321 -351.341085)
			(xy 23.611039 -351.382306) (xy 23.640527 -351.428191) (xy 23.663185 -351.477806) (xy 23.678551 -351.53014)
			(xy 23.686314 -351.584128) (xy 23.686314 -351.638665) (xy 25.169162 -351.638665) (xy 25.169162 -351.584135)
			(xy 25.176922 -351.530159) (xy 25.192284 -351.477838) (xy 25.214936 -351.428234) (xy 25.244416 -351.38236)
			(xy 25.280124 -351.341147) (xy 25.321334 -351.305435) (xy 25.367206 -351.275951) (xy 25.416808 -351.253296)
			(xy 25.469128 -351.237929) (xy 25.523103 -351.230165) (xy 25.550368 -351.229676) (xy 26.413968 -351.229676)
			(xy 26.441243 -351.230061) (xy 26.495239 -351.237821) (xy 26.547581 -351.253186) (xy 26.597203 -351.275844)
			(xy 26.643095 -351.305333) (xy 26.684323 -351.341054) (xy 26.720047 -351.382279) (xy 26.749541 -351.428169)
			(xy 26.772203 -351.477789) (xy 26.787573 -351.53013) (xy 26.795336 -351.584125) (xy 26.795336 -351.63867)
			(xy 28.278039 -351.63867) (xy 28.278039 -351.58413) (xy 28.285802 -351.530146) (xy 28.301168 -351.477817)
			(xy 28.323825 -351.428207) (xy 28.353312 -351.382326) (xy 28.389029 -351.341109) (xy 28.430249 -351.305396)
			(xy 28.476131 -351.275912) (xy 28.525743 -351.253258) (xy 28.578074 -351.237896) (xy 28.632058 -351.230137)
			(xy 28.659328 -351.229676) (xy 29.522928 -351.229676) (xy 29.550199 -351.230088) (xy 29.604185 -351.237854)
			(xy 29.656516 -351.253223) (xy 29.706128 -351.275883) (xy 29.75201 -351.305373) (xy 29.793228 -351.341092)
			(xy 29.828944 -351.382313) (xy 29.85843 -351.428197) (xy 29.881086 -351.47781) (xy 29.896452 -351.530143)
			(xy 29.904214 -351.584129) (xy 29.904214 -351.638666) (xy 31.387062 -351.638666) (xy 31.387062 -351.584134)
			(xy 31.394823 -351.530157) (xy 31.410186 -351.477833) (xy 31.432839 -351.428229) (xy 31.462321 -351.382353)
			(xy 31.498031 -351.34114) (xy 31.539243 -351.305428) (xy 31.585118 -351.275945) (xy 31.634722 -351.25329)
			(xy 31.687045 -351.237925) (xy 31.741022 -351.230163) (xy 31.768288 -351.229676) (xy 32.631888 -351.229676)
			(xy 32.659162 -351.230063) (xy 32.713156 -351.237824) (xy 32.765495 -351.253191) (xy 32.815115 -351.27585)
			(xy 32.861004 -351.30534) (xy 32.90223 -351.341061) (xy 32.937952 -351.382286) (xy 32.967444 -351.428175)
			(xy 32.990105 -351.477794) (xy 33.005473 -351.530132) (xy 33.013236 -351.584126) (xy 33.013236 -351.63867)
			(xy 34.49594 -351.63867) (xy 34.49594 -351.58413) (xy 34.503702 -351.530144) (xy 34.519069 -351.477812)
			(xy 34.541728 -351.428201) (xy 34.571217 -351.38232) (xy 34.606936 -351.341102) (xy 34.648158 -351.305388)
			(xy 34.694043 -351.275905) (xy 34.743658 -351.253253) (xy 34.795991 -351.237892) (xy 34.849977 -351.230136)
			(xy 34.877248 -351.229676) (xy 35.740848 -351.229676) (xy 35.768118 -351.23009) (xy 35.822102 -351.237858)
			(xy 35.874431 -351.253229) (xy 35.92404 -351.27589) (xy 35.969919 -351.30538) (xy 36.011135 -351.341099)
			(xy 36.046849 -351.382319) (xy 36.076333 -351.428203) (xy 36.098988 -351.477814) (xy 36.114352 -351.530145)
			(xy 36.122114 -351.58413) (xy 36.122114 -351.638669) (xy 37.604939 -351.638669) (xy 37.604939 -351.584131)
			(xy 37.612701 -351.530149) (xy 37.628066 -351.477821) (xy 37.650722 -351.428212) (xy 37.680207 -351.382333)
			(xy 37.715922 -351.341117) (xy 37.757139 -351.305403) (xy 37.803019 -351.275918) (xy 37.852629 -351.253263)
			(xy 37.904957 -351.237899) (xy 37.958939 -351.230139) (xy 37.986208 -351.229676) (xy 38.849808 -351.229676)
			(xy 38.87708 -351.230087) (xy 38.931068 -351.23785) (xy 38.983402 -351.253218) (xy 39.033016 -351.275877)
			(xy 39.0789 -351.305366) (xy 39.120121 -351.341085) (xy 39.155839 -351.382306) (xy 39.185327 -351.428191)
			(xy 39.207985 -351.477806) (xy 39.223351 -351.53014) (xy 39.231114 -351.584128) (xy 39.231114 -351.638665)
			(xy 40.713962 -351.638665) (xy 40.713962 -351.584135) (xy 40.721722 -351.530159) (xy 40.737084 -351.477838)
			(xy 40.759736 -351.428234) (xy 40.789216 -351.38236) (xy 40.824924 -351.341147) (xy 40.866134 -351.305435)
			(xy 40.912006 -351.275951) (xy 40.961608 -351.253296) (xy 41.013928 -351.237929) (xy 41.067903 -351.230165)
			(xy 41.095168 -351.229676) (xy 41.958768 -351.229676) (xy 41.986043 -351.230061) (xy 42.040039 -351.237821)
			(xy 42.092381 -351.253186) (xy 42.142003 -351.275844) (xy 42.187895 -351.305333) (xy 42.229123 -351.341054)
			(xy 42.264847 -351.382279) (xy 42.294341 -351.428169) (xy 42.317003 -351.477789) (xy 42.332373 -351.53013)
			(xy 42.340136 -351.584125) (xy 42.340136 -351.63867) (xy 43.822839 -351.63867) (xy 43.822839 -351.58413)
			(xy 43.830602 -351.530146) (xy 43.845968 -351.477817) (xy 43.868625 -351.428207) (xy 43.898112 -351.382326)
			(xy 43.933829 -351.341109) (xy 43.975049 -351.305396) (xy 44.020931 -351.275912) (xy 44.070543 -351.253258)
			(xy 44.122874 -351.237896) (xy 44.176858 -351.230137) (xy 44.204128 -351.229676) (xy 45.067728 -351.229676)
			(xy 45.094999 -351.230088) (xy 45.148985 -351.237854) (xy 45.201316 -351.253223) (xy 45.250928 -351.275883)
			(xy 45.29681 -351.305373) (xy 45.338028 -351.341092) (xy 45.373744 -351.382313) (xy 45.40323 -351.428197)
			(xy 45.425886 -351.47781) (xy 45.441252 -351.530143) (xy 45.449014 -351.584129) (xy 45.449014 -351.638666)
			(xy 46.931862 -351.638666) (xy 46.931862 -351.584134) (xy 46.939623 -351.530157) (xy 46.954986 -351.477833)
			(xy 46.977639 -351.428229) (xy 47.007121 -351.382353) (xy 47.042831 -351.34114) (xy 47.084043 -351.305428)
			(xy 47.129918 -351.275945) (xy 47.179522 -351.25329) (xy 47.231845 -351.237925) (xy 47.285822 -351.230163)
			(xy 47.313088 -351.229676) (xy 48.176688 -351.229676) (xy 48.203962 -351.230063) (xy 48.257956 -351.237824)
			(xy 48.310295 -351.253191) (xy 48.359915 -351.27585) (xy 48.405804 -351.30534) (xy 48.44703 -351.341061)
			(xy 48.482752 -351.382286) (xy 48.512244 -351.428175) (xy 48.534905 -351.477794) (xy 48.550273 -351.530132)
			(xy 48.558036 -351.584126) (xy 48.558036 -351.63867) (xy 50.04074 -351.63867) (xy 50.04074 -351.58413)
			(xy 50.048502 -351.530144) (xy 50.063869 -351.477812) (xy 50.086528 -351.428201) (xy 50.116017 -351.38232)
			(xy 50.151736 -351.341102) (xy 50.192958 -351.305388) (xy 50.238843 -351.275905) (xy 50.288458 -351.253253)
			(xy 50.340791 -351.237892) (xy 50.394777 -351.230136) (xy 50.422048 -351.229676) (xy 51.285648 -351.229676)
			(xy 51.312918 -351.23009) (xy 51.366902 -351.237858) (xy 51.419231 -351.253229) (xy 51.46884 -351.27589)
			(xy 51.514719 -351.30538) (xy 51.555935 -351.341099) (xy 51.591649 -351.382319) (xy 51.621133 -351.428203)
			(xy 51.643788 -351.477814) (xy 51.659152 -351.530145) (xy 51.666914 -351.58413) (xy 51.666914 -351.63867)
			(xy 51.659152 -351.692655) (xy 51.643788 -351.744986) (xy 51.621133 -351.794597) (xy 51.591649 -351.840481)
			(xy 51.555935 -351.881701) (xy 51.514719 -351.91742) (xy 51.46884 -351.94691) (xy 51.419231 -351.969571)
			(xy 51.366902 -351.984942) (xy 51.312918 -351.99271) (xy 51.285648 -351.9932) (xy 50.422048 -351.9932)
			(xy 50.394777 -351.992664) (xy 50.340791 -351.984908) (xy 50.288458 -351.969547) (xy 50.238843 -351.946895)
			(xy 50.192958 -351.917411) (xy 50.151736 -351.881698) (xy 50.116017 -351.84048) (xy 50.086528 -351.794599)
			(xy 50.063869 -351.744987) (xy 50.048502 -351.692656) (xy 50.04074 -351.63867) (xy 48.558036 -351.63867)
			(xy 48.558036 -351.638674) (xy 48.550273 -351.692668) (xy 48.534905 -351.745006) (xy 48.512244 -351.794625)
			(xy 48.482752 -351.840514) (xy 48.44703 -351.881739) (xy 48.405804 -351.91746) (xy 48.359915 -351.94695)
			(xy 48.310295 -351.969609) (xy 48.257956 -351.984976) (xy 48.203962 -351.992737) (xy 48.176688 -351.9932)
			(xy 47.313088 -351.9932) (xy 47.285822 -351.992637) (xy 47.231845 -351.984875) (xy 47.179522 -351.96951)
			(xy 47.129918 -351.946855) (xy 47.084044 -351.917372) (xy 47.042831 -351.88166) (xy 47.007121 -351.840447)
			(xy 46.977639 -351.794571) (xy 46.954986 -351.744967) (xy 46.939623 -351.692643) (xy 46.931862 -351.638666)
			(xy 45.449014 -351.638666) (xy 45.449014 -351.638671) (xy 45.441252 -351.692657) (xy 45.425886 -351.74499)
			(xy 45.40323 -351.794603) (xy 45.373744 -351.840487) (xy 45.338028 -351.881708) (xy 45.29681 -351.917427)
			(xy 45.250928 -351.946917) (xy 45.201316 -351.969577) (xy 45.148985 -351.984946) (xy 45.094999 -351.992712)
			(xy 45.067728 -351.9932) (xy 44.204128 -351.9932) (xy 44.176858 -351.992663) (xy 44.122874 -351.984904)
			(xy 44.070543 -351.969542) (xy 44.020931 -351.946888) (xy 43.975049 -351.917404) (xy 43.933829 -351.881691)
			(xy 43.898112 -351.840474) (xy 43.868625 -351.794593) (xy 43.845968 -351.744983) (xy 43.830602 -351.692654)
			(xy 43.822839 -351.63867) (xy 42.340136 -351.63867) (xy 42.340136 -351.638675) (xy 42.332373 -351.69267)
			(xy 42.317003 -351.745011) (xy 42.294341 -351.794631) (xy 42.264847 -351.840521) (xy 42.229123 -351.881746)
			(xy 42.187895 -351.917467) (xy 42.142003 -351.946956) (xy 42.092381 -351.969614) (xy 42.040039 -351.984979)
			(xy 41.986043 -351.992739) (xy 41.958768 -351.9932) (xy 41.095168 -351.9932) (xy 41.067903 -351.992635)
			(xy 41.013928 -351.984871) (xy 40.961608 -351.969504) (xy 40.912006 -351.946849) (xy 40.866134 -351.917365)
			(xy 40.824924 -351.881653) (xy 40.789216 -351.84044) (xy 40.759736 -351.794566) (xy 40.737084 -351.744962)
			(xy 40.721722 -351.692641) (xy 40.713962 -351.638665) (xy 39.231114 -351.638665) (xy 39.231114 -351.638672)
			(xy 39.223351 -351.69266) (xy 39.207985 -351.744994) (xy 39.185327 -351.794609) (xy 39.155839 -351.840494)
			(xy 39.120121 -351.881715) (xy 39.0789 -351.917434) (xy 39.033016 -351.946923) (xy 38.983402 -351.969582)
			(xy 38.931068 -351.98495) (xy 38.87708 -351.992713) (xy 38.849808 -351.9932) (xy 37.986208 -351.9932)
			(xy 37.958939 -351.992661) (xy 37.904957 -351.984901) (xy 37.852629 -351.969537) (xy 37.803019 -351.946882)
			(xy 37.757139 -351.917397) (xy 37.715922 -351.881683) (xy 37.680207 -351.840467) (xy 37.650722 -351.794588)
			(xy 37.628066 -351.744979) (xy 37.612701 -351.692651) (xy 37.604939 -351.638669) (xy 36.122114 -351.638669)
			(xy 36.122114 -351.63867) (xy 36.114352 -351.692655) (xy 36.098988 -351.744986) (xy 36.076333 -351.794597)
			(xy 36.046849 -351.840481) (xy 36.011135 -351.881701) (xy 35.969919 -351.91742) (xy 35.92404 -351.94691)
			(xy 35.874431 -351.969571) (xy 35.822102 -351.984942) (xy 35.768118 -351.99271) (xy 35.740848 -351.9932)
			(xy 34.877248 -351.9932) (xy 34.849977 -351.992664) (xy 34.795991 -351.984908) (xy 34.743658 -351.969547)
			(xy 34.694043 -351.946895) (xy 34.648158 -351.917411) (xy 34.606936 -351.881698) (xy 34.571217 -351.84048)
			(xy 34.541728 -351.794599) (xy 34.519069 -351.744987) (xy 34.503702 -351.692656) (xy 34.49594 -351.63867)
			(xy 33.013236 -351.63867) (xy 33.013236 -351.638674) (xy 33.005473 -351.692668) (xy 32.990105 -351.745006)
			(xy 32.967444 -351.794625) (xy 32.937952 -351.840514) (xy 32.90223 -351.881739) (xy 32.861004 -351.91746)
			(xy 32.815115 -351.94695) (xy 32.765495 -351.969609) (xy 32.713156 -351.984976) (xy 32.659162 -351.992737)
			(xy 32.631888 -351.9932) (xy 31.768288 -351.9932) (xy 31.741022 -351.992637) (xy 31.687045 -351.984875)
			(xy 31.634722 -351.96951) (xy 31.585118 -351.946855) (xy 31.539244 -351.917372) (xy 31.498031 -351.88166)
			(xy 31.462321 -351.840447) (xy 31.432839 -351.794571) (xy 31.410186 -351.744967) (xy 31.394823 -351.692643)
			(xy 31.387062 -351.638666) (xy 29.904214 -351.638666) (xy 29.904214 -351.638671) (xy 29.896452 -351.692657)
			(xy 29.881086 -351.74499) (xy 29.85843 -351.794603) (xy 29.828944 -351.840487) (xy 29.793228 -351.881708)
			(xy 29.75201 -351.917427) (xy 29.706128 -351.946917) (xy 29.656516 -351.969577) (xy 29.604185 -351.984946)
			(xy 29.550199 -351.992712) (xy 29.522928 -351.9932) (xy 28.659328 -351.9932) (xy 28.632058 -351.992663)
			(xy 28.578074 -351.984904) (xy 28.525743 -351.969542) (xy 28.476131 -351.946888) (xy 28.430249 -351.917404)
			(xy 28.389029 -351.881691) (xy 28.353312 -351.840474) (xy 28.323825 -351.794593) (xy 28.301168 -351.744983)
			(xy 28.285802 -351.692654) (xy 28.278039 -351.63867) (xy 26.795336 -351.63867) (xy 26.795336 -351.638675)
			(xy 26.787573 -351.69267) (xy 26.772203 -351.745011) (xy 26.749541 -351.794631) (xy 26.720047 -351.840521)
			(xy 26.684323 -351.881746) (xy 26.643095 -351.917467) (xy 26.597203 -351.946956) (xy 26.547581 -351.969614)
			(xy 26.495239 -351.984979) (xy 26.441243 -351.992739) (xy 26.413968 -351.9932) (xy 25.550368 -351.9932)
			(xy 25.523103 -351.992635) (xy 25.469128 -351.984871) (xy 25.416808 -351.969504) (xy 25.367206 -351.946849)
			(xy 25.321334 -351.917365) (xy 25.280124 -351.881653) (xy 25.244416 -351.84044) (xy 25.214936 -351.794566)
			(xy 25.192284 -351.744962) (xy 25.176922 -351.692641) (xy 25.169162 -351.638665) (xy 23.686314 -351.638665)
			(xy 23.686314 -351.638672) (xy 23.678551 -351.69266) (xy 23.663185 -351.744994) (xy 23.640527 -351.794609)
			(xy 23.611039 -351.840494) (xy 23.575321 -351.881715) (xy 23.5341 -351.917434) (xy 23.488216 -351.946923)
			(xy 23.438602 -351.969582) (xy 23.386268 -351.98495) (xy 23.33228 -351.992713) (xy 23.305008 -351.9932)
			(xy 22.441408 -351.9932) (xy 22.414139 -351.992661) (xy 22.360157 -351.984901) (xy 22.307829 -351.969537)
			(xy 22.258219 -351.946882) (xy 22.212339 -351.917397) (xy 22.171122 -351.881683) (xy 22.135407 -351.840467)
			(xy 22.105922 -351.794588) (xy 22.083266 -351.744979) (xy 22.067901 -351.692651) (xy 22.060139 -351.638669)
			(xy 20.577347 -351.638669) (xy 20.577347 -351.638711) (xy 20.569584 -351.692698) (xy 20.554218 -351.74503)
			(xy 20.53156 -351.794643) (xy 20.502073 -351.840527) (xy 20.466355 -351.881747) (xy 20.425135 -351.917464)
			(xy 20.379252 -351.946951) (xy 20.329638 -351.969609) (xy 20.277306 -351.984975) (xy 20.223319 -351.992737)
			(xy 20.196048 -351.9932) (xy 19.332448 -351.9932) (xy 19.305179 -351.992717) (xy 19.251195 -351.984955)
			(xy 19.198865 -351.96959) (xy 19.149255 -351.946933) (xy 19.103374 -351.917447) (xy 19.062157 -351.881732)
			(xy 19.026441 -351.840514) (xy 18.996956 -351.794633) (xy 18.974299 -351.745023) (xy 18.958934 -351.692693)
			(xy 18.951172 -351.638709) (xy 0.529844 -351.638709) (xy 0.529844 -354.759373) (xy 22.060084 -354.759373)
			(xy 22.060084 -354.704827) (xy 22.067846 -354.650837) (xy 22.083214 -354.598501) (xy 22.105873 -354.548885)
			(xy 22.135363 -354.502999) (xy 22.171083 -354.461777) (xy 22.212306 -354.426058) (xy 22.258192 -354.396569)
			(xy 22.307809 -354.373911) (xy 22.360145 -354.358545) (xy 22.414135 -354.350783) (xy 22.441408 -354.35032)
			(xy 23.305008 -354.35032) (xy 23.332276 -354.350843) (xy 23.386256 -354.358605) (xy 23.438582 -354.37397)
			(xy 23.488189 -354.396626) (xy 23.534067 -354.426111) (xy 23.575281 -354.461824) (xy 23.610994 -354.50304)
			(xy 23.640478 -354.548918) (xy 23.663132 -354.598525) (xy 23.678497 -354.650852) (xy 23.686258 -354.704832)
			(xy 23.686258 -354.759368) (xy 23.686258 -354.759369) (xy 25.169106 -354.759369) (xy 25.169106 -354.704831)
			(xy 25.176868 -354.650847) (xy 25.192232 -354.598518) (xy 25.214887 -354.548908) (xy 25.244371 -354.503026)
			(xy 25.280085 -354.461807) (xy 25.3213 -354.42609) (xy 25.36718 -354.396602) (xy 25.416788 -354.373943)
			(xy 25.469116 -354.358574) (xy 25.523099 -354.350809) (xy 25.550368 -354.35032) (xy 26.413968 -354.35032)
			(xy 26.441239 -354.350817) (xy 26.495227 -354.358575) (xy 26.547561 -354.373938) (xy 26.597176 -354.396593)
			(xy 26.643061 -354.426078) (xy 26.684283 -354.461794) (xy 26.720003 -354.503013) (xy 26.749492 -354.548896)
			(xy 26.772151 -354.598509) (xy 26.787518 -354.650842) (xy 26.79528 -354.704829) (xy 26.79528 -354.759371)
			(xy 26.79528 -354.759374) (xy 28.277984 -354.759374) (xy 28.277984 -354.704826) (xy 28.285747 -354.650835)
			(xy 28.301115 -354.598497) (xy 28.323776 -354.54888) (xy 28.353268 -354.502993) (xy 28.38899 -354.46177)
			(xy 28.430215 -354.426051) (xy 28.476104 -354.396562) (xy 28.525723 -354.373905) (xy 28.578062 -354.358541)
			(xy 28.632054 -354.350782) (xy 28.659328 -354.35032) (xy 29.522928 -354.35032) (xy 29.550195 -354.350844)
			(xy 29.604173 -354.358609) (xy 29.656497 -354.373976) (xy 29.706101 -354.396633) (xy 29.751976 -354.426118)
			(xy 29.793188 -354.461831) (xy 29.828899 -354.503046) (xy 29.858381 -354.548924) (xy 29.881034 -354.59853)
			(xy 29.896397 -354.650855) (xy 29.904158 -354.704833) (xy 29.904158 -354.759367) (xy 29.904158 -354.75937)
			(xy 31.387006 -354.75937) (xy 31.387006 -354.70483) (xy 31.394768 -354.650845) (xy 31.410134 -354.598514)
			(xy 31.43279 -354.548902) (xy 31.462276 -354.50302) (xy 31.497992 -354.4618) (xy 31.53921 -354.426083)
			(xy 31.585091 -354.396596) (xy 31.634703 -354.373938) (xy 31.687033 -354.358571) (xy 31.741018 -354.350807)
			(xy 31.768288 -354.35032) (xy 32.631888 -354.35032) (xy 32.659158 -354.350819) (xy 32.713144 -354.358579)
			(xy 32.765476 -354.373944) (xy 32.815088 -354.396599) (xy 32.860971 -354.426085) (xy 32.902191 -354.461801)
			(xy 32.937908 -354.503019) (xy 32.967395 -354.548902) (xy 32.990052 -354.598513) (xy 33.005418 -354.650844)
			(xy 33.013181 -354.70483) (xy 33.013181 -354.75937) (xy 33.01318 -354.759374) (xy 34.495884 -354.759374)
			(xy 34.495884 -354.704826) (xy 34.503647 -354.650832) (xy 34.519017 -354.598493) (xy 34.541679 -354.548874)
			(xy 34.571172 -354.502986) (xy 34.606897 -354.461763) (xy 34.648125 -354.426044) (xy 34.694016 -354.396556)
			(xy 34.743638 -354.3739) (xy 34.795979 -354.358537) (xy 34.849973 -354.35078) (xy 34.877248 -354.35032)
			(xy 35.740848 -354.35032) (xy 35.768114 -354.350846) (xy 35.82209 -354.358613) (xy 35.874411 -354.373981)
			(xy 35.924013 -354.396639) (xy 35.969886 -354.426125) (xy 36.011095 -354.461839) (xy 36.046804 -354.503053)
			(xy 36.076284 -354.548929) (xy 36.098936 -354.598534) (xy 36.114298 -354.650857) (xy 36.122058 -354.704834)
			(xy 36.122058 -354.759366) (xy 36.122057 -354.759373) (xy 37.604884 -354.759373) (xy 37.604884 -354.704827)
			(xy 37.612646 -354.650837) (xy 37.628014 -354.598501) (xy 37.650673 -354.548885) (xy 37.680163 -354.502999)
			(xy 37.715883 -354.461777) (xy 37.757106 -354.426058) (xy 37.802992 -354.396569) (xy 37.852609 -354.373911)
			(xy 37.904945 -354.358545) (xy 37.958935 -354.350783) (xy 37.986208 -354.35032) (xy 38.849808 -354.35032)
			(xy 38.877076 -354.350843) (xy 38.931056 -354.358605) (xy 38.983382 -354.37397) (xy 39.032989 -354.396626)
			(xy 39.078867 -354.426111) (xy 39.120081 -354.461824) (xy 39.155794 -354.50304) (xy 39.185278 -354.548918)
			(xy 39.207932 -354.598525) (xy 39.223297 -354.650852) (xy 39.231058 -354.704832) (xy 39.231058 -354.759368)
			(xy 39.231058 -354.759369) (xy 40.713906 -354.759369) (xy 40.713906 -354.704831) (xy 40.721668 -354.650847)
			(xy 40.737032 -354.598518) (xy 40.759687 -354.548908) (xy 40.789171 -354.503026) (xy 40.824885 -354.461807)
			(xy 40.8661 -354.42609) (xy 40.91198 -354.396602) (xy 40.961588 -354.373943) (xy 41.013916 -354.358574)
			(xy 41.067899 -354.350809) (xy 41.095168 -354.35032) (xy 41.958768 -354.35032) (xy 41.986039 -354.350817)
			(xy 42.040027 -354.358575) (xy 42.092361 -354.373938) (xy 42.141976 -354.396593) (xy 42.187861 -354.426078)
			(xy 42.229083 -354.461794) (xy 42.264803 -354.503013) (xy 42.294292 -354.548896) (xy 42.316951 -354.598509)
			(xy 42.332318 -354.650842) (xy 42.34008 -354.704829) (xy 42.34008 -354.759371) (xy 42.34008 -354.759374)
			(xy 43.822784 -354.759374) (xy 43.822784 -354.704826) (xy 43.830547 -354.650835) (xy 43.845915 -354.598497)
			(xy 43.868576 -354.54888) (xy 43.898068 -354.502993) (xy 43.93379 -354.46177) (xy 43.975015 -354.426051)
			(xy 44.020904 -354.396562) (xy 44.070523 -354.373905) (xy 44.122862 -354.358541) (xy 44.176854 -354.350782)
			(xy 44.204128 -354.35032) (xy 45.067728 -354.35032) (xy 45.094995 -354.350844) (xy 45.148973 -354.358609)
			(xy 45.201297 -354.373976) (xy 45.250901 -354.396633) (xy 45.296776 -354.426118) (xy 45.337988 -354.461831)
			(xy 45.373699 -354.503046) (xy 45.403181 -354.548924) (xy 45.425834 -354.59853) (xy 45.441197 -354.650855)
			(xy 45.448958 -354.704833) (xy 45.448958 -354.759367) (xy 45.448958 -354.75937) (xy 46.931806 -354.75937)
			(xy 46.931806 -354.70483) (xy 46.939568 -354.650845) (xy 46.954934 -354.598514) (xy 46.97759 -354.548902)
			(xy 47.007076 -354.50302) (xy 47.042792 -354.4618) (xy 47.08401 -354.426083) (xy 47.129891 -354.396596)
			(xy 47.179503 -354.373938) (xy 47.231833 -354.358571) (xy 47.285818 -354.350807) (xy 47.313088 -354.35032)
			(xy 48.176688 -354.35032) (xy 48.203958 -354.350819) (xy 48.257944 -354.358579) (xy 48.310276 -354.373944)
			(xy 48.359888 -354.396599) (xy 48.405771 -354.426085) (xy 48.446991 -354.461801) (xy 48.482708 -354.503019)
			(xy 48.512195 -354.548902) (xy 48.534852 -354.598513) (xy 48.550218 -354.650844) (xy 48.557981 -354.70483)
			(xy 48.557981 -354.75937) (xy 48.55798 -354.759374) (xy 50.040684 -354.759374) (xy 50.040684 -354.704826)
			(xy 50.048447 -354.650832) (xy 50.063817 -354.598493) (xy 50.086479 -354.548874) (xy 50.115972 -354.502986)
			(xy 50.151697 -354.461763) (xy 50.192925 -354.426044) (xy 50.238816 -354.396556) (xy 50.288438 -354.3739)
			(xy 50.340779 -354.358537) (xy 50.394773 -354.35078) (xy 50.422048 -354.35032) (xy 51.285648 -354.35032)
			(xy 51.312914 -354.350846) (xy 51.36689 -354.358613) (xy 51.419211 -354.373981) (xy 51.468813 -354.396639)
			(xy 51.514686 -354.426125) (xy 51.555895 -354.461839) (xy 51.591604 -354.503053) (xy 51.621084 -354.548929)
			(xy 51.643736 -354.598534) (xy 51.659098 -354.650857) (xy 51.666858 -354.704834) (xy 51.666858 -354.759366)
			(xy 51.659098 -354.813343) (xy 51.643736 -354.865666) (xy 51.621084 -354.915271) (xy 51.591604 -354.961147)
			(xy 51.555895 -355.002361) (xy 51.514686 -355.038075) (xy 51.468813 -355.067561) (xy 51.419211 -355.090219)
			(xy 51.36689 -355.105587) (xy 51.312914 -355.113354) (xy 51.285648 -355.113844) (xy 50.422048 -355.113844)
			(xy 50.394773 -355.11342) (xy 50.340779 -355.105663) (xy 50.288438 -355.0903) (xy 50.238816 -355.067644)
			(xy 50.192925 -355.038156) (xy 50.151697 -355.002437) (xy 50.115972 -354.961214) (xy 50.086479 -354.915326)
			(xy 50.063817 -354.865707) (xy 50.048447 -354.813368) (xy 50.040684 -354.759374) (xy 48.55798 -354.759374)
			(xy 48.550218 -354.813356) (xy 48.534852 -354.865687) (xy 48.512195 -354.915298) (xy 48.482708 -354.961181)
			(xy 48.446991 -355.002399) (xy 48.405771 -355.038115) (xy 48.359888 -355.067601) (xy 48.310276 -355.090256)
			(xy 48.257944 -355.105621) (xy 48.203958 -355.113381) (xy 48.176688 -355.113844) (xy 47.313088 -355.113844)
			(xy 47.285818 -355.113393) (xy 47.231833 -355.105629) (xy 47.179503 -355.090262) (xy 47.129891 -355.067604)
			(xy 47.08401 -355.038117) (xy 47.042792 -355.0024) (xy 47.007076 -354.96118) (xy 46.97759 -354.915298)
			(xy 46.954934 -354.865686) (xy 46.939568 -354.813355) (xy 46.931806 -354.75937) (xy 45.448958 -354.75937)
			(xy 45.441197 -354.813345) (xy 45.425834 -354.86567) (xy 45.403181 -354.915276) (xy 45.373699 -354.961154)
			(xy 45.337988 -355.002369) (xy 45.296776 -355.038082) (xy 45.250901 -355.067567) (xy 45.201297 -355.090224)
			(xy 45.148973 -355.105591) (xy 45.094995 -355.113356) (xy 45.067728 -355.113844) (xy 44.204128 -355.113844)
			(xy 44.176854 -355.113418) (xy 44.122862 -355.105659) (xy 44.070523 -355.090295) (xy 44.020904 -355.067638)
			(xy 43.975015 -355.038149) (xy 43.93379 -355.00243) (xy 43.898068 -354.961207) (xy 43.868576 -354.91532)
			(xy 43.845915 -354.865703) (xy 43.830547 -354.813365) (xy 43.822784 -354.759374) (xy 42.34008 -354.759374)
			(xy 42.332318 -354.813358) (xy 42.316951 -354.865691) (xy 42.294292 -354.915304) (xy 42.264803 -354.961187)
			(xy 42.229083 -355.002406) (xy 42.187861 -355.038122) (xy 42.141976 -355.067607) (xy 42.092361 -355.090262)
			(xy 42.040027 -355.105625) (xy 41.986039 -355.113383) (xy 41.958768 -355.113844) (xy 41.095168 -355.113844)
			(xy 41.067899 -355.113391) (xy 41.013916 -355.105626) (xy 40.961588 -355.090257) (xy 40.91198 -355.067598)
			(xy 40.8661 -355.03811) (xy 40.824885 -355.002393) (xy 40.789171 -354.961174) (xy 40.759687 -354.915292)
			(xy 40.737032 -354.865682) (xy 40.721668 -354.813353) (xy 40.713906 -354.759369) (xy 39.231058 -354.759369)
			(xy 39.223297 -354.813348) (xy 39.207932 -354.865675) (xy 39.185278 -354.915282) (xy 39.155794 -354.96116)
			(xy 39.120081 -355.002376) (xy 39.078867 -355.038089) (xy 39.032989 -355.067574) (xy 38.983382 -355.09023)
			(xy 38.931056 -355.105595) (xy 38.877076 -355.113357) (xy 38.849808 -355.113844) (xy 37.986208 -355.113844)
			(xy 37.958935 -355.113417) (xy 37.904945 -355.105655) (xy 37.852609 -355.090289) (xy 37.802992 -355.067631)
			(xy 37.757106 -355.038142) (xy 37.715883 -355.002423) (xy 37.680163 -354.961201) (xy 37.650673 -354.915315)
			(xy 37.628014 -354.865699) (xy 37.612646 -354.813363) (xy 37.604884 -354.759373) (xy 36.122057 -354.759373)
			(xy 36.114298 -354.813343) (xy 36.098936 -354.865666) (xy 36.076284 -354.915271) (xy 36.046804 -354.961147)
			(xy 36.011095 -355.002361) (xy 35.969886 -355.038075) (xy 35.924013 -355.067561) (xy 35.874411 -355.090219)
			(xy 35.82209 -355.105587) (xy 35.768114 -355.113354) (xy 35.740848 -355.113844) (xy 34.877248 -355.113844)
			(xy 34.849973 -355.11342) (xy 34.795979 -355.105663) (xy 34.743638 -355.0903) (xy 34.694016 -355.067644)
			(xy 34.648125 -355.038156) (xy 34.606897 -355.002437) (xy 34.571172 -354.961214) (xy 34.541679 -354.915326)
			(xy 34.519017 -354.865707) (xy 34.503647 -354.813368) (xy 34.495884 -354.759374) (xy 33.01318 -354.759374)
			(xy 33.005418 -354.813356) (xy 32.990052 -354.865687) (xy 32.967395 -354.915298) (xy 32.937908 -354.961181)
			(xy 32.902191 -355.002399) (xy 32.860971 -355.038115) (xy 32.815088 -355.067601) (xy 32.765476 -355.090256)
			(xy 32.713144 -355.105621) (xy 32.659158 -355.113381) (xy 32.631888 -355.113844) (xy 31.768288 -355.113844)
			(xy 31.741018 -355.113393) (xy 31.687033 -355.105629) (xy 31.634703 -355.090262) (xy 31.585091 -355.067604)
			(xy 31.53921 -355.038117) (xy 31.497992 -355.0024) (xy 31.462276 -354.96118) (xy 31.43279 -354.915298)
			(xy 31.410134 -354.865686) (xy 31.394768 -354.813355) (xy 31.387006 -354.75937) (xy 29.904158 -354.75937)
			(xy 29.896397 -354.813345) (xy 29.881034 -354.86567) (xy 29.858381 -354.915276) (xy 29.828899 -354.961154)
			(xy 29.793188 -355.002369) (xy 29.751976 -355.038082) (xy 29.706101 -355.067567) (xy 29.656497 -355.090224)
			(xy 29.604173 -355.105591) (xy 29.550195 -355.113356) (xy 29.522928 -355.113844) (xy 28.659328 -355.113844)
			(xy 28.632054 -355.113418) (xy 28.578062 -355.105659) (xy 28.525723 -355.090295) (xy 28.476104 -355.067638)
			(xy 28.430215 -355.038149) (xy 28.38899 -355.00243) (xy 28.353268 -354.961207) (xy 28.323776 -354.91532)
			(xy 28.301115 -354.865703) (xy 28.285747 -354.813365) (xy 28.277984 -354.759374) (xy 26.79528 -354.759374)
			(xy 26.787518 -354.813358) (xy 26.772151 -354.865691) (xy 26.749492 -354.915304) (xy 26.720003 -354.961187)
			(xy 26.684283 -355.002406) (xy 26.643061 -355.038122) (xy 26.597176 -355.067607) (xy 26.547561 -355.090262)
			(xy 26.495227 -355.105625) (xy 26.441239 -355.113383) (xy 26.413968 -355.113844) (xy 25.550368 -355.113844)
			(xy 25.523099 -355.113391) (xy 25.469116 -355.105626) (xy 25.416788 -355.090257) (xy 25.36718 -355.067598)
			(xy 25.3213 -355.03811) (xy 25.280085 -355.002393) (xy 25.244371 -354.961174) (xy 25.214887 -354.915292)
			(xy 25.192232 -354.865682) (xy 25.176868 -354.813353) (xy 25.169106 -354.759369) (xy 23.686258 -354.759369)
			(xy 23.678497 -354.813348) (xy 23.663132 -354.865675) (xy 23.640478 -354.915282) (xy 23.610994 -354.96116)
			(xy 23.575281 -355.002376) (xy 23.534067 -355.038089) (xy 23.488189 -355.067574) (xy 23.438582 -355.09023)
			(xy 23.386256 -355.105595) (xy 23.332276 -355.113357) (xy 23.305008 -355.113844) (xy 22.441408 -355.113844)
			(xy 22.414135 -355.113417) (xy 22.360145 -355.105655) (xy 22.307809 -355.090289) (xy 22.258192 -355.067631)
			(xy 22.212306 -355.038142) (xy 22.171083 -355.002423) (xy 22.135363 -354.961201) (xy 22.105873 -354.915315)
			(xy 22.083214 -354.865699) (xy 22.067846 -354.813363) (xy 22.060084 -354.759373) (xy 0.529844 -354.759373)
			(xy 0.529844 -357.784969) (xy 22.060131 -357.784969) (xy 22.060131 -357.730431) (xy 22.067893 -357.676447)
			(xy 22.083259 -357.624118) (xy 22.105915 -357.574508) (xy 22.135401 -357.528628) (xy 22.171117 -357.487411)
			(xy 22.212334 -357.451696) (xy 22.258215 -357.422211) (xy 22.307826 -357.399556) (xy 22.360155 -357.384191)
			(xy 22.414139 -357.376431) (xy 22.441408 -357.375968) (xy 23.305008 -357.375968) (xy 23.332279 -357.376395)
			(xy 23.386266 -357.384158) (xy 23.438599 -357.399525) (xy 23.488212 -357.422184) (xy 23.534095 -357.451672)
			(xy 23.575315 -357.48739) (xy 23.611032 -357.528611) (xy 23.64052 -357.574495) (xy 23.663177 -357.624109)
			(xy 23.678543 -357.676442) (xy 23.686306 -357.730429) (xy 23.686306 -357.784966) (xy 25.169154 -357.784966)
			(xy 25.169154 -357.730434) (xy 25.176914 -357.676458) (xy 25.192277 -357.624135) (xy 25.214929 -357.574531)
			(xy 25.24441 -357.528655) (xy 25.280119 -357.487441) (xy 25.321329 -357.451729) (xy 25.367203 -357.422244)
			(xy 25.416805 -357.399588) (xy 25.469126 -357.384221) (xy 25.523102 -357.376457) (xy 25.550368 -357.375968)
			(xy 26.413968 -357.375968) (xy 26.441243 -357.376369) (xy 26.495237 -357.384128) (xy 26.547578 -357.399493)
			(xy 26.597199 -357.422151) (xy 26.64309 -357.45164) (xy 26.684317 -357.48736) (xy 26.720041 -357.528584)
			(xy 26.749534 -357.574473) (xy 26.772196 -357.624092) (xy 26.787565 -357.676431) (xy 26.795328 -357.730425)
			(xy 26.795328 -357.78497) (xy 28.278031 -357.78497) (xy 28.278032 -357.73043) (xy 28.285794 -357.676445)
			(xy 28.30116 -357.624114) (xy 28.323818 -357.574503) (xy 28.353306 -357.528621) (xy 28.389024 -357.487404)
			(xy 28.430244 -357.451689) (xy 28.476127 -357.422205) (xy 28.52574 -357.39955) (xy 28.578072 -357.384188)
			(xy 28.632058 -357.37643) (xy 28.659328 -357.375968) (xy 29.522928 -357.375968) (xy 29.550198 -357.376396)
			(xy 29.604183 -357.384162) (xy 29.656513 -357.399531) (xy 29.706124 -357.42219) (xy 29.752005 -357.451679)
			(xy 29.793222 -357.487397) (xy 29.828937 -357.528618) (xy 29.858423 -357.574501) (xy 29.881079 -357.624113)
			(xy 29.896444 -357.676444) (xy 29.904206 -357.73043) (xy 29.904206 -357.784967) (xy 31.387054 -357.784967)
			(xy 31.387054 -357.730433) (xy 31.394815 -357.676455) (xy 31.410179 -357.624131) (xy 31.432832 -357.574525)
			(xy 31.462315 -357.528648) (xy 31.498026 -357.487434) (xy 31.539239 -357.451722) (xy 31.585115 -357.422238)
			(xy 31.634719 -357.399583) (xy 31.687043 -357.384218) (xy 31.741021 -357.376455) (xy 31.768288 -357.375968)
			(xy 32.631888 -357.375968) (xy 32.659162 -357.376371) (xy 32.713154 -357.384132) (xy 32.765492 -357.399499)
			(xy 32.815111 -357.422157) (xy 32.861 -357.451647) (xy 32.902224 -357.487367) (xy 32.937946 -357.528591)
			(xy 32.967437 -357.574479) (xy 32.990097 -357.624096) (xy 33.005465 -357.676434) (xy 33.013228 -357.730426)
			(xy 33.013228 -357.784971) (xy 34.495932 -357.784971) (xy 34.495932 -357.730429) (xy 34.503694 -357.676442)
			(xy 34.519062 -357.62411) (xy 34.541721 -357.574497) (xy 34.571211 -357.528615) (xy 34.606931 -357.487397)
			(xy 34.648153 -357.451682) (xy 34.694039 -357.422198) (xy 34.743655 -357.399545) (xy 34.795989 -357.384184)
			(xy 34.849977 -357.376428) (xy 34.877248 -357.375968) (xy 35.740848 -357.375968) (xy 35.768117 -357.376398)
			(xy 35.8221 -357.384166) (xy 35.874428 -357.399536) (xy 35.924036 -357.422197) (xy 35.969914 -357.451687)
			(xy 36.011129 -357.487405) (xy 36.046842 -357.528624) (xy 36.076326 -357.574506) (xy 36.09898 -357.624117)
			(xy 36.114345 -357.676447) (xy 36.122106 -357.730431) (xy 36.122106 -357.784969) (xy 37.604931 -357.784969)
			(xy 37.604931 -357.730431) (xy 37.612693 -357.676447) (xy 37.628059 -357.624118) (xy 37.650715 -357.574508)
			(xy 37.680201 -357.528628) (xy 37.715917 -357.487411) (xy 37.757134 -357.451696) (xy 37.803015 -357.422211)
			(xy 37.852626 -357.399556) (xy 37.904955 -357.384191) (xy 37.958939 -357.376431) (xy 37.986208 -357.375968)
			(xy 38.849808 -357.375968) (xy 38.877079 -357.376395) (xy 38.931066 -357.384158) (xy 38.983399 -357.399525)
			(xy 39.033012 -357.422184) (xy 39.078895 -357.451672) (xy 39.120115 -357.48739) (xy 39.155832 -357.528611)
			(xy 39.18532 -357.574495) (xy 39.207977 -357.624109) (xy 39.223343 -357.676442) (xy 39.231106 -357.730429)
			(xy 39.231106 -357.784966) (xy 40.713954 -357.784966) (xy 40.713954 -357.730434) (xy 40.721714 -357.676458)
			(xy 40.737077 -357.624135) (xy 40.759729 -357.574531) (xy 40.78921 -357.528655) (xy 40.824919 -357.487441)
			(xy 40.866129 -357.451729) (xy 40.912003 -357.422244) (xy 40.961605 -357.399588) (xy 41.013926 -357.384221)
			(xy 41.067902 -357.376457) (xy 41.095168 -357.375968) (xy 41.958768 -357.375968) (xy 41.986043 -357.376369)
			(xy 42.040037 -357.384128) (xy 42.092378 -357.399493) (xy 42.141999 -357.422151) (xy 42.18789 -357.45164)
			(xy 42.229117 -357.48736) (xy 42.264841 -357.528584) (xy 42.294334 -357.574473) (xy 42.316996 -357.624092)
			(xy 42.332365 -357.676431) (xy 42.340128 -357.730425) (xy 42.340128 -357.78497) (xy 43.822831 -357.78497)
			(xy 43.822832 -357.73043) (xy 43.830594 -357.676445) (xy 43.84596 -357.624114) (xy 43.868618 -357.574503)
			(xy 43.898106 -357.528621) (xy 43.933824 -357.487404) (xy 43.975044 -357.451689) (xy 44.020927 -357.422205)
			(xy 44.07054 -357.39955) (xy 44.122872 -357.384188) (xy 44.176858 -357.37643) (xy 44.204128 -357.375968)
			(xy 45.067728 -357.375968) (xy 45.094998 -357.376396) (xy 45.148983 -357.384162) (xy 45.201313 -357.399531)
			(xy 45.250924 -357.42219) (xy 45.296805 -357.451679) (xy 45.338022 -357.487397) (xy 45.373737 -357.528618)
			(xy 45.403223 -357.574501) (xy 45.425879 -357.624113) (xy 45.441244 -357.676444) (xy 45.449006 -357.73043)
			(xy 45.449006 -357.784967) (xy 46.931854 -357.784967) (xy 46.931854 -357.730433) (xy 46.939615 -357.676455)
			(xy 46.954979 -357.624131) (xy 46.977632 -357.574525) (xy 47.007115 -357.528648) (xy 47.042826 -357.487434)
			(xy 47.084039 -357.451722) (xy 47.129915 -357.422238) (xy 47.179519 -357.399583) (xy 47.231843 -357.384218)
			(xy 47.285821 -357.376455) (xy 47.313088 -357.375968) (xy 48.176688 -357.375968) (xy 48.203962 -357.376371)
			(xy 48.257954 -357.384132) (xy 48.310292 -357.399499) (xy 48.359911 -357.422157) (xy 48.4058 -357.451647)
			(xy 48.447024 -357.487367) (xy 48.482746 -357.528591) (xy 48.512237 -357.574479) (xy 48.534897 -357.624096)
			(xy 48.550265 -357.676434) (xy 48.558028 -357.730426) (xy 48.558028 -357.784974) (xy 48.550265 -357.838966)
			(xy 48.534897 -357.891304) (xy 48.512237 -357.940921) (xy 48.482746 -357.986809) (xy 48.447024 -358.028033)
			(xy 48.4058 -358.063753) (xy 48.359911 -358.093243) (xy 48.310292 -358.115901) (xy 48.257954 -358.131268)
			(xy 48.203962 -358.139029) (xy 48.176688 -358.139492) (xy 47.313088 -358.139492) (xy 47.285821 -358.138945)
			(xy 47.231843 -358.131182) (xy 47.179519 -358.115817) (xy 47.129915 -358.093162) (xy 47.084039 -358.063678)
			(xy 47.042826 -358.027966) (xy 47.007115 -357.986752) (xy 46.977632 -357.940875) (xy 46.954979 -357.891269)
			(xy 46.939615 -357.838945) (xy 46.931854 -357.784967) (xy 45.449006 -357.784967) (xy 45.449006 -357.78497)
			(xy 45.441244 -357.838956) (xy 45.425879 -357.891287) (xy 45.403223 -357.940899) (xy 45.373737 -357.986782)
			(xy 45.338022 -358.028003) (xy 45.296805 -358.063721) (xy 45.250924 -358.09321) (xy 45.201313 -358.115869)
			(xy 45.148983 -358.131238) (xy 45.094998 -358.139004) (xy 45.067728 -358.139492) (xy 44.204128 -358.139492)
			(xy 44.176858 -358.13897) (xy 44.122872 -358.131212) (xy 44.07054 -358.11585) (xy 44.020927 -358.093195)
			(xy 43.975044 -358.063711) (xy 43.933824 -358.027996) (xy 43.898106 -357.986779) (xy 43.868618 -357.940897)
			(xy 43.84596 -357.891286) (xy 43.830594 -357.838955) (xy 43.822831 -357.78497) (xy 42.340128 -357.78497)
			(xy 42.340128 -357.784975) (xy 42.332365 -357.838969) (xy 42.316996 -357.891308) (xy 42.294334 -357.940927)
			(xy 42.264841 -357.986816) (xy 42.229117 -358.02804) (xy 42.18789 -358.06376) (xy 42.141999 -358.093249)
			(xy 42.092378 -358.115907) (xy 42.040037 -358.131272) (xy 41.986043 -358.139031) (xy 41.958768 -358.139492)
			(xy 41.095168 -358.139492) (xy 41.067902 -358.138943) (xy 41.013926 -358.131179) (xy 40.961605 -358.115812)
			(xy 40.912003 -358.093156) (xy 40.866129 -358.063671) (xy 40.824919 -358.027959) (xy 40.78921 -357.986745)
			(xy 40.759729 -357.940869) (xy 40.737077 -357.891265) (xy 40.721714 -357.838942) (xy 40.713954 -357.784966)
			(xy 39.231106 -357.784966) (xy 39.231106 -357.784971) (xy 39.223343 -357.838958) (xy 39.207977 -357.891291)
			(xy 39.18532 -357.940905) (xy 39.155832 -357.986789) (xy 39.120115 -358.02801) (xy 39.078895 -358.063728)
			(xy 39.033012 -358.093216) (xy 38.983399 -358.115875) (xy 38.931066 -358.131242) (xy 38.877079 -358.139005)
			(xy 38.849808 -358.139492) (xy 37.986208 -358.139492) (xy 37.958939 -358.138969) (xy 37.904955 -358.131209)
			(xy 37.852626 -358.115844) (xy 37.803015 -358.093189) (xy 37.757134 -358.063704) (xy 37.715917 -358.027989)
			(xy 37.680201 -357.986772) (xy 37.650715 -357.940892) (xy 37.628059 -357.891282) (xy 37.612693 -357.838953)
			(xy 37.604931 -357.784969) (xy 36.122106 -357.784969) (xy 36.114345 -357.838953) (xy 36.09898 -357.891283)
			(xy 36.076326 -357.940894) (xy 36.046842 -357.986776) (xy 36.011129 -358.027995) (xy 35.969914 -358.063713)
			(xy 35.924036 -358.093203) (xy 35.874428 -358.115864) (xy 35.8221 -358.131234) (xy 35.768117 -358.139002)
			(xy 35.740848 -358.139492) (xy 34.877248 -358.139492) (xy 34.849977 -358.138972) (xy 34.795989 -358.131216)
			(xy 34.743655 -358.115855) (xy 34.694039 -358.093202) (xy 34.648153 -358.063718) (xy 34.606931 -358.028003)
			(xy 34.571211 -357.986785) (xy 34.541721 -357.940903) (xy 34.519062 -357.89129) (xy 34.503694 -357.838958)
			(xy 34.495932 -357.784971) (xy 33.013228 -357.784971) (xy 33.013228 -357.784974) (xy 33.005465 -357.838966)
			(xy 32.990097 -357.891304) (xy 32.967437 -357.940921) (xy 32.937946 -357.986809) (xy 32.902224 -358.028033)
			(xy 32.861 -358.063753) (xy 32.815111 -358.093243) (xy 32.765492 -358.115901) (xy 32.713154 -358.131268)
			(xy 32.659162 -358.139029) (xy 32.631888 -358.139492) (xy 31.768288 -358.139492) (xy 31.741021 -358.138945)
			(xy 31.687043 -358.131182) (xy 31.634719 -358.115817) (xy 31.585115 -358.093162) (xy 31.539239 -358.063678)
			(xy 31.498026 -358.027966) (xy 31.462315 -357.986752) (xy 31.432832 -357.940875) (xy 31.410179 -357.891269)
			(xy 31.394815 -357.838945) (xy 31.387054 -357.784967) (xy 29.904206 -357.784967) (xy 29.904206 -357.78497)
			(xy 29.896444 -357.838956) (xy 29.881079 -357.891287) (xy 29.858423 -357.940899) (xy 29.828937 -357.986782)
			(xy 29.793222 -358.028003) (xy 29.752005 -358.063721) (xy 29.706124 -358.09321) (xy 29.656513 -358.115869)
			(xy 29.604183 -358.131238) (xy 29.550198 -358.139004) (xy 29.522928 -358.139492) (xy 28.659328 -358.139492)
			(xy 28.632058 -358.13897) (xy 28.578072 -358.131212) (xy 28.52574 -358.11585) (xy 28.476127 -358.093195)
			(xy 28.430244 -358.063711) (xy 28.389024 -358.027996) (xy 28.353306 -357.986779) (xy 28.323818 -357.940897)
			(xy 28.30116 -357.891286) (xy 28.285794 -357.838955) (xy 28.278031 -357.78497) (xy 26.795328 -357.78497)
			(xy 26.795328 -357.784975) (xy 26.787565 -357.838969) (xy 26.772196 -357.891308) (xy 26.749534 -357.940927)
			(xy 26.720041 -357.986816) (xy 26.684317 -358.02804) (xy 26.64309 -358.06376) (xy 26.597199 -358.093249)
			(xy 26.547578 -358.115907) (xy 26.495237 -358.131272) (xy 26.441243 -358.139031) (xy 26.413968 -358.139492)
			(xy 25.550368 -358.139492) (xy 25.523102 -358.138943) (xy 25.469126 -358.131179) (xy 25.416805 -358.115812)
			(xy 25.367203 -358.093156) (xy 25.321329 -358.063671) (xy 25.280119 -358.027959) (xy 25.24441 -357.986745)
			(xy 25.214929 -357.940869) (xy 25.192277 -357.891265) (xy 25.176914 -357.838942) (xy 25.169154 -357.784966)
			(xy 23.686306 -357.784966) (xy 23.686306 -357.784971) (xy 23.678543 -357.838958) (xy 23.663177 -357.891291)
			(xy 23.64052 -357.940905) (xy 23.611032 -357.986789) (xy 23.575315 -358.02801) (xy 23.534095 -358.063728)
			(xy 23.488212 -358.093216) (xy 23.438599 -358.115875) (xy 23.386266 -358.131242) (xy 23.332279 -358.139005)
			(xy 23.305008 -358.139492) (xy 22.441408 -358.139492) (xy 22.414139 -358.138969) (xy 22.360155 -358.131209)
			(xy 22.307826 -358.115844) (xy 22.258215 -358.093189) (xy 22.212334 -358.063704) (xy 22.171117 -358.027989)
			(xy 22.135401 -357.986772) (xy 22.105915 -357.940892) (xy 22.083259 -357.891282) (xy 22.067893 -357.838953)
			(xy 22.060131 -357.784969) (xy 0.529844 -357.784969) (xy 0.529844 -365.288322) (xy 2.818128 -365.288322)
			(xy 2.822199 -365.2327) (xy 2.834325 -365.178263) (xy 2.854248 -365.126172) (xy 2.881544 -365.077537)
			(xy 2.91563 -365.033394) (xy 2.955779 -364.994685) (xy 3.001137 -364.962234) (xy 3.050737 -364.936733)
			(xy 3.103521 -364.918726) (xy 3.158364 -364.908596) (xy 3.214098 -364.906559) (xy 3.269535 -364.912659)
			(xy 3.323492 -364.926765) (xy 3.374821 -364.948577) (xy 3.422427 -364.977631) (xy 3.465295 -365.013306)
			(xy 3.502512 -365.054843) (xy 3.533285 -365.101356) (xy 3.556957 -365.151853) (xy 3.573025 -365.20526)
			(xy 3.581145 -365.260436) (xy 3.581654 -365.288322) (xy 3.581145 -365.316208) (xy 3.573025 -365.371384)
			(xy 3.56676 -365.392208) (xy 7.202932 -365.392208) (xy 7.203418 -365.364957) (xy 7.211174 -365.311009)
			(xy 7.226529 -365.258714) (xy 7.249171 -365.209137) (xy 7.278637 -365.163287) (xy 7.314328 -365.122096)
			(xy 7.355519 -365.086405) (xy 7.401369 -365.056939) (xy 7.450946 -365.034297) (xy 7.503241 -365.018942)
			(xy 7.557189 -365.011186) (xy 7.611691 -365.011186) (xy 7.665639 -365.018942) (xy 7.717934 -365.034297)
			(xy 7.767511 -365.056939) (xy 7.813361 -365.086405) (xy 7.854552 -365.122096) (xy 7.890243 -365.163287)
			(xy 7.919709 -365.209137) (xy 7.942351 -365.258714) (xy 7.957706 -365.311009) (xy 7.965462 -365.364957)
			(xy 7.965948 -365.392208) (xy 7.965512 -365.418628) (xy 7.958226 -365.470963) (xy 7.94378 -365.521791)
			(xy 7.922453 -365.570135) (xy 7.894652 -365.61507) (xy 7.86091 -365.655735) (xy 7.821875 -365.691348)
			(xy 7.80034 -365.70666) (xy 7.788863 -365.715046) (xy 7.770739 -365.736932) (xy 7.759346 -365.762963)
			(xy 7.755566 -365.791126) (xy 7.759691 -365.819241) (xy 7.771402 -365.845131) (xy 7.789793 -365.866792)
			(xy 7.801356 -365.875062) (xy 7.823355 -365.890327) (xy 7.863301 -365.925982) (xy 7.897866 -365.966875)
			(xy 7.926371 -366.012201) (xy 7.948254 -366.061069) (xy 7.963087 -366.112518) (xy 7.970576 -366.165536)
			(xy 7.971028 -366.192308) (xy 7.970542 -366.219559) (xy 7.962786 -366.273507) (xy 7.947431 -366.325802)
			(xy 7.924789 -366.375379) (xy 7.895323 -366.421229) (xy 7.859632 -366.46242) (xy 7.818441 -366.498111)
			(xy 7.772591 -366.527577) (xy 7.723014 -366.550219) (xy 7.670719 -366.565574) (xy 7.616771 -366.57333)
			(xy 7.562269 -366.57333) (xy 7.508321 -366.565574) (xy 7.456026 -366.550219) (xy 7.406449 -366.527577)
			(xy 7.360599 -366.498111) (xy 7.319408 -366.46242) (xy 7.283717 -366.421229) (xy 7.254251 -366.375379)
			(xy 7.231609 -366.325802) (xy 7.216254 -366.273507) (xy 7.208498 -366.219559) (xy 7.208012 -366.192308)
			(xy 7.208434 -366.165887) (xy 7.215719 -366.11355) (xy 7.230165 -366.062722) (xy 7.251495 -366.014376)
			(xy 7.279298 -365.969441) (xy 7.313043 -365.928777) (xy 7.352082 -365.893166) (xy 7.37362 -365.877856)
			(xy 7.385086 -365.869453) (xy 7.403216 -365.847574) (xy 7.414615 -365.821545) (xy 7.418399 -365.793383)
			(xy 7.414275 -365.765268) (xy 7.402562 -365.739379) (xy 7.384168 -365.717721) (xy 7.372604 -365.709454)
			(xy 7.350584 -365.694217) (xy 7.31064 -365.658556) (xy 7.276077 -365.617658) (xy 7.247575 -365.572327)
			(xy 7.225695 -365.523455) (xy 7.210867 -365.472002) (xy 7.203382 -365.418981) (xy 7.202932 -365.392208)
			(xy 3.56676 -365.392208) (xy 3.556957 -365.424791) (xy 3.533285 -365.475288) (xy 3.502512 -365.521801)
			(xy 3.465295 -365.563338) (xy 3.422427 -365.599013) (xy 3.374821 -365.628067) (xy 3.323492 -365.649879)
			(xy 3.269535 -365.663985) (xy 3.214098 -365.670085) (xy 3.158364 -365.668048) (xy 3.103521 -365.657918)
			(xy 3.050737 -365.639911) (xy 3.001137 -365.61441) (xy 2.955779 -365.581959) (xy 2.91563 -365.54325)
			(xy 2.881544 -365.499107) (xy 2.854248 -365.450472) (xy 2.834325 -365.398381) (xy 2.822199 -365.343944)
			(xy 2.818128 -365.288322) (xy 0.529844 -365.288322) (xy 0.529844 -368.23269) (xy 5.613144 -368.23269)
			(xy 5.617215 -368.177068) (xy 5.629341 -368.122631) (xy 5.649264 -368.07054) (xy 5.67656 -368.021905)
			(xy 5.710646 -367.977762) (xy 5.750795 -367.939053) (xy 5.796153 -367.906602) (xy 5.845753 -367.881101)
			(xy 5.898537 -367.863094) (xy 5.95338 -367.852964) (xy 6.009114 -367.850927) (xy 6.064551 -367.857027)
			(xy 6.118508 -367.871133) (xy 6.169837 -367.892945) (xy 6.217443 -367.921999) (xy 6.260311 -367.957674)
			(xy 6.297528 -367.999211) (xy 6.328301 -368.045724) (xy 6.351973 -368.096221) (xy 6.368041 -368.149628)
			(xy 6.376161 -368.204804) (xy 6.37667 -368.23269) (xy 6.376161 -368.260576) (xy 6.368041 -368.315752)
			(xy 6.351973 -368.369159) (xy 6.328301 -368.419656) (xy 6.297528 -368.466169) (xy 6.260311 -368.507706)
			(xy 6.217443 -368.543381) (xy 6.169837 -368.572435) (xy 6.118508 -368.594247) (xy 6.064551 -368.608353)
			(xy 6.009114 -368.614453) (xy 5.95338 -368.612416) (xy 5.898537 -368.602286) (xy 5.845753 -368.584279)
			(xy 5.796153 -368.558778) (xy 5.750795 -368.526327) (xy 5.710646 -368.487618) (xy 5.67656 -368.443475)
			(xy 5.649264 -368.39484) (xy 5.629341 -368.342749) (xy 5.617215 -368.288312) (xy 5.613144 -368.23269)
			(xy 0.529844 -368.23269) (xy 0.529844 -368.990118) (xy 29.623774 -368.990118) (xy 29.627765 -368.927951)
			(xy 29.639674 -368.866804) (xy 29.659303 -368.807683) (xy 29.686332 -368.751557) (xy 29.720316 -368.699348)
			(xy 29.760698 -368.651913) (xy 29.806814 -368.610032) (xy 29.857906 -368.574392) (xy 29.913137 -368.545578)
			(xy 29.971599 -368.524064) (xy 30.032333 -368.510202) (xy 30.09434 -368.50422) (xy 30.156603 -368.506216)
			(xy 30.2181 -368.516159) (xy 30.277821 -368.533883) (xy 30.334784 -368.5591) (xy 30.388055 -368.591393)
			(xy 30.43676 -368.630233) (xy 30.480097 -368.674983) (xy 30.517357 -368.724907) (xy 30.547926 -368.779186)
			(xy 30.571304 -368.836929) (xy 30.587105 -368.897187) (xy 30.595071 -368.95897) (xy 30.59557 -368.990118)
			(xy 34.023816 -368.990118) (xy 34.027807 -368.927951) (xy 34.039716 -368.866804) (xy 34.059345 -368.807683)
			(xy 34.086374 -368.751557) (xy 34.120358 -368.699348) (xy 34.16074 -368.651913) (xy 34.206856 -368.610032)
			(xy 34.257948 -368.574392) (xy 34.313179 -368.545578) (xy 34.371641 -368.524064) (xy 34.432375 -368.510202)
			(xy 34.494382 -368.50422) (xy 34.556645 -368.506216) (xy 34.618142 -368.516159) (xy 34.677863 -368.533883)
			(xy 34.734826 -368.5591) (xy 34.788097 -368.591393) (xy 34.836802 -368.630233) (xy 34.880139 -368.674983)
			(xy 34.917399 -368.724907) (xy 34.947968 -368.779186) (xy 34.971346 -368.836929) (xy 34.987147 -368.897187)
			(xy 34.995113 -368.95897) (xy 34.995612 -368.990118) (xy 38.423858 -368.990118) (xy 38.427849 -368.927951)
			(xy 38.439758 -368.866804) (xy 38.459387 -368.807683) (xy 38.486416 -368.751557) (xy 38.5204 -368.699348)
			(xy 38.560782 -368.651913) (xy 38.606898 -368.610032) (xy 38.65799 -368.574392) (xy 38.713221 -368.545578)
			(xy 38.771683 -368.524064) (xy 38.832417 -368.510202) (xy 38.894424 -368.50422) (xy 38.956687 -368.506216)
			(xy 39.018184 -368.516159) (xy 39.077905 -368.533883) (xy 39.134868 -368.5591) (xy 39.188139 -368.591393)
			(xy 39.236844 -368.630233) (xy 39.280181 -368.674983) (xy 39.317441 -368.724907) (xy 39.34801 -368.779186)
			(xy 39.371388 -368.836929) (xy 39.387189 -368.897187) (xy 39.395155 -368.95897) (xy 39.395654 -368.990118)
			(xy 42.8239 -368.990118) (xy 42.827891 -368.927951) (xy 42.8398 -368.866804) (xy 42.859429 -368.807683)
			(xy 42.886458 -368.751557) (xy 42.920442 -368.699348) (xy 42.960824 -368.651913) (xy 43.00694 -368.610032)
			(xy 43.058032 -368.574392) (xy 43.113263 -368.545578) (xy 43.171725 -368.524064) (xy 43.232459 -368.510202)
			(xy 43.294466 -368.50422) (xy 43.356729 -368.506216) (xy 43.418226 -368.516159) (xy 43.477947 -368.533883)
			(xy 43.53491 -368.5591) (xy 43.588181 -368.591393) (xy 43.636886 -368.630233) (xy 43.680223 -368.674983)
			(xy 43.717483 -368.724907) (xy 43.748052 -368.779186) (xy 43.77143 -368.836929) (xy 43.787231 -368.897187)
			(xy 43.795197 -368.95897) (xy 43.795696 -368.990118) (xy 43.795197 -369.021266) (xy 43.787231 -369.083049)
			(xy 43.77143 -369.143307) (xy 43.748052 -369.20105) (xy 43.717483 -369.255329) (xy 43.680223 -369.305253)
			(xy 43.636886 -369.350003) (xy 43.588181 -369.388843) (xy 43.53491 -369.421136) (xy 43.477947 -369.446353)
			(xy 43.418226 -369.464077) (xy 43.356729 -369.47402) (xy 43.294466 -369.476016) (xy 43.232459 -369.470034)
			(xy 43.171725 -369.456172) (xy 43.113263 -369.434658) (xy 43.058032 -369.405844) (xy 43.00694 -369.370204)
			(xy 42.960824 -369.328323) (xy 42.920442 -369.280888) (xy 42.886458 -369.228679) (xy 42.859429 -369.172553)
			(xy 42.8398 -369.113432) (xy 42.827891 -369.052285) (xy 42.8239 -368.990118) (xy 39.395654 -368.990118)
			(xy 39.395155 -369.021266) (xy 39.387189 -369.083049) (xy 39.371388 -369.143307) (xy 39.34801 -369.20105)
			(xy 39.317441 -369.255329) (xy 39.280181 -369.305253) (xy 39.236844 -369.350003) (xy 39.188139 -369.388843)
			(xy 39.134868 -369.421136) (xy 39.077905 -369.446353) (xy 39.018184 -369.464077) (xy 38.956687 -369.47402)
			(xy 38.894424 -369.476016) (xy 38.832417 -369.470034) (xy 38.771683 -369.456172) (xy 38.713221 -369.434658)
			(xy 38.65799 -369.405844) (xy 38.606898 -369.370204) (xy 38.560782 -369.328323) (xy 38.5204 -369.280888)
			(xy 38.486416 -369.228679) (xy 38.459387 -369.172553) (xy 38.439758 -369.113432) (xy 38.427849 -369.052285)
			(xy 38.423858 -368.990118) (xy 34.995612 -368.990118) (xy 34.995113 -369.021266) (xy 34.987147 -369.083049)
			(xy 34.971346 -369.143307) (xy 34.947968 -369.20105) (xy 34.917399 -369.255329) (xy 34.880139 -369.305253)
			(xy 34.836802 -369.350003) (xy 34.788097 -369.388843) (xy 34.734826 -369.421136) (xy 34.677863 -369.446353)
			(xy 34.618142 -369.464077) (xy 34.556645 -369.47402) (xy 34.494382 -369.476016) (xy 34.432375 -369.470034)
			(xy 34.371641 -369.456172) (xy 34.313179 -369.434658) (xy 34.257948 -369.405844) (xy 34.206856 -369.370204)
			(xy 34.16074 -369.328323) (xy 34.120358 -369.280888) (xy 34.086374 -369.228679) (xy 34.059345 -369.172553)
			(xy 34.039716 -369.113432) (xy 34.027807 -369.052285) (xy 34.023816 -368.990118) (xy 30.59557 -368.990118)
			(xy 30.595071 -369.021266) (xy 30.587105 -369.083049) (xy 30.571304 -369.143307) (xy 30.547926 -369.20105)
			(xy 30.517357 -369.255329) (xy 30.480097 -369.305253) (xy 30.43676 -369.350003) (xy 30.388055 -369.388843)
			(xy 30.334784 -369.421136) (xy 30.277821 -369.446353) (xy 30.2181 -369.464077) (xy 30.156603 -369.47402)
			(xy 30.09434 -369.476016) (xy 30.032333 -369.470034) (xy 29.971599 -369.456172) (xy 29.913137 -369.434658)
			(xy 29.857906 -369.405844) (xy 29.806814 -369.370204) (xy 29.760698 -369.328323) (xy 29.720316 -369.280888)
			(xy 29.686332 -369.228679) (xy 29.659303 -369.172553) (xy 29.639674 -369.113432) (xy 29.627765 -369.052285)
			(xy 29.623774 -368.990118) (xy 0.529844 -368.990118) (xy 0.529844 -372.100847) (xy 8.642336 -372.100847)
			(xy 8.642336 -372.040913) (xy 8.650159 -371.981491) (xy 8.665671 -371.923598) (xy 8.688607 -371.868226)
			(xy 8.718575 -371.81632) (xy 8.755061 -371.768771) (xy 8.797441 -371.726391) (xy 8.84499 -371.689905)
			(xy 8.896896 -371.659937) (xy 8.952268 -371.637001) (xy 9.010161 -371.621489) (xy 9.069583 -371.613666)
			(xy 9.09955 -371.613176) (xy 9.96315 -371.613176) (xy 9.993118 -371.613658) (xy 10.052541 -371.621481)
			(xy 10.110435 -371.636994) (xy 10.165808 -371.65993) (xy 10.217714 -371.689898) (xy 10.265264 -371.726385)
			(xy 10.307645 -371.768766) (xy 10.324103 -371.790214) (xy 27.42438 -371.790214) (xy 27.424932 -371.757484)
			(xy 27.433792 -371.692625) (xy 27.451287 -371.629545) (xy 27.477098 -371.569388) (xy 27.493468 -371.54104)
			(xy 27.496766 -371.535007) (xy 27.500382 -371.52175) (xy 27.50058 -371.514878) (xy 27.50058 -370.765324)
			(xy 27.500381 -370.758451) (xy 27.496778 -370.745188) (xy 27.493468 -370.739162) (xy 27.477094 -370.710817)
			(xy 27.451293 -370.650657) (xy 27.433805 -370.587576) (xy 27.424948 -370.522717) (xy 27.42438 -370.489988)
			(xy 27.424966 -370.457259) (xy 27.433816 -370.392402) (xy 27.451301 -370.329322) (xy 27.477102 -370.269163)
			(xy 27.493468 -370.240814) (xy 27.496775 -370.234786) (xy 27.500386 -370.221525) (xy 27.50058 -370.214652)
			(xy 27.50058 -369.928902) (xy 27.501029 -369.918771) (xy 27.508764 -369.900042) (xy 27.523062 -369.885684)
			(xy 27.541759 -369.877872) (xy 27.551888 -369.87734) (xy 28.268168 -369.87734) (xy 28.278325 -369.877748)
			(xy 28.297085 -369.885541) (xy 28.311411 -369.899943) (xy 28.319104 -369.918743) (xy 28.319476 -369.928902)
			(xy 28.319476 -370.214652) (xy 28.319689 -370.221524) (xy 28.323283 -370.234786) (xy 28.326588 -370.240814)
			(xy 28.342958 -370.269161) (xy 28.368759 -370.329321) (xy 28.386247 -370.392401) (xy 28.395106 -370.457259)
			(xy 28.395676 -370.489988) (xy 28.39513 -370.522709) (xy 31.825015 -370.522709) (xy 31.825017 -370.457271)
			(xy 31.833802 -370.392425) (xy 31.851212 -370.329346) (xy 31.876932 -370.269175) (xy 31.893256 -370.240814)
			(xy 31.896562 -370.234785) (xy 31.900174 -370.221525) (xy 31.900368 -370.214652) (xy 31.900368 -369.928902)
			(xy 31.900766 -369.918727) (xy 31.908556 -369.899926) (xy 31.92295 -369.88554) (xy 31.941755 -369.877761)
			(xy 31.95193 -369.87734) (xy 32.66821 -369.87734) (xy 32.678369 -369.877825) (xy 32.697138 -369.885603)
			(xy 32.711503 -369.899972) (xy 32.719277 -369.918743) (xy 32.719772 -369.928902) (xy 32.719772 -370.214652)
			(xy 32.719986 -370.221524) (xy 32.723579 -370.234786) (xy 32.726884 -370.240814) (xy 32.743195 -370.269181)
			(xy 32.768913 -370.329351) (xy 32.786321 -370.392429) (xy 32.795105 -370.457272) (xy 32.795107 -370.522708)
			(xy 32.786325 -370.587551) (xy 32.76892 -370.650629) (xy 32.743205 -370.710801) (xy 32.726884 -370.739162)
			(xy 32.723582 -370.745193) (xy 32.719968 -370.758452) (xy 32.719772 -370.765324) (xy 32.719772 -371.514878)
			(xy 32.719976 -371.52175) (xy 32.723576 -371.535013) (xy 32.726884 -371.54104) (xy 32.743217 -371.569395)
			(xy 32.768933 -371.629568) (xy 32.786339 -371.692648) (xy 32.79512 -371.757493) (xy 32.795119 -371.822931)
			(xy 32.786334 -371.887776) (xy 32.768925 -371.950855) (xy 32.743206 -372.011026) (xy 32.726884 -372.039388)
			(xy 32.723572 -372.045414) (xy 32.719965 -372.058677) (xy 32.719772 -372.06555) (xy 32.719772 -372.351554)
			(xy 32.719299 -372.361721) (xy 32.711531 -372.380513) (xy 32.69716 -372.394899) (xy 32.678377 -372.402688)
			(xy 32.66821 -372.403116) (xy 31.95193 -372.403116) (xy 31.941755 -372.40271) (xy 31.922952 -372.394927)
			(xy 31.908564 -372.380535) (xy 31.900787 -372.361729) (xy 31.900368 -372.351554) (xy 31.900368 -372.06555)
			(xy 31.900161 -372.058678) (xy 31.896563 -372.045415) (xy 31.893256 -372.039388) (xy 31.876945 -372.01102)
			(xy 31.851225 -371.950851) (xy 31.833815 -371.887774) (xy 31.82503 -371.82293) (xy 31.825028 -371.757494)
			(xy 31.833811 -371.69265) (xy 31.851218 -371.629572) (xy 31.876934 -371.569401) (xy 31.893256 -371.54104)
			(xy 31.896553 -371.535007) (xy 31.90017 -371.52175) (xy 31.900368 -371.514878) (xy 31.900368 -370.765324)
			(xy 31.900171 -370.758451) (xy 31.896567 -370.745188) (xy 31.893256 -370.739162) (xy 31.876923 -370.710807)
			(xy 31.851206 -370.650634) (xy 31.833798 -370.587554) (xy 31.825015 -370.522709) (xy 28.39513 -370.522709)
			(xy 28.39513 -370.522718) (xy 28.386269 -370.587577) (xy 28.368773 -370.650658) (xy 28.342959 -370.710815)
			(xy 28.326588 -370.739162) (xy 28.323286 -370.745193) (xy 28.319673 -370.758452) (xy 28.319476 -370.765324)
			(xy 28.319476 -371.514878) (xy 28.319679 -371.52175) (xy 28.32328 -371.535013) (xy 28.326588 -371.54104)
			(xy 28.342968 -371.569381) (xy 28.365869 -371.622787) (xy 29.624859 -371.622787) (xy 29.624864 -371.557348)
			(xy 29.633651 -371.492502) (xy 29.651063 -371.429422) (xy 29.676784 -371.36925) (xy 29.693108 -371.340888)
			(xy 29.696428 -371.334866) (xy 29.70003 -371.3216) (xy 29.70022 -371.314726) (xy 29.70022 -371.028722)
			(xy 29.700682 -371.018554) (xy 29.708456 -370.999763) (xy 29.72283 -370.985378) (xy 29.741614 -370.97759)
			(xy 29.751782 -370.97716) (xy 30.468062 -370.97716) (xy 30.478234 -370.977596) (xy 30.497032 -370.985372)
			(xy 30.511419 -370.999755) (xy 30.519201 -371.01855) (xy 30.519624 -371.028722) (xy 30.519624 -371.314726)
			(xy 30.519803 -371.3216) (xy 30.52342 -371.334863) (xy 30.526736 -371.340888) (xy 30.543027 -371.369267)
			(xy 30.568749 -371.429434) (xy 30.586161 -371.492509) (xy 30.594949 -371.55735) (xy 30.594954 -371.622785)
			(xy 30.586174 -371.687627) (xy 30.56877 -371.750705) (xy 30.543056 -371.810875) (xy 30.526736 -371.839236)
			(xy 30.523411 -371.845256) (xy 30.519812 -371.858523) (xy 30.519624 -371.865398) (xy 30.519624 -372.614698)
			(xy 30.519814 -372.621571) (xy 30.523423 -372.634834) (xy 30.526736 -372.64086) (xy 30.543088 -372.669205)
			(xy 30.568804 -372.72938) (xy 30.58621 -372.792462) (xy 30.59499 -372.857309) (xy 30.594988 -372.890034)
			(xy 34.024316 -372.890034) (xy 34.024873 -372.857304) (xy 34.033731 -372.792445) (xy 34.051224 -372.729365)
			(xy 34.077034 -372.669208) (xy 34.093404 -372.64086) (xy 34.096733 -372.634842) (xy 34.10033 -372.621573)
			(xy 34.100516 -372.614698) (xy 34.100516 -371.865398) (xy 34.100323 -371.858525) (xy 34.096715 -371.845262)
			(xy 34.093404 -371.839236) (xy 34.077053 -371.810879) (xy 34.051248 -371.750722) (xy 34.033754 -371.687645)
			(xy 34.024889 -371.62279) (xy 34.024316 -371.590062) (xy 34.024885 -371.557333) (xy 34.033739 -371.492474)
			(xy 34.051229 -371.429394) (xy 34.077036 -371.369236) (xy 34.093404 -371.340888) (xy 34.096723 -371.334866)
			(xy 34.100326 -371.3216) (xy 34.100516 -371.314726) (xy 34.100516 -371.028722) (xy 34.101044 -371.0186)
			(xy 34.10876 -370.999883) (xy 34.123033 -370.985527) (xy 34.141705 -370.977703) (xy 34.151824 -370.97716)
			(xy 34.868104 -370.97716) (xy 34.878253 -370.977618) (xy 34.896998 -370.985407) (xy 34.91132 -370.999792)
			(xy 34.919027 -371.018571) (xy 34.919412 -371.028722) (xy 34.919412 -371.314726) (xy 34.919592 -371.3216)
			(xy 34.923208 -371.334863) (xy 34.926524 -371.340888) (xy 34.942887 -371.369239) (xy 34.968689 -371.429398)
			(xy 34.986179 -371.492477) (xy 34.995041 -371.557333) (xy 34.995612 -371.590062) (xy 34.99505 -371.622792)
			(xy 34.986193 -371.68765) (xy 34.968701 -371.75073) (xy 34.951762 -371.790214) (xy 36.224464 -371.790214)
			(xy 36.225018 -371.757484) (xy 36.233878 -371.692626) (xy 36.251372 -371.629546) (xy 36.277182 -371.569388)
			(xy 36.293552 -371.54104) (xy 36.296849 -371.535006) (xy 36.300466 -371.52175) (xy 36.300664 -371.514878)
			(xy 36.300664 -370.765324) (xy 36.300467 -370.758451) (xy 36.296863 -370.745188) (xy 36.293552 -370.739162)
			(xy 36.277176 -370.710818) (xy 36.251376 -370.650657) (xy 36.233889 -370.587576) (xy 36.225032 -370.522718)
			(xy 36.224464 -370.489988) (xy 36.225052 -370.457259) (xy 36.233902 -370.392402) (xy 36.251386 -370.329322)
			(xy 36.277187 -370.269163) (xy 36.293552 -370.240814) (xy 36.296858 -370.234785) (xy 36.30047 -370.221525)
			(xy 36.300664 -370.214652) (xy 36.300664 -369.928902) (xy 36.301129 -369.918772) (xy 36.308861 -369.900047)
			(xy 36.323154 -369.88569) (xy 36.341845 -369.877875) (xy 36.351972 -369.87734) (xy 37.068252 -369.87734)
			(xy 37.078408 -369.877762) (xy 37.097167 -369.885549) (xy 37.111494 -369.899947) (xy 37.119188 -369.918744)
			(xy 37.11956 -369.928902) (xy 37.11956 -370.214652) (xy 37.119775 -370.221523) (xy 37.123368 -370.234786)
			(xy 37.126672 -370.240814) (xy 37.14304 -370.269162) (xy 37.168842 -370.329322) (xy 37.186331 -370.392402)
			(xy 37.19519 -370.457259) (xy 37.19576 -370.489988) (xy 37.195203 -370.522718) (xy 37.186343 -370.587576)
			(xy 37.16885 -370.650656) (xy 37.143041 -370.710814) (xy 37.126672 -370.739162) (xy 37.123369 -370.745192)
			(xy 37.119756 -370.758452) (xy 37.11956 -370.765324) (xy 37.11956 -371.514878) (xy 37.119765 -371.52175)
			(xy 37.123365 -371.535013) (xy 37.126672 -371.54104) (xy 37.143051 -371.569382) (xy 37.165952 -371.622787)
			(xy 38.424945 -371.622787) (xy 38.42495 -371.557348) (xy 38.433737 -371.492502) (xy 38.451148 -371.429422)
			(xy 38.476869 -371.36925) (xy 38.493192 -371.340888) (xy 38.49651 -371.334865) (xy 38.500114 -371.3216)
			(xy 38.500304 -371.314726) (xy 38.500304 -371.028722) (xy 38.50085 -371.01857) (xy 38.508611 -370.999808)
			(xy 38.522961 -370.985443) (xy 38.541714 -370.977661) (xy 38.551866 -370.97716) (xy 39.268146 -370.97716)
			(xy 39.278309 -370.977596) (xy 39.297084 -370.98539) (xy 39.311448 -370.999773) (xy 39.319217 -371.018558)
			(xy 39.319708 -371.028722) (xy 39.319708 -371.314726) (xy 39.319889 -371.3216) (xy 39.323504 -371.334863)
			(xy 39.32682 -371.340888) (xy 39.343111 -371.369267) (xy 39.368834 -371.429433) (xy 39.386247 -371.492508)
			(xy 39.395036 -371.55735) (xy 39.39504 -371.622785) (xy 39.38626 -371.687628) (xy 39.368856 -371.750705)
			(xy 39.351971 -371.790214) (xy 40.624252 -371.790214) (xy 40.624808 -371.757484) (xy 40.633668 -371.692626)
			(xy 40.651161 -371.629546) (xy 40.67697 -371.569388) (xy 40.69334 -371.54104) (xy 40.696636 -371.535006)
			(xy 40.700254 -371.52175) (xy 40.700452 -371.514878) (xy 40.700452 -370.765324) (xy 40.700257 -370.758451)
			(xy 40.696651 -370.745188) (xy 40.69334 -370.739162) (xy 40.676963 -370.710819) (xy 40.651163 -370.650657)
			(xy 40.633676 -370.587576) (xy 40.62482 -370.522718) (xy 40.624252 -370.489988) (xy 40.624841 -370.457259)
			(xy 40.633691 -370.392402) (xy 40.651174 -370.329322) (xy 40.676975 -370.269163) (xy 40.69334 -370.240814)
			(xy 40.696645 -370.234785) (xy 40.700258 -370.221525) (xy 40.700452 -370.214652) (xy 40.700452 -369.928902)
			(xy 40.700929 -369.918774) (xy 40.708658 -369.900051) (xy 40.722947 -369.885694) (xy 40.741634 -369.877877)
			(xy 40.75176 -369.87734) (xy 41.46804 -369.87734) (xy 41.478202 -369.87769) (xy 41.496963 -369.885506)
			(xy 41.511286 -369.899925) (xy 41.518977 -369.918738) (xy 41.519348 -369.928902) (xy 41.519348 -370.214652)
			(xy 41.519552 -370.221524) (xy 41.523151 -370.234787) (xy 41.52646 -370.240814) (xy 41.542827 -370.269162)
			(xy 41.56863 -370.329322) (xy 41.586119 -370.392402) (xy 41.594978 -370.457259) (xy 41.595548 -370.489988)
			(xy 41.594993 -370.522718) (xy 41.586133 -370.587576) (xy 41.568639 -370.650656) (xy 41.54283 -370.710814)
			(xy 41.52646 -370.739162) (xy 41.523163 -370.745196) (xy 41.519546 -370.758452) (xy 41.519348 -370.765324)
			(xy 41.519348 -371.514878) (xy 41.519542 -371.521751) (xy 41.523148 -371.535014) (xy 41.52646 -371.54104)
			(xy 41.542838 -371.569383) (xy 41.568637 -371.629544) (xy 41.586124 -371.692626) (xy 41.59498 -371.757484)
			(xy 41.595548 -371.790214) (xy 41.59496 -371.822943) (xy 41.58611 -371.8878) (xy 41.568626 -371.95088)
			(xy 41.542825 -372.011039) (xy 41.52646 -372.039388) (xy 41.523154 -372.045417) (xy 41.519542 -372.058677)
			(xy 41.519348 -372.06555) (xy 41.519348 -372.351554) (xy 41.518835 -372.361679) (xy 41.51112 -372.380402)
			(xy 41.496842 -372.39476) (xy 41.478162 -372.402579) (xy 41.46804 -372.403116) (xy 40.75176 -372.403116)
			(xy 40.741605 -372.402711) (xy 40.722855 -372.394906) (xy 40.708534 -372.380504) (xy 40.700833 -372.361711)
			(xy 40.700452 -372.351554) (xy 40.700452 -372.06555) (xy 40.700247 -372.058678) (xy 40.696648 -372.045415)
			(xy 40.69334 -372.039388) (xy 40.676973 -372.011039) (xy 40.651171 -371.95088) (xy 40.633681 -371.8878)
			(xy 40.624822 -371.822943) (xy 40.624252 -371.790214) (xy 39.351971 -371.790214) (xy 39.343141 -371.810875)
			(xy 39.32682 -371.839236) (xy 39.323494 -371.845255) (xy 39.319895 -371.858523) (xy 39.319708 -371.865398)
			(xy 39.319708 -372.614698) (xy 39.319899 -372.621571) (xy 39.323508 -372.634834) (xy 39.32682 -372.64086)
			(xy 39.343172 -372.669205) (xy 39.368889 -372.729379) (xy 39.386296 -372.792462) (xy 39.395077 -372.857309)
			(xy 39.395075 -372.890034) (xy 42.8244 -372.890034) (xy 42.824959 -372.857304) (xy 42.833817 -372.792446)
			(xy 42.851309 -372.729366) (xy 42.877119 -372.669208) (xy 42.893488 -372.64086) (xy 42.896816 -372.634842)
			(xy 42.900414 -372.621573) (xy 42.9006 -372.614698) (xy 42.9006 -371.865398) (xy 42.900409 -371.858525)
			(xy 42.8968 -371.845262) (xy 42.893488 -371.839236) (xy 42.877136 -371.81088) (xy 42.851331 -371.750723)
			(xy 42.833838 -371.687645) (xy 42.824973 -371.62279) (xy 42.8244 -371.590062) (xy 42.824971 -371.557333)
			(xy 42.833825 -371.492475) (xy 42.851314 -371.429394) (xy 42.87712 -371.369236) (xy 42.893488 -371.340888)
			(xy 42.896806 -371.334865) (xy 42.90041 -371.3216) (xy 42.9006 -371.314726) (xy 42.9006 -371.028722)
			(xy 42.901143 -371.018602) (xy 42.908856 -370.999888) (xy 42.923125 -370.985533) (xy 42.941791 -370.977706)
			(xy 42.951908 -370.97716) (xy 43.668188 -370.97716) (xy 43.678336 -370.977631) (xy 43.697081 -370.985415)
			(xy 43.711403 -370.999796) (xy 43.71911 -371.018572) (xy 43.719496 -371.028722) (xy 43.719496 -371.314726)
			(xy 43.719678 -371.3216) (xy 43.723293 -371.334863) (xy 43.726608 -371.340888) (xy 43.74297 -371.369239)
			(xy 43.768772 -371.429398) (xy 43.786263 -371.492477) (xy 43.795125 -371.557333) (xy 43.795696 -371.590062)
			(xy 43.795136 -371.622792) (xy 43.786279 -371.68765) (xy 43.768787 -371.75073) (xy 43.742977 -371.810888)
			(xy 43.726608 -371.839236) (xy 43.723281 -371.845255) (xy 43.719683 -371.858523) (xy 43.719496 -371.865398)
			(xy 43.719496 -372.614698) (xy 43.719689 -372.621571) (xy 43.723296 -372.634834) (xy 43.726608 -372.64086)
			(xy 43.742958 -372.669218) (xy 43.768764 -372.729374) (xy 43.786258 -372.792451) (xy 43.795123 -372.857306)
			(xy 43.795696 -372.890034) (xy 43.795124 -372.922763) (xy 43.78627 -372.987621) (xy 43.768781 -373.050701)
			(xy 43.742976 -373.11086) (xy 43.726608 -373.139208) (xy 43.723291 -373.145232) (xy 43.719687 -373.158496)
			(xy 43.719496 -373.16537) (xy 43.719496 -373.451374) (xy 43.718953 -373.461495) (xy 43.711241 -373.480208)
			(xy 43.696972 -373.494564) (xy 43.678306 -373.502391) (xy 43.668188 -373.502936) (xy 42.951908 -373.502936)
			(xy 42.941759 -373.502473) (xy 42.923014 -373.494686) (xy 42.908691 -373.480303) (xy 42.900985 -373.461525)
			(xy 42.9006 -373.451374) (xy 42.9006 -373.16537) (xy 42.90042 -373.158496) (xy 42.896804 -373.145233)
			(xy 42.893488 -373.139208) (xy 42.877124 -373.110858) (xy 42.851322 -373.050698) (xy 42.833832 -372.987619)
			(xy 42.824971 -372.922763) (xy 42.8244 -372.890034) (xy 39.395075 -372.890034) (xy 39.395073 -372.922749)
			(xy 39.386284 -372.987596) (xy 39.36887 -373.050676) (xy 39.343146 -373.110847) (xy 39.32682 -373.139208)
			(xy 39.323504 -373.145232) (xy 39.319899 -373.158496) (xy 39.319708 -373.16537) (xy 39.319708 -373.451374)
			(xy 39.319147 -373.461525) (xy 39.311389 -373.480284) (xy 39.297045 -373.494649) (xy 39.278296 -373.502432)
			(xy 39.268146 -373.502936) (xy 38.551866 -373.502936) (xy 38.541703 -373.502494) (xy 38.522928 -373.494703)
			(xy 38.508563 -373.480322) (xy 38.500794 -373.461538) (xy 38.500304 -373.451374) (xy 38.500304 -373.16537)
			(xy 38.500123 -373.158496) (xy 38.496507 -373.145233) (xy 38.493192 -373.139208) (xy 38.4769 -373.11083)
			(xy 38.451182 -373.050662) (xy 38.433773 -372.987587) (xy 38.424986 -372.922746) (xy 38.424982 -372.857312)
			(xy 38.433761 -372.79247) (xy 38.451163 -372.729393) (xy 38.476873 -372.669222) (xy 38.493192 -372.64086)
			(xy 38.49652 -372.634842) (xy 38.500118 -372.621573) (xy 38.500304 -372.614698) (xy 38.500304 -371.865398)
			(xy 38.500112 -371.858525) (xy 38.496504 -371.845262) (xy 38.493192 -371.839236) (xy 38.476839 -371.810892)
			(xy 38.451127 -371.750716) (xy 38.433724 -371.687634) (xy 38.424945 -371.622787) (xy 37.165952 -371.622787)
			(xy 37.16885 -371.629544) (xy 37.186336 -371.692626) (xy 37.195192 -371.757484) (xy 37.19576 -371.790214)
			(xy 37.19517 -371.822943) (xy 37.18632 -371.8878) (xy 37.168837 -371.95088) (xy 37.143037 -372.011039)
			(xy 37.126672 -372.039388) (xy 37.12336 -372.045414) (xy 37.119753 -372.058677) (xy 37.11956 -372.06555)
			(xy 37.11956 -372.351554) (xy 37.119036 -372.361678) (xy 37.111323 -372.380398) (xy 37.097048 -372.394756)
			(xy 37.078373 -372.402576) (xy 37.068252 -372.403116) (xy 36.351972 -372.403116) (xy 36.341818 -372.402702)
			(xy 36.323068 -372.3949) (xy 36.308746 -372.380501) (xy 36.301045 -372.36171) (xy 36.300664 -372.351554)
			(xy 36.300664 -372.06555) (xy 36.300457 -372.058678) (xy 36.29686 -372.045415) (xy 36.293552 -372.039388)
			(xy 36.277187 -372.011039) (xy 36.251384 -371.950879) (xy 36.233894 -371.8878) (xy 36.225034 -371.822943)
			(xy 36.224464 -371.790214) (xy 34.951762 -371.790214) (xy 34.942893 -371.810888) (xy 34.926524 -371.839236)
			(xy 34.923198 -371.845255) (xy 34.919599 -371.858523) (xy 34.919412 -371.865398) (xy 34.919412 -372.614698)
			(xy 34.919603 -372.621571) (xy 34.923212 -372.634834) (xy 34.926524 -372.64086) (xy 34.942876 -372.669217)
			(xy 34.968681 -372.729374) (xy 34.986174 -372.792451) (xy 34.995039 -372.857306) (xy 34.995612 -372.890034)
			(xy 34.995037 -372.922763) (xy 34.986184 -372.987621) (xy 34.968696 -373.050701) (xy 34.942891 -373.11086)
			(xy 34.926524 -373.139208) (xy 34.923208 -373.145232) (xy 34.919603 -373.158496) (xy 34.919412 -373.16537)
			(xy 34.919412 -373.451374) (xy 34.918854 -373.461493) (xy 34.911144 -373.480203) (xy 34.89688 -373.494559)
			(xy 34.878219 -373.502388) (xy 34.868104 -373.502936) (xy 34.151824 -373.502936) (xy 34.141676 -373.50246)
			(xy 34.122931 -373.494679) (xy 34.108608 -373.480299) (xy 34.100901 -373.461524) (xy 34.100516 -373.451374)
			(xy 34.100516 -373.16537) (xy 34.100333 -373.158496) (xy 34.096719 -373.145233) (xy 34.093404 -373.139208)
			(xy 34.077042 -373.110857) (xy 34.051239 -373.050698) (xy 34.033749 -372.987619) (xy 34.024887 -372.922763)
			(xy 34.024316 -372.890034) (xy 30.594988 -372.890034) (xy 30.594986 -372.922749) (xy 30.586198 -372.987595)
			(xy 30.568785 -373.050675) (xy 30.543061 -373.110847) (xy 30.526736 -373.139208) (xy 30.523421 -373.145233)
			(xy 30.519815 -373.158496) (xy 30.519624 -373.16537) (xy 30.519624 -373.451374) (xy 30.519214 -373.461549)
			(xy 30.51143 -373.48035) (xy 30.49704 -373.494737) (xy 30.478237 -373.502516) (xy 30.468062 -373.502936)
			(xy 29.751782 -373.502936) (xy 29.741606 -373.50255) (xy 29.722806 -373.494754) (xy 29.708421 -373.480357)
			(xy 29.700641 -373.46155) (xy 29.70022 -373.451374) (xy 29.70022 -373.16537) (xy 29.700037 -373.158496)
			(xy 29.696422 -373.145233) (xy 29.693108 -373.139208) (xy 29.676816 -373.110831) (xy 29.651097 -373.050663)
			(xy 29.633687 -372.987588) (xy 29.6249 -372.922746) (xy 29.624896 -372.857312) (xy 29.633675 -372.79247)
			(xy 29.651078 -372.729392) (xy 29.676789 -372.669222) (xy 29.693108 -372.64086) (xy 29.696438 -372.634843)
			(xy 29.700034 -372.621573) (xy 29.70022 -372.614698) (xy 29.70022 -371.865398) (xy 29.700026 -371.858525)
			(xy 29.696419 -371.845262) (xy 29.693108 -371.839236) (xy 29.676755 -371.810892) (xy 29.651042 -371.750717)
			(xy 29.633638 -371.687634) (xy 29.624859 -371.622787) (xy 28.365869 -371.622787) (xy 28.368767 -371.629544)
			(xy 28.386252 -371.692626) (xy 28.395108 -371.757484) (xy 28.395676 -371.790214) (xy 28.395097 -371.822943)
			(xy 28.386246 -371.887801) (xy 28.368759 -371.950881) (xy 28.342955 -372.01104) (xy 28.326588 -372.039388)
			(xy 28.323277 -372.045414) (xy 28.319669 -372.058677) (xy 28.319476 -372.06555) (xy 28.319476 -372.351554)
			(xy 28.318936 -372.361676) (xy 28.311226 -372.380393) (xy 28.296956 -372.39475) (xy 28.278287 -372.402574)
			(xy 28.268168 -372.403116) (xy 27.551888 -372.403116) (xy 27.541735 -372.402689) (xy 27.522985 -372.394892)
			(xy 27.508663 -372.380498) (xy 27.500961 -372.361709) (xy 27.50058 -372.351554) (xy 27.50058 -372.06555)
			(xy 27.500371 -372.058678) (xy 27.496775 -372.045415) (xy 27.493468 -372.039388) (xy 27.477104 -372.011038)
			(xy 27.4513 -371.950879) (xy 27.43381 -371.8878) (xy 27.42495 -371.822943) (xy 27.42438 -371.790214)
			(xy 10.324103 -371.790214) (xy 10.344132 -371.816316) (xy 10.3741 -371.868222) (xy 10.397036 -371.923595)
			(xy 10.412549 -371.981489) (xy 10.420372 -372.040912) (xy 10.420372 -372.100848) (xy 10.412549 -372.160271)
			(xy 10.397036 -372.218165) (xy 10.3741 -372.273538) (xy 10.344132 -372.325444) (xy 10.307645 -372.372994)
			(xy 10.265264 -372.415375) (xy 10.217714 -372.451862) (xy 10.165808 -372.48183) (xy 10.110435 -372.504766)
			(xy 10.052541 -372.520279) (xy 9.993118 -372.528102) (xy 9.96315 -372.528592) (xy 9.09955 -372.528592)
			(xy 9.069583 -372.528094) (xy 9.010161 -372.520271) (xy 8.952268 -372.504759) (xy 8.896896 -372.481823)
			(xy 8.84499 -372.451855) (xy 8.797441 -372.415369) (xy 8.755061 -372.372989) (xy 8.718575 -372.32544)
			(xy 8.688607 -372.273534) (xy 8.665671 -372.218162) (xy 8.650159 -372.160269) (xy 8.642336 -372.100847)
			(xy 0.529844 -372.100847) (xy 0.529844 -372.921784) (xy 3.759198 -372.921784) (xy 3.763269 -372.866162)
			(xy 3.775395 -372.811725) (xy 3.795318 -372.759634) (xy 3.822614 -372.710999) (xy 3.8567 -372.666856)
			(xy 3.896849 -372.628147) (xy 3.942207 -372.595696) (xy 3.991807 -372.570195) (xy 4.044591 -372.552188)
			(xy 4.099434 -372.542058) (xy 4.155168 -372.540021) (xy 4.210605 -372.546121) (xy 4.264562 -372.560227)
			(xy 4.315891 -372.582039) (xy 4.363497 -372.611093) (xy 4.406365 -372.646768) (xy 4.443582 -372.688305)
			(xy 4.474355 -372.734818) (xy 4.498027 -372.785315) (xy 4.514095 -372.838722) (xy 4.522215 -372.893898)
			(xy 4.522724 -372.921784) (xy 4.522215 -372.94967) (xy 4.514095 -373.004846) (xy 4.498027 -373.058253)
			(xy 4.474355 -373.10875) (xy 4.443582 -373.155263) (xy 4.406365 -373.1968) (xy 4.363497 -373.232475)
			(xy 4.315891 -373.261529) (xy 4.264562 -373.283341) (xy 4.210605 -373.297447) (xy 4.155168 -373.303547)
			(xy 4.099434 -373.30151) (xy 4.044591 -373.29138) (xy 3.991807 -373.273373) (xy 3.942207 -373.247872)
			(xy 3.896849 -373.215421) (xy 3.8567 -373.176712) (xy 3.822614 -373.132569) (xy 3.795318 -373.083934)
			(xy 3.775395 -373.031843) (xy 3.763269 -372.977406) (xy 3.759198 -372.921784) (xy 0.529844 -372.921784)
			(xy 0.529844 -375.69013) (xy 27.42438 -375.69013) (xy 27.424939 -375.6574) (xy 27.433797 -375.592542)
			(xy 27.45129 -375.529462) (xy 27.477099 -375.469304) (xy 27.493468 -375.440956) (xy 27.496796 -375.434938)
			(xy 27.500393 -375.421669) (xy 27.50058 -375.414794) (xy 27.50058 -374.665494) (xy 27.500393 -374.65862)
			(xy 27.496781 -374.645358) (xy 27.493468 -374.639332) (xy 27.477122 -374.610972) (xy 27.451314 -374.550817)
			(xy 27.433818 -374.487741) (xy 27.424953 -374.422886) (xy 27.42438 -374.390158) (xy 27.424952 -374.357429)
			(xy 27.433807 -374.292571) (xy 27.451295 -374.229491) (xy 27.477101 -374.169332) (xy 27.493468 -374.140984)
			(xy 27.496786 -374.134961) (xy 27.50039 -374.121696) (xy 27.50058 -374.114822) (xy 27.50058 -373.828818)
			(xy 27.501042 -373.818688) (xy 27.508772 -373.799959) (xy 27.523066 -373.785601) (xy 27.54176 -373.777788)
			(xy 27.551888 -373.777256) (xy 28.268168 -373.777256) (xy 28.278315 -373.777747) (xy 28.297058 -373.785523)
			(xy 28.311381 -373.799899) (xy 28.31909 -373.81867) (xy 28.319476 -373.828818) (xy 28.319476 -374.114822)
			(xy 28.319663 -374.121696) (xy 28.323275 -374.134958) (xy 28.326588 -374.140984) (xy 28.342946 -374.169337)
			(xy 28.36875 -374.229495) (xy 28.386242 -374.292574) (xy 28.395104 -374.357429) (xy 28.395676 -374.390158)
			(xy 28.395117 -374.422884) (xy 31.824998 -374.422884) (xy 31.825003 -374.357444) (xy 31.833792 -374.292597)
			(xy 31.851206 -374.229517) (xy 31.87693 -374.169345) (xy 31.893256 -374.140984) (xy 31.896573 -374.13496)
			(xy 31.900178 -374.121696) (xy 31.900368 -374.114822) (xy 31.900368 -373.828818) (xy 31.900779 -373.818644)
			(xy 31.908564 -373.799844) (xy 31.922954 -373.785457) (xy 31.941756 -373.777677) (xy 31.95193 -373.777256)
			(xy 32.66821 -373.777256) (xy 32.678384 -373.777656) (xy 32.697183 -373.785448) (xy 32.711568 -373.799841)
			(xy 32.719349 -373.818643) (xy 32.719772 -373.828818) (xy 32.719772 -374.114822) (xy 32.719959 -374.121696)
			(xy 32.723571 -374.134958) (xy 32.726884 -374.140984) (xy 32.74317 -374.169365) (xy 32.76889 -374.229532)
			(xy 32.786301 -374.292606) (xy 32.795088 -374.357447) (xy 32.795093 -374.422881) (xy 32.786315 -374.487723)
			(xy 32.768914 -374.5508) (xy 32.743203 -374.610971) (xy 32.726884 -374.639332) (xy 32.723557 -374.64535)
			(xy 32.719959 -374.658619) (xy 32.719772 -374.665494) (xy 32.719772 -375.414794) (xy 32.71997 -375.421667)
			(xy 32.723574 -375.434929) (xy 32.726884 -375.440956) (xy 32.743231 -375.469303) (xy 32.768945 -375.529478)
			(xy 32.786349 -375.59256) (xy 32.795129 -375.657406) (xy 32.795126 -375.722845) (xy 32.786339 -375.787691)
			(xy 32.768928 -375.850771) (xy 32.743208 -375.910942) (xy 32.726884 -375.939304) (xy 32.723567 -375.945327)
			(xy 32.719963 -375.958592) (xy 32.719772 -375.965466) (xy 32.719772 -376.25147) (xy 32.719312 -376.261638)
			(xy 32.711538 -376.28043) (xy 32.697164 -376.294816) (xy 32.678378 -376.302604) (xy 32.66821 -376.303032)
			(xy 31.95193 -376.303032) (xy 31.941757 -376.302611) (xy 31.922957 -376.29483) (xy 31.90857 -376.280443)
			(xy 31.900789 -376.261643) (xy 31.900368 -376.25147) (xy 31.900368 -375.965466) (xy 31.900193 -375.958591)
			(xy 31.896573 -375.945329) (xy 31.893256 -375.939304) (xy 31.876959 -375.910929) (xy 31.851238 -375.850761)
			(xy 31.833826 -375.787685) (xy 31.825039 -375.722843) (xy 31.825036 -375.657408) (xy 31.833816 -375.592565)
			(xy 31.851221 -375.529488) (xy 31.876935 -375.469317) (xy 31.893256 -375.440956) (xy 31.896583 -375.434937)
			(xy 31.900181 -375.421669) (xy 31.900368 -375.414794) (xy 31.900368 -374.665494) (xy 31.900182 -374.65862)
			(xy 31.89657 -374.645357) (xy 31.893256 -374.639332) (xy 31.876898 -374.610991) (xy 31.851182 -374.550815)
			(xy 31.833778 -374.487732) (xy 31.824998 -374.422884) (xy 28.395117 -374.422884) (xy 28.395117 -374.422888)
			(xy 28.38626 -374.487746) (xy 28.368768 -374.550827) (xy 28.342958 -374.610984) (xy 28.326588 -374.639332)
			(xy 28.323261 -374.645351) (xy 28.319663 -374.658619) (xy 28.319476 -374.665494) (xy 28.319476 -375.414794)
			(xy 28.319673 -375.421667) (xy 28.323278 -375.434929) (xy 28.326588 -375.440956) (xy 28.342935 -375.469316)
			(xy 28.368742 -375.529471) (xy 28.386236 -375.592548) (xy 28.395103 -375.657402) (xy 28.395676 -375.69013)
			(xy 28.395105 -375.722859) (xy 28.386251 -375.787718) (xy 28.368762 -375.850798) (xy 28.342956 -375.910956)
			(xy 28.326588 -375.939304) (xy 28.323271 -375.945327) (xy 28.319667 -375.958592) (xy 28.319476 -375.965466)
			(xy 28.319476 -376.25147) (xy 28.31895 -376.261593) (xy 28.311235 -376.28031) (xy 28.29696 -376.294667)
			(xy 28.278288 -376.30249) (xy 28.268168 -376.303032) (xy 27.551888 -376.303032) (xy 27.541737 -376.302589)
			(xy 27.52299 -376.294796) (xy 27.508669 -376.280406) (xy 27.500964 -376.261623) (xy 27.50058 -376.25147)
			(xy 27.50058 -375.965466) (xy 27.500404 -375.958592) (xy 27.496785 -375.945329) (xy 27.493468 -375.939304)
			(xy 27.477111 -375.91095) (xy 27.451305 -375.850793) (xy 27.433813 -375.787715) (xy 27.424951 -375.722859)
			(xy 27.42438 -375.69013) (xy 0.529844 -375.69013) (xy 0.529844 -376.822921) (xy 29.624883 -376.822921)
			(xy 29.624883 -376.757485) (xy 29.633665 -376.692641) (xy 29.651072 -376.629563) (xy 29.676787 -376.569392)
			(xy 29.693108 -376.54103) (xy 29.696413 -376.535) (xy 29.700025 -376.52174) (xy 29.70022 -376.514868)
			(xy 29.70022 -375.765568) (xy 29.700038 -375.758694) (xy 29.696423 -375.745431) (xy 29.693108 -375.739406)
			(xy 29.676814 -375.711029) (xy 29.651095 -375.650862) (xy 29.633685 -375.587786) (xy 29.624899 -375.522944)
			(xy 29.624895 -375.45751) (xy 29.633674 -375.392668) (xy 29.651077 -375.32959) (xy 29.676789 -375.26942)
			(xy 29.693108 -375.241058) (xy 29.696438 -375.235041) (xy 29.700034 -375.221771) (xy 29.70022 -375.214896)
			(xy 29.70022 -374.928638) (xy 29.700695 -374.918471) (xy 29.708464 -374.899681) (xy 29.722834 -374.885295)
			(xy 29.741616 -374.877506) (xy 29.751782 -374.877076) (xy 30.468062 -374.877076) (xy 30.478236 -374.877496)
			(xy 30.497037 -374.885276) (xy 30.511424 -374.899663) (xy 30.519204 -374.918464) (xy 30.519624 -374.928638)
			(xy 30.519624 -375.214896) (xy 30.519815 -375.221769) (xy 30.523424 -375.235032) (xy 30.526736 -375.241058)
			(xy 30.543086 -375.269404) (xy 30.568803 -375.329578) (xy 30.586209 -375.39266) (xy 30.594989 -375.457508)
			(xy 30.594985 -375.522947) (xy 30.586198 -375.587794) (xy 30.568784 -375.650873) (xy 30.543061 -375.711045)
			(xy 30.526736 -375.739406) (xy 30.523422 -375.745431) (xy 30.519816 -375.758694) (xy 30.519624 -375.765568)
			(xy 30.519624 -376.514868) (xy 30.519825 -376.521741) (xy 30.523427 -376.535003) (xy 30.526736 -376.54103)
			(xy 30.543062 -376.569389) (xy 30.568781 -376.629561) (xy 30.58619 -376.69264) (xy 30.594973 -376.757485)
			(xy 30.594973 -376.790204) (xy 34.024316 -376.790204) (xy 34.024859 -376.757474) (xy 34.033721 -376.692615)
			(xy 34.051218 -376.629534) (xy 34.077032 -376.569377) (xy 34.093404 -376.54103) (xy 34.096708 -376.535)
			(xy 34.10032 -376.52174) (xy 34.100516 -376.514868) (xy 34.100516 -375.765568) (xy 34.100334 -375.758694)
			(xy 34.096719 -375.745431) (xy 34.093404 -375.739406) (xy 34.077041 -375.711055) (xy 34.051239 -375.650896)
			(xy 34.033748 -375.587817) (xy 34.024887 -375.522961) (xy 34.024316 -375.490232) (xy 34.024872 -375.457502)
			(xy 34.03373 -375.392643) (xy 34.051223 -375.329563) (xy 34.077034 -375.269406) (xy 34.093404 -375.241058)
			(xy 34.096734 -375.235041) (xy 34.10033 -375.221771) (xy 34.100516 -375.214896) (xy 34.100516 -374.928638)
			(xy 34.101057 -374.918517) (xy 34.108768 -374.899801) (xy 34.123038 -374.885444) (xy 34.141706 -374.87762)
			(xy 34.151824 -374.877076) (xy 34.868104 -374.877076) (xy 34.878255 -374.877518) (xy 34.897003 -374.88531)
			(xy 34.911325 -374.8997) (xy 34.919029 -374.918485) (xy 34.919412 -374.928638) (xy 34.919412 -375.214896)
			(xy 34.919604 -375.221769) (xy 34.923212 -375.235032) (xy 34.926524 -375.241058) (xy 34.942875 -375.269415)
			(xy 34.96868 -375.329572) (xy 34.986174 -375.392649) (xy 34.995039 -375.457504) (xy 34.995612 -375.490232)
			(xy 34.995036 -375.522961) (xy 34.986183 -375.587819) (xy 34.968696 -375.650899) (xy 34.951868 -375.69013)
			(xy 36.224464 -375.69013) (xy 36.225026 -375.6574) (xy 36.233883 -375.592542) (xy 36.251375 -375.529462)
			(xy 36.277183 -375.469304) (xy 36.293552 -375.440956) (xy 36.296879 -375.434937) (xy 36.300477 -375.421669)
			(xy 36.300664 -375.414794) (xy 36.300664 -374.665494) (xy 36.300479 -374.65862) (xy 36.296866 -374.645357)
			(xy 36.293552 -374.639332) (xy 36.277204 -374.610973) (xy 36.251397 -374.550817) (xy 36.233902 -374.487741)
			(xy 36.225037 -374.422886) (xy 36.224464 -374.390158) (xy 36.225038 -374.357429) (xy 36.233892 -374.292571)
			(xy 36.25138 -374.229491) (xy 36.277185 -374.169332) (xy 36.293552 -374.140984) (xy 36.296869 -374.13496)
			(xy 36.300474 -374.121696) (xy 36.300664 -374.114822) (xy 36.300664 -373.828818) (xy 36.301142 -373.818689)
			(xy 36.308868 -373.799964) (xy 36.323158 -373.785606) (xy 36.341846 -373.777791) (xy 36.351972 -373.777256)
			(xy 37.068252 -373.777256) (xy 37.078398 -373.77776) (xy 37.09714 -373.785532) (xy 37.111464 -373.799903)
			(xy 37.119173 -373.818671) (xy 37.11956 -373.828818) (xy 37.11956 -374.114822) (xy 37.119749 -374.121695)
			(xy 37.12336 -374.134958) (xy 37.126672 -374.140984) (xy 37.143029 -374.169338) (xy 37.168833 -374.229496)
			(xy 37.186325 -374.292574) (xy 37.195188 -374.357429) (xy 37.19576 -374.390158) (xy 37.19519 -374.422887)
			(xy 37.186334 -374.487745) (xy 37.168845 -374.550825) (xy 37.14304 -374.610984) (xy 37.126672 -374.639332)
			(xy 37.123344 -374.64535) (xy 37.119747 -374.658619) (xy 37.11956 -374.665494) (xy 37.11956 -375.414794)
			(xy 37.119759 -375.421667) (xy 37.123363 -375.434929) (xy 37.126672 -375.440956) (xy 37.143017 -375.469316)
			(xy 37.168825 -375.529472) (xy 37.18632 -375.592548) (xy 37.195187 -375.657402) (xy 37.19576 -375.69013)
			(xy 37.195177 -375.722859) (xy 37.186325 -375.787716) (xy 37.16884 -375.850796) (xy 37.143038 -375.910955)
			(xy 37.126672 -375.939304) (xy 37.123354 -375.945327) (xy 37.119751 -375.958592) (xy 37.11956 -375.965466)
			(xy 37.11956 -376.25147) (xy 37.119049 -376.261595) (xy 37.111331 -376.280315) (xy 37.097052 -376.294673)
			(xy 37.078374 -376.302493) (xy 37.068252 -376.303032) (xy 36.351972 -376.303032) (xy 36.34182 -376.302602)
			(xy 36.323073 -376.294803) (xy 36.308752 -376.28041) (xy 36.301047 -376.261624) (xy 36.300664 -376.25147)
			(xy 36.300664 -375.965466) (xy 36.300489 -375.958591) (xy 36.29687 -375.945329) (xy 36.293552 -375.939304)
			(xy 36.277193 -375.910951) (xy 36.251388 -375.850793) (xy 36.233897 -375.787715) (xy 36.225035 -375.722859)
			(xy 36.224464 -375.69013) (xy 34.951868 -375.69013) (xy 34.942891 -375.711058) (xy 34.926524 -375.739406)
			(xy 34.923209 -375.74543) (xy 34.919603 -375.758694) (xy 34.919412 -375.765568) (xy 34.919412 -376.514868)
			(xy 34.919615 -376.52174) (xy 34.923216 -376.535003) (xy 34.926524 -376.54103) (xy 34.942904 -376.569371)
			(xy 34.968702 -376.629534) (xy 34.986187 -376.692616) (xy 34.995044 -376.757474) (xy 34.995612 -376.790204)
			(xy 34.995069 -376.822921) (xy 38.424969 -376.822921) (xy 38.424969 -376.757486) (xy 38.433751 -376.692642)
			(xy 38.451157 -376.629563) (xy 38.476871 -376.569392) (xy 38.493192 -376.54103) (xy 38.496496 -376.535)
			(xy 38.500108 -376.52174) (xy 38.500304 -376.514868) (xy 38.500304 -375.765568) (xy 38.500124 -375.758694)
			(xy 38.496508 -375.745431) (xy 38.493192 -375.739406) (xy 38.476898 -375.711029) (xy 38.451181 -375.650861)
			(xy 38.433771 -375.587786) (xy 38.424985 -375.522944) (xy 38.424982 -375.45751) (xy 38.43376 -375.392668)
			(xy 38.451163 -375.329591) (xy 38.476873 -375.26942) (xy 38.493192 -375.241058) (xy 38.496521 -375.23504)
			(xy 38.500118 -375.221771) (xy 38.500304 -375.214896) (xy 38.500304 -374.928638) (xy 38.500794 -374.918473)
			(xy 38.50856 -374.899686) (xy 38.522925 -374.885301) (xy 38.541702 -374.877508) (xy 38.551866 -374.877076)
			(xy 39.268146 -374.877076) (xy 39.278311 -374.877497) (xy 39.297089 -374.885293) (xy 39.311454 -374.899682)
			(xy 39.31922 -374.918472) (xy 39.319708 -374.928638) (xy 39.319708 -375.214896) (xy 39.3199 -375.221769)
			(xy 39.323508 -375.235032) (xy 39.32682 -375.241058) (xy 39.343171 -375.269404) (xy 39.368888 -375.329578)
			(xy 39.386294 -375.39266) (xy 39.395075 -375.457508) (xy 39.395072 -375.522947) (xy 39.386283 -375.587794)
			(xy 39.36887 -375.650874) (xy 39.352087 -375.69013) (xy 40.624252 -375.69013) (xy 40.624815 -375.6574)
			(xy 40.633673 -375.592542) (xy 40.651164 -375.529462) (xy 40.676971 -375.469304) (xy 40.69334 -375.440956)
			(xy 40.696666 -375.434937) (xy 40.700265 -375.421669) (xy 40.700452 -375.414794) (xy 40.700452 -374.665494)
			(xy 40.700268 -374.65862) (xy 40.696655 -374.645357) (xy 40.69334 -374.639332) (xy 40.676991 -374.610974)
			(xy 40.651184 -374.550818) (xy 40.63369 -374.487741) (xy 40.624825 -374.422886) (xy 40.624252 -374.390158)
			(xy 40.624828 -374.357429) (xy 40.633681 -374.292571) (xy 40.651169 -374.229491) (xy 40.676973 -374.169332)
			(xy 40.69334 -374.140984) (xy 40.696656 -374.13496) (xy 40.700262 -374.121696) (xy 40.700452 -374.114822)
			(xy 40.700452 -373.828818) (xy 40.700942 -373.818691) (xy 40.708666 -373.799968) (xy 40.722951 -373.785611)
			(xy 40.741636 -373.777793) (xy 40.75176 -373.777256) (xy 41.46804 -373.777256) (xy 41.478191 -373.777688)
			(xy 41.496936 -373.785489) (xy 41.511256 -373.799881) (xy 41.518963 -373.818665) (xy 41.519348 -373.828818)
			(xy 41.519348 -374.114822) (xy 41.519526 -374.121696) (xy 41.523143 -374.134959) (xy 41.52646 -374.140984)
			(xy 41.542815 -374.169339) (xy 41.568621 -374.229496) (xy 41.586113 -374.292574) (xy 41.594976 -374.357429)
			(xy 41.595548 -374.390158) (xy 41.594979 -374.422887) (xy 41.586124 -374.487745) (xy 41.568634 -374.550825)
			(xy 41.542828 -374.610984) (xy 41.52646 -374.639332) (xy 41.523139 -374.645353) (xy 41.519536 -374.65862)
			(xy 41.519348 -374.665494) (xy 41.519348 -375.414794) (xy 41.519536 -375.421668) (xy 41.523146 -375.434931)
			(xy 41.52646 -375.440956) (xy 41.542804 -375.469317) (xy 41.568612 -375.529472) (xy 41.586108 -375.592548)
			(xy 41.594975 -375.657402) (xy 41.595548 -375.69013) (xy 41.594967 -375.722859) (xy 41.586115 -375.787716)
			(xy 41.568629 -375.850797) (xy 41.542826 -375.910955) (xy 41.52646 -375.939304) (xy 41.523149 -375.94533)
			(xy 41.51954 -375.958593) (xy 41.519348 -375.965466) (xy 41.519348 -376.25147) (xy 41.518849 -376.261596)
			(xy 41.511129 -376.280319) (xy 41.496846 -376.294677) (xy 41.478164 -376.302495) (xy 41.46804 -376.303032)
			(xy 40.75176 -376.303032) (xy 40.741607 -376.302612) (xy 40.72286 -376.294809) (xy 40.708539 -376.280413)
			(xy 40.700835 -376.261625) (xy 40.700452 -376.25147) (xy 40.700452 -375.965466) (xy 40.700279 -375.958591)
			(xy 40.696658 -375.945328) (xy 40.69334 -375.939304) (xy 40.67698 -375.910952) (xy 40.651176 -375.850794)
			(xy 40.633684 -375.787715) (xy 40.624823 -375.722859) (xy 40.624252 -375.69013) (xy 39.352087 -375.69013)
			(xy 39.343146 -375.711045) (xy 39.32682 -375.739406) (xy 39.323505 -375.74543) (xy 39.319899 -375.758694)
			(xy 39.319708 -375.765568) (xy 39.319708 -376.514868) (xy 39.319911 -376.52174) (xy 39.323512 -376.535003)
			(xy 39.32682 -376.54103) (xy 39.343147 -376.569389) (xy 39.368866 -376.62956) (xy 39.386276 -376.692639)
			(xy 39.395059 -376.757485) (xy 39.395059 -376.790204) (xy 42.8244 -376.790204) (xy 42.824945 -376.757474)
			(xy 42.833807 -376.692615) (xy 42.851303 -376.629535) (xy 42.877116 -376.569377) (xy 42.893488 -376.54103)
			(xy 42.896791 -376.535) (xy 42.900404 -376.52174) (xy 42.9006 -376.514868) (xy 42.9006 -375.765568)
			(xy 42.90042 -375.758694) (xy 42.896804 -375.745431) (xy 42.893488 -375.739406) (xy 42.877124 -375.711056)
			(xy 42.851322 -375.650897) (xy 42.833832 -375.587817) (xy 42.824971 -375.522961) (xy 42.8244 -375.490232)
			(xy 42.824958 -375.457502) (xy 42.833816 -375.392644) (xy 42.851309 -375.329564) (xy 42.877118 -375.269406)
			(xy 42.893488 -375.241058) (xy 42.896817 -375.23504) (xy 42.900414 -375.221771) (xy 42.9006 -375.214896)
			(xy 42.9006 -374.928638) (xy 42.901157 -374.918519) (xy 42.908865 -374.899806) (xy 42.923129 -374.88545)
			(xy 42.941792 -374.877622) (xy 42.951908 -374.877076) (xy 43.668188 -374.877076) (xy 43.678338 -374.877531)
			(xy 43.697086 -374.885318) (xy 43.711409 -374.899704) (xy 43.719113 -374.918486) (xy 43.719496 -374.928638)
			(xy 43.719496 -375.214896) (xy 43.71969 -375.221769) (xy 43.723297 -375.235032) (xy 43.726608 -375.241058)
			(xy 43.742958 -375.269416) (xy 43.768763 -375.329572) (xy 43.786257 -375.392649) (xy 43.795123 -375.457504)
			(xy 43.795696 -375.490232) (xy 43.795123 -375.522961) (xy 43.786269 -375.587819) (xy 43.768781 -375.650899)
			(xy 43.742976 -375.711058) (xy 43.726608 -375.739406) (xy 43.723292 -375.74543) (xy 43.719687 -375.758694)
			(xy 43.719496 -375.765568) (xy 43.719496 -376.514868) (xy 43.719701 -376.52174) (xy 43.723301 -376.535003)
			(xy 43.726608 -376.54103) (xy 43.742986 -376.569372) (xy 43.768785 -376.629534) (xy 43.786271 -376.692616)
			(xy 43.795128 -376.757474) (xy 43.795696 -376.790204) (xy 43.795155 -376.822934) (xy 43.786292 -376.887794)
			(xy 43.768795 -376.950874) (xy 43.74298 -377.011031) (xy 43.726608 -377.039378) (xy 43.723302 -377.045407)
			(xy 43.719691 -377.058667) (xy 43.719496 -377.06554) (xy 43.719496 -377.35129) (xy 43.718966 -377.361412)
			(xy 43.711248 -377.380126) (xy 43.696976 -377.394481) (xy 43.678307 -377.402307) (xy 43.668188 -377.402852)
			(xy 42.951908 -377.402852) (xy 42.941761 -377.402373) (xy 42.923019 -377.39459) (xy 42.908697 -377.380211)
			(xy 42.900988 -377.361439) (xy 42.9006 -377.35129) (xy 42.9006 -377.06554) (xy 42.900393 -377.058668)
			(xy 42.896795 -377.045405) (xy 42.893488 -377.039378) (xy 42.877113 -377.011034) (xy 42.851313 -376.950873)
			(xy 42.833827 -376.887791) (xy 42.824969 -376.822933) (xy 42.8244 -376.790204) (xy 39.395059 -376.790204)
			(xy 39.395059 -376.822922) (xy 39.386274 -376.887767) (xy 39.368864 -376.950846) (xy 39.343144 -377.011017)
			(xy 39.32682 -377.039378) (xy 39.323514 -377.045407) (xy 39.319903 -377.058667) (xy 39.319708 -377.06554)
			(xy 39.319708 -377.35129) (xy 39.31916 -377.361441) (xy 39.311397 -377.380202) (xy 39.297049 -377.394566)
			(xy 39.278297 -377.402349) (xy 39.268146 -377.402852) (xy 38.551866 -377.402852) (xy 38.541705 -377.402394)
			(xy 38.522933 -377.394607) (xy 38.508569 -377.38023) (xy 38.500797 -377.361452) (xy 38.500304 -377.35129)
			(xy 38.500304 -377.06554) (xy 38.500096 -377.058668) (xy 38.496499 -377.045405) (xy 38.493192 -377.039378)
			(xy 38.476875 -377.011014) (xy 38.451159 -376.950843) (xy 38.433752 -376.887765) (xy 38.424969 -376.822921)
			(xy 34.995069 -376.822921) (xy 34.995069 -376.822934) (xy 34.986206 -376.887793) (xy 34.968709 -376.950874)
			(xy 34.942896 -377.011031) (xy 34.926524 -377.039378) (xy 34.923219 -377.045407) (xy 34.919607 -377.058667)
			(xy 34.919412 -377.06554) (xy 34.919412 -377.35129) (xy 34.918867 -377.36141) (xy 34.911152 -377.380121)
			(xy 34.896884 -377.394476) (xy 34.878221 -377.402304) (xy 34.868104 -377.402852) (xy 34.151824 -377.402852)
			(xy 34.141678 -377.40236) (xy 34.122936 -377.394582) (xy 34.108614 -377.380208) (xy 34.100904 -377.361438)
			(xy 34.100516 -377.35129) (xy 34.100516 -377.06554) (xy 34.100307 -377.058668) (xy 34.09671 -377.045405)
			(xy 34.093404 -377.039378) (xy 34.07703 -377.011033) (xy 34.05123 -376.950872) (xy 34.033743 -376.887791)
			(xy 34.024885 -376.822933) (xy 34.024316 -376.790204) (xy 30.594973 -376.790204) (xy 30.594973 -376.822922)
			(xy 30.586188 -376.887767) (xy 30.568779 -376.950846) (xy 30.543059 -377.011017) (xy 30.526736 -377.039378)
			(xy 30.523432 -377.045408) (xy 30.519819 -377.058668) (xy 30.519624 -377.06554) (xy 30.519624 -377.35129)
			(xy 30.519227 -377.361466) (xy 30.511438 -377.380267) (xy 30.497044 -377.394654) (xy 30.478238 -377.402433)
			(xy 30.468062 -377.402852) (xy 29.751782 -377.402852) (xy 29.741622 -377.402381) (xy 29.72285 -377.394599)
			(xy 29.708485 -377.380226) (xy 29.700713 -377.36145) (xy 29.70022 -377.35129) (xy 29.70022 -377.06554)
			(xy 29.70001 -377.058668) (xy 29.696414 -377.045405) (xy 29.693108 -377.039378) (xy 29.67679 -377.011015)
			(xy 29.651074 -376.950844) (xy 29.633666 -376.887765) (xy 29.624883 -376.822921) (xy 0.529844 -376.822921)
			(xy 0.529844 -379.540516) (xy 2.180588 -379.540516) (xy 2.184659 -379.484894) (xy 2.196785 -379.430457)
			(xy 2.216708 -379.378366) (xy 2.244004 -379.329731) (xy 2.27809 -379.285588) (xy 2.318239 -379.246879)
			(xy 2.363597 -379.214428) (xy 2.413197 -379.188927) (xy 2.465981 -379.17092) (xy 2.520824 -379.16079)
			(xy 2.576558 -379.158753) (xy 2.631995 -379.164853) (xy 2.685952 -379.178959) (xy 2.737281 -379.200771)
			(xy 2.784887 -379.229825) (xy 2.827755 -379.2655) (xy 2.864972 -379.307037) (xy 2.895745 -379.35355)
			(xy 2.919417 -379.404047) (xy 2.935485 -379.457454) (xy 2.943605 -379.51263) (xy 2.944114 -379.540516)
			(xy 3.653788 -379.540516) (xy 3.657859 -379.484894) (xy 3.669985 -379.430457) (xy 3.689908 -379.378366)
			(xy 3.717204 -379.329731) (xy 3.75129 -379.285588) (xy 3.791439 -379.246879) (xy 3.836797 -379.214428)
			(xy 3.886397 -379.188927) (xy 3.939181 -379.17092) (xy 3.994024 -379.16079) (xy 4.049758 -379.158753)
			(xy 4.105195 -379.164853) (xy 4.159152 -379.178959) (xy 4.210481 -379.200771) (xy 4.258087 -379.229825)
			(xy 4.300955 -379.2655) (xy 4.338172 -379.307037) (xy 4.368945 -379.35355) (xy 4.392617 -379.404047)
			(xy 4.408685 -379.457454) (xy 4.416805 -379.51263) (xy 4.417314 -379.540516) (xy 4.416805 -379.568402)
			(xy 4.41362 -379.590046) (xy 27.42438 -379.590046) (xy 27.424946 -379.557317) (xy 27.433802 -379.492458)
			(xy 27.451292 -379.429378) (xy 27.477099 -379.36922) (xy 27.493468 -379.340872) (xy 27.49679 -379.334851)
			(xy 27.500391 -379.321584) (xy 27.50058 -379.31471) (xy 27.50058 -378.56541) (xy 27.500387 -378.558537)
			(xy 27.496779 -378.545274) (xy 27.493468 -378.539248) (xy 27.477088 -378.510906) (xy 27.451288 -378.450745)
			(xy 27.433802 -378.387663) (xy 27.424947 -378.322804) (xy 27.42438 -378.290074) (xy 27.424959 -378.257345)
			(xy 27.433812 -378.192487) (xy 27.451298 -378.129407) (xy 27.477102 -378.069249) (xy 27.493468 -378.0409)
			(xy 27.49678 -378.034874) (xy 27.500388 -378.021611) (xy 27.50058 -378.014738) (xy 27.50058 -377.728734)
			(xy 27.501056 -377.718605) (xy 27.50878 -377.699877) (xy 27.52307 -377.685518) (xy 27.541761 -377.677705)
			(xy 27.551888 -377.677172) (xy 28.268168 -377.677172) (xy 28.278317 -377.677647) (xy 28.297063 -377.685427)
			(xy 28.311387 -377.699807) (xy 28.319092 -377.718584) (xy 28.319476 -377.728734) (xy 28.319476 -378.014738)
			(xy 28.319695 -378.021609) (xy 28.323285 -378.034872) (xy 28.326588 -378.0409) (xy 28.342952 -378.06925)
			(xy 28.368755 -378.129409) (xy 28.386245 -378.192488) (xy 28.395106 -378.257345) (xy 28.395676 -378.290074)
			(xy 28.395124 -378.322797) (xy 31.825007 -378.322797) (xy 31.82501 -378.257358) (xy 31.833797 -378.192512)
			(xy 31.85121 -378.129433) (xy 31.876931 -378.069261) (xy 31.893256 -378.0409) (xy 31.896567 -378.034874)
			(xy 31.900176 -378.021611) (xy 31.900368 -378.014738) (xy 31.900368 -377.728734) (xy 31.900793 -377.718561)
			(xy 31.908572 -377.699761) (xy 31.922958 -377.685374) (xy 31.941757 -377.677593) (xy 31.95193 -377.677172)
			(xy 32.66821 -377.677172) (xy 32.678386 -377.677557) (xy 32.697188 -377.685351) (xy 32.711574 -377.699749)
			(xy 32.719352 -377.718557) (xy 32.719772 -377.728734) (xy 32.719772 -378.014738) (xy 32.719991 -378.021609)
			(xy 32.723581 -378.034872) (xy 32.726884 -378.0409) (xy 32.743183 -378.069274) (xy 32.768902 -378.129442)
			(xy 32.786312 -378.192518) (xy 32.795097 -378.25736) (xy 32.7951 -378.322795) (xy 32.786321 -378.387638)
			(xy 32.768917 -378.450716) (xy 32.743204 -378.510887) (xy 32.726884 -378.539248) (xy 32.723551 -378.545264)
			(xy 32.719957 -378.558534) (xy 32.719772 -378.56541) (xy 32.719772 -379.31471) (xy 32.719964 -379.321583)
			(xy 32.723572 -379.334846) (xy 32.726884 -379.340872) (xy 32.743244 -379.369212) (xy 32.768957 -379.429388)
			(xy 32.78636 -379.492471) (xy 32.795138 -379.55732) (xy 32.795133 -379.622759) (xy 32.786344 -379.687606)
			(xy 32.768931 -379.750686) (xy 32.743209 -379.810858) (xy 32.726884 -379.83922) (xy 32.723561 -379.845241)
			(xy 32.719961 -379.858507) (xy 32.719772 -379.865382) (xy 32.719772 -380.151386) (xy 32.719325 -380.161556)
			(xy 32.711547 -380.180348) (xy 32.697168 -380.194733) (xy 32.678379 -380.20252) (xy 32.66821 -380.202948)
			(xy 31.95193 -380.202948) (xy 31.941759 -380.202511) (xy 31.922962 -380.194733) (xy 31.908576 -380.180351)
			(xy 31.900792 -380.161557) (xy 31.900368 -380.151386) (xy 31.900368 -379.865382) (xy 31.900187 -379.858508)
			(xy 31.896572 -379.845245) (xy 31.893256 -379.83922) (xy 31.876972 -379.810837) (xy 31.85125 -379.750671)
			(xy 31.833837 -379.687597) (xy 31.825048 -379.622756) (xy 31.825043 -379.557323) (xy 31.833821 -379.49248)
			(xy 31.851224 -379.429403) (xy 31.876936 -379.369233) (xy 31.893256 -379.340872) (xy 31.896577 -379.33485)
			(xy 31.900179 -379.321584) (xy 31.900368 -379.31471) (xy 31.900368 -378.56541) (xy 31.900176 -378.558537)
			(xy 31.896568 -378.545274) (xy 31.893256 -378.539248) (xy 31.876911 -378.510899) (xy 31.851195 -378.450725)
			(xy 31.833788 -378.387644) (xy 31.825007 -378.322797) (xy 28.395124 -378.322797) (xy 28.395124 -378.322804)
			(xy 28.386265 -378.387663) (xy 28.36877 -378.450743) (xy 28.342959 -378.510901) (xy 28.326588 -378.539248)
			(xy 28.323255 -378.545264) (xy 28.319661 -378.558534) (xy 28.319476 -378.56541) (xy 28.319476 -379.31471)
			(xy 28.319667 -379.321583) (xy 28.323276 -379.334846) (xy 28.326588 -379.340872) (xy 28.342941 -379.369228)
			(xy 28.368746 -379.429385) (xy 28.386239 -379.492462) (xy 28.395104 -379.557318) (xy 28.395676 -379.590046)
			(xy 28.395112 -379.622776) (xy 28.386256 -379.687634) (xy 28.368765 -379.750714) (xy 28.342957 -379.810872)
			(xy 28.326588 -379.83922) (xy 28.323265 -379.845241) (xy 28.319665 -379.858508) (xy 28.319476 -379.865382)
			(xy 28.319476 -380.151386) (xy 28.318962 -380.16151) (xy 28.311242 -380.180228) (xy 28.296964 -380.194584)
			(xy 28.278289 -380.202406) (xy 28.268168 -380.202948) (xy 27.551888 -380.202948) (xy 27.541739 -380.202489)
			(xy 27.522996 -380.194699) (xy 27.508674 -380.180314) (xy 27.500966 -380.161537) (xy 27.50058 -380.151386)
			(xy 27.50058 -379.865382) (xy 27.500398 -379.858508) (xy 27.496783 -379.845245) (xy 27.493468 -379.83922)
			(xy 27.477117 -379.810863) (xy 27.45131 -379.750707) (xy 27.433816 -379.687629) (xy 27.424952 -379.622774)
			(xy 27.42438 -379.590046) (xy 4.41362 -379.590046) (xy 4.408685 -379.623578) (xy 4.392617 -379.676985)
			(xy 4.368945 -379.727482) (xy 4.338172 -379.773995) (xy 4.300955 -379.815532) (xy 4.258087 -379.851207)
			(xy 4.210481 -379.880261) (xy 4.159152 -379.902073) (xy 4.105195 -379.916179) (xy 4.049758 -379.922279)
			(xy 3.994024 -379.920242) (xy 3.939181 -379.910112) (xy 3.886397 -379.892105) (xy 3.836797 -379.866604)
			(xy 3.791439 -379.834153) (xy 3.75129 -379.795444) (xy 3.717204 -379.751301) (xy 3.689908 -379.702666)
			(xy 3.669985 -379.650575) (xy 3.657859 -379.596138) (xy 3.653788 -379.540516) (xy 2.944114 -379.540516)
			(xy 2.943605 -379.568402) (xy 2.935485 -379.623578) (xy 2.919417 -379.676985) (xy 2.895745 -379.727482)
			(xy 2.864972 -379.773995) (xy 2.827755 -379.815532) (xy 2.784887 -379.851207) (xy 2.737281 -379.880261)
			(xy 2.685952 -379.902073) (xy 2.631995 -379.916179) (xy 2.576558 -379.922279) (xy 2.520824 -379.920242)
			(xy 2.465981 -379.910112) (xy 2.413197 -379.892105) (xy 2.363597 -379.866604) (xy 2.318239 -379.834153)
			(xy 2.27809 -379.795444) (xy 2.244004 -379.751301) (xy 2.216708 -379.702666) (xy 2.196785 -379.650575)
			(xy 2.184659 -379.596138) (xy 2.180588 -379.540516) (xy 0.529844 -379.540516) (xy 0.529844 -380.6574)
			(xy 29.62489 -380.6574) (xy 29.63367 -380.592557) (xy 29.651075 -380.529479) (xy 29.676788 -380.469308)
			(xy 29.693108 -380.440946) (xy 29.696407 -380.434914) (xy 29.700022 -380.421656) (xy 29.70022 -380.414784)
			(xy 29.70022 -379.665484) (xy 29.700032 -379.658611) (xy 29.696421 -379.645348) (xy 29.693108 -379.639322)
			(xy 29.676827 -379.610938) (xy 29.651108 -379.550772) (xy 29.633696 -379.487698) (xy 29.624908 -379.422858)
			(xy 29.624903 -379.357425) (xy 29.63368 -379.292583) (xy 29.65108 -379.229506) (xy 29.67679 -379.169336)
			(xy 29.693108 -379.140974) (xy 29.696433 -379.134954) (xy 29.700032 -379.121687) (xy 29.70022 -379.114812)
			(xy 29.70022 -378.828554) (xy 29.700695 -378.818396) (xy 29.708482 -378.799629) (xy 29.722852 -378.785266)
			(xy 29.741623 -378.77749) (xy 29.751782 -378.776992) (xy 30.468062 -378.776992) (xy 30.478212 -378.777564)
			(xy 30.496971 -378.785317) (xy 30.511336 -378.799658) (xy 30.51912 -378.818405) (xy 30.519624 -378.828554)
			(xy 30.519624 -379.114812) (xy 30.519809 -379.121686) (xy 30.523422 -379.134949) (xy 30.526736 -379.140974)
			(xy 30.5431 -379.169313) (xy 30.568815 -379.229489) (xy 30.586219 -379.292572) (xy 30.594998 -379.357421)
			(xy 30.594993 -379.422861) (xy 30.586203 -379.487709) (xy 30.568788 -379.550789) (xy 30.543062 -379.610961)
			(xy 30.526736 -379.639322) (xy 30.523416 -379.645344) (xy 30.519814 -379.65861) (xy 30.519624 -379.665484)
			(xy 30.519624 -380.414784) (xy 30.519819 -380.421657) (xy 30.523425 -380.43492) (xy 30.526736 -380.440946)
			(xy 30.543076 -380.469298) (xy 30.568793 -380.529471) (xy 30.5862 -380.592551) (xy 30.594982 -380.657398)
			(xy 30.594981 -380.69012) (xy 34.024316 -380.69012) (xy 34.024866 -380.65739) (xy 34.033726 -380.592531)
			(xy 34.051221 -380.529451) (xy 34.077033 -380.469293) (xy 34.093404 -380.440946) (xy 34.096703 -380.434914)
			(xy 34.100318 -380.421656) (xy 34.100516 -380.414784) (xy 34.100516 -379.665484) (xy 34.100328 -379.65861)
			(xy 34.096717 -379.645348) (xy 34.093404 -379.639322) (xy 34.077048 -379.610968) (xy 34.051243 -379.55081)
			(xy 34.033751 -379.487732) (xy 34.024888 -379.422877) (xy 34.024316 -379.390148) (xy 34.024879 -379.357418)
			(xy 34.033735 -379.29256) (xy 34.051226 -379.22948) (xy 34.077035 -379.169322) (xy 34.093404 -379.140974)
			(xy 34.096728 -379.134954) (xy 34.100328 -379.121687) (xy 34.100516 -379.114812) (xy 34.100516 -378.828554)
			(xy 34.100988 -378.818427) (xy 34.108727 -378.79971) (xy 34.123017 -378.785356) (xy 34.1417 -378.777534)
			(xy 34.151824 -378.776992) (xy 34.868104 -378.776992) (xy 34.878257 -378.777418) (xy 34.897008 -378.785214)
			(xy 34.911331 -378.799609) (xy 34.919032 -378.818399) (xy 34.919412 -378.828554) (xy 34.919412 -379.114812)
			(xy 34.919598 -379.121686) (xy 34.92321 -379.134949) (xy 34.926524 -379.140974) (xy 34.942882 -379.169328)
			(xy 34.968685 -379.229486) (xy 34.986177 -379.292564) (xy 34.99504 -379.357419) (xy 34.995612 -379.390148)
			(xy 34.995044 -379.422877) (xy 34.986188 -379.487735) (xy 34.968699 -379.550816) (xy 34.95187 -379.590046)
			(xy 36.224464 -379.590046) (xy 36.225033 -379.557317) (xy 36.233888 -379.492459) (xy 36.251378 -379.429379)
			(xy 36.277184 -379.36922) (xy 36.293552 -379.340872) (xy 36.296873 -379.33485) (xy 36.300475 -379.321584)
			(xy 36.300664 -379.31471) (xy 36.300664 -378.56541) (xy 36.300473 -378.558537) (xy 36.296864 -378.545274)
			(xy 36.293552 -378.539248) (xy 36.277171 -378.510907) (xy 36.251371 -378.450745) (xy 36.233886 -378.387663)
			(xy 36.225031 -378.322804) (xy 36.224464 -378.290074) (xy 36.225045 -378.257345) (xy 36.233897 -378.192488)
			(xy 36.251383 -378.129407) (xy 36.277186 -378.069249) (xy 36.293552 -378.0409) (xy 36.296863 -378.034873)
			(xy 36.300472 -378.021611) (xy 36.300664 -378.014738) (xy 36.300664 -377.728734) (xy 36.301155 -377.718607)
			(xy 36.308876 -377.699882) (xy 36.323162 -377.685523) (xy 36.341847 -377.677707) (xy 36.351972 -377.677172)
			(xy 37.068252 -377.677172) (xy 37.0784 -377.67766) (xy 37.097145 -377.685435) (xy 37.11147 -377.699811)
			(xy 37.119176 -377.718585) (xy 37.11956 -377.728734) (xy 37.11956 -378.014738) (xy 37.119781 -378.021609)
			(xy 37.12337 -378.034872) (xy 37.126672 -378.0409) (xy 37.143035 -378.069251) (xy 37.168838 -378.12941)
			(xy 37.186329 -378.192489) (xy 37.195189 -378.257345) (xy 37.19576 -378.290074) (xy 37.195197 -378.322804)
			(xy 37.186339 -378.387662) (xy 37.168848 -378.450742) (xy 37.14304 -378.5109) (xy 37.126672 -378.539248)
			(xy 37.123338 -378.545263) (xy 37.119745 -378.558534) (xy 37.11956 -378.56541) (xy 37.11956 -379.31471)
			(xy 37.119753 -379.321583) (xy 37.123361 -379.334846) (xy 37.126672 -379.340872) (xy 37.143024 -379.369229)
			(xy 37.16883 -379.429385) (xy 37.186323 -379.492463) (xy 37.195188 -379.557318) (xy 37.19576 -379.590046)
			(xy 37.195184 -379.622775) (xy 37.18633 -379.687633) (xy 37.168843 -379.750713) (xy 37.143039 -379.810871)
			(xy 37.126672 -379.83922) (xy 37.123348 -379.84524) (xy 37.119749 -379.858507) (xy 37.11956 -379.865382)
			(xy 37.11956 -380.151386) (xy 37.119062 -380.161512) (xy 37.111339 -380.180233) (xy 37.097056 -380.194589)
			(xy 37.078375 -380.202409) (xy 37.068252 -380.202948) (xy 36.351972 -380.202948) (xy 36.341822 -380.202502)
			(xy 36.323078 -380.194707) (xy 36.308758 -380.180318) (xy 36.30105 -380.161538) (xy 36.300664 -380.151386)
			(xy 36.300664 -379.865382) (xy 36.300483 -379.858508) (xy 36.296868 -379.845245) (xy 36.293552 -379.83922)
			(xy 36.277199 -379.810864) (xy 36.251393 -379.750707) (xy 36.2339 -379.68763) (xy 36.225036 -379.622774)
			(xy 36.224464 -379.590046) (xy 34.95187 -379.590046) (xy 34.942892 -379.610974) (xy 34.926524 -379.639322)
			(xy 34.923203 -379.645344) (xy 34.919601 -379.65861) (xy 34.919412 -379.665484) (xy 34.919412 -380.414784)
			(xy 34.919609 -380.421657) (xy 34.923214 -380.43492) (xy 34.926524 -380.440946) (xy 34.94291 -380.469284)
			(xy 34.968707 -380.529448) (xy 34.98619 -380.592531) (xy 34.995045 -380.65739) (xy 34.995045 -380.6574)
			(xy 38.424976 -380.6574) (xy 38.433756 -380.592557) (xy 38.45116 -380.529479) (xy 38.476873 -380.469308)
			(xy 38.493192 -380.440946) (xy 38.49649 -380.434913) (xy 38.500106 -380.421656) (xy 38.500304 -380.414784)
			(xy 38.500304 -379.665484) (xy 38.500118 -379.65861) (xy 38.496506 -379.645348) (xy 38.493192 -379.639322)
			(xy 38.476912 -379.610938) (xy 38.451193 -379.550771) (xy 38.433782 -379.487698) (xy 38.424994 -379.422858)
			(xy 38.424989 -379.357425) (xy 38.433766 -379.292583) (xy 38.451166 -379.229506) (xy 38.476874 -379.169336)
			(xy 38.493192 -379.140974) (xy 38.496515 -379.134954) (xy 38.500116 -379.121687) (xy 38.500304 -379.114812)
			(xy 38.500304 -378.828554) (xy 38.500795 -378.818397) (xy 38.508578 -378.799634) (xy 38.522944 -378.785271)
			(xy 38.541709 -378.777493) (xy 38.551866 -378.776992) (xy 39.268146 -378.776992) (xy 39.278301 -378.777495)
			(xy 39.297062 -378.785276) (xy 39.311424 -378.799638) (xy 39.319205 -378.818399) (xy 39.319708 -378.828554)
			(xy 39.319708 -379.114812) (xy 39.319894 -379.121686) (xy 39.323506 -379.134949) (xy 39.32682 -379.140974)
			(xy 39.343184 -379.169312) (xy 39.3689 -379.229488) (xy 39.386305 -379.292572) (xy 39.395085 -379.357421)
			(xy 39.395079 -379.422861) (xy 39.386289 -379.487709) (xy 39.368873 -379.550789) (xy 39.352089 -379.590046)
			(xy 40.624252 -379.590046) (xy 40.624822 -379.557317) (xy 40.633678 -379.492459) (xy 40.651167 -379.429379)
			(xy 40.676972 -379.36922) (xy 40.69334 -379.340872) (xy 40.69666 -379.33485) (xy 40.700263 -379.321584)
			(xy 40.700452 -379.31471) (xy 40.700452 -378.56541) (xy 40.700262 -378.558537) (xy 40.696653 -378.545274)
			(xy 40.69334 -378.539248) (xy 40.676958 -378.510908) (xy 40.651159 -378.450745) (xy 40.633674 -378.387663)
			(xy 40.624819 -378.322804) (xy 40.624252 -378.290074) (xy 40.624835 -378.257345) (xy 40.633686 -378.192488)
			(xy 40.651172 -378.129408) (xy 40.676974 -378.069249) (xy 40.69334 -378.0409) (xy 40.69665 -378.034873)
			(xy 40.700259 -378.021611) (xy 40.700452 -378.014738) (xy 40.700452 -377.728734) (xy 40.700955 -377.718608)
			(xy 40.708674 -377.699885) (xy 40.722955 -377.685528) (xy 40.741637 -377.677709) (xy 40.75176 -377.677172)
			(xy 41.46804 -377.677172) (xy 41.478193 -377.677588) (xy 41.496941 -377.685392) (xy 41.511262 -377.699789)
			(xy 41.518965 -377.718579) (xy 41.519348 -377.728734) (xy 41.519348 -378.014738) (xy 41.519558 -378.02161)
			(xy 41.523153 -378.034873) (xy 41.52646 -378.0409) (xy 41.542822 -378.069251) (xy 41.568625 -378.12941)
			(xy 41.586116 -378.192489) (xy 41.594977 -378.257345) (xy 41.595548 -378.290074) (xy 45.023794 -378.290074)
			(xy 45.027785 -378.227907) (xy 45.039694 -378.16676) (xy 45.059323 -378.107639) (xy 45.086352 -378.051513)
			(xy 45.120336 -377.999304) (xy 45.160718 -377.951869) (xy 45.206834 -377.909988) (xy 45.257926 -377.874348)
			(xy 45.313157 -377.845534) (xy 45.371619 -377.82402) (xy 45.432353 -377.810158) (xy 45.49436 -377.804176)
			(xy 45.556623 -377.806172) (xy 45.61812 -377.816115) (xy 45.677841 -377.833839) (xy 45.734804 -377.859056)
			(xy 45.788075 -377.891349) (xy 45.83678 -377.930189) (xy 45.880117 -377.974939) (xy 45.917377 -378.024863)
			(xy 45.947946 -378.079142) (xy 45.971324 -378.136885) (xy 45.987125 -378.197143) (xy 45.995091 -378.258926)
			(xy 45.99559 -378.290074) (xy 45.995091 -378.321222) (xy 45.987972 -378.376434) (xy 54.891938 -378.376434)
			(xy 54.896009 -378.320812) (xy 54.908135 -378.266375) (xy 54.928058 -378.214284) (xy 54.955354 -378.165649)
			(xy 54.98944 -378.121506) (xy 55.029589 -378.082797) (xy 55.074947 -378.050346) (xy 55.124547 -378.024845)
			(xy 55.177331 -378.006838) (xy 55.232174 -377.996708) (xy 55.287908 -377.994671) (xy 55.343345 -378.000771)
			(xy 55.397302 -378.014877) (xy 55.448631 -378.036689) (xy 55.496237 -378.065743) (xy 55.539105 -378.101418)
			(xy 55.576322 -378.142955) (xy 55.607095 -378.189468) (xy 55.630767 -378.239965) (xy 55.646835 -378.293372)
			(xy 55.654955 -378.348548) (xy 55.655464 -378.376434) (xy 55.654955 -378.40432) (xy 55.646835 -378.459496)
			(xy 55.630767 -378.512903) (xy 55.607095 -378.5634) (xy 55.576322 -378.609913) (xy 55.539105 -378.65145)
			(xy 55.496237 -378.687125) (xy 55.448631 -378.716179) (xy 55.397302 -378.737991) (xy 55.343345 -378.752097)
			(xy 55.287908 -378.758197) (xy 55.232174 -378.75616) (xy 55.177331 -378.74603) (xy 55.124547 -378.728023)
			(xy 55.074947 -378.702522) (xy 55.029589 -378.670071) (xy 54.98944 -378.631362) (xy 54.955354 -378.587219)
			(xy 54.928058 -378.538584) (xy 54.908135 -378.486493) (xy 54.896009 -378.432056) (xy 54.891938 -378.376434)
			(xy 45.987972 -378.376434) (xy 45.987125 -378.383005) (xy 45.971324 -378.443263) (xy 45.947946 -378.501006)
			(xy 45.917377 -378.555285) (xy 45.880117 -378.605209) (xy 45.83678 -378.649959) (xy 45.788075 -378.688799)
			(xy 45.734804 -378.721092) (xy 45.677841 -378.746309) (xy 45.61812 -378.764033) (xy 45.556623 -378.773976)
			(xy 45.49436 -378.775972) (xy 45.432353 -378.76999) (xy 45.371619 -378.756128) (xy 45.313157 -378.734614)
			(xy 45.257926 -378.7058) (xy 45.206834 -378.67016) (xy 45.160718 -378.628279) (xy 45.120336 -378.580844)
			(xy 45.086352 -378.528635) (xy 45.059323 -378.472509) (xy 45.039694 -378.413388) (xy 45.027785 -378.352241)
			(xy 45.023794 -378.290074) (xy 41.595548 -378.290074) (xy 41.594987 -378.322804) (xy 41.586129 -378.387662)
			(xy 41.568637 -378.450742) (xy 41.542829 -378.5109) (xy 41.52646 -378.539248) (xy 41.523133 -378.545267)
			(xy 41.519534 -378.558535) (xy 41.519348 -378.56541) (xy 41.519348 -379.31471) (xy 41.51953 -379.321584)
			(xy 41.523144 -379.334847) (xy 41.52646 -379.340872) (xy 41.542811 -379.36923) (xy 41.568617 -379.429386)
			(xy 41.586111 -379.492463) (xy 41.594976 -379.557318) (xy 41.595548 -379.590046) (xy 41.594974 -379.622775)
			(xy 41.58612 -379.687633) (xy 41.568632 -379.750713) (xy 41.542827 -379.810872) (xy 41.52646 -379.83922)
			(xy 41.523143 -379.845244) (xy 41.519538 -379.858508) (xy 41.519348 -379.865382) (xy 41.519348 -380.151386)
			(xy 41.518862 -380.161513) (xy 41.511136 -380.180236) (xy 41.49685 -380.194594) (xy 41.478165 -380.202411)
			(xy 41.46804 -380.202948) (xy 40.75176 -380.202948) (xy 40.741609 -380.202512) (xy 40.722865 -380.194712)
			(xy 40.708545 -380.180321) (xy 40.700838 -380.161539) (xy 40.700452 -380.151386) (xy 40.700452 -379.865382)
			(xy 40.700273 -379.858508) (xy 40.696656 -379.845245) (xy 40.69334 -379.83922) (xy 40.676986 -379.810864)
			(xy 40.651181 -379.750707) (xy 40.633687 -379.68763) (xy 40.624824 -379.622774) (xy 40.624252 -379.590046)
			(xy 39.352089 -379.590046) (xy 39.343147 -379.610961) (xy 39.32682 -379.639322) (xy 39.323499 -379.645344)
			(xy 39.319897 -379.65861) (xy 39.319708 -379.665484) (xy 39.319708 -380.414784) (xy 39.319905 -380.421657)
			(xy 39.32351 -380.43492) (xy 39.32682 -380.440946) (xy 39.34316 -380.469297) (xy 39.368879 -380.52947)
			(xy 39.386286 -380.592551) (xy 39.395069 -380.657398) (xy 39.395067 -380.69012) (xy 42.8244 -380.69012)
			(xy 42.824953 -380.65739) (xy 42.833812 -380.592531) (xy 42.851306 -380.529451) (xy 42.877118 -380.469294)
			(xy 42.893488 -380.440946) (xy 42.896786 -380.434913) (xy 42.900402 -380.421656) (xy 42.9006 -380.414784)
			(xy 42.9006 -379.665484) (xy 42.900414 -379.65861) (xy 42.896802 -379.645347) (xy 42.893488 -379.639322)
			(xy 42.87713 -379.610969) (xy 42.851327 -379.55081) (xy 42.833835 -379.487732) (xy 42.824972 -379.422877)
			(xy 42.8244 -379.390148) (xy 42.824965 -379.357418) (xy 42.833821 -379.29256) (xy 42.851312 -379.22948)
			(xy 42.877119 -379.169322) (xy 42.893488 -379.140974) (xy 42.896811 -379.134953) (xy 42.900412 -379.121687)
			(xy 42.9006 -379.114812) (xy 42.9006 -378.828554) (xy 42.901088 -378.818429) (xy 42.908823 -378.799715)
			(xy 42.923108 -378.785361) (xy 42.941786 -378.777537) (xy 42.951908 -378.776992) (xy 43.668188 -378.776992)
			(xy 43.67834 -378.777431) (xy 43.697091 -378.785221) (xy 43.711414 -378.799613) (xy 43.719116 -378.8184)
			(xy 43.719496 -378.828554) (xy 43.719496 -379.114812) (xy 43.719684 -379.121686) (xy 43.723295 -379.134948)
			(xy 43.726608 -379.140974) (xy 43.742964 -379.169329) (xy 43.768768 -379.229486) (xy 43.78626 -379.292564)
			(xy 43.795124 -379.357419) (xy 43.795696 -379.390148) (xy 43.79513 -379.422878) (xy 43.786274 -379.487736)
			(xy 43.768784 -379.550816) (xy 43.751954 -379.590046) (xy 45.023794 -379.590046) (xy 45.027785 -379.527879)
			(xy 45.039694 -379.466732) (xy 45.059323 -379.407611) (xy 45.086352 -379.351485) (xy 45.120336 -379.299276)
			(xy 45.160718 -379.251841) (xy 45.206834 -379.20996) (xy 45.257926 -379.17432) (xy 45.313157 -379.145506)
			(xy 45.371619 -379.123992) (xy 45.432353 -379.11013) (xy 45.49436 -379.104148) (xy 45.556623 -379.106144)
			(xy 45.61812 -379.116087) (xy 45.677841 -379.133811) (xy 45.734804 -379.159028) (xy 45.788075 -379.191321)
			(xy 45.83678 -379.230161) (xy 45.880117 -379.274911) (xy 45.917377 -379.324835) (xy 45.947946 -379.379114)
			(xy 45.952413 -379.390148) (xy 47.223942 -379.390148) (xy 47.227933 -379.327981) (xy 47.239842 -379.266834)
			(xy 47.259471 -379.207713) (xy 47.2865 -379.151587) (xy 47.320484 -379.099378) (xy 47.360866 -379.051943)
			(xy 47.406982 -379.010062) (xy 47.458074 -378.974422) (xy 47.513305 -378.945608) (xy 47.571767 -378.924094)
			(xy 47.632501 -378.910232) (xy 47.694508 -378.90425) (xy 47.756771 -378.906246) (xy 47.818268 -378.916189)
			(xy 47.877989 -378.933913) (xy 47.934952 -378.95913) (xy 47.988223 -378.991423) (xy 48.036928 -379.030263)
			(xy 48.080265 -379.075013) (xy 48.117525 -379.124937) (xy 48.148094 -379.179216) (xy 48.171472 -379.236959)
			(xy 48.187273 -379.297217) (xy 48.195239 -379.359) (xy 48.195738 -379.390148) (xy 48.195239 -379.421296)
			(xy 48.187273 -379.483079) (xy 48.171472 -379.543337) (xy 48.148094 -379.60108) (xy 48.117525 -379.655359)
			(xy 48.114139 -379.659896) (xy 54.995316 -379.659896) (xy 54.999387 -379.604274) (xy 55.011513 -379.549837)
			(xy 55.031436 -379.497746) (xy 55.058732 -379.449111) (xy 55.092818 -379.404968) (xy 55.132967 -379.366259)
			(xy 55.178325 -379.333808) (xy 55.227925 -379.308307) (xy 55.280709 -379.2903) (xy 55.335552 -379.28017)
			(xy 55.391286 -379.278133) (xy 55.446723 -379.284233) (xy 55.50068 -379.298339) (xy 55.552009 -379.320151)
			(xy 55.599615 -379.349205) (xy 55.642483 -379.38488) (xy 55.6797 -379.426417) (xy 55.710473 -379.47293)
			(xy 55.734145 -379.523427) (xy 55.750213 -379.576834) (xy 55.758333 -379.63201) (xy 55.758842 -379.659896)
			(xy 55.758333 -379.687782) (xy 55.750213 -379.742958) (xy 55.734145 -379.796365) (xy 55.710473 -379.846862)
			(xy 55.6797 -379.893375) (xy 55.642483 -379.934912) (xy 55.599615 -379.970587) (xy 55.552009 -379.999641)
			(xy 55.50068 -380.021453) (xy 55.446723 -380.035559) (xy 55.391286 -380.041659) (xy 55.335552 -380.039622)
			(xy 55.280709 -380.029492) (xy 55.227925 -380.011485) (xy 55.178325 -379.985984) (xy 55.132967 -379.953533)
			(xy 55.092818 -379.914824) (xy 55.058732 -379.870681) (xy 55.031436 -379.822046) (xy 55.011513 -379.769955)
			(xy 54.999387 -379.715518) (xy 54.995316 -379.659896) (xy 48.114139 -379.659896) (xy 48.080265 -379.705283)
			(xy 48.036928 -379.750033) (xy 47.988223 -379.788873) (xy 47.934952 -379.821166) (xy 47.877989 -379.846383)
			(xy 47.818268 -379.864107) (xy 47.756771 -379.87405) (xy 47.694508 -379.876046) (xy 47.632501 -379.870064)
			(xy 47.571767 -379.856202) (xy 47.513305 -379.834688) (xy 47.458074 -379.805874) (xy 47.406982 -379.770234)
			(xy 47.360866 -379.728353) (xy 47.320484 -379.680918) (xy 47.2865 -379.628709) (xy 47.259471 -379.572583)
			(xy 47.239842 -379.513462) (xy 47.227933 -379.452315) (xy 47.223942 -379.390148) (xy 45.952413 -379.390148)
			(xy 45.971324 -379.436857) (xy 45.987125 -379.497115) (xy 45.995091 -379.558898) (xy 45.99559 -379.590046)
			(xy 45.995091 -379.621194) (xy 45.987125 -379.682977) (xy 45.971324 -379.743235) (xy 45.947946 -379.800978)
			(xy 45.917377 -379.855257) (xy 45.880117 -379.905181) (xy 45.83678 -379.949931) (xy 45.788075 -379.988771)
			(xy 45.734804 -380.021064) (xy 45.677841 -380.046281) (xy 45.61812 -380.064005) (xy 45.556623 -380.073948)
			(xy 45.49436 -380.075944) (xy 45.432353 -380.069962) (xy 45.371619 -380.0561) (xy 45.313157 -380.034586)
			(xy 45.257926 -380.005772) (xy 45.206834 -379.970132) (xy 45.160718 -379.928251) (xy 45.120336 -379.880816)
			(xy 45.086352 -379.828607) (xy 45.059323 -379.772481) (xy 45.039694 -379.71336) (xy 45.027785 -379.652213)
			(xy 45.023794 -379.590046) (xy 43.751954 -379.590046) (xy 43.742976 -379.610974) (xy 43.726608 -379.639322)
			(xy 43.723286 -379.645343) (xy 43.719685 -379.65861) (xy 43.719496 -379.665484) (xy 43.719496 -380.414784)
			(xy 43.719694 -380.421657) (xy 43.723298 -380.43492) (xy 43.726608 -380.440946) (xy 43.742993 -380.469285)
			(xy 43.76879 -380.529448) (xy 43.786274 -380.592531) (xy 43.795129 -380.65739) (xy 43.795696 -380.69012)
			(xy 47.223942 -380.69012) (xy 47.227933 -380.627953) (xy 47.239842 -380.566806) (xy 47.259471 -380.507685)
			(xy 47.2865 -380.451559) (xy 47.320484 -380.39935) (xy 47.360866 -380.351915) (xy 47.406982 -380.310034)
			(xy 47.458074 -380.274394) (xy 47.513305 -380.24558) (xy 47.571767 -380.224066) (xy 47.632501 -380.210204)
			(xy 47.694508 -380.204222) (xy 47.756771 -380.206218) (xy 47.818268 -380.216161) (xy 47.877989 -380.233885)
			(xy 47.934952 -380.259102) (xy 47.988223 -380.291395) (xy 48.036928 -380.330235) (xy 48.080265 -380.374985)
			(xy 48.117525 -380.424909) (xy 48.148094 -380.479188) (xy 48.171472 -380.536931) (xy 48.187273 -380.597189)
			(xy 48.195239 -380.658972) (xy 48.195738 -380.69012) (xy 48.195239 -380.721268) (xy 48.187273 -380.783051)
			(xy 48.171472 -380.843309) (xy 48.148094 -380.901052) (xy 48.117525 -380.955331) (xy 48.080265 -381.005255)
			(xy 48.036928 -381.050005) (xy 47.988223 -381.088845) (xy 47.934952 -381.121138) (xy 47.877989 -381.146355)
			(xy 47.818268 -381.164079) (xy 47.756771 -381.174022) (xy 47.694508 -381.176018) (xy 47.632501 -381.170036)
			(xy 47.571767 -381.156174) (xy 47.513305 -381.13466) (xy 47.458074 -381.105846) (xy 47.406982 -381.070206)
			(xy 47.360866 -381.028325) (xy 47.320484 -380.98089) (xy 47.2865 -380.928681) (xy 47.259471 -380.872555)
			(xy 47.239842 -380.813434) (xy 47.227933 -380.752287) (xy 47.223942 -380.69012) (xy 43.795696 -380.69012)
			(xy 43.795117 -380.722849) (xy 43.786265 -380.787707) (xy 43.768779 -380.850787) (xy 43.742975 -380.910946)
			(xy 43.726608 -380.939294) (xy 43.723296 -380.94532) (xy 43.719688 -380.958583) (xy 43.719496 -380.965456)
			(xy 43.719496 -381.251206) (xy 43.718979 -381.261329) (xy 43.711256 -381.280043) (xy 43.69698 -381.294398)
			(xy 43.678308 -381.302223) (xy 43.668188 -381.302768) (xy 42.951908 -381.302768) (xy 42.94175 -381.302371)
			(xy 42.922992 -381.294572) (xy 42.908667 -381.280167) (xy 42.900973 -381.261366) (xy 42.9006 -381.251206)
			(xy 42.9006 -380.965456) (xy 42.900386 -380.958584) (xy 42.896793 -380.945322) (xy 42.893488 -380.939294)
			(xy 42.877119 -380.910947) (xy 42.851318 -380.850786) (xy 42.83383 -380.787706) (xy 42.82497 -380.722849)
			(xy 42.8244 -380.69012) (xy 39.395067 -380.69012) (xy 39.395066 -380.722836) (xy 39.386279 -380.787682)
			(xy 39.368867 -380.850762) (xy 39.343145 -380.910933) (xy 39.32682 -380.939294) (xy 39.323509 -380.94532)
			(xy 39.319901 -380.958583) (xy 39.319708 -380.965456) (xy 39.319708 -381.251206) (xy 39.319173 -381.261358)
			(xy 39.311405 -381.280119) (xy 39.297052 -381.294482) (xy 39.278298 -381.302265) (xy 39.268146 -381.302768)
			(xy 38.551866 -381.302768) (xy 38.541707 -381.302295) (xy 38.522938 -381.29451) (xy 38.508574 -381.280138)
			(xy 38.5008 -381.261365) (xy 38.500304 -381.251206) (xy 38.500304 -380.965456) (xy 38.50009 -380.958584)
			(xy 38.496497 -380.945322) (xy 38.493192 -380.939294) (xy 38.476888 -380.910923) (xy 38.451171 -380.850754)
			(xy 38.433763 -380.787677) (xy 38.424978 -380.722835) (xy 38.424976 -380.6574) (xy 34.995045 -380.6574)
			(xy 34.995612 -380.69012) (xy 34.995031 -380.722849) (xy 34.98618 -380.787707) (xy 34.968694 -380.850787)
			(xy 34.94289 -380.910945) (xy 34.926524 -380.939294) (xy 34.923213 -380.945321) (xy 34.919605 -380.958583)
			(xy 34.919412 -380.965456) (xy 34.919412 -381.251206) (xy 34.91888 -381.261327) (xy 34.91116 -381.280038)
			(xy 34.896888 -381.294392) (xy 34.878222 -381.30222) (xy 34.868104 -381.302768) (xy 34.151824 -381.302768)
			(xy 34.141667 -381.302358) (xy 34.122909 -381.294565) (xy 34.108584 -381.280164) (xy 34.100889 -381.261365)
			(xy 34.100516 -381.251206) (xy 34.100516 -380.965456) (xy 34.1003 -380.958585) (xy 34.096708 -380.945322)
			(xy 34.093404 -380.939294) (xy 34.077036 -380.910946) (xy 34.051235 -380.850786) (xy 34.033746 -380.787706)
			(xy 34.024886 -380.722849) (xy 34.024316 -380.69012) (xy 30.594981 -380.69012) (xy 30.59498 -380.722836)
			(xy 30.586194 -380.787682) (xy 30.568782 -380.850762) (xy 30.54306 -380.910933) (xy 30.526736 -380.939294)
			(xy 30.523426 -380.945321) (xy 30.519817 -380.958583) (xy 30.519624 -380.965456) (xy 30.519624 -381.251206)
			(xy 30.51924 -381.261383) (xy 30.511446 -381.280185) (xy 30.497048 -381.294571) (xy 30.478239 -381.302349)
			(xy 30.468062 -381.302768) (xy 29.751782 -381.302768) (xy 29.741624 -381.302282) (xy 29.722855 -381.294502)
			(xy 29.708491 -381.280135) (xy 29.700716 -381.261364) (xy 29.70022 -381.251206) (xy 29.70022 -380.965456)
			(xy 29.700004 -380.958585) (xy 29.696412 -380.945322) (xy 29.693108 -380.939294) (xy 29.676804 -380.910923)
			(xy 29.651086 -380.850754) (xy 29.633677 -380.787677) (xy 29.624892 -380.722835) (xy 29.62489 -380.6574)
			(xy 0.529844 -380.6574) (xy 0.529844 -381.338836) (xy 1.266188 -381.338836) (xy 1.270259 -381.283214)
			(xy 1.282385 -381.228777) (xy 1.302308 -381.176686) (xy 1.329604 -381.128051) (xy 1.36369 -381.083908)
			(xy 1.403839 -381.045199) (xy 1.449197 -381.012748) (xy 1.498797 -380.987247) (xy 1.551581 -380.96924)
			(xy 1.606424 -380.95911) (xy 1.662158 -380.957073) (xy 1.717595 -380.963173) (xy 1.771552 -380.977279)
			(xy 1.822881 -380.999091) (xy 1.870487 -381.028145) (xy 1.913355 -381.06382) (xy 1.950572 -381.105357)
			(xy 1.981345 -381.15187) (xy 2.005017 -381.202367) (xy 2.021085 -381.255774) (xy 2.029205 -381.31095)
			(xy 2.029714 -381.338836) (xy 2.029533 -381.348742) (xy 8.047988 -381.348742) (xy 8.052059 -381.29312)
			(xy 8.064185 -381.238683) (xy 8.084108 -381.186592) (xy 8.111404 -381.137957) (xy 8.14549 -381.093814)
			(xy 8.185639 -381.055105) (xy 8.230997 -381.022654) (xy 8.280597 -380.997153) (xy 8.333381 -380.979146)
			(xy 8.388224 -380.969016) (xy 8.443958 -380.966979) (xy 8.499395 -380.973079) (xy 8.553352 -380.987185)
			(xy 8.604681 -381.008997) (xy 8.652287 -381.038051) (xy 8.695155 -381.073726) (xy 8.732372 -381.115263)
			(xy 8.763145 -381.161776) (xy 8.786817 -381.212273) (xy 8.802885 -381.26568) (xy 8.811005 -381.320856)
			(xy 8.811458 -381.345694) (xy 9.548112 -381.345694) (xy 9.552183 -381.290072) (xy 9.564309 -381.235635)
			(xy 9.584232 -381.183544) (xy 9.611528 -381.134909) (xy 9.645614 -381.090766) (xy 9.685763 -381.052057)
			(xy 9.731121 -381.019606) (xy 9.780721 -380.994105) (xy 9.833505 -380.976098) (xy 9.888348 -380.965968)
			(xy 9.944082 -380.963931) (xy 9.999519 -380.970031) (xy 10.053476 -380.984137) (xy 10.104805 -381.005949)
			(xy 10.152411 -381.035003) (xy 10.195279 -381.070678) (xy 10.232496 -381.112215) (xy 10.263269 -381.158728)
			(xy 10.286941 -381.209225) (xy 10.303009 -381.262632) (xy 10.311129 -381.317808) (xy 10.311638 -381.345694)
			(xy 10.311517 -381.352298) (xy 11.832588 -381.352298) (xy 11.836659 -381.296676) (xy 11.848785 -381.242239)
			(xy 11.868708 -381.190148) (xy 11.896004 -381.141513) (xy 11.93009 -381.09737) (xy 11.970239 -381.058661)
			(xy 12.015597 -381.02621) (xy 12.065197 -381.000709) (xy 12.117981 -380.982702) (xy 12.172824 -380.972572)
			(xy 12.228558 -380.970535) (xy 12.283995 -380.976635) (xy 12.337952 -380.990741) (xy 12.389281 -381.012553)
			(xy 12.436887 -381.041607) (xy 12.479755 -381.077282) (xy 12.516972 -381.118819) (xy 12.547745 -381.165332)
			(xy 12.571417 -381.215829) (xy 12.587485 -381.269236) (xy 12.595605 -381.324412) (xy 12.596114 -381.352298)
			(xy 12.595605 -381.380184) (xy 12.590812 -381.41275) (xy 13.548104 -381.41275) (xy 13.552175 -381.357128)
			(xy 13.564301 -381.302691) (xy 13.584224 -381.2506) (xy 13.61152 -381.201965) (xy 13.645606 -381.157822)
			(xy 13.685755 -381.119113) (xy 13.731113 -381.086662) (xy 13.780713 -381.061161) (xy 13.833497 -381.043154)
			(xy 13.88834 -381.033024) (xy 13.944074 -381.030987) (xy 13.999511 -381.037087) (xy 14.053468 -381.051193)
			(xy 14.104797 -381.073005) (xy 14.152403 -381.102059) (xy 14.195271 -381.137734) (xy 14.232488 -381.179271)
			(xy 14.263261 -381.225784) (xy 14.286933 -381.276281) (xy 14.303001 -381.329688) (xy 14.311121 -381.384864)
			(xy 14.31163 -381.41275) (xy 14.311121 -381.440636) (xy 14.303001 -381.495812) (xy 14.286933 -381.549219)
			(xy 14.263261 -381.599716) (xy 14.232488 -381.646229) (xy 14.195271 -381.687766) (xy 14.152403 -381.723441)
			(xy 14.104797 -381.752495) (xy 14.053468 -381.774307) (xy 13.999511 -381.788413) (xy 13.944074 -381.794513)
			(xy 13.88834 -381.792476) (xy 13.833497 -381.782346) (xy 13.780713 -381.764339) (xy 13.731113 -381.738838)
			(xy 13.685755 -381.706387) (xy 13.645606 -381.667678) (xy 13.61152 -381.623535) (xy 13.584224 -381.5749)
			(xy 13.564301 -381.522809) (xy 13.552175 -381.468372) (xy 13.548104 -381.41275) (xy 12.590812 -381.41275)
			(xy 12.587485 -381.43536) (xy 12.571417 -381.488767) (xy 12.547745 -381.539264) (xy 12.516972 -381.585777)
			(xy 12.479755 -381.627314) (xy 12.436887 -381.662989) (xy 12.389281 -381.692043) (xy 12.337952 -381.713855)
			(xy 12.283995 -381.727961) (xy 12.228558 -381.734061) (xy 12.172824 -381.732024) (xy 12.117981 -381.721894)
			(xy 12.065197 -381.703887) (xy 12.015597 -381.678386) (xy 11.970239 -381.645935) (xy 11.93009 -381.607226)
			(xy 11.896004 -381.563083) (xy 11.868708 -381.514448) (xy 11.848785 -381.462357) (xy 11.836659 -381.40792)
			(xy 11.832588 -381.352298) (xy 10.311517 -381.352298) (xy 10.311129 -381.37358) (xy 10.303009 -381.428756)
			(xy 10.286941 -381.482163) (xy 10.263269 -381.53266) (xy 10.232496 -381.579173) (xy 10.195279 -381.62071)
			(xy 10.152411 -381.656385) (xy 10.104805 -381.685439) (xy 10.053476 -381.707251) (xy 9.999519 -381.721357)
			(xy 9.944082 -381.727457) (xy 9.888348 -381.72542) (xy 9.833505 -381.71529) (xy 9.780721 -381.697283)
			(xy 9.731121 -381.671782) (xy 9.685763 -381.639331) (xy 9.645614 -381.600622) (xy 9.611528 -381.556479)
			(xy 9.584232 -381.507844) (xy 9.564309 -381.455753) (xy 9.552183 -381.401316) (xy 9.548112 -381.345694)
			(xy 8.811458 -381.345694) (xy 8.811514 -381.348742) (xy 8.811005 -381.376628) (xy 8.802885 -381.431804)
			(xy 8.786817 -381.485211) (xy 8.763145 -381.535708) (xy 8.732372 -381.582221) (xy 8.695155 -381.623758)
			(xy 8.652287 -381.659433) (xy 8.604681 -381.688487) (xy 8.553352 -381.710299) (xy 8.499395 -381.724405)
			(xy 8.443958 -381.730505) (xy 8.388224 -381.728468) (xy 8.333381 -381.718338) (xy 8.280597 -381.700331)
			(xy 8.230997 -381.67483) (xy 8.185639 -381.642379) (xy 8.14549 -381.60367) (xy 8.111404 -381.559527)
			(xy 8.084108 -381.510892) (xy 8.064185 -381.458801) (xy 8.052059 -381.404364) (xy 8.047988 -381.348742)
			(xy 2.029533 -381.348742) (xy 2.029205 -381.366722) (xy 2.021085 -381.421898) (xy 2.005017 -381.475305)
			(xy 1.981345 -381.525802) (xy 1.950572 -381.572315) (xy 1.913355 -381.613852) (xy 1.870487 -381.649527)
			(xy 1.822881 -381.678581) (xy 1.771552 -381.700393) (xy 1.717595 -381.714499) (xy 1.662158 -381.720599)
			(xy 1.606424 -381.718562) (xy 1.551581 -381.708432) (xy 1.498797 -381.690425) (xy 1.449197 -381.664924)
			(xy 1.403839 -381.632473) (xy 1.36369 -381.593764) (xy 1.329604 -381.549621) (xy 1.302308 -381.500986)
			(xy 1.282385 -381.448895) (xy 1.270259 -381.394458) (xy 1.266188 -381.338836) (xy 0.529844 -381.338836)
			(xy 0.529844 -383.246884) (xy 4.633212 -383.246884) (xy 4.637283 -383.191262) (xy 4.649409 -383.136825)
			(xy 4.669332 -383.084734) (xy 4.696628 -383.036099) (xy 4.730714 -382.991956) (xy 4.770863 -382.953247)
			(xy 4.816221 -382.920796) (xy 4.865821 -382.895295) (xy 4.918605 -382.877288) (xy 4.973448 -382.867158)
			(xy 5.029182 -382.865121) (xy 5.084619 -382.871221) (xy 5.138576 -382.885327) (xy 5.189905 -382.907139)
			(xy 5.237511 -382.936193) (xy 5.280379 -382.971868) (xy 5.317596 -383.013405) (xy 5.348369 -383.059918)
			(xy 5.372041 -383.110415) (xy 5.388109 -383.163822) (xy 5.396229 -383.218998) (xy 5.396738 -383.246884)
			(xy 5.396229 -383.27477) (xy 5.388109 -383.329946) (xy 5.372041 -383.383353) (xy 5.348369 -383.43385)
			(xy 5.317596 -383.480363) (xy 5.308768 -383.490216) (xy 27.42438 -383.490216) (xy 27.424933 -383.457486)
			(xy 27.433793 -383.392627) (xy 27.451287 -383.329547) (xy 27.477098 -383.26939) (xy 27.493468 -383.241042)
			(xy 27.496765 -383.235009) (xy 27.500382 -383.221752) (xy 27.50058 -383.21488) (xy 27.50058 -382.465326)
			(xy 27.50038 -382.458453) (xy 27.496778 -382.44519) (xy 27.493468 -382.439164) (xy 27.477095 -382.410819)
			(xy 27.451293 -382.350658) (xy 27.433805 -382.287578) (xy 27.424948 -382.222719) (xy 27.42438 -382.18999)
			(xy 27.424967 -382.157261) (xy 27.433817 -382.092404) (xy 27.451301 -382.029324) (xy 27.477102 -381.969165)
			(xy 27.493468 -381.940816) (xy 27.496774 -381.934787) (xy 27.500386 -381.921527) (xy 27.50058 -381.914654)
			(xy 27.50058 -381.628904) (xy 27.501088 -381.618798) (xy 27.508821 -381.600124) (xy 27.52311 -381.58583)
			(xy 27.541782 -381.578091) (xy 27.551888 -381.577596) (xy 28.268168 -381.577596) (xy 28.278288 -381.578042)
			(xy 28.29699 -381.585779) (xy 28.311306 -381.600086) (xy 28.319053 -381.618784) (xy 28.319476 -381.628904)
			(xy 28.319476 -381.914654) (xy 28.319688 -381.921526) (xy 28.323283 -381.934788) (xy 28.326588 -381.940816)
			(xy 28.342959 -381.969162) (xy 28.36876 -382.029323) (xy 28.386248 -382.092403) (xy 28.395107 -382.157261)
			(xy 28.395676 -382.18999) (xy 28.395131 -382.22271) (xy 31.825016 -382.22271) (xy 31.825018 -382.157273)
			(xy 31.833803 -382.092427) (xy 31.851213 -382.029348) (xy 31.876933 -381.969177) (xy 31.893256 -381.940816)
			(xy 31.896561 -381.934787) (xy 31.900173 -381.921527) (xy 31.900368 -381.914654) (xy 31.900368 -381.628904)
			(xy 31.900824 -381.618754) (xy 31.908613 -381.600008) (xy 31.922998 -381.585686) (xy 31.941778 -381.57798)
			(xy 31.95193 -381.577596) (xy 32.66821 -381.577596) (xy 32.678332 -381.578117) (xy 32.697045 -381.58584)
			(xy 32.711399 -381.600115) (xy 32.719226 -381.618785) (xy 32.719772 -381.628904) (xy 32.719772 -381.914654)
			(xy 32.719985 -381.921526) (xy 32.723579 -381.934788) (xy 32.726884 -381.940816) (xy 32.743197 -381.969182)
			(xy 32.768914 -382.029352) (xy 32.786322 -382.09243) (xy 32.795107 -382.157274) (xy 32.795108 -382.222709)
			(xy 32.786326 -382.287553) (xy 32.76892 -382.350631) (xy 32.743205 -382.410803) (xy 32.726884 -382.439164)
			(xy 32.723581 -382.445194) (xy 32.719968 -382.458454) (xy 32.719772 -382.465326) (xy 32.719772 -383.21488)
			(xy 32.719975 -383.221752) (xy 32.723576 -383.235015) (xy 32.726884 -383.241042) (xy 32.743219 -383.269396)
			(xy 32.768934 -383.329569) (xy 32.78634 -383.392649) (xy 32.795121 -383.457495) (xy 32.79512 -383.522932)
			(xy 32.786334 -383.587778) (xy 32.768925 -383.650857) (xy 32.743207 -383.711028) (xy 32.726884 -383.73939)
			(xy 32.723572 -383.745416) (xy 32.719965 -383.758679) (xy 32.719772 -383.765552) (xy 32.719772 -384.051556)
			(xy 32.719342 -384.061711) (xy 32.711555 -384.080468) (xy 32.697161 -384.094793) (xy 32.678367 -384.10249)
			(xy 32.66821 -384.102864) (xy 31.95193 -384.102864) (xy 31.941806 -384.102349) (xy 31.923086 -384.094632)
			(xy 31.908729 -384.080354) (xy 31.900908 -384.061678) (xy 31.900368 -384.051556) (xy 31.900368 -383.765552)
			(xy 31.90016 -383.75868) (xy 31.896563 -383.745417) (xy 31.893256 -383.73939) (xy 31.876947 -383.711021)
			(xy 31.851227 -383.650852) (xy 31.833817 -383.587775) (xy 31.825031 -383.522932) (xy 31.825029 -383.457496)
			(xy 31.833811 -383.392652) (xy 31.851218 -383.329574) (xy 31.876934 -383.269403) (xy 31.893256 -383.241042)
			(xy 31.896552 -383.235008) (xy 31.90017 -383.221752) (xy 31.900368 -383.21488) (xy 31.900368 -382.465326)
			(xy 31.90017 -382.458453) (xy 31.896566 -382.44519) (xy 31.893256 -382.439164) (xy 31.876925 -382.410808)
			(xy 31.851207 -382.350635) (xy 31.833799 -382.287556) (xy 31.825016 -382.22271) (xy 28.395131 -382.22271)
			(xy 28.395131 -382.22272) (xy 28.38627 -382.287579) (xy 28.368773 -382.35066) (xy 28.34296 -382.410817)
			(xy 28.326588 -382.439164) (xy 28.323285 -382.445194) (xy 28.319672 -382.458454) (xy 28.319476 -382.465326)
			(xy 28.319476 -383.21488) (xy 28.319679 -383.221752) (xy 28.32328 -383.235015) (xy 28.326588 -383.241042)
			(xy 28.342969 -383.269383) (xy 28.365871 -383.322789) (xy 29.62486 -383.322789) (xy 29.624864 -383.25735)
			(xy 29.633652 -383.192504) (xy 29.651064 -383.129424) (xy 29.676784 -383.069252) (xy 29.693108 -383.04089)
			(xy 29.696427 -383.034867) (xy 29.70003 -383.021602) (xy 29.70022 -383.014728) (xy 29.70022 -382.728724)
			(xy 29.700641 -382.718569) (xy 29.708433 -382.699813) (xy 29.72283 -382.685488) (xy 29.741625 -382.677791)
			(xy 29.751782 -382.677416) (xy 30.468062 -382.677416) (xy 30.478183 -382.677957) (xy 30.496899 -382.685668)
			(xy 30.511256 -382.699938) (xy 30.51908 -382.718606) (xy 30.519624 -382.728724) (xy 30.519624 -383.014728)
			(xy 30.519802 -383.021602) (xy 30.523419 -383.034865) (xy 30.526736 -383.04089) (xy 30.543029 -383.069268)
			(xy 30.56875 -383.129435) (xy 30.586163 -383.19251) (xy 30.59495 -383.257352) (xy 30.594955 -383.322786)
			(xy 30.586175 -383.387629) (xy 30.568771 -383.450707) (xy 30.543057 -383.510877) (xy 30.526736 -383.539238)
			(xy 30.523411 -383.545258) (xy 30.519811 -383.558525) (xy 30.519624 -383.5654) (xy 30.519624 -384.3147)
			(xy 30.519813 -384.321573) (xy 30.523423 -384.334836) (xy 30.526736 -384.340862) (xy 30.54309 -384.369206)
			(xy 30.568806 -384.429381) (xy 30.586211 -384.492463) (xy 30.594991 -384.557311) (xy 30.594989 -384.590036)
			(xy 34.024316 -384.590036) (xy 34.024873 -384.557306) (xy 34.033731 -384.492448) (xy 34.051224 -384.429367)
			(xy 34.077034 -384.36921) (xy 34.093404 -384.340862) (xy 34.096733 -384.334844) (xy 34.100329 -384.321575)
			(xy 34.100516 -384.3147) (xy 34.100516 -383.5654) (xy 34.100322 -383.558527) (xy 34.096715 -383.545264)
			(xy 34.093404 -383.539238) (xy 34.077054 -383.51088) (xy 34.051248 -383.450724) (xy 34.033754 -383.387647)
			(xy 34.024889 -383.322792) (xy 34.024316 -383.290064) (xy 34.024886 -383.257335) (xy 34.03374 -383.192476)
			(xy 34.051229 -383.129396) (xy 34.077036 -383.069238) (xy 34.093404 -383.04089) (xy 34.096723 -383.034867)
			(xy 34.100326 -383.021602) (xy 34.100516 -383.014728) (xy 34.100516 -382.728724) (xy 34.100936 -382.718601)
			(xy 34.108679 -382.699895) (xy 34.122995 -382.685579) (xy 34.141701 -382.677836) (xy 34.151824 -382.677416)
			(xy 34.868104 -382.677416) (xy 34.878229 -382.677813) (xy 34.896935 -382.685566) (xy 34.91125 -382.699888)
			(xy 34.918992 -382.718599) (xy 34.919412 -382.728724) (xy 34.919412 -383.014728) (xy 34.919592 -383.021602)
			(xy 34.923208 -383.034865) (xy 34.926524 -383.04089) (xy 34.942888 -383.06924) (xy 34.96869 -383.1294)
			(xy 34.98618 -383.192479) (xy 34.995041 -383.257335) (xy 34.995612 -383.290064) (xy 34.995051 -383.322794)
			(xy 34.986193 -383.387652) (xy 34.968702 -383.450732) (xy 34.951763 -383.490216) (xy 36.224464 -383.490216)
			(xy 36.225019 -383.457486) (xy 36.233879 -383.392628) (xy 36.251372 -383.329548) (xy 36.277182 -383.26939)
			(xy 36.293552 -383.241042) (xy 36.296848 -383.235008) (xy 36.300466 -383.221752) (xy 36.300664 -383.21488)
			(xy 36.300664 -382.465326) (xy 36.300467 -382.458453) (xy 36.296863 -382.44519) (xy 36.293552 -382.439164)
			(xy 36.277177 -382.41082) (xy 36.251376 -382.350659) (xy 36.233889 -382.287578) (xy 36.225032 -382.22272)
			(xy 36.224464 -382.18999) (xy 36.225053 -382.157261) (xy 36.233903 -382.092404) (xy 36.251386 -382.029324)
			(xy 36.277187 -381.969165) (xy 36.293552 -381.940816) (xy 36.296857 -381.934787) (xy 36.300469 -381.921527)
			(xy 36.300664 -381.914654) (xy 36.300664 -381.628904) (xy 36.301188 -381.6188) (xy 36.308917 -381.600129)
			(xy 36.323202 -381.585835) (xy 36.341868 -381.578094) (xy 36.351972 -381.577596) (xy 37.068252 -381.577596)
			(xy 37.078371 -381.578055) (xy 37.097073 -381.585787) (xy 37.111388 -381.60009) (xy 37.119136 -381.618786)
			(xy 37.11956 -381.628904) (xy 37.11956 -381.914654) (xy 37.119774 -381.921526) (xy 37.123368 -381.934788)
			(xy 37.126672 -381.940816) (xy 37.143041 -381.969163) (xy 37.168843 -382.029323) (xy 37.186332 -382.092403)
			(xy 37.195191 -382.157261) (xy 37.19576 -382.18999) (xy 37.195204 -382.22272) (xy 37.186344 -382.287578)
			(xy 37.168851 -382.350658) (xy 37.143041 -382.410816) (xy 37.126672 -382.439164) (xy 37.123368 -382.445194)
			(xy 37.119756 -382.458454) (xy 37.11956 -382.465326) (xy 37.11956 -383.21488) (xy 37.119765 -383.221752)
			(xy 37.123365 -383.235015) (xy 37.126672 -383.241042) (xy 37.143052 -383.269384) (xy 37.165953 -383.322788)
			(xy 38.424947 -383.322788) (xy 38.424951 -383.25735) (xy 38.433738 -383.192504) (xy 38.451149 -383.129424)
			(xy 38.476869 -383.069252) (xy 38.493192 -383.04089) (xy 38.49651 -383.034867) (xy 38.500114 -383.021602)
			(xy 38.500304 -383.014728) (xy 38.500304 -382.728724) (xy 38.500741 -382.718571) (xy 38.50853 -382.699818)
			(xy 38.522922 -382.685494) (xy 38.541711 -382.677794) (xy 38.551866 -382.677416) (xy 39.268146 -382.677416)
			(xy 39.278273 -382.677888) (xy 39.29699 -382.685627) (xy 39.311344 -382.699917) (xy 39.319166 -382.7186)
			(xy 39.319708 -382.728724) (xy 39.319708 -383.014728) (xy 39.319888 -383.021602) (xy 39.323504 -383.034865)
			(xy 39.32682 -383.04089) (xy 39.343113 -383.069268) (xy 39.368836 -383.129435) (xy 39.386249 -383.19251)
			(xy 39.395037 -383.257352) (xy 39.395041 -383.322787) (xy 39.386261 -383.38763) (xy 39.368856 -383.450707)
			(xy 39.351971 -383.490216) (xy 40.624252 -383.490216) (xy 40.624809 -383.457486) (xy 40.633668 -383.392628)
			(xy 40.651161 -383.329548) (xy 40.676971 -383.26939) (xy 40.69334 -383.241042) (xy 40.696635 -383.235008)
			(xy 40.700254 -383.221752) (xy 40.700452 -383.21488) (xy 40.700452 -382.465326) (xy 40.700256 -382.458453)
			(xy 40.696651 -382.44519) (xy 40.69334 -382.439164) (xy 40.676964 -382.41082) (xy 40.651164 -382.350659)
			(xy 40.633677 -382.287578) (xy 40.62482 -382.22272) (xy 40.624252 -382.18999) (xy 40.624842 -382.157261)
			(xy 40.633691 -382.092404) (xy 40.651175 -382.029324) (xy 40.676975 -381.969165) (xy 40.69334 -381.940816)
			(xy 40.696644 -381.934786) (xy 40.700257 -381.921527) (xy 40.700452 -381.914654) (xy 40.700452 -381.628904)
			(xy 40.700987 -381.618801) (xy 40.708715 -381.600133) (xy 40.722996 -381.585839) (xy 40.741658 -381.578096)
			(xy 40.75176 -381.577596) (xy 41.46804 -381.577596) (xy 41.478151 -381.578052) (xy 41.496829 -381.585802)
			(xy 41.511122 -381.600108) (xy 41.518856 -381.618793) (xy 41.519348 -381.628904) (xy 41.519348 -381.914654)
			(xy 41.519551 -381.921526) (xy 41.523151 -381.93479) (xy 41.52646 -381.940816) (xy 41.542828 -381.969164)
			(xy 41.56863 -382.029324) (xy 41.586119 -382.092404) (xy 41.594979 -382.157261) (xy 41.595548 -382.18999)
			(xy 41.594994 -382.22271) (xy 45.024892 -382.22271) (xy 45.024893 -382.157273) (xy 45.033678 -382.092428)
			(xy 45.051087 -382.029349) (xy 45.076805 -381.969177) (xy 45.093128 -381.940816) (xy 45.096439 -381.93479)
			(xy 45.100047 -381.921527) (xy 45.10024 -381.914654) (xy 45.10024 -381.628904) (xy 45.100626 -381.618745)
			(xy 45.108427 -381.599985) (xy 45.122836 -381.58566) (xy 45.141641 -381.577968) (xy 45.151802 -381.577596)
			(xy 45.868082 -381.577596) (xy 45.878202 -381.57814) (xy 45.896915 -381.585854) (xy 45.91127 -381.600122)
			(xy 45.919098 -381.618787) (xy 45.919644 -381.628904) (xy 45.919644 -381.914654) (xy 45.919848 -381.921526)
			(xy 45.923447 -381.934789) (xy 45.926756 -381.940816) (xy 45.94307 -381.969182) (xy 45.968789 -382.029352)
			(xy 45.986198 -382.09243) (xy 45.994982 -382.157273) (xy 45.994984 -382.222709) (xy 45.986201 -382.287554)
			(xy 45.968794 -382.350632) (xy 45.943078 -382.410803) (xy 45.926756 -382.439164) (xy 45.923458 -382.445197)
			(xy 45.919841 -382.458454) (xy 45.919644 -382.465326) (xy 45.919644 -383.21488) (xy 45.919838 -383.221753)
			(xy 45.923444 -383.235016) (xy 45.926756 -383.241042) (xy 45.943092 -383.269396) (xy 45.965911 -383.322789)
			(xy 47.225019 -383.322789) (xy 47.225023 -383.257349) (xy 47.233812 -383.192502) (xy 47.251226 -383.129422)
			(xy 47.27695 -383.069251) (xy 47.293276 -383.04089) (xy 47.296593 -383.034866) (xy 47.300198 -383.021602)
			(xy 47.300388 -383.014728) (xy 47.300388 -382.728724) (xy 47.300841 -382.718573) (xy 47.308626 -382.699823)
			(xy 47.323013 -382.685499) (xy 47.341797 -382.677797) (xy 47.35195 -382.677416) (xy 48.06823 -382.677416)
			(xy 48.078356 -382.677901) (xy 48.097073 -382.685634) (xy 48.111427 -382.699921) (xy 48.11925 -382.718601)
			(xy 48.119792 -382.728724) (xy 48.119792 -383.014728) (xy 48.119974 -383.021602) (xy 48.123589 -383.034865)
			(xy 48.126904 -383.04089) (xy 48.143194 -383.069269) (xy 48.168913 -383.129436) (xy 48.186322 -383.192511)
			(xy 48.195109 -383.257352) (xy 48.195113 -383.322786) (xy 48.186335 -383.387628) (xy 48.168933 -383.450705)
			(xy 48.143222 -383.510876) (xy 48.126904 -383.539238) (xy 48.123576 -383.545256) (xy 48.119979 -383.558525)
			(xy 48.119792 -383.5654) (xy 48.119792 -384.3147) (xy 48.119985 -384.321573) (xy 48.123592 -384.334836)
			(xy 48.126904 -384.340862) (xy 48.143255 -384.369207) (xy 48.168968 -384.429382) (xy 48.186371 -384.492464)
			(xy 48.19515 -384.557312) (xy 48.195146 -384.62275) (xy 48.186359 -384.687596) (xy 48.182159 -384.702812)
			(xy 57.268616 -384.702812) (xy 57.272687 -384.64719) (xy 57.284813 -384.592753) (xy 57.304736 -384.540662)
			(xy 57.332032 -384.492027) (xy 57.366118 -384.447884) (xy 57.406267 -384.409175) (xy 57.451625 -384.376724)
			(xy 57.501225 -384.351223) (xy 57.554009 -384.333216) (xy 57.608852 -384.323086) (xy 57.664586 -384.321049)
			(xy 57.720023 -384.327149) (xy 57.77398 -384.341255) (xy 57.825309 -384.363067) (xy 57.872915 -384.392121)
			(xy 57.915783 -384.427796) (xy 57.953 -384.469333) (xy 57.983773 -384.515846) (xy 58.007445 -384.566343)
			(xy 58.023513 -384.61975) (xy 58.031633 -384.674926) (xy 58.032142 -384.702812) (xy 58.031633 -384.730698)
			(xy 58.023513 -384.785874) (xy 58.007445 -384.839281) (xy 57.983773 -384.889778) (xy 57.953 -384.936291)
			(xy 57.915783 -384.977828) (xy 57.872915 -385.013503) (xy 57.825309 -385.042557) (xy 57.77398 -385.064369)
			(xy 57.720023 -385.078475) (xy 57.664586 -385.084575) (xy 57.608852 -385.082538) (xy 57.554009 -385.072408)
			(xy 57.501225 -385.054401) (xy 57.451625 -385.0289) (xy 57.406267 -384.996449) (xy 57.366118 -384.95774)
			(xy 57.332032 -384.913597) (xy 57.304736 -384.864962) (xy 57.284813 -384.812871) (xy 57.272687 -384.758434)
			(xy 57.268616 -384.702812) (xy 48.182159 -384.702812) (xy 48.168947 -384.750676) (xy 48.143227 -384.810848)
			(xy 48.126904 -384.83921) (xy 48.123586 -384.845233) (xy 48.119982 -384.858498) (xy 48.119792 -384.865372)
			(xy 48.119792 -385.151376) (xy 48.119359 -385.16153) (xy 48.11157 -385.180283) (xy 48.097176 -385.194608)
			(xy 48.078386 -385.202307) (xy 48.06823 -385.202684) (xy 47.35195 -385.202684) (xy 47.341829 -385.202133)
			(xy 47.323114 -385.194426) (xy 47.308757 -385.18016) (xy 47.300932 -385.161493) (xy 47.300388 -385.151376)
			(xy 47.300388 -384.865372) (xy 47.300208 -384.858498) (xy 47.296592 -384.845235) (xy 47.293276 -384.83921)
			(xy 47.276983 -384.810832) (xy 47.251261 -384.750665) (xy 47.233848 -384.68759) (xy 47.22506 -384.622748)
			(xy 47.225056 -384.557314) (xy 47.233835 -384.492471) (xy 47.25124 -384.429393) (xy 47.276955 -384.369223)
			(xy 47.293276 -384.340862) (xy 47.296603 -384.334843) (xy 47.300201 -384.321575) (xy 47.300388 -384.3147)
			(xy 47.300388 -383.5654) (xy 47.300197 -383.558527) (xy 47.296588 -383.545264) (xy 47.293276 -383.539238)
			(xy 47.276922 -383.510894) (xy 47.251205 -383.450719) (xy 47.233799 -383.387637) (xy 47.225019 -383.322789)
			(xy 45.965911 -383.322789) (xy 45.968809 -383.329569) (xy 45.986215 -383.392649) (xy 45.994997 -383.457495)
			(xy 45.994995 -383.522933) (xy 45.98621 -383.587778) (xy 45.968799 -383.650857) (xy 45.943079 -383.711029)
			(xy 45.926756 -383.73939) (xy 45.923449 -383.745419) (xy 45.919838 -383.758679) (xy 45.919644 -383.765552)
			(xy 45.919644 -384.051556) (xy 45.919143 -384.061702) (xy 45.91137 -384.080445) (xy 45.896998 -384.094768)
			(xy 45.878229 -384.102477) (xy 45.868082 -384.102864) (xy 45.151802 -384.102864) (xy 45.141676 -384.102372)
			(xy 45.122956 -384.094645) (xy 45.108599 -384.080361) (xy 45.100779 -384.06168) (xy 45.10024 -384.051556)
			(xy 45.10024 -383.765552) (xy 45.100023 -383.758681) (xy 45.096431 -383.745418) (xy 45.093128 -383.73939)
			(xy 45.07682 -383.711021) (xy 45.051101 -383.650852) (xy 45.033692 -383.587775) (xy 45.024907 -383.522931)
			(xy 45.024905 -383.457496) (xy 45.033687 -383.392652) (xy 45.051092 -383.329574) (xy 45.076807 -383.269403)
			(xy 45.093128 -383.241042) (xy 45.09643 -383.235011) (xy 45.100043 -383.221752) (xy 45.10024 -383.21488)
			(xy 45.10024 -382.465326) (xy 45.100033 -382.458454) (xy 45.096435 -382.445191) (xy 45.093128 -382.439164)
			(xy 45.076798 -382.410807) (xy 45.051081 -382.350635) (xy 45.033675 -382.287555) (xy 45.024892 -382.22271)
			(xy 41.594994 -382.22271) (xy 41.594994 -382.22272) (xy 41.586134 -382.287578) (xy 41.56864 -382.350658)
			(xy 41.54283 -382.410816) (xy 41.52646 -382.439164) (xy 41.523163 -382.445197) (xy 41.519545 -382.458454)
			(xy 41.519348 -382.465326) (xy 41.519348 -383.21488) (xy 41.519542 -383.221753) (xy 41.523148 -383.235016)
			(xy 41.52646 -383.241042) (xy 41.542838 -383.269384) (xy 41.568638 -383.329546) (xy 41.586124 -383.392628)
			(xy 41.59498 -383.457486) (xy 41.595548 -383.490216) (xy 41.594961 -383.522945) (xy 41.58611 -383.587802)
			(xy 41.568626 -383.650882) (xy 41.542825 -383.711041) (xy 41.52646 -383.73939) (xy 41.523154 -383.745419)
			(xy 41.519542 -383.758679) (xy 41.519348 -383.765552) (xy 41.519348 -384.051556) (xy 41.518849 -384.06167)
			(xy 41.511124 -384.080363) (xy 41.496834 -384.094677) (xy 41.478153 -384.102432) (xy 41.46804 -384.102864)
			(xy 40.75176 -384.102864) (xy 40.74163 -384.102516) (xy 40.722919 -384.094748) (xy 40.708605 -384.08041)
			(xy 40.700868 -384.061686) (xy 40.700452 -384.051556) (xy 40.700452 -383.765552) (xy 40.700246 -383.75868)
			(xy 40.696648 -383.745417) (xy 40.69334 -383.73939) (xy 40.676974 -383.711041) (xy 40.651172 -383.650882)
			(xy 40.633682 -383.587802) (xy 40.624822 -383.522945) (xy 40.624252 -383.490216) (xy 39.351971 -383.490216)
			(xy 39.343141 -383.510877) (xy 39.32682 -383.539238) (xy 39.323493 -383.545257) (xy 39.319895 -383.558525)
			(xy 39.319708 -383.5654) (xy 39.319708 -384.3147) (xy 39.319899 -384.321573) (xy 39.323508 -384.334836)
			(xy 39.32682 -384.340862) (xy 39.343174 -384.369206) (xy 39.368891 -384.429381) (xy 39.386297 -384.492463)
			(xy 39.395078 -384.557311) (xy 39.395076 -384.590036) (xy 42.8244 -384.590036) (xy 42.82496 -384.557306)
			(xy 42.833817 -384.492448) (xy 42.851309 -384.429368) (xy 42.877119 -384.36921) (xy 42.893488 -384.340862)
			(xy 42.896815 -384.334844) (xy 42.900413 -384.321575) (xy 42.9006 -384.3147) (xy 42.9006 -383.5654)
			(xy 42.900408 -383.558527) (xy 42.8968 -383.545264) (xy 42.893488 -383.539238) (xy 42.877136 -383.510881)
			(xy 42.851331 -383.450724) (xy 42.833838 -383.387647) (xy 42.824973 -383.322792) (xy 42.8244 -383.290064)
			(xy 42.824972 -383.257335) (xy 42.833826 -383.192477) (xy 42.851315 -383.129397) (xy 42.87712 -383.069238)
			(xy 42.893488 -383.04089) (xy 42.896805 -383.034867) (xy 42.90041 -383.021602) (xy 42.9006 -383.014728)
			(xy 42.9006 -382.728724) (xy 42.901035 -382.718603) (xy 42.908776 -382.6999) (xy 42.923086 -382.685585)
			(xy 42.941787 -382.677839) (xy 42.951908 -382.677416) (xy 43.668188 -382.677416) (xy 43.678312 -382.677826)
			(xy 43.697018 -382.685573) (xy 43.711333 -382.699892) (xy 43.719076 -382.7186) (xy 43.719496 -382.728724)
			(xy 43.719496 -383.014728) (xy 43.719678 -383.021602) (xy 43.723293 -383.034865) (xy 43.726608 -383.04089)
			(xy 43.74297 -383.069241) (xy 43.768773 -383.1294) (xy 43.786263 -383.192479) (xy 43.795125 -383.257335)
			(xy 43.795696 -383.290064) (xy 43.795137 -383.322794) (xy 43.786279 -383.387652) (xy 43.768787 -383.450732)
			(xy 43.742977 -383.51089) (xy 43.726608 -383.539238) (xy 43.72328 -383.545256) (xy 43.719683 -383.558525)
			(xy 43.719496 -383.5654) (xy 43.719496 -384.3147) (xy 43.719688 -384.321573) (xy 43.723296 -384.334836)
			(xy 43.726608 -384.340862) (xy 43.742959 -384.369219) (xy 43.768764 -384.429376) (xy 43.786258 -384.492453)
			(xy 43.795123 -384.557308) (xy 43.795696 -384.590036) (xy 43.795124 -384.622765) (xy 43.78627 -384.687623)
			(xy 43.768782 -384.750704) (xy 43.742976 -384.810862) (xy 43.726608 -384.83921) (xy 43.72329 -384.845233)
			(xy 43.719686 -384.858498) (xy 43.719496 -384.865372) (xy 43.719496 -385.151376) (xy 43.719064 -385.161497)
			(xy 43.711323 -385.180201) (xy 43.697011 -385.194517) (xy 43.678309 -385.202262) (xy 43.668188 -385.202684)
			(xy 42.951908 -385.202684) (xy 42.941784 -385.202277) (xy 42.923078 -385.194529) (xy 42.908762 -385.180209)
			(xy 42.90102 -385.1615) (xy 42.9006 -385.151376) (xy 42.9006 -384.865372) (xy 42.900419 -384.858498)
			(xy 42.896803 -384.845235) (xy 42.893488 -384.83921) (xy 42.877125 -384.810859) (xy 42.851323 -384.7507)
			(xy 42.833833 -384.687621) (xy 42.824971 -384.622765) (xy 42.8244 -384.590036) (xy 39.395076 -384.590036)
			(xy 39.395074 -384.622751) (xy 39.386285 -384.687598) (xy 39.36887 -384.750678) (xy 39.343146 -384.810849)
			(xy 39.32682 -384.83921) (xy 39.323503 -384.845234) (xy 39.319898 -384.858498) (xy 39.319708 -384.865372)
			(xy 39.319708 -385.151376) (xy 39.319259 -385.161528) (xy 39.311473 -385.180278) (xy 39.297085 -385.194602)
			(xy 39.278299 -385.202304) (xy 39.268146 -385.202684) (xy 38.551866 -385.202684) (xy 38.54174 -385.202202)
			(xy 38.523023 -385.194468) (xy 38.508668 -385.18018) (xy 38.500846 -385.1615) (xy 38.500304 -385.151376)
			(xy 38.500304 -384.865372) (xy 38.500122 -384.858498) (xy 38.496507 -384.845235) (xy 38.493192 -384.83921)
			(xy 38.476902 -384.810831) (xy 38.451184 -384.750664) (xy 38.433774 -384.687589) (xy 38.424988 -384.622748)
			(xy 38.424983 -384.557314) (xy 38.433762 -384.492472) (xy 38.451163 -384.429395) (xy 38.476874 -384.369224)
			(xy 38.493192 -384.340862) (xy 38.49652 -384.334844) (xy 38.500117 -384.321575) (xy 38.500304 -384.3147)
			(xy 38.500304 -383.5654) (xy 38.500112 -383.558527) (xy 38.496504 -383.545264) (xy 38.493192 -383.539238)
			(xy 38.476841 -383.510893) (xy 38.451128 -383.450718) (xy 38.433725 -383.387636) (xy 38.424947 -383.322788)
			(xy 37.165953 -383.322788) (xy 37.168851 -383.329546) (xy 37.186337 -383.392628) (xy 37.195192 -383.457486)
			(xy 37.19576 -383.490216) (xy 37.195171 -383.522945) (xy 37.186321 -383.587802) (xy 37.168837 -383.650882)
			(xy 37.143037 -383.711041) (xy 37.126672 -383.73939) (xy 37.123359 -383.745415) (xy 37.119753 -383.758679)
			(xy 37.11956 -383.765552) (xy 37.11956 -384.051556) (xy 37.119147 -384.061681) (xy 37.111406 -384.080391)
			(xy 37.097087 -384.094708) (xy 37.078377 -384.102448) (xy 37.068252 -384.102864) (xy 36.351972 -384.102864)
			(xy 36.341843 -384.102506) (xy 36.323132 -384.094742) (xy 36.308817 -384.080407) (xy 36.30108 -384.061685)
			(xy 36.300664 -384.051556) (xy 36.300664 -383.765552) (xy 36.300457 -383.75868) (xy 36.296859 -383.745417)
			(xy 36.293552 -383.73939) (xy 36.277187 -383.71104) (xy 36.251384 -383.650881) (xy 36.233894 -383.587802)
			(xy 36.225034 -383.522945) (xy 36.224464 -383.490216) (xy 34.951763 -383.490216) (xy 34.942893 -383.51089)
			(xy 34.926524 -383.539238) (xy 34.923197 -383.545257) (xy 34.919599 -383.558525) (xy 34.919412 -383.5654)
			(xy 34.919412 -384.3147) (xy 34.919603 -384.321573) (xy 34.923212 -384.334836) (xy 34.926524 -384.340862)
			(xy 34.942877 -384.369218) (xy 34.968681 -384.429375) (xy 34.986174 -384.492453) (xy 34.995039 -384.557308)
			(xy 34.995612 -384.590036) (xy 34.995038 -384.622765) (xy 34.986185 -384.687623) (xy 34.968696 -384.750703)
			(xy 34.942891 -384.810862) (xy 34.926524 -384.83921) (xy 34.923207 -384.845234) (xy 34.919602 -384.858498)
			(xy 34.919412 -384.865372) (xy 34.919412 -385.151376) (xy 34.918965 -385.161495) (xy 34.911227 -385.180196)
			(xy 34.89692 -385.194511) (xy 34.878223 -385.202259) (xy 34.868104 -385.202684) (xy 34.151824 -385.202684)
			(xy 34.141701 -385.202264) (xy 34.122995 -385.194521) (xy 34.108679 -385.180205) (xy 34.100936 -385.161499)
			(xy 34.100516 -385.151376) (xy 34.100516 -384.865372) (xy 34.100333 -384.858498) (xy 34.096718 -384.845235)
			(xy 34.093404 -384.83921) (xy 34.077043 -384.810858) (xy 34.05124 -384.7507) (xy 34.033749 -384.687621)
			(xy 34.024887 -384.622765) (xy 34.024316 -384.590036) (xy 30.594989 -384.590036) (xy 30.594987 -384.622751)
			(xy 30.586199 -384.687597) (xy 30.568785 -384.750677) (xy 30.543061 -384.810849) (xy 30.526736 -384.83921)
			(xy 30.523421 -384.845234) (xy 30.519815 -384.858498) (xy 30.519624 -384.865372) (xy 30.519624 -385.151376)
			(xy 30.519159 -385.161526) (xy 30.511376 -385.180273) (xy 30.496993 -385.194596) (xy 30.478213 -385.202301)
			(xy 30.468062 -385.202684) (xy 29.751782 -385.202684) (xy 29.741657 -385.202189) (xy 29.72294 -385.19446)
			(xy 29.708585 -385.180177) (xy 29.700762 -385.161498) (xy 29.70022 -385.151376) (xy 29.70022 -384.865372)
			(xy 29.700036 -384.858498) (xy 29.696422 -384.845236) (xy 29.693108 -384.83921) (xy 29.676817 -384.810832)
			(xy 29.651098 -384.750664) (xy 29.633688 -384.687589) (xy 29.624901 -384.622748) (xy 29.624897 -384.557314)
			(xy 29.633676 -384.492472) (xy 29.651078 -384.429394) (xy 29.676789 -384.369224) (xy 29.693108 -384.340862)
			(xy 29.696437 -384.334844) (xy 29.700033 -384.321575) (xy 29.70022 -384.3147) (xy 29.70022 -383.5654)
			(xy 29.700026 -383.558527) (xy 29.696419 -383.545264) (xy 29.693108 -383.539238) (xy 29.676756 -383.510893)
			(xy 29.651043 -383.450718) (xy 29.633639 -383.387636) (xy 29.62486 -383.322789) (xy 28.365871 -383.322789)
			(xy 28.368768 -383.329545) (xy 28.386253 -383.392627) (xy 28.395108 -383.457486) (xy 28.395676 -383.490216)
			(xy 28.395098 -383.522945) (xy 28.386247 -383.587803) (xy 28.36876 -383.650883) (xy 28.342955 -383.711042)
			(xy 28.326588 -383.73939) (xy 28.323276 -383.745416) (xy 28.319669 -383.758679) (xy 28.319476 -383.765552)
			(xy 28.319476 -384.051556) (xy 28.319047 -384.061679) (xy 28.311309 -384.080386) (xy 28.296996 -384.094702)
			(xy 28.27829 -384.102445) (xy 28.268168 -384.102864) (xy 27.551888 -384.102864) (xy 27.54176 -384.102493)
			(xy 27.523049 -384.094734) (xy 27.508734 -384.080404) (xy 27.500996 -384.061684) (xy 27.50058 -384.051556)
			(xy 27.50058 -383.765552) (xy 27.500371 -383.75868) (xy 27.496774 -383.745417) (xy 27.493468 -383.73939)
			(xy 27.477105 -383.711039) (xy 27.451301 -383.650881) (xy 27.43381 -383.587802) (xy 27.42495 -383.522945)
			(xy 27.42438 -383.490216) (xy 5.308768 -383.490216) (xy 5.280379 -383.5219) (xy 5.237511 -383.557575)
			(xy 5.189905 -383.586629) (xy 5.138576 -383.608441) (xy 5.084619 -383.622547) (xy 5.029182 -383.628647)
			(xy 4.973448 -383.62661) (xy 4.918605 -383.61648) (xy 4.865821 -383.598473) (xy 4.816221 -383.572972)
			(xy 4.770863 -383.540521) (xy 4.730714 -383.501812) (xy 4.696628 -383.457669) (xy 4.669332 -383.409034)
			(xy 4.649409 -383.356943) (xy 4.637283 -383.302506) (xy 4.633212 -383.246884) (xy 0.529844 -383.246884)
			(xy 0.529844 -384.746754) (xy 14.91564 -384.746754) (xy 14.919711 -384.691132) (xy 14.931837 -384.636695)
			(xy 14.95176 -384.584604) (xy 14.979056 -384.535969) (xy 15.013142 -384.491826) (xy 15.053291 -384.453117)
			(xy 15.098649 -384.420666) (xy 15.148249 -384.395165) (xy 15.201033 -384.377158) (xy 15.255876 -384.367028)
			(xy 15.31161 -384.364991) (xy 15.367047 -384.371091) (xy 15.421004 -384.385197) (xy 15.472333 -384.407009)
			(xy 15.519939 -384.436063) (xy 15.562807 -384.471738) (xy 15.600024 -384.513275) (xy 15.630797 -384.559788)
			(xy 15.654469 -384.610285) (xy 15.670537 -384.663692) (xy 15.678657 -384.718868) (xy 15.679166 -384.746754)
			(xy 15.678657 -384.77464) (xy 15.670537 -384.829816) (xy 15.654469 -384.883223) (xy 15.630797 -384.93372)
			(xy 15.600024 -384.980233) (xy 15.562807 -385.02177) (xy 15.519939 -385.057445) (xy 15.472333 -385.086499)
			(xy 15.421004 -385.108311) (xy 15.367047 -385.122417) (xy 15.31161 -385.128517) (xy 15.255876 -385.12648)
			(xy 15.201033 -385.11635) (xy 15.148249 -385.098343) (xy 15.098649 -385.072842) (xy 15.053291 -385.040391)
			(xy 15.013142 -385.001682) (xy 14.979056 -384.957539) (xy 14.95176 -384.908904) (xy 14.931837 -384.856813)
			(xy 14.919711 -384.802376) (xy 14.91564 -384.746754) (xy 0.529844 -384.746754) (xy 0.529844 -385.718812)
			(xy 56.34177 -385.718812) (xy 56.345841 -385.66319) (xy 56.357967 -385.608753) (xy 56.37789 -385.556662)
			(xy 56.405186 -385.508027) (xy 56.439272 -385.463884) (xy 56.479421 -385.425175) (xy 56.524779 -385.392724)
			(xy 56.574379 -385.367223) (xy 56.627163 -385.349216) (xy 56.682006 -385.339086) (xy 56.73774 -385.337049)
			(xy 56.793177 -385.343149) (xy 56.847134 -385.357255) (xy 56.898463 -385.379067) (xy 56.946069 -385.408121)
			(xy 56.988937 -385.443796) (xy 57.026154 -385.485333) (xy 57.056927 -385.531846) (xy 57.080599 -385.582343)
			(xy 57.096667 -385.63575) (xy 57.104787 -385.690926) (xy 57.105296 -385.718812) (xy 57.104787 -385.746698)
			(xy 57.096667 -385.801874) (xy 57.080599 -385.855281) (xy 57.056927 -385.905778) (xy 57.026154 -385.952291)
			(xy 56.988937 -385.993828) (xy 56.946069 -386.029503) (xy 56.898463 -386.058557) (xy 56.847134 -386.080369)
			(xy 56.793177 -386.094475) (xy 56.73774 -386.100575) (xy 56.682006 -386.098538) (xy 56.627163 -386.088408)
			(xy 56.574379 -386.070401) (xy 56.524779 -386.0449) (xy 56.479421 -386.012449) (xy 56.439272 -385.97374)
			(xy 56.405186 -385.929597) (xy 56.37789 -385.880962) (xy 56.357967 -385.828871) (xy 56.345841 -385.774434)
			(xy 56.34177 -385.718812) (xy 0.529844 -385.718812) (xy 0.529844 -386.246878) (xy 4.662168 -386.246878)
			(xy 4.666239 -386.191256) (xy 4.678365 -386.136819) (xy 4.698288 -386.084728) (xy 4.725584 -386.036093)
			(xy 4.75967 -385.99195) (xy 4.799819 -385.953241) (xy 4.845177 -385.92079) (xy 4.894777 -385.895289)
			(xy 4.947561 -385.877282) (xy 5.002404 -385.867152) (xy 5.058138 -385.865115) (xy 5.113575 -385.871215)
			(xy 5.167532 -385.885321) (xy 5.218861 -385.907133) (xy 5.266467 -385.936187) (xy 5.309335 -385.971862)
			(xy 5.346552 -386.013399) (xy 5.377325 -386.059912) (xy 5.400997 -386.110409) (xy 5.417065 -386.163816)
			(xy 5.425185 -386.218992) (xy 5.425694 -386.246878) (xy 5.425185 -386.274764) (xy 5.417065 -386.32994)
			(xy 5.400997 -386.383347) (xy 5.377325 -386.433844) (xy 5.346552 -386.480357) (xy 5.309335 -386.521894)
			(xy 5.266467 -386.557569) (xy 5.218861 -386.586623) (xy 5.167532 -386.608435) (xy 5.113575 -386.622541)
			(xy 5.058138 -386.628641) (xy 5.002404 -386.626604) (xy 4.947561 -386.616474) (xy 4.894777 -386.598467)
			(xy 4.845177 -386.572966) (xy 4.799819 -386.540515) (xy 4.75967 -386.501806) (xy 4.725584 -386.457663)
			(xy 4.698288 -386.409028) (xy 4.678365 -386.356937) (xy 4.666239 -386.3025) (xy 4.662168 -386.246878)
			(xy 0.529844 -386.246878) (xy 0.529844 -386.734812) (xy 57.268616 -386.734812) (xy 57.272687 -386.67919)
			(xy 57.284813 -386.624753) (xy 57.304736 -386.572662) (xy 57.332032 -386.524027) (xy 57.366118 -386.479884)
			(xy 57.406267 -386.441175) (xy 57.451625 -386.408724) (xy 57.501225 -386.383223) (xy 57.554009 -386.365216)
			(xy 57.608852 -386.355086) (xy 57.664586 -386.353049) (xy 57.720023 -386.359149) (xy 57.77398 -386.373255)
			(xy 57.825309 -386.395067) (xy 57.872915 -386.424121) (xy 57.915783 -386.459796) (xy 57.953 -386.501333)
			(xy 57.983773 -386.547846) (xy 58.007445 -386.598343) (xy 58.023513 -386.65175) (xy 58.031633 -386.706926)
			(xy 58.032142 -386.734812) (xy 58.031633 -386.762698) (xy 58.023513 -386.817874) (xy 58.007445 -386.871281)
			(xy 57.983773 -386.921778) (xy 57.953 -386.968291) (xy 57.915783 -387.009828) (xy 57.872915 -387.045503)
			(xy 57.825309 -387.074557) (xy 57.77398 -387.096369) (xy 57.720023 -387.110475) (xy 57.664586 -387.116575)
			(xy 57.608852 -387.114538) (xy 57.554009 -387.104408) (xy 57.501225 -387.086401) (xy 57.451625 -387.0609)
			(xy 57.406267 -387.028449) (xy 57.366118 -386.98974) (xy 57.332032 -386.945597) (xy 57.304736 -386.896962)
			(xy 57.284813 -386.844871) (xy 57.272687 -386.790434) (xy 57.268616 -386.734812) (xy 0.529844 -386.734812)
			(xy 0.529844 -388.37489) (xy 1.56972 -388.37489) (xy 1.56972 -387.51129) (xy 1.57021 -387.481322)
			(xy 1.578033 -387.4219) (xy 1.593546 -387.364007) (xy 1.616482 -387.308634) (xy 1.646449 -387.256728)
			(xy 1.682936 -387.209178) (xy 1.725316 -387.166798) (xy 1.772866 -387.130311) (xy 1.824772 -387.100344)
			(xy 1.880145 -387.077408) (xy 1.938038 -387.061895) (xy 1.99746 -387.054072) (xy 2.057396 -387.054072)
			(xy 2.116818 -387.061895) (xy 2.174711 -387.077408) (xy 2.230084 -387.100344) (xy 2.28199 -387.130311)
			(xy 2.32954 -387.166798) (xy 2.37192 -387.209178) (xy 2.408407 -387.256728) (xy 2.438374 -387.308634)
			(xy 2.46131 -387.364007) (xy 2.476823 -387.4219) (xy 2.484646 -387.481322) (xy 2.485136 -387.51129)
			(xy 2.485136 -388.21233) (xy 14.92834 -388.21233) (xy 14.932411 -388.156708) (xy 14.944537 -388.102271)
			(xy 14.96446 -388.05018) (xy 14.991756 -388.001545) (xy 15.025842 -387.957402) (xy 15.065991 -387.918693)
			(xy 15.111349 -387.886242) (xy 15.160949 -387.860741) (xy 15.213733 -387.842734) (xy 15.268576 -387.832604)
			(xy 15.32431 -387.830567) (xy 15.379747 -387.836667) (xy 15.433704 -387.850773) (xy 15.485033 -387.872585)
			(xy 15.532639 -387.901639) (xy 15.575507 -387.937314) (xy 15.612724 -387.978851) (xy 15.643497 -388.025364)
			(xy 15.667169 -388.075861) (xy 15.683237 -388.129268) (xy 15.691357 -388.184444) (xy 15.691866 -388.21233)
			(xy 15.691357 -388.240216) (xy 15.687648 -388.265416) (xy 59.963302 -388.265416) (xy 59.967373 -388.209794)
			(xy 59.979499 -388.155357) (xy 59.999422 -388.103266) (xy 60.026718 -388.054631) (xy 60.060804 -388.010488)
			(xy 60.100953 -387.971779) (xy 60.146311 -387.939328) (xy 60.195911 -387.913827) (xy 60.248695 -387.89582)
			(xy 60.303538 -387.88569) (xy 60.359272 -387.883653) (xy 60.414709 -387.889753) (xy 60.468666 -387.903859)
			(xy 60.519995 -387.925671) (xy 60.567601 -387.954725) (xy 60.610469 -387.9904) (xy 60.647686 -388.031937)
			(xy 60.678459 -388.07845) (xy 60.702131 -388.128947) (xy 60.718199 -388.182354) (xy 60.726319 -388.23753)
			(xy 60.726828 -388.265416) (xy 60.726319 -388.293302) (xy 60.718199 -388.348478) (xy 60.702131 -388.401885)
			(xy 60.678459 -388.452382) (xy 60.647686 -388.498895) (xy 60.610469 -388.540432) (xy 60.567601 -388.576107)
			(xy 60.519995 -388.605161) (xy 60.468666 -388.626973) (xy 60.414709 -388.641079) (xy 60.359272 -388.647179)
			(xy 60.303538 -388.645142) (xy 60.248695 -388.635012) (xy 60.195911 -388.617005) (xy 60.146311 -388.591504)
			(xy 60.100953 -388.559053) (xy 60.060804 -388.520344) (xy 60.026718 -388.476201) (xy 59.999422 -388.427566)
			(xy 59.979499 -388.375475) (xy 59.967373 -388.321038) (xy 59.963302 -388.265416) (xy 15.687648 -388.265416)
			(xy 15.683237 -388.295392) (xy 15.667169 -388.348799) (xy 15.643497 -388.399296) (xy 15.612724 -388.445809)
			(xy 15.575507 -388.487346) (xy 15.532639 -388.523021) (xy 15.485033 -388.552075) (xy 15.433704 -388.573887)
			(xy 15.379747 -388.587993) (xy 15.32431 -388.594093) (xy 15.268576 -388.592056) (xy 15.213733 -388.581926)
			(xy 15.160949 -388.563919) (xy 15.111349 -388.538418) (xy 15.065991 -388.505967) (xy 15.025842 -388.467258)
			(xy 14.991756 -388.423115) (xy 14.96446 -388.37448) (xy 14.944537 -388.322389) (xy 14.932411 -388.267952)
			(xy 14.92834 -388.21233) (xy 2.485136 -388.21233) (xy 2.485136 -388.37489) (xy 2.484646 -388.404858)
			(xy 2.476823 -388.46428) (xy 2.46131 -388.522173) (xy 2.438374 -388.577546) (xy 2.408407 -388.629452)
			(xy 2.37192 -388.677002) (xy 2.32954 -388.719382) (xy 2.293879 -388.746746) (xy 4.630672 -388.746746)
			(xy 4.634743 -388.691124) (xy 4.646869 -388.636687) (xy 4.666792 -388.584596) (xy 4.694088 -388.535961)
			(xy 4.728174 -388.491818) (xy 4.768323 -388.453109) (xy 4.813681 -388.420658) (xy 4.863281 -388.395157)
			(xy 4.916065 -388.37715) (xy 4.970908 -388.36702) (xy 5.026642 -388.364983) (xy 5.082079 -388.371083)
			(xy 5.136036 -388.385189) (xy 5.187365 -388.407001) (xy 5.234971 -388.436055) (xy 5.277839 -388.47173)
			(xy 5.315056 -388.513267) (xy 5.345829 -388.55978) (xy 5.369501 -388.610277) (xy 5.385569 -388.663684)
			(xy 5.393689 -388.71886) (xy 5.394198 -388.746746) (xy 5.393689 -388.774632) (xy 5.386654 -388.822438)
			(xy 55.493156 -388.822438) (xy 55.497227 -388.766816) (xy 55.509353 -388.712379) (xy 55.529276 -388.660288)
			(xy 55.556572 -388.611653) (xy 55.590658 -388.56751) (xy 55.630807 -388.528801) (xy 55.676165 -388.49635)
			(xy 55.725765 -388.470849) (xy 55.778549 -388.452842) (xy 55.833392 -388.442712) (xy 55.889126 -388.440675)
			(xy 55.944563 -388.446775) (xy 55.99852 -388.460881) (xy 56.049849 -388.482693) (xy 56.097455 -388.511747)
			(xy 56.140323 -388.547422) (xy 56.17754 -388.588959) (xy 56.208313 -388.635472) (xy 56.231985 -388.685969)
			(xy 56.248053 -388.739376) (xy 56.255716 -388.79145) (xy 57.41619 -388.79145) (xy 57.420261 -388.735828)
			(xy 57.432387 -388.681391) (xy 57.45231 -388.6293) (xy 57.479606 -388.580665) (xy 57.513692 -388.536522)
			(xy 57.553841 -388.497813) (xy 57.599199 -388.465362) (xy 57.648799 -388.439861) (xy 57.701583 -388.421854)
			(xy 57.756426 -388.411724) (xy 57.81216 -388.409687) (xy 57.867597 -388.415787) (xy 57.921554 -388.429893)
			(xy 57.972883 -388.451705) (xy 58.020489 -388.480759) (xy 58.063357 -388.516434) (xy 58.100574 -388.557971)
			(xy 58.131347 -388.604484) (xy 58.155019 -388.654981) (xy 58.171087 -388.708388) (xy 58.179207 -388.763564)
			(xy 58.179716 -388.79145) (xy 58.179207 -388.819336) (xy 58.171087 -388.874512) (xy 58.163294 -388.900416)
			(xy 58.70397 -388.900416) (xy 58.708041 -388.844794) (xy 58.720167 -388.790357) (xy 58.74009 -388.738266)
			(xy 58.767386 -388.689631) (xy 58.801472 -388.645488) (xy 58.841621 -388.606779) (xy 58.886979 -388.574328)
			(xy 58.936579 -388.548827) (xy 58.989363 -388.53082) (xy 59.044206 -388.52069) (xy 59.09994 -388.518653)
			(xy 59.155377 -388.524753) (xy 59.209334 -388.538859) (xy 59.260663 -388.560671) (xy 59.308269 -388.589725)
			(xy 59.351137 -388.6254) (xy 59.388354 -388.666937) (xy 59.419127 -388.71345) (xy 59.442799 -388.763947)
			(xy 59.458867 -388.817354) (xy 59.466987 -388.87253) (xy 59.467496 -388.900416) (xy 59.466987 -388.928302)
			(xy 59.458867 -388.983478) (xy 59.442799 -389.036885) (xy 59.419127 -389.087382) (xy 59.388354 -389.133895)
			(xy 59.351137 -389.175432) (xy 59.308269 -389.211107) (xy 59.260663 -389.240161) (xy 59.209334 -389.261973)
			(xy 59.155377 -389.276079) (xy 59.09994 -389.282179) (xy 59.044206 -389.280142) (xy 58.989363 -389.270012)
			(xy 58.936579 -389.252005) (xy 58.886979 -389.226504) (xy 58.841621 -389.194053) (xy 58.801472 -389.155344)
			(xy 58.767386 -389.111201) (xy 58.74009 -389.062566) (xy 58.720167 -389.010475) (xy 58.708041 -388.956038)
			(xy 58.70397 -388.900416) (xy 58.163294 -388.900416) (xy 58.155019 -388.927919) (xy 58.131347 -388.978416)
			(xy 58.100574 -389.024929) (xy 58.063357 -389.066466) (xy 58.020489 -389.102141) (xy 57.972883 -389.131195)
			(xy 57.921554 -389.153007) (xy 57.867597 -389.167113) (xy 57.81216 -389.173213) (xy 57.756426 -389.171176)
			(xy 57.701583 -389.161046) (xy 57.648799 -389.143039) (xy 57.599199 -389.117538) (xy 57.553841 -389.085087)
			(xy 57.513692 -389.046378) (xy 57.479606 -389.002235) (xy 57.45231 -388.9536) (xy 57.432387 -388.901509)
			(xy 57.420261 -388.847072) (xy 57.41619 -388.79145) (xy 56.255716 -388.79145) (xy 56.256173 -388.794552)
			(xy 56.256682 -388.822438) (xy 56.256173 -388.850324) (xy 56.248053 -388.9055) (xy 56.231985 -388.958907)
			(xy 56.208313 -389.009404) (xy 56.17754 -389.055917) (xy 56.140323 -389.097454) (xy 56.097455 -389.133129)
			(xy 56.049849 -389.162183) (xy 55.99852 -389.183995) (xy 55.944563 -389.198101) (xy 55.889126 -389.204201)
			(xy 55.833392 -389.202164) (xy 55.778549 -389.192034) (xy 55.725765 -389.174027) (xy 55.676165 -389.148526)
			(xy 55.630807 -389.116075) (xy 55.590658 -389.077366) (xy 55.556572 -389.033223) (xy 55.529276 -388.984588)
			(xy 55.509353 -388.932497) (xy 55.497227 -388.87806) (xy 55.493156 -388.822438) (xy 5.386654 -388.822438)
			(xy 5.385569 -388.829808) (xy 5.369501 -388.883215) (xy 5.345829 -388.933712) (xy 5.315056 -388.980225)
			(xy 5.277839 -389.021762) (xy 5.234971 -389.057437) (xy 5.187365 -389.086491) (xy 5.136036 -389.108303)
			(xy 5.082079 -389.122409) (xy 5.026642 -389.128509) (xy 4.970908 -389.126472) (xy 4.916065 -389.116342)
			(xy 4.863281 -389.098335) (xy 4.813681 -389.072834) (xy 4.768323 -389.040383) (xy 4.728174 -389.001674)
			(xy 4.694088 -388.957531) (xy 4.666792 -388.908896) (xy 4.646869 -388.856805) (xy 4.634743 -388.802368)
			(xy 4.630672 -388.746746) (xy 2.293879 -388.746746) (xy 2.28199 -388.755869) (xy 2.230084 -388.785836)
			(xy 2.174711 -388.808772) (xy 2.116818 -388.824285) (xy 2.057396 -388.832108) (xy 1.99746 -388.832108)
			(xy 1.938038 -388.824285) (xy 1.880145 -388.808772) (xy 1.824772 -388.785836) (xy 1.772866 -388.755869)
			(xy 1.725316 -388.719382) (xy 1.682936 -388.677002) (xy 1.646449 -388.629452) (xy 1.616482 -388.577546)
			(xy 1.593546 -388.522173) (xy 1.578033 -388.46428) (xy 1.57021 -388.404858) (xy 1.56972 -388.37489)
			(xy 0.529844 -388.37489) (xy 0.529844 -389.720836) (xy 4.413248 -389.720836) (xy 4.417319 -389.665214)
			(xy 4.429445 -389.610777) (xy 4.449368 -389.558686) (xy 4.476664 -389.510051) (xy 4.51075 -389.465908)
			(xy 4.550899 -389.427199) (xy 4.596257 -389.394748) (xy 4.645857 -389.369247) (xy 4.698641 -389.35124)
			(xy 4.753484 -389.34111) (xy 4.809218 -389.339073) (xy 4.864655 -389.345173) (xy 4.918612 -389.359279)
			(xy 4.969941 -389.381091) (xy 5.017547 -389.410145) (xy 5.060415 -389.44582) (xy 5.097632 -389.487357)
			(xy 5.128405 -389.53387) (xy 5.152077 -389.584367) (xy 5.168145 -389.637774) (xy 5.176265 -389.69295)
			(xy 5.176774 -389.720836) (xy 5.176301 -389.746744) (xy 14.934944 -389.746744) (xy 14.939015 -389.691122)
			(xy 14.951141 -389.636685) (xy 14.971064 -389.584594) (xy 14.99836 -389.535959) (xy 15.032446 -389.491816)
			(xy 15.072595 -389.453107) (xy 15.117953 -389.420656) (xy 15.167553 -389.395155) (xy 15.220337 -389.377148)
			(xy 15.27518 -389.367018) (xy 15.330914 -389.364981) (xy 15.386351 -389.371081) (xy 15.440308 -389.385187)
			(xy 15.491637 -389.406999) (xy 15.539243 -389.436053) (xy 15.582111 -389.471728) (xy 15.619328 -389.513265)
			(xy 15.650101 -389.559778) (xy 15.673773 -389.610275) (xy 15.689841 -389.663682) (xy 15.697961 -389.718858)
			(xy 15.69847 -389.746744) (xy 15.697961 -389.77463) (xy 15.689841 -389.829806) (xy 15.673773 -389.883213)
			(xy 15.650101 -389.93371) (xy 15.619328 -389.980223) (xy 15.582111 -390.02176) (xy 15.539243 -390.057435)
			(xy 15.491637 -390.086489) (xy 15.440308 -390.108301) (xy 15.386351 -390.122407) (xy 15.330914 -390.128507)
			(xy 15.27518 -390.12647) (xy 15.220337 -390.11634) (xy 15.167553 -390.098333) (xy 15.117953 -390.072832)
			(xy 15.072595 -390.040381) (xy 15.032446 -390.001672) (xy 14.99836 -389.957529) (xy 14.971064 -389.908894)
			(xy 14.951141 -389.856803) (xy 14.939015 -389.802366) (xy 14.934944 -389.746744) (xy 5.176301 -389.746744)
			(xy 5.176265 -389.748722) (xy 5.168145 -389.803898) (xy 5.152077 -389.857305) (xy 5.128405 -389.907802)
			(xy 5.097632 -389.954315) (xy 5.060415 -389.995852) (xy 5.017547 -390.031527) (xy 4.969941 -390.060581)
			(xy 4.918612 -390.082393) (xy 4.864655 -390.096499) (xy 4.809218 -390.102599) (xy 4.753484 -390.100562)
			(xy 4.698641 -390.090432) (xy 4.645857 -390.072425) (xy 4.596257 -390.046924) (xy 4.550899 -390.014473)
			(xy 4.51075 -389.975764) (xy 4.476664 -389.931621) (xy 4.449368 -389.882986) (xy 4.429445 -389.830895)
			(xy 4.417319 -389.776458) (xy 4.413248 -389.720836) (xy 0.529844 -389.720836) (xy 0.529844 -390.790938)
			(xy 1.383536 -390.790938) (xy 1.387607 -390.735316) (xy 1.399733 -390.680879) (xy 1.419656 -390.628788)
			(xy 1.446952 -390.580153) (xy 1.481038 -390.53601) (xy 1.521187 -390.497301) (xy 1.566545 -390.46485)
			(xy 1.616145 -390.439349) (xy 1.668929 -390.421342) (xy 1.723772 -390.411212) (xy 1.779506 -390.409175)
			(xy 1.834943 -390.415275) (xy 1.8889 -390.429381) (xy 1.940229 -390.451193) (xy 1.987835 -390.480247)
			(xy 2.030703 -390.515922) (xy 2.06792 -390.557459) (xy 2.098693 -390.603972) (xy 2.122365 -390.654469)
			(xy 2.138433 -390.707876) (xy 2.146553 -390.763052) (xy 2.147062 -390.790938) (xy 2.146553 -390.818824)
			(xy 2.138433 -390.874) (xy 2.122365 -390.927407) (xy 2.098693 -390.977904) (xy 2.06792 -391.024417)
			(xy 2.030703 -391.065954) (xy 1.987835 -391.101629) (xy 1.940229 -391.130683) (xy 1.906505 -391.145014)
			(xy 56.036208 -391.145014) (xy 56.040279 -391.089392) (xy 56.052405 -391.034955) (xy 56.072328 -390.982864)
			(xy 56.099624 -390.934229) (xy 56.13371 -390.890086) (xy 56.173859 -390.851377) (xy 56.219217 -390.818926)
			(xy 56.268817 -390.793425) (xy 56.321601 -390.775418) (xy 56.376444 -390.765288) (xy 56.432178 -390.763251)
			(xy 56.487615 -390.769351) (xy 56.541572 -390.783457) (xy 56.592901 -390.805269) (xy 56.640507 -390.834323)
			(xy 56.683375 -390.869998) (xy 56.720592 -390.911535) (xy 56.751365 -390.958048) (xy 56.775037 -391.008545)
			(xy 56.791105 -391.061952) (xy 56.799225 -391.117128) (xy 56.799734 -391.145014) (xy 56.799225 -391.1729)
			(xy 56.791105 -391.228076) (xy 56.775037 -391.281483) (xy 56.751365 -391.33198) (xy 56.728021 -391.367264)
			(xy 57.50001 -391.367264) (xy 57.504081 -391.311642) (xy 57.516207 -391.257205) (xy 57.53613 -391.205114)
			(xy 57.563426 -391.156479) (xy 57.597512 -391.112336) (xy 57.637661 -391.073627) (xy 57.683019 -391.041176)
			(xy 57.732619 -391.015675) (xy 57.785403 -390.997668) (xy 57.840246 -390.987538) (xy 57.89598 -390.985501)
			(xy 57.951417 -390.991601) (xy 58.005374 -391.005707) (xy 58.056703 -391.027519) (xy 58.104309 -391.056573)
			(xy 58.147177 -391.092248) (xy 58.151442 -391.097008) (xy 58.991244 -391.097008) (xy 58.995315 -391.041386)
			(xy 59.007441 -390.986949) (xy 59.027364 -390.934858) (xy 59.05466 -390.886223) (xy 59.088746 -390.84208)
			(xy 59.128895 -390.803371) (xy 59.174253 -390.77092) (xy 59.223853 -390.745419) (xy 59.276637 -390.727412)
			(xy 59.33148 -390.717282) (xy 59.387214 -390.715245) (xy 59.442651 -390.721345) (xy 59.496608 -390.735451)
			(xy 59.547937 -390.757263) (xy 59.595543 -390.786317) (xy 59.638411 -390.821992) (xy 59.675628 -390.863529)
			(xy 59.706401 -390.910042) (xy 59.730073 -390.960539) (xy 59.743391 -391.004806) (xy 61.82563 -391.004806)
			(xy 61.829701 -390.949184) (xy 61.841827 -390.894747) (xy 61.86175 -390.842656) (xy 61.889046 -390.794021)
			(xy 61.923132 -390.749878) (xy 61.963281 -390.711169) (xy 62.008639 -390.678718) (xy 62.058239 -390.653217)
			(xy 62.111023 -390.63521) (xy 62.165866 -390.62508) (xy 62.2216 -390.623043) (xy 62.277037 -390.629143)
			(xy 62.330994 -390.643249) (xy 62.382323 -390.665061) (xy 62.429929 -390.694115) (xy 62.472797 -390.72979)
			(xy 62.510014 -390.771327) (xy 62.540787 -390.81784) (xy 62.564459 -390.868337) (xy 62.580527 -390.921744)
			(xy 62.588647 -390.97692) (xy 62.589156 -391.004806) (xy 62.588647 -391.032692) (xy 62.580527 -391.087868)
			(xy 62.577242 -391.098786) (xy 63.318642 -391.098786) (xy 63.322713 -391.043164) (xy 63.334839 -390.988727)
			(xy 63.354762 -390.936636) (xy 63.382058 -390.888001) (xy 63.416144 -390.843858) (xy 63.456293 -390.805149)
			(xy 63.501651 -390.772698) (xy 63.551251 -390.747197) (xy 63.604035 -390.72919) (xy 63.658878 -390.71906)
			(xy 63.714612 -390.717023) (xy 63.770049 -390.723123) (xy 63.824006 -390.737229) (xy 63.875335 -390.759041)
			(xy 63.922941 -390.788095) (xy 63.965809 -390.82377) (xy 64.003026 -390.865307) (xy 64.033799 -390.91182)
			(xy 64.057471 -390.962317) (xy 64.073539 -391.015724) (xy 64.081659 -391.0709) (xy 64.082168 -391.098786)
			(xy 64.081659 -391.126672) (xy 64.073539 -391.181848) (xy 64.057471 -391.235255) (xy 64.033799 -391.285752)
			(xy 64.003026 -391.332265) (xy 63.965809 -391.373802) (xy 63.922941 -391.409477) (xy 63.875335 -391.438531)
			(xy 63.824006 -391.460343) (xy 63.770049 -391.474449) (xy 63.714612 -391.480549) (xy 63.658878 -391.478512)
			(xy 63.604035 -391.468382) (xy 63.551251 -391.450375) (xy 63.501651 -391.424874) (xy 63.456293 -391.392423)
			(xy 63.416144 -391.353714) (xy 63.382058 -391.309571) (xy 63.354762 -391.260936) (xy 63.334839 -391.208845)
			(xy 63.322713 -391.154408) (xy 63.318642 -391.098786) (xy 62.577242 -391.098786) (xy 62.564459 -391.141275)
			(xy 62.540787 -391.191772) (xy 62.510014 -391.238285) (xy 62.472797 -391.279822) (xy 62.429929 -391.315497)
			(xy 62.382323 -391.344551) (xy 62.330994 -391.366363) (xy 62.277037 -391.380469) (xy 62.2216 -391.386569)
			(xy 62.165866 -391.384532) (xy 62.111023 -391.374402) (xy 62.058239 -391.356395) (xy 62.008639 -391.330894)
			(xy 61.963281 -391.298443) (xy 61.923132 -391.259734) (xy 61.889046 -391.215591) (xy 61.86175 -391.166956)
			(xy 61.841827 -391.114865) (xy 61.829701 -391.060428) (xy 61.82563 -391.004806) (xy 59.743391 -391.004806)
			(xy 59.746141 -391.013946) (xy 59.754261 -391.069122) (xy 59.75477 -391.097008) (xy 59.754261 -391.124894)
			(xy 59.746141 -391.18007) (xy 59.730073 -391.233477) (xy 59.706401 -391.283974) (xy 59.675628 -391.330487)
			(xy 59.638411 -391.372024) (xy 59.595543 -391.407699) (xy 59.547937 -391.436753) (xy 59.496608 -391.458565)
			(xy 59.442651 -391.472671) (xy 59.387214 -391.478771) (xy 59.33148 -391.476734) (xy 59.276637 -391.466604)
			(xy 59.223853 -391.448597) (xy 59.174253 -391.423096) (xy 59.128895 -391.390645) (xy 59.088746 -391.351936)
			(xy 59.05466 -391.307793) (xy 59.027364 -391.259158) (xy 59.007441 -391.207067) (xy 58.995315 -391.15263)
			(xy 58.991244 -391.097008) (xy 58.151442 -391.097008) (xy 58.184394 -391.133785) (xy 58.215167 -391.180298)
			(xy 58.238839 -391.230795) (xy 58.254907 -391.284202) (xy 58.263027 -391.339378) (xy 58.263536 -391.367264)
			(xy 58.263027 -391.39515) (xy 58.254907 -391.450326) (xy 58.240847 -391.497058) (xy 60.565028 -391.497058)
			(xy 60.569099 -391.441436) (xy 60.581225 -391.386999) (xy 60.601148 -391.334908) (xy 60.628444 -391.286273)
			(xy 60.66253 -391.24213) (xy 60.702679 -391.203421) (xy 60.748037 -391.17097) (xy 60.797637 -391.145469)
			(xy 60.850421 -391.127462) (xy 60.905264 -391.117332) (xy 60.960998 -391.115295) (xy 61.016435 -391.121395)
			(xy 61.070392 -391.135501) (xy 61.121721 -391.157313) (xy 61.169327 -391.186367) (xy 61.212195 -391.222042)
			(xy 61.249412 -391.263579) (xy 61.280185 -391.310092) (xy 61.303857 -391.360589) (xy 61.319925 -391.413996)
			(xy 61.328045 -391.469172) (xy 61.328554 -391.497058) (xy 61.328045 -391.524944) (xy 61.319925 -391.58012)
			(xy 61.303857 -391.633527) (xy 61.280185 -391.684024) (xy 61.249412 -391.730537) (xy 61.212195 -391.772074)
			(xy 61.169327 -391.807749) (xy 61.121721 -391.836803) (xy 61.070392 -391.858615) (xy 61.016435 -391.872721)
			(xy 60.960998 -391.878821) (xy 60.905264 -391.876784) (xy 60.850421 -391.866654) (xy 60.797637 -391.848647)
			(xy 60.748037 -391.823146) (xy 60.702679 -391.790695) (xy 60.66253 -391.751986) (xy 60.628444 -391.707843)
			(xy 60.601148 -391.659208) (xy 60.581225 -391.607117) (xy 60.569099 -391.55268) (xy 60.565028 -391.497058)
			(xy 58.240847 -391.497058) (xy 58.238839 -391.503733) (xy 58.215167 -391.55423) (xy 58.184394 -391.600743)
			(xy 58.147177 -391.64228) (xy 58.104309 -391.677955) (xy 58.056703 -391.707009) (xy 58.005374 -391.728821)
			(xy 57.951417 -391.742927) (xy 57.89598 -391.749027) (xy 57.840246 -391.74699) (xy 57.785403 -391.73686)
			(xy 57.732619 -391.718853) (xy 57.683019 -391.693352) (xy 57.637661 -391.660901) (xy 57.597512 -391.622192)
			(xy 57.563426 -391.578049) (xy 57.53613 -391.529414) (xy 57.516207 -391.477323) (xy 57.504081 -391.422886)
			(xy 57.50001 -391.367264) (xy 56.728021 -391.367264) (xy 56.720592 -391.378493) (xy 56.683375 -391.42003)
			(xy 56.640507 -391.455705) (xy 56.592901 -391.484759) (xy 56.541572 -391.506571) (xy 56.487615 -391.520677)
			(xy 56.432178 -391.526777) (xy 56.376444 -391.52474) (xy 56.321601 -391.51461) (xy 56.268817 -391.496603)
			(xy 56.219217 -391.471102) (xy 56.173859 -391.438651) (xy 56.13371 -391.399942) (xy 56.099624 -391.355799)
			(xy 56.072328 -391.307164) (xy 56.052405 -391.255073) (xy 56.040279 -391.200636) (xy 56.036208 -391.145014)
			(xy 1.906505 -391.145014) (xy 1.8889 -391.152495) (xy 1.834943 -391.166601) (xy 1.779506 -391.172701)
			(xy 1.723772 -391.170664) (xy 1.668929 -391.160534) (xy 1.616145 -391.142527) (xy 1.566545 -391.117026)
			(xy 1.521187 -391.084575) (xy 1.481038 -391.045866) (xy 1.446952 -391.001723) (xy 1.419656 -390.953088)
			(xy 1.399733 -390.900997) (xy 1.387607 -390.84656) (xy 1.383536 -390.790938) (xy 0.529844 -390.790938)
			(xy 0.529844 -391.614914) (xy 13.80693 -391.614914) (xy 13.811001 -391.559292) (xy 13.823127 -391.504855)
			(xy 13.84305 -391.452764) (xy 13.870346 -391.404129) (xy 13.904432 -391.359986) (xy 13.944581 -391.321277)
			(xy 13.989939 -391.288826) (xy 14.039539 -391.263325) (xy 14.092323 -391.245318) (xy 14.147166 -391.235188)
			(xy 14.2029 -391.233151) (xy 14.258337 -391.239251) (xy 14.312294 -391.253357) (xy 14.363623 -391.275169)
			(xy 14.411229 -391.304223) (xy 14.454097 -391.339898) (xy 14.491314 -391.381435) (xy 14.522087 -391.427948)
			(xy 14.545759 -391.478445) (xy 14.561827 -391.531852) (xy 14.569947 -391.587028) (xy 14.570456 -391.614914)
			(xy 14.569947 -391.6428) (xy 14.566986 -391.66292) (xy 16.249394 -391.66292) (xy 16.253465 -391.607298)
			(xy 16.265591 -391.552861) (xy 16.285514 -391.50077) (xy 16.31281 -391.452135) (xy 16.346896 -391.407992)
			(xy 16.387045 -391.369283) (xy 16.432403 -391.336832) (xy 16.482003 -391.311331) (xy 16.534787 -391.293324)
			(xy 16.58963 -391.283194) (xy 16.645364 -391.281157) (xy 16.700801 -391.287257) (xy 16.754758 -391.301363)
			(xy 16.806087 -391.323175) (xy 16.853693 -391.352229) (xy 16.896561 -391.387904) (xy 16.933778 -391.429441)
			(xy 16.964551 -391.475954) (xy 16.988223 -391.526451) (xy 17.004291 -391.579858) (xy 17.012411 -391.635034)
			(xy 17.01292 -391.66292) (xy 17.012411 -391.690806) (xy 17.004291 -391.745982) (xy 16.988223 -391.799389)
			(xy 16.964551 -391.849886) (xy 16.933778 -391.896399) (xy 16.896561 -391.937936) (xy 16.853693 -391.973611)
			(xy 16.806087 -392.002665) (xy 16.754758 -392.024477) (xy 16.700801 -392.038583) (xy 16.645364 -392.044683)
			(xy 16.58963 -392.042646) (xy 16.534787 -392.032516) (xy 16.482003 -392.014509) (xy 16.432403 -391.989008)
			(xy 16.387045 -391.956557) (xy 16.346896 -391.917848) (xy 16.31281 -391.873705) (xy 16.285514 -391.82507)
			(xy 16.265591 -391.772979) (xy 16.253465 -391.718542) (xy 16.249394 -391.66292) (xy 14.566986 -391.66292)
			(xy 14.561827 -391.697976) (xy 14.545759 -391.751383) (xy 14.522087 -391.80188) (xy 14.491314 -391.848393)
			(xy 14.454097 -391.88993) (xy 14.411229 -391.925605) (xy 14.363623 -391.954659) (xy 14.312294 -391.976471)
			(xy 14.258337 -391.990577) (xy 14.2029 -391.996677) (xy 14.147166 -391.99464) (xy 14.092323 -391.98451)
			(xy 14.039539 -391.966503) (xy 13.989939 -391.941002) (xy 13.944581 -391.908551) (xy 13.904432 -391.869842)
			(xy 13.870346 -391.825699) (xy 13.84305 -391.777064) (xy 13.823127 -391.724973) (xy 13.811001 -391.670536)
			(xy 13.80693 -391.614914) (xy 0.529844 -391.614914) (xy 0.529844 -393.133072) (xy 23.365966 -393.133072)
			(xy 23.370037 -393.07745) (xy 23.382163 -393.023013) (xy 23.402086 -392.970922) (xy 23.429382 -392.922287)
			(xy 23.463468 -392.878144) (xy 23.503617 -392.839435) (xy 23.548975 -392.806984) (xy 23.598575 -392.781483)
			(xy 23.651359 -392.763476) (xy 23.706202 -392.753346) (xy 23.761936 -392.751309) (xy 23.817373 -392.757409)
			(xy 23.87133 -392.771515) (xy 23.922659 -392.793327) (xy 23.970265 -392.822381) (xy 24.013133 -392.858056)
			(xy 24.05035 -392.899593) (xy 24.081123 -392.946106) (xy 24.104795 -392.996603) (xy 24.120863 -393.05001)
			(xy 24.128983 -393.105186) (xy 24.129492 -393.133072) (xy 24.128983 -393.160958) (xy 24.120863 -393.216134)
			(xy 24.104795 -393.269541) (xy 24.081123 -393.320038) (xy 24.05035 -393.366551) (xy 24.013133 -393.408088)
			(xy 23.970265 -393.443763) (xy 23.922659 -393.472817) (xy 23.87133 -393.494629) (xy 23.817373 -393.508735)
			(xy 23.761936 -393.514835) (xy 23.706202 -393.512798) (xy 23.651359 -393.502668) (xy 23.598575 -393.484661)
			(xy 23.548975 -393.45916) (xy 23.503617 -393.426709) (xy 23.463468 -393.388) (xy 23.429382 -393.343857)
			(xy 23.402086 -393.295222) (xy 23.382163 -393.243131) (xy 23.370037 -393.188694) (xy 23.365966 -393.133072)
			(xy 0.529844 -393.133072) (xy 0.529844 -394.48232) (xy 2.2512 -394.48232) (xy 2.255271 -394.426698)
			(xy 2.267397 -394.372261) (xy 2.28732 -394.32017) (xy 2.314616 -394.271535) (xy 2.348702 -394.227392)
			(xy 2.388851 -394.188683) (xy 2.434209 -394.156232) (xy 2.483809 -394.130731) (xy 2.536593 -394.112724)
			(xy 2.591436 -394.102594) (xy 2.64717 -394.100557) (xy 2.702607 -394.106657) (xy 2.756564 -394.120763)
			(xy 2.807893 -394.142575) (xy 2.855499 -394.171629) (xy 2.898367 -394.207304) (xy 2.935584 -394.248841)
			(xy 2.966357 -394.295354) (xy 2.990029 -394.345851) (xy 3.006097 -394.399258) (xy 3.014217 -394.454434)
			(xy 3.014726 -394.48232) (xy 3.014217 -394.510206) (xy 3.006097 -394.565382) (xy 2.990029 -394.618789)
			(xy 2.966357 -394.669286) (xy 2.935584 -394.715799) (xy 2.900811 -394.754608) (xy 5.302756 -394.754608)
			(xy 5.306827 -394.698986) (xy 5.318953 -394.644549) (xy 5.338876 -394.592458) (xy 5.366172 -394.543823)
			(xy 5.400258 -394.49968) (xy 5.440407 -394.460971) (xy 5.485765 -394.42852) (xy 5.535365 -394.403019)
			(xy 5.588149 -394.385012) (xy 5.642992 -394.374882) (xy 5.698726 -394.372845) (xy 5.754163 -394.378945)
			(xy 5.80812 -394.393051) (xy 5.859449 -394.414863) (xy 5.907055 -394.443917) (xy 5.949923 -394.479592)
			(xy 5.98714 -394.521129) (xy 6.017913 -394.567642) (xy 6.041585 -394.618139) (xy 6.057653 -394.671546)
			(xy 6.065773 -394.726722) (xy 6.066282 -394.754608) (xy 6.066212 -394.758418) (xy 6.280656 -394.758418)
			(xy 6.284727 -394.702796) (xy 6.296853 -394.648359) (xy 6.316776 -394.596268) (xy 6.344072 -394.547633)
			(xy 6.378158 -394.50349) (xy 6.418307 -394.464781) (xy 6.463665 -394.43233) (xy 6.513265 -394.406829)
			(xy 6.566049 -394.388822) (xy 6.620892 -394.378692) (xy 6.676626 -394.376655) (xy 6.732063 -394.382755)
			(xy 6.78602 -394.396861) (xy 6.837349 -394.418673) (xy 6.884955 -394.447727) (xy 6.927823 -394.483402)
			(xy 6.96504 -394.524939) (xy 6.995813 -394.571452) (xy 7.019485 -394.621949) (xy 7.035553 -394.675356)
			(xy 7.043673 -394.730532) (xy 7.044182 -394.758418) (xy 7.043673 -394.786304) (xy 7.035553 -394.84148)
			(xy 7.019485 -394.894887) (xy 6.995813 -394.945384) (xy 6.96504 -394.991897) (xy 6.927823 -395.033434)
			(xy 6.884955 -395.069109) (xy 6.837349 -395.098163) (xy 6.78602 -395.119975) (xy 6.732063 -395.134081)
			(xy 6.676626 -395.140181) (xy 6.620892 -395.138144) (xy 6.566049 -395.128014) (xy 6.513265 -395.110007)
			(xy 6.463665 -395.084506) (xy 6.418307 -395.052055) (xy 6.378158 -395.013346) (xy 6.344072 -394.969203)
			(xy 6.316776 -394.920568) (xy 6.296853 -394.868477) (xy 6.284727 -394.81404) (xy 6.280656 -394.758418)
			(xy 6.066212 -394.758418) (xy 6.065773 -394.782494) (xy 6.057653 -394.83767) (xy 6.041585 -394.891077)
			(xy 6.017913 -394.941574) (xy 5.98714 -394.988087) (xy 5.949923 -395.029624) (xy 5.907055 -395.065299)
			(xy 5.859449 -395.094353) (xy 5.80812 -395.116165) (xy 5.754163 -395.130271) (xy 5.698726 -395.136371)
			(xy 5.642992 -395.134334) (xy 5.588149 -395.124204) (xy 5.535365 -395.106197) (xy 5.485765 -395.080696)
			(xy 5.440407 -395.048245) (xy 5.400258 -395.009536) (xy 5.366172 -394.965393) (xy 5.338876 -394.916758)
			(xy 5.318953 -394.864667) (xy 5.306827 -394.81023) (xy 5.302756 -394.754608) (xy 2.900811 -394.754608)
			(xy 2.898367 -394.757336) (xy 2.855499 -394.793011) (xy 2.807893 -394.822065) (xy 2.756564 -394.843877)
			(xy 2.702607 -394.857983) (xy 2.64717 -394.864083) (xy 2.591436 -394.862046) (xy 2.536593 -394.851916)
			(xy 2.483809 -394.833909) (xy 2.434209 -394.808408) (xy 2.388851 -394.775957) (xy 2.348702 -394.737248)
			(xy 2.314616 -394.693105) (xy 2.28732 -394.64447) (xy 2.267397 -394.592379) (xy 2.255271 -394.537942)
			(xy 2.2512 -394.48232) (xy 0.529844 -394.48232) (xy 0.529844 -395.206728) (xy 10.019536 -395.206728)
			(xy 10.023607 -395.151106) (xy 10.035733 -395.096669) (xy 10.055656 -395.044578) (xy 10.082952 -394.995943)
			(xy 10.117038 -394.9518) (xy 10.157187 -394.913091) (xy 10.202545 -394.88064) (xy 10.252145 -394.855139)
			(xy 10.304929 -394.837132) (xy 10.359772 -394.827002) (xy 10.415506 -394.824965) (xy 10.470943 -394.831065)
			(xy 10.5249 -394.845171) (xy 10.576229 -394.866983) (xy 10.623835 -394.896037) (xy 10.666703 -394.931712)
			(xy 10.70392 -394.973249) (xy 10.734693 -395.019762) (xy 10.758365 -395.070259) (xy 10.774433 -395.123666)
			(xy 10.782553 -395.178842) (xy 10.78302 -395.204442) (xy 11.574778 -395.204442) (xy 11.578849 -395.14882)
			(xy 11.590975 -395.094383) (xy 11.610898 -395.042292) (xy 11.638194 -394.993657) (xy 11.67228 -394.949514)
			(xy 11.712429 -394.910805) (xy 11.757787 -394.878354) (xy 11.807387 -394.852853) (xy 11.860171 -394.834846)
			(xy 11.915014 -394.824716) (xy 11.970748 -394.822679) (xy 12.026185 -394.828779) (xy 12.080142 -394.842885)
			(xy 12.131471 -394.864697) (xy 12.179077 -394.893751) (xy 12.221945 -394.929426) (xy 12.259162 -394.970963)
			(xy 12.289935 -395.017476) (xy 12.313607 -395.067973) (xy 12.329675 -395.12138) (xy 12.337795 -395.176556)
			(xy 12.338151 -395.19606) (xy 15.04772 -395.19606) (xy 15.051791 -395.140438) (xy 15.063917 -395.086001)
			(xy 15.08384 -395.03391) (xy 15.111136 -394.985275) (xy 15.145222 -394.941132) (xy 15.185371 -394.902423)
			(xy 15.230729 -394.869972) (xy 15.280329 -394.844471) (xy 15.333113 -394.826464) (xy 15.387956 -394.816334)
			(xy 15.44369 -394.814297) (xy 15.499127 -394.820397) (xy 15.553084 -394.834503) (xy 15.604413 -394.856315)
			(xy 15.652019 -394.885369) (xy 15.694887 -394.921044) (xy 15.732104 -394.962581) (xy 15.762877 -395.009094)
			(xy 15.786549 -395.059591) (xy 15.802617 -395.112998) (xy 15.810737 -395.168174) (xy 15.811246 -395.19606)
			(xy 16.06372 -395.19606) (xy 16.067791 -395.140438) (xy 16.079917 -395.086001) (xy 16.09984 -395.03391)
			(xy 16.127136 -394.985275) (xy 16.161222 -394.941132) (xy 16.201371 -394.902423) (xy 16.246729 -394.869972)
			(xy 16.296329 -394.844471) (xy 16.349113 -394.826464) (xy 16.403956 -394.816334) (xy 16.45969 -394.814297)
			(xy 16.515127 -394.820397) (xy 16.569084 -394.834503) (xy 16.620413 -394.856315) (xy 16.668019 -394.885369)
			(xy 16.710887 -394.921044) (xy 16.748104 -394.962581) (xy 16.778877 -395.009094) (xy 16.802549 -395.059591)
			(xy 16.818617 -395.112998) (xy 16.826737 -395.168174) (xy 16.827246 -395.19606) (xy 16.826737 -395.223946)
			(xy 16.818617 -395.279122) (xy 16.802549 -395.332529) (xy 16.778877 -395.383026) (xy 16.748104 -395.429539)
			(xy 16.710887 -395.471076) (xy 16.668019 -395.506751) (xy 16.620413 -395.535805) (xy 16.569084 -395.557617)
			(xy 16.515127 -395.571723) (xy 16.45969 -395.577823) (xy 16.403956 -395.575786) (xy 16.349113 -395.565656)
			(xy 16.296329 -395.547649) (xy 16.246729 -395.522148) (xy 16.201371 -395.489697) (xy 16.161222 -395.450988)
			(xy 16.127136 -395.406845) (xy 16.09984 -395.35821) (xy 16.079917 -395.306119) (xy 16.067791 -395.251682)
			(xy 16.06372 -395.19606) (xy 15.811246 -395.19606) (xy 15.810737 -395.223946) (xy 15.802617 -395.279122)
			(xy 15.786549 -395.332529) (xy 15.762877 -395.383026) (xy 15.732104 -395.429539) (xy 15.694887 -395.471076)
			(xy 15.652019 -395.506751) (xy 15.604413 -395.535805) (xy 15.553084 -395.557617) (xy 15.499127 -395.571723)
			(xy 15.44369 -395.577823) (xy 15.387956 -395.575786) (xy 15.333113 -395.565656) (xy 15.280329 -395.547649)
			(xy 15.230729 -395.522148) (xy 15.185371 -395.489697) (xy 15.145222 -395.450988) (xy 15.111136 -395.406845)
			(xy 15.08384 -395.35821) (xy 15.063917 -395.306119) (xy 15.051791 -395.251682) (xy 15.04772 -395.19606)
			(xy 12.338151 -395.19606) (xy 12.338304 -395.204442) (xy 12.337795 -395.232328) (xy 12.329675 -395.287504)
			(xy 12.313607 -395.340911) (xy 12.289935 -395.391408) (xy 12.259162 -395.437921) (xy 12.221945 -395.479458)
			(xy 12.179077 -395.515133) (xy 12.131471 -395.544187) (xy 12.080142 -395.565999) (xy 12.026185 -395.580105)
			(xy 11.970748 -395.586205) (xy 11.915014 -395.584168) (xy 11.860171 -395.574038) (xy 11.807387 -395.556031)
			(xy 11.757787 -395.53053) (xy 11.712429 -395.498079) (xy 11.67228 -395.45937) (xy 11.638194 -395.415227)
			(xy 11.610898 -395.366592) (xy 11.590975 -395.314501) (xy 11.578849 -395.260064) (xy 11.574778 -395.204442)
			(xy 10.78302 -395.204442) (xy 10.783062 -395.206728) (xy 10.782553 -395.234614) (xy 10.774433 -395.28979)
			(xy 10.758365 -395.343197) (xy 10.734693 -395.393694) (xy 10.70392 -395.440207) (xy 10.666703 -395.481744)
			(xy 10.623835 -395.517419) (xy 10.576229 -395.546473) (xy 10.5249 -395.568285) (xy 10.470943 -395.582391)
			(xy 10.415506 -395.588491) (xy 10.359772 -395.586454) (xy 10.304929 -395.576324) (xy 10.252145 -395.558317)
			(xy 10.202545 -395.532816) (xy 10.157187 -395.500365) (xy 10.117038 -395.461656) (xy 10.082952 -395.417513)
			(xy 10.055656 -395.368878) (xy 10.035733 -395.316787) (xy 10.023607 -395.26235) (xy 10.019536 -395.206728)
			(xy 0.529844 -395.206728) (xy 0.529844 -398.164722) (xy 3.141726 -398.164722) (xy 3.141726 -398.035362)
			(xy 3.149849 -397.906256) (xy 3.166062 -397.777916) (xy 3.190302 -397.650846) (xy 3.222472 -397.52555)
			(xy 3.262447 -397.40252) (xy 3.310068 -397.282244) (xy 3.365147 -397.165195) (xy 3.427467 -397.051835)
			(xy 3.496782 -396.942612) (xy 3.572818 -396.837957) (xy 3.655276 -396.738283) (xy 3.743829 -396.643983)
			(xy 3.838129 -396.55543) (xy 3.937803 -396.472972) (xy 4.042458 -396.396936) (xy 4.151681 -396.327621)
			(xy 4.265041 -396.265301) (xy 4.38209 -396.210222) (xy 4.502366 -396.162601) (xy 4.625396 -396.122626)
			(xy 4.750692 -396.090456) (xy 4.877762 -396.066216) (xy 5.006102 -396.050003) (xy 5.135208 -396.04188)
			(xy 5.199888 -396.041372) (xy 6.800088 -396.041372) (xy 6.864769 -396.041866) (xy 6.993875 -396.049988)
			(xy 7.122217 -396.066201) (xy 7.249287 -396.090441) (xy 7.374584 -396.122612) (xy 7.497614 -396.162587)
			(xy 7.617892 -396.210208) (xy 7.734942 -396.265287) (xy 7.848302 -396.327608) (xy 7.957526 -396.396923)
			(xy 8.062181 -396.47296) (xy 8.161856 -396.555418) (xy 8.256157 -396.643972) (xy 8.344711 -396.738272)
			(xy 8.427169 -396.837947) (xy 8.503206 -396.942603) (xy 8.572521 -397.051826) (xy 8.634842 -397.165187)
			(xy 8.689921 -397.282236) (xy 8.737543 -397.402514) (xy 8.777518 -397.525544) (xy 8.809688 -397.650841)
			(xy 8.833928 -397.777911) (xy 8.835476 -397.790162) (xy 27.42438 -397.790162) (xy 27.424954 -397.757433)
			(xy 27.433808 -397.692575) (xy 27.451296 -397.629495) (xy 27.477101 -397.569336) (xy 27.493468 -397.540988)
			(xy 27.496784 -397.534964) (xy 27.500389 -397.5217) (xy 27.50058 -397.514826) (xy 27.50058 -396.765526)
			(xy 27.50038 -396.758653) (xy 27.496778 -396.74539) (xy 27.493468 -396.739364) (xy 27.477095 -396.711019)
			(xy 27.451293 -396.650858) (xy 27.433805 -396.587778) (xy 27.424948 -396.522919) (xy 27.42438 -396.49019)
			(xy 27.424967 -396.457461) (xy 27.433817 -396.392604) (xy 27.451301 -396.329524) (xy 27.477102 -396.269365)
			(xy 27.493468 -396.241016) (xy 27.496774 -396.234987) (xy 27.500386 -396.221727) (xy 27.50058 -396.214854)
			(xy 27.50058 -395.92885) (xy 27.501069 -395.918722) (xy 27.508787 -395.899994) (xy 27.523074 -395.885635)
			(xy 27.541762 -395.877821) (xy 27.551888 -395.877288) (xy 28.268168 -395.877288) (xy 28.278319 -395.877747)
			(xy 28.297068 -395.88553) (xy 28.311392 -395.899915) (xy 28.319095 -395.918698) (xy 28.319476 -395.92885)
			(xy 28.319476 -396.214854) (xy 28.319688 -396.221726) (xy 28.323283 -396.234988) (xy 28.326588 -396.241016)
			(xy 28.342959 -396.269362) (xy 28.36876 -396.329523) (xy 28.386248 -396.392603) (xy 28.395107 -396.457461)
			(xy 28.395676 -396.49019) (xy 28.395131 -396.52292) (xy 28.38627 -396.587779) (xy 28.368773 -396.65086)
			(xy 28.34296 -396.711017) (xy 28.326588 -396.739364) (xy 28.323285 -396.745394) (xy 28.319672 -396.758654)
			(xy 28.319476 -396.765526) (xy 28.319476 -397.514826) (xy 28.319661 -397.5217) (xy 28.323274 -397.534962)
			(xy 28.326588 -397.540988) (xy 28.335995 -397.557291) (xy 29.624885 -397.557291) (xy 29.633667 -397.492447)
			(xy 29.651073 -397.429369) (xy 29.676787 -397.369198) (xy 29.693108 -397.340836) (xy 29.696411 -397.334805)
			(xy 29.700024 -397.321546) (xy 29.70022 -397.314674) (xy 29.70022 -397.028924) (xy 29.700641 -397.018769)
			(xy 29.708433 -397.000013) (xy 29.72283 -396.985688) (xy 29.741625 -396.977991) (xy 29.751782 -396.977616)
			(xy 30.468062 -396.977616) (xy 30.478183 -396.978157) (xy 30.496899 -396.985868) (xy 30.511256 -397.000138)
			(xy 30.51908 -397.018806) (xy 30.519624 -397.028924) (xy 30.519624 -397.314674) (xy 30.519823 -397.321547)
			(xy 30.523426 -397.33481) (xy 30.526736 -397.340836) (xy 30.543067 -397.369192) (xy 30.568786 -397.429364)
			(xy 30.586194 -397.492444) (xy 30.594977 -397.55729) (xy 30.594976 -397.622727) (xy 30.58619 -397.687573)
			(xy 30.56878 -397.750652) (xy 30.54306 -397.810823) (xy 30.536116 -397.822887) (xy 31.825 -397.822887)
			(xy 31.825005 -397.757448) (xy 31.833793 -397.692601) (xy 31.851207 -397.629521) (xy 31.876931 -397.569349)
			(xy 31.893256 -397.540988) (xy 31.896571 -397.534964) (xy 31.900177 -397.5217) (xy 31.900368 -397.514826)
			(xy 31.900368 -396.765526) (xy 31.90017 -396.758653) (xy 31.896566 -396.74539) (xy 31.893256 -396.739364)
			(xy 31.876925 -396.711008) (xy 31.851207 -396.650835) (xy 31.833799 -396.587756) (xy 31.825016 -396.52291)
			(xy 31.825018 -396.457473) (xy 31.833803 -396.392627) (xy 31.851213 -396.329548) (xy 31.876933 -396.269377)
			(xy 31.893256 -396.241016) (xy 31.896561 -396.234987) (xy 31.900173 -396.221727) (xy 31.900368 -396.214854)
			(xy 31.900368 -395.92885) (xy 31.900805 -395.918678) (xy 31.90858 -395.899879) (xy 31.922962 -395.885491)
			(xy 31.941758 -395.877709) (xy 31.95193 -395.877288) (xy 32.66821 -395.877288) (xy 32.678388 -395.877657)
			(xy 32.697193 -395.885455) (xy 32.711579 -395.899858) (xy 32.719355 -395.918671) (xy 32.719772 -395.92885)
			(xy 32.719772 -396.214854) (xy 32.719985 -396.221726) (xy 32.723579 -396.234988) (xy 32.726884 -396.241016)
			(xy 32.743197 -396.269382) (xy 32.768914 -396.329552) (xy 32.786322 -396.39263) (xy 32.795107 -396.457474)
			(xy 32.795108 -396.522909) (xy 32.786326 -396.587753) (xy 32.76892 -396.650831) (xy 32.743205 -396.711003)
			(xy 32.726884 -396.739364) (xy 32.723581 -396.745394) (xy 32.719968 -396.758654) (xy 32.719772 -396.765526)
			(xy 32.719772 -397.514826) (xy 32.719958 -397.5217) (xy 32.723571 -397.534962) (xy 32.726884 -397.540988)
			(xy 32.743173 -397.569367) (xy 32.768893 -397.629534) (xy 32.786304 -397.692609) (xy 32.795091 -397.757451)
			(xy 32.795095 -397.822884) (xy 32.786317 -397.887727) (xy 32.768914 -397.950804) (xy 32.743203 -398.010975)
			(xy 32.726884 -398.039336) (xy 32.723555 -398.045354) (xy 32.719959 -398.058623) (xy 32.719772 -398.065498)
			(xy 32.719772 -398.351502) (xy 32.719268 -398.361659) (xy 32.711495 -398.380426) (xy 32.697133 -398.394791)
			(xy 32.678367 -398.402567) (xy 32.66821 -398.403064) (xy 31.95193 -398.403064) (xy 31.941761 -398.402611)
			(xy 31.922967 -398.394837) (xy 31.908581 -398.38046) (xy 31.900795 -398.361671) (xy 31.900368 -398.351502)
			(xy 31.900368 -398.065498) (xy 31.900181 -398.058624) (xy 31.89657 -398.045361) (xy 31.893256 -398.039336)
			(xy 31.876901 -398.010993) (xy 31.851186 -397.950818) (xy 31.83378 -397.887735) (xy 31.825 -397.822887)
			(xy 30.536116 -397.822887) (xy 30.526736 -397.839184) (xy 30.52343 -397.845213) (xy 30.519818 -397.858473)
			(xy 30.519624 -397.865346) (xy 30.519624 -398.6149) (xy 30.519813 -398.621773) (xy 30.523423 -398.635036)
			(xy 30.526736 -398.641062) (xy 30.54309 -398.669406) (xy 30.568806 -398.729581) (xy 30.586211 -398.792663)
			(xy 30.594991 -398.857511) (xy 30.594989 -398.890236) (xy 34.024316 -398.890236) (xy 34.024873 -398.857506)
			(xy 34.033731 -398.792648) (xy 34.051224 -398.729567) (xy 34.077034 -398.66941) (xy 34.093404 -398.641062)
			(xy 34.096733 -398.635044) (xy 34.100329 -398.621775) (xy 34.100516 -398.6149) (xy 34.100516 -397.865346)
			(xy 34.100305 -397.858474) (xy 34.09671 -397.845211) (xy 34.093404 -397.839184) (xy 34.077032 -397.810838)
			(xy 34.051232 -397.750677) (xy 34.033744 -397.687597) (xy 34.024885 -397.622739) (xy 34.024316 -397.59001)
			(xy 34.024862 -397.55728) (xy 34.033723 -397.492421) (xy 34.051219 -397.429341) (xy 34.077033 -397.369183)
			(xy 34.093404 -397.340836) (xy 34.096706 -397.334805) (xy 34.10032 -397.321546) (xy 34.100516 -397.314674)
			(xy 34.100516 -397.028924) (xy 34.100936 -397.018801) (xy 34.108679 -397.000095) (xy 34.122995 -396.985779)
			(xy 34.141701 -396.978036) (xy 34.151824 -396.977616) (xy 34.868104 -396.977616) (xy 34.878229 -396.978013)
			(xy 34.896935 -396.985766) (xy 34.91125 -397.000088) (xy 34.918992 -397.018799) (xy 34.919412 -397.028924)
			(xy 34.919412 -397.314674) (xy 34.919613 -397.321547) (xy 34.923215 -397.334809) (xy 34.926524 -397.340836)
			(xy 34.942906 -397.369176) (xy 34.968704 -397.429339) (xy 34.986188 -397.492421) (xy 34.995044 -397.55728)
			(xy 34.995612 -397.59001) (xy 34.995027 -397.622739) (xy 34.986176 -397.687596) (xy 34.968692 -397.750676)
			(xy 34.951757 -397.790162) (xy 36.224464 -397.790162) (xy 36.22504 -397.757433) (xy 36.233893 -397.692575)
			(xy 36.251381 -397.629495) (xy 36.277185 -397.569336) (xy 36.293552 -397.540988) (xy 36.296867 -397.534964)
			(xy 36.300473 -397.5217) (xy 36.300664 -397.514826) (xy 36.300664 -396.765526) (xy 36.300467 -396.758653)
			(xy 36.296863 -396.74539) (xy 36.293552 -396.739364) (xy 36.277177 -396.71102) (xy 36.251376 -396.650859)
			(xy 36.233889 -396.587778) (xy 36.225032 -396.52292) (xy 36.224464 -396.49019) (xy 36.225053 -396.457461)
			(xy 36.233903 -396.392604) (xy 36.251386 -396.329524) (xy 36.277187 -396.269365) (xy 36.293552 -396.241016)
			(xy 36.296857 -396.234987) (xy 36.300469 -396.221727) (xy 36.300664 -396.214854) (xy 36.300664 -395.92885)
			(xy 36.301168 -395.918724) (xy 36.308884 -395.899999) (xy 36.323166 -395.88564) (xy 36.341848 -395.877823)
			(xy 36.351972 -395.877288) (xy 37.068252 -395.877288) (xy 37.078402 -395.877761) (xy 37.097151 -395.885538)
			(xy 37.111475 -395.899919) (xy 37.119179 -395.918699) (xy 37.11956 -395.92885) (xy 37.11956 -396.214854)
			(xy 37.119774 -396.221726) (xy 37.123368 -396.234988) (xy 37.126672 -396.241016) (xy 37.143041 -396.269363)
			(xy 37.168843 -396.329523) (xy 37.186332 -396.392603) (xy 37.195191 -396.457461) (xy 37.19576 -396.49019)
			(xy 37.195204 -396.52292) (xy 37.186344 -396.587778) (xy 37.168851 -396.650858) (xy 37.143041 -396.711016)
			(xy 37.126672 -396.739364) (xy 37.123368 -396.745394) (xy 37.119756 -396.758654) (xy 37.11956 -396.765526)
			(xy 37.11956 -397.514826) (xy 37.119747 -397.5217) (xy 37.123359 -397.534962) (xy 37.126672 -397.540988)
			(xy 37.136078 -397.557291) (xy 38.424972 -397.557291) (xy 38.433753 -397.492447) (xy 38.451158 -397.429369)
			(xy 38.476872 -397.369198) (xy 38.493192 -397.340836) (xy 38.496493 -397.334805) (xy 38.500108 -397.321546)
			(xy 38.500304 -397.314674) (xy 38.500304 -397.028924) (xy 38.500741 -397.018771) (xy 38.50853 -397.000018)
			(xy 38.522922 -396.985694) (xy 38.541711 -396.977994) (xy 38.551866 -396.977616) (xy 39.268146 -396.977616)
			(xy 39.278273 -396.978088) (xy 39.29699 -396.985827) (xy 39.311344 -397.000117) (xy 39.319166 -397.0188)
			(xy 39.319708 -397.028924) (xy 39.319708 -397.314674) (xy 39.319909 -397.321547) (xy 39.323511 -397.334809)
			(xy 39.32682 -397.340836) (xy 39.343152 -397.369192) (xy 39.368871 -397.429364) (xy 39.38628 -397.492444)
			(xy 39.395063 -397.55729) (xy 39.395062 -397.622728) (xy 39.386276 -397.687573) (xy 39.368865 -397.750652)
			(xy 39.351976 -397.790162) (xy 40.624252 -397.790162) (xy 40.624829 -397.757433) (xy 40.633683 -397.692575)
			(xy 40.65117 -397.629495) (xy 40.676973 -397.569337) (xy 40.69334 -397.540988) (xy 40.696654 -397.534963)
			(xy 40.700261 -397.5217) (xy 40.700452 -397.514826) (xy 40.700452 -396.765526) (xy 40.700256 -396.758653)
			(xy 40.696651 -396.74539) (xy 40.69334 -396.739364) (xy 40.676964 -396.71102) (xy 40.651164 -396.650859)
			(xy 40.633677 -396.587778) (xy 40.62482 -396.52292) (xy 40.624252 -396.49019) (xy 40.624842 -396.457461)
			(xy 40.633691 -396.392604) (xy 40.651175 -396.329524) (xy 40.676975 -396.269365) (xy 40.69334 -396.241016)
			(xy 40.696644 -396.234986) (xy 40.700257 -396.221727) (xy 40.700452 -396.214854) (xy 40.700452 -395.92885)
			(xy 40.700968 -395.918725) (xy 40.708682 -395.900003) (xy 40.722959 -395.885644) (xy 40.741638 -395.877825)
			(xy 40.75176 -395.877288) (xy 41.46804 -395.877288) (xy 41.478195 -395.877689) (xy 41.496946 -395.885495)
			(xy 41.511268 -395.899898) (xy 41.518968 -395.918693) (xy 41.519348 -395.92885) (xy 41.519348 -396.214854)
			(xy 41.519551 -396.221726) (xy 41.523151 -396.23499) (xy 41.52646 -396.241016) (xy 41.542828 -396.269364)
			(xy 41.56863 -396.329524) (xy 41.586119 -396.392604) (xy 41.594979 -396.457461) (xy 41.595548 -396.49019)
			(xy 41.594994 -396.52292) (xy 41.586134 -396.587778) (xy 41.56864 -396.650858) (xy 41.54283 -396.711016)
			(xy 41.52646 -396.739364) (xy 41.523163 -396.745397) (xy 41.519545 -396.758654) (xy 41.519348 -396.765526)
			(xy 41.519348 -397.514826) (xy 41.519524 -397.5217) (xy 41.523143 -397.534963) (xy 41.52646 -397.540988)
			(xy 41.542817 -397.569342) (xy 41.568622 -397.6295) (xy 41.586114 -397.692578) (xy 41.594977 -397.757433)
			(xy 41.595548 -397.790162) (xy 41.594981 -397.822891) (xy 41.586125 -397.887749) (xy 41.568635 -397.95083)
			(xy 41.542828 -398.010988) (xy 41.52646 -398.039336) (xy 41.523137 -398.045357) (xy 41.519536 -398.058623)
			(xy 41.519348 -398.065498) (xy 41.519348 -398.351502) (xy 41.518875 -398.36163) (xy 41.511144 -398.380354)
			(xy 41.496853 -398.39471) (xy 41.478166 -398.402527) (xy 41.46804 -398.403064) (xy 40.75176 -398.403064)
			(xy 40.741599 -398.40271) (xy 40.722839 -398.394895) (xy 40.708515 -398.380477) (xy 40.700824 -398.361666)
			(xy 40.700452 -398.351502) (xy 40.700452 -398.065498) (xy 40.700267 -398.058624) (xy 40.696655 -398.045361)
			(xy 40.69334 -398.039336) (xy 40.676993 -398.010977) (xy 40.651185 -397.950821) (xy 40.633691 -397.887745)
			(xy 40.624825 -397.82289) (xy 40.624252 -397.790162) (xy 39.351976 -397.790162) (xy 39.343144 -397.810823)
			(xy 39.32682 -397.839184) (xy 39.323512 -397.845212) (xy 39.319902 -397.858473) (xy 39.319708 -397.865346)
			(xy 39.319708 -398.6149) (xy 39.319899 -398.621773) (xy 39.323508 -398.635036) (xy 39.32682 -398.641062)
			(xy 39.343174 -398.669406) (xy 39.368891 -398.729581) (xy 39.386297 -398.792663) (xy 39.395078 -398.857511)
			(xy 39.395076 -398.890236) (xy 42.8244 -398.890236) (xy 42.82496 -398.857506) (xy 42.833817 -398.792648)
			(xy 42.851309 -398.729568) (xy 42.877119 -398.66941) (xy 42.893488 -398.641062) (xy 42.896815 -398.635044)
			(xy 42.900413 -398.621775) (xy 42.9006 -398.6149) (xy 42.9006 -397.865346) (xy 42.90039 -397.858474)
			(xy 42.896794 -397.845211) (xy 42.893488 -397.839184) (xy 42.877115 -397.810839) (xy 42.851315 -397.750678)
			(xy 42.833828 -397.687597) (xy 42.824969 -397.622739) (xy 42.8244 -397.59001) (xy 42.824948 -397.55728)
			(xy 42.833809 -397.492421) (xy 42.851304 -397.429341) (xy 42.877117 -397.369183) (xy 42.893488 -397.340836)
			(xy 42.896789 -397.334805) (xy 42.900404 -397.321546) (xy 42.9006 -397.314674) (xy 42.9006 -397.028924)
			(xy 42.901035 -397.018803) (xy 42.908776 -397.0001) (xy 42.923086 -396.985785) (xy 42.941787 -396.978039)
			(xy 42.951908 -396.977616) (xy 43.668188 -396.977616) (xy 43.678312 -396.978026) (xy 43.697018 -396.985773)
			(xy 43.711333 -397.000092) (xy 43.719076 -397.0188) (xy 43.719496 -397.028924) (xy 43.719496 -397.314674)
			(xy 43.719698 -397.321546) (xy 43.723299 -397.334809) (xy 43.726608 -397.340836) (xy 43.742989 -397.369177)
			(xy 43.768787 -397.42934) (xy 43.786272 -397.492422) (xy 43.795128 -397.55728) (xy 43.795696 -397.59001)
			(xy 43.795113 -397.622739) (xy 43.786262 -397.687597) (xy 43.768777 -397.750677) (xy 43.742974 -397.810835)
			(xy 43.736016 -397.822887) (xy 45.024876 -397.822887) (xy 45.024881 -397.757448) (xy 45.033669 -397.692601)
			(xy 45.051081 -397.629521) (xy 45.076804 -397.569349) (xy 45.093128 -397.540988) (xy 45.096449 -397.534966)
			(xy 45.10005 -397.5217) (xy 45.10024 -397.514826) (xy 45.10024 -396.765526) (xy 45.100033 -396.758654)
			(xy 45.096435 -396.745391) (xy 45.093128 -396.739364) (xy 45.076798 -396.711007) (xy 45.051081 -396.650835)
			(xy 45.033675 -396.587755) (xy 45.024892 -396.52291) (xy 45.024893 -396.457473) (xy 45.033678 -396.392628)
			(xy 45.051087 -396.329549) (xy 45.076805 -396.269377) (xy 45.093128 -396.241016) (xy 45.096439 -396.23499)
			(xy 45.100047 -396.221727) (xy 45.10024 -396.214854) (xy 45.10024 -395.92885) (xy 45.100705 -395.918681)
			(xy 45.108474 -395.899887) (xy 45.122847 -395.885501) (xy 45.141634 -395.877714) (xy 45.151802 -395.877288)
			(xy 45.868082 -395.877288) (xy 45.878259 -395.87768) (xy 45.897063 -395.885468) (xy 45.91145 -395.899864)
			(xy 45.919227 -395.918673) (xy 45.919644 -395.92885) (xy 45.919644 -396.214854) (xy 45.919848 -396.221726)
			(xy 45.923447 -396.234989) (xy 45.926756 -396.241016) (xy 45.94307 -396.269382) (xy 45.968789 -396.329552)
			(xy 45.986198 -396.39263) (xy 45.994982 -396.457473) (xy 45.994984 -396.522909) (xy 45.986201 -396.587754)
			(xy 45.968794 -396.650832) (xy 45.943078 -396.711003) (xy 45.926756 -396.739364) (xy 45.923458 -396.745397)
			(xy 45.919841 -396.758654) (xy 45.919644 -396.765526) (xy 45.919644 -397.514826) (xy 45.919821 -397.5217)
			(xy 45.923439 -397.534963) (xy 45.926756 -397.540988) (xy 45.936114 -397.55729) (xy 47.225044 -397.55729)
			(xy 47.233827 -397.492446) (xy 47.251235 -397.429368) (xy 47.276953 -397.369197) (xy 47.293276 -397.340836)
			(xy 47.296576 -397.334804) (xy 47.300191 -397.321546) (xy 47.300388 -397.314674) (xy 47.300388 -397.028924)
			(xy 47.300841 -397.018773) (xy 47.308626 -397.000023) (xy 47.323013 -396.985699) (xy 47.341797 -396.977997)
			(xy 47.35195 -396.977616) (xy 48.06823 -396.977616) (xy 48.078356 -396.978101) (xy 48.097073 -396.985834)
			(xy 48.111427 -397.000121) (xy 48.11925 -397.018801) (xy 48.119792 -397.028924) (xy 48.119792 -397.314674)
			(xy 48.119995 -397.321546) (xy 48.123596 -397.334809) (xy 48.126904 -397.340836) (xy 48.143233 -397.369193)
			(xy 48.168948 -397.429366) (xy 48.186354 -397.492445) (xy 48.195135 -397.55729) (xy 48.195134 -397.622727)
			(xy 48.18635 -397.687572) (xy 48.168942 -397.750651) (xy 48.143226 -397.810822) (xy 48.126904 -397.839184)
			(xy 48.123595 -397.845212) (xy 48.119986 -397.858473) (xy 48.119792 -397.865346) (xy 48.119792 -398.6149)
			(xy 48.119985 -398.621773) (xy 48.123592 -398.635036) (xy 48.126904 -398.641062) (xy 48.143255 -398.669407)
			(xy 48.168968 -398.729582) (xy 48.186371 -398.792664) (xy 48.19515 -398.857512) (xy 48.195146 -398.92295)
			(xy 48.186359 -398.987796) (xy 48.168947 -399.050876) (xy 48.143227 -399.111048) (xy 48.126904 -399.13941)
			(xy 48.123586 -399.145433) (xy 48.119982 -399.158698) (xy 48.119792 -399.165572) (xy 48.119792 -399.451576)
			(xy 48.119359 -399.46173) (xy 48.11157 -399.480483) (xy 48.097176 -399.494808) (xy 48.078386 -399.502507)
			(xy 48.06823 -399.502884) (xy 47.35195 -399.502884) (xy 47.341829 -399.502333) (xy 47.323114 -399.494626)
			(xy 47.308757 -399.48036) (xy 47.300932 -399.461693) (xy 47.300388 -399.451576) (xy 47.300388 -399.165572)
			(xy 47.300208 -399.158698) (xy 47.296592 -399.145435) (xy 47.293276 -399.13941) (xy 47.276983 -399.111032)
			(xy 47.251261 -399.050865) (xy 47.233848 -398.98779) (xy 47.22506 -398.922948) (xy 47.225056 -398.857514)
			(xy 47.233835 -398.792671) (xy 47.25124 -398.729593) (xy 47.276955 -398.669423) (xy 47.293276 -398.641062)
			(xy 47.296603 -398.635043) (xy 47.300201 -398.621775) (xy 47.300388 -398.6149) (xy 47.300388 -397.865346)
			(xy 47.30018 -397.858474) (xy 47.296583 -397.845211) (xy 47.293276 -397.839184) (xy 47.276961 -397.810818)
			(xy 47.251241 -397.750649) (xy 47.23383 -397.687571) (xy 47.225045 -397.622727) (xy 47.225044 -397.55729)
			(xy 45.936114 -397.55729) (xy 45.943046 -397.569367) (xy 45.968767 -397.629534) (xy 45.986179 -397.692609)
			(xy 45.994967 -397.75745) (xy 45.994971 -397.822884) (xy 45.986192 -397.887727) (xy 45.968789 -397.950804)
			(xy 45.943076 -398.010975) (xy 45.926756 -398.039336) (xy 45.923433 -398.045357) (xy 45.919832 -398.058623)
			(xy 45.919644 -398.065498) (xy 45.919644 -398.351502) (xy 45.919237 -398.361676) (xy 45.911448 -398.380474)
			(xy 45.897057 -398.39486) (xy 45.878256 -398.402641) (xy 45.868082 -398.403064) (xy 45.151802 -398.403064)
			(xy 45.141645 -398.402565) (xy 45.122876 -398.394792) (xy 45.108511 -398.380427) (xy 45.100736 -398.361659)
			(xy 45.10024 -398.351502) (xy 45.10024 -398.065498) (xy 45.100044 -398.058625) (xy 45.096438 -398.045363)
			(xy 45.093128 -398.039336) (xy 45.076774 -398.010992) (xy 45.05106 -397.950817) (xy 45.033656 -397.887735)
			(xy 45.024876 -397.822887) (xy 43.736016 -397.822887) (xy 43.726608 -397.839184) (xy 43.7233 -397.845212)
			(xy 43.71969 -397.858473) (xy 43.719496 -397.865346) (xy 43.719496 -398.6149) (xy 43.719688 -398.621773)
			(xy 43.723296 -398.635036) (xy 43.726608 -398.641062) (xy 43.742959 -398.669419) (xy 43.768764 -398.729576)
			(xy 43.786258 -398.792653) (xy 43.795123 -398.857508) (xy 43.795696 -398.890236) (xy 43.795124 -398.922965)
			(xy 43.78627 -398.987823) (xy 43.768782 -399.050904) (xy 43.742976 -399.111062) (xy 43.726608 -399.13941)
			(xy 43.72329 -399.145433) (xy 43.719686 -399.158698) (xy 43.719496 -399.165572) (xy 43.719496 -399.451576)
			(xy 43.719064 -399.461697) (xy 43.711323 -399.480401) (xy 43.697011 -399.494717) (xy 43.678309 -399.502462)
			(xy 43.668188 -399.502884) (xy 42.951908 -399.502884) (xy 42.941784 -399.502477) (xy 42.923078 -399.494729)
			(xy 42.908762 -399.480409) (xy 42.90102 -399.4617) (xy 42.9006 -399.451576) (xy 42.9006 -399.165572)
			(xy 42.900419 -399.158698) (xy 42.896803 -399.145435) (xy 42.893488 -399.13941) (xy 42.877125 -399.111059)
			(xy 42.851323 -399.0509) (xy 42.833833 -398.987821) (xy 42.824971 -398.922965) (xy 42.8244 -398.890236)
			(xy 39.395076 -398.890236) (xy 39.395074 -398.922951) (xy 39.386285 -398.987798) (xy 39.36887 -399.050878)
			(xy 39.343146 -399.111049) (xy 39.32682 -399.13941) (xy 39.323503 -399.145434) (xy 39.319898 -399.158698)
			(xy 39.319708 -399.165572) (xy 39.319708 -399.451576) (xy 39.319259 -399.461728) (xy 39.311473 -399.480478)
			(xy 39.297085 -399.494802) (xy 39.278299 -399.502504) (xy 39.268146 -399.502884) (xy 38.551866 -399.502884)
			(xy 38.54174 -399.502402) (xy 38.523023 -399.494668) (xy 38.508668 -399.48038) (xy 38.500846 -399.4617)
			(xy 38.500304 -399.451576) (xy 38.500304 -399.165572) (xy 38.500122 -399.158698) (xy 38.496507 -399.145435)
			(xy 38.493192 -399.13941) (xy 38.476902 -399.111031) (xy 38.451184 -399.050864) (xy 38.433774 -398.987789)
			(xy 38.424988 -398.922948) (xy 38.424983 -398.857514) (xy 38.433762 -398.792672) (xy 38.451163 -398.729595)
			(xy 38.476874 -398.669424) (xy 38.493192 -398.641062) (xy 38.49652 -398.635044) (xy 38.500117 -398.621775)
			(xy 38.500304 -398.6149) (xy 38.500304 -397.865346) (xy 38.500094 -397.858474) (xy 38.496498 -397.845211)
			(xy 38.493192 -397.839184) (xy 38.47688 -397.810818) (xy 38.451164 -397.750647) (xy 38.433756 -397.68757)
			(xy 38.424973 -397.622726) (xy 38.424972 -397.557291) (xy 37.136078 -397.557291) (xy 37.14303 -397.569341)
			(xy 37.168834 -397.629499) (xy 37.186326 -397.692577) (xy 37.195189 -397.757433) (xy 37.19576 -397.790162)
			(xy 37.195192 -397.822891) (xy 37.186335 -397.887749) (xy 37.168846 -397.950829) (xy 37.14304 -398.010988)
			(xy 37.126672 -398.039336) (xy 37.123343 -398.045353) (xy 37.119747 -398.058623) (xy 37.11956 -398.065498)
			(xy 37.11956 -398.351502) (xy 37.119075 -398.361629) (xy 37.111347 -398.38035) (xy 37.09706 -398.394706)
			(xy 37.078376 -398.402525) (xy 37.068252 -398.403064) (xy 36.351972 -398.403064) (xy 36.341812 -398.402701)
			(xy 36.323052 -398.394889) (xy 36.308728 -398.380474) (xy 36.301036 -398.361665) (xy 36.300664 -398.351502)
			(xy 36.300664 -398.065498) (xy 36.300477 -398.058624) (xy 36.296866 -398.045361) (xy 36.293552 -398.039336)
			(xy 36.277206 -398.010976) (xy 36.251398 -397.950821) (xy 36.233903 -397.887745) (xy 36.225037 -397.82289)
			(xy 36.224464 -397.790162) (xy 34.951757 -397.790162) (xy 34.94289 -397.810835) (xy 34.926524 -397.839184)
			(xy 34.923217 -397.845212) (xy 34.919606 -397.858473) (xy 34.919412 -397.865346) (xy 34.919412 -398.6149)
			(xy 34.919603 -398.621773) (xy 34.923212 -398.635036) (xy 34.926524 -398.641062) (xy 34.942877 -398.669418)
			(xy 34.968681 -398.729575) (xy 34.986174 -398.792653) (xy 34.995039 -398.857508) (xy 34.995612 -398.890236)
			(xy 34.995038 -398.922965) (xy 34.986185 -398.987823) (xy 34.968696 -399.050903) (xy 34.942891 -399.111062)
			(xy 34.926524 -399.13941) (xy 34.923207 -399.145434) (xy 34.919602 -399.158698) (xy 34.919412 -399.165572)
			(xy 34.919412 -399.451576) (xy 34.918965 -399.461695) (xy 34.911227 -399.480396) (xy 34.89692 -399.494711)
			(xy 34.878223 -399.502459) (xy 34.868104 -399.502884) (xy 34.151824 -399.502884) (xy 34.141701 -399.502464)
			(xy 34.122995 -399.494721) (xy 34.108679 -399.480405) (xy 34.100936 -399.461699) (xy 34.100516 -399.451576)
			(xy 34.100516 -399.165572) (xy 34.100333 -399.158698) (xy 34.096718 -399.145435) (xy 34.093404 -399.13941)
			(xy 34.077043 -399.111058) (xy 34.05124 -399.0509) (xy 34.033749 -398.987821) (xy 34.024887 -398.922965)
			(xy 34.024316 -398.890236) (xy 30.594989 -398.890236) (xy 30.594987 -398.922951) (xy 30.586199 -398.987797)
			(xy 30.568785 -399.050877) (xy 30.543061 -399.111049) (xy 30.526736 -399.13941) (xy 30.523421 -399.145434)
			(xy 30.519815 -399.158698) (xy 30.519624 -399.165572) (xy 30.519624 -399.451576) (xy 30.519159 -399.461726)
			(xy 30.511376 -399.480473) (xy 30.496993 -399.494796) (xy 30.478213 -399.502501) (xy 30.468062 -399.502884)
			(xy 29.751782 -399.502884) (xy 29.741657 -399.502389) (xy 29.72294 -399.49466) (xy 29.708585 -399.480377)
			(xy 29.700762 -399.461698) (xy 29.70022 -399.451576) (xy 29.70022 -399.165572) (xy 29.700036 -399.158698)
			(xy 29.696422 -399.145436) (xy 29.693108 -399.13941) (xy 29.676817 -399.111032) (xy 29.651098 -399.050864)
			(xy 29.633688 -398.987789) (xy 29.624901 -398.922948) (xy 29.624897 -398.857514) (xy 29.633676 -398.792672)
			(xy 29.651078 -398.729594) (xy 29.676789 -398.669424) (xy 29.693108 -398.641062) (xy 29.696437 -398.635044)
			(xy 29.700033 -398.621775) (xy 29.70022 -398.6149) (xy 29.70022 -397.865346) (xy 29.700008 -397.858474)
			(xy 29.696413 -397.845212) (xy 29.693108 -397.839184) (xy 29.676795 -397.810818) (xy 29.651078 -397.750647)
			(xy 29.633671 -397.68757) (xy 29.624887 -397.622726) (xy 29.624885 -397.557291) (xy 28.335995 -397.557291)
			(xy 28.342948 -397.569341) (xy 28.368751 -397.629499) (xy 28.386243 -397.692577) (xy 28.395105 -397.757433)
			(xy 28.395676 -397.790162) (xy 28.395119 -397.822892) (xy 28.386261 -397.887751) (xy 28.368768 -397.950831)
			(xy 28.342958 -398.010988) (xy 28.326588 -398.039336) (xy 28.32326 -398.045354) (xy 28.319663 -398.058623)
			(xy 28.319476 -398.065498) (xy 28.319476 -398.351502) (xy 28.318975 -398.361627) (xy 28.31125 -398.380345)
			(xy 28.296968 -398.394701) (xy 28.27829 -398.402523) (xy 28.268168 -398.403064) (xy 27.551888 -398.403064)
			(xy 27.541729 -398.402688) (xy 27.522969 -398.394881) (xy 27.508645 -398.38047) (xy 27.500952 -398.361664)
			(xy 27.50058 -398.351502) (xy 27.50058 -398.065498) (xy 27.500391 -398.058625) (xy 27.496781 -398.045362)
			(xy 27.493468 -398.039336) (xy 27.477123 -398.010975) (xy 27.451315 -397.95082) (xy 27.433819 -397.887744)
			(xy 27.424953 -397.82289) (xy 27.42438 -397.790162) (xy 8.835476 -397.790162) (xy 8.850142 -397.906253)
			(xy 8.858264 -398.035359) (xy 8.858264 -398.164721) (xy 8.850142 -398.293827) (xy 8.833928 -398.422169)
			(xy 8.809688 -398.549239) (xy 8.777518 -398.674536) (xy 8.737543 -398.797566) (xy 8.689921 -398.917844)
			(xy 8.634842 -399.034893) (xy 8.572521 -399.148254) (xy 8.503206 -399.257477) (xy 8.427169 -399.362133)
			(xy 8.344711 -399.461808) (xy 8.256157 -399.556108) (xy 8.161856 -399.644662) (xy 8.062181 -399.72712)
			(xy 7.957526 -399.803157) (xy 7.848302 -399.872472) (xy 7.734942 -399.934793) (xy 7.617892 -399.989872)
			(xy 7.497614 -400.037493) (xy 7.374584 -400.077468) (xy 7.249287 -400.109639) (xy 7.122217 -400.133879)
			(xy 6.993875 -400.150092) (xy 6.864769 -400.158214) (xy 6.800088 -400.158712) (xy 5.199888 -400.158712)
			(xy 5.135208 -400.158204) (xy 5.006102 -400.150081) (xy 4.877762 -400.133868) (xy 4.750692 -400.109628)
			(xy 4.625396 -400.077458) (xy 4.502366 -400.037483) (xy 4.38209 -399.989862) (xy 4.265041 -399.934783)
			(xy 4.151681 -399.872463) (xy 4.042458 -399.803148) (xy 3.937803 -399.727112) (xy 3.838129 -399.644654)
			(xy 3.743829 -399.556101) (xy 3.655276 -399.461801) (xy 3.572818 -399.362127) (xy 3.496782 -399.257472)
			(xy 3.427467 -399.148249) (xy 3.365147 -399.034889) (xy 3.310068 -398.91784) (xy 3.262447 -398.797564)
			(xy 3.222472 -398.674534) (xy 3.190302 -398.549238) (xy 3.166062 -398.422168) (xy 3.149849 -398.293828)
			(xy 3.141726 -398.164722) (xy 0.529844 -398.164722) (xy 0.529844 -401.690078) (xy 27.42438 -401.690078)
			(xy 27.424961 -401.657349) (xy 27.433813 -401.592491) (xy 27.451299 -401.529411) (xy 27.477102 -401.469253)
			(xy 27.493468 -401.440904) (xy 27.496779 -401.434877) (xy 27.500387 -401.421615) (xy 27.50058 -401.414742)
			(xy 27.50058 -400.665442) (xy 27.500374 -400.65857) (xy 27.496776 -400.645307) (xy 27.493468 -400.63928)
			(xy 27.477101 -400.610931) (xy 27.451298 -400.550772) (xy 27.433808 -400.487692) (xy 27.424949 -400.422835)
			(xy 27.42438 -400.390106) (xy 27.424929 -400.357376) (xy 27.43379 -400.292517) (xy 27.451285 -400.229437)
			(xy 27.477097 -400.169279) (xy 27.493468 -400.140932) (xy 27.496769 -400.1349) (xy 27.500383 -400.121642)
			(xy 27.50058 -400.11477) (xy 27.50058 -399.828766) (xy 27.501 -399.818632) (xy 27.508746 -399.799903)
			(xy 27.523053 -399.785546) (xy 27.541756 -399.777735) (xy 27.551888 -399.777204) (xy 28.268168 -399.777204)
			(xy 28.278321 -399.777648) (xy 28.297073 -399.785433) (xy 28.311398 -399.799824) (xy 28.319098 -399.818612)
			(xy 28.319476 -399.828766) (xy 28.319476 -400.11477) (xy 28.319682 -400.121642) (xy 28.323281 -400.134905)
			(xy 28.326588 -400.140932) (xy 28.342965 -400.169275) (xy 28.368764 -400.229437) (xy 28.386251 -400.292518)
			(xy 28.395108 -400.357376) (xy 28.395676 -400.390106) (xy 28.395094 -400.422835) (xy 28.386243 -400.487693)
			(xy 28.368758 -400.550773) (xy 28.342955 -400.610932) (xy 28.326588 -400.63928) (xy 28.32328 -400.645308)
			(xy 28.31967 -400.658569) (xy 28.319476 -400.665442) (xy 28.319476 -401.414742) (xy 28.319693 -401.421613)
			(xy 28.323284 -401.434876) (xy 28.326588 -401.440904) (xy 28.342954 -401.469253) (xy 28.368756 -401.529413)
			(xy 28.386246 -401.592492) (xy 28.395106 -401.657349) (xy 28.395676 -401.690078) (xy 28.395126 -401.722808)
			(xy 28.386266 -401.787667) (xy 28.368771 -401.850747) (xy 28.342959 -401.910905) (xy 28.326588 -401.939252)
			(xy 28.323254 -401.945267) (xy 28.319661 -401.958538) (xy 28.319476 -401.965414) (xy 28.319476 -402.251418)
			(xy 28.318989 -402.261544) (xy 28.311258 -402.280263) (xy 28.296972 -402.294618) (xy 28.278291 -402.302439)
			(xy 28.268168 -402.30298) (xy 27.551888 -402.30298) (xy 27.541731 -402.302588) (xy 27.522974 -402.294785)
			(xy 27.50865 -402.280379) (xy 27.500954 -402.261578) (xy 27.50058 -402.251418) (xy 27.50058 -401.965414)
			(xy 27.500385 -401.958541) (xy 27.496779 -401.945278) (xy 27.493468 -401.939252) (xy 27.47709 -401.91091)
			(xy 27.451289 -401.850748) (xy 27.433803 -401.787666) (xy 27.424947 -401.722808) (xy 27.42438 -401.690078)
			(xy 0.529844 -401.690078) (xy 0.529844 -402.232191) (xy 13.656034 -402.232191) (xy 13.656034 -402.177689)
			(xy 13.66379 -402.123741) (xy 13.679145 -402.071446) (xy 13.701786 -402.021868) (xy 13.731253 -401.976018)
			(xy 13.766944 -401.934827) (xy 13.808134 -401.899135) (xy 13.853985 -401.869668) (xy 13.903562 -401.847027)
			(xy 13.955857 -401.831671) (xy 14.009805 -401.823914) (xy 14.037056 -401.823428) (xy 14.063372 -401.823849)
			(xy 14.115503 -401.831092) (xy 14.166146 -401.84542) (xy 14.214345 -401.866561) (xy 14.259188 -401.894115)
			(xy 14.299825 -401.927562) (xy 14.31798 -401.946618) (xy 14.325505 -401.954016) (xy 14.344782 -401.962542)
			(xy 14.355318 -401.963128) (xy 14.429994 -401.963128) (xy 14.440544 -401.962601) (xy 14.459839 -401.954063)
			(xy 14.467332 -401.946618) (xy 14.487152 -401.92583) (xy 14.531924 -401.889855) (xy 14.581582 -401.860995)
			(xy 14.635004 -401.839902) (xy 14.690983 -401.827053) (xy 14.748256 -401.822738) (xy 14.805529 -401.827053)
			(xy 14.861508 -401.839902) (xy 14.91493 -401.860995) (xy 14.964588 -401.889855) (xy 15.00936 -401.92583)
			(xy 15.02918 -401.946618) (xy 15.036705 -401.954016) (xy 15.055982 -401.962542) (xy 15.066518 -401.963128)
			(xy 15.141194 -401.963128) (xy 15.151744 -401.962601) (xy 15.171039 -401.954063) (xy 15.178532 -401.946618)
			(xy 15.196683 -401.927557) (xy 15.237313 -401.8941) (xy 15.282154 -401.866541) (xy 15.330356 -401.845403)
			(xy 15.381005 -401.831088) (xy 15.433139 -401.823865) (xy 15.459456 -401.823428) (xy 15.486709 -401.823899)
			(xy 15.54066 -401.831655) (xy 15.592957 -401.847011) (xy 15.642537 -401.869653) (xy 15.688391 -401.899121)
			(xy 15.729583 -401.934814) (xy 15.765277 -401.976006) (xy 15.794745 -402.021859) (xy 15.817388 -402.071439)
			(xy 15.832744 -402.123737) (xy 15.840501 -402.177687) (xy 15.840501 -402.232193) (xy 15.832744 -402.286143)
			(xy 15.817388 -402.338441) (xy 15.794745 -402.388021) (xy 15.765277 -402.433874) (xy 15.729583 -402.475066)
			(xy 15.688391 -402.510759) (xy 15.642537 -402.540227) (xy 15.592957 -402.562869) (xy 15.54066 -402.578225)
			(xy 15.486709 -402.585981) (xy 15.459456 -402.586444) (xy 15.43314 -402.586024) (xy 15.381009 -402.578782)
			(xy 15.330365 -402.564455) (xy 15.282165 -402.543313) (xy 15.237323 -402.515758) (xy 15.196686 -402.48231)
			(xy 15.178532 -402.463254) (xy 15.170993 -402.455873) (xy 15.151727 -402.447335) (xy 15.141194 -402.446744)
			(xy 15.066518 -402.446744) (xy 15.055966 -402.447256) (xy 15.03667 -402.455802) (xy 15.02918 -402.463254)
			(xy 15.00936 -402.484042) (xy 14.964588 -402.520017) (xy 14.91493 -402.548877) (xy 14.861508 -402.56997)
			(xy 14.805529 -402.582819) (xy 14.748256 -402.587134) (xy 14.690983 -402.582819) (xy 14.635004 -402.56997)
			(xy 14.581582 -402.548877) (xy 14.531924 -402.520017) (xy 14.487152 -402.484042) (xy 14.467332 -402.463254)
			(xy 14.459793 -402.455873) (xy 14.440527 -402.447335) (xy 14.429994 -402.446744) (xy 14.355318 -402.446744)
			(xy 14.344766 -402.447256) (xy 14.32547 -402.455802) (xy 14.31798 -402.463254) (xy 14.299838 -402.482323)
			(xy 14.259204 -402.515776) (xy 14.214361 -402.543332) (xy 14.166157 -402.564468) (xy 14.115508 -402.578783)
			(xy 14.063373 -402.586006) (xy 14.037056 -402.586444) (xy 14.009805 -402.585966) (xy 13.955857 -402.578209)
			(xy 13.903562 -402.562853) (xy 13.853985 -402.540212) (xy 13.808134 -402.510745) (xy 13.766944 -402.475053)
			(xy 13.731253 -402.433862) (xy 13.701786 -402.388012) (xy 13.679145 -402.338434) (xy 13.66379 -402.286139)
			(xy 13.656034 -402.232191) (xy 0.529844 -402.232191) (xy 0.529844 -402.822879) (xy 29.624853 -402.822879)
			(xy 29.624859 -402.757439) (xy 29.633648 -402.692592) (xy 29.651061 -402.629512) (xy 29.676784 -402.56934)
			(xy 29.693108 -402.540978) (xy 29.696431 -402.534958) (xy 29.700031 -402.521691) (xy 29.70022 -402.514816)
			(xy 29.70022 -401.765516) (xy 29.70002 -401.758643) (xy 29.696417 -401.745381) (xy 29.693108 -401.739354)
			(xy 29.67677 -401.711002) (xy 29.651055 -401.650828) (xy 29.63365 -401.587748) (xy 29.624869 -401.522902)
			(xy 29.624872 -401.457464) (xy 29.633657 -401.392619) (xy 29.651067 -401.329539) (xy 29.676785 -401.269368)
			(xy 29.693108 -401.241006) (xy 29.696421 -401.234981) (xy 29.700028 -401.221717) (xy 29.70022 -401.214844)
			(xy 29.70022 -400.92884) (xy 29.700655 -400.918686) (xy 29.708441 -400.899931) (xy 29.722834 -400.885605)
			(xy 29.741626 -400.877908) (xy 29.751782 -400.877532) (xy 30.468062 -400.877532) (xy 30.478185 -400.878058)
			(xy 30.496904 -400.885771) (xy 30.511261 -400.900046) (xy 30.519083 -400.91872) (xy 30.519624 -400.92884)
			(xy 30.519624 -401.214844) (xy 30.519834 -401.221716) (xy 30.52343 -401.234979) (xy 30.526736 -401.241006)
			(xy 30.543042 -401.269376) (xy 30.568763 -401.329545) (xy 30.586173 -401.392622) (xy 30.59496 -401.457465)
			(xy 30.594962 -401.522901) (xy 30.58618 -401.587744) (xy 30.568774 -401.650822) (xy 30.543058 -401.710993)
			(xy 30.536263 -401.7228) (xy 31.82501 -401.7228) (xy 31.825012 -401.657362) (xy 31.833799 -401.592516)
			(xy 31.85121 -401.529437) (xy 31.876932 -401.469265) (xy 31.893256 -401.440904) (xy 31.896566 -401.434877)
			(xy 31.900175 -401.421615) (xy 31.900368 -401.414742) (xy 31.900368 -400.665442) (xy 31.900164 -400.65857)
			(xy 31.896564 -400.645307) (xy 31.893256 -400.63928) (xy 31.876938 -400.610916) (xy 31.851219 -400.550746)
			(xy 31.83381 -400.487668) (xy 31.825026 -400.422823) (xy 31.825025 -400.357387) (xy 31.833808 -400.292543)
			(xy 31.851216 -400.229464) (xy 31.876934 -400.169293) (xy 31.893256 -400.140932) (xy 31.896556 -400.1349)
			(xy 31.900171 -400.121642) (xy 31.900368 -400.11477) (xy 31.900368 -399.828766) (xy 31.900806 -399.818602)
			(xy 31.908597 -399.799827) (xy 31.92298 -399.785462) (xy 31.941766 -399.777694) (xy 31.95193 -399.777204)
			(xy 32.66821 -399.777204) (xy 32.678364 -399.777725) (xy 32.697127 -399.785496) (xy 32.711491 -399.799853)
			(xy 32.719271 -399.818612) (xy 32.719772 -399.828766) (xy 32.719772 -400.11477) (xy 32.719979 -400.121642)
			(xy 32.723577 -400.134905) (xy 32.726884 -400.140932) (xy 32.743211 -400.169291) (xy 32.768927 -400.229463)
			(xy 32.786333 -400.292542) (xy 32.795116 -400.357387) (xy 32.795115 -400.422824) (xy 32.786331 -400.487668)
			(xy 32.768923 -400.550747) (xy 32.743206 -400.610918) (xy 32.726884 -400.63928) (xy 32.723575 -400.645308)
			(xy 32.719966 -400.658569) (xy 32.719772 -400.665442) (xy 32.719772 -401.414742) (xy 32.719989 -401.421613)
			(xy 32.723581 -401.434876) (xy 32.726884 -401.440904) (xy 32.743187 -401.469276) (xy 32.768905 -401.529445)
			(xy 32.786314 -401.592521) (xy 32.7951 -401.657364) (xy 32.795102 -401.722799) (xy 32.786322 -401.787642)
			(xy 32.768918 -401.85072) (xy 32.743204 -401.910891) (xy 32.726884 -401.939252) (xy 32.72355 -401.945267)
			(xy 32.719957 -401.958538) (xy 32.719772 -401.965414) (xy 32.719772 -402.251418) (xy 32.719282 -402.261576)
			(xy 32.711503 -402.280343) (xy 32.697137 -402.294708) (xy 32.678368 -402.302483) (xy 32.66821 -402.30298)
			(xy 31.95193 -402.30298) (xy 31.941763 -402.302512) (xy 31.922972 -402.29474) (xy 31.908587 -402.280368)
			(xy 31.900798 -402.261585) (xy 31.900368 -402.251418) (xy 31.900368 -401.965414) (xy 31.900175 -401.958541)
			(xy 31.896568 -401.945278) (xy 31.893256 -401.939252) (xy 31.876915 -401.910901) (xy 31.851198 -401.850728)
			(xy 31.833791 -401.787647) (xy 31.82501 -401.7228) (xy 30.536263 -401.7228) (xy 30.526736 -401.739354)
			(xy 30.523441 -401.745388) (xy 30.519822 -401.758644) (xy 30.519624 -401.765516) (xy 30.519624 -402.514816)
			(xy 30.519807 -402.52169) (xy 30.523421 -402.534953) (xy 30.526736 -402.540978) (xy 30.543018 -402.569361)
			(xy 30.568741 -402.629527) (xy 30.586155 -402.692601) (xy 30.594944 -402.757442) (xy 30.594946 -402.790152)
			(xy 34.024316 -402.790152) (xy 34.024881 -402.757422) (xy 34.033736 -402.692564) (xy 34.051227 -402.629484)
			(xy 34.077035 -402.569326) (xy 34.093404 -402.540978) (xy 34.096727 -402.534957) (xy 34.100327 -402.521691)
			(xy 34.100516 -402.514816) (xy 34.100516 -401.765516) (xy 34.100316 -401.758643) (xy 34.096713 -401.745381)
			(xy 34.093404 -401.739354) (xy 34.07702 -401.711015) (xy 34.051223 -401.650852) (xy 34.033738 -401.587769)
			(xy 34.024883 -401.52291) (xy 34.024316 -401.49018) (xy 34.024893 -401.457451) (xy 34.033745 -401.392593)
			(xy 34.051232 -401.329513) (xy 34.077037 -401.269354) (xy 34.093404 -401.241006) (xy 34.096717 -401.23498)
			(xy 34.100324 -401.221717) (xy 34.100516 -401.214844) (xy 34.100516 -400.92884) (xy 34.100949 -400.918718)
			(xy 34.108687 -400.900012) (xy 34.122999 -400.885696) (xy 34.141702 -400.877952) (xy 34.151824 -400.877532)
			(xy 34.868104 -400.877532) (xy 34.878231 -400.877914) (xy 34.89694 -400.885669) (xy 34.911256 -400.899997)
			(xy 34.918995 -400.918713) (xy 34.919412 -400.92884) (xy 34.919412 -401.214844) (xy 34.919624 -401.221716)
			(xy 34.923218 -401.234979) (xy 34.926524 -401.241006) (xy 34.942894 -401.269353) (xy 34.968694 -401.329513)
			(xy 34.986183 -401.392594) (xy 34.995042 -401.457451) (xy 34.995612 -401.49018) (xy 34.995058 -401.52291)
			(xy 34.986199 -401.587769) (xy 34.968705 -401.650849) (xy 34.951873 -401.690078) (xy 36.224464 -401.690078)
			(xy 36.225047 -401.657349) (xy 36.233899 -401.592492) (xy 36.251384 -401.529412) (xy 36.277186 -401.469253)
			(xy 36.293552 -401.440904) (xy 36.296861 -401.434877) (xy 36.300471 -401.421615) (xy 36.300664 -401.414742)
			(xy 36.300664 -400.665442) (xy 36.30046 -400.65857) (xy 36.296861 -400.645307) (xy 36.293552 -400.63928)
			(xy 36.277183 -400.610932) (xy 36.251381 -400.550773) (xy 36.233892 -400.487693) (xy 36.225033 -400.422835)
			(xy 36.224464 -400.390106) (xy 36.225015 -400.357376) (xy 36.233876 -400.292517) (xy 36.25137 -400.229437)
			(xy 36.277182 -400.16928) (xy 36.293552 -400.140932) (xy 36.296852 -400.1349) (xy 36.300467 -400.121642)
			(xy 36.300664 -400.11477) (xy 36.300664 -399.828766) (xy 36.301099 -399.818634) (xy 36.308843 -399.799908)
			(xy 36.323145 -399.785552) (xy 36.341842 -399.777738) (xy 36.351972 -399.777204) (xy 37.068252 -399.777204)
			(xy 37.078404 -399.777661) (xy 37.097156 -399.785442) (xy 37.111481 -399.799828) (xy 37.119181 -399.818613)
			(xy 37.11956 -399.828766) (xy 37.11956 -400.11477) (xy 37.119768 -400.121642) (xy 37.123366 -400.134905)
			(xy 37.126672 -400.140932) (xy 37.143048 -400.169276) (xy 37.168848 -400.229437) (xy 37.186335 -400.292518)
			(xy 37.195192 -400.357376) (xy 37.19576 -400.390106) (xy 37.195167 -400.422834) (xy 37.186318 -400.487691)
			(xy 37.168835 -400.550772) (xy 37.143036 -400.610931) (xy 37.126672 -400.63928) (xy 37.123362 -400.645307)
			(xy 37.119754 -400.658569) (xy 37.11956 -400.665442) (xy 37.11956 -401.414742) (xy 37.119779 -401.421613)
			(xy 37.123369 -401.434876) (xy 37.126672 -401.440904) (xy 37.143036 -401.469254) (xy 37.168839 -401.529413)
			(xy 37.186329 -401.592492) (xy 37.19519 -401.657349) (xy 37.19576 -401.690078) (xy 37.195199 -401.722808)
			(xy 37.18634 -401.787666) (xy 37.168849 -401.850746) (xy 37.143041 -401.910904) (xy 37.126672 -401.939252)
			(xy 37.123337 -401.945267) (xy 37.119745 -401.958538) (xy 37.11956 -401.965414) (xy 37.11956 -402.251418)
			(xy 37.119088 -402.261546) (xy 37.111355 -402.280268) (xy 37.097064 -402.294623) (xy 37.078378 -402.302442)
			(xy 37.068252 -402.30298) (xy 36.351972 -402.30298) (xy 36.341814 -402.302601) (xy 36.323057 -402.294792)
			(xy 36.308734 -402.280383) (xy 36.301038 -402.261579) (xy 36.300664 -402.251418) (xy 36.300664 -401.965414)
			(xy 36.300471 -401.958541) (xy 36.296864 -401.945278) (xy 36.293552 -401.939252) (xy 36.277172 -401.91091)
			(xy 36.251373 -401.850748) (xy 36.233887 -401.787667) (xy 36.225031 -401.722808) (xy 36.224464 -401.690078)
			(xy 34.951873 -401.690078) (xy 34.942894 -401.711006) (xy 34.926524 -401.739354) (xy 34.923227 -401.745388)
			(xy 34.91961 -401.758644) (xy 34.919412 -401.765516) (xy 34.919412 -402.514816) (xy 34.919596 -402.52169)
			(xy 34.923209 -402.534953) (xy 34.926524 -402.540978) (xy 34.942883 -402.569331) (xy 34.968686 -402.629489)
			(xy 34.986177 -402.692568) (xy 34.99504 -402.757423) (xy 34.995612 -402.790152) (xy 34.995045 -402.822879)
			(xy 38.42494 -402.822879) (xy 38.424945 -402.757439) (xy 38.433734 -402.692593) (xy 38.451146 -402.629512)
			(xy 38.476868 -402.56934) (xy 38.493192 -402.540978) (xy 38.496514 -402.534957) (xy 38.500115 -402.52169)
			(xy 38.500304 -402.514816) (xy 38.500304 -401.765516) (xy 38.500106 -401.758643) (xy 38.496502 -401.74538)
			(xy 38.493192 -401.739354) (xy 38.476854 -401.711002) (xy 38.451141 -401.650828) (xy 38.433736 -401.587747)
			(xy 38.424956 -401.522902) (xy 38.424958 -401.457464) (xy 38.433743 -401.392619) (xy 38.451152 -401.32954)
			(xy 38.47687 -401.269368) (xy 38.493192 -401.241006) (xy 38.496504 -401.23498) (xy 38.500112 -401.221717)
			(xy 38.500304 -401.214844) (xy 38.500304 -400.92884) (xy 38.500755 -400.918688) (xy 38.508538 -400.899936)
			(xy 38.522926 -400.885611) (xy 38.541712 -400.87791) (xy 38.551866 -400.877532) (xy 39.268146 -400.877532)
			(xy 39.278275 -400.877989) (xy 39.296995 -400.88573) (xy 39.31135 -400.900025) (xy 39.319169 -400.918714)
			(xy 39.319708 -400.92884) (xy 39.319708 -401.214844) (xy 39.31992 -401.221716) (xy 39.323515 -401.234979)
			(xy 39.32682 -401.241006) (xy 39.343127 -401.269376) (xy 39.368848 -401.329545) (xy 39.386259 -401.392622)
			(xy 39.395046 -401.457465) (xy 39.395048 -401.522901) (xy 39.386266 -401.587745) (xy 39.368859 -401.650823)
			(xy 39.352081 -401.690078) (xy 40.624252 -401.690078) (xy 40.624837 -401.657349) (xy 40.633688 -401.592492)
			(xy 40.651173 -401.529412) (xy 40.676974 -401.469253) (xy 40.69334 -401.440904) (xy 40.696649 -401.434876)
			(xy 40.700259 -401.421615) (xy 40.700452 -401.414742) (xy 40.700452 -400.665442) (xy 40.70025 -400.658569)
			(xy 40.696649 -400.645306) (xy 40.69334 -400.63928) (xy 40.67697 -400.610933) (xy 40.651169 -400.550773)
			(xy 40.63368 -400.487693) (xy 40.624821 -400.422835) (xy 40.624252 -400.390106) (xy 40.624804 -400.357376)
			(xy 40.633665 -400.292518) (xy 40.651159 -400.229438) (xy 40.67697 -400.16928) (xy 40.69334 -400.140932)
			(xy 40.696639 -400.134899) (xy 40.700255 -400.121642) (xy 40.700452 -400.11477) (xy 40.700452 -399.828766)
			(xy 40.700899 -399.818636) (xy 40.70864 -399.799911) (xy 40.722939 -399.785556) (xy 40.741632 -399.77774)
			(xy 40.75176 -399.777204) (xy 41.46804 -399.777204) (xy 41.478197 -399.777589) (xy 41.496951 -399.785399)
			(xy 41.511273 -399.799806) (xy 41.518971 -399.818606) (xy 41.519348 -399.828766) (xy 41.519348 -400.11477)
			(xy 41.519545 -400.121643) (xy 41.523149 -400.134906) (xy 41.52646 -400.140932) (xy 41.542834 -400.169276)
			(xy 41.568635 -400.229437) (xy 41.586122 -400.292518) (xy 41.59498 -400.357377) (xy 41.595548 -400.390106)
			(xy 41.594956 -400.422835) (xy 41.586107 -400.487692) (xy 41.568624 -400.550772) (xy 41.542825 -400.610931)
			(xy 41.52646 -400.63928) (xy 41.523157 -400.645311) (xy 41.519543 -400.65857) (xy 41.519348 -400.665442)
			(xy 41.519348 -401.414742) (xy 41.519556 -401.421614) (xy 41.523153 -401.434877) (xy 41.52646 -401.440904)
			(xy 41.542823 -401.469255) (xy 41.568627 -401.529413) (xy 41.586117 -401.592492) (xy 41.594978 -401.657349)
			(xy 41.595548 -401.690078) (xy 41.594988 -401.722808) (xy 41.58613 -401.787666) (xy 41.568638 -401.850746)
			(xy 41.542829 -401.910904) (xy 41.52646 -401.939252) (xy 41.523131 -401.94527) (xy 41.519534 -401.958539)
			(xy 41.519348 -401.965414) (xy 41.519348 -402.251418) (xy 41.518888 -402.261547) (xy 41.511152 -402.280271)
			(xy 41.496858 -402.294627) (xy 41.478167 -402.302444) (xy 41.46804 -402.30298) (xy 40.75176 -402.30298)
			(xy 40.741601 -402.302611) (xy 40.722844 -402.294798) (xy 40.708521 -402.280385) (xy 40.700826 -402.26158)
			(xy 40.700452 -402.251418) (xy 40.700452 -401.965414) (xy 40.700261 -401.958541) (xy 40.696653 -401.945278)
			(xy 40.69334 -401.939252) (xy 40.676959 -401.910911) (xy 40.65116 -401.850749) (xy 40.633675 -401.787667)
			(xy 40.624819 -401.722808) (xy 40.624252 -401.690078) (xy 39.352081 -401.690078) (xy 39.343142 -401.710993)
			(xy 39.32682 -401.739354) (xy 39.323523 -401.745387) (xy 39.319906 -401.758644) (xy 39.319708 -401.765516)
			(xy 39.319708 -402.514816) (xy 39.319893 -402.52169) (xy 39.323506 -402.534953) (xy 39.32682 -402.540978)
			(xy 39.343103 -402.569361) (xy 39.368826 -402.629527) (xy 39.38624 -402.692601) (xy 39.39503 -402.757442)
			(xy 39.395032 -402.790152) (xy 42.8244 -402.790152) (xy 42.824967 -402.757423) (xy 42.833822 -402.692564)
			(xy 42.851312 -402.629484) (xy 42.87712 -402.569326) (xy 42.893488 -402.540978) (xy 42.89681 -402.534957)
			(xy 42.900411 -402.52169) (xy 42.9006 -402.514816) (xy 42.9006 -401.765516) (xy 42.900402 -401.758643)
			(xy 42.896798 -401.74538) (xy 42.893488 -401.739354) (xy 42.877103 -401.711015) (xy 42.851306 -401.650852)
			(xy 42.833822 -401.587769) (xy 42.824967 -401.52291) (xy 42.8244 -401.49018) (xy 42.824979 -401.457451)
			(xy 42.833831 -401.392593) (xy 42.851317 -401.329513) (xy 42.877121 -401.269355) (xy 42.893488 -401.241006)
			(xy 42.8968 -401.23498) (xy 42.900408 -401.221717) (xy 42.9006 -401.214844) (xy 42.9006 -400.92884)
			(xy 42.901049 -400.91872) (xy 42.908784 -400.900017) (xy 42.923091 -400.885702) (xy 42.941788 -400.877955)
			(xy 42.951908 -400.877532) (xy 43.668188 -400.877532) (xy 43.678314 -400.877927) (xy 43.697023 -400.885677)
			(xy 43.711339 -400.9) (xy 43.719079 -400.918714) (xy 43.719496 -400.92884) (xy 43.719496 -401.214844)
			(xy 43.71971 -401.221716) (xy 43.723303 -401.234978) (xy 43.726608 -401.241006) (xy 43.742977 -401.269353)
			(xy 43.768778 -401.329514) (xy 43.786266 -401.392594) (xy 43.795126 -401.457451) (xy 43.795696 -401.49018)
			(xy 43.795144 -401.52291) (xy 43.786284 -401.587769) (xy 43.76879 -401.650849) (xy 43.742978 -401.711006)
			(xy 43.736167 -401.7228) (xy 45.024886 -401.7228) (xy 45.024888 -401.657362) (xy 45.033674 -401.592517)
			(xy 45.051085 -401.529437) (xy 45.076805 -401.469265) (xy 45.093128 -401.440904) (xy 45.096443 -401.43488)
			(xy 45.100048 -401.421616) (xy 45.10024 -401.414742) (xy 45.10024 -400.665442) (xy 45.100027 -400.65857)
			(xy 45.096433 -400.645308) (xy 45.093128 -400.63928) (xy 45.076811 -400.610916) (xy 45.051094 -400.550745)
			(xy 45.033685 -400.487667) (xy 45.024901 -400.422823) (xy 45.024901 -400.357387) (xy 45.033683 -400.292543)
			(xy 45.05109 -400.229465) (xy 45.076807 -400.169293) (xy 45.093128 -400.140932) (xy 45.096433 -400.134903)
			(xy 45.100044 -400.121643) (xy 45.10024 -400.11477) (xy 45.10024 -399.828766) (xy 45.100706 -399.818606)
			(xy 45.108492 -399.799835) (xy 45.122866 -399.785471) (xy 45.141641 -399.777698) (xy 45.151802 -399.777204)
			(xy 45.868082 -399.777204) (xy 45.878234 -399.777747) (xy 45.896997 -399.785509) (xy 45.911361 -399.79986)
			(xy 45.919143 -399.818614) (xy 45.919644 -399.828766) (xy 45.919644 -400.11477) (xy 45.919842 -400.121643)
			(xy 45.923445 -400.134906) (xy 45.926756 -400.140932) (xy 45.943083 -400.16929) (xy 45.968801 -400.229462)
			(xy 45.986209 -400.292541) (xy 45.994992 -400.357387) (xy 45.994991 -400.422824) (xy 45.986207 -400.487669)
			(xy 45.968797 -400.550748) (xy 45.943079 -400.610919) (xy 45.926756 -400.63928) (xy 45.923453 -400.64531)
			(xy 45.919839 -400.65857) (xy 45.919644 -400.665442) (xy 45.919644 -401.414742) (xy 45.919853 -401.421614)
			(xy 45.923449 -401.434877) (xy 45.926756 -401.440904) (xy 45.94306 -401.469275) (xy 45.951996 -401.49018)
			(xy 47.223942 -401.49018) (xy 47.227933 -401.428013) (xy 47.239842 -401.366866) (xy 47.259471 -401.307745)
			(xy 47.2865 -401.251619) (xy 47.320484 -401.19941) (xy 47.360866 -401.151975) (xy 47.406982 -401.110094)
			(xy 47.458074 -401.074454) (xy 47.513305 -401.04564) (xy 47.571767 -401.024126) (xy 47.632501 -401.010264)
			(xy 47.694508 -401.004282) (xy 47.756771 -401.006278) (xy 47.818268 -401.016221) (xy 47.877989 -401.033945)
			(xy 47.934952 -401.059162) (xy 47.988223 -401.091455) (xy 48.036928 -401.130295) (xy 48.080265 -401.175045)
			(xy 48.117525 -401.224969) (xy 48.148094 -401.279248) (xy 48.171472 -401.336991) (xy 48.187273 -401.397249)
			(xy 48.195239 -401.459032) (xy 48.195738 -401.49018) (xy 48.195239 -401.521328) (xy 48.187273 -401.583111)
			(xy 48.171472 -401.643369) (xy 48.148094 -401.701112) (xy 48.117525 -401.755391) (xy 48.080265 -401.805315)
			(xy 48.036928 -401.850065) (xy 47.988223 -401.888905) (xy 47.934952 -401.921198) (xy 47.877989 -401.946415)
			(xy 47.818268 -401.964139) (xy 47.756771 -401.974082) (xy 47.694508 -401.976078) (xy 47.632501 -401.970096)
			(xy 47.571767 -401.956234) (xy 47.513305 -401.93472) (xy 47.458074 -401.905906) (xy 47.406982 -401.870266)
			(xy 47.360866 -401.828385) (xy 47.320484 -401.78095) (xy 47.2865 -401.728741) (xy 47.259471 -401.672615)
			(xy 47.239842 -401.613494) (xy 47.227933 -401.552347) (xy 47.223942 -401.49018) (xy 45.951996 -401.49018)
			(xy 45.968779 -401.529444) (xy 45.98619 -401.592521) (xy 45.994976 -401.657364) (xy 45.994978 -401.722799)
			(xy 45.986197 -401.787642) (xy 45.968792 -401.85072) (xy 45.943077 -401.910891) (xy 45.926756 -401.939252)
			(xy 45.923427 -401.94527) (xy 45.91983 -401.958539) (xy 45.919644 -401.965414) (xy 45.919644 -402.251418)
			(xy 45.919181 -402.261579) (xy 45.911397 -402.280352) (xy 45.897022 -402.294718) (xy 45.878244 -402.302488)
			(xy 45.868082 -402.30298) (xy 45.151802 -402.30298) (xy 45.141647 -402.302465) (xy 45.122881 -402.294695)
			(xy 45.108516 -402.280336) (xy 45.100739 -402.261573) (xy 45.10024 -402.251418) (xy 45.10024 -401.965414)
			(xy 45.100038 -401.958542) (xy 45.096436 -401.945279) (xy 45.093128 -401.939252) (xy 45.076787 -401.910901)
			(xy 45.051072 -401.850727) (xy 45.033667 -401.787646) (xy 45.024886 -401.7228) (xy 43.736167 -401.7228)
			(xy 43.726608 -401.739354) (xy 43.72331 -401.745387) (xy 43.719694 -401.758644) (xy 43.719496 -401.765516)
			(xy 43.719496 -402.514816) (xy 43.719682 -402.52169) (xy 43.723294 -402.534952) (xy 43.726608 -402.540978)
			(xy 43.742966 -402.569332) (xy 43.768769 -402.62949) (xy 43.786261 -402.692568) (xy 43.795124 -402.757423)
			(xy 43.795696 -402.790152) (xy 47.223942 -402.790152) (xy 47.227933 -402.727985) (xy 47.239842 -402.666838)
			(xy 47.259471 -402.607717) (xy 47.2865 -402.551591) (xy 47.320484 -402.499382) (xy 47.360866 -402.451947)
			(xy 47.406982 -402.410066) (xy 47.458074 -402.374426) (xy 47.513305 -402.345612) (xy 47.571767 -402.324098)
			(xy 47.632501 -402.310236) (xy 47.694508 -402.304254) (xy 47.756771 -402.30625) (xy 47.818268 -402.316193)
			(xy 47.877989 -402.333917) (xy 47.934952 -402.359134) (xy 47.988223 -402.391427) (xy 48.036928 -402.430267)
			(xy 48.080265 -402.475017) (xy 48.117525 -402.524941) (xy 48.148094 -402.57922) (xy 48.171472 -402.636963)
			(xy 48.187273 -402.697221) (xy 48.195239 -402.759004) (xy 48.195738 -402.790152) (xy 48.195239 -402.8213)
			(xy 48.187273 -402.883083) (xy 48.171472 -402.943341) (xy 48.148094 -403.001084) (xy 48.117525 -403.055363)
			(xy 48.080265 -403.105287) (xy 48.036928 -403.150037) (xy 47.988223 -403.188877) (xy 47.934952 -403.22117)
			(xy 47.877989 -403.246387) (xy 47.818268 -403.264111) (xy 47.756771 -403.274054) (xy 47.694508 -403.27605)
			(xy 47.632501 -403.270068) (xy 47.571767 -403.256206) (xy 47.513305 -403.234692) (xy 47.458074 -403.205878)
			(xy 47.406982 -403.170238) (xy 47.360866 -403.128357) (xy 47.320484 -403.080922) (xy 47.2865 -403.028713)
			(xy 47.259471 -402.972587) (xy 47.239842 -402.913466) (xy 47.227933 -402.852319) (xy 47.223942 -402.790152)
			(xy 43.795696 -402.790152) (xy 43.795132 -402.822882) (xy 43.786275 -402.88774) (xy 43.768785 -402.95082)
			(xy 43.742977 -403.010978) (xy 43.726608 -403.039326) (xy 43.723285 -403.045346) (xy 43.719684 -403.058613)
			(xy 43.719496 -403.065488) (xy 43.719496 -403.351492) (xy 43.719077 -403.361614) (xy 43.711331 -403.380319)
			(xy 43.697015 -403.394633) (xy 43.67831 -403.402378) (xy 43.668188 -403.4028) (xy 42.951908 -403.4028)
			(xy 42.941786 -403.402377) (xy 42.923083 -403.394632) (xy 42.908768 -403.380317) (xy 42.901023 -403.361614)
			(xy 42.9006 -403.351492) (xy 42.9006 -403.065488) (xy 42.900413 -403.058614) (xy 42.896801 -403.045352)
			(xy 42.893488 -403.039326) (xy 42.877132 -403.010972) (xy 42.851328 -402.950814) (xy 42.833836 -402.887736)
			(xy 42.824972 -402.822881) (xy 42.8244 -402.790152) (xy 39.395032 -402.790152) (xy 39.395035 -402.822876)
			(xy 39.386257 -402.887718) (xy 39.368854 -402.950795) (xy 39.34314 -403.010965) (xy 39.32682 -403.039326)
			(xy 39.323497 -403.045347) (xy 39.319896 -403.058613) (xy 39.319708 -403.065488) (xy 39.319708 -403.351492)
			(xy 39.319272 -403.361645) (xy 39.311481 -403.380395) (xy 39.297088 -403.394719) (xy 39.278301 -403.40242)
			(xy 39.268146 -403.4028) (xy 38.551866 -403.4028) (xy 38.541742 -403.402303) (xy 38.523028 -403.394571)
			(xy 38.508674 -403.380289) (xy 38.500849 -403.361613) (xy 38.500304 -403.351492) (xy 38.500304 -403.065488)
			(xy 38.500116 -403.058614) (xy 38.496505 -403.045352) (xy 38.493192 -403.039326) (xy 38.476831 -403.010987)
			(xy 38.451119 -402.95081) (xy 38.433717 -402.887727) (xy 38.42494 -402.822879) (xy 34.995045 -402.822879)
			(xy 34.995045 -402.822881) (xy 34.98619 -402.88774) (xy 34.968699 -402.95082) (xy 34.942892 -403.010978)
			(xy 34.926524 -403.039326) (xy 34.923202 -403.045347) (xy 34.9196 -403.058613) (xy 34.919412 -403.065488)
			(xy 34.919412 -403.351492) (xy 34.918978 -403.361612) (xy 34.911234 -403.380314) (xy 34.896924 -403.394628)
			(xy 34.878224 -403.402375) (xy 34.868104 -403.4028) (xy 34.151824 -403.4028) (xy 34.141703 -403.402365)
			(xy 34.123 -403.394624) (xy 34.108685 -403.380314) (xy 34.100939 -403.361613) (xy 34.100516 -403.351492)
			(xy 34.100516 -403.065488) (xy 34.100327 -403.058615) (xy 34.096716 -403.045352) (xy 34.093404 -403.039326)
			(xy 34.077049 -403.010971) (xy 34.051245 -402.950814) (xy 34.033752 -402.887736) (xy 34.024888 -402.82288)
			(xy 34.024316 -402.790152) (xy 30.594946 -402.790152) (xy 30.594949 -402.822876) (xy 30.586171 -402.887718)
			(xy 30.568768 -402.950795) (xy 30.543056 -403.010965) (xy 30.526736 -403.039326) (xy 30.523415 -403.045348)
			(xy 30.519813 -403.058614) (xy 30.519624 -403.065488) (xy 30.519624 -403.351492) (xy 30.519172 -403.361643)
			(xy 30.511384 -403.38039) (xy 30.496997 -403.394713) (xy 30.478214 -403.402417) (xy 30.468062 -403.4028)
			(xy 29.751782 -403.4028) (xy 29.741659 -403.40229) (xy 29.722945 -403.394563) (xy 29.708591 -403.380285)
			(xy 29.700765 -403.361612) (xy 29.70022 -403.351492) (xy 29.70022 -403.065488) (xy 29.70003 -403.058615)
			(xy 29.69642 -403.045352) (xy 29.693108 -403.039326) (xy 29.676746 -403.010987) (xy 29.651034 -402.95081)
			(xy 29.633631 -402.887727) (xy 29.624853 -402.822879) (xy 0.529844 -402.822879) (xy 0.529844 -404.501858)
			(xy 17.351246 -404.501858) (xy 17.355317 -404.446236) (xy 17.367443 -404.391799) (xy 17.387366 -404.339708)
			(xy 17.414662 -404.291073) (xy 17.448748 -404.24693) (xy 17.488897 -404.208221) (xy 17.534255 -404.17577)
			(xy 17.583855 -404.150269) (xy 17.636639 -404.132262) (xy 17.691482 -404.122132) (xy 17.747216 -404.120095)
			(xy 17.802653 -404.126195) (xy 17.85661 -404.140301) (xy 17.907939 -404.162113) (xy 17.955545 -404.191167)
			(xy 17.998413 -404.226842) (xy 18.03563 -404.268379) (xy 18.066403 -404.314892) (xy 18.090075 -404.365389)
			(xy 18.106143 -404.418796) (xy 18.114263 -404.473972) (xy 18.114772 -404.501858) (xy 18.114263 -404.529744)
			(xy 18.106143 -404.58492) (xy 18.094299 -404.624286) (xy 18.644868 -404.624286) (xy 18.648939 -404.568664)
			(xy 18.661065 -404.514227) (xy 18.680988 -404.462136) (xy 18.708284 -404.413501) (xy 18.74237 -404.369358)
			(xy 18.782519 -404.330649) (xy 18.827877 -404.298198) (xy 18.877477 -404.272697) (xy 18.930261 -404.25469)
			(xy 18.985104 -404.24456) (xy 19.040838 -404.242523) (xy 19.096275 -404.248623) (xy 19.150232 -404.262729)
			(xy 19.201561 -404.284541) (xy 19.249167 -404.313595) (xy 19.292035 -404.34927) (xy 19.329252 -404.390807)
			(xy 19.360025 -404.43732) (xy 19.383697 -404.487817) (xy 19.399765 -404.541224) (xy 19.407885 -404.5964)
			(xy 19.408394 -404.624286) (xy 19.407885 -404.652172) (xy 19.399765 -404.707348) (xy 19.383697 -404.760755)
			(xy 19.360025 -404.811252) (xy 19.329252 -404.857765) (xy 19.292035 -404.899302) (xy 19.249167 -404.934977)
			(xy 19.201561 -404.964031) (xy 19.150232 -404.985843) (xy 19.096275 -404.999949) (xy 19.040838 -405.006049)
			(xy 18.985104 -405.004012) (xy 18.930261 -404.993882) (xy 18.877477 -404.975875) (xy 18.827877 -404.950374)
			(xy 18.782519 -404.917923) (xy 18.74237 -404.879214) (xy 18.708284 -404.835071) (xy 18.680988 -404.786436)
			(xy 18.661065 -404.734345) (xy 18.648939 -404.679908) (xy 18.644868 -404.624286) (xy 18.094299 -404.624286)
			(xy 18.090075 -404.638327) (xy 18.066403 -404.688824) (xy 18.03563 -404.735337) (xy 17.998413 -404.776874)
			(xy 17.955545 -404.812549) (xy 17.907939 -404.841603) (xy 17.85661 -404.863415) (xy 17.802653 -404.877521)
			(xy 17.747216 -404.883621) (xy 17.691482 -404.881584) (xy 17.636639 -404.871454) (xy 17.583855 -404.853447)
			(xy 17.534255 -404.827946) (xy 17.488897 -404.795495) (xy 17.448748 -404.756786) (xy 17.414662 -404.712643)
			(xy 17.387366 -404.664008) (xy 17.367443 -404.611917) (xy 17.355317 -404.55748) (xy 17.351246 -404.501858)
			(xy 0.529844 -404.501858) (xy 0.529844 -405.589994) (xy 27.42438 -405.589994) (xy 27.424968 -405.557265)
			(xy 27.433818 -405.492408) (xy 27.451302 -405.429328) (xy 27.477103 -405.369169) (xy 27.493468 -405.34082)
			(xy 27.496773 -405.334791) (xy 27.500385 -405.321531) (xy 27.50058 -405.314658) (xy 27.50058 -404.565358)
			(xy 27.500368 -404.558486) (xy 27.496774 -404.545223) (xy 27.493468 -404.539196) (xy 27.477107 -404.510844)
			(xy 27.451303 -404.450686) (xy 27.433811 -404.387607) (xy 27.42495 -404.322751) (xy 27.42438 -404.290022)
			(xy 27.424936 -404.257292) (xy 27.433795 -404.192434) (xy 27.451288 -404.129353) (xy 27.477098 -404.069196)
			(xy 27.493468 -404.040848) (xy 27.496799 -404.034831) (xy 27.500394 -404.021561) (xy 27.50058 -404.014686)
			(xy 27.50058 -403.728682) (xy 27.501013 -403.718549) (xy 27.508754 -403.69982) (xy 27.523057 -403.685463)
			(xy 27.541757 -403.677651) (xy 27.551888 -403.67712) (xy 28.268168 -403.67712) (xy 28.278323 -403.677548)
			(xy 28.297078 -403.685337) (xy 28.311404 -403.699732) (xy 28.319101 -403.718525) (xy 28.319476 -403.728682)
			(xy 28.319476 -404.014686) (xy 28.319676 -404.021559) (xy 28.323279 -404.034821) (xy 28.326588 -404.040848)
			(xy 28.342972 -404.069187) (xy 28.368769 -404.12935) (xy 28.386254 -404.192433) (xy 28.395109 -404.257292)
			(xy 28.395676 -404.290022) (xy 28.395101 -404.322751) (xy 28.386248 -404.387609) (xy 28.368761 -404.45069)
			(xy 28.342956 -404.510848) (xy 28.326588 -404.539196) (xy 28.323274 -404.545221) (xy 28.319668 -404.558484)
			(xy 28.319476 -404.565358) (xy 28.319476 -405.314658) (xy 28.319687 -405.32153) (xy 28.323282 -405.334793)
			(xy 28.326588 -405.34082) (xy 28.34296 -405.369166) (xy 28.368761 -405.429326) (xy 28.386249 -405.492407)
			(xy 28.395107 -405.557265) (xy 28.395676 -405.589994) (xy 28.395133 -405.622724) (xy 28.386271 -405.687584)
			(xy 28.368774 -405.750664) (xy 28.34296 -405.810821) (xy 28.326588 -405.839168) (xy 28.323284 -405.845198)
			(xy 28.319672 -405.858458) (xy 28.319476 -405.86533) (xy 28.319476 -406.151334) (xy 28.319002 -406.161461)
			(xy 28.311266 -406.18018) (xy 28.296976 -406.194534) (xy 28.278293 -406.202355) (xy 28.268168 -406.202896)
			(xy 27.551888 -406.202896) (xy 27.541733 -406.202488) (xy 27.522979 -406.194688) (xy 27.508656 -406.180287)
			(xy 27.500957 -406.161492) (xy 27.50058 -406.151334) (xy 27.50058 -405.86533) (xy 27.500379 -405.858457)
			(xy 27.496777 -405.845195) (xy 27.493468 -405.839168) (xy 27.477096 -405.810822) (xy 27.451294 -405.750662)
			(xy 27.433806 -405.687581) (xy 27.424948 -405.622723) (xy 27.42438 -405.589994) (xy 0.529844 -405.589994)
			(xy 0.529844 -406.722792) (xy 29.624863 -406.722792) (xy 29.624866 -406.657353) (xy 29.633653 -406.592507)
			(xy 29.651064 -406.529428) (xy 29.676785 -406.469256) (xy 29.693108 -406.440894) (xy 29.696425 -406.434871)
			(xy 29.700029 -406.421606) (xy 29.70022 -406.414732) (xy 29.70022 -405.665432) (xy 29.700013 -405.65856)
			(xy 29.696415 -405.645297) (xy 29.693108 -405.63927) (xy 29.676783 -405.61091) (xy 29.651068 -405.550738)
			(xy 29.633661 -405.487659) (xy 29.624879 -405.422815) (xy 29.624879 -405.357378) (xy 29.633662 -405.292534)
			(xy 29.65107 -405.229455) (xy 29.676786 -405.169284) (xy 29.693108 -405.140922) (xy 29.696415 -405.134894)
			(xy 29.700026 -405.121633) (xy 29.70022 -405.11476) (xy 29.70022 -404.828756) (xy 29.700586 -404.818597)
			(xy 29.7084 -404.799839) (xy 29.722814 -404.785517) (xy 29.74162 -404.777822) (xy 29.751782 -404.777448)
			(xy 30.468062 -404.777448) (xy 30.478187 -404.777958) (xy 30.496909 -404.785675) (xy 30.511267 -404.799954)
			(xy 30.519086 -404.818634) (xy 30.519624 -404.828756) (xy 30.519624 -405.11476) (xy 30.519828 -405.121632)
			(xy 30.523428 -405.134895) (xy 30.526736 -405.140922) (xy 30.543056 -405.169285) (xy 30.568775 -405.229455)
			(xy 30.586184 -405.292534) (xy 30.594969 -405.357378) (xy 30.594969 -405.422815) (xy 30.586186 -405.48766)
			(xy 30.568777 -405.550738) (xy 30.543059 -405.610909) (xy 30.536265 -405.622714) (xy 31.825019 -405.622714)
			(xy 31.825019 -405.557276) (xy 31.833804 -405.492431) (xy 31.851214 -405.429352) (xy 31.876933 -405.369181)
			(xy 31.893256 -405.34082) (xy 31.89656 -405.33479) (xy 31.900173 -405.32153) (xy 31.900368 -405.314658)
			(xy 31.900368 -404.565358) (xy 31.900158 -404.558486) (xy 31.896562 -404.545223) (xy 31.893256 -404.539196)
			(xy 31.876952 -404.510825) (xy 31.851232 -404.450656) (xy 31.833821 -404.387579) (xy 31.825035 -404.322737)
			(xy 31.825032 -404.257301) (xy 31.833813 -404.192458) (xy 31.851219 -404.12938) (xy 31.876935 -404.069209)
			(xy 31.893256 -404.040848) (xy 31.896586 -404.034831) (xy 31.900182 -404.021561) (xy 31.900368 -404.014686)
			(xy 31.900368 -403.728682) (xy 31.90075 -403.718506) (xy 31.908547 -403.699705) (xy 31.922945 -403.68532)
			(xy 31.941753 -403.677541) (xy 31.95193 -403.67712) (xy 32.66821 -403.67712) (xy 32.678366 -403.677625)
			(xy 32.697132 -403.685399) (xy 32.711496 -403.699761) (xy 32.719273 -403.718526) (xy 32.719772 -403.728682)
			(xy 32.719772 -404.014686) (xy 32.719973 -404.021559) (xy 32.723575 -404.034821) (xy 32.726884 -404.040848)
			(xy 32.743224 -404.069199) (xy 32.768939 -404.129373) (xy 32.786344 -404.192454) (xy 32.795125 -404.2573)
			(xy 32.795122 -404.322738) (xy 32.786336 -404.387583) (xy 32.768926 -404.450663) (xy 32.743207 -404.510834)
			(xy 32.726884 -404.539196) (xy 32.72357 -404.545221) (xy 32.719964 -404.558484) (xy 32.719772 -404.565358)
			(xy 32.719772 -405.314658) (xy 32.719983 -405.32153) (xy 32.723579 -405.334792) (xy 32.726884 -405.34082)
			(xy 32.7432 -405.369184) (xy 32.768917 -405.429355) (xy 32.786325 -405.492433) (xy 32.795109 -405.557277)
			(xy 32.79511 -405.622713) (xy 32.786327 -405.687557) (xy 32.768921 -405.750635) (xy 32.743205 -405.810807)
			(xy 32.726884 -405.839168) (xy 32.72358 -405.845198) (xy 32.719968 -405.858458) (xy 32.719772 -405.86533)
			(xy 32.719772 -406.151334) (xy 32.719295 -406.161493) (xy 32.711511 -406.180261) (xy 32.697141 -406.194624)
			(xy 32.678369 -406.202399) (xy 32.66821 -406.202896) (xy 31.95193 -406.202896) (xy 31.941778 -406.202343)
			(xy 31.923016 -406.194585) (xy 31.908651 -406.180237) (xy 31.900869 -406.161485) (xy 31.900368 -406.151334)
			(xy 31.900368 -405.86533) (xy 31.900169 -405.858457) (xy 31.896566 -405.845194) (xy 31.893256 -405.839168)
			(xy 31.876928 -405.81081) (xy 31.85121 -405.750638) (xy 31.833802 -405.687559) (xy 31.825019 -405.622714)
			(xy 30.536265 -405.622714) (xy 30.526736 -405.63927) (xy 30.523435 -405.645301) (xy 30.51982 -405.65856)
			(xy 30.519624 -405.665432) (xy 30.519624 -406.414732) (xy 30.519801 -406.421606) (xy 30.523419 -406.434869)
			(xy 30.526736 -406.440894) (xy 30.543032 -406.46927) (xy 30.568753 -406.529437) (xy 30.586165 -406.592513)
			(xy 30.594953 -406.657355) (xy 30.594954 -406.690068) (xy 34.024316 -406.690068) (xy 34.024888 -406.657339)
			(xy 34.033741 -406.592481) (xy 34.05123 -406.5294) (xy 34.077036 -406.469242) (xy 34.093404 -406.440894)
			(xy 34.096721 -406.434871) (xy 34.100325 -406.421606) (xy 34.100516 -406.414732) (xy 34.100516 -405.665432)
			(xy 34.10031 -405.65856) (xy 34.096711 -405.645297) (xy 34.093404 -405.63927) (xy 34.077027 -405.610927)
			(xy 34.051228 -405.550765) (xy 34.033741 -405.487684) (xy 34.024884 -405.422826) (xy 34.024316 -405.390096)
			(xy 34.024856 -405.357366) (xy 34.033719 -405.292506) (xy 34.051217 -405.229426) (xy 34.077032 -405.169269)
			(xy 34.093404 -405.140922) (xy 34.096711 -405.134894) (xy 34.100322 -405.121633) (xy 34.100516 -405.11476)
			(xy 34.100516 -404.828756) (xy 34.10095 -404.818642) (xy 34.108705 -404.79996) (xy 34.123017 -404.785666)
			(xy 34.14171 -404.777936) (xy 34.151824 -404.777448) (xy 34.868104 -404.777448) (xy 34.878207 -404.777981)
			(xy 34.896875 -404.78571) (xy 34.911168 -404.799992) (xy 34.918911 -404.818654) (xy 34.919412 -404.828756)
			(xy 34.919412 -405.11476) (xy 34.919618 -405.121632) (xy 34.923217 -405.134895) (xy 34.926524 -405.140922)
			(xy 34.942901 -405.169265) (xy 34.968699 -405.229427) (xy 34.986186 -405.292508) (xy 34.995043 -405.357367)
			(xy 34.995612 -405.390096) (xy 34.995065 -405.422826) (xy 34.986204 -405.487685) (xy 34.968708 -405.550765)
			(xy 34.951875 -405.589994) (xy 36.224464 -405.589994) (xy 36.225055 -405.557265) (xy 36.233904 -405.492408)
			(xy 36.251387 -405.429328) (xy 36.277187 -405.369169) (xy 36.293552 -405.34082) (xy 36.296856 -405.33479)
			(xy 36.300469 -405.32153) (xy 36.300664 -405.314658) (xy 36.300664 -404.565358) (xy 36.300454 -404.558486)
			(xy 36.296859 -404.545223) (xy 36.293552 -404.539196) (xy 36.27719 -404.510845) (xy 36.251386 -404.450686)
			(xy 36.233895 -404.387607) (xy 36.225034 -404.322751) (xy 36.224464 -404.290022) (xy 36.225022 -404.257292)
			(xy 36.233881 -404.192434) (xy 36.251373 -404.129354) (xy 36.277183 -404.069196) (xy 36.293552 -404.040848)
			(xy 36.296881 -404.03483) (xy 36.300478 -404.021561) (xy 36.300664 -404.014686) (xy 36.300664 -403.728682)
			(xy 36.301112 -403.718551) (xy 36.30885 -403.699825) (xy 36.323149 -403.685468) (xy 36.341843 -403.677654)
			(xy 36.351972 -403.67712) (xy 37.068252 -403.67712) (xy 37.078405 -403.677561) (xy 37.097161 -403.685345)
			(xy 37.111486 -403.699736) (xy 37.119184 -403.718527) (xy 37.11956 -403.728682) (xy 37.11956 -404.014686)
			(xy 37.119762 -404.021558) (xy 37.123364 -404.034821) (xy 37.126672 -404.040848) (xy 37.143054 -404.069188)
			(xy 37.168853 -404.129351) (xy 37.186338 -404.192433) (xy 37.195193 -404.257292) (xy 37.19576 -404.290022)
			(xy 37.195174 -404.322751) (xy 37.186323 -404.387608) (xy 37.168838 -404.450688) (xy 37.143037 -404.510847)
			(xy 37.126672 -404.539196) (xy 37.123357 -404.54522) (xy 37.119752 -404.558484) (xy 37.11956 -404.565358)
			(xy 37.11956 -405.314658) (xy 37.119773 -405.32153) (xy 37.123367 -405.334792) (xy 37.126672 -405.34082)
			(xy 37.143043 -405.369166) (xy 37.168844 -405.429327) (xy 37.186332 -405.492407) (xy 37.195191 -405.557265)
			(xy 37.19576 -405.589994) (xy 37.195206 -405.622724) (xy 37.186345 -405.687582) (xy 37.168852 -405.750662)
			(xy 37.143042 -405.81082) (xy 37.126672 -405.839168) (xy 37.123367 -405.845197) (xy 37.119756 -405.858457)
			(xy 37.11956 -405.86533) (xy 37.11956 -406.151334) (xy 37.119101 -406.161463) (xy 37.111362 -406.180185)
			(xy 37.097068 -406.19454) (xy 37.078379 -406.202358) (xy 37.068252 -406.202896) (xy 36.351972 -406.202896)
			(xy 36.341816 -406.202501) (xy 36.323062 -406.194696) (xy 36.308739 -406.180291) (xy 36.301041 -406.161493)
			(xy 36.300664 -406.151334) (xy 36.300664 -405.86533) (xy 36.300465 -405.858457) (xy 36.296862 -405.845194)
			(xy 36.293552 -405.839168) (xy 36.277179 -405.810823) (xy 36.251378 -405.750662) (xy 36.23389 -405.687581)
			(xy 36.225032 -405.622723) (xy 36.224464 -405.589994) (xy 34.951875 -405.589994) (xy 34.942895 -405.610923)
			(xy 34.926524 -405.63927) (xy 34.923222 -405.645301) (xy 34.919608 -405.65856) (xy 34.919412 -405.665432)
			(xy 34.919412 -406.414732) (xy 34.91959 -406.421606) (xy 34.923208 -406.434869) (xy 34.926524 -406.440894)
			(xy 34.942889 -406.469243) (xy 34.968691 -406.529403) (xy 34.98618 -406.592482) (xy 34.995041 -406.657339)
			(xy 34.995612 -406.690068) (xy 34.995053 -406.722792) (xy 38.424949 -406.722792) (xy 38.424953 -406.657353)
			(xy 38.433739 -406.592508) (xy 38.45115 -406.529428) (xy 38.476869 -406.469256) (xy 38.493192 -406.440894)
			(xy 38.496508 -406.43487) (xy 38.500113 -406.421606) (xy 38.500304 -406.414732) (xy 38.500304 -405.665432)
			(xy 38.500099 -405.65856) (xy 38.496499 -405.645297) (xy 38.493192 -405.63927) (xy 38.476868 -405.61091)
			(xy 38.451153 -405.550738) (xy 38.433747 -405.487659) (xy 38.424965 -405.422815) (xy 38.424965 -405.357378)
			(xy 38.433748 -405.292534) (xy 38.451155 -405.229455) (xy 38.476871 -405.169284) (xy 38.493192 -405.140922)
			(xy 38.496498 -405.134893) (xy 38.500109 -405.121633) (xy 38.500304 -405.11476) (xy 38.500304 -404.828756)
			(xy 38.500686 -404.818599) (xy 38.508497 -404.799844) (xy 38.522905 -404.785523) (xy 38.541706 -404.777825)
			(xy 38.551866 -404.777448) (xy 39.268146 -404.777448) (xy 39.278277 -404.777889) (xy 39.297 -404.785634)
			(xy 39.311355 -404.799934) (xy 39.319171 -404.818627) (xy 39.319708 -404.828756) (xy 39.319708 -405.11476)
			(xy 39.319914 -405.121632) (xy 39.323513 -405.134895) (xy 39.32682 -405.140922) (xy 39.34314 -405.169285)
			(xy 39.36886 -405.229455) (xy 39.38627 -405.292533) (xy 39.395055 -405.357378) (xy 39.395055 -405.422815)
			(xy 39.386272 -405.48766) (xy 39.368862 -405.550738) (xy 39.352083 -405.589994) (xy 40.624252 -405.589994)
			(xy 40.624844 -405.557265) (xy 40.633693 -405.492408) (xy 40.651176 -405.429328) (xy 40.676975 -405.369169)
			(xy 40.69334 -405.34082) (xy 40.696643 -405.334789) (xy 40.700257 -405.32153) (xy 40.700452 -405.314658)
			(xy 40.700452 -404.565358) (xy 40.700244 -404.558486) (xy 40.696647 -404.545223) (xy 40.69334 -404.539196)
			(xy 40.676977 -404.510845) (xy 40.651173 -404.450687) (xy 40.633683 -404.387608) (xy 40.624822 -404.322751)
			(xy 40.624252 -404.290022) (xy 40.624812 -404.257292) (xy 40.63367 -404.192434) (xy 40.651162 -404.129354)
			(xy 40.676971 -404.069196) (xy 40.69334 -404.040848) (xy 40.696669 -404.03483) (xy 40.700266 -404.021561)
			(xy 40.700452 -404.014686) (xy 40.700452 -403.728682) (xy 40.700912 -403.718553) (xy 40.708648 -403.699829)
			(xy 40.722942 -403.685473) (xy 40.741633 -403.677656) (xy 40.75176 -403.67712) (xy 41.46804 -403.67712)
			(xy 41.478199 -403.677489) (xy 41.496956 -403.685302) (xy 41.511279 -403.699715) (xy 41.518974 -403.71852)
			(xy 41.519348 -403.728682) (xy 41.519348 -404.014686) (xy 41.519539 -404.021559) (xy 41.523147 -404.034822)
			(xy 41.52646 -404.040848) (xy 41.542841 -404.069189) (xy 41.56864 -404.129351) (xy 41.586125 -404.192433)
			(xy 41.594981 -404.257292) (xy 41.595548 -404.290022) (xy 45.023794 -404.290022) (xy 45.027785 -404.227855)
			(xy 45.039694 -404.166708) (xy 45.059323 -404.107587) (xy 45.086352 -404.051461) (xy 45.120336 -403.999252)
			(xy 45.160718 -403.951817) (xy 45.206834 -403.909936) (xy 45.257926 -403.874296) (xy 45.313157 -403.845482)
			(xy 45.371619 -403.823968) (xy 45.432353 -403.810106) (xy 45.49436 -403.804124) (xy 45.556623 -403.80612)
			(xy 45.61812 -403.816063) (xy 45.677841 -403.833787) (xy 45.734804 -403.859004) (xy 45.788075 -403.891297)
			(xy 45.83678 -403.930137) (xy 45.880117 -403.974887) (xy 45.917377 -404.024811) (xy 45.947946 -404.07909)
			(xy 45.971324 -404.136833) (xy 45.987125 -404.197091) (xy 45.995091 -404.258874) (xy 45.99559 -404.290022)
			(xy 45.995091 -404.32117) (xy 45.987125 -404.382953) (xy 45.971324 -404.443211) (xy 45.947946 -404.500954)
			(xy 45.917377 -404.555233) (xy 45.880117 -404.605157) (xy 45.83678 -404.649907) (xy 45.788075 -404.688747)
			(xy 45.734804 -404.72104) (xy 45.677841 -404.746257) (xy 45.61812 -404.763981) (xy 45.556623 -404.773924)
			(xy 45.49436 -404.77592) (xy 45.432353 -404.769938) (xy 45.371619 -404.756076) (xy 45.313157 -404.734562)
			(xy 45.257926 -404.705748) (xy 45.206834 -404.670108) (xy 45.160718 -404.628227) (xy 45.120336 -404.580792)
			(xy 45.086352 -404.528583) (xy 45.059323 -404.472457) (xy 45.039694 -404.413336) (xy 45.027785 -404.352189)
			(xy 45.023794 -404.290022) (xy 41.595548 -404.290022) (xy 41.594963 -404.322751) (xy 41.586112 -404.387608)
			(xy 41.568627 -404.450688) (xy 41.542826 -404.510847) (xy 41.52646 -404.539196) (xy 41.523151 -404.545224)
			(xy 41.519541 -404.558485) (xy 41.519348 -404.565358) (xy 41.519348 -405.314658) (xy 41.51955 -405.321531)
			(xy 41.523151 -405.334794) (xy 41.52646 -405.34082) (xy 41.54283 -405.369167) (xy 41.568631 -405.429327)
			(xy 41.58612 -405.492407) (xy 41.594979 -405.557265) (xy 41.595548 -405.589994) (xy 41.594996 -405.622724)
			(xy 41.586135 -405.687582) (xy 41.568641 -405.750662) (xy 41.54283 -405.81082) (xy 41.52646 -405.839168)
			(xy 41.523161 -405.845201) (xy 41.519545 -405.858458) (xy 41.519348 -405.86533) (xy 41.519348 -406.151334)
			(xy 41.518901 -406.161464) (xy 41.51116 -406.180189) (xy 41.496861 -406.194544) (xy 41.478168 -406.20236)
			(xy 41.46804 -406.202896) (xy 40.75176 -406.202896) (xy 40.741603 -406.202511) (xy 40.722849 -406.194701)
			(xy 40.708527 -406.180294) (xy 40.700829 -406.161494) (xy 40.700452 -406.151334) (xy 40.700452 -405.86533)
			(xy 40.700255 -405.858457) (xy 40.696651 -405.845194) (xy 40.69334 -405.839168) (xy 40.676966 -405.810824)
			(xy 40.651165 -405.750663) (xy 40.633678 -405.687582) (xy 40.62482 -405.622723) (xy 40.624252 -405.589994)
			(xy 39.352083 -405.589994) (xy 39.343143 -405.610909) (xy 39.32682 -405.63927) (xy 39.323517 -405.645301)
			(xy 39.319904 -405.65856) (xy 39.319708 -405.665432) (xy 39.319708 -406.414732) (xy 39.319887 -406.421606)
			(xy 39.323504 -406.434869) (xy 39.32682 -406.440894) (xy 39.343116 -406.46927) (xy 39.368839 -406.529437)
			(xy 39.386251 -406.592513) (xy 39.395039 -406.657355) (xy 39.395041 -406.690068) (xy 42.8244 -406.690068)
			(xy 42.824974 -406.657339) (xy 42.833827 -406.592481) (xy 42.851315 -406.529401) (xy 42.877121 -406.469242)
			(xy 42.893488 -406.440894) (xy 42.896804 -406.43487) (xy 42.900409 -406.421606) (xy 42.9006 -406.414732)
			(xy 42.9006 -405.665432) (xy 42.900396 -405.65856) (xy 42.896796 -405.645297) (xy 42.893488 -405.63927)
			(xy 42.877109 -405.610928) (xy 42.851311 -405.550766) (xy 42.833825 -405.487684) (xy 42.824968 -405.422826)
			(xy 42.8244 -405.390096) (xy 42.824941 -405.357366) (xy 42.833804 -405.292506) (xy 42.851302 -405.229426)
			(xy 42.877116 -405.169269) (xy 42.893488 -405.140922) (xy 42.896794 -405.134893) (xy 42.900405 -405.121633)
			(xy 42.9006 -405.11476) (xy 42.9006 -404.828756) (xy 42.901049 -404.818644) (xy 42.908801 -404.799965)
			(xy 42.923109 -404.785672) (xy 42.941796 -404.777939) (xy 42.951908 -404.777448) (xy 43.668188 -404.777448)
			(xy 43.67829 -404.777994) (xy 43.696958 -404.785718) (xy 43.711251 -404.799995) (xy 43.718995 -404.818655)
			(xy 43.719496 -404.828756) (xy 43.719496 -405.11476) (xy 43.719704 -405.121632) (xy 43.723301 -405.134895)
			(xy 43.726608 -405.140922) (xy 43.742983 -405.169266) (xy 43.768782 -405.229427) (xy 43.786269 -405.292509)
			(xy 43.795127 -405.357367) (xy 43.795696 -405.390096) (xy 43.795152 -405.422826) (xy 43.78629 -405.487685)
			(xy 43.768793 -405.550766) (xy 43.751961 -405.589994) (xy 45.023794 -405.589994) (xy 45.027785 -405.527827)
			(xy 45.039694 -405.46668) (xy 45.059323 -405.407559) (xy 45.086352 -405.351433) (xy 45.120336 -405.299224)
			(xy 45.160718 -405.251789) (xy 45.206834 -405.209908) (xy 45.257926 -405.174268) (xy 45.313157 -405.145454)
			(xy 45.371619 -405.12394) (xy 45.432353 -405.110078) (xy 45.49436 -405.104096) (xy 45.556623 -405.106092)
			(xy 45.61812 -405.116035) (xy 45.677841 -405.133759) (xy 45.734804 -405.158976) (xy 45.788075 -405.191269)
			(xy 45.83678 -405.230109) (xy 45.880117 -405.274859) (xy 45.917377 -405.324783) (xy 45.947946 -405.379062)
			(xy 45.971324 -405.436805) (xy 45.987125 -405.497063) (xy 45.995091 -405.558846) (xy 45.99559 -405.589994)
			(xy 45.995091 -405.621142) (xy 45.987125 -405.682925) (xy 45.971324 -405.743183) (xy 45.947946 -405.800926)
			(xy 45.917377 -405.855205) (xy 45.880117 -405.905129) (xy 45.83678 -405.949879) (xy 45.788075 -405.988719)
			(xy 45.734804 -406.021012) (xy 45.677841 -406.046229) (xy 45.61812 -406.063953) (xy 45.556623 -406.073896)
			(xy 45.49436 -406.075892) (xy 45.432353 -406.06991) (xy 45.371619 -406.056048) (xy 45.313157 -406.034534)
			(xy 45.257926 -406.00572) (xy 45.206834 -405.97008) (xy 45.160718 -405.928199) (xy 45.120336 -405.880764)
			(xy 45.086352 -405.828555) (xy 45.059323 -405.772429) (xy 45.039694 -405.713308) (xy 45.027785 -405.652161)
			(xy 45.023794 -405.589994) (xy 43.751961 -405.589994) (xy 43.74298 -405.610923) (xy 43.726608 -405.63927)
			(xy 43.723304 -405.6453) (xy 43.719692 -405.65856) (xy 43.719496 -405.665432) (xy 43.719496 -406.414732)
			(xy 43.719676 -406.421606) (xy 43.723292 -406.434869) (xy 43.726608 -406.440894) (xy 43.742972 -406.469244)
			(xy 43.768774 -406.529403) (xy 43.786264 -406.592483) (xy 43.795125 -406.657339) (xy 43.795696 -406.690068)
			(xy 43.795139 -406.722792) (xy 47.225021 -406.722792) (xy 47.225025 -406.657353) (xy 47.233813 -406.592506)
			(xy 47.251227 -406.529426) (xy 47.27695 -406.469255) (xy 47.293276 -406.440894) (xy 47.296591 -406.43487)
			(xy 47.300197 -406.421606) (xy 47.300388 -406.414732) (xy 47.300388 -405.665432) (xy 47.300185 -405.65856)
			(xy 47.296584 -405.645297) (xy 47.293276 -405.63927) (xy 47.276949 -405.610911) (xy 47.25123 -405.55074)
			(xy 47.233821 -405.487661) (xy 47.225037 -405.422815) (xy 47.225038 -405.357378) (xy 47.233822 -405.292533)
			(xy 47.251232 -405.229454) (xy 47.276952 -405.169283) (xy 47.293276 -405.140922) (xy 47.296581 -405.134893)
			(xy 47.300193 -405.121633) (xy 47.300388 -405.11476) (xy 47.300388 -404.828756) (xy 47.300785 -404.818601)
			(xy 47.308593 -404.79985) (xy 47.322997 -404.785528) (xy 47.341792 -404.777828) (xy 47.35195 -404.777448)
			(xy 48.06823 -404.777448) (xy 48.07836 -404.777902) (xy 48.097083 -404.785641) (xy 48.111439 -404.799937)
			(xy 48.119255 -404.818629) (xy 48.119792 -404.828756) (xy 48.119792 -405.11476) (xy 48.12 -405.121632)
			(xy 48.123598 -405.134895) (xy 48.126904 -405.140922) (xy 48.143222 -405.169286) (xy 48.168937 -405.229457)
			(xy 48.186344 -405.292535) (xy 48.195127 -405.357379) (xy 48.195128 -405.422815) (xy 48.186345 -405.487658)
			(xy 48.168939 -405.550737) (xy 48.143225 -405.610908) (xy 48.126904 -405.63927) (xy 48.1236 -405.6453)
			(xy 48.119988 -405.65856) (xy 48.119792 -405.665432) (xy 48.119792 -406.414732) (xy 48.119973 -406.421606)
			(xy 48.123589 -406.434869) (xy 48.126904 -406.440894) (xy 48.143198 -406.469271) (xy 48.168916 -406.529439)
			(xy 48.186325 -406.592514) (xy 48.195111 -406.657356) (xy 48.195115 -406.72279) (xy 48.186336 -406.787632)
			(xy 48.168934 -406.850709) (xy 48.143223 -406.91088) (xy 48.126904 -406.939242) (xy 48.123575 -406.945259)
			(xy 48.119978 -406.958529) (xy 48.119792 -406.965404) (xy 48.119792 -407.251408) (xy 48.119385 -407.261564)
			(xy 48.111585 -407.280318) (xy 48.097184 -407.294641) (xy 48.078388 -407.302339) (xy 48.06823 -407.302716)
			(xy 47.35195 -407.302716) (xy 47.341821 -407.302231) (xy 47.323093 -407.294512) (xy 47.308733 -407.280224)
			(xy 47.30092 -407.261534) (xy 47.300388 -407.251408) (xy 47.300388 -406.965404) (xy 47.300196 -406.958531)
			(xy 47.296588 -406.945268) (xy 47.293276 -406.939242) (xy 47.276926 -406.910896) (xy 47.251208 -406.850722)
			(xy 47.233802 -406.78764) (xy 47.225021 -406.722792) (xy 43.795139 -406.722792) (xy 43.795139 -406.722798)
			(xy 43.78628 -406.787656) (xy 43.768788 -406.850737) (xy 43.742978 -406.910894) (xy 43.726608 -406.939242)
			(xy 43.723279 -406.94526) (xy 43.719682 -406.958529) (xy 43.719496 -406.965404) (xy 43.719496 -407.251408)
			(xy 43.71909 -407.261531) (xy 43.711339 -407.280236) (xy 43.697019 -407.29455) (xy 43.678312 -407.302294)
			(xy 43.668188 -407.302716) (xy 42.951908 -407.302716) (xy 42.941802 -407.302209) (xy 42.923127 -407.294477)
			(xy 42.908832 -407.280187) (xy 42.901094 -407.261514) (xy 42.9006 -407.251408) (xy 42.9006 -406.965404)
			(xy 42.900407 -406.958531) (xy 42.8968 -406.945268) (xy 42.893488 -406.939242) (xy 42.877138 -406.910884)
			(xy 42.851333 -406.850728) (xy 42.833839 -406.787651) (xy 42.824973 -406.722796) (xy 42.8244 -406.690068)
			(xy 39.395041 -406.690068) (xy 39.395043 -406.72279) (xy 39.386262 -406.787633) (xy 39.368857 -406.850711)
			(xy 39.343141 -406.910881) (xy 39.32682 -406.939242) (xy 39.323492 -406.94526) (xy 39.319894 -406.958529)
			(xy 39.319708 -406.965404) (xy 39.319708 -407.251408) (xy 39.319285 -407.261562) (xy 39.311488 -407.280313)
			(xy 39.297092 -407.294635) (xy 39.278302 -407.302336) (xy 39.268146 -407.302716) (xy 38.551866 -407.302716)
			(xy 38.541732 -407.3023) (xy 38.523001 -407.294553) (xy 38.508645 -407.280245) (xy 38.500835 -407.261541)
			(xy 38.500304 -407.251408) (xy 38.500304 -406.965404) (xy 38.50011 -406.958531) (xy 38.496503 -406.945268)
			(xy 38.493192 -406.939242) (xy 38.476844 -406.910895) (xy 38.451132 -406.85072) (xy 38.433728 -406.787638)
			(xy 38.424949 -406.722792) (xy 34.995053 -406.722792) (xy 34.995053 -406.722798) (xy 34.986195 -406.787656)
			(xy 34.968703 -406.850736) (xy 34.942894 -406.910894) (xy 34.926524 -406.939242) (xy 34.923196 -406.94526)
			(xy 34.919598 -406.958529) (xy 34.919412 -406.965404) (xy 34.919412 -407.251408) (xy 34.918922 -407.261516)
			(xy 34.911184 -407.280192) (xy 34.896888 -407.294486) (xy 34.878212 -407.302222) (xy 34.868104 -407.302716)
			(xy 34.151824 -407.302716) (xy 34.141705 -407.302265) (xy 34.123005 -407.294528) (xy 34.10869 -407.280222)
			(xy 34.100941 -407.261527) (xy 34.100516 -407.251408) (xy 34.100516 -406.965404) (xy 34.100321 -406.958531)
			(xy 34.096715 -406.945268) (xy 34.093404 -406.939242) (xy 34.077056 -406.910883) (xy 34.051249 -406.850727)
			(xy 34.033755 -406.787651) (xy 34.024889 -406.722796) (xy 34.024316 -406.690068) (xy 30.594954 -406.690068)
			(xy 30.594956 -406.72279) (xy 30.586176 -406.787633) (xy 30.568772 -406.850711) (xy 30.543057 -406.910881)
			(xy 30.526736 -406.939242) (xy 30.523409 -406.945261) (xy 30.519811 -406.958529) (xy 30.519624 -406.965404)
			(xy 30.519624 -407.251408) (xy 30.519185 -407.26156) (xy 30.511392 -407.280307) (xy 30.497001 -407.29463)
			(xy 30.478216 -407.302333) (xy 30.468062 -407.302716) (xy 29.751782 -407.302716) (xy 29.741649 -407.302287)
			(xy 29.722919 -407.294545) (xy 29.708561 -407.280241) (xy 29.700751 -407.261539) (xy 29.70022 -407.251408)
			(xy 29.70022 -406.965404) (xy 29.700024 -406.958531) (xy 29.696418 -406.945268) (xy 29.693108 -406.939242)
			(xy 29.67676 -406.910895) (xy 29.651046 -406.85072) (xy 29.633642 -406.787639) (xy 29.624863 -406.722792)
			(xy 0.529844 -406.722792) (xy 0.529844 -409.490164) (xy 27.42438 -409.490164) (xy 27.424955 -409.457435)
			(xy 27.433808 -409.392577) (xy 27.451296 -409.329497) (xy 27.477101 -409.269339) (xy 27.493468 -409.24099)
			(xy 27.496784 -409.234966) (xy 27.500389 -409.221702) (xy 27.50058 -409.214828) (xy 27.50058 -408.465528)
			(xy 27.50038 -408.458655) (xy 27.496777 -408.445393) (xy 27.493468 -408.439366) (xy 27.477095 -408.411021)
			(xy 27.451294 -408.35086) (xy 27.433806 -408.287779) (xy 27.424948 -408.222921) (xy 27.42438 -408.190192)
			(xy 27.424967 -408.157463) (xy 27.433817 -408.092606) (xy 27.451301 -408.029526) (xy 27.477103 -407.969367)
			(xy 27.493468 -407.941018) (xy 27.496774 -407.934989) (xy 27.500385 -407.921729) (xy 27.50058 -407.914856)
			(xy 27.50058 -407.628852) (xy 27.501045 -407.618743) (xy 27.508795 -407.600067) (xy 27.523098 -407.585775)
			(xy 27.541778 -407.578038) (xy 27.551888 -407.577544) (xy 28.268168 -407.577544) (xy 28.278268 -407.57811)
			(xy 28.296935 -407.585826) (xy 28.311229 -407.600098) (xy 28.318975 -407.618753) (xy 28.319476 -407.628852)
			(xy 28.319476 -407.914856) (xy 28.319688 -407.921728) (xy 28.323283 -407.93499) (xy 28.326588 -407.941018)
			(xy 28.34296 -407.969364) (xy 28.36876 -408.029525) (xy 28.386248 -408.092605) (xy 28.395107 -408.157463)
			(xy 28.395676 -408.190192) (xy 28.395132 -408.222922) (xy 28.38627 -408.287781) (xy 28.368774 -408.350862)
			(xy 28.34296 -408.411019) (xy 28.326588 -408.439366) (xy 28.323285 -408.445396) (xy 28.319672 -408.458656)
			(xy 28.319476 -408.465528) (xy 28.319476 -409.214828) (xy 28.31966 -409.221702) (xy 28.323274 -409.234964)
			(xy 28.326588 -409.24099) (xy 28.342948 -409.269342) (xy 28.368752 -409.3295) (xy 28.386243 -409.392579)
			(xy 28.395105 -409.457435) (xy 28.395676 -409.490164) (xy 28.39512 -409.522894) (xy 28.386262 -409.587753)
			(xy 28.368769 -409.650833) (xy 28.342958 -409.71099) (xy 28.326588 -409.739338) (xy 28.323259 -409.745356)
			(xy 28.319663 -409.758625) (xy 28.319476 -409.7655) (xy 28.319476 -410.051504) (xy 28.319087 -410.06163)
			(xy 28.311333 -410.080338) (xy 28.297008 -410.094653) (xy 28.278294 -410.102394) (xy 28.268168 -410.102812)
			(xy 27.551888 -410.102812) (xy 27.54178 -410.102325) (xy 27.523104 -410.094585) (xy 27.50881 -410.080289)
			(xy 27.501074 -410.061612) (xy 27.50058 -410.051504) (xy 27.50058 -409.7655) (xy 27.50039 -409.758627)
			(xy 27.496781 -409.745364) (xy 27.493468 -409.739338) (xy 27.477124 -409.710977) (xy 27.451315 -409.650822)
			(xy 27.433819 -409.587746) (xy 27.424953 -409.522892) (xy 27.42438 -409.490164) (xy 0.529844 -409.490164)
			(xy 0.529844 -410.248608) (xy 14.998698 -410.248608) (xy 15.002769 -410.192986) (xy 15.014895 -410.138549)
			(xy 15.034818 -410.086458) (xy 15.062114 -410.037823) (xy 15.0962 -409.99368) (xy 15.136349 -409.954971)
			(xy 15.181707 -409.92252) (xy 15.231307 -409.897019) (xy 15.284091 -409.879012) (xy 15.338934 -409.868882)
			(xy 15.394668 -409.866845) (xy 15.450105 -409.872945) (xy 15.504062 -409.887051) (xy 15.555391 -409.908863)
			(xy 15.602997 -409.937917) (xy 15.645865 -409.973592) (xy 15.683082 -410.015129) (xy 15.713855 -410.061642)
			(xy 15.737527 -410.112139) (xy 15.753595 -410.165546) (xy 15.761715 -410.220722) (xy 15.762224 -410.248608)
			(xy 15.761715 -410.276494) (xy 15.753595 -410.33167) (xy 15.737527 -410.385077) (xy 15.713855 -410.435574)
			(xy 15.683082 -410.482087) (xy 15.645865 -410.523624) (xy 15.602997 -410.559299) (xy 15.555391 -410.588353)
			(xy 15.504062 -410.610165) (xy 15.456095 -410.622705) (xy 29.624872 -410.622705) (xy 29.624874 -410.557268)
			(xy 29.633659 -410.492423) (xy 29.651068 -410.429343) (xy 29.676786 -410.369172) (xy 29.693108 -410.34081)
			(xy 29.69642 -410.334784) (xy 29.700027 -410.321521) (xy 29.70022 -410.314648) (xy 29.70022 -409.565348)
			(xy 29.700007 -409.558476) (xy 29.696413 -409.545214) (xy 29.693108 -409.539186) (xy 29.676797 -409.510819)
			(xy 29.65108 -409.450649) (xy 29.633672 -409.387571) (xy 29.624888 -409.322728) (xy 29.624886 -409.257293)
			(xy 29.633668 -409.192449) (xy 29.651073 -409.129371) (xy 29.676788 -409.0692) (xy 29.693108 -409.040838)
			(xy 29.69641 -409.034807) (xy 29.700023 -409.021548) (xy 29.70022 -409.014676) (xy 29.70022 -408.728672)
			(xy 29.700599 -408.718514) (xy 29.708408 -408.699757) (xy 29.722817 -408.685434) (xy 29.741621 -408.677738)
			(xy 29.751782 -408.677364) (xy 30.468062 -408.677364) (xy 30.478189 -408.677859) (xy 30.496914 -408.685578)
			(xy 30.511272 -408.699863) (xy 30.519089 -408.718547) (xy 30.519624 -408.728672) (xy 30.519624 -409.014676)
			(xy 30.519822 -409.021549) (xy 30.523426 -409.034812) (xy 30.526736 -409.040838) (xy 30.543069 -409.069193)
			(xy 30.568787 -409.129366) (xy 30.586195 -409.192446) (xy 30.594978 -409.257291) (xy 30.594976 -409.322729)
			(xy 30.586191 -409.387575) (xy 30.56878 -409.450654) (xy 30.54306 -409.510825) (xy 30.536116 -409.522889)
			(xy 31.825002 -409.522889) (xy 31.825006 -409.457449) (xy 31.833794 -409.392603) (xy 31.851208 -409.329523)
			(xy 31.876931 -409.269351) (xy 31.893256 -409.24099) (xy 31.896571 -409.234965) (xy 31.900177 -409.221702)
			(xy 31.900368 -409.214828) (xy 31.900368 -408.465528) (xy 31.900169 -408.458655) (xy 31.896566 -408.445392)
			(xy 31.893256 -408.439366) (xy 31.876926 -408.411009) (xy 31.851209 -408.350837) (xy 31.833801 -408.287757)
			(xy 31.825018 -408.222912) (xy 31.825019 -408.157474) (xy 31.833803 -408.092629) (xy 31.851213 -408.02955)
			(xy 31.876933 -407.969379) (xy 31.893256 -407.941018) (xy 31.896561 -407.934988) (xy 31.900173 -407.921729)
			(xy 31.900368 -407.914856) (xy 31.900368 -407.628852) (xy 31.900782 -407.618699) (xy 31.908587 -407.599952)
			(xy 31.922985 -407.585631) (xy 31.941775 -407.577927) (xy 31.95193 -407.577544) (xy 32.66821 -407.577544)
			(xy 32.678338 -407.578019) (xy 32.69706 -407.58575) (xy 32.711416 -407.60004) (xy 32.719234 -407.618727)
			(xy 32.719772 -407.628852) (xy 32.719772 -407.914856) (xy 32.719984 -407.921728) (xy 32.723579 -407.93499)
			(xy 32.726884 -407.941018) (xy 32.743199 -407.969383) (xy 32.768916 -408.029554) (xy 32.786324 -408.092632)
			(xy 32.795108 -408.157475) (xy 32.795109 -408.222911) (xy 32.786327 -408.287755) (xy 32.76892 -408.350833)
			(xy 32.743205 -408.411005) (xy 32.726884 -408.439366) (xy 32.72358 -408.445396) (xy 32.719968 -408.458656)
			(xy 32.719772 -408.465528) (xy 32.719772 -409.214828) (xy 32.719957 -409.221702) (xy 32.72357 -409.234964)
			(xy 32.726884 -409.24099) (xy 32.743175 -409.269368) (xy 32.768894 -409.329536) (xy 32.786305 -409.392611)
			(xy 32.795092 -409.457452) (xy 32.795096 -409.522886) (xy 32.786317 -409.587728) (xy 32.768915 -409.650806)
			(xy 32.743203 -409.710977) (xy 32.726884 -409.739338) (xy 32.723555 -409.745355) (xy 32.719959 -409.758625)
			(xy 32.719772 -409.7655) (xy 32.719772 -410.051504) (xy 32.719381 -410.061662) (xy 32.711579 -410.08042)
			(xy 32.697172 -410.094744) (xy 32.67837 -410.102438) (xy 32.66821 -410.102812) (xy 31.95193 -410.102812)
			(xy 31.941812 -410.102251) (xy 31.923101 -410.094542) (xy 31.908745 -410.080279) (xy 31.900916 -410.061619)
			(xy 31.900368 -410.051504) (xy 31.900368 -409.7655) (xy 31.90018 -409.758626) (xy 31.896569 -409.745364)
			(xy 31.893256 -409.739338) (xy 31.876903 -409.710994) (xy 31.851187 -409.650819) (xy 31.833782 -409.587737)
			(xy 31.825002 -409.522889) (xy 30.536116 -409.522889) (xy 30.526736 -409.539186) (xy 30.523429 -409.545215)
			(xy 30.519818 -409.558475) (xy 30.519624 -409.565348) (xy 30.519624 -410.314648) (xy 30.519833 -410.32152)
			(xy 30.523429 -410.334783) (xy 30.526736 -410.34081) (xy 30.543045 -410.369178) (xy 30.568766 -410.429348)
			(xy 30.586176 -410.492425) (xy 30.594962 -410.557268) (xy 30.594963 -410.589984) (xy 34.024316 -410.589984)
			(xy 34.024895 -410.557255) (xy 34.033746 -410.492397) (xy 34.051233 -410.429317) (xy 34.077037 -410.369158)
			(xy 34.093404 -410.34081) (xy 34.096715 -410.334784) (xy 34.100323 -410.321521) (xy 34.100516 -410.314648)
			(xy 34.100516 -409.565348) (xy 34.100303 -409.558476) (xy 34.096709 -409.545214) (xy 34.093404 -409.539186)
			(xy 34.077033 -409.51084) (xy 34.051233 -409.450679) (xy 34.033744 -409.387599) (xy 34.024886 -409.322741)
			(xy 34.024316 -409.290012) (xy 34.024863 -409.257282) (xy 34.033724 -409.192423) (xy 34.05122 -409.129343)
			(xy 34.077033 -409.069185) (xy 34.093404 -409.040838) (xy 34.096706 -409.034807) (xy 34.100319 -409.021548)
			(xy 34.100516 -409.014676) (xy 34.100516 -408.728672) (xy 34.100962 -408.718559) (xy 34.108712 -408.699878)
			(xy 34.123021 -408.685583) (xy 34.141711 -408.677852) (xy 34.151824 -408.677364) (xy 34.868104 -408.677364)
			(xy 34.878209 -408.677881) (xy 34.89688 -408.685613) (xy 34.911173 -408.6999) (xy 34.918914 -408.718568)
			(xy 34.919412 -408.728672) (xy 34.919412 -409.014676) (xy 34.919612 -409.021549) (xy 34.923215 -409.034811)
			(xy 34.926524 -409.040838) (xy 34.942907 -409.069178) (xy 34.968704 -409.129341) (xy 34.986189 -409.192423)
			(xy 34.995044 -409.257282) (xy 34.995612 -409.290012) (xy 34.995027 -409.322741) (xy 34.986177 -409.387598)
			(xy 34.968692 -409.450678) (xy 34.951757 -409.490164) (xy 36.224464 -409.490164) (xy 36.225041 -409.457435)
			(xy 36.233894 -409.392577) (xy 36.251381 -409.329497) (xy 36.277185 -409.269338) (xy 36.293552 -409.24099)
			(xy 36.296866 -409.234965) (xy 36.300473 -409.221702) (xy 36.300664 -409.214828) (xy 36.300664 -408.465528)
			(xy 36.300466 -408.458655) (xy 36.296862 -408.445392) (xy 36.293552 -408.439366) (xy 36.277178 -408.411021)
			(xy 36.251377 -408.350861) (xy 36.233889 -408.28778) (xy 36.225032 -408.222921) (xy 36.224464 -408.190192)
			(xy 36.225054 -408.157463) (xy 36.233903 -408.092606) (xy 36.251387 -408.029526) (xy 36.277187 -407.969367)
			(xy 36.293552 -407.941018) (xy 36.296856 -407.934988) (xy 36.300469 -407.921729) (xy 36.300664 -407.914856)
			(xy 36.300664 -407.628852) (xy 36.301145 -407.618745) (xy 36.308892 -407.600072) (xy 36.323189 -407.585781)
			(xy 36.341864 -407.578041) (xy 36.351972 -407.577544) (xy 37.068252 -407.577544) (xy 37.078351 -407.578123)
			(xy 37.097017 -407.585835) (xy 37.111312 -407.600102) (xy 37.119058 -407.618754) (xy 37.11956 -407.628852)
			(xy 37.11956 -407.914856) (xy 37.119774 -407.921728) (xy 37.123368 -407.93499) (xy 37.126672 -407.941018)
			(xy 37.143042 -407.969365) (xy 37.168843 -408.029525) (xy 37.186332 -408.092605) (xy 37.195191 -408.157463)
			(xy 37.19576 -408.190192) (xy 37.195205 -408.222922) (xy 37.186345 -408.28778) (xy 37.168851 -408.35086)
			(xy 37.143042 -408.411018) (xy 37.126672 -408.439366) (xy 37.123367 -408.445396) (xy 37.119756 -408.458656)
			(xy 37.11956 -408.465528) (xy 37.11956 -409.214828) (xy 37.119746 -409.221702) (xy 37.123359 -409.234964)
			(xy 37.126672 -409.24099) (xy 37.143031 -409.269343) (xy 37.168835 -409.329501) (xy 37.186327 -409.392579)
			(xy 37.195189 -409.457435) (xy 37.19576 -409.490164) (xy 37.195192 -409.522893) (xy 37.186336 -409.587751)
			(xy 37.168846 -409.650831) (xy 37.14304 -409.71099) (xy 37.126672 -409.739338) (xy 37.123342 -409.745355)
			(xy 37.119746 -409.758625) (xy 37.11956 -409.7655) (xy 37.11956 -410.051504) (xy 37.119186 -410.061632)
			(xy 37.111429 -410.080343) (xy 37.097099 -410.094659) (xy 37.07838 -410.102396) (xy 37.068252 -410.102812)
			(xy 36.351972 -410.102812) (xy 36.341863 -410.102338) (xy 36.323186 -410.094594) (xy 36.308893 -410.080293)
			(xy 36.301157 -410.061613) (xy 36.300664 -410.051504) (xy 36.300664 -409.7655) (xy 36.300476 -409.758626)
			(xy 36.296866 -409.745363) (xy 36.293552 -409.739338) (xy 36.277207 -409.710978) (xy 36.251399 -409.650823)
			(xy 36.233903 -409.587746) (xy 36.225037 -409.522892) (xy 36.224464 -409.490164) (xy 34.951757 -409.490164)
			(xy 34.94289 -409.510837) (xy 34.926524 -409.539186) (xy 34.923216 -409.545214) (xy 34.919606 -409.558475)
			(xy 34.919412 -409.565348) (xy 34.919412 -410.314648) (xy 34.919622 -410.32152) (xy 34.923218 -410.334783)
			(xy 34.926524 -410.34081) (xy 34.942896 -410.369156) (xy 34.968696 -410.429317) (xy 34.986183 -410.492397)
			(xy 34.995042 -410.557255) (xy 34.995612 -410.589984) (xy 34.99506 -410.622705) (xy 38.424958 -410.622705)
			(xy 38.42496 -410.557268) (xy 38.433744 -410.492423) (xy 38.451153 -410.429344) (xy 38.47687 -410.369172)
			(xy 38.493192 -410.34081) (xy 38.496503 -410.334783) (xy 38.500111 -410.321521) (xy 38.500304 -410.314648)
			(xy 38.500304 -409.565348) (xy 38.500093 -409.558476) (xy 38.496498 -409.545213) (xy 38.493192 -409.539186)
			(xy 38.476881 -409.510819) (xy 38.451165 -409.450648) (xy 38.433758 -409.387571) (xy 38.424974 -409.322728)
			(xy 38.424972 -409.257293) (xy 38.433754 -409.192449) (xy 38.451159 -409.129371) (xy 38.476872 -409.0692)
			(xy 38.493192 -409.040838) (xy 38.496493 -409.034806) (xy 38.500107 -409.021548) (xy 38.500304 -409.014676)
			(xy 38.500304 -408.728672) (xy 38.500699 -408.718516) (xy 38.508504 -408.699762) (xy 38.522909 -408.685439)
			(xy 38.541707 -408.677741) (xy 38.551866 -408.677364) (xy 39.268146 -408.677364) (xy 39.278279 -408.67779)
			(xy 39.297005 -408.685537) (xy 39.311361 -408.699842) (xy 39.319174 -408.718541) (xy 39.319708 -408.728672)
			(xy 39.319708 -409.014676) (xy 39.319908 -409.021549) (xy 39.323511 -409.034811) (xy 39.32682 -409.040838)
			(xy 39.343154 -409.069193) (xy 39.368872 -409.129365) (xy 39.386281 -409.192445) (xy 39.395064 -409.257291)
			(xy 39.395063 -409.322729) (xy 39.386277 -409.387575) (xy 39.368866 -409.450654) (xy 39.351976 -409.490164)
			(xy 40.624252 -409.490164) (xy 40.62483 -409.457435) (xy 40.633683 -409.392577) (xy 40.65117 -409.329497)
			(xy 40.676973 -409.269339) (xy 40.69334 -409.24099) (xy 40.696654 -409.234965) (xy 40.700261 -409.221702)
			(xy 40.700452 -409.214828) (xy 40.700452 -408.465528) (xy 40.700255 -408.458655) (xy 40.696651 -408.445392)
			(xy 40.69334 -408.439366) (xy 40.676965 -408.411022) (xy 40.651164 -408.350861) (xy 40.633677 -408.28778)
			(xy 40.62482 -408.222922) (xy 40.624252 -408.190192) (xy 40.624843 -408.157463) (xy 40.633692 -408.092606)
			(xy 40.651175 -408.029526) (xy 40.676975 -407.969367) (xy 40.69334 -407.941018) (xy 40.696644 -407.934988)
			(xy 40.700257 -407.921728) (xy 40.700452 -407.914856) (xy 40.700452 -407.628852) (xy 40.700945 -407.618746)
			(xy 40.708689 -407.600076) (xy 40.722983 -407.585785) (xy 40.741654 -407.578043) (xy 40.75176 -407.577544)
			(xy 41.46804 -407.577544) (xy 41.478144 -407.578051) (xy 41.496813 -407.585791) (xy 41.511104 -407.600081)
			(xy 41.518847 -407.618748) (xy 41.519348 -407.628852) (xy 41.519348 -407.914856) (xy 41.519551 -407.921729)
			(xy 41.523151 -407.934992) (xy 41.52646 -407.941018) (xy 41.542829 -407.969365) (xy 41.568631 -408.029525)
			(xy 41.58612 -408.092605) (xy 41.594979 -408.157463) (xy 41.595548 -408.190192) (xy 45.023794 -408.190192)
			(xy 45.027785 -408.128025) (xy 45.039694 -408.066878) (xy 45.059323 -408.007757) (xy 45.086352 -407.951631)
			(xy 45.120336 -407.899422) (xy 45.160718 -407.851987) (xy 45.206834 -407.810106) (xy 45.257926 -407.774466)
			(xy 45.313157 -407.745652) (xy 45.371619 -407.724138) (xy 45.432353 -407.710276) (xy 45.49436 -407.704294)
			(xy 45.556623 -407.70629) (xy 45.61812 -407.716233) (xy 45.677841 -407.733957) (xy 45.734804 -407.759174)
			(xy 45.788075 -407.791467) (xy 45.83678 -407.830307) (xy 45.880117 -407.875057) (xy 45.917377 -407.924981)
			(xy 45.947946 -407.97926) (xy 45.971324 -408.037003) (xy 45.987125 -408.097261) (xy 45.995091 -408.159044)
			(xy 45.99559 -408.190192) (xy 45.995091 -408.22134) (xy 45.987125 -408.283123) (xy 45.971324 -408.343381)
			(xy 45.947946 -408.401124) (xy 45.917377 -408.455403) (xy 45.880117 -408.505327) (xy 45.83678 -408.550077)
			(xy 45.788075 -408.588917) (xy 45.734804 -408.62121) (xy 45.677841 -408.646427) (xy 45.61812 -408.664151)
			(xy 45.556623 -408.674094) (xy 45.49436 -408.67609) (xy 45.432353 -408.670108) (xy 45.371619 -408.656246)
			(xy 45.313157 -408.634732) (xy 45.257926 -408.605918) (xy 45.206834 -408.570278) (xy 45.160718 -408.528397)
			(xy 45.120336 -408.480962) (xy 45.086352 -408.428753) (xy 45.059323 -408.372627) (xy 45.039694 -408.313506)
			(xy 45.027785 -408.252359) (xy 45.023794 -408.190192) (xy 41.595548 -408.190192) (xy 41.594995 -408.222922)
			(xy 41.586134 -408.28778) (xy 41.56864 -408.35086) (xy 41.54283 -408.411018) (xy 41.52646 -408.439366)
			(xy 41.523162 -408.445399) (xy 41.519545 -408.458656) (xy 41.519348 -408.465528) (xy 41.519348 -409.214828)
			(xy 41.519523 -409.221703) (xy 41.523142 -409.234966) (xy 41.52646 -409.24099) (xy 41.542818 -409.269344)
			(xy 41.568622 -409.329501) (xy 41.586114 -409.392579) (xy 41.594977 -409.457435) (xy 41.595548 -409.490164)
			(xy 41.594982 -409.522893) (xy 41.586125 -409.587751) (xy 41.568635 -409.650832) (xy 41.542828 -409.71099)
			(xy 41.52646 -409.739338) (xy 41.523136 -409.745358) (xy 41.519536 -409.758625) (xy 41.519348 -409.7655)
			(xy 41.519348 -410.051504) (xy 41.518819 -410.061607) (xy 41.511089 -410.080276) (xy 41.496806 -410.094569)
			(xy 41.478143 -410.102312) (xy 41.46804 -410.102812) (xy 40.75176 -410.102812) (xy 40.74165 -410.102348)
			(xy 40.722973 -410.094599) (xy 40.70868 -410.080296) (xy 40.700945 -410.061614) (xy 40.700452 -410.051504)
			(xy 40.700452 -409.7655) (xy 40.700266 -409.758626) (xy 40.696654 -409.745363) (xy 40.69334 -409.739338)
			(xy 40.676993 -409.710978) (xy 40.651186 -409.650823) (xy 40.633691 -409.587747) (xy 40.624825 -409.522892)
			(xy 40.624252 -409.490164) (xy 39.351976 -409.490164) (xy 39.343144 -409.510825) (xy 39.32682 -409.539186)
			(xy 39.323512 -409.545214) (xy 39.319902 -409.558475) (xy 39.319708 -409.565348) (xy 39.319708 -410.314648)
			(xy 39.319919 -410.32152) (xy 39.323514 -410.334783) (xy 39.32682 -410.34081) (xy 39.34313 -410.369178)
			(xy 39.368851 -410.429347) (xy 39.386262 -410.492425) (xy 39.395048 -410.557268) (xy 39.395049 -410.589984)
			(xy 42.8244 -410.589984) (xy 42.824981 -410.557255) (xy 42.833832 -410.492397) (xy 42.851318 -410.429317)
			(xy 42.877122 -410.369159) (xy 42.893488 -410.34081) (xy 42.896798 -410.334783) (xy 42.900407 -410.321521)
			(xy 42.9006 -410.314648) (xy 42.9006 -409.565348) (xy 42.90039 -409.558476) (xy 42.896794 -409.545213)
			(xy 42.893488 -409.539186) (xy 42.877116 -409.51084) (xy 42.851316 -409.45068) (xy 42.833828 -409.387599)
			(xy 42.82497 -409.322741) (xy 42.8244 -409.290012) (xy 42.824948 -409.257282) (xy 42.833809 -409.192423)
			(xy 42.851305 -409.129343) (xy 42.877117 -409.069185) (xy 42.893488 -409.040838) (xy 42.896788 -409.034806)
			(xy 42.900403 -409.021548) (xy 42.9006 -409.014676) (xy 42.9006 -408.728672) (xy 42.901062 -408.718561)
			(xy 42.908809 -408.699883) (xy 42.923113 -408.685589) (xy 42.941797 -408.677855) (xy 42.951908 -408.677364)
			(xy 43.668188 -408.677364) (xy 43.678292 -408.677894) (xy 43.696963 -408.685621) (xy 43.711257 -408.699904)
			(xy 43.718998 -408.718569) (xy 43.719496 -408.728672) (xy 43.719496 -409.014676) (xy 43.719697 -409.021549)
			(xy 43.723299 -409.034811) (xy 43.726608 -409.040838) (xy 43.742989 -409.069178) (xy 43.768787 -409.129341)
			(xy 43.786272 -409.192423) (xy 43.795128 -409.257282) (xy 43.795696 -409.290012) (xy 43.795114 -409.322741)
			(xy 43.786263 -409.387599) (xy 43.768777 -409.450679) (xy 43.751841 -409.490164) (xy 45.023794 -409.490164)
			(xy 45.027785 -409.427997) (xy 45.039694 -409.36685) (xy 45.059323 -409.307729) (xy 45.086352 -409.251603)
			(xy 45.120336 -409.199394) (xy 45.160718 -409.151959) (xy 45.206834 -409.110078) (xy 45.257926 -409.074438)
			(xy 45.313157 -409.045624) (xy 45.371619 -409.02411) (xy 45.432353 -409.010248) (xy 45.49436 -409.004266)
			(xy 45.556623 -409.006262) (xy 45.61812 -409.016205) (xy 45.677841 -409.033929) (xy 45.734804 -409.059146)
			(xy 45.788075 -409.091439) (xy 45.83678 -409.130279) (xy 45.880117 -409.175029) (xy 45.917377 -409.224953)
			(xy 45.947946 -409.279232) (xy 45.971324 -409.336975) (xy 45.987125 -409.397233) (xy 45.995091 -409.459016)
			(xy 45.99559 -409.490164) (xy 45.995091 -409.521312) (xy 45.987125 -409.583095) (xy 45.971324 -409.643353)
			(xy 45.947946 -409.701096) (xy 45.917377 -409.755375) (xy 45.880117 -409.805299) (xy 45.83678 -409.850049)
			(xy 45.788075 -409.888889) (xy 45.734804 -409.921182) (xy 45.677841 -409.946399) (xy 45.61812 -409.964123)
			(xy 45.556623 -409.974066) (xy 45.49436 -409.976062) (xy 45.432353 -409.97008) (xy 45.371619 -409.956218)
			(xy 45.313157 -409.934704) (xy 45.257926 -409.90589) (xy 45.206834 -409.87025) (xy 45.160718 -409.828369)
			(xy 45.120336 -409.780934) (xy 45.086352 -409.728725) (xy 45.059323 -409.672599) (xy 45.039694 -409.613478)
			(xy 45.027785 -409.552331) (xy 45.023794 -409.490164) (xy 43.751841 -409.490164) (xy 43.742974 -409.510837)
			(xy 43.726608 -409.539186) (xy 43.723299 -409.545213) (xy 43.71969 -409.558475) (xy 43.719496 -409.565348)
			(xy 43.719496 -410.314648) (xy 43.719709 -410.32152) (xy 43.723303 -410.334782) (xy 43.726608 -410.34081)
			(xy 43.742978 -410.369157) (xy 43.768779 -410.429317) (xy 43.786267 -410.492397) (xy 43.795126 -410.557255)
			(xy 43.795696 -410.589984) (xy 43.795146 -410.622705) (xy 47.22503 -410.622705) (xy 47.225032 -410.557267)
			(xy 47.233818 -410.492421) (xy 47.25123 -410.429342) (xy 47.276952 -410.369171) (xy 47.293276 -410.34081)
			(xy 47.296585 -410.334783) (xy 47.300195 -410.321521) (xy 47.300388 -410.314648) (xy 47.300388 -409.565348)
			(xy 47.300179 -409.558476) (xy 47.296583 -409.545213) (xy 47.293276 -409.539186) (xy 47.276963 -409.51082)
			(xy 47.251242 -409.45065) (xy 47.233832 -409.387572) (xy 47.225046 -409.322728) (xy 47.225045 -409.257292)
			(xy 47.233828 -409.192448) (xy 47.251235 -409.129369) (xy 47.276953 -409.069199) (xy 47.293276 -409.040838)
			(xy 47.296576 -409.034806) (xy 47.300191 -409.021548) (xy 47.300388 -409.014676) (xy 47.300388 -408.728672)
			(xy 47.300798 -408.718518) (xy 47.308601 -408.699767) (xy 47.323001 -408.685445) (xy 47.341793 -408.677744)
			(xy 47.35195 -408.677364) (xy 48.06823 -408.677364) (xy 48.078362 -408.677803) (xy 48.097088 -408.685545)
			(xy 48.111444 -408.699846) (xy 48.119258 -408.718542) (xy 48.119792 -408.728672) (xy 48.119792 -409.014676)
			(xy 48.119994 -409.021548) (xy 48.123595 -409.034811) (xy 48.126904 -409.040838) (xy 48.143235 -409.069194)
			(xy 48.168949 -409.129367) (xy 48.186355 -409.192447) (xy 48.195136 -409.257292) (xy 48.195135 -409.322729)
			(xy 48.186351 -409.387574) (xy 48.168943 -409.450653) (xy 48.143226 -409.510824) (xy 48.126904 -409.539186)
			(xy 48.123595 -409.545213) (xy 48.119985 -409.558475) (xy 48.119792 -409.565348) (xy 48.119792 -410.314648)
			(xy 48.120005 -410.32152) (xy 48.123599 -410.334782) (xy 48.126904 -410.34081) (xy 48.143211 -410.369179)
			(xy 48.168928 -410.429349) (xy 48.186336 -410.492426) (xy 48.19512 -410.557269) (xy 48.195122 -410.622704)
			(xy 48.186341 -410.687547) (xy 48.168937 -410.750625) (xy 48.143224 -410.810796) (xy 48.126904 -410.839158)
			(xy 48.123604 -410.84519) (xy 48.119989 -410.858448) (xy 48.119792 -410.86532) (xy 48.119792 -411.151324)
			(xy 48.119398 -411.161481) (xy 48.111593 -411.180235) (xy 48.097188 -411.194558) (xy 48.078389 -411.202255)
			(xy 48.06823 -411.202632) (xy 47.35195 -411.202632) (xy 47.341823 -411.202132) (xy 47.323098 -411.194415)
			(xy 47.308739 -411.180132) (xy 47.300923 -411.161448) (xy 47.300388 -411.151324) (xy 47.300388 -410.86532)
			(xy 47.30019 -410.858447) (xy 47.296586 -410.845184) (xy 47.293276 -410.839158) (xy 47.276939 -410.810805)
			(xy 47.251221 -410.750632) (xy 47.233813 -410.687552) (xy 47.22503 -410.622705) (xy 43.795146 -410.622705)
			(xy 43.795146 -410.622714) (xy 43.786285 -410.687573) (xy 43.768791 -410.750653) (xy 43.742979 -410.81081)
			(xy 43.726608 -410.839158) (xy 43.723309 -410.84519) (xy 43.719693 -410.858448) (xy 43.719496 -410.86532)
			(xy 43.719496 -411.151324) (xy 43.719035 -411.161435) (xy 43.711288 -411.180114) (xy 43.696984 -411.194408)
			(xy 43.678299 -411.202142) (xy 43.668188 -411.202632) (xy 42.951908 -411.202632) (xy 42.941804 -411.202109)
			(xy 42.923132 -411.19438) (xy 42.908838 -411.180095) (xy 42.901097 -411.161428) (xy 42.9006 -411.151324)
			(xy 42.9006 -410.86532) (xy 42.9004 -410.858447) (xy 42.896797 -410.845185) (xy 42.893488 -410.839158)
			(xy 42.877105 -410.810819) (xy 42.851307 -410.750655) (xy 42.833823 -410.687573) (xy 42.824968 -410.622714)
			(xy 42.8244 -410.589984) (xy 39.395049 -410.589984) (xy 39.39505 -410.622704) (xy 39.386268 -410.687548)
			(xy 39.36886 -410.750627) (xy 39.343142 -410.810797) (xy 39.32682 -410.839158) (xy 39.323522 -410.845191)
			(xy 39.319905 -410.858448) (xy 39.319708 -410.86532) (xy 39.319708 -411.151324) (xy 39.319298 -411.161479)
			(xy 39.311496 -411.18023) (xy 39.297096 -411.194552) (xy 39.278303 -411.202253) (xy 39.268146 -411.202632)
			(xy 38.551866 -411.202632) (xy 38.541734 -411.202201) (xy 38.523006 -411.194456) (xy 38.50865 -411.180153)
			(xy 38.500837 -411.161454) (xy 38.500304 -411.151324) (xy 38.500304 -410.86532) (xy 38.500104 -410.858447)
			(xy 38.496501 -410.845185) (xy 38.493192 -410.839158) (xy 38.476858 -410.810804) (xy 38.451144 -410.75063)
			(xy 38.433739 -410.68755) (xy 38.424958 -410.622705) (xy 34.99506 -410.622705) (xy 34.99506 -410.622714)
			(xy 34.9862 -410.687573) (xy 34.968706 -410.750653) (xy 34.942895 -410.810811) (xy 34.926524 -410.839158)
			(xy 34.923226 -410.845191) (xy 34.919609 -410.858448) (xy 34.919412 -410.86532) (xy 34.919412 -411.151324)
			(xy 34.918935 -411.161433) (xy 34.911192 -411.180109) (xy 34.896893 -411.194403) (xy 34.878213 -411.202139)
			(xy 34.868104 -411.202632) (xy 34.151824 -411.202632) (xy 34.141721 -411.202096) (xy 34.123049 -411.194372)
			(xy 34.108755 -411.180091) (xy 34.101013 -411.161427) (xy 34.100516 -411.151324) (xy 34.100516 -410.86532)
			(xy 34.100315 -410.858447) (xy 34.096713 -410.845185) (xy 34.093404 -410.839158) (xy 34.077022 -410.810818)
			(xy 34.051224 -410.750655) (xy 34.033739 -410.687573) (xy 34.024884 -410.622714) (xy 34.024316 -410.589984)
			(xy 30.594963 -410.589984) (xy 30.594964 -410.622704) (xy 30.586182 -410.687548) (xy 30.568775 -410.750626)
			(xy 30.543058 -410.810797) (xy 30.526736 -410.839158) (xy 30.523439 -410.845191) (xy 30.519822 -410.858448)
			(xy 30.519624 -410.86532) (xy 30.519624 -411.151324) (xy 30.519199 -411.161477) (xy 30.5114 -411.180225)
			(xy 30.497005 -411.194547) (xy 30.478217 -411.20225) (xy 30.468062 -411.202632) (xy 29.751782 -411.202632)
			(xy 29.741651 -411.202188) (xy 29.722924 -411.194449) (xy 29.708567 -411.180149) (xy 29.700753 -411.161453)
			(xy 29.70022 -411.151324) (xy 29.70022 -410.86532) (xy 29.700018 -410.858448) (xy 29.696416 -410.845185)
			(xy 29.693108 -410.839158) (xy 29.676773 -410.810804) (xy 29.651058 -410.750631) (xy 29.633653 -410.687551)
			(xy 29.624872 -410.622705) (xy 15.456095 -410.622705) (xy 15.450105 -410.624271) (xy 15.394668 -410.630371)
			(xy 15.338934 -410.628334) (xy 15.284091 -410.618204) (xy 15.231307 -410.600197) (xy 15.181707 -410.574696)
			(xy 15.136349 -410.542245) (xy 15.0962 -410.503536) (xy 15.062114 -410.459393) (xy 15.034818 -410.410758)
			(xy 15.014895 -410.358667) (xy 15.002769 -410.30423) (xy 14.998698 -410.248608) (xy 0.529844 -410.248608)
			(xy 0.529844 -412.090108) (xy 27.42388 -412.090108) (xy 27.427871 -412.027941) (xy 27.43978 -411.966794)
			(xy 27.459409 -411.907673) (xy 27.486438 -411.851547) (xy 27.520422 -411.799338) (xy 27.560804 -411.751903)
			(xy 27.60692 -411.710022) (xy 27.658012 -411.674382) (xy 27.713243 -411.645568) (xy 27.771705 -411.624054)
			(xy 27.832439 -411.610192) (xy 27.894446 -411.60421) (xy 27.956709 -411.606206) (xy 28.018206 -411.616149)
			(xy 28.077927 -411.633873) (xy 28.13489 -411.65909) (xy 28.188161 -411.691383) (xy 28.236866 -411.730223)
			(xy 28.280203 -411.774973) (xy 28.317463 -411.824897) (xy 28.348032 -411.879176) (xy 28.37141 -411.936919)
			(xy 28.387211 -411.997177) (xy 28.395177 -412.05896) (xy 28.395676 -412.090108) (xy 31.823922 -412.090108)
			(xy 31.827913 -412.027941) (xy 31.839822 -411.966794) (xy 31.859451 -411.907673) (xy 31.88648 -411.851547)
			(xy 31.920464 -411.799338) (xy 31.960846 -411.751903) (xy 32.006962 -411.710022) (xy 32.058054 -411.674382)
			(xy 32.113285 -411.645568) (xy 32.171747 -411.624054) (xy 32.232481 -411.610192) (xy 32.294488 -411.60421)
			(xy 32.356751 -411.606206) (xy 32.418248 -411.616149) (xy 32.477969 -411.633873) (xy 32.534932 -411.65909)
			(xy 32.588203 -411.691383) (xy 32.636908 -411.730223) (xy 32.680245 -411.774973) (xy 32.717505 -411.824897)
			(xy 32.748074 -411.879176) (xy 32.771452 -411.936919) (xy 32.787253 -411.997177) (xy 32.795219 -412.05896)
			(xy 32.795718 -412.090108) (xy 36.223964 -412.090108) (xy 36.227955 -412.027941) (xy 36.239864 -411.966794)
			(xy 36.259493 -411.907673) (xy 36.286522 -411.851547) (xy 36.320506 -411.799338) (xy 36.360888 -411.751903)
			(xy 36.407004 -411.710022) (xy 36.458096 -411.674382) (xy 36.513327 -411.645568) (xy 36.571789 -411.624054)
			(xy 36.632523 -411.610192) (xy 36.69453 -411.60421) (xy 36.756793 -411.606206) (xy 36.81829 -411.616149)
			(xy 36.878011 -411.633873) (xy 36.934974 -411.65909) (xy 36.988245 -411.691383) (xy 37.03695 -411.730223)
			(xy 37.080287 -411.774973) (xy 37.117547 -411.824897) (xy 37.148116 -411.879176) (xy 37.171494 -411.936919)
			(xy 37.187295 -411.997177) (xy 37.195261 -412.05896) (xy 37.19576 -412.090108) (xy 40.623752 -412.090108)
			(xy 40.627743 -412.027941) (xy 40.639652 -411.966794) (xy 40.659281 -411.907673) (xy 40.68631 -411.851547)
			(xy 40.720294 -411.799338) (xy 40.760676 -411.751903) (xy 40.806792 -411.710022) (xy 40.857884 -411.674382)
			(xy 40.913115 -411.645568) (xy 40.971577 -411.624054) (xy 41.032311 -411.610192) (xy 41.094318 -411.60421)
			(xy 41.156581 -411.606206) (xy 41.218078 -411.616149) (xy 41.277799 -411.633873) (xy 41.334762 -411.65909)
			(xy 41.388033 -411.691383) (xy 41.436738 -411.730223) (xy 41.480075 -411.774973) (xy 41.517335 -411.824897)
			(xy 41.547904 -411.879176) (xy 41.571282 -411.936919) (xy 41.587083 -411.997177) (xy 41.595049 -412.05896)
			(xy 41.595548 -412.090108) (xy 45.023794 -412.090108) (xy 45.027785 -412.027941) (xy 45.039694 -411.966794)
			(xy 45.059323 -411.907673) (xy 45.086352 -411.851547) (xy 45.120336 -411.799338) (xy 45.160718 -411.751903)
			(xy 45.206834 -411.710022) (xy 45.257926 -411.674382) (xy 45.313157 -411.645568) (xy 45.371619 -411.624054)
			(xy 45.432353 -411.610192) (xy 45.49436 -411.60421) (xy 45.556623 -411.606206) (xy 45.61812 -411.616149)
			(xy 45.677841 -411.633873) (xy 45.734804 -411.65909) (xy 45.788075 -411.691383) (xy 45.83678 -411.730223)
			(xy 45.880117 -411.774973) (xy 45.917377 -411.824897) (xy 45.947946 -411.879176) (xy 45.971324 -411.936919)
			(xy 45.987125 -411.997177) (xy 45.995091 -412.05896) (xy 45.99559 -412.090108) (xy 45.995091 -412.121256)
			(xy 45.987125 -412.183039) (xy 45.971324 -412.243297) (xy 45.947946 -412.30104) (xy 45.917377 -412.355319)
			(xy 45.880117 -412.405243) (xy 45.83678 -412.449993) (xy 45.788075 -412.488833) (xy 45.734804 -412.521126)
			(xy 45.677841 -412.546343) (xy 45.61812 -412.564067) (xy 45.556623 -412.57401) (xy 45.49436 -412.576006)
			(xy 45.432353 -412.570024) (xy 45.371619 -412.556162) (xy 45.313157 -412.534648) (xy 45.257926 -412.505834)
			(xy 45.206834 -412.470194) (xy 45.160718 -412.428313) (xy 45.120336 -412.380878) (xy 45.086352 -412.328669)
			(xy 45.059323 -412.272543) (xy 45.039694 -412.213422) (xy 45.027785 -412.152275) (xy 45.023794 -412.090108)
			(xy 41.595548 -412.090108) (xy 41.595049 -412.121256) (xy 41.587083 -412.183039) (xy 41.571282 -412.243297)
			(xy 41.547904 -412.30104) (xy 41.517335 -412.355319) (xy 41.480075 -412.405243) (xy 41.436738 -412.449993)
			(xy 41.388033 -412.488833) (xy 41.334762 -412.521126) (xy 41.277799 -412.546343) (xy 41.218078 -412.564067)
			(xy 41.156581 -412.57401) (xy 41.094318 -412.576006) (xy 41.032311 -412.570024) (xy 40.971577 -412.556162)
			(xy 40.913115 -412.534648) (xy 40.857884 -412.505834) (xy 40.806792 -412.470194) (xy 40.760676 -412.428313)
			(xy 40.720294 -412.380878) (xy 40.68631 -412.328669) (xy 40.659281 -412.272543) (xy 40.639652 -412.213422)
			(xy 40.627743 -412.152275) (xy 40.623752 -412.090108) (xy 37.19576 -412.090108) (xy 37.195261 -412.121256)
			(xy 37.187295 -412.183039) (xy 37.171494 -412.243297) (xy 37.148116 -412.30104) (xy 37.117547 -412.355319)
			(xy 37.080287 -412.405243) (xy 37.03695 -412.449993) (xy 36.988245 -412.488833) (xy 36.934974 -412.521126)
			(xy 36.878011 -412.546343) (xy 36.81829 -412.564067) (xy 36.756793 -412.57401) (xy 36.69453 -412.576006)
			(xy 36.632523 -412.570024) (xy 36.571789 -412.556162) (xy 36.513327 -412.534648) (xy 36.458096 -412.505834)
			(xy 36.407004 -412.470194) (xy 36.360888 -412.428313) (xy 36.320506 -412.380878) (xy 36.286522 -412.328669)
			(xy 36.259493 -412.272543) (xy 36.239864 -412.213422) (xy 36.227955 -412.152275) (xy 36.223964 -412.090108)
			(xy 32.795718 -412.090108) (xy 32.795219 -412.121256) (xy 32.787253 -412.183039) (xy 32.771452 -412.243297)
			(xy 32.748074 -412.30104) (xy 32.717505 -412.355319) (xy 32.680245 -412.405243) (xy 32.636908 -412.449993)
			(xy 32.588203 -412.488833) (xy 32.534932 -412.521126) (xy 32.477969 -412.546343) (xy 32.418248 -412.564067)
			(xy 32.356751 -412.57401) (xy 32.294488 -412.576006) (xy 32.232481 -412.570024) (xy 32.171747 -412.556162)
			(xy 32.113285 -412.534648) (xy 32.058054 -412.505834) (xy 32.006962 -412.470194) (xy 31.960846 -412.428313)
			(xy 31.920464 -412.380878) (xy 31.88648 -412.328669) (xy 31.859451 -412.272543) (xy 31.839822 -412.213422)
			(xy 31.827913 -412.152275) (xy 31.823922 -412.090108) (xy 28.395676 -412.090108) (xy 28.395177 -412.121256)
			(xy 28.387211 -412.183039) (xy 28.37141 -412.243297) (xy 28.348032 -412.30104) (xy 28.317463 -412.355319)
			(xy 28.280203 -412.405243) (xy 28.236866 -412.449993) (xy 28.188161 -412.488833) (xy 28.13489 -412.521126)
			(xy 28.077927 -412.546343) (xy 28.018206 -412.564067) (xy 27.956709 -412.57401) (xy 27.894446 -412.576006)
			(xy 27.832439 -412.570024) (xy 27.771705 -412.556162) (xy 27.713243 -412.534648) (xy 27.658012 -412.505834)
			(xy 27.60692 -412.470194) (xy 27.560804 -412.428313) (xy 27.520422 -412.380878) (xy 27.486438 -412.328669)
			(xy 27.459409 -412.272543) (xy 27.43978 -412.213422) (xy 27.427871 -412.152275) (xy 27.42388 -412.090108)
			(xy 0.529844 -412.090108) (xy 0.529844 -412.752286) (xy 17.883122 -412.752286) (xy 17.887193 -412.696664)
			(xy 17.899319 -412.642227) (xy 17.919242 -412.590136) (xy 17.946538 -412.541501) (xy 17.980624 -412.497358)
			(xy 18.020773 -412.458649) (xy 18.066131 -412.426198) (xy 18.115731 -412.400697) (xy 18.168515 -412.38269)
			(xy 18.223358 -412.37256) (xy 18.279092 -412.370523) (xy 18.334529 -412.376623) (xy 18.388486 -412.390729)
			(xy 18.439815 -412.412541) (xy 18.487421 -412.441595) (xy 18.530289 -412.47727) (xy 18.567506 -412.518807)
			(xy 18.598279 -412.56532) (xy 18.621951 -412.615817) (xy 18.638019 -412.669224) (xy 18.646139 -412.7244)
			(xy 18.646648 -412.752286) (xy 18.646139 -412.780172) (xy 18.638019 -412.835348) (xy 18.621951 -412.888755)
			(xy 18.598527 -412.938722) (xy 19.503896 -412.938722) (xy 19.507967 -412.8831) (xy 19.520093 -412.828663)
			(xy 19.540016 -412.776572) (xy 19.567312 -412.727937) (xy 19.601398 -412.683794) (xy 19.641547 -412.645085)
			(xy 19.686905 -412.612634) (xy 19.736505 -412.587133) (xy 19.789289 -412.569126) (xy 19.844132 -412.558996)
			(xy 19.899866 -412.556959) (xy 19.955303 -412.563059) (xy 20.00926 -412.577165) (xy 20.060589 -412.598977)
			(xy 20.108195 -412.628031) (xy 20.151063 -412.663706) (xy 20.1683 -412.682944) (xy 20.874988 -412.682944)
			(xy 20.879059 -412.627322) (xy 20.891185 -412.572885) (xy 20.911108 -412.520794) (xy 20.938404 -412.472159)
			(xy 20.97249 -412.428016) (xy 21.012639 -412.389307) (xy 21.057997 -412.356856) (xy 21.107597 -412.331355)
			(xy 21.160381 -412.313348) (xy 21.215224 -412.303218) (xy 21.270958 -412.301181) (xy 21.326395 -412.307281)
			(xy 21.380352 -412.321387) (xy 21.431681 -412.343199) (xy 21.479287 -412.372253) (xy 21.522155 -412.407928)
			(xy 21.559372 -412.449465) (xy 21.590145 -412.495978) (xy 21.613817 -412.546475) (xy 21.629885 -412.599882)
			(xy 21.638005 -412.655058) (xy 21.638514 -412.682944) (xy 21.638005 -412.71083) (xy 21.629885 -412.766006)
			(xy 21.613817 -412.819413) (xy 21.590145 -412.86991) (xy 21.559372 -412.916423) (xy 21.522155 -412.95796)
			(xy 21.479287 -412.993635) (xy 21.431681 -413.022689) (xy 21.380352 -413.044501) (xy 21.326395 -413.058607)
			(xy 21.270958 -413.064707) (xy 21.215224 -413.06267) (xy 21.160381 -413.05254) (xy 21.107597 -413.034533)
			(xy 21.057997 -413.009032) (xy 21.012639 -412.976581) (xy 20.97249 -412.937872) (xy 20.938404 -412.893729)
			(xy 20.911108 -412.845094) (xy 20.891185 -412.793003) (xy 20.879059 -412.738566) (xy 20.874988 -412.682944)
			(xy 20.1683 -412.682944) (xy 20.18828 -412.705243) (xy 20.219053 -412.751756) (xy 20.242725 -412.802253)
			(xy 20.258793 -412.85566) (xy 20.266913 -412.910836) (xy 20.267422 -412.938722) (xy 20.266913 -412.966608)
			(xy 20.258793 -413.021784) (xy 20.242725 -413.075191) (xy 20.219053 -413.125688) (xy 20.18828 -413.172201)
			(xy 20.151063 -413.213738) (xy 20.108195 -413.249413) (xy 20.060589 -413.278467) (xy 20.00926 -413.300279)
			(xy 19.955303 -413.314385) (xy 19.899866 -413.320485) (xy 19.844132 -413.318448) (xy 19.789289 -413.308318)
			(xy 19.736505 -413.290311) (xy 19.686905 -413.26481) (xy 19.641547 -413.232359) (xy 19.601398 -413.19365)
			(xy 19.567312 -413.149507) (xy 19.540016 -413.100872) (xy 19.520093 -413.048781) (xy 19.507967 -412.994344)
			(xy 19.503896 -412.938722) (xy 18.598527 -412.938722) (xy 18.598279 -412.939252) (xy 18.567506 -412.985765)
			(xy 18.530289 -413.027302) (xy 18.487421 -413.062977) (xy 18.439815 -413.092031) (xy 18.388486 -413.113843)
			(xy 18.334529 -413.127949) (xy 18.279092 -413.134049) (xy 18.223358 -413.132012) (xy 18.168515 -413.121882)
			(xy 18.115731 -413.103875) (xy 18.066131 -413.078374) (xy 18.020773 -413.045923) (xy 17.980624 -413.007214)
			(xy 17.946538 -412.963071) (xy 17.919242 -412.914436) (xy 17.899319 -412.862345) (xy 17.887193 -412.807908)
			(xy 17.883122 -412.752286) (xy 0.529844 -412.752286) (xy 0.529844 -414.985454) (xy 17.471896 -414.985454)
			(xy 17.475967 -414.929832) (xy 17.488093 -414.875395) (xy 17.508016 -414.823304) (xy 17.535312 -414.774669)
			(xy 17.569398 -414.730526) (xy 17.609547 -414.691817) (xy 17.654905 -414.659366) (xy 17.704505 -414.633865)
			(xy 17.757289 -414.615858) (xy 17.812132 -414.605728) (xy 17.867866 -414.603691) (xy 17.923303 -414.609791)
			(xy 17.97726 -414.623897) (xy 18.028589 -414.645709) (xy 18.076195 -414.674763) (xy 18.119063 -414.710438)
			(xy 18.15628 -414.751975) (xy 18.187053 -414.798488) (xy 18.210725 -414.848985) (xy 18.226793 -414.902392)
			(xy 18.234913 -414.957568) (xy 18.235422 -414.985454) (xy 19.503896 -414.985454) (xy 19.507967 -414.929832)
			(xy 19.520093 -414.875395) (xy 19.540016 -414.823304) (xy 19.567312 -414.774669) (xy 19.601398 -414.730526)
			(xy 19.641547 -414.691817) (xy 19.686905 -414.659366) (xy 19.736505 -414.633865) (xy 19.789289 -414.615858)
			(xy 19.844132 -414.605728) (xy 19.899866 -414.603691) (xy 19.955303 -414.609791) (xy 20.00926 -414.623897)
			(xy 20.060589 -414.645709) (xy 20.108195 -414.674763) (xy 20.151063 -414.710438) (xy 20.18828 -414.751975)
			(xy 20.219053 -414.798488) (xy 20.242725 -414.848985) (xy 20.258793 -414.902392) (xy 20.266913 -414.957568)
			(xy 20.267422 -414.985454) (xy 20.519896 -414.985454) (xy 20.523967 -414.929832) (xy 20.536093 -414.875395)
			(xy 20.556016 -414.823304) (xy 20.583312 -414.774669) (xy 20.617398 -414.730526) (xy 20.657547 -414.691817)
			(xy 20.702905 -414.659366) (xy 20.752505 -414.633865) (xy 20.805289 -414.615858) (xy 20.860132 -414.605728)
			(xy 20.915866 -414.603691) (xy 20.971303 -414.609791) (xy 21.02526 -414.623897) (xy 21.076589 -414.645709)
			(xy 21.124195 -414.674763) (xy 21.167063 -414.710438) (xy 21.20428 -414.751975) (xy 21.235053 -414.798488)
			(xy 21.258725 -414.848985) (xy 21.274793 -414.902392) (xy 21.282913 -414.957568) (xy 21.283422 -414.985454)
			(xy 21.282913 -415.01334) (xy 21.274793 -415.068516) (xy 21.258725 -415.121923) (xy 21.235053 -415.17242)
			(xy 21.20428 -415.218933) (xy 21.167063 -415.26047) (xy 21.124195 -415.296145) (xy 21.076589 -415.325199)
			(xy 21.02526 -415.347011) (xy 20.971303 -415.361117) (xy 20.915866 -415.367217) (xy 20.860132 -415.36518)
			(xy 20.805289 -415.35505) (xy 20.752505 -415.337043) (xy 20.702905 -415.311542) (xy 20.657547 -415.279091)
			(xy 20.617398 -415.240382) (xy 20.583312 -415.196239) (xy 20.556016 -415.147604) (xy 20.536093 -415.095513)
			(xy 20.523967 -415.041076) (xy 20.519896 -414.985454) (xy 20.267422 -414.985454) (xy 20.266913 -415.01334)
			(xy 20.258793 -415.068516) (xy 20.242725 -415.121923) (xy 20.219053 -415.17242) (xy 20.18828 -415.218933)
			(xy 20.151063 -415.26047) (xy 20.108195 -415.296145) (xy 20.060589 -415.325199) (xy 20.00926 -415.347011)
			(xy 19.955303 -415.361117) (xy 19.899866 -415.367217) (xy 19.844132 -415.36518) (xy 19.789289 -415.35505)
			(xy 19.736505 -415.337043) (xy 19.686905 -415.311542) (xy 19.641547 -415.279091) (xy 19.601398 -415.240382)
			(xy 19.567312 -415.196239) (xy 19.540016 -415.147604) (xy 19.520093 -415.095513) (xy 19.507967 -415.041076)
			(xy 19.503896 -414.985454) (xy 18.235422 -414.985454) (xy 18.234913 -415.01334) (xy 18.226793 -415.068516)
			(xy 18.210725 -415.121923) (xy 18.187053 -415.17242) (xy 18.15628 -415.218933) (xy 18.119063 -415.26047)
			(xy 18.076195 -415.296145) (xy 18.028589 -415.325199) (xy 17.97726 -415.347011) (xy 17.923303 -415.361117)
			(xy 17.867866 -415.367217) (xy 17.812132 -415.36518) (xy 17.757289 -415.35505) (xy 17.704505 -415.337043)
			(xy 17.654905 -415.311542) (xy 17.609547 -415.279091) (xy 17.569398 -415.240382) (xy 17.535312 -415.196239)
			(xy 17.508016 -415.147604) (xy 17.488093 -415.095513) (xy 17.475967 -415.041076) (xy 17.471896 -414.985454)
			(xy 0.529844 -414.985454) (xy 0.529844 -416.63493) (xy 0.53086 -416.644582) (xy 0.532492 -416.651823)
			(xy 0.539342 -416.664984) (xy 0.544322 -416.67049) (xy 1.894078 -418.020246) (xy 1.897606 -418.023563)
			(xy 1.905659 -418.028939) (xy 1.91008 -418.030914) (xy 1.919478 -418.034978)
		)
		(stroke
			(width 0)
			(type solid)
		)
		(fill yes)
		(layer "In13.Cu")
		(net "GND")
	)
	(gr_line
		(start 24.2697 -313.212734)
		(end 24.406098 -312.527696)
		(stroke
			(width 0.08255)
			(type default)
		)
		(layer "In13.Cu")
	)
	(gr_line
		(start 24.502618 -312.042048)
		(end 24.639016 -311.356756)
		(stroke
			(width 0.08255)
			(type default)
		)
		(layer "In13.Cu")
	)
	(gr_line
		(start 24.54783 -313.266836)
		(end 24.66594 -313.188096)
		(stroke
			(width 0.08255)
			(type default)
		)
		(layer "In13.Cu")
	)
	(gr_line
		(start 24.66594 -313.188096)
		(end 24.76246 -312.70194)
		(stroke
			(width 0.08255)
			(type default)
		)
		(layer "In13.Cu")
	)
	(gr_line
		(start 24.735536 -310.871108)
		(end 24.871934 -310.185308)
		(stroke
			(width 0.08255)
			(type default)
		)
		(layer "In13.Cu")
	)
	(gr_line
		(start 24.76246 -312.70194)
		(end 24.68372 -312.58383)
		(stroke
			(width 0.08255)
			(type default)
		)
		(layer "In13.Cu")
	)
	(gr_line
		(start 24.780748 -312.095896)
		(end 24.898858 -312.017156)
		(stroke
			(width 0.08255)
			(type default)
		)
		(layer "In13.Cu")
	)
	(gr_line
		(start 24.898858 -312.017156)
		(end 24.995378 -311.531)
		(stroke
			(width 0.08255)
			(type default)
		)
		(layer "In13.Cu")
	)
	(gr_line
		(start 24.995378 -311.531)
		(end 24.916384 -311.41289)
		(stroke
			(width 0.08255)
			(type default)
		)
		(layer "In13.Cu")
	)
	(gr_line
		(start 25.013412 -310.924956)
		(end 25.131776 -310.845962)
		(stroke
			(width 0.08255)
			(type default)
		)
		(layer "In13.Cu")
	)
	(gr_line
		(start 25.131776 -310.845962)
		(end 25.22855 -310.36006)
		(stroke
			(width 0.08255)
			(type default)
		)
		(layer "In13.Cu")
	)
	(gr_line
		(start 25.22855 -310.36006)
		(end 25.149556 -310.241696)
		(stroke
			(width 0.08255)
			(type default)
		)
		(layer "In13.Cu")
	)
	(gr_line
		(start 29.176218 -292.703758)
		(end 29.48559 -291.957252)
		(stroke
			(width 0.08255)
			(type default)
		)
		(layer "In13.Cu")
	)
	(gr_line
		(start 29.436822 -292.811708)
		(end 29.74594 -292.065202)
		(stroke
			(width 0.08255)
			(type default)
		)
		(layer "In13.Cu")
	)
	(gr_line
		(start 29.48559 -291.957252)
		(end 29.753306 -291.311584)
		(stroke
			(width 0.08255)
			(type default)
		)
		(layer "In13.Cu")
	)
	(gr_line
		(start 29.747718 -292.06444)
		(end 29.878782 -292.010084)
		(stroke
			(width 0.08255)
			(type default)
		)
		(layer "In13.Cu")
	)
	(gr_line
		(start 29.753306 -291.311584)
		(end 29.94279 -290.85413)
		(stroke
			(width 0.08255)
			(type default)
		)
		(layer "In13.Cu")
	)
	(gr_line
		(start 29.878782 -292.010084)
		(end 30.068774 -291.552376)
		(stroke
			(width 0.08255)
			(type default)
		)
		(layer "In13.Cu")
	)
	(gr_line
		(start 29.94279 -290.85413)
		(end 30.210252 -290.208716)
		(stroke
			(width 0.08255)
			(type default)
		)
		(layer "In13.Cu")
	)
	(gr_line
		(start 30.013656 -291.419534)
		(end 30.20314 -290.96208)
		(stroke
			(width 0.08255)
			(type default)
		)
		(layer "In13.Cu")
	)
	(gr_line
		(start 30.068774 -291.552376)
		(end 30.014418 -291.421312)
		(stroke
			(width 0.08255)
			(type default)
		)
		(layer "In13.Cu")
	)
	(gr_line
		(start 30.204918 -290.961318)
		(end 30.335982 -290.907216)
		(stroke
			(width 0.08255)
			(type default)
		)
		(layer "In13.Cu")
	)
	(gr_line
		(start 30.335982 -290.907216)
		(end 30.52572 -290.449254)
		(stroke
			(width 0.08255)
			(type default)
		)
		(layer "In13.Cu")
	)
	(gr_line
		(start 30.52572 -290.449254)
		(end 30.471364 -290.31819)
		(stroke
			(width 0.08255)
			(type default)
		)
		(layer "In13.Cu")
	)
	(gr_line
		(start 35.575748 -287.494726)
		(end 35.583368 -287.487106)
		(stroke
			(width 0.05715)
			(type default)
		)
		(layer "In13.Cu")
	)
	(gr_line
		(start 35.575748 -287.212786)
		(end 35.597846 -287.212786)
		(stroke
			(width 0.05715)
			(type default)
		)
		(layer "In13.Cu")
	)
	(gr_line
		(start 35.583368 -287.487106)
		(end 35.597846 -287.487106)
		(stroke
			(width 0.05715)
			(type default)
		)
		(layer "In13.Cu")
	)
	(gr_line
		(start 35.597846 -287.487106)
		(end 35.639756 -287.445196)
		(stroke
			(width 0.05715)
			(type default)
		)
		(layer "In13.Cu")
	)
	(gr_line
		(start 35.597846 -287.212786)
		(end 35.639756 -287.254696)
		(stroke
			(width 0.05715)
			(type default)
		)
		(layer "In13.Cu")
	)
	(gr_line
		(start 35.636454 -291.081206)
		(end 35.636454 -291.103304)
		(stroke
			(width 0.05715)
			(type default)
		)
		(layer "In13.Cu")
	)
	(gr_line
		(start 35.678364 -291.039296)
		(end 35.636454 -291.081206)
		(stroke
			(width 0.05715)
			(type default)
		)
		(layer "In13.Cu")
	)
	(gr_line
		(start 35.868864 -291.039296)
		(end 35.910774 -291.081206)
		(stroke
			(width 0.05715)
			(type default)
		)
		(layer "In13.Cu")
	)
	(gr_line
		(start 35.910774 -291.095684)
		(end 35.918394 -291.103304)
		(stroke
			(width 0.05715)
			(type default)
		)
		(layer "In13.Cu")
	)
	(gr_line
		(start 35.910774 -291.081206)
		(end 35.910774 -291.095684)
		(stroke
			(width 0.05715)
			(type default)
		)
		(layer "In13.Cu")
	)
	(gr_line
		(start 36.664646 -320.74612)
		(end 37.00907 -321.35445)
		(stroke
			(width 0.08255)
			(type default)
		)
		(layer "In13.Cu")
	)
	(gr_line
		(start 36.911534 -320.60769)
		(end 37.048694 -320.645536)
		(stroke
			(width 0.08255)
			(type default)
		)
		(layer "In13.Cu")
	)
	(gr_line
		(start 37.048694 -320.645536)
		(end 37.293042 -321.076828)
		(stroke
			(width 0.08255)
			(type default)
		)
		(layer "In13.Cu")
	)
	(gr_line
		(start 37.253164 -321.785234)
		(end 37.597588 -322.39331)
		(stroke
			(width 0.08255)
			(type default)
		)
		(layer "In13.Cu")
	)
	(gr_line
		(start 37.293042 -321.076828)
		(end 37.254942 -321.213988)
		(stroke
			(width 0.08255)
			(type default)
		)
		(layer "In13.Cu")
	)
	(gr_line
		(start 37.500052 -321.646296)
		(end 37.637212 -321.684396)
		(stroke
			(width 0.08255)
			(type default)
		)
		(layer "In13.Cu")
	)
	(gr_line
		(start 37.637212 -321.684396)
		(end 37.88156 -322.115688)
		(stroke
			(width 0.08255)
			(type default)
		)
		(layer "In13.Cu")
	)
	(gr_line
		(start 37.88156 -322.115688)
		(end 37.84346 -322.252848)
		(stroke
			(width 0.08255)
			(type default)
		)
		(layer "In13.Cu")
	)
	(gr_line
		(start 38.565836 -287.824926)
		(end 38.275006 -287.824926)
		(stroke
			(width 0.05715)
			(type default)
		)
		(layer "In13.Cu")
	)
	(gr_line
		(start 38.654736 -287.736026)
		(end 38.565836 -287.824926)
		(stroke
			(width 0.05715)
			(type default)
		)
		(layer "In13.Cu")
	)
	(gr_line
		(start 38.845236 -287.736026)
		(end 38.934136 -287.824926)
		(stroke
			(width 0.05715)
			(type default)
		)
		(layer "In13.Cu")
	)
	(gr_line
		(start 38.934136 -287.824926)
		(end 39.224966 -287.824926)
		(stroke
			(width 0.05715)
			(type default)
		)
		(layer "In13.Cu")
	)
	(gr_line
		(start 40.455342 -326.25792)
		(end 40.897302 -326.799194)
		(stroke
			(width 0.08255)
			(type default)
		)
		(layer "In13.Cu")
	)
	(gr_line
		(start 40.675306 -326.079612)
		(end 40.816784 -326.093836)
		(stroke
			(width 0.08255)
			(type default)
		)
		(layer "In13.Cu")
	)
	(gr_line
		(start 40.816784 -326.093836)
		(end 41.13022 -326.47763)
		(stroke
			(width 0.08255)
			(type default)
		)
		(layer "In13.Cu")
	)
	(gr_line
		(start 41.13022 -326.47763)
		(end 41.115996 -326.619108)
		(stroke
			(width 0.08255)
			(type default)
		)
		(layer "In13.Cu")
	)
	(gr_line
		(start 43.024806 -288.774886)
		(end 43.315636 -288.774886)
		(stroke
			(width 0.05715)
			(type default)
		)
		(layer "In13.Cu")
	)
	(gr_line
		(start 43.315636 -288.774886)
		(end 43.404536 -288.685986)
		(stroke
			(width 0.05715)
			(type default)
		)
		(layer "In13.Cu")
	)
	(gr_line
		(start 43.683936 -288.774886)
		(end 43.595036 -288.685986)
		(stroke
			(width 0.05715)
			(type default)
		)
		(layer "In13.Cu")
	)
	(gr_line
		(start 43.974766 -288.774886)
		(end 43.683936 -288.774886)
		(stroke
			(width 0.05715)
			(type default)
		)
		(layer "In13.Cu")
	)
	(gr_line
		(start 45.509942 -375.69013)
		(end 45.509942 -375.308114)
		(stroke
			(width 0.08255)
			(type default)
		)
		(layer "In13.Cu")
	)
	(gr_line
		(start 45.509942 -375.308114)
		(end 45.636942 -375.181114)
		(stroke
			(width 0.08255)
			(type default)
		)
		(layer "In13.Cu")
	)
	(gr_line
		(start 45.509942 -374.772174)
		(end 45.636942 -374.899174)
		(stroke
			(width 0.08255)
			(type default)
		)
		(layer "In13.Cu")
	)
	(gr_line
		(start 45.509942 -374.390158)
		(end 45.509942 -374.772174)
		(stroke
			(width 0.08255)
			(type default)
		)
		(layer "In13.Cu")
	)
	(gr_line
		(start 50.140362 -362.64596)
		(end 50.138584 -362.638848)
		(stroke
			(width 0.08255)
			(type default)
		)
		(layer "In13.Cu")
	)
	(gr_line
		(start 52.998878 -343.929462)
		(end 53.053234 -343.798144)
		(stroke
			(width 0.08255)
			(type default)
		)
		(layer "In13.Cu")
	)
	(gr_line
		(start 53.188616 -344.38717)
		(end 52.998878 -343.929462)
		(stroke
			(width 0.08255)
			(type default)
		)
		(layer "In13.Cu")
	)
	(gr_line
		(start 53.31968 -344.44178)
		(end 53.188616 -344.38717)
		(stroke
			(width 0.08255)
			(type default)
		)
		(layer "In13.Cu")
	)
	(gr_line
		(start 53.455824 -345.032584)
		(end 53.51018 -344.901266)
		(stroke
			(width 0.08255)
			(type default)
		)
		(layer "In13.Cu")
	)
	(gr_line
		(start 53.581808 -344.334338)
		(end 53.314346 -343.68867)
		(stroke
			(width 0.08255)
			(type default)
		)
		(layer "In13.Cu")
	)
	(gr_line
		(start 53.645562 -345.490292)
		(end 53.455824 -345.032584)
		(stroke
			(width 0.08255)
			(type default)
		)
		(layer "In13.Cu")
	)
	(gr_line
		(start 53.776626 -345.544648)
		(end 53.645562 -345.490292)
		(stroke
			(width 0.08255)
			(type default)
		)
		(layer "In13.Cu")
	)
	(gr_line
		(start 53.912516 -346.135706)
		(end 53.966872 -346.004388)
		(stroke
			(width 0.08255)
			(type default)
		)
		(layer "In13.Cu")
	)
	(gr_line
		(start 54.038754 -345.43746)
		(end 53.771292 -344.791792)
		(stroke
			(width 0.08255)
			(type default)
		)
		(layer "In13.Cu")
	)
	(gr_line
		(start 54.102508 -346.593414)
		(end 53.912516 -346.135706)
		(stroke
			(width 0.08255)
			(type default)
		)
		(layer "In13.Cu")
	)
	(gr_line
		(start 54.233572 -346.64777)
		(end 54.102508 -346.593414)
		(stroke
			(width 0.08255)
			(type default)
		)
		(layer "In13.Cu")
	)
	(gr_line
		(start 54.32298 -348.198186)
		(end 54.32298 -347.702886)
		(stroke
			(width 0.08255)
			(type default)
		)
		(layer "In13.Cu")
	)
	(gr_line
		(start 54.32298 -347.702886)
		(end 54.42331 -347.602556)
		(stroke
			(width 0.08255)
			(type default)
		)
		(layer "In13.Cu")
	)
	(gr_line
		(start 54.42331 -348.298516)
		(end 54.32298 -348.198186)
		(stroke
			(width 0.08255)
			(type default)
		)
		(layer "In13.Cu")
	)
	(gr_line
		(start 54.4957 -346.540582)
		(end 54.228238 -345.894914)
		(stroke
			(width 0.08255)
			(type default)
		)
		(layer "In13.Cu")
	)
	(gr_line
		(start 54.70652 -348.299786)
		(end 54.70652 -347.601286)
		(stroke
			(width 0.08255)
			(type default)
		)
		(layer "In13.Cu")
	)
	(gr_line
		(start 58.012076 -371.019832)
		(end 57.721246 -371.310662)
		(stroke
			(width 0.08255)
			(type default)
		)
		(layer "In13.Cu")
	)
	(gr_line
		(start 58.012076 -370.737892)
		(end 57.721246 -370.447062)
		(stroke
			(width 0.08255)
			(type default)
		)
		(layer "In13.Cu")
	)
	(gr_line
		(start 58.761122 -358.631744)
		(end 58.84545 -359.120186)
		(stroke
			(width 0.08255)
			(type default)
		)
		(layer "In13.Cu")
	)
	(gr_line
		(start 58.843164 -358.515412)
		(end 58.761122 -358.631744)
		(stroke
			(width 0.08255)
			(type default)
		)
		(layer "In13.Cu")
	)
	(gr_line
		(start 58.84545 -359.120186)
		(end 58.961782 -359.201974)
		(stroke
			(width 0.08255)
			(type default)
		)
		(layer "In13.Cu")
	)
	(gr_line
		(start 58.964322 -359.808272)
		(end 59.04865 -360.296714)
		(stroke
			(width 0.08255)
			(type default)
		)
		(layer "In13.Cu")
	)
	(gr_line
		(start 59.046364 -359.69194)
		(end 58.964322 -359.808272)
		(stroke
			(width 0.08255)
			(type default)
		)
		(layer "In13.Cu")
	)
	(gr_line
		(start 59.04865 -360.296714)
		(end 59.164982 -360.378502)
		(stroke
			(width 0.08255)
			(type default)
		)
		(layer "In13.Cu")
	)
	(gr_line
		(start 59.122056 -358.46639)
		(end 59.240928 -359.154984)
		(stroke
			(width 0.08255)
			(type default)
		)
		(layer "In13.Cu")
	)
	(gr_line
		(start 59.325256 -359.642918)
		(end 59.444128 -360.331512)
		(stroke
			(width 0.08255)
			(type default)
		)
		(layer "In13.Cu")
	)
	(gr_line
		(start 59.669934 -364.335568)
		(end 59.669934 -364.335314)
		(stroke
			(width 0.08255)
			(type default)
		)
		(layer "In13.Cu")
	)
	(gr_line
		(start 59.95035 -364.30458)
		(end 59.95035 -364.304834)
		(stroke
			(width 0.08255)
			(type default)
		)
		(layer "In13.Cu")
	)
	(gr_line
		(start 59.983116 -367.187226)
		(end 59.982862 -367.186972)
		(stroke
			(width 0.08255)
			(type default)
		)
		(layer "In13.Cu")
	)
	(gr_line
		(start 60.263278 -367.156238)
		(end 60.265056 -367.171478)
		(stroke
			(width 0.08255)
			(type default)
		)
		(layer "In13.Cu")
	)
	(gr_line
		(start 60.265056 -367.171478)
		(end 60.265056 -367.187226)
		(stroke
			(width 0.08255)
			(type default)
		)
		(layer "In13.Cu")
	)
	(gr_line
		(start 95.274638 -27.049476)
		(end 94.981268 -27.342846)
		(stroke
			(width 0.08255)
			(type default)
		)
		(layer "In13.Cu")
	)
	(gr_line
		(start 103.390192 -35.366198)
		(end 103.390192 -34.870898)
		(stroke
			(width 0.08255)
			(type default)
		)
		(layer "In13.Cu")
	)
	(gr_line
		(start 103.390192 -34.870898)
		(end 103.503222 -34.757868)
		(stroke
			(width 0.08255)
			(type default)
		)
		(layer "In13.Cu")
	)
	(gr_line
		(start 103.390192 -34.146998)
		(end 103.390192 -33.651698)
		(stroke
			(width 0.08255)
			(type default)
		)
		(layer "In13.Cu")
	)
	(gr_line
		(start 103.390192 -33.651698)
		(end 103.503222 -33.538668)
		(stroke
			(width 0.08255)
			(type default)
		)
		(layer "In13.Cu")
	)
	(gr_line
		(start 103.390192 -32.927798)
		(end 103.390192 -32.432498)
		(stroke
			(width 0.08255)
			(type default)
		)
		(layer "In13.Cu")
	)
	(gr_line
		(start 103.390192 -32.432498)
		(end 103.503222 -32.319468)
		(stroke
			(width 0.08255)
			(type default)
		)
		(layer "In13.Cu")
	)
	(gr_line
		(start 103.503222 -35.479228)
		(end 103.390192 -35.366198)
		(stroke
			(width 0.08255)
			(type default)
		)
		(layer "In13.Cu")
	)
	(gr_line
		(start 103.503222 -34.260028)
		(end 103.390192 -34.146998)
		(stroke
			(width 0.08255)
			(type default)
		)
		(layer "In13.Cu")
	)
	(gr_line
		(start 103.503222 -33.040828)
		(end 103.390192 -32.927798)
		(stroke
			(width 0.08255)
			(type default)
		)
		(layer "In13.Cu")
	)
	(gr_line
		(start 103.691182 -36.56711)
		(end 103.73741 -36.413948)
		(stroke
			(width 0.08255)
			(type default)
		)
		(layer "In13.Cu")
	)
	(gr_line
		(start 103.924862 -37.004244)
		(end 103.691182 -36.56711)
		(stroke
			(width 0.08255)
			(type default)
		)
		(layer "In13.Cu")
	)
	(gr_line
		(start 104.078024 -37.050472)
		(end 103.924862 -37.004244)
		(stroke
			(width 0.08255)
			(type default)
		)
		(layer "In13.Cu")
	)
	(gr_line
		(start 104.266238 -37.642292)
		(end 104.312466 -37.48913)
		(stroke
			(width 0.08255)
			(type default)
		)
		(layer "In13.Cu")
	)
	(gr_line
		(start 104.499918 -38.079426)
		(end 104.266238 -37.642292)
		(stroke
			(width 0.08255)
			(type default)
		)
		(layer "In13.Cu")
	)
	(gr_line
		(start 104.65308 -38.125654)
		(end 104.499918 -38.079426)
		(stroke
			(width 0.08255)
			(type default)
		)
		(layer "In13.Cu")
	)
	(gr_line
		(start 104.841294 -38.717474)
		(end 104.887522 -38.564312)
		(stroke
			(width 0.08255)
			(type default)
		)
		(layer "In13.Cu")
	)
	(gr_line
		(start 105.074974 -39.154608)
		(end 104.841294 -38.717474)
		(stroke
			(width 0.08255)
			(type default)
		)
		(layer "In13.Cu")
	)
	(gr_line
		(start 105.227882 -39.200836)
		(end 105.074974 -39.154608)
		(stroke
			(width 0.08255)
			(type default)
		)
		(layer "In13.Cu")
	)
	(gr_line
		(start 105.41635 -39.792656)
		(end 105.462578 -39.639494)
		(stroke
			(width 0.08255)
			(type default)
		)
		(layer "In13.Cu")
	)
	(gr_line
		(start 105.65003 -40.22979)
		(end 105.41635 -39.792656)
		(stroke
			(width 0.08255)
			(type default)
		)
		(layer "In13.Cu")
	)
	(gr_line
		(start 105.802938 -40.276018)
		(end 105.65003 -40.22979)
		(stroke
			(width 0.08255)
			(type default)
		)
		(layer "In13.Cu")
	)
	(gr_line
		(start 105.991406 -40.867838)
		(end 106.037634 -40.714676)
		(stroke
			(width 0.08255)
			(type default)
		)
		(layer "In13.Cu")
	)
	(gr_line
		(start 106.225086 -41.304972)
		(end 105.991406 -40.867838)
		(stroke
			(width 0.08255)
			(type default)
		)
		(layer "In13.Cu")
	)
	(gr_line
		(start 106.377994 -41.3512)
		(end 106.225086 -41.304972)
		(stroke
			(width 0.08255)
			(type default)
		)
		(layer "In13.Cu")
	)
	(gr_line
		(start 106.566208 -41.94302)
		(end 106.61269 -41.789858)
		(stroke
			(width 0.08255)
			(type default)
		)
		(layer "In13.Cu")
	)
	(gr_line
		(start 106.800142 -42.380154)
		(end 106.566208 -41.94302)
		(stroke
			(width 0.08255)
			(type default)
		)
		(layer "In13.Cu")
	)
	(gr_line
		(start 106.95305 -42.426382)
		(end 106.800142 -42.380154)
		(stroke
			(width 0.08255)
			(type default)
		)
		(layer "In13.Cu")
	)
	(gr_line
		(start 106.954828 -42.42689)
		(end 106.954574 -42.42689)
		(stroke
			(width 0.08255)
			(type default)
		)
		(layer "In13.Cu")
	)
	(gr_line
		(start 110.470696 -94.058486)
		(end 110.179866 -94.349316)
		(stroke
			(width 0.08255)
			(type default)
		)
		(layer "In13.Cu")
	)
	(gr_line
		(start 117.0813 -86.495382)
		(end 117.374416 -86.788498)
		(stroke
			(width 0.08255)
			(type default)
		)
		(layer "In13.Cu")
	)
	(gr_line
		(start 117.0813 -82.49539)
		(end 117.374416 -82.788506)
		(stroke
			(width 0.08255)
			(type default)
		)
		(layer "In13.Cu")
	)
	(gr_line
		(start 117.8433 -89.358978)
		(end 117.8433 -89.35847)
		(stroke
			(width 0.08255)
			(type default)
		)
		(layer "In13.Cu")
	)
	(gr_line
		(start 117.8433 -89.35847)
		(end 118.136416 -89.065354)
		(stroke
			(width 0.08255)
			(type default)
		)
		(layer "In13.Cu")
	)
	(gr_line
		(start 117.8433 -88.495378)
		(end 118.130066 -88.782144)
		(stroke
			(width 0.08255)
			(type default)
		)
		(layer "In13.Cu")
	)
	(gr_line
		(start 118.130066 -88.782144)
		(end 118.137686 -88.782144)
		(stroke
			(width 0.08255)
			(type default)
		)
		(layer "In13.Cu")
	)
	(gr_line
		(start 156.857446 -40.168322)
		(end 156.857446 -40.008302)
		(stroke
			(width 0.08255)
			(type default)
		)
		(layer "In13.Cu")
	)
	(gr_line
		(start 156.857446 -40.008302)
		(end 157.207966 -39.657782)
		(stroke
			(width 0.08255)
			(type default)
		)
		(layer "In13.Cu")
	)
	(gr_line
		(start 157.207966 -39.657782)
		(end 157.367986 -39.657782)
		(stroke
			(width 0.08255)
			(type default)
		)
		(layer "In13.Cu")
	)
	(gr_line
		(start 158.879032 -37.224208)
		(end 158.879032 -37.064188)
		(stroke
			(width 0.08255)
			(type default)
		)
		(layer "In13.Cu")
	)
	(gr_line
		(start 158.879032 -37.064188)
		(end 159.229552 -36.713668)
		(stroke
			(width 0.08255)
			(type default)
		)
		(layer "In13.Cu")
	)
	(gr_line
		(start 159.229552 -36.713668)
		(end 159.389572 -36.713668)
		(stroke
			(width 0.08255)
			(type default)
		)
		(layer "In13.Cu")
	)
	(gr_line
		(start 159.36849 -27.055826)
		(end 159.08147 -27.342846)
		(stroke
			(width 0.08255)
			(type default)
		)
		(layer "In13.Cu")
	)
	(gr_line
		(start 159.37611 -27.055826)
		(end 159.36849 -27.055826)
		(stroke
			(width 0.08255)
			(type default)
		)
		(layer "In13.Cu")
	)
	(gr_line
		(start 159.627062 -35.68065)
		(end 159.627062 -35.18535)
		(stroke
			(width 0.08255)
			(type default)
		)
		(layer "In13.Cu")
	)
	(gr_line
		(start 159.627062 -35.18535)
		(end 159.740092 -35.07232)
		(stroke
			(width 0.08255)
			(type default)
		)
		(layer "In13.Cu")
	)
	(gr_line
		(start 159.627062 -34.46145)
		(end 159.627062 -33.96615)
		(stroke
			(width 0.08255)
			(type default)
		)
		(layer "In13.Cu")
	)
	(gr_line
		(start 159.627062 -33.96615)
		(end 159.740092 -33.85312)
		(stroke
			(width 0.08255)
			(type default)
		)
		(layer "In13.Cu")
	)
	(gr_line
		(start 159.627062 -33.24225)
		(end 159.627062 -32.74695)
		(stroke
			(width 0.08255)
			(type default)
		)
		(layer "In13.Cu")
	)
	(gr_line
		(start 159.627062 -32.74695)
		(end 159.740092 -32.63392)
		(stroke
			(width 0.08255)
			(type default)
		)
		(layer "In13.Cu")
	)
	(gr_line
		(start 159.627062 -32.02305)
		(end 159.627062 -31.52775)
		(stroke
			(width 0.08255)
			(type default)
		)
		(layer "In13.Cu")
	)
	(gr_line
		(start 159.627062 -31.52775)
		(end 159.740092 -31.41472)
		(stroke
			(width 0.08255)
			(type default)
		)
		(layer "In13.Cu")
	)
	(gr_line
		(start 159.627062 -30.80385)
		(end 159.627062 -30.30855)
		(stroke
			(width 0.08255)
			(type default)
		)
		(layer "In13.Cu")
	)
	(gr_line
		(start 159.627062 -30.30855)
		(end 159.740092 -30.19552)
		(stroke
			(width 0.08255)
			(type default)
		)
		(layer "In13.Cu")
	)
	(gr_line
		(start 159.627062 -29.58465)
		(end 159.627062 -29.08935)
		(stroke
			(width 0.08255)
			(type default)
		)
		(layer "In13.Cu")
	)
	(gr_line
		(start 159.627062 -29.08935)
		(end 159.740092 -28.97632)
		(stroke
			(width 0.08255)
			(type default)
		)
		(layer "In13.Cu")
	)
	(gr_line
		(start 159.627062 -28.36545)
		(end 159.627062 -27.87015)
		(stroke
			(width 0.08255)
			(type default)
		)
		(layer "In13.Cu")
	)
	(gr_line
		(start 159.627062 -27.87015)
		(end 159.740092 -27.75712)
		(stroke
			(width 0.08255)
			(type default)
		)
		(layer "In13.Cu")
	)
	(gr_line
		(start 159.740092 -35.79368)
		(end 159.627062 -35.68065)
		(stroke
			(width 0.08255)
			(type default)
		)
		(layer "In13.Cu")
	)
	(gr_line
		(start 159.740092 -34.57448)
		(end 159.627062 -34.46145)
		(stroke
			(width 0.08255)
			(type default)
		)
		(layer "In13.Cu")
	)
	(gr_line
		(start 159.740092 -33.35528)
		(end 159.627062 -33.24225)
		(stroke
			(width 0.08255)
			(type default)
		)
		(layer "In13.Cu")
	)
	(gr_line
		(start 159.740092 -32.13608)
		(end 159.627062 -32.02305)
		(stroke
			(width 0.08255)
			(type default)
		)
		(layer "In13.Cu")
	)
	(gr_line
		(start 159.740092 -30.91688)
		(end 159.627062 -30.80385)
		(stroke
			(width 0.08255)
			(type default)
		)
		(layer "In13.Cu")
	)
	(gr_line
		(start 159.740092 -29.69768)
		(end 159.627062 -29.58465)
		(stroke
			(width 0.08255)
			(type default)
		)
		(layer "In13.Cu")
	)
	(gr_line
		(start 159.740092 -28.47848)
		(end 159.627062 -28.36545)
		(stroke
			(width 0.08255)
			(type default)
		)
		(layer "In13.Cu")
	)
	(gr_line
		(start 176.100486 -79.625952)
		(end 176.213516 -79.512922)
		(stroke
			(width 0.08255)
			(type default)
		)
		(layer "In13.Cu")
	)
	(gr_line
		(start 176.213516 -79.512922)
		(end 176.708816 -79.512922)
		(stroke
			(width 0.08255)
			(type default)
		)
		(layer "In13.Cu")
	)
	(gr_line
		(start 176.708816 -79.512922)
		(end 176.821846 -79.625952)
		(stroke
			(width 0.08255)
			(type default)
		)
		(layer "In13.Cu")
	)
	(gr_line
		(start 177.319686 -79.625952)
		(end 177.432716 -79.512922)
		(stroke
			(width 0.08255)
			(type default)
		)
		(layer "In13.Cu")
	)
	(gr_line
		(start 177.432716 -79.512922)
		(end 177.928016 -79.512922)
		(stroke
			(width 0.08255)
			(type default)
		)
		(layer "In13.Cu")
	)
	(gr_line
		(start 177.928016 -79.512922)
		(end 178.041046 -79.625952)
		(stroke
			(width 0.08255)
			(type default)
		)
		(layer "In13.Cu")
	)
	(gr_line
		(start 178.538886 -79.625952)
		(end 178.651916 -79.512922)
		(stroke
			(width 0.08255)
			(type default)
		)
		(layer "In13.Cu")
	)
	(gr_line
		(start 178.651916 -79.512922)
		(end 179.147216 -79.512922)
		(stroke
			(width 0.08255)
			(type default)
		)
		(layer "In13.Cu")
	)
	(gr_line
		(start 179.147216 -79.512922)
		(end 179.260246 -79.625952)
		(stroke
			(width 0.08255)
			(type default)
		)
		(layer "In13.Cu")
	)
	(gr_line
		(start 179.38877 -48.586136)
		(end 179.389786 -48.585882)
		(stroke
			(width 0.08255)
			(type default)
		)
		(layer "In13.Cu")
	)
	(gr_line
		(start 179.389786 -48.585882)
		(end 179.395882 -48.579278)
		(stroke
			(width 0.08255)
			(type default)
		)
		(layer "In13.Cu")
	)
	(gr_line
		(start 179.395374 -48.572674)
		(end 179.396136 -48.552354)
		(stroke
			(width 0.08255)
			(type default)
		)
		(layer "In13.Cu")
	)
	(gr_line
		(start 179.395882 -48.579278)
		(end 179.395374 -48.572674)
		(stroke
			(width 0.08255)
			(type default)
		)
		(layer "In13.Cu")
	)
	(gr_line
		(start 179.670202 -48.569118)
		(end 179.678076 -48.562006)
		(stroke
			(width 0.08255)
			(type default)
		)
		(layer "In13.Cu")
	)
	(gr_line
		(start 179.758086 -79.625952)
		(end 179.871116 -79.512922)
		(stroke
			(width 0.08255)
			(type default)
		)
		(layer "In13.Cu")
	)
	(gr_line
		(start 179.871116 -79.512922)
		(end 180.366416 -79.512922)
		(stroke
			(width 0.08255)
			(type default)
		)
		(layer "In13.Cu")
	)
	(gr_line
		(start 180.366416 -79.512922)
		(end 180.479446 -79.625952)
		(stroke
			(width 0.08255)
			(type default)
		)
		(layer "In13.Cu")
	)
	(gr_line
		(start 180.977286 -79.625952)
		(end 181.090316 -79.512922)
		(stroke
			(width 0.08255)
			(type default)
		)
		(layer "In13.Cu")
	)
	(gr_line
		(start 181.090316 -79.512922)
		(end 181.585616 -79.512922)
		(stroke
			(width 0.08255)
			(type default)
		)
		(layer "In13.Cu")
	)
	(gr_line
		(start 181.533038 -41.429686)
		(end 181.533038 -41.269666)
		(stroke
			(width 0.08255)
			(type default)
		)
		(layer "In13.Cu")
	)
	(gr_line
		(start 181.533038 -41.269666)
		(end 181.883558 -40.919146)
		(stroke
			(width 0.08255)
			(type default)
		)
		(layer "In13.Cu")
	)
	(gr_line
		(start 181.585616 -79.512922)
		(end 181.698646 -79.625952)
		(stroke
			(width 0.08255)
			(type default)
		)
		(layer "In13.Cu")
	)
	(gr_line
		(start 181.732428 -41.630854)
		(end 181.814978 -41.548304)
		(stroke
			(width 0.08255)
			(type default)
		)
		(layer "In13.Cu")
	)
	(gr_line
		(start 181.815232 -41.548304)
		(end 181.814978 -41.548304)
		(stroke
			(width 0.08255)
			(type default)
		)
		(layer "In13.Cu")
	)
	(gr_line
		(start 181.815232 -41.548304)
		(end 182.244746 -41.118536)
		(stroke
			(width 0.08255)
			(type default)
		)
		(layer "In13.Cu")
	)
	(gr_line
		(start 181.883558 -40.919146)
		(end 182.043832 -40.919146)
		(stroke
			(width 0.08255)
			(type default)
		)
		(layer "In13.Cu")
	)
	(gr_line
		(start 182.395368 -40.56761)
		(end 182.395368 -40.407336)
		(stroke
			(width 0.08255)
			(type default)
		)
		(layer "In13.Cu")
	)
	(gr_line
		(start 182.395368 -40.407336)
		(end 182.745888 -40.056816)
		(stroke
			(width 0.08255)
			(type default)
		)
		(layer "In13.Cu")
	)
	(gr_line
		(start 182.594758 -40.768524)
		(end 183.107076 -40.256206)
		(stroke
			(width 0.08255)
			(type default)
		)
		(layer "In13.Cu")
	)
	(gr_line
		(start 182.745888 -40.056816)
		(end 182.906162 -40.056816)
		(stroke
			(width 0.08255)
			(type default)
		)
		(layer "In13.Cu")
	)
	(gr_line
		(start 183.257698 -39.70528)
		(end 183.257698 -39.545006)
		(stroke
			(width 0.08255)
			(type default)
		)
		(layer "In13.Cu")
	)
	(gr_line
		(start 183.257698 -39.545006)
		(end 183.608218 -39.194486)
		(stroke
			(width 0.08255)
			(type default)
		)
		(layer "In13.Cu")
	)
	(gr_line
		(start 183.457088 -39.906194)
		(end 183.969406 -39.393876)
		(stroke
			(width 0.08255)
			(type default)
		)
		(layer "In13.Cu")
	)
	(gr_line
		(start 183.608218 -39.194486)
		(end 183.768492 -39.194486)
		(stroke
			(width 0.08255)
			(type default)
		)
		(layer "In13.Cu")
	)
	(gr_line
		(start 184.120028 -38.842696)
		(end 184.120028 -38.682676)
		(stroke
			(width 0.08255)
			(type default)
		)
		(layer "In13.Cu")
	)
	(gr_line
		(start 184.120028 -38.682676)
		(end 184.470548 -38.332156)
		(stroke
			(width 0.08255)
			(type default)
		)
		(layer "In13.Cu")
	)
	(gr_line
		(start 184.319418 -39.043864)
		(end 184.831736 -38.531546)
		(stroke
			(width 0.08255)
			(type default)
		)
		(layer "In13.Cu")
	)
	(gr_line
		(start 184.470548 -38.332156)
		(end 184.630568 -38.332156)
		(stroke
			(width 0.08255)
			(type default)
		)
		(layer "In13.Cu")
	)
	(gr_line
		(start 185.368438 -27.055826)
		(end 185.081418 -27.342846)
		(stroke
			(width 0.08255)
			(type default)
		)
		(layer "In13.Cu")
	)
	(gr_line
		(start 185.374788 -26.772616)
		(end 185.081418 -26.479246)
		(stroke
			(width 0.08255)
			(type default)
		)
		(layer "In13.Cu")
	)
	(gr_line
		(start 185.376058 -27.055826)
		(end 185.368438 -27.055826)
		(stroke
			(width 0.08255)
			(type default)
		)
		(layer "In13.Cu")
	)
	(gr_line
		(start 185.617612 -34.407094)
		(end 185.617612 -33.911794)
		(stroke
			(width 0.08255)
			(type default)
		)
		(layer "In13.Cu")
	)
	(gr_line
		(start 185.617612 -33.911794)
		(end 185.730642 -33.798764)
		(stroke
			(width 0.08255)
			(type default)
		)
		(layer "In13.Cu")
	)
	(gr_line
		(start 185.617612 -33.187894)
		(end 185.617612 -32.692594)
		(stroke
			(width 0.08255)
			(type default)
		)
		(layer "In13.Cu")
	)
	(gr_line
		(start 185.617612 -32.692594)
		(end 185.730642 -32.579564)
		(stroke
			(width 0.08255)
			(type default)
		)
		(layer "In13.Cu")
	)
	(gr_line
		(start 185.617612 -31.968694)
		(end 185.617612 -31.473394)
		(stroke
			(width 0.08255)
			(type default)
		)
		(layer "In13.Cu")
	)
	(gr_line
		(start 185.617612 -31.473394)
		(end 185.730642 -31.360364)
		(stroke
			(width 0.08255)
			(type default)
		)
		(layer "In13.Cu")
	)
	(gr_line
		(start 185.617612 -30.749494)
		(end 185.617612 -30.254194)
		(stroke
			(width 0.08255)
			(type default)
		)
		(layer "In13.Cu")
	)
	(gr_line
		(start 185.617612 -30.254194)
		(end 185.730642 -30.141164)
		(stroke
			(width 0.08255)
			(type default)
		)
		(layer "In13.Cu")
	)
	(gr_line
		(start 185.617612 -29.530294)
		(end 185.617612 -29.034994)
		(stroke
			(width 0.08255)
			(type default)
		)
		(layer "In13.Cu")
	)
	(gr_line
		(start 185.617612 -29.034994)
		(end 185.730642 -28.921964)
		(stroke
			(width 0.08255)
			(type default)
		)
		(layer "In13.Cu")
	)
	(gr_line
		(start 185.617612 -28.311094)
		(end 185.617612 -27.815794)
		(stroke
			(width 0.08255)
			(type default)
		)
		(layer "In13.Cu")
	)
	(gr_line
		(start 185.617612 -27.815794)
		(end 185.730642 -27.702764)
		(stroke
			(width 0.08255)
			(type default)
		)
		(layer "In13.Cu")
	)
	(gr_line
		(start 185.730642 -34.520124)
		(end 185.617612 -34.407094)
		(stroke
			(width 0.08255)
			(type default)
		)
		(layer "In13.Cu")
	)
	(gr_line
		(start 185.730642 -33.300924)
		(end 185.617612 -33.187894)
		(stroke
			(width 0.08255)
			(type default)
		)
		(layer "In13.Cu")
	)
	(gr_line
		(start 185.730642 -32.081724)
		(end 185.617612 -31.968694)
		(stroke
			(width 0.08255)
			(type default)
		)
		(layer "In13.Cu")
	)
	(gr_line
		(start 185.730642 -30.862524)
		(end 185.617612 -30.749494)
		(stroke
			(width 0.08255)
			(type default)
		)
		(layer "In13.Cu")
	)
	(gr_line
		(start 185.730642 -29.643324)
		(end 185.617612 -29.530294)
		(stroke
			(width 0.08255)
			(type default)
		)
		(layer "In13.Cu")
	)
	(gr_line
		(start 185.730642 -28.424124)
		(end 185.617612 -28.311094)
		(stroke
			(width 0.08255)
			(type default)
		)
		(layer "In13.Cu")
	)
	(gr_line
		(start 186.013852 -34.521394)
		(end 186.013852 -33.797494)
		(stroke
			(width 0.08255)
			(type default)
		)
		(layer "In13.Cu")
	)
	(gr_line
		(start 186.013852 -33.302194)
		(end 186.013852 -32.578294)
		(stroke
			(width 0.08255)
			(type default)
		)
		(layer "In13.Cu")
	)
	(gr_line
		(start 186.013852 -32.082994)
		(end 186.013852 -31.359094)
		(stroke
			(width 0.08255)
			(type default)
		)
		(layer "In13.Cu")
	)
	(gr_line
		(start 186.013852 -30.863794)
		(end 186.013852 -30.139894)
		(stroke
			(width 0.08255)
			(type default)
		)
		(layer "In13.Cu")
	)
	(gr_line
		(start 186.013852 -29.644594)
		(end 186.013852 -28.920694)
		(stroke
			(width 0.08255)
			(type default)
		)
		(layer "In13.Cu")
	)
	(gr_line
		(start 186.013852 -28.425394)
		(end 186.013852 -27.701494)
		(stroke
			(width 0.08255)
			(type default)
		)
		(layer "In13.Cu")
	)
	(gr_line
		(start 210.0326 -38.537388)
		(end 210.0326 -38.377368)
		(stroke
			(width 0.08255)
			(type default)
		)
		(layer "In13.Cu")
	)
	(gr_line
		(start 210.0326 -38.377368)
		(end 210.38312 -38.026848)
		(stroke
			(width 0.08255)
			(type default)
		)
		(layer "In13.Cu")
	)
	(gr_line
		(start 210.38312 -38.026848)
		(end 210.54314 -38.026848)
		(stroke
			(width 0.08255)
			(type default)
		)
		(layer "In13.Cu")
	)
	(gr_line
		(start 210.89493 -37.675058)
		(end 210.89493 -37.515038)
		(stroke
			(width 0.08255)
			(type default)
		)
		(layer "In13.Cu")
	)
	(gr_line
		(start 210.89493 -37.515038)
		(end 211.24545 -37.164518)
		(stroke
			(width 0.08255)
			(type default)
		)
		(layer "In13.Cu")
	)
	(gr_line
		(start 211.24545 -37.164518)
		(end 211.40547 -37.164518)
		(stroke
			(width 0.08255)
			(type default)
		)
		(layer "In13.Cu")
	)
	(gr_line
		(start 211.370672 -27.05354)
		(end 211.081366 -27.342846)
		(stroke
			(width 0.08255)
			(type default)
		)
		(layer "In13.Cu")
	)
	(gr_line
		(start 211.37372 -27.05354)
		(end 211.370672 -27.05354)
		(stroke
			(width 0.08255)
			(type default)
		)
		(layer "In13.Cu")
	)
	(gr_line
		(start 211.64296 -35.663886)
		(end 211.64296 -35.168586)
		(stroke
			(width 0.08255)
			(type default)
		)
		(layer "In13.Cu")
	)
	(gr_line
		(start 211.64296 -35.168586)
		(end 211.75599 -35.055556)
		(stroke
			(width 0.08255)
			(type default)
		)
		(layer "In13.Cu")
	)
	(gr_line
		(start 211.64296 -34.444686)
		(end 211.64296 -33.949386)
		(stroke
			(width 0.08255)
			(type default)
		)
		(layer "In13.Cu")
	)
	(gr_line
		(start 211.64296 -33.949386)
		(end 211.75599 -33.836356)
		(stroke
			(width 0.08255)
			(type default)
		)
		(layer "In13.Cu")
	)
	(gr_line
		(start 211.64296 -33.225486)
		(end 211.64296 -32.730186)
		(stroke
			(width 0.08255)
			(type default)
		)
		(layer "In13.Cu")
	)
	(gr_line
		(start 211.64296 -32.730186)
		(end 211.75599 -32.617156)
		(stroke
			(width 0.08255)
			(type default)
		)
		(layer "In13.Cu")
	)
	(gr_line
		(start 211.64296 -32.006286)
		(end 211.64296 -31.510986)
		(stroke
			(width 0.08255)
			(type default)
		)
		(layer "In13.Cu")
	)
	(gr_line
		(start 211.64296 -31.510986)
		(end 211.75599 -31.397956)
		(stroke
			(width 0.08255)
			(type default)
		)
		(layer "In13.Cu")
	)
	(gr_line
		(start 211.64296 -30.787086)
		(end 211.64296 -30.291786)
		(stroke
			(width 0.08255)
			(type default)
		)
		(layer "In13.Cu")
	)
	(gr_line
		(start 211.64296 -30.291786)
		(end 211.75599 -30.178756)
		(stroke
			(width 0.08255)
			(type default)
		)
		(layer "In13.Cu")
	)
	(gr_line
		(start 211.64296 -29.567886)
		(end 211.64296 -29.072586)
		(stroke
			(width 0.08255)
			(type default)
		)
		(layer "In13.Cu")
	)
	(gr_line
		(start 211.64296 -29.072586)
		(end 211.75599 -28.959556)
		(stroke
			(width 0.08255)
			(type default)
		)
		(layer "In13.Cu")
	)
	(gr_line
		(start 211.64296 -28.348686)
		(end 211.64296 -27.853386)
		(stroke
			(width 0.08255)
			(type default)
		)
		(layer "In13.Cu")
	)
	(gr_line
		(start 211.64296 -27.853386)
		(end 211.75599 -27.740356)
		(stroke
			(width 0.08255)
			(type default)
		)
		(layer "In13.Cu")
	)
	(gr_line
		(start 211.75599 -35.776916)
		(end 211.64296 -35.663886)
		(stroke
			(width 0.08255)
			(type default)
		)
		(layer "In13.Cu")
	)
	(gr_line
		(start 211.75599 -34.557716)
		(end 211.64296 -34.444686)
		(stroke
			(width 0.08255)
			(type default)
		)
		(layer "In13.Cu")
	)
	(gr_line
		(start 211.75599 -33.338516)
		(end 211.64296 -33.225486)
		(stroke
			(width 0.08255)
			(type default)
		)
		(layer "In13.Cu")
	)
	(gr_line
		(start 211.75599 -32.119316)
		(end 211.64296 -32.006286)
		(stroke
			(width 0.08255)
			(type default)
		)
		(layer "In13.Cu")
	)
	(gr_line
		(start 211.75599 -30.900116)
		(end 211.64296 -30.787086)
		(stroke
			(width 0.08255)
			(type default)
		)
		(layer "In13.Cu")
	)
	(gr_line
		(start 211.75599 -29.680916)
		(end 211.64296 -29.567886)
		(stroke
			(width 0.08255)
			(type default)
		)
		(layer "In13.Cu")
	)
	(gr_line
		(start 211.75599 -28.461716)
		(end 211.64296 -28.348686)
		(stroke
			(width 0.08255)
			(type default)
		)
		(layer "In13.Cu")
	)
	(gr_line
		(start 249.472196 -27.052016)
		(end 249.181366 -27.342846)
		(stroke
			(width 0.08255)
			(type default)
		)
		(layer "In13.Cu")
	)
	(gr_line
		(start 249.472196 -26.770076)
		(end 249.181366 -26.479246)
		(stroke
			(width 0.08255)
			(type default)
		)
		(layer "In13.Cu")
	)
	(gr_line
		(start 256.763012 -34.31921)
		(end 256.763012 -34.15919)
		(stroke
			(width 0.08255)
			(type default)
		)
		(layer "In13.Cu")
	)
	(gr_line
		(start 257.113532 -34.66973)
		(end 256.763012 -34.31921)
		(stroke
			(width 0.08255)
			(type default)
		)
		(layer "In13.Cu")
	)
	(gr_line
		(start 257.273552 -34.66973)
		(end 257.113532 -34.66973)
		(stroke
			(width 0.08255)
			(type default)
		)
		(layer "In13.Cu")
	)
	(gr_line
		(start 257.47472 -34.47034)
		(end 256.962402 -33.958022)
		(stroke
			(width 0.08255)
			(type default)
		)
		(layer "In13.Cu")
	)
	(gr_line
		(start 257.625342 -35.18154)
		(end 257.625342 -35.02152)
		(stroke
			(width 0.08255)
			(type default)
		)
		(layer "In13.Cu")
	)
	(gr_line
		(start 257.975862 -35.53206)
		(end 257.625342 -35.18154)
		(stroke
			(width 0.08255)
			(type default)
		)
		(layer "In13.Cu")
	)
	(gr_line
		(start 258.135882 -35.53206)
		(end 257.975862 -35.53206)
		(stroke
			(width 0.08255)
			(type default)
		)
		(layer "In13.Cu")
	)
	(gr_line
		(start 258.33705 -35.33267)
		(end 257.824732 -34.820352)
		(stroke
			(width 0.08255)
			(type default)
		)
		(layer "In13.Cu")
	)
	(gr_line
		(start 258.487672 -36.04387)
		(end 258.487672 -35.88385)
		(stroke
			(width 0.08255)
			(type default)
		)
		(layer "In13.Cu")
	)
	(gr_line
		(start 258.838192 -36.39439)
		(end 258.487672 -36.04387)
		(stroke
			(width 0.08255)
			(type default)
		)
		(layer "In13.Cu")
	)
	(gr_line
		(start 258.998212 -36.39439)
		(end 258.838192 -36.39439)
		(stroke
			(width 0.08255)
			(type default)
		)
		(layer "In13.Cu")
	)
	(gr_line
		(start 259.19938 -36.195)
		(end 258.687062 -35.682682)
		(stroke
			(width 0.08255)
			(type default)
		)
		(layer "In13.Cu")
	)
	(gr_line
		(start 259.350002 -36.9062)
		(end 259.350002 -36.74618)
		(stroke
			(width 0.08255)
			(type default)
		)
		(layer "In13.Cu")
	)
	(gr_line
		(start 259.700522 -37.25672)
		(end 259.350002 -36.9062)
		(stroke
			(width 0.08255)
			(type default)
		)
		(layer "In13.Cu")
	)
	(gr_line
		(start 259.860542 -37.25672)
		(end 259.700522 -37.25672)
		(stroke
			(width 0.08255)
			(type default)
		)
		(layer "In13.Cu")
	)
	(gr_line
		(start 260.06171 -37.05733)
		(end 259.549392 -36.545012)
		(stroke
			(width 0.08255)
			(type default)
		)
		(layer "In13.Cu")
	)
	(gr_line
		(start 260.212332 -37.76853)
		(end 260.212332 -37.60851)
		(stroke
			(width 0.08255)
			(type default)
		)
		(layer "In13.Cu")
	)
	(gr_line
		(start 260.562852 -38.11905)
		(end 260.212332 -37.76853)
		(stroke
			(width 0.08255)
			(type default)
		)
		(layer "In13.Cu")
	)
	(gr_line
		(start 260.722872 -38.11905)
		(end 260.562852 -38.11905)
		(stroke
			(width 0.08255)
			(type default)
		)
		(layer "In13.Cu")
	)
	(gr_line
		(start 260.92404 -37.91966)
		(end 260.411722 -37.407342)
		(stroke
			(width 0.08255)
			(type default)
		)
		(layer "In13.Cu")
	)
	(gr_line
		(start 263.47166 -75.258422)
		(end 263.18083 -74.967592)
		(stroke
			(width 0.08255)
			(type default)
		)
		(layer "In13.Cu")
	)
	(gr_line
		(start 275.472144 -27.052016)
		(end 275.181314 -27.342846)
		(stroke
			(width 0.08255)
			(type default)
		)
		(layer "In13.Cu")
	)
	(gr_line
		(start 275.472144 -26.770076)
		(end 275.181314 -26.479246)
		(stroke
			(width 0.08255)
			(type default)
		)
		(layer "In13.Cu")
	)
	(gr_line
		(start 283.608272 -34.29127)
		(end 283.608272 -34.13125)
		(stroke
			(width 0.08255)
			(type default)
		)
		(layer "In13.Cu")
	)
	(gr_line
		(start 283.958792 -34.64179)
		(end 283.608272 -34.29127)
		(stroke
			(width 0.08255)
			(type default)
		)
		(layer "In13.Cu")
	)
	(gr_line
		(start 284.118812 -34.64179)
		(end 283.958792 -34.64179)
		(stroke
			(width 0.08255)
			(type default)
		)
		(layer "In13.Cu")
	)
	(gr_line
		(start 284.31998 -34.4424)
		(end 283.807662 -33.930082)
		(stroke
			(width 0.08255)
			(type default)
		)
		(layer "In13.Cu")
	)
	(gr_line
		(start 284.470602 -35.1536)
		(end 284.470602 -34.99358)
		(stroke
			(width 0.08255)
			(type default)
		)
		(layer "In13.Cu")
	)
	(gr_line
		(start 284.821122 -35.50412)
		(end 284.470602 -35.1536)
		(stroke
			(width 0.08255)
			(type default)
		)
		(layer "In13.Cu")
	)
	(gr_line
		(start 284.981142 -35.50412)
		(end 284.821122 -35.50412)
		(stroke
			(width 0.08255)
			(type default)
		)
		(layer "In13.Cu")
	)
	(gr_line
		(start 285.18231 -35.30473)
		(end 284.669992 -34.792412)
		(stroke
			(width 0.08255)
			(type default)
		)
		(layer "In13.Cu")
	)
	(gr_line
		(start 285.332932 -36.01593)
		(end 285.332932 -35.85591)
		(stroke
			(width 0.08255)
			(type default)
		)
		(layer "In13.Cu")
	)
	(gr_line
		(start 285.683452 -36.36645)
		(end 285.332932 -36.01593)
		(stroke
			(width 0.08255)
			(type default)
		)
		(layer "In13.Cu")
	)
	(gr_line
		(start 285.843472 -36.36645)
		(end 285.683452 -36.36645)
		(stroke
			(width 0.08255)
			(type default)
		)
		(layer "In13.Cu")
	)
	(gr_line
		(start 286.04464 -36.16706)
		(end 285.532322 -35.654742)
		(stroke
			(width 0.08255)
			(type default)
		)
		(layer "In13.Cu")
	)
	(gr_line
		(start 286.195262 -36.87826)
		(end 286.195262 -36.71824)
		(stroke
			(width 0.08255)
			(type default)
		)
		(layer "In13.Cu")
	)
	(gr_line
		(start 286.545782 -37.22878)
		(end 286.195262 -36.87826)
		(stroke
			(width 0.08255)
			(type default)
		)
		(layer "In13.Cu")
	)
	(gr_line
		(start 286.705802 -37.22878)
		(end 286.545782 -37.22878)
		(stroke
			(width 0.08255)
			(type default)
		)
		(layer "In13.Cu")
	)
	(gr_line
		(start 286.90697 -37.02939)
		(end 286.394652 -36.517072)
		(stroke
			(width 0.08255)
			(type default)
		)
		(layer "In13.Cu")
	)
	(gr_line
		(start 324.923658 -84.064094)
		(end 325.207884 -84.348066)
		(stroke
			(width 0.08255)
			(type default)
		)
		(layer "In13.Cu")
	)
	(gr_line
		(start 324.923658 -83.871816)
		(end 324.923658 -84.064094)
		(stroke
			(width 0.08255)
			(type default)
		)
		(layer "In13.Cu")
	)
	(gr_line
		(start 325.207884 -84.348066)
		(end 325.399908 -84.348066)
		(stroke
			(width 0.08255)
			(type default)
		)
		(layer "In13.Cu")
	)
	(gr_line
		(start 325.685404 -84.82584)
		(end 325.96963 -85.109812)
		(stroke
			(width 0.08255)
			(type default)
		)
		(layer "In13.Cu")
	)
	(gr_line
		(start 325.685404 -84.633562)
		(end 325.685404 -84.82584)
		(stroke
			(width 0.08255)
			(type default)
		)
		(layer "In13.Cu")
	)
	(gr_line
		(start 325.96963 -85.109812)
		(end 326.161654 -85.109812)
		(stroke
			(width 0.08255)
			(type default)
		)
		(layer "In13.Cu")
	)
	(gr_line
		(start 326.44715 -85.587586)
		(end 326.731376 -85.871558)
		(stroke
			(width 0.08255)
			(type default)
		)
		(layer "In13.Cu")
	)
	(gr_line
		(start 326.44715 -85.395308)
		(end 326.44715 -85.587586)
		(stroke
			(width 0.08255)
			(type default)
		)
		(layer "In13.Cu")
	)
	(gr_line
		(start 326.731376 -85.871558)
		(end 326.9234 -85.871558)
		(stroke
			(width 0.08255)
			(type default)
		)
		(layer "In13.Cu")
	)
	(gr_line
		(start 327.208896 -86.349332)
		(end 327.492868 -86.633304)
		(stroke
			(width 0.08255)
			(type default)
		)
		(layer "In13.Cu")
	)
	(gr_line
		(start 327.208896 -86.157054)
		(end 327.208896 -86.349332)
		(stroke
			(width 0.08255)
			(type default)
		)
		(layer "In13.Cu")
	)
	(gr_line
		(start 327.47204 -27.052016)
		(end 327.18121 -27.342846)
		(stroke
			(width 0.08255)
			(type default)
		)
		(layer "In13.Cu")
	)
	(gr_line
		(start 327.47204 -26.770076)
		(end 327.18121 -26.479246)
		(stroke
			(width 0.08255)
			(type default)
		)
		(layer "In13.Cu")
	)
	(gr_line
		(start 327.492868 -86.633304)
		(end 327.685146 -86.633304)
		(stroke
			(width 0.08255)
			(type default)
		)
		(layer "In13.Cu")
	)
	(gr_line
		(start 330.644754 -87.033608)
		(end 330.935584 -87.324438)
		(stroke
			(width 0.08255)
			(type default)
		)
		(layer "In13.Cu")
	)
	(gr_line
		(start 331.36332 -28.0289)
		(end 331.25029 -27.91587)
		(stroke
			(width 0.08255)
			(type default)
		)
		(layer "In13.Cu")
	)
	(gr_line
		(start 331.85862 -28.0289)
		(end 331.36332 -28.0289)
		(stroke
			(width 0.08255)
			(type default)
		)
		(layer "In13.Cu")
	)
	(gr_line
		(start 331.97165 -27.91587)
		(end 331.85862 -28.0289)
		(stroke
			(width 0.08255)
			(type default)
		)
		(layer "In13.Cu")
	)
	(gr_line
		(start 331.97292 -27.63266)
		(end 331.24902 -27.63266)
		(stroke
			(width 0.08255)
			(type default)
		)
		(layer "In13.Cu")
	)
	(gr_line
		(start 332.818232 -28.42641)
		(end 332.818232 -28.26639)
		(stroke
			(width 0.08255)
			(type default)
		)
		(layer "In13.Cu")
	)
	(gr_line
		(start 333.168752 -28.77693)
		(end 332.818232 -28.42641)
		(stroke
			(width 0.08255)
			(type default)
		)
		(layer "In13.Cu")
	)
	(gr_line
		(start 333.328772 -28.77693)
		(end 333.168752 -28.77693)
		(stroke
			(width 0.08255)
			(type default)
		)
		(layer "In13.Cu")
	)
	(gr_line
		(start 333.52994 -28.57754)
		(end 333.017622 -28.065222)
		(stroke
			(width 0.08255)
			(type default)
		)
		(layer "In13.Cu")
	)
	(gr_line
		(start 333.680562 -29.28874)
		(end 333.680562 -29.12872)
		(stroke
			(width 0.08255)
			(type default)
		)
		(layer "In13.Cu")
	)
	(gr_line
		(start 334.031082 -29.63926)
		(end 333.680562 -29.28874)
		(stroke
			(width 0.08255)
			(type default)
		)
		(layer "In13.Cu")
	)
	(gr_line
		(start 334.191102 -29.63926)
		(end 334.031082 -29.63926)
		(stroke
			(width 0.08255)
			(type default)
		)
		(layer "In13.Cu")
	)
	(gr_line
		(start 334.39227 -29.43987)
		(end 333.879952 -28.927552)
		(stroke
			(width 0.08255)
			(type default)
		)
		(layer "In13.Cu")
	)
	(gr_line
		(start 334.542892 -30.15107)
		(end 334.542892 -29.99105)
		(stroke
			(width 0.08255)
			(type default)
		)
		(layer "In13.Cu")
	)
	(gr_line
		(start 334.863948 -78.882748)
		(end 335.154778 -78.591918)
		(stroke
			(width 0.08255)
			(type default)
		)
		(layer "In13.Cu")
	)
	(gr_line
		(start 334.893412 -30.50159)
		(end 334.542892 -30.15107)
		(stroke
			(width 0.08255)
			(type default)
		)
		(layer "In13.Cu")
	)
	(gr_line
		(start 335.053432 -30.50159)
		(end 334.893412 -30.50159)
		(stroke
			(width 0.08255)
			(type default)
		)
		(layer "In13.Cu")
	)
	(gr_line
		(start 335.2546 -30.3022)
		(end 334.742282 -29.789882)
		(stroke
			(width 0.08255)
			(type default)
		)
		(layer "In13.Cu")
	)
	(gr_line
		(start 335.405222 -31.0134)
		(end 335.405222 -30.85338)
		(stroke
			(width 0.08255)
			(type default)
		)
		(layer "In13.Cu")
	)
	(gr_line
		(start 335.727548 -78.882748)
		(end 335.436718 -78.591918)
		(stroke
			(width 0.08255)
			(type default)
		)
		(layer "In13.Cu")
	)
	(gr_line
		(start 335.755742 -31.36392)
		(end 335.405222 -31.0134)
		(stroke
			(width 0.08255)
			(type default)
		)
		(layer "In13.Cu")
	)
	(gr_line
		(start 335.915762 -31.36392)
		(end 335.755742 -31.36392)
		(stroke
			(width 0.08255)
			(type default)
		)
		(layer "In13.Cu")
	)
	(gr_line
		(start 336.11693 -31.16453)
		(end 335.604612 -30.652212)
		(stroke
			(width 0.08255)
			(type default)
		)
		(layer "In13.Cu")
	)
	(gr_line
		(start 336.267552 -31.87573)
		(end 336.267552 -31.71571)
		(stroke
			(width 0.08255)
			(type default)
		)
		(layer "In13.Cu")
	)
	(gr_line
		(start 336.618072 -32.22625)
		(end 336.267552 -31.87573)
		(stroke
			(width 0.08255)
			(type default)
		)
		(layer "In13.Cu")
	)
	(gr_line
		(start 336.778092 -32.22625)
		(end 336.618072 -32.22625)
		(stroke
			(width 0.08255)
			(type default)
		)
		(layer "In13.Cu")
	)
	(gr_line
		(start 336.863944 -78.120748)
		(end 337.154774 -77.829918)
		(stroke
			(width 0.08255)
			(type default)
		)
		(layer "In13.Cu")
	)
	(gr_line
		(start 336.97926 -32.02686)
		(end 336.466942 -31.514542)
		(stroke
			(width 0.08255)
			(type default)
		)
		(layer "In13.Cu")
	)
	(gr_line
		(start 337.129882 -32.73806)
		(end 337.129882 -32.57804)
		(stroke
			(width 0.08255)
			(type default)
		)
		(layer "In13.Cu")
	)
	(gr_line
		(start 337.480402 -33.08858)
		(end 337.129882 -32.73806)
		(stroke
			(width 0.08255)
			(type default)
		)
		(layer "In13.Cu")
	)
	(gr_line
		(start 337.640422 -33.08858)
		(end 337.480402 -33.08858)
		(stroke
			(width 0.08255)
			(type default)
		)
		(layer "In13.Cu")
	)
	(gr_line
		(start 337.727544 -78.120748)
		(end 337.436714 -77.829918)
		(stroke
			(width 0.08255)
			(type default)
		)
		(layer "In13.Cu")
	)
	(gr_line
		(start 337.84159 -32.88919)
		(end 337.329272 -32.376872)
		(stroke
			(width 0.08255)
			(type default)
		)
		(layer "In13.Cu")
	)
	(gr_line
		(start 337.992212 -33.60039)
		(end 337.992212 -33.44037)
		(stroke
			(width 0.08255)
			(type default)
		)
		(layer "In13.Cu")
	)
	(gr_line
		(start 338.342732 -33.95091)
		(end 337.992212 -33.60039)
		(stroke
			(width 0.08255)
			(type default)
		)
		(layer "In13.Cu")
	)
	(gr_line
		(start 338.502752 -33.95091)
		(end 338.342732 -33.95091)
		(stroke
			(width 0.08255)
			(type default)
		)
		(layer "In13.Cu")
	)
	(gr_line
		(start 338.70392 -33.75152)
		(end 338.191602 -33.239202)
		(stroke
			(width 0.08255)
			(type default)
		)
		(layer "In13.Cu")
	)
	(gr_line
		(start 338.854542 -34.46272)
		(end 338.854542 -34.3027)
		(stroke
			(width 0.08255)
			(type default)
		)
		(layer "In13.Cu")
	)
	(gr_line
		(start 338.863686 -94.843854)
		(end 339.154516 -95.134684)
		(stroke
			(width 0.08255)
			(type default)
		)
		(layer "In13.Cu")
	)
	(gr_line
		(start 339.205062 -34.81324)
		(end 338.854542 -34.46272)
		(stroke
			(width 0.08255)
			(type default)
		)
		(layer "In13.Cu")
	)
	(gr_line
		(start 339.365082 -34.81324)
		(end 339.205062 -34.81324)
		(stroke
			(width 0.08255)
			(type default)
		)
		(layer "In13.Cu")
	)
	(gr_line
		(start 339.56625 -34.61385)
		(end 339.053932 -34.101532)
		(stroke
			(width 0.08255)
			(type default)
		)
		(layer "In13.Cu")
	)
	(gr_line
		(start 339.727286 -94.843854)
		(end 339.436456 -95.134684)
		(stroke
			(width 0.08255)
			(type default)
		)
		(layer "In13.Cu")
	)
	(gr_line
		(start 340.125558 -35.898582)
		(end 340.1568 -35.741864)
		(stroke
			(width 0.08255)
			(type default)
		)
		(layer "In13.Cu")
	)
	(gr_line
		(start 340.400894 -36.31057)
		(end 340.125558 -35.898582)
		(stroke
			(width 0.08255)
			(type default)
		)
		(layer "In13.Cu")
	)
	(gr_line
		(start 340.557612 -36.341812)
		(end 340.400894 -36.31057)
		(stroke
			(width 0.08255)
			(type default)
		)
		(layer "In13.Cu")
	)
	(gr_line
		(start 340.576408 -36.367466)
		(end 340.55939 -36.342066)
		(stroke
			(width 0.08255)
			(type default)
		)
		(layer "In13.Cu")
	)
	(gr_line
		(start 340.793832 -36.185348)
		(end 340.391496 -35.583368)
		(stroke
			(width 0.08255)
			(type default)
		)
		(layer "In13.Cu")
	)
	(gr_line
		(start 340.81085 -36.210748)
		(end 340.793832 -36.185348)
		(stroke
			(width 0.08255)
			(type default)
		)
		(layer "In13.Cu")
	)
	(gr_line
		(start 346.33789 -87.28075)
		(end 346.62872 -87.57158)
		(stroke
			(width 0.08255)
			(type default)
		)
		(layer "In13.Cu")
	)
	(gr_line
		(start 346.33789 -84.144358)
		(end 346.62872 -83.853528)
		(stroke
			(width 0.08255)
			(type default)
		)
		(layer "In13.Cu")
	)
	(gr_line
		(start 346.33789 -83.280758)
		(end 346.62872 -83.571588)
		(stroke
			(width 0.08255)
			(type default)
		)
		(layer "In13.Cu")
	)
	(gr_line
		(start 347.09989 -89.280746)
		(end 347.39072 -89.571576)
		(stroke
			(width 0.08255)
			(type default)
		)
		(layer "In13.Cu")
	)
	(gr_line
		(start 347.09989 -85.280754)
		(end 347.39072 -85.571584)
		(stroke
			(width 0.08255)
			(type default)
		)
		(layer "In13.Cu")
	)
	(gr_line
		(start 361.897168 -85.522054)
		(end 361.897168 -85.362288)
		(stroke
			(width 0.08255)
			(type default)
		)
		(layer "In13.Cu")
	)
	(gr_line
		(start 361.897168 -85.362288)
		(end 362.247688 -85.011768)
		(stroke
			(width 0.08255)
			(type default)
		)
		(layer "In13.Cu")
	)
	(gr_line
		(start 362.096558 -85.723222)
		(end 362.608622 -85.211158)
		(stroke
			(width 0.08255)
			(type default)
		)
		(layer "In13.Cu")
	)
	(gr_line
		(start 362.247688 -85.011768)
		(end 362.407454 -85.011768)
		(stroke
			(width 0.08255)
			(type default)
		)
		(layer "In13.Cu")
	)
	(gr_line
		(start 364.2614 -38.326822)
		(end 364.2614 -38.166802)
		(stroke
			(width 0.08255)
			(type default)
		)
		(layer "In13.Cu")
	)
	(gr_line
		(start 364.2614 -38.166802)
		(end 364.61192 -37.816282)
		(stroke
			(width 0.08255)
			(type default)
		)
		(layer "In13.Cu")
	)
	(gr_line
		(start 364.61192 -37.816282)
		(end 364.77194 -37.816282)
		(stroke
			(width 0.08255)
			(type default)
		)
		(layer "In13.Cu")
	)
	(gr_line
		(start 365.12373 -37.464492)
		(end 365.12373 -37.304472)
		(stroke
			(width 0.08255)
			(type default)
		)
		(layer "In13.Cu")
	)
	(gr_line
		(start 365.12373 -37.304472)
		(end 365.47425 -36.953952)
		(stroke
			(width 0.08255)
			(type default)
		)
		(layer "In13.Cu")
	)
	(gr_line
		(start 365.47425 -36.953952)
		(end 365.63427 -36.953952)
		(stroke
			(width 0.08255)
			(type default)
		)
		(layer "In13.Cu")
	)
	(gr_line
		(start 365.572294 -27.052016)
		(end 365.281464 -27.342846)
		(stroke
			(width 0.08255)
			(type default)
		)
		(layer "In13.Cu")
	)
	(gr_line
		(start 365.87176 -35.664394)
		(end 365.87176 -35.169094)
		(stroke
			(width 0.08255)
			(type default)
		)
		(layer "In13.Cu")
	)
	(gr_line
		(start 365.87176 -35.169094)
		(end 365.98479 -35.056064)
		(stroke
			(width 0.08255)
			(type default)
		)
		(layer "In13.Cu")
	)
	(gr_line
		(start 365.87176 -34.445194)
		(end 365.87176 -33.949894)
		(stroke
			(width 0.08255)
			(type default)
		)
		(layer "In13.Cu")
	)
	(gr_line
		(start 365.87176 -33.949894)
		(end 365.98479 -33.836864)
		(stroke
			(width 0.08255)
			(type default)
		)
		(layer "In13.Cu")
	)
	(gr_line
		(start 365.87176 -33.225994)
		(end 365.87176 -32.730694)
		(stroke
			(width 0.08255)
			(type default)
		)
		(layer "In13.Cu")
	)
	(gr_line
		(start 365.87176 -32.730694)
		(end 365.98479 -32.617664)
		(stroke
			(width 0.08255)
			(type default)
		)
		(layer "In13.Cu")
	)
	(gr_line
		(start 365.87176 -32.006794)
		(end 365.87176 -31.511494)
		(stroke
			(width 0.08255)
			(type default)
		)
		(layer "In13.Cu")
	)
	(gr_line
		(start 365.87176 -31.511494)
		(end 365.98479 -31.398464)
		(stroke
			(width 0.08255)
			(type default)
		)
		(layer "In13.Cu")
	)
	(gr_line
		(start 365.87176 -30.787594)
		(end 365.87176 -30.292294)
		(stroke
			(width 0.08255)
			(type default)
		)
		(layer "In13.Cu")
	)
	(gr_line
		(start 365.87176 -30.292294)
		(end 365.98479 -30.179264)
		(stroke
			(width 0.08255)
			(type default)
		)
		(layer "In13.Cu")
	)
	(gr_line
		(start 365.87176 -29.568394)
		(end 365.87176 -29.073094)
		(stroke
			(width 0.08255)
			(type default)
		)
		(layer "In13.Cu")
	)
	(gr_line
		(start 365.87176 -29.073094)
		(end 365.98479 -28.960064)
		(stroke
			(width 0.08255)
			(type default)
		)
		(layer "In13.Cu")
	)
	(gr_line
		(start 365.87176 -28.349194)
		(end 365.87176 -27.853894)
		(stroke
			(width 0.08255)
			(type default)
		)
		(layer "In13.Cu")
	)
	(gr_line
		(start 365.87176 -27.853894)
		(end 365.98479 -27.740864)
		(stroke
			(width 0.08255)
			(type default)
		)
		(layer "In13.Cu")
	)
	(gr_line
		(start 365.98479 -35.777424)
		(end 365.87176 -35.664394)
		(stroke
			(width 0.08255)
			(type default)
		)
		(layer "In13.Cu")
	)
	(gr_line
		(start 365.98479 -34.558224)
		(end 365.87176 -34.445194)
		(stroke
			(width 0.08255)
			(type default)
		)
		(layer "In13.Cu")
	)
	(gr_line
		(start 365.98479 -33.339024)
		(end 365.87176 -33.225994)
		(stroke
			(width 0.08255)
			(type default)
		)
		(layer "In13.Cu")
	)
	(gr_line
		(start 365.98479 -32.119824)
		(end 365.87176 -32.006794)
		(stroke
			(width 0.08255)
			(type default)
		)
		(layer "In13.Cu")
	)
	(gr_line
		(start 365.98479 -30.900624)
		(end 365.87176 -30.787594)
		(stroke
			(width 0.08255)
			(type default)
		)
		(layer "In13.Cu")
	)
	(gr_line
		(start 365.98479 -29.681424)
		(end 365.87176 -29.568394)
		(stroke
			(width 0.08255)
			(type default)
		)
		(layer "In13.Cu")
	)
	(gr_line
		(start 365.98479 -28.462224)
		(end 365.87176 -28.349194)
		(stroke
			(width 0.08255)
			(type default)
		)
		(layer "In13.Cu")
	)
	(gr_line
		(start 390.22274 -38.382702)
		(end 390.22274 -38.222682)
		(stroke
			(width 0.08255)
			(type default)
		)
		(layer "In13.Cu")
	)
	(gr_line
		(start 390.22274 -38.222682)
		(end 390.57326 -37.872162)
		(stroke
			(width 0.08255)
			(type default)
		)
		(layer "In13.Cu")
	)
	(gr_line
		(start 390.57326 -37.872162)
		(end 390.73328 -37.872162)
		(stroke
			(width 0.08255)
			(type default)
		)
		(layer "In13.Cu")
	)
	(gr_line
		(start 391.08507 -37.520372)
		(end 391.08507 -37.360352)
		(stroke
			(width 0.08255)
			(type default)
		)
		(layer "In13.Cu")
	)
	(gr_line
		(start 391.08507 -37.360352)
		(end 391.43559 -37.009832)
		(stroke
			(width 0.08255)
			(type default)
		)
		(layer "In13.Cu")
	)
	(gr_line
		(start 391.43559 -37.009832)
		(end 391.59561 -37.009832)
		(stroke
			(width 0.08255)
			(type default)
		)
		(layer "In13.Cu")
	)
	(gr_line
		(start 391.572242 -27.052016)
		(end 391.281412 -27.342846)
		(stroke
			(width 0.08255)
			(type default)
		)
		(layer "In13.Cu")
	)
	(gr_line
		(start 391.8331 -35.613594)
		(end 391.8331 -35.118294)
		(stroke
			(width 0.08255)
			(type default)
		)
		(layer "In13.Cu")
	)
	(gr_line
		(start 391.8331 -35.118294)
		(end 391.94613 -35.005264)
		(stroke
			(width 0.08255)
			(type default)
		)
		(layer "In13.Cu")
	)
	(gr_line
		(start 391.8331 -34.394394)
		(end 391.8331 -33.899094)
		(stroke
			(width 0.08255)
			(type default)
		)
		(layer "In13.Cu")
	)
	(gr_line
		(start 391.8331 -33.899094)
		(end 391.94613 -33.786064)
		(stroke
			(width 0.08255)
			(type default)
		)
		(layer "In13.Cu")
	)
	(gr_line
		(start 391.8331 -33.175194)
		(end 391.8331 -32.679894)
		(stroke
			(width 0.08255)
			(type default)
		)
		(layer "In13.Cu")
	)
	(gr_line
		(start 391.8331 -32.679894)
		(end 391.94613 -32.566864)
		(stroke
			(width 0.08255)
			(type default)
		)
		(layer "In13.Cu")
	)
	(gr_line
		(start 391.8331 -31.955994)
		(end 391.8331 -31.460694)
		(stroke
			(width 0.08255)
			(type default)
		)
		(layer "In13.Cu")
	)
	(gr_line
		(start 391.8331 -31.460694)
		(end 391.94613 -31.347664)
		(stroke
			(width 0.08255)
			(type default)
		)
		(layer "In13.Cu")
	)
	(gr_line
		(start 391.8331 -30.736794)
		(end 391.8331 -30.241494)
		(stroke
			(width 0.08255)
			(type default)
		)
		(layer "In13.Cu")
	)
	(gr_line
		(start 391.8331 -30.241494)
		(end 391.94613 -30.128464)
		(stroke
			(width 0.08255)
			(type default)
		)
		(layer "In13.Cu")
	)
	(gr_line
		(start 391.8331 -29.517594)
		(end 391.8331 -29.022294)
		(stroke
			(width 0.08255)
			(type default)
		)
		(layer "In13.Cu")
	)
	(gr_line
		(start 391.8331 -29.022294)
		(end 391.94613 -28.909264)
		(stroke
			(width 0.08255)
			(type default)
		)
		(layer "In13.Cu")
	)
	(gr_line
		(start 391.8331 -28.298394)
		(end 391.8331 -27.803094)
		(stroke
			(width 0.08255)
			(type default)
		)
		(layer "In13.Cu")
	)
	(gr_line
		(start 391.8331 -27.803094)
		(end 391.94613 -27.690064)
		(stroke
			(width 0.08255)
			(type default)
		)
		(layer "In13.Cu")
	)
	(gr_line
		(start 391.94613 -35.726624)
		(end 391.8331 -35.613594)
		(stroke
			(width 0.08255)
			(type default)
		)
		(layer "In13.Cu")
	)
	(gr_line
		(start 391.94613 -34.507424)
		(end 391.8331 -34.394394)
		(stroke
			(width 0.08255)
			(type default)
		)
		(layer "In13.Cu")
	)
	(gr_line
		(start 391.94613 -33.288224)
		(end 391.8331 -33.175194)
		(stroke
			(width 0.08255)
			(type default)
		)
		(layer "In13.Cu")
	)
	(gr_line
		(start 391.94613 -32.069024)
		(end 391.8331 -31.955994)
		(stroke
			(width 0.08255)
			(type default)
		)
		(layer "In13.Cu")
	)
	(gr_line
		(start 391.94613 -30.849824)
		(end 391.8331 -30.736794)
		(stroke
			(width 0.08255)
			(type default)
		)
		(layer "In13.Cu")
	)
	(gr_line
		(start 391.94613 -29.630624)
		(end 391.8331 -29.517594)
		(stroke
			(width 0.08255)
			(type default)
		)
		(layer "In13.Cu")
	)
	(gr_line
		(start 391.94613 -28.411424)
		(end 391.8331 -28.298394)
		(stroke
			(width 0.08255)
			(type default)
		)
		(layer "In13.Cu")
	)
	(gr_line
		(start 416.18154 -38.425882)
		(end 416.18154 -38.265862)
		(stroke
			(width 0.08255)
			(type default)
		)
		(layer "In13.Cu")
	)
	(gr_line
		(start 416.18154 -38.265862)
		(end 416.53206 -37.915342)
		(stroke
			(width 0.08255)
			(type default)
		)
		(layer "In13.Cu")
	)
	(gr_line
		(start 416.53206 -37.915342)
		(end 416.69208 -37.915342)
		(stroke
			(width 0.08255)
			(type default)
		)
		(layer "In13.Cu")
	)
	(gr_line
		(start 417.04387 -37.563552)
		(end 417.04387 -37.403532)
		(stroke
			(width 0.08255)
			(type default)
		)
		(layer "In13.Cu")
	)
	(gr_line
		(start 417.04387 -37.403532)
		(end 417.39439 -37.053012)
		(stroke
			(width 0.08255)
			(type default)
		)
		(layer "In13.Cu")
	)
	(gr_line
		(start 417.39439 -37.053012)
		(end 417.55441 -37.053012)
		(stroke
			(width 0.08255)
			(type default)
		)
		(layer "In13.Cu")
	)
	(gr_line
		(start 417.57219 -27.052016)
		(end 417.28136 -27.342846)
		(stroke
			(width 0.08255)
			(type default)
		)
		(layer "In13.Cu")
	)
	(gr_line
		(start 417.7919 -35.599116)
		(end 417.7919 -35.103816)
		(stroke
			(width 0.08255)
			(type default)
		)
		(layer "In13.Cu")
	)
	(gr_line
		(start 417.7919 -35.103816)
		(end 417.90493 -34.990786)
		(stroke
			(width 0.08255)
			(type default)
		)
		(layer "In13.Cu")
	)
	(gr_line
		(start 417.7919 -34.379916)
		(end 417.7919 -33.884616)
		(stroke
			(width 0.08255)
			(type default)
		)
		(layer "In13.Cu")
	)
	(gr_line
		(start 417.7919 -33.884616)
		(end 417.90493 -33.771586)
		(stroke
			(width 0.08255)
			(type default)
		)
		(layer "In13.Cu")
	)
	(gr_line
		(start 417.7919 -33.160716)
		(end 417.7919 -32.665416)
		(stroke
			(width 0.08255)
			(type default)
		)
		(layer "In13.Cu")
	)
	(gr_line
		(start 417.7919 -32.665416)
		(end 417.90493 -32.552386)
		(stroke
			(width 0.08255)
			(type default)
		)
		(layer "In13.Cu")
	)
	(gr_line
		(start 417.7919 -31.941516)
		(end 417.7919 -31.446216)
		(stroke
			(width 0.08255)
			(type default)
		)
		(layer "In13.Cu")
	)
	(gr_line
		(start 417.7919 -31.446216)
		(end 417.90493 -31.333186)
		(stroke
			(width 0.08255)
			(type default)
		)
		(layer "In13.Cu")
	)
	(gr_line
		(start 417.7919 -30.722316)
		(end 417.7919 -30.227016)
		(stroke
			(width 0.08255)
			(type default)
		)
		(layer "In13.Cu")
	)
	(gr_line
		(start 417.7919 -30.227016)
		(end 417.90493 -30.113986)
		(stroke
			(width 0.08255)
			(type default)
		)
		(layer "In13.Cu")
	)
	(gr_line
		(start 417.7919 -29.503116)
		(end 417.7919 -29.007816)
		(stroke
			(width 0.08255)
			(type default)
		)
		(layer "In13.Cu")
	)
	(gr_line
		(start 417.7919 -29.007816)
		(end 417.90493 -28.894786)
		(stroke
			(width 0.08255)
			(type default)
		)
		(layer "In13.Cu")
	)
	(gr_line
		(start 417.7919 -28.283916)
		(end 417.7919 -27.788616)
		(stroke
			(width 0.08255)
			(type default)
		)
		(layer "In13.Cu")
	)
	(gr_line
		(start 417.7919 -27.788616)
		(end 417.90493 -27.675586)
		(stroke
			(width 0.08255)
			(type default)
		)
		(layer "In13.Cu")
	)
	(gr_line
		(start 417.90493 -35.712146)
		(end 417.7919 -35.599116)
		(stroke
			(width 0.08255)
			(type default)
		)
		(layer "In13.Cu")
	)
	(gr_line
		(start 417.90493 -34.492946)
		(end 417.7919 -34.379916)
		(stroke
			(width 0.08255)
			(type default)
		)
		(layer "In13.Cu")
	)
	(gr_line
		(start 417.90493 -33.273746)
		(end 417.7919 -33.160716)
		(stroke
			(width 0.08255)
			(type default)
		)
		(layer "In13.Cu")
	)
	(gr_line
		(start 417.90493 -32.054546)
		(end 417.7919 -31.941516)
		(stroke
			(width 0.08255)
			(type default)
		)
		(layer "In13.Cu")
	)
	(gr_line
		(start 417.90493 -30.835346)
		(end 417.7919 -30.722316)
		(stroke
			(width 0.08255)
			(type default)
		)
		(layer "In13.Cu")
	)
	(gr_line
		(start 417.90493 -29.616146)
		(end 417.7919 -29.503116)
		(stroke
			(width 0.08255)
			(type default)
		)
		(layer "In13.Cu")
	)
	(gr_line
		(start 417.90493 -28.396946)
		(end 417.7919 -28.283916)
		(stroke
			(width 0.08255)
			(type default)
		)
		(layer "In13.Cu")
	)
	(gr_line
		(start 435.023768 -67.538854)
		(end 435.023768 -67.379088)
		(stroke
			(width 0.08255)
			(type default)
		)
		(layer "In13.Cu")
	)
	(gr_line
		(start 435.023768 -67.379088)
		(end 435.374288 -67.028568)
		(stroke
			(width 0.08255)
			(type default)
		)
		(layer "In13.Cu")
	)
	(gr_line
		(start 435.223158 -67.740022)
		(end 435.735222 -67.227958)
		(stroke
			(width 0.08255)
			(type default)
		)
		(layer "In13.Cu")
	)
	(gr_line
		(start 435.374288 -67.028568)
		(end 435.534054 -67.028568)
		(stroke
			(width 0.08255)
			(type default)
		)
		(layer "In13.Cu")
	)
	(gr_line
		(start 436.669688 -65.108328)
		(end 436.859172 -64.65062)
		(stroke
			(width 0.08255)
			(type default)
		)
		(layer "In13.Cu")
	)
	(gr_line
		(start 436.730902 -65.255902)
		(end 436.669688 -65.108328)
		(stroke
			(width 0.08255)
			(type default)
		)
		(layer "In13.Cu")
	)
	(gr_line
		(start 436.859172 -64.65062)
		(end 437.007254 -64.589406)
		(stroke
			(width 0.08255)
			(type default)
		)
		(layer "In13.Cu")
	)
	(gr_line
		(start 436.992268 -65.36563)
		(end 437.269382 -64.696594)
		(stroke
			(width 0.08255)
			(type default)
		)
		(layer "In13.Cu")
	)
	(gr_line
		(start 437.136286 -63.981838)
		(end 437.32577 -63.52413)
		(stroke
			(width 0.08255)
			(type default)
		)
		(layer "In13.Cu")
	)
	(gr_line
		(start 437.1975 -64.129666)
		(end 437.136286 -63.981838)
		(stroke
			(width 0.08255)
			(type default)
		)
		(layer "In13.Cu")
	)
	(gr_line
		(start 437.32577 -63.52413)
		(end 437.473852 -63.462916)
		(stroke
			(width 0.08255)
			(type default)
		)
		(layer "In13.Cu")
	)
	(gr_line
		(start 437.458866 -64.23914)
		(end 437.73598 -63.570104)
		(stroke
			(width 0.08255)
			(type default)
		)
		(layer "In13.Cu")
	)
	(gr_line
		(start 437.55056 -62.3951)
		(end 437.55056 -61.8998)
		(stroke
			(width 0.08255)
			(type default)
		)
		(layer "In13.Cu")
	)
	(gr_line
		(start 437.55056 -61.8998)
		(end 437.66359 -61.78677)
		(stroke
			(width 0.08255)
			(type default)
		)
		(layer "In13.Cu")
	)
	(gr_line
		(start 437.55056 -61.1759)
		(end 437.55056 -60.6806)
		(stroke
			(width 0.08255)
			(type default)
		)
		(layer "In13.Cu")
	)
	(gr_line
		(start 437.55056 -60.6806)
		(end 437.66359 -60.56757)
		(stroke
			(width 0.08255)
			(type default)
		)
		(layer "In13.Cu")
	)
	(gr_line
		(start 437.66359 -62.50813)
		(end 437.55056 -62.3951)
		(stroke
			(width 0.08255)
			(type default)
		)
		(layer "In13.Cu")
	)
	(gr_line
		(start 437.66359 -61.28893)
		(end 437.55056 -61.1759)
		(stroke
			(width 0.08255)
			(type default)
		)
		(layer "In13.Cu")
	)
	(gr_line
		(start 437.9468 -62.5094)
		(end 437.9468 -61.7855)
		(stroke
			(width 0.08255)
			(type default)
		)
		(layer "In13.Cu")
	)
	(gr_line
		(start 437.9468 -61.2902)
		(end 437.9468 -60.5663)
		(stroke
			(width 0.08255)
			(type default)
		)
		(layer "In13.Cu")
	)
	(gr_line
		(start 439.511948 -41.359074)
		(end 439.511948 -41.199054)
		(stroke
			(width 0.08255)
			(type default)
		)
		(layer "In13.Cu")
	)
	(gr_line
		(start 439.511948 -41.199054)
		(end 439.862468 -40.848534)
		(stroke
			(width 0.08255)
			(type default)
		)
		(layer "In13.Cu")
	)
	(gr_line
		(start 439.711338 -41.560242)
		(end 440.223656 -41.047924)
		(stroke
			(width 0.08255)
			(type default)
		)
		(layer "In13.Cu")
	)
	(gr_line
		(start 439.862468 -40.848534)
		(end 440.022488 -40.848534)
		(stroke
			(width 0.08255)
			(type default)
		)
		(layer "In13.Cu")
	)
	(gr_line
		(start 440.374278 -40.496744)
		(end 440.374278 -40.336724)
		(stroke
			(width 0.08255)
			(type default)
		)
		(layer "In13.Cu")
	)
	(gr_line
		(start 440.374278 -40.336724)
		(end 440.724798 -39.986204)
		(stroke
			(width 0.08255)
			(type default)
		)
		(layer "In13.Cu")
	)
	(gr_line
		(start 440.573668 -40.697912)
		(end 441.085986 -40.185594)
		(stroke
			(width 0.08255)
			(type default)
		)
		(layer "In13.Cu")
	)
	(gr_line
		(start 440.724798 -39.986204)
		(end 440.884818 -39.986204)
		(stroke
			(width 0.08255)
			(type default)
		)
		(layer "In13.Cu")
	)
	(gr_line
		(start 441.236608 -39.634414)
		(end 441.236608 -39.474394)
		(stroke
			(width 0.08255)
			(type default)
		)
		(layer "In13.Cu")
	)
	(gr_line
		(start 441.236608 -39.474394)
		(end 441.587128 -39.123874)
		(stroke
			(width 0.08255)
			(type default)
		)
		(layer "In13.Cu")
	)
	(gr_line
		(start 441.435998 -39.835582)
		(end 441.948316 -39.323264)
		(stroke
			(width 0.08255)
			(type default)
		)
		(layer "In13.Cu")
	)
	(gr_line
		(start 441.587128 -39.123874)
		(end 441.747148 -39.123874)
		(stroke
			(width 0.08255)
			(type default)
		)
		(layer "In13.Cu")
	)
	(gr_line
		(start 442.098938 -38.772084)
		(end 442.098938 -38.612064)
		(stroke
			(width 0.08255)
			(type default)
		)
		(layer "In13.Cu")
	)
	(gr_line
		(start 442.098938 -38.612064)
		(end 442.449458 -38.261544)
		(stroke
			(width 0.08255)
			(type default)
		)
		(layer "In13.Cu")
	)
	(gr_line
		(start 442.298328 -38.973252)
		(end 442.810646 -38.460934)
		(stroke
			(width 0.08255)
			(type default)
		)
		(layer "In13.Cu")
	)
	(gr_line
		(start 442.449458 -38.261544)
		(end 442.609478 -38.261544)
		(stroke
			(width 0.08255)
			(type default)
		)
		(layer "In13.Cu")
	)
	(gr_line
		(start 442.961268 -37.909754)
		(end 442.961268 -37.749988)
		(stroke
			(width 0.08255)
			(type default)
		)
		(layer "In13.Cu")
	)
	(gr_line
		(start 442.961268 -37.749988)
		(end 443.311788 -37.399468)
		(stroke
			(width 0.08255)
			(type default)
		)
		(layer "In13.Cu")
	)
	(gr_line
		(start 443.160658 -38.110922)
		(end 443.672722 -37.598858)
		(stroke
			(width 0.08255)
			(type default)
		)
		(layer "In13.Cu")
	)
	(gr_line
		(start 443.311788 -37.399468)
		(end 443.471554 -37.399468)
		(stroke
			(width 0.08255)
			(type default)
		)
		(layer "In13.Cu")
	)
	(gr_line
		(start 443.572138 -27.052016)
		(end 443.281308 -27.342846)
		(stroke
			(width 0.08255)
			(type default)
		)
		(layer "In13.Cu")
	)
	(gr_line
		(start 443.572138 -26.770076)
		(end 443.281308 -26.479246)
		(stroke
			(width 0.08255)
			(type default)
		)
		(layer "In13.Cu")
	)
	(gr_line
		(start 443.8015 -31.941516)
		(end 443.8015 -31.446216)
		(stroke
			(width 0.08255)
			(type default)
		)
		(layer "In13.Cu")
	)
	(gr_line
		(start 443.8015 -31.446216)
		(end 443.91453 -31.333186)
		(stroke
			(width 0.08255)
			(type default)
		)
		(layer "In13.Cu")
	)
	(gr_line
		(start 443.8015 -30.722316)
		(end 443.8015 -30.227016)
		(stroke
			(width 0.08255)
			(type default)
		)
		(layer "In13.Cu")
	)
	(gr_line
		(start 443.8015 -30.227016)
		(end 443.91453 -30.113986)
		(stroke
			(width 0.08255)
			(type default)
		)
		(layer "In13.Cu")
	)
	(gr_line
		(start 443.8015 -29.503116)
		(end 443.8015 -29.007816)
		(stroke
			(width 0.08255)
			(type default)
		)
		(layer "In13.Cu")
	)
	(gr_line
		(start 443.8015 -29.007816)
		(end 443.91453 -28.894786)
		(stroke
			(width 0.08255)
			(type default)
		)
		(layer "In13.Cu")
	)
	(gr_line
		(start 443.8015 -28.283916)
		(end 443.8015 -27.788616)
		(stroke
			(width 0.08255)
			(type default)
		)
		(layer "In13.Cu")
	)
	(gr_line
		(start 443.8015 -27.788616)
		(end 443.91453 -27.675586)
		(stroke
			(width 0.08255)
			(type default)
		)
		(layer "In13.Cu")
	)
	(gr_line
		(start 443.91453 -32.054546)
		(end 443.8015 -31.941516)
		(stroke
			(width 0.08255)
			(type default)
		)
		(layer "In13.Cu")
	)
	(gr_line
		(start 443.91453 -30.835346)
		(end 443.8015 -30.722316)
		(stroke
			(width 0.08255)
			(type default)
		)
		(layer "In13.Cu")
	)
	(gr_line
		(start 443.91453 -29.616146)
		(end 443.8015 -29.503116)
		(stroke
			(width 0.08255)
			(type default)
		)
		(layer "In13.Cu")
	)
	(gr_line
		(start 443.91453 -28.396946)
		(end 443.8015 -28.283916)
		(stroke
			(width 0.08255)
			(type default)
		)
		(layer "In13.Cu")
	)
	(gr_line
		(start 444.19774 -32.055816)
		(end 444.19774 -31.331916)
		(stroke
			(width 0.08255)
			(type default)
		)
		(layer "In13.Cu")
	)
	(gr_line
		(start 444.19774 -30.836616)
		(end 444.19774 -30.112716)
		(stroke
			(width 0.08255)
			(type default)
		)
		(layer "In13.Cu")
	)
	(gr_line
		(start 444.19774 -29.617416)
		(end 444.19774 -28.893516)
		(stroke
			(width 0.08255)
			(type default)
		)
		(layer "In13.Cu")
	)
	(gr_line
		(start 444.19774 -28.398216)
		(end 444.19774 -27.674316)
		(stroke
			(width 0.08255)
			(type default)
		)
		(layer "In13.Cu")
	)
	(gr_poly
		(pts
			(arc
				(start 265.615928 -377.679966)
				(mid 265.635451 -377.676065)
				(end 265.651996 -377.66498)
			)
			(arc
				(start 265.851386 -377.46559)
				(mid 265.862497 -377.449056)
				(end 265.866372 -377.429522)
			)
			(arc
				(start 265.866372 -368.884962)
				(mid 265.862471 -368.865439)
				(end 265.851386 -368.848894)
			)
			(arc
				(start 265.514582 -368.51209)
				(mid 265.498048 -368.500979)
				(end 265.478514 -368.497104)
			)
			(arc
				(start 242.901216 -368.497104)
				(mid 242.881693 -368.501005)
				(end 242.865148 -368.51209)
			)
			(arc
				(start 242.760754 -368.616484)
				(mid 242.749643 -368.633018)
				(end 242.745768 -368.652552)
			)
			(arc
				(start 242.745768 -377.268994)
				(mid 242.749669 -377.288517)
				(end 242.760754 -377.305062)
			)
			(arc
				(start 243.120672 -377.66498)
				(mid 243.137206 -377.676091)
				(end 243.15674 -377.679966)
			)
		)
		(stroke
			(width 0)
			(type solid)
		)
		(fill yes)
		(layer "In14.Cu")
		(net "P12V_STBY_R2")
	)
	(gr_poly
		(pts
			(arc
				(start 241.741198 -376.399806)
				(mid 241.763367 -376.39459)
				(end 241.781076 -376.380248)
			)
			(arc
				(start 241.781076 -376.380248)
				(mid 241.793461 -376.365378)
				(end 241.80673 -376.351292)
			)
			(xy 242.08994 -376.068082)
			(arc
				(start 242.09502 -376.063002)
				(mid 242.106647 -376.046325)
				(end 242.110768 -376.026426)
			)
			(arc
				(start 242.110768 -368.666268)
				(mid 242.106867 -368.646745)
				(end 242.095782 -368.6302)
			)
			(arc
				(start 241.977672 -368.51209)
				(mid 241.961138 -368.500979)
				(end 241.941604 -368.497104)
			)
			(arc
				(start 236.370368 -368.497104)
				(mid 236.350845 -368.501005)
				(end 236.3343 -368.51209)
			)
			(arc
				(start 236.123734 -368.722656)
				(mid 236.112623 -368.73919)
				(end 236.108748 -368.758724)
			)
			(arc
				(start 236.108748 -376.146314)
				(mid 236.112649 -376.165837)
				(end 236.123734 -376.182382)
			)
			(arc
				(start 236.326172 -376.38482)
				(mid 236.342706 -376.395931)
				(end 236.36224 -376.399806)
			)
		)
		(stroke
			(width 0)
			(type solid)
		)
		(fill yes)
		(layer "In14.Cu")
		(net "P12V_STBY_R1")
	)
	(gr_poly
		(pts
			(arc
				(start 235.60151 -413.087058)
				(mid 235.621033 -413.083157)
				(end 235.637578 -413.072072)
			)
			(arc
				(start 236.756956 -411.952694)
				(mid 236.768067 -411.93616)
				(end 236.771942 -411.916626)
			)
			(arc
				(start 236.771942 -402.84527)
				(mid 236.796095 -402.723754)
				(end 236.864906 -402.620734)
			)
			(arc
				(start 238.766604 -400.719036)
				(mid 238.869636 -400.650255)
				(end 238.99114 -400.626072)
			)
			(arc
				(start 242.910868 -400.626072)
				(mid 242.930391 -400.622171)
				(end 242.946936 -400.611086)
			)
			(arc
				(start 243.79682 -399.761202)
				(mid 243.807931 -399.744668)
				(end 243.811806 -399.725134)
			)
			(arc
				(start 243.811806 -392.09472)
				(mid 243.835959 -391.973204)
				(end 243.90477 -391.870184)
			)
			(arc
				(start 244.93093 -390.844024)
				(mid 245.033962 -390.775243)
				(end 245.155466 -390.75106)
			)
			(arc
				(start 259.056124 -390.75106)
				(mid 259.075647 -390.747159)
				(end 259.092192 -390.736074)
			)
			(arc
				(start 262.00481 -387.823456)
				(mid 262.015921 -387.806922)
				(end 262.019796 -387.787388)
			)
			(arc
				(start 262.019796 -379.197616)
				(mid 262.015895 -379.178093)
				(end 262.00481 -379.161548)
			)
			(arc
				(start 261.967472 -379.12421)
				(mid 261.950938 -379.113099)
				(end 261.931404 -379.109224)
			)
			(arc
				(start 240.584482 -379.109224)
				(mid 240.564959 -379.113125)
				(end 240.548414 -379.12421)
			)
			(arc
				(start 239.998504 -379.67412)
				(mid 239.895472 -379.742901)
				(end 239.773968 -379.767084)
			)
			(arc
				(start 237.129066 -379.767084)
				(mid 237.00755 -379.742931)
				(end 236.90453 -379.67412)
			)
			(arc
				(start 232.953814 -375.723404)
				(mid 232.885033 -375.620372)
				(end 232.86085 -375.498868)
			)
			(arc
				(start 232.86085 -372.11508)
				(mid 232.856949 -372.095557)
				(end 232.845864 -372.079012)
			)
			(arc
				(start 232.203752 -371.4369)
				(mid 232.134971 -371.333868)
				(end 232.110788 -371.212364)
			)
			(arc
				(start 232.110788 -371.075712)
				(mid 232.106887 -371.056189)
				(end 232.095802 -371.039644)
			)
			(arc
				(start 232.035858 -370.9797)
				(mid 231.967077 -370.876668)
				(end 231.942894 -370.755164)
			)
			(arc
				(start 231.942894 -367.397792)
				(mid 231.938993 -367.378269)
				(end 231.927908 -367.361724)
			)
			(arc
				(start 231.89057 -367.324386)
				(mid 231.874036 -367.313275)
				(end 231.854502 -367.3094)
			)
			(arc
				(start 228.741986 -367.3094)
				(mid 228.722463 -367.313301)
				(end 228.705918 -367.324386)
			)
			(arc
				(start 228.66858 -367.361724)
				(mid 228.657469 -367.378258)
				(end 228.653594 -367.397792)
			)
			(arc
				(start 228.653594 -370.74856)
				(mid 228.629441 -370.870076)
				(end 228.56063 -370.973096)
			)
			(arc
				(start 228.481128 -371.052598)
				(mid 228.470017 -371.069132)
				(end 228.466142 -371.088666)
			)
			(arc
				(start 228.466142 -371.354096)
				(mid 228.441989 -371.475612)
				(end 228.373178 -371.578632)
			)
			(arc
				(start 227.178362 -372.773448)
				(mid 227.167251 -372.789982)
				(end 227.163376 -372.809516)
			)
			(arc
				(start 227.163376 -374.166384)
				(mid 227.139223 -374.2879)
				(end 227.070412 -374.39092)
			)
			(arc
				(start 225.794062 -375.66727)
				(mid 225.69103 -375.736051)
				(end 225.569526 -375.760234)
			)
			(arc
				(start 223.648016 -375.760234)
				(mid 223.5265 -375.736081)
				(end 223.42348 -375.66727)
			)
			(arc
				(start 221.55531 -373.7991)
				(mid 221.486529 -373.696068)
				(end 221.462346 -373.574564)
			)
			(arc
				(start 221.462346 -371.091714)
				(mid 221.458445 -371.072191)
				(end 221.44736 -371.055646)
			)
			(arc
				(start 221.361508 -370.969794)
				(mid 221.292727 -370.866762)
				(end 221.268544 -370.745258)
			)
			(arc
				(start 221.268544 -367.391442)
				(mid 221.264643 -367.371919)
				(end 221.253558 -367.355374)
			)
			(arc
				(start 221.225872 -367.327688)
				(mid 221.209338 -367.316577)
				(end 221.189804 -367.312702)
			)
			(arc
				(start 218.110308 -367.312702)
				(mid 218.090785 -367.316603)
				(end 218.07424 -367.327688)
			)
			(arc
				(start 217.967306 -367.434622)
				(mid 217.956195 -367.451156)
				(end 217.95232 -367.47069)
			)
			(arc
				(start 217.95232 -370.719096)
				(mid 217.928167 -370.840612)
				(end 217.859356 -370.943632)
			)
			(arc
				(start 216.82964 -371.973348)
				(mid 216.726608 -372.042129)
				(end 216.605104 -372.066312)
			)
			(arc
				(start 210.424014 -372.066312)
				(mid 210.302498 -372.042159)
				(end 210.199478 -371.973348)
			)
			(arc
				(start 210.067906 -371.841776)
				(mid 209.999125 -371.738744)
				(end 209.974942 -371.61724)
			)
			(arc
				(start 209.974942 -371.309138)
				(mid 209.971041 -371.289615)
				(end 209.959956 -371.27307)
			)
			(arc
				(start 209.949034 -371.262148)
				(mid 209.9325 -371.251037)
				(end 209.912966 -371.247162)
			)
			(arc
				(start 209.559144 -371.247162)
				(mid 209.437628 -371.223009)
				(end 209.334608 -371.154198)
			)
			(arc
				(start 208.669382 -370.488972)
				(mid 208.652848 -370.477861)
				(end 208.633314 -370.473986)
			)
			(arc
				(start 208.394554 -370.473986)
				(mid 208.273038 -370.449833)
				(end 208.170018 -370.381022)
			)
			(arc
				(start 208.11744 -370.328444)
				(mid 208.048659 -370.225412)
				(end 208.024476 -370.103908)
			)
			(arc
				(start 208.024476 -367.401348)
				(mid 208.020575 -367.381825)
				(end 208.00949 -367.36528)
			)
			(arc
				(start 207.981804 -367.337594)
				(mid 207.96527 -367.326483)
				(end 207.945736 -367.322608)
			)
			(arc
				(start 204.823822 -367.322608)
				(mid 204.804299 -367.326509)
				(end 204.787754 -367.337594)
			)
			(arc
				(start 204.740002 -367.385346)
				(mid 204.728891 -367.40188)
				(end 204.725016 -367.421414)
			)
			(arc
				(start 204.725016 -370.796312)
				(mid 204.728917 -370.815835)
				(end 204.740002 -370.83238)
			)
			(arc
				(start 204.77353 -370.865908)
				(mid 204.842311 -370.96894)
				(end 204.866494 -371.090444)
			)
			(arc
				(start 204.866494 -374.47474)
				(mid 204.870058 -374.493432)
				(end 204.88021 -374.509538)
			)
			(arc
				(start 204.88021 -374.509538)
				(mid 204.94326 -374.609679)
				(end 204.9653 -374.725946)
			)
			(arc
				(start 204.9653 -387.02361)
				(mid 204.969201 -387.043133)
				(end 204.980286 -387.059678)
			)
			(arc
				(start 207.47482 -389.554212)
				(mid 207.543601 -389.657244)
				(end 207.567784 -389.778748)
			)
			(arc
				(start 207.567784 -411.696662)
				(mid 207.571685 -411.716185)
				(end 207.58277 -411.73273)
			)
			(arc
				(start 208.922112 -413.072072)
				(mid 208.938646 -413.083183)
				(end 208.95818 -413.087058)
			)
		)
		(stroke
			(width 0)
			(type solid)
		)
		(fill yes)
		(layer "In14.Cu")
		(net "P12V_STBY")
	)
	(gr_poly
		(pts
			(xy 465.600034 -461.99552) (xy 465.655841 -461.994997) (xy 465.767141 -461.986654) (xy 465.877508 -461.970017)
			(xy 465.986322 -461.945179) (xy 466.092976 -461.912278) (xy 466.196873 -461.8715) (xy 466.297432 -461.823072)
			(xy 466.394091 -461.767264) (xy 466.48631 -461.70439) (xy 466.573572 -461.6348) (xy 466.65539 -461.558883)
			(xy 466.731306 -461.477065) (xy 466.800896 -461.389802) (xy 466.86377 -461.297583) (xy 466.919577 -461.200923)
			(xy 466.968004 -461.100364) (xy 467.008782 -460.996466) (xy 467.041681 -460.889812) (xy 467.066519 -460.780998)
			(xy 467.083155 -460.670631) (xy 467.091497 -460.559331) (xy 467.09203 -460.503524) (xy 467.09203 -422.58996)
			(xy 467.091507 -422.534153) (xy 467.083163 -422.422853) (xy 467.066526 -422.312487) (xy 467.041687 -422.203672)
			(xy 467.008787 -422.097019) (xy 466.968009 -421.993121) (xy 466.91958 -421.892562) (xy 466.863773 -421.795903)
			(xy 466.800898 -421.703684) (xy 466.731308 -421.616422) (xy 466.655392 -421.534604) (xy 466.573573 -421.458688)
			(xy 466.486311 -421.389098) (xy 466.394092 -421.326224) (xy 466.297433 -421.270417) (xy 466.196873 -421.221989)
			(xy 466.092976 -421.181211) (xy 465.986322 -421.148311) (xy 465.877508 -421.123473) (xy 465.767141 -421.106836)
			(xy 465.655841 -421.098493) (xy 465.600034 -421.097964) (xy 447.939922 -421.097964) (xy 447.884114 -421.098485)
			(xy 447.77281 -421.106824) (xy 447.66244 -421.123458) (xy 447.553622 -421.148293) (xy 447.446964 -421.181191)
			(xy 447.343062 -421.221967) (xy 447.242499 -421.270394) (xy 447.145835 -421.3262) (xy 447.053613 -421.389074)
			(xy 446.966346 -421.458664) (xy 446.884524 -421.53458) (xy 446.808604 -421.616399) (xy 446.739011 -421.703663)
			(xy 446.676133 -421.795883) (xy 446.620323 -421.892544) (xy 446.571892 -421.993106) (xy 446.531111 -422.097005)
			(xy 446.498209 -422.203662) (xy 446.47337 -422.312479) (xy 446.456731 -422.422848) (xy 446.448387 -422.534152)
			(xy 446.447926 -422.58996) (xy 446.447926 -429.090074) (xy 446.447433 -429.160429) (xy 446.439545 -429.300916)
			(xy 446.423792 -429.440741) (xy 446.400224 -429.579462) (xy 446.368915 -429.716643) (xy 446.329963 -429.851854)
			(xy 446.283491 -429.984667) (xy 446.229646 -430.114666) (xy 446.168596 -430.241441) (xy 446.100533 -430.364593)
			(xy 446.025673 -430.483736) (xy 445.94425 -430.598494) (xy 445.856521 -430.708505) (xy 445.762761 -430.813425)
			(xy 445.663266 -430.912922) (xy 445.558348 -431.006684) (xy 445.448338 -431.094416) (xy 445.333582 -431.175842)
			(xy 445.214442 -431.250705) (xy 445.091291 -431.31877) (xy 444.964517 -431.379823) (xy 444.834519 -431.433671)
			(xy 444.701707 -431.480146) (xy 444.566498 -431.519101) (xy 444.429317 -431.550413) (xy 444.290596 -431.573985)
			(xy 444.150772 -431.589741) (xy 444.010285 -431.597632) (xy 443.93993 -431.59807) (xy 371.24005 -431.59807)
			(xy 371.169695 -431.597587) (xy 371.029207 -431.5897) (xy 370.889383 -431.573948) (xy 370.750661 -431.550381)
			(xy 370.613479 -431.519072) (xy 370.478269 -431.480121) (xy 370.345455 -431.433649) (xy 370.215456 -431.379804)
			(xy 370.088681 -431.318754) (xy 369.965528 -431.250691) (xy 369.846385 -431.175831) (xy 369.731628 -431.094407)
			(xy 369.621616 -431.006677) (xy 369.516697 -430.912917) (xy 369.4172 -430.813421) (xy 369.323438 -430.708502)
			(xy 369.235707 -430.598492) (xy 369.154283 -430.483735) (xy 369.079421 -430.364593) (xy 369.011357 -430.241441)
			(xy 368.950306 -430.114666) (xy 368.896459 -429.984667) (xy 368.849986 -429.851854) (xy 368.811034 -429.716644)
			(xy 368.779724 -429.579463) (xy 368.756155 -429.440741) (xy 368.740402 -429.300917) (xy 368.732514 -429.160429)
			(xy 368.732054 -429.090074) (xy 368.732054 -422.58996) (xy 368.731543 -422.534154) (xy 368.7232 -422.422854)
			(xy 368.706562 -422.31249) (xy 368.681723 -422.203677) (xy 368.648822 -422.097024) (xy 368.608042 -421.993129)
			(xy 368.559613 -421.892571) (xy 368.503804 -421.795914) (xy 368.440929 -421.703697) (xy 368.371337 -421.616438)
			(xy 368.29542 -421.534622) (xy 368.2136 -421.458709) (xy 368.126337 -421.389123) (xy 368.034117 -421.326252)
			(xy 367.937456 -421.270449) (xy 367.836896 -421.222025) (xy 367.732998 -421.181251) (xy 367.626344 -421.148356)
			(xy 367.51753 -421.123523) (xy 367.407164 -421.106891) (xy 367.295864 -421.098554) (xy 367.240058 -421.097964)
			(xy 359.940098 -421.097964) (xy 359.88429 -421.098486) (xy 359.772988 -421.106827) (xy 359.662619 -421.123462)
			(xy 359.553802 -421.148298) (xy 359.447146 -421.181197) (xy 359.343246 -421.221974) (xy 359.242684 -421.270401)
			(xy 359.146022 -421.326208) (xy 359.053801 -421.389082) (xy 358.966536 -421.458672) (xy 358.884716 -421.534589)
			(xy 358.808797 -421.616407) (xy 358.739205 -421.70367) (xy 358.676328 -421.79589) (xy 358.620519 -421.892551)
			(xy 358.572089 -421.993111) (xy 358.53131 -422.09701) (xy 358.498408 -422.203666) (xy 358.473569 -422.312482)
			(xy 358.456931 -422.42285) (xy 358.448587 -422.534152) (xy 358.448102 -422.58996) (xy 358.448102 -429.090074)
			(xy 358.447618 -429.160429) (xy 358.43973 -429.300916) (xy 358.423977 -429.440741) (xy 358.400409 -429.579462)
			(xy 358.369099 -429.716643) (xy 358.330147 -429.851853) (xy 358.283675 -429.984667) (xy 358.229829 -430.114665)
			(xy 358.168779 -430.24144) (xy 358.100716 -430.364593) (xy 358.025856 -430.483735) (xy 357.944432 -430.598492)
			(xy 357.856702 -430.708504) (xy 357.762942 -430.813423) (xy 357.663446 -430.91292) (xy 357.558528 -431.006682)
			(xy 357.448518 -431.094413) (xy 357.333762 -431.175838) (xy 357.21462 -431.2507) (xy 357.091469 -431.318764)
			(xy 356.964695 -431.379816) (xy 356.834697 -431.433664) (xy 356.701884 -431.480138) (xy 356.566674 -431.519091)
			(xy 356.429493 -431.550403) (xy 356.290772 -431.573973) (xy 356.150948 -431.589728) (xy 356.010461 -431.597618)
			(xy 355.940106 -431.59807) (xy 283.239972 -431.59807) (xy 283.169619 -431.597576) (xy 283.029135 -431.589685)
			(xy 282.889313 -431.573929) (xy 282.750596 -431.550359) (xy 282.613418 -431.519047) (xy 282.478212 -431.480093)
			(xy 282.345402 -431.43362) (xy 282.215407 -431.379772) (xy 282.088636 -431.318721) (xy 281.965488 -431.250657)
			(xy 281.84635 -431.175796) (xy 281.731596 -431.094372) (xy 281.621589 -431.006642) (xy 281.516674 -430.912882)
			(xy 281.417181 -430.813387) (xy 281.323423 -430.70847) (xy 281.235695 -430.598461) (xy 281.154274 -430.483705)
			(xy 281.079415 -430.364565) (xy 281.011354 -430.241416) (xy 280.950306 -430.114643) (xy 280.896461 -429.984647)
			(xy 280.84999 -429.851837) (xy 280.811039 -429.71663) (xy 280.779731 -429.579451) (xy 280.756163 -429.440733)
			(xy 280.740411 -429.300912) (xy 280.732523 -429.160427) (xy 280.731976 -429.090074) (xy 280.731976 -422.58996)
			(xy 280.731453 -422.534154) (xy 280.723109 -422.422855) (xy 280.706471 -422.31249) (xy 280.681633 -422.203678)
			(xy 280.648732 -422.097025) (xy 280.607953 -421.99313) (xy 280.559525 -421.892573) (xy 280.503717 -421.795915)
			(xy 280.440842 -421.703699) (xy 280.371251 -421.616439) (xy 280.295334 -421.534623) (xy 280.213516 -421.45871)
			(xy 280.126253 -421.389123) (xy 280.034034 -421.326251) (xy 279.937374 -421.270447) (xy 279.836815 -421.222023)
			(xy 279.732918 -421.181248) (xy 279.626264 -421.148352) (xy 279.517451 -421.123517) (xy 279.407085 -421.106884)
			(xy 279.295786 -421.098545) (xy 279.23998 -421.097964) (xy 276.880066 -421.097964) (xy 276.824259 -421.098487)
			(xy 276.712958 -421.10683) (xy 276.602591 -421.123467) (xy 276.493777 -421.148305) (xy 276.387122 -421.181205)
			(xy 276.283225 -421.221984) (xy 276.182665 -421.270412) (xy 276.086005 -421.326219) (xy 275.993786 -421.389094)
			(xy 275.906523 -421.458684) (xy 275.824704 -421.5346) (xy 275.748787 -421.616418) (xy 275.679197 -421.703681)
			(xy 275.616322 -421.7959) (xy 275.560514 -421.892559) (xy 275.512086 -421.993119) (xy 275.471307 -422.097017)
			(xy 275.438407 -422.203671) (xy 275.413568 -422.312485) (xy 275.396931 -422.422852) (xy 275.388587 -422.534153)
			(xy 275.38807 -422.58996) (xy 275.38807 -430.55794) (xy 275.387576 -430.628293) (xy 275.379684 -430.768777)
			(xy 275.363928 -430.908597) (xy 275.340357 -431.047314) (xy 275.309045 -431.184492) (xy 275.27009 -431.319698)
			(xy 275.223616 -431.452506) (xy 275.169769 -431.582501) (xy 275.108717 -431.709271) (xy 275.040653 -431.832419)
			(xy 274.965792 -431.951557) (xy 274.884368 -432.066309) (xy 274.796638 -432.176316) (xy 274.702878 -432.281231)
			(xy 274.603383 -432.380723) (xy 274.498466 -432.474481) (xy 274.388457 -432.562208) (xy 274.273702 -432.643629)
			(xy 274.154562 -432.718487) (xy 274.031412 -432.786547) (xy 273.90464 -432.847596) (xy 273.774645 -432.90144)
			(xy 273.641835 -432.94791) (xy 273.506628 -432.986861) (xy 273.36945 -433.018169) (xy 273.230732 -433.041737)
			(xy 273.090911 -433.05749) (xy 272.950427 -433.065377) (xy 272.880074 -433.065936) (xy 202.360022 -433.065936)
			(xy 202.289667 -433.065443) (xy 202.14918 -433.057555) (xy 202.009355 -433.041802) (xy 201.870634 -433.018234)
			(xy 201.733452 -432.986924) (xy 201.598242 -432.947972) (xy 201.465429 -432.9015) (xy 201.33543 -432.847655)
			(xy 201.208655 -432.786605) (xy 201.085502 -432.718542) (xy 200.96636 -432.643682) (xy 200.851602 -432.562259)
			(xy 200.74159 -432.47453) (xy 200.63667 -432.38077) (xy 200.537173 -432.281275) (xy 200.44341 -432.176357)
			(xy 200.355678 -432.066348) (xy 200.274252 -431.951592) (xy 200.199389 -431.832451) (xy 200.131324 -431.7093)
			(xy 200.070271 -431.582527) (xy 200.016422 -431.452529) (xy 199.969947 -431.319717) (xy 199.930991 -431.184508)
			(xy 199.899679 -431.047327) (xy 199.876107 -430.908606) (xy 199.86035 -430.768782) (xy 199.852458 -430.628295)
			(xy 199.852026 -430.55794) (xy 199.852026 -422.58996) (xy 199.851503 -422.534154) (xy 199.843159 -422.422853)
			(xy 199.826522 -422.312487) (xy 199.801683 -422.203673) (xy 199.768783 -422.097019) (xy 199.728004 -421.993122)
			(xy 199.679576 -421.892563) (xy 199.623769 -421.795904) (xy 199.560894 -421.703685) (xy 199.491304 -421.616423)
			(xy 199.415387 -421.534606) (xy 199.333569 -421.45869) (xy 199.246306 -421.3891) (xy 199.154088 -421.326226)
			(xy 199.057428 -421.270419) (xy 198.956869 -421.221992) (xy 198.852972 -421.181214) (xy 198.746318 -421.148314)
			(xy 198.637503 -421.123476) (xy 198.527137 -421.10684) (xy 198.415836 -421.098497) (xy 198.36003 -421.097964)
			(xy 188.36005 -421.097964) (xy 188.304244 -421.098488) (xy 188.192943 -421.106832) (xy 188.082578 -421.12347)
			(xy 187.973764 -421.148309) (xy 187.86711 -421.18121) (xy 187.763214 -421.221988) (xy 187.662655 -421.270417)
			(xy 187.565996 -421.326225) (xy 187.473778 -421.389099) (xy 187.386516 -421.458689) (xy 187.304699 -421.534606)
			(xy 187.228783 -421.616424) (xy 187.159193 -421.703686) (xy 187.096319 -421.795905) (xy 187.040512 -421.892564)
			(xy 186.992084 -421.993123) (xy 186.951306 -422.09702) (xy 186.918406 -422.203673) (xy 186.893568 -422.312487)
			(xy 186.876931 -422.422853) (xy 186.868587 -422.534154) (xy 186.868054 -422.58996) (xy 186.868054 -429.090074)
			(xy 186.86757 -429.160428) (xy 186.859682 -429.300915) (xy 186.843929 -429.440738) (xy 186.820361 -429.579458)
			(xy 186.789051 -429.716639) (xy 186.750099 -429.851848) (xy 186.703626 -429.98466) (xy 186.64978 -430.114658)
			(xy 186.58873 -430.241431) (xy 186.520667 -430.364582) (xy 186.445806 -430.483723) (xy 186.364382 -430.598479)
			(xy 186.276652 -430.708489) (xy 186.182891 -430.813407) (xy 186.083395 -430.912902) (xy 185.978477 -431.006662)
			(xy 185.868467 -431.094392) (xy 185.75371 -431.175815) (xy 185.634569 -431.250675) (xy 185.511417 -431.318737)
			(xy 185.384643 -431.379787) (xy 185.254645 -431.433632) (xy 185.121833 -431.480104) (xy 184.986623 -431.519055)
			(xy 184.849443 -431.550364) (xy 184.710722 -431.573931) (xy 184.570899 -431.589684) (xy 184.430412 -431.597571)
			(xy 184.360058 -431.59807) (xy 111.660178 -431.59807) (xy 111.589825 -431.597585) (xy 111.449339 -431.589694)
			(xy 111.309518 -431.573939) (xy 111.170799 -431.550369) (xy 111.033621 -431.519057) (xy 110.898414 -431.480103)
			(xy 110.765603 -431.43363) (xy 110.635608 -431.379782) (xy 110.508836 -431.318731) (xy 110.385687 -431.250667)
			(xy 110.266548 -431.175806) (xy 110.151794 -431.094382) (xy 110.041786 -431.006651) (xy 109.93687 -430.912891)
			(xy 109.837376 -430.813395) (xy 109.743618 -430.708478) (xy 109.65589 -430.598468) (xy 109.574468 -430.483712)
			(xy 109.499608 -430.364572) (xy 109.431547 -430.241421) (xy 109.370498 -430.114648) (xy 109.316653 -429.984652)
			(xy 109.270182 -429.851841) (xy 109.231231 -429.716633) (xy 109.199922 -429.579454) (xy 109.176354 -429.440735)
			(xy 109.160602 -429.300913) (xy 109.152714 -429.160427) (xy 109.152182 -429.090074) (xy 109.152182 -422.58996)
			(xy 109.151659 -422.534154) (xy 109.143315 -422.422855) (xy 109.126678 -422.31249) (xy 109.101839 -422.203677)
			(xy 109.068938 -422.097025) (xy 109.02816 -421.993129) (xy 108.979731 -421.892571) (xy 108.923923 -421.795914)
			(xy 108.861048 -421.703697) (xy 108.791457 -421.616437) (xy 108.715541 -421.534621) (xy 108.633722 -421.458707)
			(xy 108.546459 -421.38912) (xy 108.45424 -421.326248) (xy 108.357581 -421.270444) (xy 108.257021 -421.222019)
			(xy 108.153124 -421.181244) (xy 108.046471 -421.148347) (xy 107.937657 -421.123512) (xy 107.827292 -421.106879)
			(xy 107.715992 -421.098539) (xy 107.660186 -421.097964) (xy 100.359972 -421.097964) (xy 100.304165 -421.098487)
			(xy 100.192864 -421.106829) (xy 100.082497 -421.123466) (xy 99.973681 -421.148304) (xy 99.867027 -421.181204)
			(xy 99.763129 -421.221982) (xy 99.662568 -421.27041) (xy 99.565908 -421.326217) (xy 99.473689 -421.389091)
			(xy 99.386425 -421.458681) (xy 99.304606 -421.534598) (xy 99.228689 -421.616416) (xy 99.159099 -421.703679)
			(xy 99.096223 -421.795898) (xy 99.040415 -421.892558) (xy 98.991987 -421.993118) (xy 98.951208 -422.097015)
			(xy 98.918307 -422.20367) (xy 98.893468 -422.312485) (xy 98.876831 -422.422852) (xy 98.868487 -422.534153)
			(xy 98.867976 -422.58996) (xy 98.867976 -429.090074) (xy 98.867492 -429.160428) (xy 98.859604 -429.300915)
			(xy 98.843851 -429.440739) (xy 98.820283 -429.57946) (xy 98.788973 -429.716641) (xy 98.750021 -429.85185)
			(xy 98.703549 -429.984663) (xy 98.649703 -430.114661) (xy 98.588652 -430.241435) (xy 98.520589 -430.364587)
			(xy 98.445729 -430.483729) (xy 98.364305 -430.598485) (xy 98.276575 -430.708496) (xy 98.182814 -430.813414)
			(xy 98.083319 -430.91291) (xy 97.9784 -431.006671) (xy 97.86839 -431.094401) (xy 97.753634 -431.175825)
			(xy 97.634492 -431.250686) (xy 97.511341 -431.31875) (xy 97.384567 -431.3798) (xy 97.254569 -431.433647)
			(xy 97.121756 -431.480119) (xy 96.986547 -431.519072) (xy 96.849366 -431.550382) (xy 96.710645 -431.57395)
			(xy 96.570821 -431.589704) (xy 96.430334 -431.597592) (xy 96.35998 -431.59807) (xy 23.6601 -431.59807)
			(xy 23.589746 -431.597586) (xy 23.44926 -431.589696) (xy 23.309437 -431.573942) (xy 23.170718 -431.550372)
			(xy 23.033539 -431.519062) (xy 22.89833 -431.480109) (xy 22.765519 -431.433636) (xy 22.635522 -431.379789)
			(xy 22.50875 -431.318738) (xy 22.385599 -431.250675) (xy 22.266459 -431.175813) (xy 22.151704 -431.094389)
			(xy 22.041695 -431.006659) (xy 21.936778 -430.912899) (xy 21.837283 -430.813403) (xy 21.743524 -430.708485)
			(xy 21.655795 -430.598475) (xy 21.574372 -430.483719) (xy 21.499512 -430.364578) (xy 21.43145 -430.241427)
			(xy 21.370401 -430.114654) (xy 21.316555 -429.984657) (xy 21.270083 -429.851845) (xy 21.231132 -429.716636)
			(xy 21.199823 -429.579456) (xy 21.176255 -429.440737) (xy 21.160502 -429.300914) (xy 21.152614 -429.160428)
			(xy 21.152104 -429.090074) (xy 21.152104 -422.58996) (xy 21.151595 -422.534153) (xy 21.143254 -422.42285)
			(xy 21.126618 -422.312481) (xy 21.101782 -422.203665) (xy 21.068883 -422.097009) (xy 21.028105 -421.993109)
			(xy 20.979677 -421.892548) (xy 20.92387 -421.795886) (xy 20.860995 -421.703666) (xy 20.791404 -421.616402)
			(xy 20.715486 -421.534582) (xy 20.633667 -421.458665) (xy 20.546403 -421.389074) (xy 20.454182 -421.326199)
			(xy 20.357521 -421.270392) (xy 20.256959 -421.221964) (xy 20.153059 -421.181187) (xy 20.046403 -421.148288)
			(xy 19.937587 -421.123451) (xy 19.827218 -421.106816) (xy 19.715915 -421.098475) (xy 19.660108 -421.097964)
			(xy 1.999996 -421.097964) (xy 1.944189 -421.098486) (xy 1.832887 -421.106827) (xy 1.72252 -421.123463)
			(xy 1.613705 -421.148299) (xy 1.50705 -421.181198) (xy 1.403151 -421.221976) (xy 1.302591 -421.270403)
			(xy 1.20593 -421.32621) (xy 1.113711 -421.389085) (xy 1.026448 -421.458675) (xy 0.944629 -421.534592)
			(xy 0.868712 -421.616411) (xy 0.799122 -421.703674) (xy 0.736248 -421.795894) (xy 0.680441 -421.892554)
			(xy 0.632014 -421.993115) (xy 0.591237 -422.097013) (xy 0.558338 -422.203669) (xy 0.533502 -422.312484)
			(xy 0.516867 -422.422851) (xy 0.508526 -422.534153) (xy 0.508 -422.58996) (xy 0.508 -457.5681) (xy 2.904225 -457.5681)
			(xy 2.904225 -457.43896) (xy 2.912175 -457.310065) (xy 2.928045 -457.181905) (xy 2.951774 -457.054964)
			(xy 2.983273 -456.929725) (xy 3.022422 -456.806662) (xy 3.069073 -456.686243) (xy 3.123048 -456.568924)
			(xy 3.184143 -456.45515) (xy 3.252126 -456.345353) (xy 3.32674 -456.23995) (xy 3.407701 -456.13934)
			(xy 3.494701 -456.043905) (xy 3.587412 -455.954006) (xy 3.685482 -455.869985) (xy 3.788537 -455.792161)
			(xy 3.896188 -455.720829) (xy 4.008027 -455.656259) (xy 4.123628 -455.598697) (xy 4.242553 -455.54836)
			(xy 4.364352 -455.50544) (xy 4.488562 -455.470099) (xy 4.614711 -455.442472) (xy 4.742323 -455.422663)
			(xy 4.870912 -455.410747) (xy 4.99999 -455.406771) (xy 5.129068 -455.410747) (xy 5.257657 -455.422663)
			(xy 5.385269 -455.442472) (xy 5.511418 -455.470099) (xy 5.635628 -455.50544) (xy 5.757427 -455.54836)
			(xy 5.876352 -455.598697) (xy 5.991953 -455.656259) (xy 6.103792 -455.720829) (xy 6.211443 -455.792161)
			(xy 6.314498 -455.869985) (xy 6.412568 -455.954006) (xy 6.505279 -456.043905) (xy 6.592279 -456.13934)
			(xy 6.67324 -456.23995) (xy 6.747854 -456.345353) (xy 6.815837 -456.45515) (xy 6.876932 -456.568924)
			(xy 6.930907 -456.686243) (xy 6.977558 -456.806662) (xy 7.016707 -456.929725) (xy 7.048206 -457.054964)
			(xy 7.071935 -457.181905) (xy 7.087805 -457.310065) (xy 7.095755 -457.43896) (xy 7.096252 -457.50353)
			(xy 7.095755 -457.5681) (xy 460.504275 -457.5681) (xy 460.504275 -457.43896) (xy 460.512225 -457.310065)
			(xy 460.528095 -457.181905) (xy 460.551824 -457.054964) (xy 460.583323 -456.929725) (xy 460.622472 -456.806662)
			(xy 460.669123 -456.686243) (xy 460.723098 -456.568924) (xy 460.784193 -456.45515) (xy 460.852176 -456.345353)
			(xy 460.92679 -456.23995) (xy 461.007751 -456.13934) (xy 461.094751 -456.043905) (xy 461.187462 -455.954006)
			(xy 461.285532 -455.869985) (xy 461.388587 -455.792161) (xy 461.496238 -455.720829) (xy 461.608077 -455.656259)
			(xy 461.723678 -455.598697) (xy 461.842603 -455.54836) (xy 461.964402 -455.50544) (xy 462.088612 -455.470099)
			(xy 462.214761 -455.442472) (xy 462.342373 -455.422663) (xy 462.470962 -455.410747) (xy 462.60004 -455.406771)
			(xy 462.729118 -455.410747) (xy 462.857707 -455.422663) (xy 462.985319 -455.442472) (xy 463.111468 -455.470099)
			(xy 463.235678 -455.50544) (xy 463.357477 -455.54836) (xy 463.476402 -455.598697) (xy 463.592003 -455.656259)
			(xy 463.703842 -455.720829) (xy 463.811493 -455.792161) (xy 463.914548 -455.869985) (xy 464.012618 -455.954006)
			(xy 464.105329 -456.043905) (xy 464.192329 -456.13934) (xy 464.27329 -456.23995) (xy 464.347904 -456.345353)
			(xy 464.415887 -456.45515) (xy 464.476982 -456.568924) (xy 464.530957 -456.686243) (xy 464.577608 -456.806662)
			(xy 464.616757 -456.929725) (xy 464.648256 -457.054964) (xy 464.671985 -457.181905) (xy 464.687855 -457.310065)
			(xy 464.695805 -457.43896) (xy 464.696302 -457.50353) (xy 464.695805 -457.5681) (xy 464.687855 -457.696995)
			(xy 464.671985 -457.825155) (xy 464.648256 -457.952096) (xy 464.616757 -458.077335) (xy 464.577608 -458.200398)
			(xy 464.530957 -458.320817) (xy 464.476982 -458.438136) (xy 464.415887 -458.55191) (xy 464.347904 -458.661707)
			(xy 464.27329 -458.76711) (xy 464.192329 -458.86772) (xy 464.105329 -458.963155) (xy 464.012618 -459.053054)
			(xy 463.914548 -459.137075) (xy 463.811493 -459.214899) (xy 463.703842 -459.286231) (xy 463.592003 -459.350801)
			(xy 463.476402 -459.408363) (xy 463.357477 -459.4587) (xy 463.235678 -459.50162) (xy 463.111468 -459.536961)
			(xy 462.985319 -459.564588) (xy 462.857707 -459.584397) (xy 462.729118 -459.596313) (xy 462.60004 -459.60029)
			(xy 462.470962 -459.596313) (xy 462.342373 -459.584397) (xy 462.214761 -459.564588) (xy 462.088612 -459.536961)
			(xy 461.964402 -459.50162) (xy 461.842603 -459.4587) (xy 461.723678 -459.408363) (xy 461.608077 -459.350801)
			(xy 461.496238 -459.286231) (xy 461.388587 -459.214899) (xy 461.285532 -459.137075) (xy 461.187462 -459.053054)
			(xy 461.094751 -458.963155) (xy 461.007751 -458.86772) (xy 460.92679 -458.76711) (xy 460.852176 -458.661707)
			(xy 460.784193 -458.55191) (xy 460.723098 -458.438136) (xy 460.669123 -458.320817) (xy 460.622472 -458.200398)
			(xy 460.583323 -458.077335) (xy 460.551824 -457.952096) (xy 460.528095 -457.825155) (xy 460.512225 -457.696995)
			(xy 460.504275 -457.5681) (xy 7.095755 -457.5681) (xy 7.087805 -457.696995) (xy 7.071935 -457.825155)
			(xy 7.048206 -457.952096) (xy 7.016707 -458.077335) (xy 6.977558 -458.200398) (xy 6.930907 -458.320817)
			(xy 6.876932 -458.438136) (xy 6.815837 -458.55191) (xy 6.747854 -458.661707) (xy 6.67324 -458.76711)
			(xy 6.592279 -458.86772) (xy 6.505279 -458.963155) (xy 6.412568 -459.053054) (xy 6.314498 -459.137075)
			(xy 6.211443 -459.214899) (xy 6.103792 -459.286231) (xy 5.991953 -459.350801) (xy 5.876352 -459.408363)
			(xy 5.757427 -459.4587) (xy 5.635628 -459.50162) (xy 5.511418 -459.536961) (xy 5.385269 -459.564588)
			(xy 5.257657 -459.584397) (xy 5.129068 -459.596313) (xy 4.99999 -459.60029) (xy 4.870912 -459.596313)
			(xy 4.742323 -459.584397) (xy 4.614711 -459.564588) (xy 4.488562 -459.536961) (xy 4.364352 -459.50162)
			(xy 4.242553 -459.4587) (xy 4.123628 -459.408363) (xy 4.008027 -459.350801) (xy 3.896188 -459.286231)
			(xy 3.788537 -459.214899) (xy 3.685482 -459.137075) (xy 3.587412 -459.053054) (xy 3.494701 -458.963155)
			(xy 3.407701 -458.86772) (xy 3.32674 -458.76711) (xy 3.252126 -458.661707) (xy 3.184143 -458.55191)
			(xy 3.123048 -458.438136) (xy 3.069073 -458.320817) (xy 3.022422 -458.200398) (xy 2.983273 -458.077335)
			(xy 2.951774 -457.952096) (xy 2.928045 -457.825155) (xy 2.912175 -457.696995) (xy 2.904225 -457.5681)
			(xy 0.508 -457.5681) (xy 0.508 -460.503524) (xy 0.508522 -460.559331) (xy 0.516863 -460.670633) (xy 0.533498 -460.781)
			(xy 0.558335 -460.889816) (xy 0.591234 -460.996471) (xy 0.632011 -461.10037) (xy 0.680438 -461.20093)
			(xy 0.736246 -461.297591) (xy 0.79912 -461.389811) (xy 0.86871 -461.477074) (xy 0.944627 -461.558893)
			(xy 1.026446 -461.63481) (xy 1.113709 -461.7044) (xy 1.205929 -461.767274) (xy 1.30259 -461.823082)
			(xy 1.40315 -461.871509) (xy 1.507049 -461.912286) (xy 1.613704 -461.945185) (xy 1.72252 -461.970022)
			(xy 1.832887 -461.986657) (xy 1.944189 -461.994998) (xy 1.999996 -461.99552)
		)
		(stroke
			(width 0)
			(type solid)
		)
		(fill yes)
		(layer "In14.Cu")
		(net "COUPON_GND1")
	)
	(gr_poly
		(pts
			(xy 13.96492 -10.342118) (xy 14.020727 -10.341596) (xy 14.132028 -10.333253) (xy 14.242395 -10.316617)
			(xy 14.35121 -10.29178) (xy 14.457865 -10.25888) (xy 14.561763 -10.218102) (xy 14.662323 -10.169674)
			(xy 14.758983 -10.113867) (xy 14.851203 -10.050993) (xy 14.938466 -9.981402) (xy 15.020284 -9.905486)
			(xy 15.096201 -9.823667) (xy 15.165791 -9.736404) (xy 15.228666 -9.644185) (xy 15.284473 -9.547525)
			(xy 15.332901 -9.446965) (xy 15.373679 -9.343067) (xy 15.406579 -9.236412) (xy 15.431417 -9.127597)
			(xy 15.448053 -9.01723) (xy 15.456395 -8.905929) (xy 15.456916 -8.850122) (xy 15.456916 0) (xy 15.4574 0.070354)
			(xy 15.46529 0.21084) (xy 15.481044 0.350663) (xy 15.504614 0.489383) (xy 15.535924 0.626563) (xy 15.574877 0.761771)
			(xy 15.62135 0.894583) (xy 15.675197 1.02458) (xy 15.736248 1.151353) (xy 15.804311 1.274504) (xy 15.879172 1.393644)
			(xy 15.960596 1.5084) (xy 16.048326 1.618409) (xy 16.142086 1.723327) (xy 16.241582 1.822822) (xy 16.3465 1.916582)
			(xy 16.45651 2.004311) (xy 16.571266 2.085734) (xy 16.690407 2.160595) (xy 16.813558 2.228658) (xy 16.940331 2.289708)
			(xy 17.070328 2.343554) (xy 17.20314 2.390026) (xy 17.338349 2.428979) (xy 17.475529 2.460289) (xy 17.614249 2.483858)
			(xy 17.754072 2.499611) (xy 17.894558 2.5075) (xy 17.964912 2.507996) (xy 33.96488 2.507996) (xy 34.035234 2.507512)
			(xy 34.175722 2.499624) (xy 34.315546 2.48387) (xy 34.454267 2.460302) (xy 34.591448 2.428992) (xy 34.726657 2.39004)
			(xy 34.85947 2.343568) (xy 34.989468 2.289721) (xy 35.116243 2.228671) (xy 35.239395 2.160608) (xy 35.358537 2.085747)
			(xy 35.473294 2.004324) (xy 35.583304 1.916594) (xy 35.688223 1.822833) (xy 35.78772 1.723338) (xy 35.881481 1.61842)
			(xy 35.969212 1.50841) (xy 36.050636 1.393653) (xy 36.125498 1.274512) (xy 36.193562 1.151361) (xy 36.254613 1.024587)
			(xy 36.30846 0.894589) (xy 36.354934 0.761776) (xy 36.393887 0.626567) (xy 36.425198 0.489386) (xy 36.448768 0.350666)
			(xy 36.464522 0.210842) (xy 36.472412 0.070354) (xy 36.472876 0) (xy 36.472876 -8.850122) (xy 36.473399 -8.905929)
			(xy 36.481741 -9.01723) (xy 36.498377 -9.127597) (xy 36.523215 -9.236413) (xy 36.556114 -9.343067)
			(xy 36.596892 -9.446965) (xy 36.64532 -9.547526) (xy 36.701127 -9.644186) (xy 36.764002 -9.736405)
			(xy 36.833592 -9.823668) (xy 36.909508 -9.905487) (xy 36.991327 -9.981404) (xy 37.07859 -10.050995)
			(xy 37.170809 -10.113869) (xy 37.267469 -10.169677) (xy 37.368029 -10.218105) (xy 37.471927 -10.258884)
			(xy 37.578582 -10.291784) (xy 37.687397 -10.316622) (xy 37.797764 -10.333258) (xy 37.909065 -10.341601)
			(xy 37.964872 -10.342118) (xy 39.965122 -10.342118) (xy 40.020929 -10.341595) (xy 40.13223 -10.333253)
			(xy 40.242597 -10.316617) (xy 40.351412 -10.291779) (xy 40.458067 -10.258879) (xy 40.561964 -10.218102)
			(xy 40.662525 -10.169674) (xy 40.759184 -10.113866) (xy 40.851404 -10.050992) (xy 40.938667 -9.981402)
			(xy 41.020485 -9.905485) (xy 41.096402 -9.823667) (xy 41.165992 -9.736404) (xy 41.228866 -9.644184)
			(xy 41.284674 -9.547525) (xy 41.333102 -9.446964) (xy 41.373879 -9.343067) (xy 41.406779 -9.236412)
			(xy 41.431617 -9.127597) (xy 41.448253 -9.01723) (xy 41.456595 -8.905929) (xy 41.457118 -8.850122)
			(xy 41.457118 0) (xy 41.457602 0.070354) (xy 41.465492 0.21084) (xy 41.481246 0.350663) (xy 41.504816 0.489383)
			(xy 41.536126 0.626563) (xy 41.575079 0.761771) (xy 41.621552 0.894583) (xy 41.675399 1.02458) (xy 41.73645 1.151353)
			(xy 41.804513 1.274503) (xy 41.879374 1.393644) (xy 41.960798 1.508399) (xy 42.048528 1.618409) (xy 42.142288 1.723326)
			(xy 42.241784 1.822821) (xy 42.346702 1.916581) (xy 42.456712 2.00431) (xy 42.571468 2.085733) (xy 42.690609 2.160594)
			(xy 42.81376 2.228657) (xy 42.940533 2.289707) (xy 43.07053 2.343553) (xy 43.203342 2.390025) (xy 43.338551 2.428977)
			(xy 43.475731 2.460287) (xy 43.614451 2.483856) (xy 43.754274 2.499609) (xy 43.89476 2.507498) (xy 43.965114 2.507996)
			(xy 59.965082 2.507996) (xy 60.035436 2.507512) (xy 60.175924 2.499624) (xy 60.315748 2.48387) (xy 60.454468 2.460301)
			(xy 60.591649 2.428992) (xy 60.726859 2.390039) (xy 60.859672 2.343567) (xy 60.98967 2.289721) (xy 61.116444 2.22867)
			(xy 61.239596 2.160607) (xy 61.358738 2.085747) (xy 61.473495 2.004323) (xy 61.583505 1.916593) (xy 61.688424 1.822833)
			(xy 61.78792 1.723337) (xy 61.881681 1.618419) (xy 61.969412 1.508409) (xy 62.050837 1.393653) (xy 62.125698 1.274512)
			(xy 62.193762 1.15136) (xy 62.254813 1.024586) (xy 62.308661 0.894588) (xy 62.355134 0.761776) (xy 62.394087 0.626567)
			(xy 62.425398 0.489386) (xy 62.448968 0.350665) (xy 62.464722 0.210842) (xy 62.472612 0.070354) (xy 62.473078 0)
			(xy 62.473078 -8.850122) (xy 62.473601 -8.905929) (xy 62.481943 -9.01723) (xy 62.498579 -9.127597)
			(xy 62.523417 -9.236412) (xy 62.556316 -9.343067) (xy 62.597094 -9.446965) (xy 62.645522 -9.547525)
			(xy 62.701329 -9.644185) (xy 62.764204 -9.736405) (xy 62.833794 -9.823668) (xy 62.909711 -9.905487)
			(xy 62.991529 -9.981403) (xy 63.078792 -10.050994) (xy 63.171011 -10.113868) (xy 63.267671 -10.169676)
			(xy 63.368231 -10.218104) (xy 63.472129 -10.258882) (xy 63.578784 -10.291782) (xy 63.687599 -10.31662)
			(xy 63.797966 -10.333257) (xy 63.909267 -10.341599) (xy 63.965074 -10.342118) (xy 65.96507 -10.342118)
			(xy 66.020879 -10.34161) (xy 66.132184 -10.333271) (xy 66.242554 -10.316637) (xy 66.351373 -10.291802)
			(xy 66.458032 -10.258905) (xy 66.561934 -10.218128) (xy 66.662499 -10.169702) (xy 66.759163 -10.113895)
			(xy 66.851386 -10.05102) (xy 66.938653 -9.98143) (xy 67.020476 -9.905512) (xy 67.096396 -9.823693)
			(xy 67.165989 -9.736428) (xy 67.228867 -9.644207) (xy 67.284677 -9.547545) (xy 67.333108 -9.446982)
			(xy 67.373888 -9.343081) (xy 67.406789 -9.236424) (xy 67.431628 -9.127605) (xy 67.448265 -9.017235)
			(xy 67.456608 -8.905931) (xy 67.457066 -8.850122) (xy 67.457066 0) (xy 67.457559 0.070354) (xy 67.465449 0.210841)
			(xy 67.481203 0.350665) (xy 67.504772 0.489385) (xy 67.536082 0.626565) (xy 67.575035 0.761774) (xy 67.621508 0.894587)
			(xy 67.675354 1.024584) (xy 67.736404 1.151358) (xy 67.804467 1.27451) (xy 67.879328 1.393651) (xy 67.960751 1.508408)
			(xy 68.04848 1.618419) (xy 68.14224 1.723337) (xy 68.241735 1.822834) (xy 68.346652 1.916595) (xy 68.456662 2.004326)
			(xy 68.571417 2.085751) (xy 68.690557 2.160614) (xy 68.813708 2.228678) (xy 68.940481 2.289731) (xy 69.070478 2.343579)
			(xy 69.203289 2.390053) (xy 69.338498 2.429008) (xy 69.475678 2.46032) (xy 69.614398 2.483892) (xy 69.754221 2.499648)
			(xy 69.894708 2.50754) (xy 69.965062 2.507996) (xy 85.96503 2.507996) (xy 86.035383 2.507502) (xy 86.175868 2.499611)
			(xy 86.31569 2.483855) (xy 86.454408 2.460284) (xy 86.591586 2.428973) (xy 86.726793 2.390019) (xy 86.859603 2.343545)
			(xy 86.989598 2.289698) (xy 87.11637 2.228647) (xy 87.239519 2.160584) (xy 87.358658 2.085722) (xy 87.473412 2.004299)
			(xy 87.58342 1.916569) (xy 87.688336 1.822809) (xy 87.78783 1.723314) (xy 87.881588 1.618397) (xy 87.969317 1.508388)
			(xy 88.050739 1.393633) (xy 88.125599 1.274493) (xy 88.193661 1.151343) (xy 88.254711 1.024571) (xy 88.308556 0.894575)
			(xy 88.355028 0.761764) (xy 88.39398 0.626557) (xy 88.42529 0.489378) (xy 88.448859 0.35066) (xy 88.464613 0.210838)
			(xy 88.472503 0.070353) (xy 88.473026 0) (xy 88.473026 -8.850122) (xy 88.473549 -8.905928) (xy 88.481891 -9.017228)
			(xy 88.498528 -9.127594) (xy 88.523365 -9.236408) (xy 88.556265 -9.343061) (xy 88.597043 -9.446957)
			(xy 88.645472 -9.547516) (xy 88.701279 -9.644174) (xy 88.764154 -9.736392) (xy 88.833745 -9.823653)
			(xy 88.909662 -9.90547) (xy 88.99148 -9.981384) (xy 89.078743 -10.050972) (xy 89.170963 -10.113844)
			(xy 89.267623 -10.169649) (xy 89.368183 -10.218074) (xy 89.472081 -10.258849) (xy 89.578735 -10.291746)
			(xy 89.687549 -10.316581) (xy 89.797915 -10.333214) (xy 89.909216 -10.341553) (xy 89.965022 -10.342118)
			(xy 91.965018 -10.342118) (xy 92.020825 -10.341596) (xy 92.132127 -10.333254) (xy 92.242494 -10.316617)
			(xy 92.351309 -10.29178) (xy 92.457964 -10.258881) (xy 92.561862 -10.218103) (xy 92.662422 -10.169675)
			(xy 92.759082 -10.113868) (xy 92.851302 -10.050993) (xy 92.938565 -9.981403) (xy 93.020384 -9.905487)
			(xy 93.096301 -9.823668) (xy 93.165891 -9.736405) (xy 93.228766 -9.644186) (xy 93.284573 -9.547526)
			(xy 93.333001 -9.446965) (xy 93.373779 -9.343067) (xy 93.406679 -9.236413) (xy 93.431517 -9.127597)
			(xy 93.448153 -9.01723) (xy 93.456495 -8.905929) (xy 93.457014 -8.850122) (xy 93.457014 0) (xy 93.457498 0.070354)
			(xy 93.465388 0.21084) (xy 93.481142 0.350663) (xy 93.504712 0.489383) (xy 93.536022 0.626563) (xy 93.574975 0.761771)
			(xy 93.621448 0.894583) (xy 93.675295 1.02458) (xy 93.736346 1.151353) (xy 93.804409 1.274504) (xy 93.87927 1.393645)
			(xy 93.960694 1.5084) (xy 94.048424 1.61841) (xy 94.142184 1.723327) (xy 94.24168 1.822823) (xy 94.346598 1.916583)
			(xy 94.456608 2.004312) (xy 94.571364 2.085735) (xy 94.690505 2.160596) (xy 94.813655 2.228659) (xy 94.940429 2.289709)
			(xy 95.070426 2.343555) (xy 95.203238 2.390028) (xy 95.338447 2.42898) (xy 95.475627 2.46029) (xy 95.614347 2.483859)
			(xy 95.75417 2.499613) (xy 95.894656 2.507502) (xy 95.96501 2.507996) (xy 124.06503 2.507996) (xy 124.135383 2.507502)
			(xy 124.275868 2.499611) (xy 124.41569 2.483855) (xy 124.554408 2.460284) (xy 124.691586 2.428973)
			(xy 124.826793 2.390019) (xy 124.959603 2.343545) (xy 125.089598 2.289698) (xy 125.21637 2.228647)
			(xy 125.339519 2.160584) (xy 125.458658 2.085722) (xy 125.573412 2.004299) (xy 125.68342 1.916569)
			(xy 125.788336 1.822809) (xy 125.88783 1.723314) (xy 125.981588 1.618397) (xy 126.069317 1.508388)
			(xy 126.150739 1.393633) (xy 126.225599 1.274493) (xy 126.293661 1.151343) (xy 126.354711 1.024571)
			(xy 126.408556 0.894575) (xy 126.455028 0.761764) (xy 126.49398 0.626557) (xy 126.52529 0.489378)
			(xy 126.548859 0.35066) (xy 126.564613 0.210838) (xy 126.572503 0.070353) (xy 126.573026 0) (xy 126.573026 -8.850122)
			(xy 126.573549 -8.905928) (xy 126.581891 -9.017228) (xy 126.598528 -9.127594) (xy 126.623365 -9.236408)
			(xy 126.656265 -9.343061) (xy 126.697043 -9.446957) (xy 126.745472 -9.547516) (xy 126.801279 -9.644174)
			(xy 126.864154 -9.736392) (xy 126.933745 -9.823653) (xy 127.009662 -9.90547) (xy 127.09148 -9.981384)
			(xy 127.178743 -10.050972) (xy 127.270963 -10.113844) (xy 127.367623 -10.169649) (xy 127.468183 -10.218074)
			(xy 127.572081 -10.258849) (xy 127.678735 -10.291746) (xy 127.787549 -10.316581) (xy 127.897915 -10.333214)
			(xy 128.009216 -10.341553) (xy 128.065022 -10.342118) (xy 130.065018 -10.342118) (xy 130.120825 -10.341596)
			(xy 130.232127 -10.333254) (xy 130.342494 -10.316617) (xy 130.451309 -10.29178) (xy 130.557964 -10.258881)
			(xy 130.661862 -10.218103) (xy 130.762422 -10.169675) (xy 130.859082 -10.113868) (xy 130.951302 -10.050993)
			(xy 131.038565 -9.981403) (xy 131.120384 -9.905487) (xy 131.196301 -9.823668) (xy 131.265891 -9.736405)
			(xy 131.328766 -9.644186) (xy 131.384573 -9.547526) (xy 131.433001 -9.446965) (xy 131.473779 -9.343067)
			(xy 131.506679 -9.236413) (xy 131.531517 -9.127597) (xy 131.548153 -9.01723) (xy 131.556495 -8.905929)
			(xy 131.557014 -8.850122) (xy 131.557014 0) (xy 131.557498 0.070354) (xy 131.565388 0.21084) (xy 131.581142 0.350663)
			(xy 131.604712 0.489383) (xy 131.636022 0.626563) (xy 131.674975 0.761771) (xy 131.721448 0.894583)
			(xy 131.775295 1.02458) (xy 131.836346 1.151353) (xy 131.904409 1.274504) (xy 131.97927 1.393645)
			(xy 132.060694 1.5084) (xy 132.148424 1.61841) (xy 132.242184 1.723327) (xy 132.34168 1.822823) (xy 132.446598 1.916583)
			(xy 132.556608 2.004312) (xy 132.671364 2.085735) (xy 132.790505 2.160596) (xy 132.913655 2.228659)
			(xy 133.040429 2.289709) (xy 133.170426 2.343555) (xy 133.303238 2.390028) (xy 133.438447 2.42898)
			(xy 133.575627 2.46029) (xy 133.714347 2.483859) (xy 133.85417 2.499613) (xy 133.994656 2.507502)
			(xy 134.06501 2.507996) (xy 150.064978 2.507996) (xy 150.135332 2.507512) (xy 150.27582 2.499624)
			(xy 150.415644 2.483871) (xy 150.554365 2.460302) (xy 150.691546 2.428993) (xy 150.826756 2.39004)
			(xy 150.959569 2.343568) (xy 151.089567 2.289722) (xy 151.216342 2.228672) (xy 151.339494 2.160609)
			(xy 151.458636 2.085748) (xy 151.573393 2.004324) (xy 151.683404 1.916594) (xy 151.788322 1.822834)
			(xy 151.887819 1.723338) (xy 151.98158 1.61842) (xy 152.069311 1.50841) (xy 152.150736 1.393654)
			(xy 152.225598 1.274513) (xy 152.293661 1.151361) (xy 152.354713 1.024587) (xy 152.40856 0.894589)
			(xy 152.455034 0.761777) (xy 152.493987 0.626567) (xy 152.525298 0.489386) (xy 152.548868 0.350666)
			(xy 152.564622 0.210842) (xy 152.572512 0.070354) (xy 152.572974 0) (xy 152.572974 -8.850122) (xy 152.573497 -8.905929)
			(xy 152.581839 -9.017231) (xy 152.598475 -9.127598) (xy 152.623313 -9.236413) (xy 152.656212 -9.343068)
			(xy 152.69699 -9.446966) (xy 152.745418 -9.547526) (xy 152.801225 -9.644186) (xy 152.8641 -9.736406)
			(xy 152.93369 -9.823669) (xy 153.009606 -9.905488) (xy 153.091425 -9.981405) (xy 153.178688 -10.050995)
			(xy 153.270907 -10.11387) (xy 153.367567 -10.169678) (xy 153.468127 -10.218107) (xy 153.572025 -10.258885)
			(xy 153.67868 -10.291785) (xy 153.787495 -10.316623) (xy 153.897862 -10.33326) (xy 154.009163 -10.341603)
			(xy 154.06497 -10.342118) (xy 156.064966 -10.342118) (xy 156.120775 -10.34161) (xy 156.23208 -10.333271)
			(xy 156.342451 -10.316638) (xy 156.45127 -10.291803) (xy 156.557929 -10.258906) (xy 156.661832 -10.21813)
			(xy 156.762396 -10.169703) (xy 156.859061 -10.113896) (xy 156.951284 -10.051022) (xy 157.038552 -9.981431)
			(xy 157.120374 -9.905514) (xy 157.196295 -9.823694) (xy 157.265888 -9.736429) (xy 157.328766 -9.644208)
			(xy 157.384577 -9.547546) (xy 157.433007 -9.446983) (xy 157.473787 -9.343082) (xy 157.506689 -9.236424)
			(xy 157.531528 -9.127606) (xy 157.548165 -9.017236) (xy 157.556508 -8.905931) (xy 157.556962 -8.850122)
			(xy 157.556962 0) (xy 157.557455 0.070354) (xy 157.565345 0.210841) (xy 157.581099 0.350665) (xy 157.604668 0.489385)
			(xy 157.635978 0.626566) (xy 157.674931 0.761775) (xy 157.721404 0.894587) (xy 157.77525 1.024585)
			(xy 157.8363 1.151359) (xy 157.904363 1.274511) (xy 157.979224 1.393652) (xy 158.060647 1.508409)
			(xy 158.148376 1.61842) (xy 158.242136 1.723339) (xy 158.341631 1.822835) (xy 158.446548 1.916597)
			(xy 158.556557 2.004328) (xy 158.671313 2.085753) (xy 158.790453 2.160616) (xy 158.913604 2.22868)
			(xy 159.040377 2.289733) (xy 159.170374 2.343581) (xy 159.303185 2.390056) (xy 159.438394 2.429011)
			(xy 159.575574 2.460324) (xy 159.714294 2.483895) (xy 159.854117 2.499652) (xy 159.994604 2.507544)
			(xy 160.064958 2.507996) (xy 176.064926 2.507996) (xy 176.135279 2.507502) (xy 176.275764 2.499611)
			(xy 176.415586 2.483856) (xy 176.554304 2.460285) (xy 176.691483 2.428974) (xy 176.82669 2.39002)
			(xy 176.9595 2.343547) (xy 177.089496 2.289699) (xy 177.216267 2.228648) (xy 177.339416 2.160585)
			(xy 177.458556 2.085724) (xy 177.57331 2.0043) (xy 177.683318 1.91657) (xy 177.788234 1.822811) (xy 177.887728 1.723315)
			(xy 177.981487 1.618398) (xy 178.069216 1.508389) (xy 178.150638 1.393634) (xy 178.225498 1.274494)
			(xy 178.29356 1.151344) (xy 178.35461 1.024572) (xy 178.408456 0.894576) (xy 178.454928 0.761765)
			(xy 178.49388 0.626558) (xy 178.52519 0.489379) (xy 178.548759 0.35066) (xy 178.564513 0.210838)
			(xy 178.572403 0.070353) (xy 178.572922 0) (xy 178.572922 -8.850122) (xy 178.573445 -8.905928) (xy 178.581787 -9.017229)
			(xy 178.598424 -9.127594) (xy 178.623261 -9.236408) (xy 178.656161 -9.343061) (xy 178.696939 -9.446958)
			(xy 178.745367 -9.547517) (xy 178.801175 -9.644175) (xy 178.86405 -9.736393) (xy 178.93364 -9.823654)
			(xy 179.009557 -9.905471) (xy 179.091376 -9.981386) (xy 179.178639 -10.050974) (xy 179.270859 -10.113846)
			(xy 179.367519 -10.169651) (xy 179.468079 -10.218077) (xy 179.571976 -10.258852) (xy 179.678631 -10.291749)
			(xy 179.787445 -10.316584) (xy 179.897811 -10.333218) (xy 180.009112 -10.341557) (xy 180.064918 -10.342118)
			(xy 182.064914 -10.342118) (xy 182.120721 -10.341596) (xy 182.232023 -10.333254) (xy 182.34239 -10.316618)
			(xy 182.451206 -10.291781) (xy 182.557861 -10.258882) (xy 182.661759 -10.218104) (xy 182.76232 -10.169676)
			(xy 182.85898 -10.113869) (xy 182.9512 -10.050995) (xy 183.038463 -9.981405) (xy 183.120282 -9.905488)
			(xy 183.196199 -9.823669) (xy 183.26579 -9.736406) (xy 183.328665 -9.644187) (xy 183.384473 -9.547527)
			(xy 183.432901 -9.446966) (xy 183.473679 -9.343068) (xy 183.506579 -9.236413) (xy 183.531416 -9.127598)
			(xy 183.548053 -9.017231) (xy 183.556395 -8.905929) (xy 183.55691 -8.850122) (xy 183.55691 0) (xy 183.557394 0.070354)
			(xy 183.565284 0.21084) (xy 183.581038 0.350664) (xy 183.604608 0.489383) (xy 183.635918 0.626563)
			(xy 183.674871 0.761772) (xy 183.721344 0.894584) (xy 183.775191 1.024581) (xy 183.836242 1.151354)
			(xy 183.904305 1.274505) (xy 183.979166 1.393646) (xy 184.06059 1.508401) (xy 184.14832 1.618411)
			(xy 184.24208 1.723329) (xy 184.341576 1.822824) (xy 184.446493 1.916584) (xy 184.556503 2.004314)
			(xy 184.671259 2.085737) (xy 184.7904 2.160598) (xy 184.913551 2.228661) (xy 185.040325 2.289712)
			(xy 185.170322 2.343558) (xy 185.303134 2.390031) (xy 185.438342 2.428983) (xy 185.575523 2.460294)
			(xy 185.714242 2.483863) (xy 185.854066 2.499617) (xy 185.994552 2.507506) (xy 186.064906 2.507996)
			(xy 202.064874 2.507996) (xy 202.135228 2.507512) (xy 202.275716 2.499624) (xy 202.41554 2.483871)
			(xy 202.554261 2.460303) (xy 202.691443 2.428993) (xy 202.826653 2.390041) (xy 202.959466 2.343569)
			(xy 203.089464 2.289723) (xy 203.216239 2.228673) (xy 203.339391 2.16061) (xy 203.458534 2.085749)
			(xy 203.573291 2.004326) (xy 203.683302 1.916596) (xy 203.788221 1.822836) (xy 203.887718 1.72334)
			(xy 203.981479 1.618422) (xy 204.06921 1.508412) (xy 204.150635 1.393655) (xy 204.225497 1.274514)
			(xy 204.293561 1.151362) (xy 204.354613 1.024588) (xy 204.40846 0.89459) (xy 204.454933 0.761778)
			(xy 204.493887 0.626568) (xy 204.525198 0.489387) (xy 204.548768 0.350666) (xy 204.564522 0.210842)
			(xy 204.572412 0.070354) (xy 204.57287 0) (xy 204.57287 -8.850122) (xy 204.573393 -8.905929) (xy 204.581735 -9.017231)
			(xy 204.598371 -9.127598) (xy 204.623209 -9.236413) (xy 204.656108 -9.343068) (xy 204.696886 -9.446966)
			(xy 204.745314 -9.547527) (xy 204.801121 -9.644187) (xy 204.863996 -9.736407) (xy 204.933586 -9.82367)
			(xy 205.009502 -9.905489) (xy 205.091321 -9.981407) (xy 205.178583 -10.050997) (xy 205.270803 -10.113872)
			(xy 205.367463 -10.16968) (xy 205.468023 -10.218109) (xy 205.571921 -10.258888) (xy 205.678575 -10.291788)
			(xy 205.78739 -10.316626) (xy 205.897757 -10.333264) (xy 206.009059 -10.341607) (xy 206.064866 -10.342118)
			(xy 208.065116 -10.342118) (xy 208.120923 -10.341596) (xy 208.232225 -10.333254) (xy 208.342592 -10.316618)
			(xy 208.451407 -10.29178) (xy 208.558062 -10.258881) (xy 208.66196 -10.218103) (xy 208.762521 -10.169676)
			(xy 208.859181 -10.113868) (xy 208.951401 -10.050994) (xy 209.038664 -9.981404) (xy 209.120483 -9.905487)
			(xy 209.1964 -9.823669) (xy 209.26599 -9.736406) (xy 209.328865 -9.644186) (xy 209.384673 -9.547526)
			(xy 209.433101 -9.446966) (xy 209.473879 -9.343068) (xy 209.506779 -9.236413) (xy 209.531617 -9.127598)
			(xy 209.548253 -9.017231) (xy 209.556595 -8.905929) (xy 209.557112 -8.850122) (xy 209.557112 0) (xy 209.557596 0.070354)
			(xy 209.565486 0.21084) (xy 209.58124 0.350663) (xy 209.60481 0.489383) (xy 209.63612 0.626563) (xy 209.675073 0.761772)
			(xy 209.721546 0.894583) (xy 209.775393 1.02458) (xy 209.836444 1.151354) (xy 209.904507 1.274505)
			(xy 209.979368 1.393645) (xy 210.060792 1.508401) (xy 210.148522 1.618411) (xy 210.242282 1.723328)
			(xy 210.341778 1.822823) (xy 210.446696 1.916583) (xy 210.556706 2.004313) (xy 210.671462 2.085736)
			(xy 210.790602 2.160597) (xy 210.913753 2.22866) (xy 211.040527 2.289711) (xy 211.170524 2.343557)
			(xy 211.303336 2.390029) (xy 211.438545 2.428982) (xy 211.575725 2.460292) (xy 211.714444 2.483861)
			(xy 211.854268 2.499615) (xy 211.994754 2.507504) (xy 212.065108 2.507996) (xy 240.164874 2.507996)
			(xy 240.235228 2.507512) (xy 240.375716 2.499624) (xy 240.51554 2.483871) (xy 240.654261 2.460303)
			(xy 240.791443 2.428993) (xy 240.926653 2.390041) (xy 241.059466 2.343569) (xy 241.189464 2.289723)
			(xy 241.316239 2.228673) (xy 241.439391 2.16061) (xy 241.558534 2.085749) (xy 241.673291 2.004326)
			(xy 241.783302 1.916596) (xy 241.888221 1.822836) (xy 241.987718 1.72334) (xy 242.081479 1.618422)
			(xy 242.16921 1.508412) (xy 242.250635 1.393655) (xy 242.325497 1.274514) (xy 242.393561 1.151362)
			(xy 242.454613 1.024588) (xy 242.50846 0.89459) (xy 242.554933 0.761778) (xy 242.593887 0.626568)
			(xy 242.625198 0.489387) (xy 242.648768 0.350666) (xy 242.664522 0.210842) (xy 242.672412 0.070354)
			(xy 242.67287 0) (xy 242.67287 -8.850122) (xy 242.673393 -8.905929) (xy 242.681735 -9.017231) (xy 242.698371 -9.127598)
			(xy 242.723209 -9.236413) (xy 242.756108 -9.343068) (xy 242.796886 -9.446966) (xy 242.845314 -9.547527)
			(xy 242.901121 -9.644187) (xy 242.963996 -9.736407) (xy 243.033586 -9.82367) (xy 243.109502 -9.905489)
			(xy 243.191321 -9.981407) (xy 243.278583 -10.050997) (xy 243.370803 -10.113872) (xy 243.467463 -10.16968)
			(xy 243.568023 -10.218109) (xy 243.671921 -10.258888) (xy 243.778575 -10.291788) (xy 243.88739 -10.316626)
			(xy 243.997757 -10.333264) (xy 244.109059 -10.341607) (xy 244.164866 -10.342118) (xy 246.165116 -10.342118)
			(xy 246.220923 -10.341596) (xy 246.332225 -10.333254) (xy 246.442592 -10.316618) (xy 246.551407 -10.29178)
			(xy 246.658062 -10.258881) (xy 246.76196 -10.218103) (xy 246.862521 -10.169676) (xy 246.959181 -10.113868)
			(xy 247.051401 -10.050994) (xy 247.138664 -9.981404) (xy 247.220483 -9.905487) (xy 247.2964 -9.823669)
			(xy 247.36599 -9.736406) (xy 247.428865 -9.644186) (xy 247.484673 -9.547526) (xy 247.533101 -9.446966)
			(xy 247.573879 -9.343068) (xy 247.606779 -9.236413) (xy 247.631617 -9.127598) (xy 247.648253 -9.017231)
			(xy 247.656595 -8.905929) (xy 247.657112 -8.850122) (xy 247.657112 0) (xy 247.657596 0.070354) (xy 247.665486 0.21084)
			(xy 247.68124 0.350663) (xy 247.70481 0.489383) (xy 247.73612 0.626563) (xy 247.775073 0.761772)
			(xy 247.821546 0.894583) (xy 247.875393 1.02458) (xy 247.936444 1.151354) (xy 248.004507 1.274505)
			(xy 248.079368 1.393645) (xy 248.160792 1.508401) (xy 248.248522 1.618411) (xy 248.342282 1.723328)
			(xy 248.441778 1.822823) (xy 248.546696 1.916583) (xy 248.656706 2.004313) (xy 248.771462 2.085736)
			(xy 248.890602 2.160597) (xy 249.013753 2.22866) (xy 249.140527 2.289711) (xy 249.270524 2.343557)
			(xy 249.403336 2.390029) (xy 249.538545 2.428982) (xy 249.675725 2.460292) (xy 249.814444 2.483861)
			(xy 249.954268 2.499615) (xy 250.094754 2.507504) (xy 250.165108 2.507996) (xy 266.165076 2.507996)
			(xy 266.23543 2.507512) (xy 266.375918 2.499624) (xy 266.515742 2.483871) (xy 266.654463 2.460303)
			(xy 266.791644 2.428993) (xy 266.926854 2.390041) (xy 267.059667 2.343569) (xy 267.189666 2.289723)
			(xy 267.31644 2.228672) (xy 267.439593 2.160609) (xy 267.558735 2.085749) (xy 267.673492 2.004325)
			(xy 267.783503 1.916595) (xy 267.888422 1.822835) (xy 267.987918 1.723339) (xy 268.08168 1.618421)
			(xy 268.169411 1.508411) (xy 268.250835 1.393655) (xy 268.325697 1.274513) (xy 268.393761 1.151362)
			(xy 268.454813 1.024588) (xy 268.50866 0.89459) (xy 268.555134 0.761777) (xy 268.594087 0.626568)
			(xy 268.625398 0.489387) (xy 268.648968 0.350666) (xy 268.664722 0.210842) (xy 268.672612 0.070354)
			(xy 268.673072 0) (xy 268.673072 -8.850122) (xy 268.673595 -8.905929) (xy 268.681937 -9.017231) (xy 268.698573 -9.127598)
			(xy 268.723411 -9.236413) (xy 268.75631 -9.343068) (xy 268.797088 -9.446966) (xy 268.845516 -9.547526)
			(xy 268.901323 -9.644187) (xy 268.964198 -9.736406) (xy 269.033788 -9.82367) (xy 269.109704 -9.905489)
			(xy 269.191523 -9.981406) (xy 269.278786 -10.050996) (xy 269.371005 -10.113871) (xy 269.467665 -10.169679)
			(xy 269.568225 -10.218108) (xy 269.672123 -10.258886) (xy 269.778777 -10.291787) (xy 269.887592 -10.316625)
			(xy 269.997959 -10.333262) (xy 270.109261 -10.341605) (xy 270.165068 -10.342118) (xy 272.165064 -10.342118)
			(xy 272.220873 -10.34161) (xy 272.332178 -10.333272) (xy 272.442549 -10.316638) (xy 272.551368 -10.291804)
			(xy 272.658028 -10.258906) (xy 272.76193 -10.21813) (xy 272.862495 -10.169703) (xy 272.95916 -10.113897)
			(xy 273.051383 -10.051022) (xy 273.138651 -9.981432) (xy 273.220473 -9.905515) (xy 273.296394 -9.823695)
			(xy 273.365988 -9.73643) (xy 273.428866 -9.644209) (xy 273.484676 -9.547546) (xy 273.533107 -9.446983)
			(xy 273.573887 -9.343082) (xy 273.606789 -9.236425) (xy 273.631628 -9.127606) (xy 273.648265 -9.017236)
			(xy 273.656608 -8.905931) (xy 273.65706 -8.850122) (xy 273.65706 0) (xy 273.657553 0.070354) (xy 273.665443 0.210841)
			(xy 273.681197 0.350665) (xy 273.704766 0.489385) (xy 273.736076 0.626566) (xy 273.775029 0.761775)
			(xy 273.821502 0.894588) (xy 273.875348 1.024585) (xy 273.936398 1.15136) (xy 274.004461 1.274511)
			(xy 274.079321 1.393653) (xy 274.160745 1.50841) (xy 274.248474 1.618421) (xy 274.342234 1.723339)
			(xy 274.441729 1.822836) (xy 274.546646 1.916598) (xy 274.656655 2.004329) (xy 274.771411 2.085754)
			(xy 274.890551 2.160617) (xy 275.013701 2.228682) (xy 275.140474 2.289734) (xy 275.270471 2.343583)
			(xy 275.403283 2.390058) (xy 275.538492 2.429013) (xy 275.675672 2.460325) (xy 275.814392 2.483897)
			(xy 275.954215 2.499654) (xy 276.094702 2.507545) (xy 276.165056 2.507996) (xy 292.165024 2.507996)
			(xy 292.235377 2.507502) (xy 292.375862 2.499611) (xy 292.515684 2.483856) (xy 292.654403 2.460285)
			(xy 292.791581 2.428974) (xy 292.926788 2.390021) (xy 293.059599 2.343547) (xy 293.189594 2.2897)
			(xy 293.316366 2.228649) (xy 293.439515 2.160586) (xy 293.558655 2.085724) (xy 293.673409 2.004301)
			(xy 293.783417 1.916571) (xy 293.888334 1.822811) (xy 293.987828 1.723316) (xy 294.081587 1.618399)
			(xy 294.169315 1.50839) (xy 294.250738 1.393635) (xy 294.325598 1.274495) (xy 294.39366 1.151345)
			(xy 294.45471 1.024572) (xy 294.508556 0.894576) (xy 294.555028 0.761765) (xy 294.59398 0.626558)
			(xy 294.62529 0.489379) (xy 294.648859 0.35066) (xy 294.664613 0.210839) (xy 294.672503 0.070353)
			(xy 294.67302 0) (xy 294.67302 -8.850122) (xy 294.673543 -8.905928) (xy 294.681885 -9.017229) (xy 294.698522 -9.127594)
			(xy 294.723359 -9.236408) (xy 294.756259 -9.343062) (xy 294.797037 -9.446958) (xy 294.845465 -9.547517)
			(xy 294.901273 -9.644176) (xy 294.964148 -9.736394) (xy 295.033738 -9.823655) (xy 295.109655 -9.905472)
			(xy 295.191474 -9.981387) (xy 295.278737 -10.050975) (xy 295.370956 -10.113847) (xy 295.467616 -10.169652)
			(xy 295.568176 -10.218078) (xy 295.672074 -10.258853) (xy 295.778728 -10.291751) (xy 295.887543 -10.316586)
			(xy 295.997909 -10.333219) (xy 296.10921 -10.341559) (xy 296.165016 -10.342118) (xy 298.165012 -10.342118)
			(xy 298.220819 -10.341596) (xy 298.332121 -10.333254) (xy 298.442488 -10.316618) (xy 298.551304 -10.291781)
			(xy 298.657959 -10.258882) (xy 298.761858 -10.218105) (xy 298.862418 -10.169677) (xy 298.959079 -10.11387)
			(xy 299.051299 -10.050995) (xy 299.138562 -9.981405) (xy 299.220382 -9.905489) (xy 299.296299 -9.82367)
			(xy 299.365889 -9.736407) (xy 299.428764 -9.644188) (xy 299.484572 -9.547527) (xy 299.533001 -9.446967)
			(xy 299.573779 -9.343069) (xy 299.606679 -9.236414) (xy 299.631516 -9.127598) (xy 299.648153 -9.017231)
			(xy 299.656495 -8.905929) (xy 299.657008 -8.850122) (xy 299.657008 0) (xy 299.657492 0.070354) (xy 299.665382 0.21084)
			(xy 299.681136 0.350664) (xy 299.704706 0.489383) (xy 299.736016 0.626564) (xy 299.774969 0.761772)
			(xy 299.821442 0.894584) (xy 299.875289 1.024581) (xy 299.93634 1.151355) (xy 300.004403 1.274505)
			(xy 300.079264 1.393646) (xy 300.160688 1.508402) (xy 300.248418 1.618412) (xy 300.342178 1.723329)
			(xy 300.441673 1.822825) (xy 300.546591 1.916585) (xy 300.656601 2.004315) (xy 300.771357 2.085738)
			(xy 300.890498 2.160599) (xy 301.013649 2.228662) (xy 301.140423 2.289713) (xy 301.27042 2.343559)
			(xy 301.403232 2.390032) (xy 301.53844 2.428985) (xy 301.67562 2.460295) (xy 301.81434 2.483864)
			(xy 301.954163 2.499618) (xy 302.09465 2.507508) (xy 302.165004 2.507996) (xy 318.164972 2.507996)
			(xy 318.235326 2.507512) (xy 318.375814 2.499624) (xy 318.515639 2.483871) (xy 318.65436 2.460303)
			(xy 318.791541 2.428994) (xy 318.926751 2.390042) (xy 319.059564 2.34357) (xy 319.189563 2.289724)
			(xy 319.316338 2.228673) (xy 319.43949 2.160611) (xy 319.558633 2.08575) (xy 319.67339 2.004327)
			(xy 319.783401 1.916597) (xy 319.88832 1.822836) (xy 319.987817 1.723341) (xy 320.081579 1.618423)
			(xy 320.16931 1.508412) (xy 320.250734 1.393656) (xy 320.325597 1.274514) (xy 320.393661 1.151363)
			(xy 320.454712 1.024589) (xy 320.50856 0.894591) (xy 320.555033 0.761778) (xy 320.593987 0.626568)
			(xy 320.625298 0.489387) (xy 320.648868 0.350666) (xy 320.664622 0.210842) (xy 320.672512 0.070354)
			(xy 320.672968 0) (xy 320.672968 -8.850122) (xy 320.673491 -8.905929) (xy 320.681833 -9.017231) (xy 320.698469 -9.127598)
			(xy 320.723307 -9.236413) (xy 320.756206 -9.343068) (xy 320.796984 -9.446967) (xy 320.845412 -9.547527)
			(xy 320.901219 -9.644188) (xy 320.964093 -9.736408) (xy 321.033684 -9.823671) (xy 321.1096 -9.90549)
			(xy 321.191418 -9.981407) (xy 321.278681 -10.050998) (xy 321.3709 -10.113873) (xy 321.46756 -10.169682)
			(xy 321.56812 -10.21811) (xy 321.672018 -10.258889) (xy 321.778673 -10.29179) (xy 321.887488 -10.316628)
			(xy 321.997855 -10.333266) (xy 322.109157 -10.341609) (xy 322.164964 -10.342118) (xy 324.16496 -10.342118)
			(xy 324.220769 -10.34161) (xy 324.332074 -10.333272) (xy 324.442446 -10.316639) (xy 324.551265 -10.291805)
			(xy 324.657925 -10.258907) (xy 324.761827 -10.218131) (xy 324.862393 -10.169705) (xy 324.959057 -10.113898)
			(xy 325.051281 -10.051024) (xy 325.138549 -9.981433) (xy 325.220372 -9.905516) (xy 325.296293 -9.823696)
			(xy 325.365887 -9.736431) (xy 325.428765 -9.64421) (xy 325.484576 -9.547547) (xy 325.533007 -9.446984)
			(xy 325.573787 -9.343083) (xy 325.606689 -9.236425) (xy 325.631528 -9.127607) (xy 325.648165 -9.017236)
			(xy 325.656508 -8.905931) (xy 325.656956 -8.850122) (xy 325.656956 0) (xy 325.657449 0.070354) (xy 325.665339 0.210841)
			(xy 325.681093 0.350665) (xy 325.704662 0.489386) (xy 325.735972 0.626566) (xy 325.774925 0.761776)
			(xy 325.821398 0.894588) (xy 325.875244 1.024586) (xy 325.936294 1.15136) (xy 326.004357 1.274512)
			(xy 326.079217 1.393654) (xy 326.16064 1.508411) (xy 326.24837 1.618422) (xy 326.342129 1.723341)
			(xy 326.441624 1.822838) (xy 326.546542 1.916599) (xy 326.656551 2.004331) (xy 326.771306 2.085756)
			(xy 326.890447 2.160619) (xy 327.013597 2.228684) (xy 327.14037 2.289737) (xy 327.270367 2.343585)
			(xy 327.403179 2.39006) (xy 327.538387 2.429016) (xy 327.675567 2.460328) (xy 327.814287 2.4839)
			(xy 327.954111 2.499657) (xy 328.094598 2.507549) (xy 328.164952 2.507996) (xy 356.264972 2.507996)
			(xy 356.335326 2.507512) (xy 356.475814 2.499624) (xy 356.615639 2.483871) (xy 356.75436 2.460303)
			(xy 356.891541 2.428994) (xy 357.026751 2.390042) (xy 357.159564 2.34357) (xy 357.289563 2.289724)
			(xy 357.416338 2.228673) (xy 357.53949 2.160611) (xy 357.658633 2.08575) (xy 357.77339 2.004327)
			(xy 357.883401 1.916597) (xy 357.98832 1.822836) (xy 358.087817 1.723341) (xy 358.181579 1.618423)
			(xy 358.26931 1.508412) (xy 358.350734 1.393656) (xy 358.425597 1.274514) (xy 358.493661 1.151363)
			(xy 358.554712 1.024589) (xy 358.60856 0.894591) (xy 358.655033 0.761778) (xy 358.693987 0.626568)
			(xy 358.725298 0.489387) (xy 358.748868 0.350666) (xy 358.764622 0.210842) (xy 358.772512 0.070354)
			(xy 358.772968 0) (xy 358.772968 -8.850122) (xy 358.773491 -8.905929) (xy 358.781833 -9.017231) (xy 358.798469 -9.127598)
			(xy 358.823307 -9.236413) (xy 358.856206 -9.343068) (xy 358.896984 -9.446967) (xy 358.945412 -9.547527)
			(xy 359.001219 -9.644188) (xy 359.064093 -9.736408) (xy 359.133684 -9.823671) (xy 359.2096 -9.90549)
			(xy 359.291418 -9.981407) (xy 359.378681 -10.050998) (xy 359.4709 -10.113873) (xy 359.56756 -10.169682)
			(xy 359.66812 -10.21811) (xy 359.772018 -10.258889) (xy 359.878673 -10.29179) (xy 359.987488 -10.316628)
			(xy 360.097855 -10.333266) (xy 360.209157 -10.341609) (xy 360.264964 -10.342118) (xy 362.26496 -10.342118)
			(xy 362.320769 -10.34161) (xy 362.432074 -10.333272) (xy 362.542446 -10.316639) (xy 362.651265 -10.291805)
			(xy 362.757925 -10.258907) (xy 362.861827 -10.218131) (xy 362.962393 -10.169705) (xy 363.059057 -10.113898)
			(xy 363.151281 -10.051024) (xy 363.238549 -9.981433) (xy 363.320372 -9.905516) (xy 363.396293 -9.823696)
			(xy 363.465887 -9.736431) (xy 363.528765 -9.64421) (xy 363.584576 -9.547547) (xy 363.633007 -9.446984)
			(xy 363.673787 -9.343083) (xy 363.706689 -9.236425) (xy 363.731528 -9.127607) (xy 363.748165 -9.017236)
			(xy 363.756508 -8.905931) (xy 363.756956 -8.850122) (xy 363.756956 0) (xy 363.757449 0.070354) (xy 363.765339 0.210841)
			(xy 363.781093 0.350665) (xy 363.804662 0.489386) (xy 363.835972 0.626566) (xy 363.874925 0.761776)
			(xy 363.921398 0.894588) (xy 363.975244 1.024586) (xy 364.036294 1.15136) (xy 364.104357 1.274512)
			(xy 364.179217 1.393654) (xy 364.26064 1.508411) (xy 364.34837 1.618422) (xy 364.442129 1.723341)
			(xy 364.541624 1.822838) (xy 364.646542 1.916599) (xy 364.756551 2.004331) (xy 364.871306 2.085756)
			(xy 364.990447 2.160619) (xy 365.113597 2.228684) (xy 365.24037 2.289737) (xy 365.370367 2.343585)
			(xy 365.503179 2.39006) (xy 365.638387 2.429016) (xy 365.775567 2.460328) (xy 365.914287 2.4839)
			(xy 366.054111 2.499657) (xy 366.194598 2.507549) (xy 366.264952 2.507996) (xy 382.26492 2.507996)
			(xy 382.335273 2.507502) (xy 382.475759 2.499612) (xy 382.615581 2.483856) (xy 382.754299 2.460286)
			(xy 382.891478 2.428975) (xy 383.026685 2.390022) (xy 383.159496 2.343548) (xy 383.289491 2.289701)
			(xy 383.416264 2.22865) (xy 383.539413 2.160587) (xy 383.658552 2.085726) (xy 383.773307 2.004302)
			(xy 383.883316 1.916573) (xy 383.988232 1.822813) (xy 384.087726 1.723318) (xy 384.181485 1.6184)
			(xy 384.269214 1.508391) (xy 384.350637 1.393636) (xy 384.425497 1.274496) (xy 384.493559 1.151346)
			(xy 384.554609 1.024573) (xy 384.608455 0.894577) (xy 384.654928 0.761766) (xy 384.69388 0.626559)
			(xy 384.72519 0.48938) (xy 384.748759 0.350661) (xy 384.764513 0.210839) (xy 384.772403 0.070353)
			(xy 384.772916 0) (xy 384.772916 -8.850122) (xy 384.773439 -8.905928) (xy 384.781781 -9.017229) (xy 384.798418 -9.127595)
			(xy 384.823255 -9.236409) (xy 384.856155 -9.343062) (xy 384.896933 -9.446959) (xy 384.945361 -9.547518)
			(xy 385.001169 -9.644177) (xy 385.064044 -9.736395) (xy 385.133634 -9.823656) (xy 385.209551 -9.905473)
			(xy 385.29137 -9.981388) (xy 385.378633 -10.050977) (xy 385.470852 -10.113849) (xy 385.567512 -10.169655)
			(xy 385.668072 -10.218081) (xy 385.77197 -10.258856) (xy 385.878624 -10.291754) (xy 385.987439 -10.316589)
			(xy 386.097805 -10.333223) (xy 386.209106 -10.341563) (xy 386.264912 -10.342118) (xy 388.264908 -10.342118)
			(xy 388.320715 -10.341596) (xy 388.432017 -10.333255) (xy 388.542385 -10.316619) (xy 388.651201 -10.291782)
			(xy 388.757856 -10.258883) (xy 388.861755 -10.218106) (xy 388.962316 -10.169678) (xy 389.058977 -10.113871)
			(xy 389.151197 -10.050997) (xy 389.238461 -9.981407) (xy 389.32028 -9.90549) (xy 389.396198 -9.823671)
			(xy 389.465789 -9.736408) (xy 389.528664 -9.644189) (xy 389.584472 -9.547528) (xy 389.6329 -9.446968)
			(xy 389.673678 -9.343069) (xy 389.706579 -9.236414) (xy 389.731416 -9.127599) (xy 389.748053 -9.017231)
			(xy 389.756395 -8.905929) (xy 389.756904 -8.850122) (xy 389.756904 0) (xy 389.757397 0.070354) (xy 389.765287 0.21084)
			(xy 389.781041 0.350663) (xy 389.80461 0.489382) (xy 389.835921 0.626562) (xy 389.874874 0.76177)
			(xy 389.921346 0.894581) (xy 389.975193 1.024578) (xy 390.036243 1.151351) (xy 390.104306 1.274502)
			(xy 390.179167 1.393642) (xy 390.260591 1.508398) (xy 390.34832 1.618407) (xy 390.44208 1.723325)
			(xy 390.541575 1.82282) (xy 390.646493 1.91658) (xy 390.756502 2.004309) (xy 390.871258 2.085733)
			(xy 390.990398 2.160594) (xy 391.113549 2.228657) (xy 391.240322 2.289707) (xy 391.370319 2.343554)
			(xy 391.50313 2.390026) (xy 391.638338 2.428979) (xy 391.775518 2.46029) (xy 391.914237 2.483859)
			(xy 392.05406 2.499613) (xy 392.194546 2.507503) (xy 392.2649 2.507996) (xy 408.265122 2.507996)
			(xy 408.335475 2.507502) (xy 408.475961 2.499611) (xy 408.615782 2.483856) (xy 408.754501 2.460286)
			(xy 408.89168 2.428975) (xy 409.026887 2.390021) (xy 409.159697 2.343548) (xy 409.289693 2.289701)
			(xy 409.416465 2.22865) (xy 409.539614 2.160586) (xy 409.658754 2.085725) (xy 409.773508 2.004302)
			(xy 409.883516 1.916572) (xy 409.988433 1.822812) (xy 410.087927 1.723317) (xy 410.181686 1.6184)
			(xy 410.269415 1.50839) (xy 410.350837 1.393635) (xy 410.425697 1.274495) (xy 410.49376 1.151345)
			(xy 410.55481 1.024573) (xy 410.608655 0.894577) (xy 410.655128 0.761766) (xy 410.69408 0.626558)
			(xy 410.72539 0.489379) (xy 410.748959 0.350661) (xy 410.764713 0.210839) (xy 410.772603 0.070353)
			(xy 410.773118 0) (xy 410.773118 -8.850122) (xy 410.773641 -8.905928) (xy 410.781983 -9.017229) (xy 410.79862 -9.127595)
			(xy 410.823457 -9.236408) (xy 410.856357 -9.343062) (xy 410.897135 -9.446959) (xy 410.945563 -9.547518)
			(xy 411.001371 -9.644176) (xy 411.064246 -9.736394) (xy 411.133836 -9.823656) (xy 411.209753 -9.905472)
			(xy 411.291572 -9.981387) (xy 411.378835 -10.050976) (xy 411.471054 -10.113848) (xy 411.567714 -10.169653)
			(xy 411.668274 -10.218079) (xy 411.772172 -10.258855) (xy 411.878826 -10.291752) (xy 411.987641 -10.316587)
			(xy 412.098007 -10.333221) (xy 412.209308 -10.341561) (xy 412.265114 -10.342118) (xy 414.26511 -10.342118)
			(xy 414.320917 -10.341596) (xy 414.432219 -10.333254) (xy 414.542587 -10.316619) (xy 414.651402 -10.291782)
			(xy 414.758058 -10.258883) (xy 414.861956 -10.218105) (xy 414.962517 -10.169678) (xy 415.059178 -10.11387)
			(xy 415.151398 -10.050996) (xy 415.238662 -9.981406) (xy 415.320481 -9.905489) (xy 415.396398 -9.823671)
			(xy 415.465989 -9.736408) (xy 415.528864 -9.644188) (xy 415.584672 -9.547528) (xy 415.6331 -9.446967)
			(xy 415.673879 -9.343069) (xy 415.706779 -9.236414) (xy 415.731616 -9.127598) (xy 415.748253 -9.017231)
			(xy 415.756595 -8.905929) (xy 415.757106 -8.850122) (xy 415.757106 0) (xy 415.75759 0.070354) (xy 415.76548 0.210841)
			(xy 415.781234 0.350664) (xy 415.804804 0.489384) (xy 415.836114 0.626564) (xy 415.875067 0.761772)
			(xy 415.92154 0.894584) (xy 415.975387 1.024581) (xy 416.036438 1.151355) (xy 416.104501 1.274506)
			(xy 416.179362 1.393647) (xy 416.260785 1.508402) (xy 416.348515 1.618412) (xy 416.442276 1.72333)
			(xy 416.541771 1.822826) (xy 416.646689 1.916586) (xy 416.756699 2.004316) (xy 416.871455 2.085739)
			(xy 416.990596 2.1606) (xy 417.113747 2.228663) (xy 417.24052 2.289714) (xy 417.370518 2.343561)
			(xy 417.503329 2.390034) (xy 417.638538 2.428986) (xy 417.775718 2.460297) (xy 417.914438 2.483866)
			(xy 418.054261 2.49962) (xy 418.194748 2.50751) (xy 418.265102 2.507996) (xy 434.26507 2.507996)
			(xy 434.335425 2.507513) (xy 434.475912 2.499625) (xy 434.615737 2.483872) (xy 434.754458 2.460304)
			(xy 434.89164 2.428994) (xy 435.02685 2.390042) (xy 435.159663 2.34357) (xy 435.289662 2.289724)
			(xy 435.416437 2.228674) (xy 435.539589 2.160612) (xy 435.658732 2.085751) (xy 435.773489 2.004327)
			(xy 435.8835 1.916597) (xy 435.988419 1.822837) (xy 436.087916 1.723341) (xy 436.181678 1.618423)
			(xy 436.269409 1.508413) (xy 436.350834 1.393656) (xy 436.425696 1.274515) (xy 436.49376 1.151363)
			(xy 436.554812 1.024589) (xy 436.60866 0.894591) (xy 436.655133 0.761778) (xy 436.694087 0.626569)
			(xy 436.725398 0.489387) (xy 436.748967 0.350667) (xy 436.764722 0.210842) (xy 436.772612 0.070355)
			(xy 436.773066 0) (xy 436.773066 -8.850122) (xy 436.773589 -8.905929) (xy 436.781931 -9.017231) (xy 436.798567 -9.127598)
			(xy 436.823405 -9.236414) (xy 436.856304 -9.343069) (xy 436.897082 -9.446967) (xy 436.94551 -9.547528)
			(xy 437.001317 -9.644188) (xy 437.064191 -9.736408) (xy 437.133781 -9.823672) (xy 437.209698 -9.905491)
			(xy 437.291516 -9.981408) (xy 437.378779 -10.050999) (xy 437.470998 -10.113874) (xy 437.567658 -10.169683)
			(xy 437.668218 -10.218112) (xy 437.772116 -10.25889) (xy 437.878771 -10.291791) (xy 437.987586 -10.31663)
			(xy 438.097953 -10.333267) (xy 438.209255 -10.341611) (xy 438.265062 -10.342118) (xy 440.265058 -10.342118)
			(xy 440.320867 -10.34161) (xy 440.432173 -10.333272) (xy 440.542544 -10.316639) (xy 440.651364 -10.291805)
			(xy 440.758023 -10.258908) (xy 440.861926 -10.218132) (xy 440.962491 -10.169705) (xy 441.059156 -10.113899)
			(xy 441.151381 -10.051025) (xy 441.238648 -9.981434) (xy 441.320471 -9.905517) (xy 441.396392 -9.823697)
			(xy 441.465987 -9.736432) (xy 441.528865 -9.64421) (xy 441.584675 -9.547548) (xy 441.633106 -9.446985)
			(xy 441.673887 -9.343084) (xy 441.706788 -9.236425) (xy 441.731628 -9.127607) (xy 441.748265 -9.017236)
			(xy 441.756608 -8.905931) (xy 441.757054 -8.850122) (xy 441.757054 0) (xy 441.757538 0.070353) (xy 441.765428 0.210839)
			(xy 441.781182 0.350661) (xy 441.804752 0.48938) (xy 441.836062 0.626559) (xy 441.875016 0.761767)
			(xy 441.921489 0.894578) (xy 441.975336 1.024574) (xy 442.036387 1.151346) (xy 442.10445 1.274495)
			(xy 442.179312 1.393635) (xy 442.260736 1.508389) (xy 442.348466 1.618398) (xy 442.442227 1.723314)
			(xy 442.541722 1.822808) (xy 442.64664 1.916566) (xy 442.756651 2.004294) (xy 442.871407 2.085716)
			(xy 442.990548 2.160575) (xy 443.113699 2.228636) (xy 443.240472 2.289685) (xy 443.370469 2.343529)
			(xy 443.503281 2.39) (xy 443.638489 2.42895) (xy 443.775669 2.460258) (xy 443.914388 2.483825) (xy 444.054211 2.499576)
			(xy 444.194697 2.507463) (xy 444.26505 2.507996) (xy 465.600034 2.507996) (xy 465.65584 2.508519)
			(xy 465.767141 2.516862) (xy 465.877506 2.533499) (xy 465.98632 2.558338) (xy 466.092974 2.591238)
			(xy 466.19687 2.632016) (xy 466.297429 2.680445) (xy 466.394088 2.736252) (xy 466.486306 2.799127)
			(xy 466.573567 2.868717) (xy 466.655384 2.944634) (xy 466.7313 3.026452) (xy 466.800888 3.113715)
			(xy 466.863762 3.205934) (xy 466.919568 3.302594) (xy 466.967994 3.403154) (xy 467.008771 3.507051)
			(xy 467.041669 3.613705) (xy 467.066505 3.722519) (xy 467.083141 3.832885) (xy 467.091482 3.944186)
			(xy 467.09203 3.999992) (xy 467.09203 24.157686) (xy 467.091509 24.213494) (xy 467.083169 24.324797)
			(xy 467.066535 24.435167) (xy 467.041699 24.543984) (xy 467.008801 24.650641) (xy 466.968025 24.754542)
			(xy 466.919598 24.855105) (xy 466.863791 24.951768) (xy 466.800917 25.04399) (xy 466.731327 25.131255)
			(xy 466.655411 25.213077) (xy 466.573592 25.288996) (xy 466.486328 25.358589) (xy 466.394108 25.421466)
			(xy 466.297447 25.477275) (xy 466.196886 25.525705) (xy 466.092987 25.566485) (xy 465.986331 25.599387)
			(xy 465.877514 25.624226) (xy 465.767145 25.640863) (xy 465.655842 25.649207) (xy 465.600034 25.649682)
			(xy 160.11398 25.649682) (xy 160.058174 25.64916) (xy 159.946873 25.640817) (xy 159.836507 25.624181)
			(xy 159.727693 25.599343) (xy 159.62104 25.566443) (xy 159.517143 25.525665) (xy 159.416584 25.477237)
			(xy 159.319925 25.42143) (xy 159.227707 25.358555) (xy 159.140445 25.288965) (xy 159.058628 25.213048)
			(xy 158.982713 25.131229) (xy 158.913125 25.043966) (xy 158.850252 24.951746) (xy 158.794447 24.855086)
			(xy 158.746021 24.754526) (xy 158.705245 24.650628) (xy 158.672348 24.543974) (xy 158.647513 24.435159)
			(xy 158.630879 24.324793) (xy 158.622539 24.213492) (xy 158.621984 24.157686) (xy 158.621984 21.802649)
			(xy 269.304757 21.802649) (xy 269.304757 21.888399) (xy 269.312669 21.973782) (xy 269.328425 22.058072)
			(xy 269.351892 22.140548) (xy 269.382868 22.220507) (xy 269.42109 22.297267) (xy 269.466231 22.370173)
			(xy 269.517907 22.438602) (xy 269.575676 22.501972) (xy 269.639046 22.559741) (xy 269.707475 22.611417)
			(xy 269.780381 22.656558) (xy 269.857141 22.69478) (xy 269.9371 22.725756) (xy 270.019576 22.749223)
			(xy 270.103866 22.764979) (xy 270.189249 22.772891) (xy 270.274999 22.772891) (xy 270.360382 22.764979)
			(xy 270.444672 22.749223) (xy 270.527148 22.725756) (xy 270.607107 22.69478) (xy 270.683867 22.656558)
			(xy 270.756773 22.611417) (xy 270.825202 22.559741) (xy 270.888572 22.501972) (xy 270.946341 22.438602)
			(xy 270.998017 22.370173) (xy 271.043158 22.297267) (xy 271.08138 22.220507) (xy 271.112356 22.140548)
			(xy 271.135823 22.058072) (xy 271.151579 21.973782) (xy 271.159491 21.888399) (xy 271.159986 21.845524)
			(xy 271.159491 21.802649) (xy 275.654757 21.802649) (xy 275.654757 21.888399) (xy 275.662669 21.973782)
			(xy 275.678425 22.058072) (xy 275.701892 22.140548) (xy 275.732868 22.220507) (xy 275.77109 22.297267)
			(xy 275.816231 22.370173) (xy 275.867907 22.438602) (xy 275.925676 22.501972) (xy 275.989046 22.559741)
			(xy 276.057475 22.611417) (xy 276.130381 22.656558) (xy 276.207141 22.69478) (xy 276.2871 22.725756)
			(xy 276.369576 22.749223) (xy 276.453866 22.764979) (xy 276.539249 22.772891) (xy 276.624999 22.772891)
			(xy 276.710382 22.764979) (xy 276.794672 22.749223) (xy 276.877148 22.725756) (xy 276.957107 22.69478)
			(xy 277.033867 22.656558) (xy 277.106773 22.611417) (xy 277.175202 22.559741) (xy 277.238572 22.501972)
			(xy 277.296341 22.438602) (xy 277.348017 22.370173) (xy 277.393158 22.297267) (xy 277.43138 22.220507)
			(xy 277.462356 22.140548) (xy 277.485823 22.058072) (xy 277.501579 21.973782) (xy 277.509491 21.888399)
			(xy 277.509986 21.845524) (xy 277.509491 21.802649) (xy 277.508832 21.795537) (xy 308.364877 21.795537)
			(xy 308.364877 21.881287) (xy 308.372789 21.96667) (xy 308.388545 22.05096) (xy 308.412012 22.133436)
			(xy 308.442988 22.213395) (xy 308.48121 22.290155) (xy 308.526351 22.363061) (xy 308.578027 22.43149)
			(xy 308.635796 22.49486) (xy 308.699166 22.552629) (xy 308.767595 22.604305) (xy 308.840501 22.649446)
			(xy 308.917261 22.687668) (xy 308.99722 22.718644) (xy 309.079696 22.742111) (xy 309.163986 22.757867)
			(xy 309.249369 22.765779) (xy 309.335119 22.765779) (xy 309.420502 22.757867) (xy 309.504792 22.742111)
			(xy 309.587268 22.718644) (xy 309.667227 22.687668) (xy 309.743987 22.649446) (xy 309.816893 22.604305)
			(xy 309.885322 22.552629) (xy 309.948692 22.49486) (xy 310.006461 22.43149) (xy 310.058137 22.363061)
			(xy 310.103278 22.290155) (xy 310.1415 22.213395) (xy 310.172476 22.133436) (xy 310.195943 22.05096)
			(xy 310.211699 21.96667) (xy 310.219611 21.881287) (xy 310.220106 21.838412) (xy 310.219611 21.795537)
			(xy 314.714877 21.795537) (xy 314.714877 21.881287) (xy 314.722789 21.96667) (xy 314.738545 22.05096)
			(xy 314.762012 22.133436) (xy 314.792988 22.213395) (xy 314.83121 22.290155) (xy 314.876351 22.363061)
			(xy 314.928027 22.43149) (xy 314.985796 22.49486) (xy 315.049166 22.552629) (xy 315.117595 22.604305)
			(xy 315.190501 22.649446) (xy 315.267261 22.687668) (xy 315.34722 22.718644) (xy 315.429696 22.742111)
			(xy 315.513986 22.757867) (xy 315.599369 22.765779) (xy 315.685119 22.765779) (xy 315.770502 22.757867)
			(xy 315.854792 22.742111) (xy 315.937268 22.718644) (xy 316.017227 22.687668) (xy 316.093987 22.649446)
			(xy 316.166893 22.604305) (xy 316.235322 22.552629) (xy 316.298692 22.49486) (xy 316.356461 22.43149)
			(xy 316.408137 22.363061) (xy 316.453278 22.290155) (xy 316.4915 22.213395) (xy 316.522476 22.133436)
			(xy 316.545943 22.05096) (xy 316.561699 21.96667) (xy 316.569611 21.881287) (xy 316.570106 21.838412)
			(xy 316.569693 21.802649) (xy 334.455757 21.802649) (xy 334.455757 21.888399) (xy 334.463669 21.973782)
			(xy 334.479425 22.058072) (xy 334.502892 22.140548) (xy 334.533868 22.220507) (xy 334.57209 22.297267)
			(xy 334.617231 22.370173) (xy 334.668907 22.438602) (xy 334.726676 22.501972) (xy 334.790046 22.559741)
			(xy 334.858475 22.611417) (xy 334.931381 22.656558) (xy 335.008141 22.69478) (xy 335.0881 22.725756)
			(xy 335.170576 22.749223) (xy 335.254866 22.764979) (xy 335.340249 22.772891) (xy 335.425999 22.772891)
			(xy 335.511382 22.764979) (xy 335.595672 22.749223) (xy 335.678148 22.725756) (xy 335.758107 22.69478)
			(xy 335.834867 22.656558) (xy 335.907773 22.611417) (xy 335.976202 22.559741) (xy 336.039572 22.501972)
			(xy 336.097341 22.438602) (xy 336.149017 22.370173) (xy 336.194158 22.297267) (xy 336.23238 22.220507)
			(xy 336.263356 22.140548) (xy 336.286823 22.058072) (xy 336.302579 21.973782) (xy 336.310491 21.888399)
			(xy 336.310986 21.845524) (xy 336.310491 21.802649) (xy 340.805757 21.802649) (xy 340.805757 21.888399)
			(xy 340.813669 21.973782) (xy 340.829425 22.058072) (xy 340.852892 22.140548) (xy 340.883868 22.220507)
			(xy 340.92209 22.297267) (xy 340.967231 22.370173) (xy 341.018907 22.438602) (xy 341.076676 22.501972)
			(xy 341.140046 22.559741) (xy 341.208475 22.611417) (xy 341.281381 22.656558) (xy 341.358141 22.69478)
			(xy 341.4381 22.725756) (xy 341.520576 22.749223) (xy 341.604866 22.764979) (xy 341.690249 22.772891)
			(xy 341.775999 22.772891) (xy 341.861382 22.764979) (xy 341.945672 22.749223) (xy 342.028148 22.725756)
			(xy 342.108107 22.69478) (xy 342.184867 22.656558) (xy 342.257773 22.611417) (xy 342.326202 22.559741)
			(xy 342.389572 22.501972) (xy 342.447341 22.438602) (xy 342.499017 22.370173) (xy 342.544158 22.297267)
			(xy 342.58238 22.220507) (xy 342.613356 22.140548) (xy 342.636823 22.058072) (xy 342.652579 21.973782)
			(xy 342.660491 21.888399) (xy 342.660986 21.845524) (xy 342.660491 21.802649) (xy 342.659832 21.795537)
			(xy 373.515877 21.795537) (xy 373.515877 21.881287) (xy 373.523789 21.96667) (xy 373.539545 22.05096)
			(xy 373.563012 22.133436) (xy 373.593988 22.213395) (xy 373.63221 22.290155) (xy 373.677351 22.363061)
			(xy 373.729027 22.43149) (xy 373.786796 22.49486) (xy 373.850166 22.552629) (xy 373.918595 22.604305)
			(xy 373.991501 22.649446) (xy 374.068261 22.687668) (xy 374.14822 22.718644) (xy 374.230696 22.742111)
			(xy 374.314986 22.757867) (xy 374.400369 22.765779) (xy 374.486119 22.765779) (xy 374.571502 22.757867)
			(xy 374.655792 22.742111) (xy 374.738268 22.718644) (xy 374.818227 22.687668) (xy 374.894987 22.649446)
			(xy 374.967893 22.604305) (xy 375.036322 22.552629) (xy 375.099692 22.49486) (xy 375.157461 22.43149)
			(xy 375.209137 22.363061) (xy 375.254278 22.290155) (xy 375.2925 22.213395) (xy 375.323476 22.133436)
			(xy 375.346943 22.05096) (xy 375.362699 21.96667) (xy 375.370611 21.881287) (xy 375.371106 21.838412)
			(xy 375.370611 21.795537) (xy 379.865877 21.795537) (xy 379.865877 21.881287) (xy 379.873789 21.96667)
			(xy 379.889545 22.05096) (xy 379.913012 22.133436) (xy 379.943988 22.213395) (xy 379.98221 22.290155)
			(xy 380.027351 22.363061) (xy 380.079027 22.43149) (xy 380.136796 22.49486) (xy 380.200166 22.552629)
			(xy 380.268595 22.604305) (xy 380.341501 22.649446) (xy 380.418261 22.687668) (xy 380.49822 22.718644)
			(xy 380.580696 22.742111) (xy 380.664986 22.757867) (xy 380.750369 22.765779) (xy 380.836119 22.765779)
			(xy 380.921502 22.757867) (xy 381.005792 22.742111) (xy 381.088268 22.718644) (xy 381.168227 22.687668)
			(xy 381.244987 22.649446) (xy 381.317893 22.604305) (xy 381.386322 22.552629) (xy 381.449692 22.49486)
			(xy 381.507461 22.43149) (xy 381.559137 22.363061) (xy 381.604278 22.290155) (xy 381.6425 22.213395)
			(xy 381.673476 22.133436) (xy 381.696943 22.05096) (xy 381.712699 21.96667) (xy 381.720611 21.881287)
			(xy 381.721106 21.838412) (xy 381.720693 21.802649) (xy 399.098757 21.802649) (xy 399.098757 21.888399)
			(xy 399.106669 21.973782) (xy 399.122425 22.058072) (xy 399.145892 22.140548) (xy 399.176868 22.220507)
			(xy 399.21509 22.297267) (xy 399.260231 22.370173) (xy 399.311907 22.438602) (xy 399.369676 22.501972)
			(xy 399.433046 22.559741) (xy 399.501475 22.611417) (xy 399.574381 22.656558) (xy 399.651141 22.69478)
			(xy 399.7311 22.725756) (xy 399.813576 22.749223) (xy 399.897866 22.764979) (xy 399.983249 22.772891)
			(xy 400.068999 22.772891) (xy 400.154382 22.764979) (xy 400.238672 22.749223) (xy 400.321148 22.725756)
			(xy 400.401107 22.69478) (xy 400.477867 22.656558) (xy 400.550773 22.611417) (xy 400.619202 22.559741)
			(xy 400.682572 22.501972) (xy 400.740341 22.438602) (xy 400.792017 22.370173) (xy 400.837158 22.297267)
			(xy 400.87538 22.220507) (xy 400.906356 22.140548) (xy 400.929823 22.058072) (xy 400.945579 21.973782)
			(xy 400.953491 21.888399) (xy 400.953986 21.845524) (xy 400.953491 21.802649) (xy 405.448757 21.802649)
			(xy 405.448757 21.888399) (xy 405.456669 21.973782) (xy 405.472425 22.058072) (xy 405.495892 22.140548)
			(xy 405.526868 22.220507) (xy 405.56509 22.297267) (xy 405.610231 22.370173) (xy 405.661907 22.438602)
			(xy 405.719676 22.501972) (xy 405.783046 22.559741) (xy 405.851475 22.611417) (xy 405.924381 22.656558)
			(xy 406.001141 22.69478) (xy 406.0811 22.725756) (xy 406.163576 22.749223) (xy 406.247866 22.764979)
			(xy 406.333249 22.772891) (xy 406.418999 22.772891) (xy 406.504382 22.764979) (xy 406.588672 22.749223)
			(xy 406.671148 22.725756) (xy 406.751107 22.69478) (xy 406.827867 22.656558) (xy 406.900773 22.611417)
			(xy 406.969202 22.559741) (xy 407.032572 22.501972) (xy 407.090341 22.438602) (xy 407.142017 22.370173)
			(xy 407.187158 22.297267) (xy 407.22538 22.220507) (xy 407.256356 22.140548) (xy 407.279823 22.058072)
			(xy 407.295579 21.973782) (xy 407.303491 21.888399) (xy 407.303986 21.845524) (xy 407.303491 21.802649)
			(xy 407.302832 21.795537) (xy 438.158877 21.795537) (xy 438.158877 21.881287) (xy 438.166789 21.96667)
			(xy 438.182545 22.05096) (xy 438.206012 22.133436) (xy 438.236988 22.213395) (xy 438.27521 22.290155)
			(xy 438.320351 22.363061) (xy 438.372027 22.43149) (xy 438.429796 22.49486) (xy 438.493166 22.552629)
			(xy 438.561595 22.604305) (xy 438.634501 22.649446) (xy 438.711261 22.687668) (xy 438.79122 22.718644)
			(xy 438.873696 22.742111) (xy 438.957986 22.757867) (xy 439.043369 22.765779) (xy 439.129119 22.765779)
			(xy 439.214502 22.757867) (xy 439.298792 22.742111) (xy 439.381268 22.718644) (xy 439.461227 22.687668)
			(xy 439.537987 22.649446) (xy 439.610893 22.604305) (xy 439.679322 22.552629) (xy 439.742692 22.49486)
			(xy 439.800461 22.43149) (xy 439.852137 22.363061) (xy 439.897278 22.290155) (xy 439.9355 22.213395)
			(xy 439.966476 22.133436) (xy 439.989943 22.05096) (xy 440.005699 21.96667) (xy 440.013611 21.881287)
			(xy 440.014106 21.838412) (xy 440.013611 21.795537) (xy 444.508877 21.795537) (xy 444.508877 21.881287)
			(xy 444.516789 21.96667) (xy 444.532545 22.05096) (xy 444.556012 22.133436) (xy 444.586988 22.213395)
			(xy 444.62521 22.290155) (xy 444.670351 22.363061) (xy 444.722027 22.43149) (xy 444.779796 22.49486)
			(xy 444.843166 22.552629) (xy 444.911595 22.604305) (xy 444.984501 22.649446) (xy 445.061261 22.687668)
			(xy 445.14122 22.718644) (xy 445.223696 22.742111) (xy 445.307986 22.757867) (xy 445.393369 22.765779)
			(xy 445.479119 22.765779) (xy 445.564502 22.757867) (xy 445.648792 22.742111) (xy 445.731268 22.718644)
			(xy 445.811227 22.687668) (xy 445.887987 22.649446) (xy 445.960893 22.604305) (xy 446.029322 22.552629)
			(xy 446.092692 22.49486) (xy 446.150461 22.43149) (xy 446.202137 22.363061) (xy 446.247278 22.290155)
			(xy 446.2855 22.213395) (xy 446.316476 22.133436) (xy 446.339943 22.05096) (xy 446.355699 21.96667)
			(xy 446.363611 21.881287) (xy 446.364106 21.838412) (xy 446.363611 21.795537) (xy 446.355699 21.710154)
			(xy 446.339943 21.625864) (xy 446.316476 21.543388) (xy 446.2855 21.463429) (xy 446.247278 21.386669)
			(xy 446.202137 21.313763) (xy 446.150461 21.245334) (xy 446.092692 21.181964) (xy 446.029322 21.124195)
			(xy 445.988175 21.093122) (xy 460.504275 21.093122) (xy 460.504275 21.222262) (xy 460.512225 21.351157)
			(xy 460.528095 21.479317) (xy 460.551824 21.606258) (xy 460.583323 21.731497) (xy 460.622472 21.85456)
			(xy 460.669123 21.974979) (xy 460.723098 22.092298) (xy 460.784193 22.206072) (xy 460.852176 22.315869)
			(xy 460.92679 22.421272) (xy 461.007751 22.521882) (xy 461.094751 22.617317) (xy 461.187462 22.707216)
			(xy 461.285532 22.791237) (xy 461.388587 22.869061) (xy 461.496238 22.940393) (xy 461.608077 23.004963)
			(xy 461.723678 23.062525) (xy 461.842603 23.112862) (xy 461.964402 23.155782) (xy 462.088612 23.191123)
			(xy 462.214761 23.21875) (xy 462.342373 23.238559) (xy 462.470962 23.250475) (xy 462.60004 23.254452)
			(xy 462.729118 23.250475) (xy 462.857707 23.238559) (xy 462.985319 23.21875) (xy 463.111468 23.191123)
			(xy 463.235678 23.155782) (xy 463.357477 23.112862) (xy 463.476402 23.062525) (xy 463.592003 23.004963)
			(xy 463.703842 22.940393) (xy 463.811493 22.869061) (xy 463.914548 22.791237) (xy 464.012618 22.707216)
			(xy 464.105329 22.617317) (xy 464.192329 22.521882) (xy 464.27329 22.421272) (xy 464.347904 22.315869)
			(xy 464.415887 22.206072) (xy 464.476982 22.092298) (xy 464.530957 21.974979) (xy 464.577608 21.85456)
			(xy 464.616757 21.731497) (xy 464.648256 21.606258) (xy 464.671985 21.479317) (xy 464.687855 21.351157)
			(xy 464.695805 21.222262) (xy 464.696302 21.157692) (xy 464.695805 21.093122) (xy 464.687855 20.964227)
			(xy 464.671985 20.836067) (xy 464.648256 20.709126) (xy 464.616757 20.583887) (xy 464.577608 20.460824)
			(xy 464.530957 20.340405) (xy 464.476982 20.223086) (xy 464.415887 20.109312) (xy 464.347904 19.999515)
			(xy 464.27329 19.894112) (xy 464.192329 19.793502) (xy 464.105329 19.698067) (xy 464.012618 19.608168)
			(xy 463.914548 19.524147) (xy 463.811493 19.446323) (xy 463.703842 19.374991) (xy 463.592003 19.310421)
			(xy 463.476402 19.252859) (xy 463.357477 19.202522) (xy 463.235678 19.159602) (xy 463.111468 19.124261)
			(xy 462.985319 19.096634) (xy 462.857707 19.076825) (xy 462.729118 19.064909) (xy 462.60004 19.060933)
			(xy 462.470962 19.064909) (xy 462.342373 19.076825) (xy 462.214761 19.096634) (xy 462.088612 19.124261)
			(xy 461.964402 19.159602) (xy 461.842603 19.202522) (xy 461.723678 19.252859) (xy 461.608077 19.310421)
			(xy 461.496238 19.374991) (xy 461.388587 19.446323) (xy 461.285532 19.524147) (xy 461.187462 19.608168)
			(xy 461.094751 19.698067) (xy 461.007751 19.793502) (xy 460.92679 19.894112) (xy 460.852176 19.999515)
			(xy 460.784193 20.109312) (xy 460.723098 20.223086) (xy 460.669123 20.340405) (xy 460.622472 20.460824)
			(xy 460.583323 20.583887) (xy 460.551824 20.709126) (xy 460.528095 20.836067) (xy 460.512225 20.964227)
			(xy 460.504275 21.093122) (xy 445.988175 21.093122) (xy 445.960893 21.072519) (xy 445.887987 21.027378)
			(xy 445.811227 20.989156) (xy 445.731268 20.95818) (xy 445.648792 20.934713) (xy 445.564502 20.918957)
			(xy 445.479119 20.911045) (xy 445.393369 20.911045) (xy 445.307986 20.918957) (xy 445.223696 20.934713)
			(xy 445.14122 20.95818) (xy 445.061261 20.989156) (xy 444.984501 21.027378) (xy 444.911595 21.072519)
			(xy 444.843166 21.124195) (xy 444.779796 21.181964) (xy 444.722027 21.245334) (xy 444.670351 21.313763)
			(xy 444.62521 21.386669) (xy 444.586988 21.463429) (xy 444.556012 21.543388) (xy 444.532545 21.625864)
			(xy 444.516789 21.710154) (xy 444.508877 21.795537) (xy 440.013611 21.795537) (xy 440.005699 21.710154)
			(xy 439.989943 21.625864) (xy 439.966476 21.543388) (xy 439.9355 21.463429) (xy 439.897278 21.386669)
			(xy 439.852137 21.313763) (xy 439.800461 21.245334) (xy 439.742692 21.181964) (xy 439.679322 21.124195)
			(xy 439.610893 21.072519) (xy 439.537987 21.027378) (xy 439.461227 20.989156) (xy 439.381268 20.95818)
			(xy 439.298792 20.934713) (xy 439.214502 20.918957) (xy 439.129119 20.911045) (xy 439.043369 20.911045)
			(xy 438.957986 20.918957) (xy 438.873696 20.934713) (xy 438.79122 20.95818) (xy 438.711261 20.989156)
			(xy 438.634501 21.027378) (xy 438.561595 21.072519) (xy 438.493166 21.124195) (xy 438.429796 21.181964)
			(xy 438.372027 21.245334) (xy 438.320351 21.313763) (xy 438.27521 21.386669) (xy 438.236988 21.463429)
			(xy 438.206012 21.543388) (xy 438.182545 21.625864) (xy 438.166789 21.710154) (xy 438.158877 21.795537)
			(xy 407.302832 21.795537) (xy 407.295579 21.717266) (xy 407.279823 21.632976) (xy 407.256356 21.5505)
			(xy 407.22538 21.470541) (xy 407.187158 21.393781) (xy 407.142017 21.320875) (xy 407.090341 21.252446)
			(xy 407.032572 21.189076) (xy 406.969202 21.131307) (xy 406.900773 21.079631) (xy 406.827867 21.03449)
			(xy 406.751107 20.996268) (xy 406.671148 20.965292) (xy 406.588672 20.941825) (xy 406.504382 20.926069)
			(xy 406.418999 20.918157) (xy 406.333249 20.918157) (xy 406.247866 20.926069) (xy 406.163576 20.941825)
			(xy 406.0811 20.965292) (xy 406.001141 20.996268) (xy 405.924381 21.03449) (xy 405.851475 21.079631)
			(xy 405.783046 21.131307) (xy 405.719676 21.189076) (xy 405.661907 21.252446) (xy 405.610231 21.320875)
			(xy 405.56509 21.393781) (xy 405.526868 21.470541) (xy 405.495892 21.5505) (xy 405.472425 21.632976)
			(xy 405.456669 21.717266) (xy 405.448757 21.802649) (xy 400.953491 21.802649) (xy 400.945579 21.717266)
			(xy 400.929823 21.632976) (xy 400.906356 21.5505) (xy 400.87538 21.470541) (xy 400.837158 21.393781)
			(xy 400.792017 21.320875) (xy 400.740341 21.252446) (xy 400.682572 21.189076) (xy 400.619202 21.131307)
			(xy 400.550773 21.079631) (xy 400.477867 21.03449) (xy 400.401107 20.996268) (xy 400.321148 20.965292)
			(xy 400.238672 20.941825) (xy 400.154382 20.926069) (xy 400.068999 20.918157) (xy 399.983249 20.918157)
			(xy 399.897866 20.926069) (xy 399.813576 20.941825) (xy 399.7311 20.965292) (xy 399.651141 20.996268)
			(xy 399.574381 21.03449) (xy 399.501475 21.079631) (xy 399.433046 21.131307) (xy 399.369676 21.189076)
			(xy 399.311907 21.252446) (xy 399.260231 21.320875) (xy 399.21509 21.393781) (xy 399.176868 21.470541)
			(xy 399.145892 21.5505) (xy 399.122425 21.632976) (xy 399.106669 21.717266) (xy 399.098757 21.802649)
			(xy 381.720693 21.802649) (xy 381.720611 21.795537) (xy 381.712699 21.710154) (xy 381.696943 21.625864)
			(xy 381.673476 21.543388) (xy 381.6425 21.463429) (xy 381.604278 21.386669) (xy 381.559137 21.313763)
			(xy 381.507461 21.245334) (xy 381.449692 21.181964) (xy 381.386322 21.124195) (xy 381.317893 21.072519)
			(xy 381.244987 21.027378) (xy 381.168227 20.989156) (xy 381.088268 20.95818) (xy 381.005792 20.934713)
			(xy 380.921502 20.918957) (xy 380.836119 20.911045) (xy 380.750369 20.911045) (xy 380.664986 20.918957)
			(xy 380.580696 20.934713) (xy 380.49822 20.95818) (xy 380.418261 20.989156) (xy 380.341501 21.027378)
			(xy 380.268595 21.072519) (xy 380.200166 21.124195) (xy 380.136796 21.181964) (xy 380.079027 21.245334)
			(xy 380.027351 21.313763) (xy 379.98221 21.386669) (xy 379.943988 21.463429) (xy 379.913012 21.543388)
			(xy 379.889545 21.625864) (xy 379.873789 21.710154) (xy 379.865877 21.795537) (xy 375.370611 21.795537)
			(xy 375.362699 21.710154) (xy 375.346943 21.625864) (xy 375.323476 21.543388) (xy 375.2925 21.463429)
			(xy 375.254278 21.386669) (xy 375.209137 21.313763) (xy 375.157461 21.245334) (xy 375.099692 21.181964)
			(xy 375.036322 21.124195) (xy 374.967893 21.072519) (xy 374.894987 21.027378) (xy 374.818227 20.989156)
			(xy 374.738268 20.95818) (xy 374.655792 20.934713) (xy 374.571502 20.918957) (xy 374.486119 20.911045)
			(xy 374.400369 20.911045) (xy 374.314986 20.918957) (xy 374.230696 20.934713) (xy 374.14822 20.95818)
			(xy 374.068261 20.989156) (xy 373.991501 21.027378) (xy 373.918595 21.072519) (xy 373.850166 21.124195)
			(xy 373.786796 21.181964) (xy 373.729027 21.245334) (xy 373.677351 21.313763) (xy 373.63221 21.386669)
			(xy 373.593988 21.463429) (xy 373.563012 21.543388) (xy 373.539545 21.625864) (xy 373.523789 21.710154)
			(xy 373.515877 21.795537) (xy 342.659832 21.795537) (xy 342.652579 21.717266) (xy 342.636823 21.632976)
			(xy 342.613356 21.5505) (xy 342.58238 21.470541) (xy 342.544158 21.393781) (xy 342.499017 21.320875)
			(xy 342.447341 21.252446) (xy 342.389572 21.189076) (xy 342.326202 21.131307) (xy 342.257773 21.079631)
			(xy 342.184867 21.03449) (xy 342.108107 20.996268) (xy 342.028148 20.965292) (xy 341.945672 20.941825)
			(xy 341.861382 20.926069) (xy 341.775999 20.918157) (xy 341.690249 20.918157) (xy 341.604866 20.926069)
			(xy 341.520576 20.941825) (xy 341.4381 20.965292) (xy 341.358141 20.996268) (xy 341.281381 21.03449)
			(xy 341.208475 21.079631) (xy 341.140046 21.131307) (xy 341.076676 21.189076) (xy 341.018907 21.252446)
			(xy 340.967231 21.320875) (xy 340.92209 21.393781) (xy 340.883868 21.470541) (xy 340.852892 21.5505)
			(xy 340.829425 21.632976) (xy 340.813669 21.717266) (xy 340.805757 21.802649) (xy 336.310491 21.802649)
			(xy 336.302579 21.717266) (xy 336.286823 21.632976) (xy 336.263356 21.5505) (xy 336.23238 21.470541)
			(xy 336.194158 21.393781) (xy 336.149017 21.320875) (xy 336.097341 21.252446) (xy 336.039572 21.189076)
			(xy 335.976202 21.131307) (xy 335.907773 21.079631) (xy 335.834867 21.03449) (xy 335.758107 20.996268)
			(xy 335.678148 20.965292) (xy 335.595672 20.941825) (xy 335.511382 20.926069) (xy 335.425999 20.918157)
			(xy 335.340249 20.918157) (xy 335.254866 20.926069) (xy 335.170576 20.941825) (xy 335.0881 20.965292)
			(xy 335.008141 20.996268) (xy 334.931381 21.03449) (xy 334.858475 21.079631) (xy 334.790046 21.131307)
			(xy 334.726676 21.189076) (xy 334.668907 21.252446) (xy 334.617231 21.320875) (xy 334.57209 21.393781)
			(xy 334.533868 21.470541) (xy 334.502892 21.5505) (xy 334.479425 21.632976) (xy 334.463669 21.717266)
			(xy 334.455757 21.802649) (xy 316.569693 21.802649) (xy 316.569611 21.795537) (xy 316.561699 21.710154)
			(xy 316.545943 21.625864) (xy 316.522476 21.543388) (xy 316.4915 21.463429) (xy 316.453278 21.386669)
			(xy 316.408137 21.313763) (xy 316.356461 21.245334) (xy 316.298692 21.181964) (xy 316.235322 21.124195)
			(xy 316.166893 21.072519) (xy 316.093987 21.027378) (xy 316.017227 20.989156) (xy 315.937268 20.95818)
			(xy 315.854792 20.934713) (xy 315.770502 20.918957) (xy 315.685119 20.911045) (xy 315.599369 20.911045)
			(xy 315.513986 20.918957) (xy 315.429696 20.934713) (xy 315.34722 20.95818) (xy 315.267261 20.989156)
			(xy 315.190501 21.027378) (xy 315.117595 21.072519) (xy 315.049166 21.124195) (xy 314.985796 21.181964)
			(xy 314.928027 21.245334) (xy 314.876351 21.313763) (xy 314.83121 21.386669) (xy 314.792988 21.463429)
			(xy 314.762012 21.543388) (xy 314.738545 21.625864) (xy 314.722789 21.710154) (xy 314.714877 21.795537)
			(xy 310.219611 21.795537) (xy 310.211699 21.710154) (xy 310.195943 21.625864) (xy 310.172476 21.543388)
			(xy 310.1415 21.463429) (xy 310.103278 21.386669) (xy 310.058137 21.313763) (xy 310.006461 21.245334)
			(xy 309.948692 21.181964) (xy 309.885322 21.124195) (xy 309.816893 21.072519) (xy 309.743987 21.027378)
			(xy 309.667227 20.989156) (xy 309.587268 20.95818) (xy 309.504792 20.934713) (xy 309.420502 20.918957)
			(xy 309.335119 20.911045) (xy 309.249369 20.911045) (xy 309.163986 20.918957) (xy 309.079696 20.934713)
			(xy 308.99722 20.95818) (xy 308.917261 20.989156) (xy 308.840501 21.027378) (xy 308.767595 21.072519)
			(xy 308.699166 21.124195) (xy 308.635796 21.181964) (xy 308.578027 21.245334) (xy 308.526351 21.313763)
			(xy 308.48121 21.386669) (xy 308.442988 21.463429) (xy 308.412012 21.543388) (xy 308.388545 21.625864)
			(xy 308.372789 21.710154) (xy 308.364877 21.795537) (xy 277.508832 21.795537) (xy 277.501579 21.717266)
			(xy 277.485823 21.632976) (xy 277.462356 21.5505) (xy 277.43138 21.470541) (xy 277.393158 21.393781)
			(xy 277.348017 21.320875) (xy 277.296341 21.252446) (xy 277.238572 21.189076) (xy 277.175202 21.131307)
			(xy 277.106773 21.079631) (xy 277.033867 21.03449) (xy 276.957107 20.996268) (xy 276.877148 20.965292)
			(xy 276.794672 20.941825) (xy 276.710382 20.926069) (xy 276.624999 20.918157) (xy 276.539249 20.918157)
			(xy 276.453866 20.926069) (xy 276.369576 20.941825) (xy 276.2871 20.965292) (xy 276.207141 20.996268)
			(xy 276.130381 21.03449) (xy 276.057475 21.079631) (xy 275.989046 21.131307) (xy 275.925676 21.189076)
			(xy 275.867907 21.252446) (xy 275.816231 21.320875) (xy 275.77109 21.393781) (xy 275.732868 21.470541)
			(xy 275.701892 21.5505) (xy 275.678425 21.632976) (xy 275.662669 21.717266) (xy 275.654757 21.802649)
			(xy 271.159491 21.802649) (xy 271.151579 21.717266) (xy 271.135823 21.632976) (xy 271.112356 21.5505)
			(xy 271.08138 21.470541) (xy 271.043158 21.393781) (xy 270.998017 21.320875) (xy 270.946341 21.252446)
			(xy 270.888572 21.189076) (xy 270.825202 21.131307) (xy 270.756773 21.079631) (xy 270.683867 21.03449)
			(xy 270.607107 20.996268) (xy 270.527148 20.965292) (xy 270.444672 20.941825) (xy 270.360382 20.926069)
			(xy 270.274999 20.918157) (xy 270.189249 20.918157) (xy 270.103866 20.926069) (xy 270.019576 20.941825)
			(xy 269.9371 20.965292) (xy 269.857141 20.996268) (xy 269.780381 21.03449) (xy 269.707475 21.079631)
			(xy 269.639046 21.131307) (xy 269.575676 21.189076) (xy 269.517907 21.252446) (xy 269.466231 21.320875)
			(xy 269.42109 21.393781) (xy 269.382868 21.470541) (xy 269.351892 21.5505) (xy 269.328425 21.632976)
			(xy 269.312669 21.717266) (xy 269.304757 21.802649) (xy 158.621984 21.802649) (xy 158.621984 19.262649)
			(xy 209.995757 19.262649) (xy 209.995757 19.348399) (xy 210.003669 19.433782) (xy 210.019425 19.518072)
			(xy 210.042892 19.600548) (xy 210.073868 19.680507) (xy 210.11209 19.757267) (xy 210.157231 19.830173)
			(xy 210.208907 19.898602) (xy 210.266676 19.961972) (xy 210.330046 20.019741) (xy 210.398475 20.071417)
			(xy 210.471381 20.116558) (xy 210.548141 20.15478) (xy 210.6281 20.185756) (xy 210.710576 20.209223)
			(xy 210.794866 20.224979) (xy 210.880249 20.232891) (xy 210.965999 20.232891) (xy 211.051382 20.224979)
			(xy 211.135672 20.209223) (xy 211.218148 20.185756) (xy 211.298107 20.15478) (xy 211.374867 20.116558)
			(xy 211.447773 20.071417) (xy 211.516202 20.019741) (xy 211.579572 19.961972) (xy 211.637341 19.898602)
			(xy 211.689017 19.830173) (xy 211.734158 19.757267) (xy 211.77238 19.680507) (xy 211.803356 19.600548)
			(xy 211.826823 19.518072) (xy 211.842579 19.433782) (xy 211.850491 19.348399) (xy 211.850986 19.305524)
			(xy 211.850491 19.262649) (xy 216.345757 19.262649) (xy 216.345757 19.348399) (xy 216.353669 19.433782)
			(xy 216.369425 19.518072) (xy 216.392892 19.600548) (xy 216.423868 19.680507) (xy 216.46209 19.757267)
			(xy 216.507231 19.830173) (xy 216.558907 19.898602) (xy 216.616676 19.961972) (xy 216.680046 20.019741)
			(xy 216.748475 20.071417) (xy 216.821381 20.116558) (xy 216.898141 20.15478) (xy 216.9781 20.185756)
			(xy 217.060576 20.209223) (xy 217.144866 20.224979) (xy 217.230249 20.232891) (xy 217.315999 20.232891)
			(xy 217.401382 20.224979) (xy 217.485672 20.209223) (xy 217.568148 20.185756) (xy 217.648107 20.15478)
			(xy 217.724867 20.116558) (xy 217.797773 20.071417) (xy 217.866202 20.019741) (xy 217.929572 19.961972)
			(xy 217.987341 19.898602) (xy 218.039017 19.830173) (xy 218.084158 19.757267) (xy 218.12238 19.680507)
			(xy 218.153356 19.600548) (xy 218.176823 19.518072) (xy 218.192579 19.433782) (xy 218.200491 19.348399)
			(xy 218.200986 19.305524) (xy 218.200491 19.262649) (xy 218.199832 19.255537) (xy 244.026677 19.255537)
			(xy 244.026677 19.341287) (xy 244.034589 19.42667) (xy 244.050345 19.51096) (xy 244.073812 19.593436)
			(xy 244.104788 19.673395) (xy 244.14301 19.750155) (xy 244.188151 19.823061) (xy 244.239827 19.89149)
			(xy 244.297596 19.95486) (xy 244.360966 20.012629) (xy 244.429395 20.064305) (xy 244.502301 20.109446)
			(xy 244.579061 20.147668) (xy 244.65902 20.178644) (xy 244.741496 20.202111) (xy 244.825786 20.217867)
			(xy 244.911169 20.225779) (xy 244.996919 20.225779) (xy 245.082302 20.217867) (xy 245.166592 20.202111)
			(xy 245.249068 20.178644) (xy 245.329027 20.147668) (xy 245.405787 20.109446) (xy 245.478693 20.064305)
			(xy 245.547122 20.012629) (xy 245.610492 19.95486) (xy 245.668261 19.89149) (xy 245.719937 19.823061)
			(xy 245.765078 19.750155) (xy 245.8033 19.673395) (xy 245.834276 19.593436) (xy 245.857743 19.51096)
			(xy 245.873499 19.42667) (xy 245.881411 19.341287) (xy 245.881906 19.298412) (xy 245.881411 19.255537)
			(xy 250.376677 19.255537) (xy 250.376677 19.341287) (xy 250.384589 19.42667) (xy 250.400345 19.51096)
			(xy 250.423812 19.593436) (xy 250.454788 19.673395) (xy 250.49301 19.750155) (xy 250.538151 19.823061)
			(xy 250.589827 19.89149) (xy 250.647596 19.95486) (xy 250.710966 20.012629) (xy 250.779395 20.064305)
			(xy 250.852301 20.109446) (xy 250.929061 20.147668) (xy 251.00902 20.178644) (xy 251.091496 20.202111)
			(xy 251.175786 20.217867) (xy 251.261169 20.225779) (xy 251.346919 20.225779) (xy 251.432302 20.217867)
			(xy 251.516592 20.202111) (xy 251.599068 20.178644) (xy 251.679027 20.147668) (xy 251.755787 20.109446)
			(xy 251.828693 20.064305) (xy 251.897122 20.012629) (xy 251.960492 19.95486) (xy 252.018261 19.89149)
			(xy 252.069937 19.823061) (xy 252.115078 19.750155) (xy 252.1533 19.673395) (xy 252.184276 19.593436)
			(xy 252.207743 19.51096) (xy 252.223499 19.42667) (xy 252.231411 19.341287) (xy 252.231906 19.298412)
			(xy 252.231493 19.262649) (xy 269.304757 19.262649) (xy 269.304757 19.348399) (xy 269.312669 19.433782)
			(xy 269.328425 19.518072) (xy 269.351892 19.600548) (xy 269.382868 19.680507) (xy 269.42109 19.757267)
			(xy 269.466231 19.830173) (xy 269.517907 19.898602) (xy 269.575676 19.961972) (xy 269.639046 20.019741)
			(xy 269.707475 20.071417) (xy 269.780381 20.116558) (xy 269.857141 20.15478) (xy 269.9371 20.185756)
			(xy 270.019576 20.209223) (xy 270.103866 20.224979) (xy 270.189249 20.232891) (xy 270.274999 20.232891)
			(xy 270.360382 20.224979) (xy 270.444672 20.209223) (xy 270.527148 20.185756) (xy 270.607107 20.15478)
			(xy 270.62931 20.143724) (xy 274.239736 20.143724) (xy 274.239736 21.007324) (xy 274.240222 21.034593)
			(xy 274.247984 21.088577) (xy 274.263349 21.140907) (xy 274.286006 21.190517) (xy 274.315492 21.236398)
			(xy 274.351207 21.277615) (xy 274.392424 21.31333) (xy 274.438305 21.342816) (xy 274.487915 21.365473)
			(xy 274.540245 21.380838) (xy 274.594229 21.3886) (xy 274.648767 21.3886) (xy 274.702751 21.380838)
			(xy 274.755081 21.365473) (xy 274.804691 21.342816) (xy 274.850572 21.31333) (xy 274.891789 21.277615)
			(xy 274.927504 21.236398) (xy 274.95699 21.190517) (xy 274.979647 21.140907) (xy 274.995012 21.088577)
			(xy 275.002774 21.034593) (xy 275.00326 21.007324) (xy 275.00326 20.143724) (xy 275.002774 20.116455)
			(xy 274.995012 20.062471) (xy 274.979647 20.010141) (xy 274.95699 19.960531) (xy 274.927504 19.91465)
			(xy 274.891789 19.873433) (xy 274.850572 19.837718) (xy 274.804691 19.808232) (xy 274.755081 19.785575)
			(xy 274.702751 19.77021) (xy 274.648767 19.762448) (xy 274.594229 19.762448) (xy 274.540245 19.77021)
			(xy 274.487915 19.785575) (xy 274.438305 19.808232) (xy 274.392424 19.837718) (xy 274.351207 19.873433)
			(xy 274.315492 19.91465) (xy 274.286006 19.960531) (xy 274.263349 20.010141) (xy 274.247984 20.062471)
			(xy 274.240222 20.116455) (xy 274.239736 20.143724) (xy 270.62931 20.143724) (xy 270.683867 20.116558)
			(xy 270.756773 20.071417) (xy 270.825202 20.019741) (xy 270.888572 19.961972) (xy 270.946341 19.898602)
			(xy 270.998017 19.830173) (xy 271.043158 19.757267) (xy 271.08138 19.680507) (xy 271.112356 19.600548)
			(xy 271.135823 19.518072) (xy 271.151579 19.433782) (xy 271.159491 19.348399) (xy 271.159986 19.305524)
			(xy 271.159491 19.262649) (xy 275.654757 19.262649) (xy 275.654757 19.348399) (xy 275.662669 19.433782)
			(xy 275.678425 19.518072) (xy 275.701892 19.600548) (xy 275.732868 19.680507) (xy 275.77109 19.757267)
			(xy 275.816231 19.830173) (xy 275.867907 19.898602) (xy 275.925676 19.961972) (xy 275.989046 20.019741)
			(xy 276.057475 20.071417) (xy 276.130381 20.116558) (xy 276.207141 20.15478) (xy 276.2871 20.185756)
			(xy 276.369576 20.209223) (xy 276.453866 20.224979) (xy 276.539249 20.232891) (xy 276.624999 20.232891)
			(xy 276.710382 20.224979) (xy 276.794672 20.209223) (xy 276.877148 20.185756) (xy 276.957107 20.15478)
			(xy 277.033867 20.116558) (xy 277.106773 20.071417) (xy 277.175202 20.019741) (xy 277.238572 19.961972)
			(xy 277.296341 19.898602) (xy 277.348017 19.830173) (xy 277.393158 19.757267) (xy 277.43138 19.680507)
			(xy 277.462356 19.600548) (xy 277.485823 19.518072) (xy 277.501579 19.433782) (xy 277.509491 19.348399)
			(xy 277.509986 19.305524) (xy 277.509491 19.262649) (xy 277.508832 19.255537) (xy 308.364877 19.255537)
			(xy 308.364877 19.341287) (xy 308.372789 19.42667) (xy 308.388545 19.51096) (xy 308.412012 19.593436)
			(xy 308.442988 19.673395) (xy 308.48121 19.750155) (xy 308.526351 19.823061) (xy 308.578027 19.89149)
			(xy 308.635796 19.95486) (xy 308.699166 20.012629) (xy 308.767595 20.064305) (xy 308.840501 20.109446)
			(xy 308.917261 20.147668) (xy 308.99722 20.178644) (xy 309.079696 20.202111) (xy 309.163986 20.217867)
			(xy 309.249369 20.225779) (xy 309.335119 20.225779) (xy 309.420502 20.217867) (xy 309.504792 20.202111)
			(xy 309.587268 20.178644) (xy 309.667227 20.147668) (xy 309.68943 20.136612) (xy 310.871108 20.136612)
			(xy 310.871108 21.000212) (xy 310.871594 21.027481) (xy 310.879356 21.081465) (xy 310.894721 21.133795)
			(xy 310.917378 21.183405) (xy 310.946864 21.229286) (xy 310.982579 21.270503) (xy 311.023796 21.306218)
			(xy 311.069677 21.335704) (xy 311.119287 21.358361) (xy 311.171617 21.373726) (xy 311.225601 21.381488)
			(xy 311.280139 21.381488) (xy 311.334123 21.373726) (xy 311.386453 21.358361) (xy 311.436063 21.335704)
			(xy 311.481944 21.306218) (xy 311.523161 21.270503) (xy 311.558876 21.229286) (xy 311.588362 21.183405)
			(xy 311.611019 21.133795) (xy 311.626384 21.081465) (xy 311.634146 21.027481) (xy 311.634632 21.000212)
			(xy 311.634632 20.136612) (xy 311.634146 20.109343) (xy 311.626384 20.055359) (xy 311.611019 20.003029)
			(xy 311.588362 19.953419) (xy 311.558876 19.907538) (xy 311.523161 19.866321) (xy 311.481944 19.830606)
			(xy 311.436063 19.80112) (xy 311.386453 19.778463) (xy 311.334123 19.763098) (xy 311.280139 19.755336)
			(xy 311.225601 19.755336) (xy 311.171617 19.763098) (xy 311.119287 19.778463) (xy 311.069677 19.80112)
			(xy 311.023796 19.830606) (xy 310.982579 19.866321) (xy 310.946864 19.907538) (xy 310.917378 19.953419)
			(xy 310.894721 20.003029) (xy 310.879356 20.055359) (xy 310.871594 20.109343) (xy 310.871108 20.136612)
			(xy 309.68943 20.136612) (xy 309.743987 20.109446) (xy 309.816893 20.064305) (xy 309.885322 20.012629)
			(xy 309.948692 19.95486) (xy 310.006461 19.89149) (xy 310.058137 19.823061) (xy 310.103278 19.750155)
			(xy 310.1415 19.673395) (xy 310.172476 19.593436) (xy 310.195943 19.51096) (xy 310.211699 19.42667)
			(xy 310.219611 19.341287) (xy 310.220106 19.298412) (xy 310.219611 19.255537) (xy 314.714877 19.255537)
			(xy 314.714877 19.341287) (xy 314.722789 19.42667) (xy 314.738545 19.51096) (xy 314.762012 19.593436)
			(xy 314.792988 19.673395) (xy 314.83121 19.750155) (xy 314.876351 19.823061) (xy 314.928027 19.89149)
			(xy 314.985796 19.95486) (xy 315.049166 20.012629) (xy 315.117595 20.064305) (xy 315.190501 20.109446)
			(xy 315.267261 20.147668) (xy 315.34722 20.178644) (xy 315.429696 20.202111) (xy 315.513986 20.217867)
			(xy 315.599369 20.225779) (xy 315.685119 20.225779) (xy 315.770502 20.217867) (xy 315.854792 20.202111)
			(xy 315.937268 20.178644) (xy 316.017227 20.147668) (xy 316.093987 20.109446) (xy 316.166893 20.064305)
			(xy 316.235322 20.012629) (xy 316.298692 19.95486) (xy 316.356461 19.89149) (xy 316.408137 19.823061)
			(xy 316.453278 19.750155) (xy 316.4915 19.673395) (xy 316.522476 19.593436) (xy 316.545943 19.51096)
			(xy 316.561699 19.42667) (xy 316.569611 19.341287) (xy 316.570106 19.298412) (xy 316.569693 19.262649)
			(xy 334.455757 19.262649) (xy 334.455757 19.348399) (xy 334.463669 19.433782) (xy 334.479425 19.518072)
			(xy 334.502892 19.600548) (xy 334.533868 19.680507) (xy 334.57209 19.757267) (xy 334.617231 19.830173)
			(xy 334.668907 19.898602) (xy 334.726676 19.961972) (xy 334.790046 20.019741) (xy 334.858475 20.071417)
			(xy 334.931381 20.116558) (xy 335.008141 20.15478) (xy 335.0881 20.185756) (xy 335.170576 20.209223)
			(xy 335.254866 20.224979) (xy 335.340249 20.232891) (xy 335.425999 20.232891) (xy 335.511382 20.224979)
			(xy 335.595672 20.209223) (xy 335.678148 20.185756) (xy 335.758107 20.15478) (xy 335.78031 20.143724)
			(xy 339.390736 20.143724) (xy 339.390736 21.007324) (xy 339.391222 21.034593) (xy 339.398984 21.088577)
			(xy 339.414349 21.140907) (xy 339.437006 21.190517) (xy 339.466492 21.236398) (xy 339.502207 21.277615)
			(xy 339.543424 21.31333) (xy 339.589305 21.342816) (xy 339.638915 21.365473) (xy 339.691245 21.380838)
			(xy 339.745229 21.3886) (xy 339.799767 21.3886) (xy 339.853751 21.380838) (xy 339.906081 21.365473)
			(xy 339.955691 21.342816) (xy 340.001572 21.31333) (xy 340.042789 21.277615) (xy 340.078504 21.236398)
			(xy 340.10799 21.190517) (xy 340.130647 21.140907) (xy 340.146012 21.088577) (xy 340.153774 21.034593)
			(xy 340.15426 21.007324) (xy 340.15426 20.143724) (xy 340.153774 20.116455) (xy 340.146012 20.062471)
			(xy 340.130647 20.010141) (xy 340.10799 19.960531) (xy 340.078504 19.91465) (xy 340.042789 19.873433)
			(xy 340.001572 19.837718) (xy 339.955691 19.808232) (xy 339.906081 19.785575) (xy 339.853751 19.77021)
			(xy 339.799767 19.762448) (xy 339.745229 19.762448) (xy 339.691245 19.77021) (xy 339.638915 19.785575)
			(xy 339.589305 19.808232) (xy 339.543424 19.837718) (xy 339.502207 19.873433) (xy 339.466492 19.91465)
			(xy 339.437006 19.960531) (xy 339.414349 20.010141) (xy 339.398984 20.062471) (xy 339.391222 20.116455)
			(xy 339.390736 20.143724) (xy 335.78031 20.143724) (xy 335.834867 20.116558) (xy 335.907773 20.071417)
			(xy 335.976202 20.019741) (xy 336.039572 19.961972) (xy 336.097341 19.898602) (xy 336.149017 19.830173)
			(xy 336.194158 19.757267) (xy 336.23238 19.680507) (xy 336.263356 19.600548) (xy 336.286823 19.518072)
			(xy 336.302579 19.433782) (xy 336.310491 19.348399) (xy 336.310986 19.305524) (xy 336.310491 19.262649)
			(xy 340.805757 19.262649) (xy 340.805757 19.348399) (xy 340.813669 19.433782) (xy 340.829425 19.518072)
			(xy 340.852892 19.600548) (xy 340.883868 19.680507) (xy 340.92209 19.757267) (xy 340.967231 19.830173)
			(xy 341.018907 19.898602) (xy 341.076676 19.961972) (xy 341.140046 20.019741) (xy 341.208475 20.071417)
			(xy 341.281381 20.116558) (xy 341.358141 20.15478) (xy 341.4381 20.185756) (xy 341.520576 20.209223)
			(xy 341.604866 20.224979) (xy 341.690249 20.232891) (xy 341.775999 20.232891) (xy 341.861382 20.224979)
			(xy 341.945672 20.209223) (xy 342.028148 20.185756) (xy 342.108107 20.15478) (xy 342.184867 20.116558)
			(xy 342.257773 20.071417) (xy 342.326202 20.019741) (xy 342.389572 19.961972) (xy 342.447341 19.898602)
			(xy 342.499017 19.830173) (xy 342.544158 19.757267) (xy 342.58238 19.680507) (xy 342.613356 19.600548)
			(xy 342.636823 19.518072) (xy 342.652579 19.433782) (xy 342.660491 19.348399) (xy 342.660986 19.305524)
			(xy 342.660491 19.262649) (xy 342.659832 19.255537) (xy 373.515877 19.255537) (xy 373.515877 19.341287)
			(xy 373.523789 19.42667) (xy 373.539545 19.51096) (xy 373.563012 19.593436) (xy 373.593988 19.673395)
			(xy 373.63221 19.750155) (xy 373.677351 19.823061) (xy 373.729027 19.89149) (xy 373.786796 19.95486)
			(xy 373.850166 20.012629) (xy 373.918595 20.064305) (xy 373.991501 20.109446) (xy 374.068261 20.147668)
			(xy 374.14822 20.178644) (xy 374.230696 20.202111) (xy 374.314986 20.217867) (xy 374.400369 20.225779)
			(xy 374.486119 20.225779) (xy 374.571502 20.217867) (xy 374.655792 20.202111) (xy 374.738268 20.178644)
			(xy 374.818227 20.147668) (xy 374.84043 20.136612) (xy 376.022108 20.136612) (xy 376.022108 21.000212)
			(xy 376.022594 21.027481) (xy 376.030356 21.081465) (xy 376.045721 21.133795) (xy 376.068378 21.183405)
			(xy 376.097864 21.229286) (xy 376.133579 21.270503) (xy 376.174796 21.306218) (xy 376.220677 21.335704)
			(xy 376.270287 21.358361) (xy 376.322617 21.373726) (xy 376.376601 21.381488) (xy 376.431139 21.381488)
			(xy 376.485123 21.373726) (xy 376.537453 21.358361) (xy 376.587063 21.335704) (xy 376.632944 21.306218)
			(xy 376.674161 21.270503) (xy 376.709876 21.229286) (xy 376.739362 21.183405) (xy 376.762019 21.133795)
			(xy 376.777384 21.081465) (xy 376.785146 21.027481) (xy 376.785632 21.000212) (xy 376.785632 20.136612)
			(xy 376.785146 20.109343) (xy 376.777384 20.055359) (xy 376.762019 20.003029) (xy 376.739362 19.953419)
			(xy 376.709876 19.907538) (xy 376.674161 19.866321) (xy 376.632944 19.830606) (xy 376.587063 19.80112)
			(xy 376.537453 19.778463) (xy 376.485123 19.763098) (xy 376.431139 19.755336) (xy 376.376601 19.755336)
			(xy 376.322617 19.763098) (xy 376.270287 19.778463) (xy 376.220677 19.80112) (xy 376.174796 19.830606)
			(xy 376.133579 19.866321) (xy 376.097864 19.907538) (xy 376.068378 19.953419) (xy 376.045721 20.003029)
			(xy 376.030356 20.055359) (xy 376.022594 20.109343) (xy 376.022108 20.136612) (xy 374.84043 20.136612)
			(xy 374.894987 20.109446) (xy 374.967893 20.064305) (xy 375.036322 20.012629) (xy 375.099692 19.95486)
			(xy 375.157461 19.89149) (xy 375.209137 19.823061) (xy 375.254278 19.750155) (xy 375.2925 19.673395)
			(xy 375.323476 19.593436) (xy 375.346943 19.51096) (xy 375.362699 19.42667) (xy 375.370611 19.341287)
			(xy 375.371106 19.298412) (xy 375.370611 19.255537) (xy 379.865877 19.255537) (xy 379.865877 19.341287)
			(xy 379.873789 19.42667) (xy 379.889545 19.51096) (xy 379.913012 19.593436) (xy 379.943988 19.673395)
			(xy 379.98221 19.750155) (xy 380.027351 19.823061) (xy 380.079027 19.89149) (xy 380.136796 19.95486)
			(xy 380.200166 20.012629) (xy 380.268595 20.064305) (xy 380.341501 20.109446) (xy 380.418261 20.147668)
			(xy 380.49822 20.178644) (xy 380.580696 20.202111) (xy 380.664986 20.217867) (xy 380.750369 20.225779)
			(xy 380.836119 20.225779) (xy 380.921502 20.217867) (xy 381.005792 20.202111) (xy 381.088268 20.178644)
			(xy 381.168227 20.147668) (xy 381.244987 20.109446) (xy 381.317893 20.064305) (xy 381.386322 20.012629)
			(xy 381.449692 19.95486) (xy 381.507461 19.89149) (xy 381.559137 19.823061) (xy 381.604278 19.750155)
			(xy 381.6425 19.673395) (xy 381.673476 19.593436) (xy 381.696943 19.51096) (xy 381.712699 19.42667)
			(xy 381.720611 19.341287) (xy 381.721106 19.298412) (xy 381.720693 19.262649) (xy 399.098757 19.262649)
			(xy 399.098757 19.348399) (xy 399.106669 19.433782) (xy 399.122425 19.518072) (xy 399.145892 19.600548)
			(xy 399.176868 19.680507) (xy 399.21509 19.757267) (xy 399.260231 19.830173) (xy 399.311907 19.898602)
			(xy 399.369676 19.961972) (xy 399.433046 20.019741) (xy 399.501475 20.071417) (xy 399.574381 20.116558)
			(xy 399.651141 20.15478) (xy 399.7311 20.185756) (xy 399.813576 20.209223) (xy 399.897866 20.224979)
			(xy 399.983249 20.232891) (xy 400.068999 20.232891) (xy 400.154382 20.224979) (xy 400.238672 20.209223)
			(xy 400.321148 20.185756) (xy 400.401107 20.15478) (xy 400.42331 20.143724) (xy 404.033736 20.143724)
			(xy 404.033736 21.007324) (xy 404.034222 21.034593) (xy 404.041984 21.088577) (xy 404.057349 21.140907)
			(xy 404.080006 21.190517) (xy 404.109492 21.236398) (xy 404.145207 21.277615) (xy 404.186424 21.31333)
			(xy 404.232305 21.342816) (xy 404.281915 21.365473) (xy 404.334245 21.380838) (xy 404.388229 21.3886)
			(xy 404.442767 21.3886) (xy 404.496751 21.380838) (xy 404.549081 21.365473) (xy 404.598691 21.342816)
			(xy 404.644572 21.31333) (xy 404.685789 21.277615) (xy 404.721504 21.236398) (xy 404.75099 21.190517)
			(xy 404.773647 21.140907) (xy 404.789012 21.088577) (xy 404.796774 21.034593) (xy 404.79726 21.007324)
			(xy 404.79726 20.143724) (xy 404.796774 20.116455) (xy 404.789012 20.062471) (xy 404.773647 20.010141)
			(xy 404.75099 19.960531) (xy 404.721504 19.91465) (xy 404.685789 19.873433) (xy 404.644572 19.837718)
			(xy 404.598691 19.808232) (xy 404.549081 19.785575) (xy 404.496751 19.77021) (xy 404.442767 19.762448)
			(xy 404.388229 19.762448) (xy 404.334245 19.77021) (xy 404.281915 19.785575) (xy 404.232305 19.808232)
			(xy 404.186424 19.837718) (xy 404.145207 19.873433) (xy 404.109492 19.91465) (xy 404.080006 19.960531)
			(xy 404.057349 20.010141) (xy 404.041984 20.062471) (xy 404.034222 20.116455) (xy 404.033736 20.143724)
			(xy 400.42331 20.143724) (xy 400.477867 20.116558) (xy 400.550773 20.071417) (xy 400.619202 20.019741)
			(xy 400.682572 19.961972) (xy 400.740341 19.898602) (xy 400.792017 19.830173) (xy 400.837158 19.757267)
			(xy 400.87538 19.680507) (xy 400.906356 19.600548) (xy 400.929823 19.518072) (xy 400.945579 19.433782)
			(xy 400.953491 19.348399) (xy 400.953986 19.305524) (xy 400.953491 19.262649) (xy 405.448757 19.262649)
			(xy 405.448757 19.348399) (xy 405.456669 19.433782) (xy 405.472425 19.518072) (xy 405.495892 19.600548)
			(xy 405.526868 19.680507) (xy 405.56509 19.757267) (xy 405.610231 19.830173) (xy 405.661907 19.898602)
			(xy 405.719676 19.961972) (xy 405.783046 20.019741) (xy 405.851475 20.071417) (xy 405.924381 20.116558)
			(xy 406.001141 20.15478) (xy 406.0811 20.185756) (xy 406.163576 20.209223) (xy 406.247866 20.224979)
			(xy 406.333249 20.232891) (xy 406.418999 20.232891) (xy 406.504382 20.224979) (xy 406.588672 20.209223)
			(xy 406.671148 20.185756) (xy 406.751107 20.15478) (xy 406.827867 20.116558) (xy 406.900773 20.071417)
			(xy 406.969202 20.019741) (xy 407.032572 19.961972) (xy 407.090341 19.898602) (xy 407.142017 19.830173)
			(xy 407.187158 19.757267) (xy 407.22538 19.680507) (xy 407.256356 19.600548) (xy 407.279823 19.518072)
			(xy 407.295579 19.433782) (xy 407.303491 19.348399) (xy 407.303986 19.305524) (xy 407.303491 19.262649)
			(xy 407.302832 19.255537) (xy 438.158877 19.255537) (xy 438.158877 19.341287) (xy 438.166789 19.42667)
			(xy 438.182545 19.51096) (xy 438.206012 19.593436) (xy 438.236988 19.673395) (xy 438.27521 19.750155)
			(xy 438.320351 19.823061) (xy 438.372027 19.89149) (xy 438.429796 19.95486) (xy 438.493166 20.012629)
			(xy 438.561595 20.064305) (xy 438.634501 20.109446) (xy 438.711261 20.147668) (xy 438.79122 20.178644)
			(xy 438.873696 20.202111) (xy 438.957986 20.217867) (xy 439.043369 20.225779) (xy 439.129119 20.225779)
			(xy 439.214502 20.217867) (xy 439.298792 20.202111) (xy 439.381268 20.178644) (xy 439.461227 20.147668)
			(xy 439.48343 20.136612) (xy 440.665108 20.136612) (xy 440.665108 21.000212) (xy 440.665594 21.027481)
			(xy 440.673356 21.081465) (xy 440.688721 21.133795) (xy 440.711378 21.183405) (xy 440.740864 21.229286)
			(xy 440.776579 21.270503) (xy 440.817796 21.306218) (xy 440.863677 21.335704) (xy 440.913287 21.358361)
			(xy 440.965617 21.373726) (xy 441.019601 21.381488) (xy 441.074139 21.381488) (xy 441.128123 21.373726)
			(xy 441.180453 21.358361) (xy 441.230063 21.335704) (xy 441.275944 21.306218) (xy 441.317161 21.270503)
			(xy 441.352876 21.229286) (xy 441.382362 21.183405) (xy 441.405019 21.133795) (xy 441.420384 21.081465)
			(xy 441.428146 21.027481) (xy 441.428632 21.000212) (xy 441.428632 20.136612) (xy 441.428146 20.109343)
			(xy 441.420384 20.055359) (xy 441.405019 20.003029) (xy 441.382362 19.953419) (xy 441.352876 19.907538)
			(xy 441.317161 19.866321) (xy 441.275944 19.830606) (xy 441.230063 19.80112) (xy 441.180453 19.778463)
			(xy 441.128123 19.763098) (xy 441.074139 19.755336) (xy 441.019601 19.755336) (xy 440.965617 19.763098)
			(xy 440.913287 19.778463) (xy 440.863677 19.80112) (xy 440.817796 19.830606) (xy 440.776579 19.866321)
			(xy 440.740864 19.907538) (xy 440.711378 19.953419) (xy 440.688721 20.003029) (xy 440.673356 20.055359)
			(xy 440.665594 20.109343) (xy 440.665108 20.136612) (xy 439.48343 20.136612) (xy 439.537987 20.109446)
			(xy 439.610893 20.064305) (xy 439.679322 20.012629) (xy 439.742692 19.95486) (xy 439.800461 19.89149)
			(xy 439.852137 19.823061) (xy 439.897278 19.750155) (xy 439.9355 19.673395) (xy 439.966476 19.593436)
			(xy 439.989943 19.51096) (xy 440.005699 19.42667) (xy 440.013611 19.341287) (xy 440.014106 19.298412)
			(xy 440.013611 19.255537) (xy 444.508877 19.255537) (xy 444.508877 19.341287) (xy 444.516789 19.42667)
			(xy 444.532545 19.51096) (xy 444.556012 19.593436) (xy 444.586988 19.673395) (xy 444.62521 19.750155)
			(xy 444.670351 19.823061) (xy 444.722027 19.89149) (xy 444.779796 19.95486) (xy 444.843166 20.012629)
			(xy 444.911595 20.064305) (xy 444.984501 20.109446) (xy 445.061261 20.147668) (xy 445.14122 20.178644)
			(xy 445.223696 20.202111) (xy 445.307986 20.217867) (xy 445.393369 20.225779) (xy 445.479119 20.225779)
			(xy 445.564502 20.217867) (xy 445.648792 20.202111) (xy 445.731268 20.178644) (xy 445.811227 20.147668)
			(xy 445.887987 20.109446) (xy 445.960893 20.064305) (xy 446.029322 20.012629) (xy 446.092692 19.95486)
			(xy 446.150461 19.89149) (xy 446.202137 19.823061) (xy 446.247278 19.750155) (xy 446.2855 19.673395)
			(xy 446.316476 19.593436) (xy 446.339943 19.51096) (xy 446.355699 19.42667) (xy 446.363611 19.341287)
			(xy 446.364106 19.298412) (xy 446.363611 19.255537) (xy 446.355699 19.170154) (xy 446.339943 19.085864)
			(xy 446.316476 19.003388) (xy 446.2855 18.923429) (xy 446.247278 18.846669) (xy 446.202137 18.773763)
			(xy 446.150461 18.705334) (xy 446.092692 18.641964) (xy 446.029322 18.584195) (xy 445.960893 18.532519)
			(xy 445.887987 18.487378) (xy 445.811227 18.449156) (xy 445.731268 18.41818) (xy 445.648792 18.394713)
			(xy 445.564502 18.378957) (xy 445.479119 18.371045) (xy 445.393369 18.371045) (xy 445.307986 18.378957)
			(xy 445.223696 18.394713) (xy 445.14122 18.41818) (xy 445.061261 18.449156) (xy 444.984501 18.487378)
			(xy 444.911595 18.532519) (xy 444.843166 18.584195) (xy 444.779796 18.641964) (xy 444.722027 18.705334)
			(xy 444.670351 18.773763) (xy 444.62521 18.846669) (xy 444.586988 18.923429) (xy 444.556012 19.003388)
			(xy 444.532545 19.085864) (xy 444.516789 19.170154) (xy 444.508877 19.255537) (xy 440.013611 19.255537)
			(xy 440.005699 19.170154) (xy 439.989943 19.085864) (xy 439.966476 19.003388) (xy 439.9355 18.923429)
			(xy 439.897278 18.846669) (xy 439.852137 18.773763) (xy 439.800461 18.705334) (xy 439.742692 18.641964)
			(xy 439.679322 18.584195) (xy 439.610893 18.532519) (xy 439.537987 18.487378) (xy 439.461227 18.449156)
			(xy 439.381268 18.41818) (xy 439.298792 18.394713) (xy 439.214502 18.378957) (xy 439.129119 18.371045)
			(xy 439.043369 18.371045) (xy 438.957986 18.378957) (xy 438.873696 18.394713) (xy 438.79122 18.41818)
			(xy 438.711261 18.449156) (xy 438.634501 18.487378) (xy 438.561595 18.532519) (xy 438.493166 18.584195)
			(xy 438.429796 18.641964) (xy 438.372027 18.705334) (xy 438.320351 18.773763) (xy 438.27521 18.846669)
			(xy 438.236988 18.923429) (xy 438.206012 19.003388) (xy 438.182545 19.085864) (xy 438.166789 19.170154)
			(xy 438.158877 19.255537) (xy 407.302832 19.255537) (xy 407.295579 19.177266) (xy 407.279823 19.092976)
			(xy 407.256356 19.0105) (xy 407.22538 18.930541) (xy 407.187158 18.853781) (xy 407.142017 18.780875)
			(xy 407.090341 18.712446) (xy 407.032572 18.649076) (xy 406.969202 18.591307) (xy 406.900773 18.539631)
			(xy 406.827867 18.49449) (xy 406.751107 18.456268) (xy 406.671148 18.425292) (xy 406.588672 18.401825)
			(xy 406.504382 18.386069) (xy 406.418999 18.378157) (xy 406.333249 18.378157) (xy 406.247866 18.386069)
			(xy 406.163576 18.401825) (xy 406.0811 18.425292) (xy 406.001141 18.456268) (xy 405.924381 18.49449)
			(xy 405.851475 18.539631) (xy 405.783046 18.591307) (xy 405.719676 18.649076) (xy 405.661907 18.712446)
			(xy 405.610231 18.780875) (xy 405.56509 18.853781) (xy 405.526868 18.930541) (xy 405.495892 19.0105)
			(xy 405.472425 19.092976) (xy 405.456669 19.177266) (xy 405.448757 19.262649) (xy 400.953491 19.262649)
			(xy 400.945579 19.177266) (xy 400.929823 19.092976) (xy 400.906356 19.0105) (xy 400.87538 18.930541)
			(xy 400.837158 18.853781) (xy 400.792017 18.780875) (xy 400.740341 18.712446) (xy 400.682572 18.649076)
			(xy 400.619202 18.591307) (xy 400.550773 18.539631) (xy 400.477867 18.49449) (xy 400.401107 18.456268)
			(xy 400.321148 18.425292) (xy 400.238672 18.401825) (xy 400.154382 18.386069) (xy 400.068999 18.378157)
			(xy 399.983249 18.378157) (xy 399.897866 18.386069) (xy 399.813576 18.401825) (xy 399.7311 18.425292)
			(xy 399.651141 18.456268) (xy 399.574381 18.49449) (xy 399.501475 18.539631) (xy 399.433046 18.591307)
			(xy 399.369676 18.649076) (xy 399.311907 18.712446) (xy 399.260231 18.780875) (xy 399.21509 18.853781)
			(xy 399.176868 18.930541) (xy 399.145892 19.0105) (xy 399.122425 19.092976) (xy 399.106669 19.177266)
			(xy 399.098757 19.262649) (xy 381.720693 19.262649) (xy 381.720611 19.255537) (xy 381.712699 19.170154)
			(xy 381.696943 19.085864) (xy 381.673476 19.003388) (xy 381.6425 18.923429) (xy 381.604278 18.846669)
			(xy 381.559137 18.773763) (xy 381.507461 18.705334) (xy 381.449692 18.641964) (xy 381.386322 18.584195)
			(xy 381.317893 18.532519) (xy 381.244987 18.487378) (xy 381.168227 18.449156) (xy 381.088268 18.41818)
			(xy 381.005792 18.394713) (xy 380.921502 18.378957) (xy 380.836119 18.371045) (xy 380.750369 18.371045)
			(xy 380.664986 18.378957) (xy 380.580696 18.394713) (xy 380.49822 18.41818) (xy 380.418261 18.449156)
			(xy 380.341501 18.487378) (xy 380.268595 18.532519) (xy 380.200166 18.584195) (xy 380.136796 18.641964)
			(xy 380.079027 18.705334) (xy 380.027351 18.773763) (xy 379.98221 18.846669) (xy 379.943988 18.923429)
			(xy 379.913012 19.003388) (xy 379.889545 19.085864) (xy 379.873789 19.170154) (xy 379.865877 19.255537)
			(xy 375.370611 19.255537) (xy 375.362699 19.170154) (xy 375.346943 19.085864) (xy 375.323476 19.003388)
			(xy 375.2925 18.923429) (xy 375.254278 18.846669) (xy 375.209137 18.773763) (xy 375.157461 18.705334)
			(xy 375.099692 18.641964) (xy 375.036322 18.584195) (xy 374.967893 18.532519) (xy 374.894987 18.487378)
			(xy 374.818227 18.449156) (xy 374.738268 18.41818) (xy 374.655792 18.394713) (xy 374.571502 18.378957)
			(xy 374.486119 18.371045) (xy 374.400369 18.371045) (xy 374.314986 18.378957) (xy 374.230696 18.394713)
			(xy 374.14822 18.41818) (xy 374.068261 18.449156) (xy 373.991501 18.487378) (xy 373.918595 18.532519)
			(xy 373.850166 18.584195) (xy 373.786796 18.641964) (xy 373.729027 18.705334) (xy 373.677351 18.773763)
			(xy 373.63221 18.846669) (xy 373.593988 18.923429) (xy 373.563012 19.003388) (xy 373.539545 19.085864)
			(xy 373.523789 19.170154) (xy 373.515877 19.255537) (xy 342.659832 19.255537) (xy 342.652579 19.177266)
			(xy 342.636823 19.092976) (xy 342.613356 19.0105) (xy 342.58238 18.930541) (xy 342.544158 18.853781)
			(xy 342.499017 18.780875) (xy 342.447341 18.712446) (xy 342.389572 18.649076) (xy 342.326202 18.591307)
			(xy 342.257773 18.539631) (xy 342.184867 18.49449) (xy 342.108107 18.456268) (xy 342.028148 18.425292)
			(xy 341.945672 18.401825) (xy 341.861382 18.386069) (xy 341.775999 18.378157) (xy 341.690249 18.378157)
			(xy 341.604866 18.386069) (xy 341.520576 18.401825) (xy 341.4381 18.425292) (xy 341.358141 18.456268)
			(xy 341.281381 18.49449) (xy 341.208475 18.539631) (xy 341.140046 18.591307) (xy 341.076676 18.649076)
			(xy 341.018907 18.712446) (xy 340.967231 18.780875) (xy 340.92209 18.853781) (xy 340.883868 18.930541)
			(xy 340.852892 19.0105) (xy 340.829425 19.092976) (xy 340.813669 19.177266) (xy 340.805757 19.262649)
			(xy 336.310491 19.262649) (xy 336.302579 19.177266) (xy 336.286823 19.092976) (xy 336.263356 19.0105)
			(xy 336.23238 18.930541) (xy 336.194158 18.853781) (xy 336.149017 18.780875) (xy 336.097341 18.712446)
			(xy 336.039572 18.649076) (xy 335.976202 18.591307) (xy 335.907773 18.539631) (xy 335.834867 18.49449)
			(xy 335.758107 18.456268) (xy 335.678148 18.425292) (xy 335.595672 18.401825) (xy 335.511382 18.386069)
			(xy 335.425999 18.378157) (xy 335.340249 18.378157) (xy 335.254866 18.386069) (xy 335.170576 18.401825)
			(xy 335.0881 18.425292) (xy 335.008141 18.456268) (xy 334.931381 18.49449) (xy 334.858475 18.539631)
			(xy 334.790046 18.591307) (xy 334.726676 18.649076) (xy 334.668907 18.712446) (xy 334.617231 18.780875)
			(xy 334.57209 18.853781) (xy 334.533868 18.930541) (xy 334.502892 19.0105) (xy 334.479425 19.092976)
			(xy 334.463669 19.177266) (xy 334.455757 19.262649) (xy 316.569693 19.262649) (xy 316.569611 19.255537)
			(xy 316.561699 19.170154) (xy 316.545943 19.085864) (xy 316.522476 19.003388) (xy 316.4915 18.923429)
			(xy 316.453278 18.846669) (xy 316.408137 18.773763) (xy 316.356461 18.705334) (xy 316.298692 18.641964)
			(xy 316.235322 18.584195) (xy 316.166893 18.532519) (xy 316.093987 18.487378) (xy 316.017227 18.449156)
			(xy 315.937268 18.41818) (xy 315.854792 18.394713) (xy 315.770502 18.378957) (xy 315.685119 18.371045)
			(xy 315.599369 18.371045) (xy 315.513986 18.378957) (xy 315.429696 18.394713) (xy 315.34722 18.41818)
			(xy 315.267261 18.449156) (xy 315.190501 18.487378) (xy 315.117595 18.532519) (xy 315.049166 18.584195)
			(xy 314.985796 18.641964) (xy 314.928027 18.705334) (xy 314.876351 18.773763) (xy 314.83121 18.846669)
			(xy 314.792988 18.923429) (xy 314.762012 19.003388) (xy 314.738545 19.085864) (xy 314.722789 19.170154)
			(xy 314.714877 19.255537) (xy 310.219611 19.255537) (xy 310.211699 19.170154) (xy 310.195943 19.085864)
			(xy 310.172476 19.003388) (xy 310.1415 18.923429) (xy 310.103278 18.846669) (xy 310.058137 18.773763)
			(xy 310.006461 18.705334) (xy 309.948692 18.641964) (xy 309.885322 18.584195) (xy 309.816893 18.532519)
			(xy 309.743987 18.487378) (xy 309.667227 18.449156) (xy 309.587268 18.41818) (xy 309.504792 18.394713)
			(xy 309.420502 18.378957) (xy 309.335119 18.371045) (xy 309.249369 18.371045) (xy 309.163986 18.378957)
			(xy 309.079696 18.394713) (xy 308.99722 18.41818) (xy 308.917261 18.449156) (xy 308.840501 18.487378)
			(xy 308.767595 18.532519) (xy 308.699166 18.584195) (xy 308.635796 18.641964) (xy 308.578027 18.705334)
			(xy 308.526351 18.773763) (xy 308.48121 18.846669) (xy 308.442988 18.923429) (xy 308.412012 19.003388)
			(xy 308.388545 19.085864) (xy 308.372789 19.170154) (xy 308.364877 19.255537) (xy 277.508832 19.255537)
			(xy 277.501579 19.177266) (xy 277.485823 19.092976) (xy 277.462356 19.0105) (xy 277.43138 18.930541)
			(xy 277.393158 18.853781) (xy 277.348017 18.780875) (xy 277.296341 18.712446) (xy 277.238572 18.649076)
			(xy 277.175202 18.591307) (xy 277.106773 18.539631) (xy 277.033867 18.49449) (xy 276.957107 18.456268)
			(xy 276.877148 18.425292) (xy 276.794672 18.401825) (xy 276.710382 18.386069) (xy 276.624999 18.378157)
			(xy 276.539249 18.378157) (xy 276.453866 18.386069) (xy 276.369576 18.401825) (xy 276.2871 18.425292)
			(xy 276.207141 18.456268) (xy 276.130381 18.49449) (xy 276.057475 18.539631) (xy 275.989046 18.591307)
			(xy 275.925676 18.649076) (xy 275.867907 18.712446) (xy 275.816231 18.780875) (xy 275.77109 18.853781)
			(xy 275.732868 18.930541) (xy 275.701892 19.0105) (xy 275.678425 19.092976) (xy 275.662669 19.177266)
			(xy 275.654757 19.262649) (xy 271.159491 19.262649) (xy 271.151579 19.177266) (xy 271.135823 19.092976)
			(xy 271.112356 19.0105) (xy 271.08138 18.930541) (xy 271.043158 18.853781) (xy 270.998017 18.780875)
			(xy 270.946341 18.712446) (xy 270.888572 18.649076) (xy 270.825202 18.591307) (xy 270.756773 18.539631)
			(xy 270.683867 18.49449) (xy 270.607107 18.456268) (xy 270.527148 18.425292) (xy 270.444672 18.401825)
			(xy 270.360382 18.386069) (xy 270.274999 18.378157) (xy 270.189249 18.378157) (xy 270.103866 18.386069)
			(xy 270.019576 18.401825) (xy 269.9371 18.425292) (xy 269.857141 18.456268) (xy 269.780381 18.49449)
			(xy 269.707475 18.539631) (xy 269.639046 18.591307) (xy 269.575676 18.649076) (xy 269.517907 18.712446)
			(xy 269.466231 18.780875) (xy 269.42109 18.853781) (xy 269.382868 18.930541) (xy 269.351892 19.0105)
			(xy 269.328425 19.092976) (xy 269.312669 19.177266) (xy 269.304757 19.262649) (xy 252.231493 19.262649)
			(xy 252.231411 19.255537) (xy 252.223499 19.170154) (xy 252.207743 19.085864) (xy 252.184276 19.003388)
			(xy 252.1533 18.923429) (xy 252.115078 18.846669) (xy 252.069937 18.773763) (xy 252.018261 18.705334)
			(xy 251.960492 18.641964) (xy 251.897122 18.584195) (xy 251.828693 18.532519) (xy 251.755787 18.487378)
			(xy 251.679027 18.449156) (xy 251.599068 18.41818) (xy 251.516592 18.394713) (xy 251.432302 18.378957)
			(xy 251.346919 18.371045) (xy 251.261169 18.371045) (xy 251.175786 18.378957) (xy 251.091496 18.394713)
			(xy 251.00902 18.41818) (xy 250.929061 18.449156) (xy 250.852301 18.487378) (xy 250.779395 18.532519)
			(xy 250.710966 18.584195) (xy 250.647596 18.641964) (xy 250.589827 18.705334) (xy 250.538151 18.773763)
			(xy 250.49301 18.846669) (xy 250.454788 18.923429) (xy 250.423812 19.003388) (xy 250.400345 19.085864)
			(xy 250.384589 19.170154) (xy 250.376677 19.255537) (xy 245.881411 19.255537) (xy 245.873499 19.170154)
			(xy 245.857743 19.085864) (xy 245.834276 19.003388) (xy 245.8033 18.923429) (xy 245.765078 18.846669)
			(xy 245.719937 18.773763) (xy 245.668261 18.705334) (xy 245.610492 18.641964) (xy 245.547122 18.584195)
			(xy 245.478693 18.532519) (xy 245.405787 18.487378) (xy 245.329027 18.449156) (xy 245.249068 18.41818)
			(xy 245.166592 18.394713) (xy 245.082302 18.378957) (xy 244.996919 18.371045) (xy 244.911169 18.371045)
			(xy 244.825786 18.378957) (xy 244.741496 18.394713) (xy 244.65902 18.41818) (xy 244.579061 18.449156)
			(xy 244.502301 18.487378) (xy 244.429395 18.532519) (xy 244.360966 18.584195) (xy 244.297596 18.641964)
			(xy 244.239827 18.705334) (xy 244.188151 18.773763) (xy 244.14301 18.846669) (xy 244.104788 18.923429)
			(xy 244.073812 19.003388) (xy 244.050345 19.085864) (xy 244.034589 19.170154) (xy 244.026677 19.255537)
			(xy 218.199832 19.255537) (xy 218.192579 19.177266) (xy 218.176823 19.092976) (xy 218.153356 19.0105)
			(xy 218.12238 18.930541) (xy 218.084158 18.853781) (xy 218.039017 18.780875) (xy 217.987341 18.712446)
			(xy 217.929572 18.649076) (xy 217.866202 18.591307) (xy 217.797773 18.539631) (xy 217.724867 18.49449)
			(xy 217.648107 18.456268) (xy 217.568148 18.425292) (xy 217.485672 18.401825) (xy 217.401382 18.386069)
			(xy 217.315999 18.378157) (xy 217.230249 18.378157) (xy 217.144866 18.386069) (xy 217.060576 18.401825)
			(xy 216.9781 18.425292) (xy 216.898141 18.456268) (xy 216.821381 18.49449) (xy 216.748475 18.539631)
			(xy 216.680046 18.591307) (xy 216.616676 18.649076) (xy 216.558907 18.712446) (xy 216.507231 18.780875)
			(xy 216.46209 18.853781) (xy 216.423868 18.930541) (xy 216.392892 19.0105) (xy 216.369425 19.092976)
			(xy 216.353669 19.177266) (xy 216.345757 19.262649) (xy 211.850491 19.262649) (xy 211.842579 19.177266)
			(xy 211.826823 19.092976) (xy 211.803356 19.0105) (xy 211.77238 18.930541) (xy 211.734158 18.853781)
			(xy 211.689017 18.780875) (xy 211.637341 18.712446) (xy 211.579572 18.649076) (xy 211.516202 18.591307)
			(xy 211.447773 18.539631) (xy 211.374867 18.49449) (xy 211.298107 18.456268) (xy 211.218148 18.425292)
			(xy 211.135672 18.401825) (xy 211.051382 18.386069) (xy 210.965999 18.378157) (xy 210.880249 18.378157)
			(xy 210.794866 18.386069) (xy 210.710576 18.401825) (xy 210.6281 18.425292) (xy 210.548141 18.456268)
			(xy 210.471381 18.49449) (xy 210.398475 18.539631) (xy 210.330046 18.591307) (xy 210.266676 18.649076)
			(xy 210.208907 18.712446) (xy 210.157231 18.780875) (xy 210.11209 18.853781) (xy 210.073868 18.930541)
			(xy 210.042892 19.0105) (xy 210.019425 19.092976) (xy 210.003669 19.177266) (xy 209.995757 19.262649)
			(xy 158.621984 19.262649) (xy 158.621984 16.722649) (xy 209.995757 16.722649) (xy 209.995757 16.808399)
			(xy 210.003669 16.893782) (xy 210.019425 16.978072) (xy 210.042892 17.060548) (xy 210.073868 17.140507)
			(xy 210.11209 17.217267) (xy 210.157231 17.290173) (xy 210.208907 17.358602) (xy 210.266676 17.421972)
			(xy 210.330046 17.479741) (xy 210.398475 17.531417) (xy 210.471381 17.576558) (xy 210.548141 17.61478)
			(xy 210.6281 17.645756) (xy 210.710576 17.669223) (xy 210.794866 17.684979) (xy 210.880249 17.692891)
			(xy 210.965999 17.692891) (xy 211.051382 17.684979) (xy 211.135672 17.669223) (xy 211.218148 17.645756)
			(xy 211.298107 17.61478) (xy 211.374867 17.576558) (xy 211.447773 17.531417) (xy 211.516202 17.479741)
			(xy 211.579572 17.421972) (xy 211.637341 17.358602) (xy 211.689017 17.290173) (xy 211.734158 17.217267)
			(xy 211.77238 17.140507) (xy 211.803356 17.060548) (xy 211.826823 16.978072) (xy 211.842579 16.893782)
			(xy 211.850491 16.808399) (xy 211.850986 16.765524) (xy 211.850491 16.722649) (xy 216.345757 16.722649)
			(xy 216.345757 16.808399) (xy 216.353669 16.893782) (xy 216.369425 16.978072) (xy 216.392892 17.060548)
			(xy 216.423868 17.140507) (xy 216.46209 17.217267) (xy 216.507231 17.290173) (xy 216.558907 17.358602)
			(xy 216.616676 17.421972) (xy 216.680046 17.479741) (xy 216.748475 17.531417) (xy 216.821381 17.576558)
			(xy 216.898141 17.61478) (xy 216.9781 17.645756) (xy 217.060576 17.669223) (xy 217.144866 17.684979)
			(xy 217.230249 17.692891) (xy 217.315999 17.692891) (xy 217.401382 17.684979) (xy 217.485672 17.669223)
			(xy 217.568148 17.645756) (xy 217.648107 17.61478) (xy 217.724867 17.576558) (xy 217.797773 17.531417)
			(xy 217.866202 17.479741) (xy 217.929572 17.421972) (xy 217.987341 17.358602) (xy 218.039017 17.290173)
			(xy 218.084158 17.217267) (xy 218.12238 17.140507) (xy 218.153356 17.060548) (xy 218.176823 16.978072)
			(xy 218.192579 16.893782) (xy 218.200491 16.808399) (xy 218.200986 16.765524) (xy 218.200491 16.722649)
			(xy 218.199832 16.715537) (xy 244.026677 16.715537) (xy 244.026677 16.801287) (xy 244.034589 16.88667)
			(xy 244.050345 16.97096) (xy 244.073812 17.053436) (xy 244.104788 17.133395) (xy 244.14301 17.210155)
			(xy 244.188151 17.283061) (xy 244.239827 17.35149) (xy 244.297596 17.41486) (xy 244.360966 17.472629)
			(xy 244.429395 17.524305) (xy 244.502301 17.569446) (xy 244.579061 17.607668) (xy 244.65902 17.638644)
			(xy 244.741496 17.662111) (xy 244.825786 17.677867) (xy 244.911169 17.685779) (xy 244.996919 17.685779)
			(xy 245.082302 17.677867) (xy 245.166592 17.662111) (xy 245.249068 17.638644) (xy 245.329027 17.607668)
			(xy 245.405787 17.569446) (xy 245.478693 17.524305) (xy 245.547122 17.472629) (xy 245.610492 17.41486)
			(xy 245.668261 17.35149) (xy 245.719937 17.283061) (xy 245.765078 17.210155) (xy 245.8033 17.133395)
			(xy 245.834276 17.053436) (xy 245.857743 16.97096) (xy 245.873499 16.88667) (xy 245.881411 16.801287)
			(xy 245.881906 16.758412) (xy 245.881411 16.715537) (xy 250.376677 16.715537) (xy 250.376677 16.801287)
			(xy 250.384589 16.88667) (xy 250.400345 16.97096) (xy 250.423812 17.053436) (xy 250.454788 17.133395)
			(xy 250.49301 17.210155) (xy 250.538151 17.283061) (xy 250.589827 17.35149) (xy 250.647596 17.41486)
			(xy 250.710966 17.472629) (xy 250.779395 17.524305) (xy 250.852301 17.569446) (xy 250.929061 17.607668)
			(xy 251.00902 17.638644) (xy 251.091496 17.662111) (xy 251.175786 17.677867) (xy 251.261169 17.685779)
			(xy 251.346919 17.685779) (xy 251.432302 17.677867) (xy 251.516592 17.662111) (xy 251.599068 17.638644)
			(xy 251.679027 17.607668) (xy 251.755787 17.569446) (xy 251.828693 17.524305) (xy 251.897122 17.472629)
			(xy 251.960492 17.41486) (xy 252.018261 17.35149) (xy 252.069937 17.283061) (xy 252.115078 17.210155)
			(xy 252.1533 17.133395) (xy 252.184276 17.053436) (xy 252.207743 16.97096) (xy 252.223499 16.88667)
			(xy 252.231411 16.801287) (xy 252.231906 16.758412) (xy 252.231493 16.722649) (xy 269.304757 16.722649)
			(xy 269.304757 16.808399) (xy 269.312669 16.893782) (xy 269.328425 16.978072) (xy 269.351892 17.060548)
			(xy 269.382868 17.140507) (xy 269.42109 17.217267) (xy 269.466231 17.290173) (xy 269.517907 17.358602)
			(xy 269.575676 17.421972) (xy 269.639046 17.479741) (xy 269.707475 17.531417) (xy 269.780381 17.576558)
			(xy 269.857141 17.61478) (xy 269.9371 17.645756) (xy 270.019576 17.669223) (xy 270.103866 17.684979)
			(xy 270.189249 17.692891) (xy 270.274999 17.692891) (xy 270.360382 17.684979) (xy 270.444672 17.669223)
			(xy 270.527148 17.645756) (xy 270.607107 17.61478) (xy 270.62931 17.603724) (xy 274.239736 17.603724)
			(xy 274.239736 18.467324) (xy 274.240222 18.494593) (xy 274.247984 18.548577) (xy 274.263349 18.600907)
			(xy 274.286006 18.650517) (xy 274.315492 18.696398) (xy 274.351207 18.737615) (xy 274.392424 18.77333)
			(xy 274.438305 18.802816) (xy 274.487915 18.825473) (xy 274.540245 18.840838) (xy 274.594229 18.8486)
			(xy 274.648767 18.8486) (xy 274.702751 18.840838) (xy 274.755081 18.825473) (xy 274.804691 18.802816)
			(xy 274.850572 18.77333) (xy 274.891789 18.737615) (xy 274.927504 18.696398) (xy 274.95699 18.650517)
			(xy 274.979647 18.600907) (xy 274.995012 18.548577) (xy 275.002774 18.494593) (xy 275.00326 18.467324)
			(xy 275.00326 17.603724) (xy 275.002774 17.576455) (xy 274.995012 17.522471) (xy 274.979647 17.470141)
			(xy 274.95699 17.420531) (xy 274.927504 17.37465) (xy 274.891789 17.333433) (xy 274.850572 17.297718)
			(xy 274.804691 17.268232) (xy 274.755081 17.245575) (xy 274.702751 17.23021) (xy 274.648767 17.222448)
			(xy 274.594229 17.222448) (xy 274.540245 17.23021) (xy 274.487915 17.245575) (xy 274.438305 17.268232)
			(xy 274.392424 17.297718) (xy 274.351207 17.333433) (xy 274.315492 17.37465) (xy 274.286006 17.420531)
			(xy 274.263349 17.470141) (xy 274.247984 17.522471) (xy 274.240222 17.576455) (xy 274.239736 17.603724)
			(xy 270.62931 17.603724) (xy 270.683867 17.576558) (xy 270.756773 17.531417) (xy 270.825202 17.479741)
			(xy 270.888572 17.421972) (xy 270.946341 17.358602) (xy 270.998017 17.290173) (xy 271.043158 17.217267)
			(xy 271.08138 17.140507) (xy 271.112356 17.060548) (xy 271.135823 16.978072) (xy 271.151579 16.893782)
			(xy 271.159491 16.808399) (xy 271.159986 16.765524) (xy 271.159491 16.722649) (xy 275.654757 16.722649)
			(xy 275.654757 16.808399) (xy 275.662669 16.893782) (xy 275.678425 16.978072) (xy 275.701892 17.060548)
			(xy 275.732868 17.140507) (xy 275.77109 17.217267) (xy 275.816231 17.290173) (xy 275.867907 17.358602)
			(xy 275.925676 17.421972) (xy 275.989046 17.479741) (xy 276.057475 17.531417) (xy 276.130381 17.576558)
			(xy 276.207141 17.61478) (xy 276.2871 17.645756) (xy 276.369576 17.669223) (xy 276.453866 17.684979)
			(xy 276.539249 17.692891) (xy 276.624999 17.692891) (xy 276.710382 17.684979) (xy 276.794672 17.669223)
			(xy 276.877148 17.645756) (xy 276.957107 17.61478) (xy 277.033867 17.576558) (xy 277.106773 17.531417)
			(xy 277.175202 17.479741) (xy 277.238572 17.421972) (xy 277.296341 17.358602) (xy 277.348017 17.290173)
			(xy 277.393158 17.217267) (xy 277.43138 17.140507) (xy 277.462356 17.060548) (xy 277.485823 16.978072)
			(xy 277.501579 16.893782) (xy 277.509491 16.808399) (xy 277.509986 16.765524) (xy 277.509491 16.722649)
			(xy 277.508832 16.715537) (xy 308.364877 16.715537) (xy 308.364877 16.801287) (xy 308.372789 16.88667)
			(xy 308.388545 16.97096) (xy 308.412012 17.053436) (xy 308.442988 17.133395) (xy 308.48121 17.210155)
			(xy 308.526351 17.283061) (xy 308.578027 17.35149) (xy 308.635796 17.41486) (xy 308.699166 17.472629)
			(xy 308.767595 17.524305) (xy 308.840501 17.569446) (xy 308.917261 17.607668) (xy 308.99722 17.638644)
			(xy 309.079696 17.662111) (xy 309.163986 17.677867) (xy 309.249369 17.685779) (xy 309.335119 17.685779)
			(xy 309.420502 17.677867) (xy 309.504792 17.662111) (xy 309.587268 17.638644) (xy 309.667227 17.607668)
			(xy 309.68943 17.596612) (xy 310.871108 17.596612) (xy 310.871108 18.460212) (xy 310.871594 18.487481)
			(xy 310.879356 18.541465) (xy 310.894721 18.593795) (xy 310.917378 18.643405) (xy 310.946864 18.689286)
			(xy 310.982579 18.730503) (xy 311.023796 18.766218) (xy 311.069677 18.795704) (xy 311.119287 18.818361)
			(xy 311.171617 18.833726) (xy 311.225601 18.841488) (xy 311.280139 18.841488) (xy 311.334123 18.833726)
			(xy 311.386453 18.818361) (xy 311.436063 18.795704) (xy 311.481944 18.766218) (xy 311.523161 18.730503)
			(xy 311.558876 18.689286) (xy 311.588362 18.643405) (xy 311.611019 18.593795) (xy 311.626384 18.541465)
			(xy 311.634146 18.487481) (xy 311.634632 18.460212) (xy 311.634632 17.596612) (xy 311.634146 17.569343)
			(xy 311.626384 17.515359) (xy 311.611019 17.463029) (xy 311.588362 17.413419) (xy 311.558876 17.367538)
			(xy 311.523161 17.326321) (xy 311.481944 17.290606) (xy 311.436063 17.26112) (xy 311.386453 17.238463)
			(xy 311.334123 17.223098) (xy 311.280139 17.215336) (xy 311.225601 17.215336) (xy 311.171617 17.223098)
			(xy 311.119287 17.238463) (xy 311.069677 17.26112) (xy 311.023796 17.290606) (xy 310.982579 17.326321)
			(xy 310.946864 17.367538) (xy 310.917378 17.413419) (xy 310.894721 17.463029) (xy 310.879356 17.515359)
			(xy 310.871594 17.569343) (xy 310.871108 17.596612) (xy 309.68943 17.596612) (xy 309.743987 17.569446)
			(xy 309.816893 17.524305) (xy 309.885322 17.472629) (xy 309.948692 17.41486) (xy 310.006461 17.35149)
			(xy 310.058137 17.283061) (xy 310.103278 17.210155) (xy 310.1415 17.133395) (xy 310.172476 17.053436)
			(xy 310.195943 16.97096) (xy 310.211699 16.88667) (xy 310.219611 16.801287) (xy 310.220106 16.758412)
			(xy 310.219611 16.715537) (xy 314.714877 16.715537) (xy 314.714877 16.801287) (xy 314.722789 16.88667)
			(xy 314.738545 16.97096) (xy 314.762012 17.053436) (xy 314.792988 17.133395) (xy 314.83121 17.210155)
			(xy 314.876351 17.283061) (xy 314.928027 17.35149) (xy 314.985796 17.41486) (xy 315.049166 17.472629)
			(xy 315.117595 17.524305) (xy 315.190501 17.569446) (xy 315.267261 17.607668) (xy 315.34722 17.638644)
			(xy 315.429696 17.662111) (xy 315.513986 17.677867) (xy 315.599369 17.685779) (xy 315.685119 17.685779)
			(xy 315.770502 17.677867) (xy 315.854792 17.662111) (xy 315.937268 17.638644) (xy 316.017227 17.607668)
			(xy 316.093987 17.569446) (xy 316.166893 17.524305) (xy 316.235322 17.472629) (xy 316.298692 17.41486)
			(xy 316.356461 17.35149) (xy 316.408137 17.283061) (xy 316.453278 17.210155) (xy 316.4915 17.133395)
			(xy 316.522476 17.053436) (xy 316.545943 16.97096) (xy 316.561699 16.88667) (xy 316.569611 16.801287)
			(xy 316.570106 16.758412) (xy 316.569693 16.722649) (xy 334.455757 16.722649) (xy 334.455757 16.808399)
			(xy 334.463669 16.893782) (xy 334.479425 16.978072) (xy 334.502892 17.060548) (xy 334.533868 17.140507)
			(xy 334.57209 17.217267) (xy 334.617231 17.290173) (xy 334.668907 17.358602) (xy 334.726676 17.421972)
			(xy 334.790046 17.479741) (xy 334.858475 17.531417) (xy 334.931381 17.576558) (xy 335.008141 17.61478)
			(xy 335.0881 17.645756) (xy 335.170576 17.669223) (xy 335.254866 17.684979) (xy 335.340249 17.692891)
			(xy 335.425999 17.692891) (xy 335.511382 17.684979) (xy 335.595672 17.669223) (xy 335.678148 17.645756)
			(xy 335.758107 17.61478) (xy 335.78031 17.603724) (xy 339.390736 17.603724) (xy 339.390736 18.467324)
			(xy 339.391222 18.494593) (xy 339.398984 18.548577) (xy 339.414349 18.600907) (xy 339.437006 18.650517)
			(xy 339.466492 18.696398) (xy 339.502207 18.737615) (xy 339.543424 18.77333) (xy 339.589305 18.802816)
			(xy 339.638915 18.825473) (xy 339.691245 18.840838) (xy 339.745229 18.8486) (xy 339.799767 18.8486)
			(xy 339.853751 18.840838) (xy 339.906081 18.825473) (xy 339.955691 18.802816) (xy 340.001572 18.77333)
			(xy 340.042789 18.737615) (xy 340.078504 18.696398) (xy 340.10799 18.650517) (xy 340.130647 18.600907)
			(xy 340.146012 18.548577) (xy 340.153774 18.494593) (xy 340.15426 18.467324) (xy 340.15426 17.603724)
			(xy 340.153774 17.576455) (xy 340.146012 17.522471) (xy 340.130647 17.470141) (xy 340.10799 17.420531)
			(xy 340.078504 17.37465) (xy 340.042789 17.333433) (xy 340.001572 17.297718) (xy 339.955691 17.268232)
			(xy 339.906081 17.245575) (xy 339.853751 17.23021) (xy 339.799767 17.222448) (xy 339.745229 17.222448)
			(xy 339.691245 17.23021) (xy 339.638915 17.245575) (xy 339.589305 17.268232) (xy 339.543424 17.297718)
			(xy 339.502207 17.333433) (xy 339.466492 17.37465) (xy 339.437006 17.420531) (xy 339.414349 17.470141)
			(xy 339.398984 17.522471) (xy 339.391222 17.576455) (xy 339.390736 17.603724) (xy 335.78031 17.603724)
			(xy 335.834867 17.576558) (xy 335.907773 17.531417) (xy 335.976202 17.479741) (xy 336.039572 17.421972)
			(xy 336.097341 17.358602) (xy 336.149017 17.290173) (xy 336.194158 17.217267) (xy 336.23238 17.140507)
			(xy 336.263356 17.060548) (xy 336.286823 16.978072) (xy 336.302579 16.893782) (xy 336.310491 16.808399)
			(xy 336.310986 16.765524) (xy 336.310491 16.722649) (xy 340.805757 16.722649) (xy 340.805757 16.808399)
			(xy 340.813669 16.893782) (xy 340.829425 16.978072) (xy 340.852892 17.060548) (xy 340.883868 17.140507)
			(xy 340.92209 17.217267) (xy 340.967231 17.290173) (xy 341.018907 17.358602) (xy 341.076676 17.421972)
			(xy 341.140046 17.479741) (xy 341.208475 17.531417) (xy 341.281381 17.576558) (xy 341.358141 17.61478)
			(xy 341.4381 17.645756) (xy 341.520576 17.669223) (xy 341.604866 17.684979) (xy 341.690249 17.692891)
			(xy 341.775999 17.692891) (xy 341.861382 17.684979) (xy 341.945672 17.669223) (xy 342.028148 17.645756)
			(xy 342.108107 17.61478) (xy 342.184867 17.576558) (xy 342.257773 17.531417) (xy 342.326202 17.479741)
			(xy 342.389572 17.421972) (xy 342.447341 17.358602) (xy 342.499017 17.290173) (xy 342.544158 17.217267)
			(xy 342.58238 17.140507) (xy 342.613356 17.060548) (xy 342.636823 16.978072) (xy 342.652579 16.893782)
			(xy 342.660491 16.808399) (xy 342.660986 16.765524) (xy 342.660491 16.722649) (xy 342.659832 16.715537)
			(xy 373.515877 16.715537) (xy 373.515877 16.801287) (xy 373.523789 16.88667) (xy 373.539545 16.97096)
			(xy 373.563012 17.053436) (xy 373.593988 17.133395) (xy 373.63221 17.210155) (xy 373.677351 17.283061)
			(xy 373.729027 17.35149) (xy 373.786796 17.41486) (xy 373.850166 17.472629) (xy 373.918595 17.524305)
			(xy 373.991501 17.569446) (xy 374.068261 17.607668) (xy 374.14822 17.638644) (xy 374.230696 17.662111)
			(xy 374.314986 17.677867) (xy 374.400369 17.685779) (xy 374.486119 17.685779) (xy 374.571502 17.677867)
			(xy 374.655792 17.662111) (xy 374.738268 17.638644) (xy 374.818227 17.607668) (xy 374.84043 17.596612)
			(xy 376.022108 17.596612) (xy 376.022108 18.460212) (xy 376.022594 18.487481) (xy 376.030356 18.541465)
			(xy 376.045721 18.593795) (xy 376.068378 18.643405) (xy 376.097864 18.689286) (xy 376.133579 18.730503)
			(xy 376.174796 18.766218) (xy 376.220677 18.795704) (xy 376.270287 18.818361) (xy 376.322617 18.833726)
			(xy 376.376601 18.841488) (xy 376.431139 18.841488) (xy 376.485123 18.833726) (xy 376.537453 18.818361)
			(xy 376.587063 18.795704) (xy 376.632944 18.766218) (xy 376.674161 18.730503) (xy 376.709876 18.689286)
			(xy 376.739362 18.643405) (xy 376.762019 18.593795) (xy 376.777384 18.541465) (xy 376.785146 18.487481)
			(xy 376.785632 18.460212) (xy 376.785632 17.596612) (xy 376.785146 17.569343) (xy 376.777384 17.515359)
			(xy 376.762019 17.463029) (xy 376.739362 17.413419) (xy 376.709876 17.367538) (xy 376.674161 17.326321)
			(xy 376.632944 17.290606) (xy 376.587063 17.26112) (xy 376.537453 17.238463) (xy 376.485123 17.223098)
			(xy 376.431139 17.215336) (xy 376.376601 17.215336) (xy 376.322617 17.223098) (xy 376.270287 17.238463)
			(xy 376.220677 17.26112) (xy 376.174796 17.290606) (xy 376.133579 17.326321) (xy 376.097864 17.367538)
			(xy 376.068378 17.413419) (xy 376.045721 17.463029) (xy 376.030356 17.515359) (xy 376.022594 17.569343)
			(xy 376.022108 17.596612) (xy 374.84043 17.596612) (xy 374.894987 17.569446) (xy 374.967893 17.524305)
			(xy 375.036322 17.472629) (xy 375.099692 17.41486) (xy 375.157461 17.35149) (xy 375.209137 17.283061)
			(xy 375.254278 17.210155) (xy 375.2925 17.133395) (xy 375.323476 17.053436) (xy 375.346943 16.97096)
			(xy 375.362699 16.88667) (xy 375.370611 16.801287) (xy 375.371106 16.758412) (xy 375.370611 16.715537)
			(xy 379.865877 16.715537) (xy 379.865877 16.801287) (xy 379.873789 16.88667) (xy 379.889545 16.97096)
			(xy 379.913012 17.053436) (xy 379.943988 17.133395) (xy 379.98221 17.210155) (xy 380.027351 17.283061)
			(xy 380.079027 17.35149) (xy 380.136796 17.41486) (xy 380.200166 17.472629) (xy 380.268595 17.524305)
			(xy 380.341501 17.569446) (xy 380.418261 17.607668) (xy 380.49822 17.638644) (xy 380.580696 17.662111)
			(xy 380.664986 17.677867) (xy 380.750369 17.685779) (xy 380.836119 17.685779) (xy 380.921502 17.677867)
			(xy 381.005792 17.662111) (xy 381.088268 17.638644) (xy 381.168227 17.607668) (xy 381.244987 17.569446)
			(xy 381.317893 17.524305) (xy 381.386322 17.472629) (xy 381.449692 17.41486) (xy 381.507461 17.35149)
			(xy 381.559137 17.283061) (xy 381.604278 17.210155) (xy 381.6425 17.133395) (xy 381.673476 17.053436)
			(xy 381.696943 16.97096) (xy 381.712699 16.88667) (xy 381.720611 16.801287) (xy 381.721106 16.758412)
			(xy 381.720693 16.722649) (xy 399.098757 16.722649) (xy 399.098757 16.808399) (xy 399.106669 16.893782)
			(xy 399.122425 16.978072) (xy 399.145892 17.060548) (xy 399.176868 17.140507) (xy 399.21509 17.217267)
			(xy 399.260231 17.290173) (xy 399.311907 17.358602) (xy 399.369676 17.421972) (xy 399.433046 17.479741)
			(xy 399.501475 17.531417) (xy 399.574381 17.576558) (xy 399.651141 17.61478) (xy 399.7311 17.645756)
			(xy 399.813576 17.669223) (xy 399.897866 17.684979) (xy 399.983249 17.692891) (xy 400.068999 17.692891)
			(xy 400.154382 17.684979) (xy 400.238672 17.669223) (xy 400.321148 17.645756) (xy 400.401107 17.61478)
			(xy 400.42331 17.603724) (xy 404.033736 17.603724) (xy 404.033736 18.467324) (xy 404.034222 18.494593)
			(xy 404.041984 18.548577) (xy 404.057349 18.600907) (xy 404.080006 18.650517) (xy 404.109492 18.696398)
			(xy 404.145207 18.737615) (xy 404.186424 18.77333) (xy 404.232305 18.802816) (xy 404.281915 18.825473)
			(xy 404.334245 18.840838) (xy 404.388229 18.8486) (xy 404.442767 18.8486) (xy 404.496751 18.840838)
			(xy 404.549081 18.825473) (xy 404.598691 18.802816) (xy 404.644572 18.77333) (xy 404.685789 18.737615)
			(xy 404.721504 18.696398) (xy 404.75099 18.650517) (xy 404.773647 18.600907) (xy 404.789012 18.548577)
			(xy 404.796774 18.494593) (xy 404.79726 18.467324) (xy 404.79726 17.603724) (xy 404.796774 17.576455)
			(xy 404.789012 17.522471) (xy 404.773647 17.470141) (xy 404.75099 17.420531) (xy 404.721504 17.37465)
			(xy 404.685789 17.333433) (xy 404.644572 17.297718) (xy 404.598691 17.268232) (xy 404.549081 17.245575)
			(xy 404.496751 17.23021) (xy 404.442767 17.222448) (xy 404.388229 17.222448) (xy 404.334245 17.23021)
			(xy 404.281915 17.245575) (xy 404.232305 17.268232) (xy 404.186424 17.297718) (xy 404.145207 17.333433)
			(xy 404.109492 17.37465) (xy 404.080006 17.420531) (xy 404.057349 17.470141) (xy 404.041984 17.522471)
			(xy 404.034222 17.576455) (xy 404.033736 17.603724) (xy 400.42331 17.603724) (xy 400.477867 17.576558)
			(xy 400.550773 17.531417) (xy 400.619202 17.479741) (xy 400.682572 17.421972) (xy 400.740341 17.358602)
			(xy 400.792017 17.290173) (xy 400.837158 17.217267) (xy 400.87538 17.140507) (xy 400.906356 17.060548)
			(xy 400.929823 16.978072) (xy 400.945579 16.893782) (xy 400.953491 16.808399) (xy 400.953986 16.765524)
			(xy 400.953491 16.722649) (xy 405.448757 16.722649) (xy 405.448757 16.808399) (xy 405.456669 16.893782)
			(xy 405.472425 16.978072) (xy 405.495892 17.060548) (xy 405.526868 17.140507) (xy 405.56509 17.217267)
			(xy 405.610231 17.290173) (xy 405.661907 17.358602) (xy 405.719676 17.421972) (xy 405.783046 17.479741)
			(xy 405.851475 17.531417) (xy 405.924381 17.576558) (xy 406.001141 17.61478) (xy 406.0811 17.645756)
			(xy 406.163576 17.669223) (xy 406.247866 17.684979) (xy 406.333249 17.692891) (xy 406.418999 17.692891)
			(xy 406.504382 17.684979) (xy 406.588672 17.669223) (xy 406.671148 17.645756) (xy 406.751107 17.61478)
			(xy 406.827867 17.576558) (xy 406.900773 17.531417) (xy 406.969202 17.479741) (xy 407.032572 17.421972)
			(xy 407.090341 17.358602) (xy 407.142017 17.290173) (xy 407.187158 17.217267) (xy 407.22538 17.140507)
			(xy 407.256356 17.060548) (xy 407.279823 16.978072) (xy 407.295579 16.893782) (xy 407.303491 16.808399)
			(xy 407.303986 16.765524) (xy 407.303491 16.722649) (xy 407.302832 16.715537) (xy 438.158877 16.715537)
			(xy 438.158877 16.801287) (xy 438.166789 16.88667) (xy 438.182545 16.97096) (xy 438.206012 17.053436)
			(xy 438.236988 17.133395) (xy 438.27521 17.210155) (xy 438.320351 17.283061) (xy 438.372027 17.35149)
			(xy 438.429796 17.41486) (xy 438.493166 17.472629) (xy 438.561595 17.524305) (xy 438.634501 17.569446)
			(xy 438.711261 17.607668) (xy 438.79122 17.638644) (xy 438.873696 17.662111) (xy 438.957986 17.677867)
			(xy 439.043369 17.685779) (xy 439.129119 17.685779) (xy 439.214502 17.677867) (xy 439.298792 17.662111)
			(xy 439.381268 17.638644) (xy 439.461227 17.607668) (xy 439.48343 17.596612) (xy 440.665108 17.596612)
			(xy 440.665108 18.460212) (xy 440.665594 18.487481) (xy 440.673356 18.541465) (xy 440.688721 18.593795)
			(xy 440.711378 18.643405) (xy 440.740864 18.689286) (xy 440.776579 18.730503) (xy 440.817796 18.766218)
			(xy 440.863677 18.795704) (xy 440.913287 18.818361) (xy 440.965617 18.833726) (xy 441.019601 18.841488)
			(xy 441.074139 18.841488) (xy 441.128123 18.833726) (xy 441.180453 18.818361) (xy 441.230063 18.795704)
			(xy 441.275944 18.766218) (xy 441.317161 18.730503) (xy 441.352876 18.689286) (xy 441.382362 18.643405)
			(xy 441.405019 18.593795) (xy 441.420384 18.541465) (xy 441.428146 18.487481) (xy 441.428632 18.460212)
			(xy 441.428632 17.596612) (xy 441.428146 17.569343) (xy 441.420384 17.515359) (xy 441.405019 17.463029)
			(xy 441.382362 17.413419) (xy 441.352876 17.367538) (xy 441.317161 17.326321) (xy 441.275944 17.290606)
			(xy 441.230063 17.26112) (xy 441.180453 17.238463) (xy 441.128123 17.223098) (xy 441.074139 17.215336)
			(xy 441.019601 17.215336) (xy 440.965617 17.223098) (xy 440.913287 17.238463) (xy 440.863677 17.26112)
			(xy 440.817796 17.290606) (xy 440.776579 17.326321) (xy 440.740864 17.367538) (xy 440.711378 17.413419)
			(xy 440.688721 17.463029) (xy 440.673356 17.515359) (xy 440.665594 17.569343) (xy 440.665108 17.596612)
			(xy 439.48343 17.596612) (xy 439.537987 17.569446) (xy 439.610893 17.524305) (xy 439.679322 17.472629)
			(xy 439.742692 17.41486) (xy 439.800461 17.35149) (xy 439.852137 17.283061) (xy 439.897278 17.210155)
			(xy 439.9355 17.133395) (xy 439.966476 17.053436) (xy 439.989943 16.97096) (xy 440.005699 16.88667)
			(xy 440.013611 16.801287) (xy 440.014106 16.758412) (xy 440.013611 16.715537) (xy 444.508877 16.715537)
			(xy 444.508877 16.801287) (xy 444.516789 16.88667) (xy 444.532545 16.97096) (xy 444.556012 17.053436)
			(xy 444.586988 17.133395) (xy 444.62521 17.210155) (xy 444.670351 17.283061) (xy 444.722027 17.35149)
			(xy 444.779796 17.41486) (xy 444.843166 17.472629) (xy 444.911595 17.524305) (xy 444.984501 17.569446)
			(xy 445.061261 17.607668) (xy 445.14122 17.638644) (xy 445.223696 17.662111) (xy 445.307986 17.677867)
			(xy 445.393369 17.685779) (xy 445.479119 17.685779) (xy 445.564502 17.677867) (xy 445.648792 17.662111)
			(xy 445.731268 17.638644) (xy 445.811227 17.607668) (xy 445.887987 17.569446) (xy 445.960893 17.524305)
			(xy 446.029322 17.472629) (xy 446.092692 17.41486) (xy 446.150461 17.35149) (xy 446.202137 17.283061)
			(xy 446.247278 17.210155) (xy 446.2855 17.133395) (xy 446.316476 17.053436) (xy 446.339943 16.97096)
			(xy 446.355699 16.88667) (xy 446.363611 16.801287) (xy 446.364106 16.758412) (xy 446.363611 16.715537)
			(xy 446.355699 16.630154) (xy 446.339943 16.545864) (xy 446.316476 16.463388) (xy 446.2855 16.383429)
			(xy 446.247278 16.306669) (xy 446.202137 16.233763) (xy 446.150461 16.165334) (xy 446.092692 16.101964)
			(xy 446.029322 16.044195) (xy 445.960893 15.992519) (xy 445.887987 15.947378) (xy 445.811227 15.909156)
			(xy 445.731268 15.87818) (xy 445.648792 15.854713) (xy 445.564502 15.838957) (xy 445.479119 15.831045)
			(xy 445.393369 15.831045) (xy 445.307986 15.838957) (xy 445.223696 15.854713) (xy 445.14122 15.87818)
			(xy 445.061261 15.909156) (xy 444.984501 15.947378) (xy 444.911595 15.992519) (xy 444.843166 16.044195)
			(xy 444.779796 16.101964) (xy 444.722027 16.165334) (xy 444.670351 16.233763) (xy 444.62521 16.306669)
			(xy 444.586988 16.383429) (xy 444.556012 16.463388) (xy 444.532545 16.545864) (xy 444.516789 16.630154)
			(xy 444.508877 16.715537) (xy 440.013611 16.715537) (xy 440.005699 16.630154) (xy 439.989943 16.545864)
			(xy 439.966476 16.463388) (xy 439.9355 16.383429) (xy 439.897278 16.306669) (xy 439.852137 16.233763)
			(xy 439.800461 16.165334) (xy 439.742692 16.101964) (xy 439.679322 16.044195) (xy 439.610893 15.992519)
			(xy 439.537987 15.947378) (xy 439.461227 15.909156) (xy 439.381268 15.87818) (xy 439.298792 15.854713)
			(xy 439.214502 15.838957) (xy 439.129119 15.831045) (xy 439.043369 15.831045) (xy 438.957986 15.838957)
			(xy 438.873696 15.854713) (xy 438.79122 15.87818) (xy 438.711261 15.909156) (xy 438.634501 15.947378)
			(xy 438.561595 15.992519) (xy 438.493166 16.044195) (xy 438.429796 16.101964) (xy 438.372027 16.165334)
			(xy 438.320351 16.233763) (xy 438.27521 16.306669) (xy 438.236988 16.383429) (xy 438.206012 16.463388)
			(xy 438.182545 16.545864) (xy 438.166789 16.630154) (xy 438.158877 16.715537) (xy 407.302832 16.715537)
			(xy 407.295579 16.637266) (xy 407.279823 16.552976) (xy 407.256356 16.4705) (xy 407.22538 16.390541)
			(xy 407.187158 16.313781) (xy 407.142017 16.240875) (xy 407.090341 16.172446) (xy 407.032572 16.109076)
			(xy 406.969202 16.051307) (xy 406.900773 15.999631) (xy 406.827867 15.95449) (xy 406.751107 15.916268)
			(xy 406.671148 15.885292) (xy 406.588672 15.861825) (xy 406.504382 15.846069) (xy 406.418999 15.838157)
			(xy 406.333249 15.838157) (xy 406.247866 15.846069) (xy 406.163576 15.861825) (xy 406.0811 15.885292)
			(xy 406.001141 15.916268) (xy 405.924381 15.95449) (xy 405.851475 15.999631) (xy 405.783046 16.051307)
			(xy 405.719676 16.109076) (xy 405.661907 16.172446) (xy 405.610231 16.240875) (xy 405.56509 16.313781)
			(xy 405.526868 16.390541) (xy 405.495892 16.4705) (xy 405.472425 16.552976) (xy 405.456669 16.637266)
			(xy 405.448757 16.722649) (xy 400.953491 16.722649) (xy 400.945579 16.637266) (xy 400.929823 16.552976)
			(xy 400.906356 16.4705) (xy 400.87538 16.390541) (xy 400.837158 16.313781) (xy 400.792017 16.240875)
			(xy 400.740341 16.172446) (xy 400.682572 16.109076) (xy 400.619202 16.051307) (xy 400.550773 15.999631)
			(xy 400.477867 15.95449) (xy 400.401107 15.916268) (xy 400.321148 15.885292) (xy 400.238672 15.861825)
			(xy 400.154382 15.846069) (xy 400.068999 15.838157) (xy 399.983249 15.838157) (xy 399.897866 15.846069)
			(xy 399.813576 15.861825) (xy 399.7311 15.885292) (xy 399.651141 15.916268) (xy 399.574381 15.95449)
			(xy 399.501475 15.999631) (xy 399.433046 16.051307) (xy 399.369676 16.109076) (xy 399.311907 16.172446)
			(xy 399.260231 16.240875) (xy 399.21509 16.313781) (xy 399.176868 16.390541) (xy 399.145892 16.4705)
			(xy 399.122425 16.552976) (xy 399.106669 16.637266) (xy 399.098757 16.722649) (xy 381.720693 16.722649)
			(xy 381.720611 16.715537) (xy 381.712699 16.630154) (xy 381.696943 16.545864) (xy 381.673476 16.463388)
			(xy 381.6425 16.383429) (xy 381.604278 16.306669) (xy 381.559137 16.233763) (xy 381.507461 16.165334)
			(xy 381.449692 16.101964) (xy 381.386322 16.044195) (xy 381.317893 15.992519) (xy 381.244987 15.947378)
			(xy 381.168227 15.909156) (xy 381.088268 15.87818) (xy 381.005792 15.854713) (xy 380.921502 15.838957)
			(xy 380.836119 15.831045) (xy 380.750369 15.831045) (xy 380.664986 15.838957) (xy 380.580696 15.854713)
			(xy 380.49822 15.87818) (xy 380.418261 15.909156) (xy 380.341501 15.947378) (xy 380.268595 15.992519)
			(xy 380.200166 16.044195) (xy 380.136796 16.101964) (xy 380.079027 16.165334) (xy 380.027351 16.233763)
			(xy 379.98221 16.306669) (xy 379.943988 16.383429) (xy 379.913012 16.463388) (xy 379.889545 16.545864)
			(xy 379.873789 16.630154) (xy 379.865877 16.715537) (xy 375.370611 16.715537) (xy 375.362699 16.630154)
			(xy 375.346943 16.545864) (xy 375.323476 16.463388) (xy 375.2925 16.383429) (xy 375.254278 16.306669)
			(xy 375.209137 16.233763) (xy 375.157461 16.165334) (xy 375.099692 16.101964) (xy 375.036322 16.044195)
			(xy 374.967893 15.992519) (xy 374.894987 15.947378) (xy 374.818227 15.909156) (xy 374.738268 15.87818)
			(xy 374.655792 15.854713) (xy 374.571502 15.838957) (xy 374.486119 15.831045) (xy 374.400369 15.831045)
			(xy 374.314986 15.838957) (xy 374.230696 15.854713) (xy 374.14822 15.87818) (xy 374.068261 15.909156)
			(xy 373.991501 15.947378) (xy 373.918595 15.992519) (xy 373.850166 16.044195) (xy 373.786796 16.101964)
			(xy 373.729027 16.165334) (xy 373.677351 16.233763) (xy 373.63221 16.306669) (xy 373.593988 16.383429)
			(xy 373.563012 16.463388) (xy 373.539545 16.545864) (xy 373.523789 16.630154) (xy 373.515877 16.715537)
			(xy 342.659832 16.715537) (xy 342.652579 16.637266) (xy 342.636823 16.552976) (xy 342.613356 16.4705)
			(xy 342.58238 16.390541) (xy 342.544158 16.313781) (xy 342.499017 16.240875) (xy 342.447341 16.172446)
			(xy 342.389572 16.109076) (xy 342.326202 16.051307) (xy 342.257773 15.999631) (xy 342.184867 15.95449)
			(xy 342.108107 15.916268) (xy 342.028148 15.885292) (xy 341.945672 15.861825) (xy 341.861382 15.846069)
			(xy 341.775999 15.838157) (xy 341.690249 15.838157) (xy 341.604866 15.846069) (xy 341.520576 15.861825)
			(xy 341.4381 15.885292) (xy 341.358141 15.916268) (xy 341.281381 15.95449) (xy 341.208475 15.999631)
			(xy 341.140046 16.051307) (xy 341.076676 16.109076) (xy 341.018907 16.172446) (xy 340.967231 16.240875)
			(xy 340.92209 16.313781) (xy 340.883868 16.390541) (xy 340.852892 16.4705) (xy 340.829425 16.552976)
			(xy 340.813669 16.637266) (xy 340.805757 16.722649) (xy 336.310491 16.722649) (xy 336.302579 16.637266)
			(xy 336.286823 16.552976) (xy 336.263356 16.4705) (xy 336.23238 16.390541) (xy 336.194158 16.313781)
			(xy 336.149017 16.240875) (xy 336.097341 16.172446) (xy 336.039572 16.109076) (xy 335.976202 16.051307)
			(xy 335.907773 15.999631) (xy 335.834867 15.95449) (xy 335.758107 15.916268) (xy 335.678148 15.885292)
			(xy 335.595672 15.861825) (xy 335.511382 15.846069) (xy 335.425999 15.838157) (xy 335.340249 15.838157)
			(xy 335.254866 15.846069) (xy 335.170576 15.861825) (xy 335.0881 15.885292) (xy 335.008141 15.916268)
			(xy 334.931381 15.95449) (xy 334.858475 15.999631) (xy 334.790046 16.051307) (xy 334.726676 16.109076)
			(xy 334.668907 16.172446) (xy 334.617231 16.240875) (xy 334.57209 16.313781) (xy 334.533868 16.390541)
			(xy 334.502892 16.4705) (xy 334.479425 16.552976) (xy 334.463669 16.637266) (xy 334.455757 16.722649)
			(xy 316.569693 16.722649) (xy 316.569611 16.715537) (xy 316.561699 16.630154) (xy 316.545943 16.545864)
			(xy 316.522476 16.463388) (xy 316.4915 16.383429) (xy 316.453278 16.306669) (xy 316.408137 16.233763)
			(xy 316.356461 16.165334) (xy 316.298692 16.101964) (xy 316.235322 16.044195) (xy 316.166893 15.992519)
			(xy 316.093987 15.947378) (xy 316.017227 15.909156) (xy 315.937268 15.87818) (xy 315.854792 15.854713)
			(xy 315.770502 15.838957) (xy 315.685119 15.831045) (xy 315.599369 15.831045) (xy 315.513986 15.838957)
			(xy 315.429696 15.854713) (xy 315.34722 15.87818) (xy 315.267261 15.909156) (xy 315.190501 15.947378)
			(xy 315.117595 15.992519) (xy 315.049166 16.044195) (xy 314.985796 16.101964) (xy 314.928027 16.165334)
			(xy 314.876351 16.233763) (xy 314.83121 16.306669) (xy 314.792988 16.383429) (xy 314.762012 16.463388)
			(xy 314.738545 16.545864) (xy 314.722789 16.630154) (xy 314.714877 16.715537) (xy 310.219611 16.715537)
			(xy 310.211699 16.630154) (xy 310.195943 16.545864) (xy 310.172476 16.463388) (xy 310.1415 16.383429)
			(xy 310.103278 16.306669) (xy 310.058137 16.233763) (xy 310.006461 16.165334) (xy 309.948692 16.101964)
			(xy 309.885322 16.044195) (xy 309.816893 15.992519) (xy 309.743987 15.947378) (xy 309.667227 15.909156)
			(xy 309.587268 15.87818) (xy 309.504792 15.854713) (xy 309.420502 15.838957) (xy 309.335119 15.831045)
			(xy 309.249369 15.831045) (xy 309.163986 15.838957) (xy 309.079696 15.854713) (xy 308.99722 15.87818)
			(xy 308.917261 15.909156) (xy 308.840501 15.947378) (xy 308.767595 15.992519) (xy 308.699166 16.044195)
			(xy 308.635796 16.101964) (xy 308.578027 16.165334) (xy 308.526351 16.233763) (xy 308.48121 16.306669)
			(xy 308.442988 16.383429) (xy 308.412012 16.463388) (xy 308.388545 16.545864) (xy 308.372789 16.630154)
			(xy 308.364877 16.715537) (xy 277.508832 16.715537) (xy 277.501579 16.637266) (xy 277.485823 16.552976)
			(xy 277.462356 16.4705) (xy 277.43138 16.390541) (xy 277.393158 16.313781) (xy 277.348017 16.240875)
			(xy 277.296341 16.172446) (xy 277.238572 16.109076) (xy 277.175202 16.051307) (xy 277.106773 15.999631)
			(xy 277.033867 15.95449) (xy 276.957107 15.916268) (xy 276.877148 15.885292) (xy 276.794672 15.861825)
			(xy 276.710382 15.846069) (xy 276.624999 15.838157) (xy 276.539249 15.838157) (xy 276.453866 15.846069)
			(xy 276.369576 15.861825) (xy 276.2871 15.885292) (xy 276.207141 15.916268) (xy 276.130381 15.95449)
			(xy 276.057475 15.999631) (xy 275.989046 16.051307) (xy 275.925676 16.109076) (xy 275.867907 16.172446)
			(xy 275.816231 16.240875) (xy 275.77109 16.313781) (xy 275.732868 16.390541) (xy 275.701892 16.4705)
			(xy 275.678425 16.552976) (xy 275.662669 16.637266) (xy 275.654757 16.722649) (xy 271.159491 16.722649)
			(xy 271.151579 16.637266) (xy 271.135823 16.552976) (xy 271.112356 16.4705) (xy 271.08138 16.390541)
			(xy 271.043158 16.313781) (xy 270.998017 16.240875) (xy 270.946341 16.172446) (xy 270.888572 16.109076)
			(xy 270.825202 16.051307) (xy 270.756773 15.999631) (xy 270.683867 15.95449) (xy 270.607107 15.916268)
			(xy 270.527148 15.885292) (xy 270.444672 15.861825) (xy 270.360382 15.846069) (xy 270.274999 15.838157)
			(xy 270.189249 15.838157) (xy 270.103866 15.846069) (xy 270.019576 15.861825) (xy 269.9371 15.885292)
			(xy 269.857141 15.916268) (xy 269.780381 15.95449) (xy 269.707475 15.999631) (xy 269.639046 16.051307)
			(xy 269.575676 16.109076) (xy 269.517907 16.172446) (xy 269.466231 16.240875) (xy 269.42109 16.313781)
			(xy 269.382868 16.390541) (xy 269.351892 16.4705) (xy 269.328425 16.552976) (xy 269.312669 16.637266)
			(xy 269.304757 16.722649) (xy 252.231493 16.722649) (xy 252.231411 16.715537) (xy 252.223499 16.630154)
			(xy 252.207743 16.545864) (xy 252.184276 16.463388) (xy 252.1533 16.383429) (xy 252.115078 16.306669)
			(xy 252.069937 16.233763) (xy 252.018261 16.165334) (xy 251.960492 16.101964) (xy 251.897122 16.044195)
			(xy 251.828693 15.992519) (xy 251.755787 15.947378) (xy 251.679027 15.909156) (xy 251.599068 15.87818)
			(xy 251.516592 15.854713) (xy 251.432302 15.838957) (xy 251.346919 15.831045) (xy 251.261169 15.831045)
			(xy 251.175786 15.838957) (xy 251.091496 15.854713) (xy 251.00902 15.87818) (xy 250.929061 15.909156)
			(xy 250.852301 15.947378) (xy 250.779395 15.992519) (xy 250.710966 16.044195) (xy 250.647596 16.101964)
			(xy 250.589827 16.165334) (xy 250.538151 16.233763) (xy 250.49301 16.306669) (xy 250.454788 16.383429)
			(xy 250.423812 16.463388) (xy 250.400345 16.545864) (xy 250.384589 16.630154) (xy 250.376677 16.715537)
			(xy 245.881411 16.715537) (xy 245.873499 16.630154) (xy 245.857743 16.545864) (xy 245.834276 16.463388)
			(xy 245.8033 16.383429) (xy 245.765078 16.306669) (xy 245.719937 16.233763) (xy 245.668261 16.165334)
			(xy 245.610492 16.101964) (xy 245.547122 16.044195) (xy 245.478693 15.992519) (xy 245.405787 15.947378)
			(xy 245.329027 15.909156) (xy 245.249068 15.87818) (xy 245.166592 15.854713) (xy 245.082302 15.838957)
			(xy 244.996919 15.831045) (xy 244.911169 15.831045) (xy 244.825786 15.838957) (xy 244.741496 15.854713)
			(xy 244.65902 15.87818) (xy 244.579061 15.909156) (xy 244.502301 15.947378) (xy 244.429395 15.992519)
			(xy 244.360966 16.044195) (xy 244.297596 16.101964) (xy 244.239827 16.165334) (xy 244.188151 16.233763)
			(xy 244.14301 16.306669) (xy 244.104788 16.383429) (xy 244.073812 16.463388) (xy 244.050345 16.545864)
			(xy 244.034589 16.630154) (xy 244.026677 16.715537) (xy 218.199832 16.715537) (xy 218.192579 16.637266)
			(xy 218.176823 16.552976) (xy 218.153356 16.4705) (xy 218.12238 16.390541) (xy 218.084158 16.313781)
			(xy 218.039017 16.240875) (xy 217.987341 16.172446) (xy 217.929572 16.109076) (xy 217.866202 16.051307)
			(xy 217.797773 15.999631) (xy 217.724867 15.95449) (xy 217.648107 15.916268) (xy 217.568148 15.885292)
			(xy 217.485672 15.861825) (xy 217.401382 15.846069) (xy 217.315999 15.838157) (xy 217.230249 15.838157)
			(xy 217.144866 15.846069) (xy 217.060576 15.861825) (xy 216.9781 15.885292) (xy 216.898141 15.916268)
			(xy 216.821381 15.95449) (xy 216.748475 15.999631) (xy 216.680046 16.051307) (xy 216.616676 16.109076)
			(xy 216.558907 16.172446) (xy 216.507231 16.240875) (xy 216.46209 16.313781) (xy 216.423868 16.390541)
			(xy 216.392892 16.4705) (xy 216.369425 16.552976) (xy 216.353669 16.637266) (xy 216.345757 16.722649)
			(xy 211.850491 16.722649) (xy 211.842579 16.637266) (xy 211.826823 16.552976) (xy 211.803356 16.4705)
			(xy 211.77238 16.390541) (xy 211.734158 16.313781) (xy 211.689017 16.240875) (xy 211.637341 16.172446)
			(xy 211.579572 16.109076) (xy 211.516202 16.051307) (xy 211.447773 15.999631) (xy 211.374867 15.95449)
			(xy 211.298107 15.916268) (xy 211.218148 15.885292) (xy 211.135672 15.861825) (xy 211.051382 15.846069)
			(xy 210.965999 15.838157) (xy 210.880249 15.838157) (xy 210.794866 15.846069) (xy 210.710576 15.861825)
			(xy 210.6281 15.885292) (xy 210.548141 15.916268) (xy 210.471381 15.95449) (xy 210.398475 15.999631)
			(xy 210.330046 16.051307) (xy 210.266676 16.109076) (xy 210.208907 16.172446) (xy 210.157231 16.240875)
			(xy 210.11209 16.313781) (xy 210.073868 16.390541) (xy 210.042892 16.4705) (xy 210.019425 16.552976)
			(xy 210.003669 16.637266) (xy 209.995757 16.722649) (xy 158.621984 16.722649) (xy 158.621984 11.850929)
			(xy 251.524757 11.850929) (xy 251.524757 11.936679) (xy 251.532669 12.022062) (xy 251.548425 12.106352)
			(xy 251.571892 12.188828) (xy 251.602868 12.268787) (xy 251.64109 12.345547) (xy 251.686231 12.418453)
			(xy 251.737907 12.486882) (xy 251.795676 12.550252) (xy 251.859046 12.608021) (xy 251.927475 12.659697)
			(xy 252.000381 12.704838) (xy 252.077141 12.74306) (xy 252.1571 12.774036) (xy 252.239576 12.797503)
			(xy 252.323866 12.813259) (xy 252.409249 12.821171) (xy 252.494999 12.821171) (xy 252.580382 12.813259)
			(xy 252.664672 12.797503) (xy 252.747148 12.774036) (xy 252.827107 12.74306) (xy 252.903867 12.704838)
			(xy 252.976773 12.659697) (xy 253.045202 12.608021) (xy 253.108572 12.550252) (xy 253.166341 12.486882)
			(xy 253.218017 12.418453) (xy 253.263158 12.345547) (xy 253.30138 12.268787) (xy 253.332356 12.188828)
			(xy 253.355823 12.106352) (xy 253.371579 12.022062) (xy 253.379491 11.936679) (xy 253.379986 11.893804)
			(xy 253.379491 11.850929) (xy 257.874757 11.850929) (xy 257.874757 11.936679) (xy 257.882669 12.022062)
			(xy 257.898425 12.106352) (xy 257.921892 12.188828) (xy 257.952868 12.268787) (xy 257.99109 12.345547)
			(xy 258.036231 12.418453) (xy 258.087907 12.486882) (xy 258.145676 12.550252) (xy 258.209046 12.608021)
			(xy 258.277475 12.659697) (xy 258.350381 12.704838) (xy 258.427141 12.74306) (xy 258.5071 12.774036)
			(xy 258.589576 12.797503) (xy 258.673866 12.813259) (xy 258.759249 12.821171) (xy 258.844999 12.821171)
			(xy 258.930382 12.813259) (xy 259.014672 12.797503) (xy 259.097148 12.774036) (xy 259.177107 12.74306)
			(xy 259.253867 12.704838) (xy 259.326773 12.659697) (xy 259.395202 12.608021) (xy 259.458572 12.550252)
			(xy 259.516341 12.486882) (xy 259.568017 12.418453) (xy 259.613158 12.345547) (xy 259.65138 12.268787)
			(xy 259.682356 12.188828) (xy 259.705823 12.106352) (xy 259.721579 12.022062) (xy 259.729491 11.936679)
			(xy 259.729986 11.893804) (xy 259.72979 11.876837) (xy 309.725301 11.876837) (xy 309.725301 11.962587)
			(xy 309.733213 12.04797) (xy 309.748969 12.13226) (xy 309.772436 12.214736) (xy 309.803412 12.294695)
			(xy 309.841634 12.371455) (xy 309.886775 12.444361) (xy 309.938451 12.51279) (xy 309.99622 12.57616)
			(xy 310.05959 12.633929) (xy 310.128019 12.685605) (xy 310.200925 12.730746) (xy 310.277685 12.768968)
			(xy 310.357644 12.799944) (xy 310.44012 12.823411) (xy 310.52441 12.839167) (xy 310.609793 12.847079)
			(xy 310.695543 12.847079) (xy 310.780926 12.839167) (xy 310.865216 12.823411) (xy 310.947692 12.799944)
			(xy 311.027651 12.768968) (xy 311.104411 12.730746) (xy 311.177317 12.685605) (xy 311.245746 12.633929)
			(xy 311.309116 12.57616) (xy 311.366885 12.51279) (xy 311.418561 12.444361) (xy 311.463702 12.371455)
			(xy 311.501924 12.294695) (xy 311.5329 12.214736) (xy 311.556367 12.13226) (xy 311.572123 12.04797)
			(xy 311.580035 11.962587) (xy 311.58053 11.919712) (xy 311.580035 11.876837) (xy 316.075301 11.876837)
			(xy 316.075301 11.962587) (xy 316.083213 12.04797) (xy 316.098969 12.13226) (xy 316.122436 12.214736)
			(xy 316.153412 12.294695) (xy 316.191634 12.371455) (xy 316.236775 12.444361) (xy 316.288451 12.51279)
			(xy 316.34622 12.57616) (xy 316.40959 12.633929) (xy 316.478019 12.685605) (xy 316.550925 12.730746)
			(xy 316.627685 12.768968) (xy 316.707644 12.799944) (xy 316.79012 12.823411) (xy 316.87441 12.839167)
			(xy 316.959793 12.847079) (xy 317.045543 12.847079) (xy 317.130926 12.839167) (xy 317.215216 12.823411)
			(xy 317.297692 12.799944) (xy 317.377651 12.768968) (xy 317.454411 12.730746) (xy 317.527317 12.685605)
			(xy 317.595746 12.633929) (xy 317.659116 12.57616) (xy 317.716885 12.51279) (xy 317.768561 12.444361)
			(xy 317.813702 12.371455) (xy 317.851924 12.294695) (xy 317.8829 12.214736) (xy 317.906367 12.13226)
			(xy 317.922123 12.04797) (xy 317.930035 11.962587) (xy 317.93053 11.919712) (xy 317.930117 11.883949)
			(xy 324.295757 11.883949) (xy 324.295757 11.969699) (xy 324.303669 12.055082) (xy 324.319425 12.139372)
			(xy 324.342892 12.221848) (xy 324.373868 12.301807) (xy 324.41209 12.378567) (xy 324.457231 12.451473)
			(xy 324.508907 12.519902) (xy 324.566676 12.583272) (xy 324.630046 12.641041) (xy 324.698475 12.692717)
			(xy 324.771381 12.737858) (xy 324.848141 12.77608) (xy 324.9281 12.807056) (xy 325.010576 12.830523)
			(xy 325.094866 12.846279) (xy 325.180249 12.854191) (xy 325.265999 12.854191) (xy 325.351382 12.846279)
			(xy 325.435672 12.830523) (xy 325.518148 12.807056) (xy 325.598107 12.77608) (xy 325.674867 12.737858)
			(xy 325.747773 12.692717) (xy 325.816202 12.641041) (xy 325.879572 12.583272) (xy 325.937341 12.519902)
			(xy 325.989017 12.451473) (xy 326.034158 12.378567) (xy 326.07238 12.301807) (xy 326.103356 12.221848)
			(xy 326.126823 12.139372) (xy 326.142579 12.055082) (xy 326.150491 11.969699) (xy 326.150986 11.926824)
			(xy 326.150491 11.883949) (xy 330.645757 11.883949) (xy 330.645757 11.969699) (xy 330.653669 12.055082)
			(xy 330.669425 12.139372) (xy 330.692892 12.221848) (xy 330.723868 12.301807) (xy 330.76209 12.378567)
			(xy 330.807231 12.451473) (xy 330.858907 12.519902) (xy 330.916676 12.583272) (xy 330.980046 12.641041)
			(xy 331.048475 12.692717) (xy 331.121381 12.737858) (xy 331.198141 12.77608) (xy 331.2781 12.807056)
			(xy 331.360576 12.830523) (xy 331.444866 12.846279) (xy 331.530249 12.854191) (xy 331.615999 12.854191)
			(xy 331.701382 12.846279) (xy 331.785672 12.830523) (xy 331.868148 12.807056) (xy 331.948107 12.77608)
			(xy 332.024867 12.737858) (xy 332.097773 12.692717) (xy 332.166202 12.641041) (xy 332.229572 12.583272)
			(xy 332.287341 12.519902) (xy 332.339017 12.451473) (xy 332.384158 12.378567) (xy 332.42238 12.301807)
			(xy 332.453356 12.221848) (xy 332.476823 12.139372) (xy 332.492579 12.055082) (xy 332.500491 11.969699)
			(xy 332.500986 11.926824) (xy 332.50079 11.909857) (xy 382.496301 11.909857) (xy 382.496301 11.995607)
			(xy 382.504213 12.08099) (xy 382.519969 12.16528) (xy 382.543436 12.247756) (xy 382.574412 12.327715)
			(xy 382.612634 12.404475) (xy 382.657775 12.477381) (xy 382.709451 12.54581) (xy 382.76722 12.60918)
			(xy 382.83059 12.666949) (xy 382.899019 12.718625) (xy 382.971925 12.763766) (xy 383.048685 12.801988)
			(xy 383.128644 12.832964) (xy 383.21112 12.856431) (xy 383.29541 12.872187) (xy 383.380793 12.880099)
			(xy 383.466543 12.880099) (xy 383.551926 12.872187) (xy 383.636216 12.856431) (xy 383.718692 12.832964)
			(xy 383.798651 12.801988) (xy 383.875411 12.763766) (xy 383.948317 12.718625) (xy 384.016746 12.666949)
			(xy 384.080116 12.60918) (xy 384.137885 12.54581) (xy 384.189561 12.477381) (xy 384.234702 12.404475)
			(xy 384.272924 12.327715) (xy 384.3039 12.247756) (xy 384.327367 12.16528) (xy 384.343123 12.08099)
			(xy 384.351035 11.995607) (xy 384.35153 11.952732) (xy 384.351035 11.909857) (xy 388.846301 11.909857)
			(xy 388.846301 11.995607) (xy 388.854213 12.08099) (xy 388.869969 12.16528) (xy 388.893436 12.247756)
			(xy 388.924412 12.327715) (xy 388.962634 12.404475) (xy 389.007775 12.477381) (xy 389.059451 12.54581)
			(xy 389.11722 12.60918) (xy 389.18059 12.666949) (xy 389.249019 12.718625) (xy 389.321925 12.763766)
			(xy 389.398685 12.801988) (xy 389.478644 12.832964) (xy 389.56112 12.856431) (xy 389.64541 12.872187)
			(xy 389.730793 12.880099) (xy 389.816543 12.880099) (xy 389.901926 12.872187) (xy 389.986216 12.856431)
			(xy 390.068692 12.832964) (xy 390.148651 12.801988) (xy 390.225411 12.763766) (xy 390.298317 12.718625)
			(xy 390.366746 12.666949) (xy 390.430116 12.60918) (xy 390.487885 12.54581) (xy 390.539561 12.477381)
			(xy 390.584702 12.404475) (xy 390.622924 12.327715) (xy 390.6539 12.247756) (xy 390.677367 12.16528)
			(xy 390.693123 12.08099) (xy 390.701035 11.995607) (xy 390.70153 11.952732) (xy 390.701117 11.916969)
			(xy 396.558757 11.916969) (xy 396.558757 12.002719) (xy 396.566669 12.088102) (xy 396.582425 12.172392)
			(xy 396.605892 12.254868) (xy 396.636868 12.334827) (xy 396.67509 12.411587) (xy 396.720231 12.484493)
			(xy 396.771907 12.552922) (xy 396.829676 12.616292) (xy 396.893046 12.674061) (xy 396.961475 12.725737)
			(xy 397.034381 12.770878) (xy 397.111141 12.8091) (xy 397.1911 12.840076) (xy 397.273576 12.863543)
			(xy 397.357866 12.879299) (xy 397.443249 12.887211) (xy 397.528999 12.887211) (xy 397.614382 12.879299)
			(xy 397.698672 12.863543) (xy 397.781148 12.840076) (xy 397.861107 12.8091) (xy 397.937867 12.770878)
			(xy 398.010773 12.725737) (xy 398.079202 12.674061) (xy 398.142572 12.616292) (xy 398.200341 12.552922)
			(xy 398.252017 12.484493) (xy 398.297158 12.411587) (xy 398.33538 12.334827) (xy 398.366356 12.254868)
			(xy 398.389823 12.172392) (xy 398.405579 12.088102) (xy 398.413491 12.002719) (xy 398.413986 11.959844)
			(xy 398.413491 11.916969) (xy 402.908757 11.916969) (xy 402.908757 12.002719) (xy 402.916669 12.088102)
			(xy 402.932425 12.172392) (xy 402.955892 12.254868) (xy 402.986868 12.334827) (xy 403.02509 12.411587)
			(xy 403.070231 12.484493) (xy 403.121907 12.552922) (xy 403.179676 12.616292) (xy 403.243046 12.674061)
			(xy 403.311475 12.725737) (xy 403.384381 12.770878) (xy 403.461141 12.8091) (xy 403.5411 12.840076)
			(xy 403.623576 12.863543) (xy 403.707866 12.879299) (xy 403.793249 12.887211) (xy 403.878999 12.887211)
			(xy 403.964382 12.879299) (xy 404.048672 12.863543) (xy 404.131148 12.840076) (xy 404.211107 12.8091)
			(xy 404.287867 12.770878) (xy 404.360773 12.725737) (xy 404.429202 12.674061) (xy 404.492572 12.616292)
			(xy 404.550341 12.552922) (xy 404.602017 12.484493) (xy 404.647158 12.411587) (xy 404.68538 12.334827)
			(xy 404.716356 12.254868) (xy 404.739823 12.172392) (xy 404.755579 12.088102) (xy 404.763491 12.002719)
			(xy 404.763986 11.959844) (xy 404.76379 11.942877) (xy 454.759301 11.942877) (xy 454.759301 12.028627)
			(xy 454.767213 12.11401) (xy 454.782969 12.1983) (xy 454.806436 12.280776) (xy 454.837412 12.360735)
			(xy 454.875634 12.437495) (xy 454.920775 12.510401) (xy 454.972451 12.57883) (xy 455.03022 12.6422)
			(xy 455.09359 12.699969) (xy 455.162019 12.751645) (xy 455.234925 12.796786) (xy 455.311685 12.835008)
			(xy 455.391644 12.865984) (xy 455.47412 12.889451) (xy 455.55841 12.905207) (xy 455.643793 12.913119)
			(xy 455.729543 12.913119) (xy 455.814926 12.905207) (xy 455.899216 12.889451) (xy 455.981692 12.865984)
			(xy 456.061651 12.835008) (xy 456.138411 12.796786) (xy 456.211317 12.751645) (xy 456.279746 12.699969)
			(xy 456.343116 12.6422) (xy 456.400885 12.57883) (xy 456.452561 12.510401) (xy 456.497702 12.437495)
			(xy 456.535924 12.360735) (xy 456.5669 12.280776) (xy 456.590367 12.1983) (xy 456.606123 12.11401)
			(xy 456.614035 12.028627) (xy 456.61453 11.985752) (xy 456.614035 11.942877) (xy 461.109301 11.942877)
			(xy 461.109301 12.028627) (xy 461.117213 12.11401) (xy 461.132969 12.1983) (xy 461.156436 12.280776)
			(xy 461.187412 12.360735) (xy 461.225634 12.437495) (xy 461.270775 12.510401) (xy 461.322451 12.57883)
			(xy 461.38022 12.6422) (xy 461.44359 12.699969) (xy 461.512019 12.751645) (xy 461.584925 12.796786)
			(xy 461.661685 12.835008) (xy 461.741644 12.865984) (xy 461.82412 12.889451) (xy 461.90841 12.905207)
			(xy 461.993793 12.913119) (xy 462.079543 12.913119) (xy 462.164926 12.905207) (xy 462.249216 12.889451)
			(xy 462.331692 12.865984) (xy 462.411651 12.835008) (xy 462.488411 12.796786) (xy 462.561317 12.751645)
			(xy 462.629746 12.699969) (xy 462.693116 12.6422) (xy 462.750885 12.57883) (xy 462.802561 12.510401)
			(xy 462.847702 12.437495) (xy 462.885924 12.360735) (xy 462.9169 12.280776) (xy 462.940367 12.1983)
			(xy 462.956123 12.11401) (xy 462.964035 12.028627) (xy 462.96453 11.985752) (xy 462.964035 11.942877)
			(xy 462.956123 11.857494) (xy 462.940367 11.773204) (xy 462.9169 11.690728) (xy 462.885924 11.610769)
			(xy 462.847702 11.534009) (xy 462.802561 11.461103) (xy 462.750885 11.392674) (xy 462.693116 11.329304)
			(xy 462.629746 11.271535) (xy 462.561317 11.219859) (xy 462.488411 11.174718) (xy 462.411651 11.136496)
			(xy 462.331692 11.10552) (xy 462.249216 11.082053) (xy 462.164926 11.066297) (xy 462.079543 11.058385)
			(xy 461.993793 11.058385) (xy 461.90841 11.066297) (xy 461.82412 11.082053) (xy 461.741644 11.10552)
			(xy 461.661685 11.136496) (xy 461.584925 11.174718) (xy 461.512019 11.219859) (xy 461.44359 11.271535)
			(xy 461.38022 11.329304) (xy 461.322451 11.392674) (xy 461.270775 11.461103) (xy 461.225634 11.534009)
			(xy 461.187412 11.610769) (xy 461.156436 11.690728) (xy 461.132969 11.773204) (xy 461.117213 11.857494)
			(xy 461.109301 11.942877) (xy 456.614035 11.942877) (xy 456.606123 11.857494) (xy 456.590367 11.773204)
			(xy 456.5669 11.690728) (xy 456.535924 11.610769) (xy 456.497702 11.534009) (xy 456.452561 11.461103)
			(xy 456.400885 11.392674) (xy 456.343116 11.329304) (xy 456.279746 11.271535) (xy 456.211317 11.219859)
			(xy 456.138411 11.174718) (xy 456.061651 11.136496) (xy 455.981692 11.10552) (xy 455.899216 11.082053)
			(xy 455.814926 11.066297) (xy 455.729543 11.058385) (xy 455.643793 11.058385) (xy 455.55841 11.066297)
			(xy 455.47412 11.082053) (xy 455.391644 11.10552) (xy 455.311685 11.136496) (xy 455.234925 11.174718)
			(xy 455.162019 11.219859) (xy 455.09359 11.271535) (xy 455.03022 11.329304) (xy 454.972451 11.392674)
			(xy 454.920775 11.461103) (xy 454.875634 11.534009) (xy 454.837412 11.610769) (xy 454.806436 11.690728)
			(xy 454.782969 11.773204) (xy 454.767213 11.857494) (xy 454.759301 11.942877) (xy 404.76379 11.942877)
			(xy 404.763491 11.916969) (xy 404.755579 11.831586) (xy 404.739823 11.747296) (xy 404.716356 11.66482)
			(xy 404.68538 11.584861) (xy 404.647158 11.508101) (xy 404.602017 11.435195) (xy 404.550341 11.366766)
			(xy 404.492572 11.303396) (xy 404.429202 11.245627) (xy 404.360773 11.193951) (xy 404.287867 11.14881)
			(xy 404.211107 11.110588) (xy 404.131148 11.079612) (xy 404.048672 11.056145) (xy 403.964382 11.040389)
			(xy 403.878999 11.032477) (xy 403.793249 11.032477) (xy 403.707866 11.040389) (xy 403.623576 11.056145)
			(xy 403.5411 11.079612) (xy 403.461141 11.110588) (xy 403.384381 11.14881) (xy 403.311475 11.193951)
			(xy 403.243046 11.245627) (xy 403.179676 11.303396) (xy 403.121907 11.366766) (xy 403.070231 11.435195)
			(xy 403.02509 11.508101) (xy 402.986868 11.584861) (xy 402.955892 11.66482) (xy 402.932425 11.747296)
			(xy 402.916669 11.831586) (xy 402.908757 11.916969) (xy 398.413491 11.916969) (xy 398.405579 11.831586)
			(xy 398.389823 11.747296) (xy 398.366356 11.66482) (xy 398.33538 11.584861) (xy 398.297158 11.508101)
			(xy 398.252017 11.435195) (xy 398.200341 11.366766) (xy 398.142572 11.303396) (xy 398.079202 11.245627)
			(xy 398.010773 11.193951) (xy 397.937867 11.14881) (xy 397.861107 11.110588) (xy 397.781148 11.079612)
			(xy 397.698672 11.056145) (xy 397.614382 11.040389) (xy 397.528999 11.032477) (xy 397.443249 11.032477)
			(xy 397.357866 11.040389) (xy 397.273576 11.056145) (xy 397.1911 11.079612) (xy 397.111141 11.110588)
			(xy 397.034381 11.14881) (xy 396.961475 11.193951) (xy 396.893046 11.245627) (xy 396.829676 11.303396)
			(xy 396.771907 11.366766) (xy 396.720231 11.435195) (xy 396.67509 11.508101) (xy 396.636868 11.584861)
			(xy 396.605892 11.66482) (xy 396.582425 11.747296) (xy 396.566669 11.831586) (xy 396.558757 11.916969)
			(xy 390.701117 11.916969) (xy 390.701035 11.909857) (xy 390.693123 11.824474) (xy 390.677367 11.740184)
			(xy 390.6539 11.657708) (xy 390.622924 11.577749) (xy 390.584702 11.500989) (xy 390.539561 11.428083)
			(xy 390.487885 11.359654) (xy 390.430116 11.296284) (xy 390.366746 11.238515) (xy 390.298317 11.186839)
			(xy 390.225411 11.141698) (xy 390.148651 11.103476) (xy 390.068692 11.0725) (xy 389.986216 11.049033)
			(xy 389.901926 11.033277) (xy 389.816543 11.025365) (xy 389.730793 11.025365) (xy 389.64541 11.033277)
			(xy 389.56112 11.049033) (xy 389.478644 11.0725) (xy 389.398685 11.103476) (xy 389.321925 11.141698)
			(xy 389.249019 11.186839) (xy 389.18059 11.238515) (xy 389.11722 11.296284) (xy 389.059451 11.359654)
			(xy 389.007775 11.428083) (xy 388.962634 11.500989) (xy 388.924412 11.577749) (xy 388.893436 11.657708)
			(xy 388.869969 11.740184) (xy 388.854213 11.824474) (xy 388.846301 11.909857) (xy 384.351035 11.909857)
			(xy 384.343123 11.824474) (xy 384.327367 11.740184) (xy 384.3039 11.657708) (xy 384.272924 11.577749)
			(xy 384.234702 11.500989) (xy 384.189561 11.428083) (xy 384.137885 11.359654) (xy 384.080116 11.296284)
			(xy 384.016746 11.238515) (xy 383.948317 11.186839) (xy 383.875411 11.141698) (xy 383.798651 11.103476)
			(xy 383.718692 11.0725) (xy 383.636216 11.049033) (xy 383.551926 11.033277) (xy 383.466543 11.025365)
			(xy 383.380793 11.025365) (xy 383.29541 11.033277) (xy 383.21112 11.049033) (xy 383.128644 11.0725)
			(xy 383.048685 11.103476) (xy 382.971925 11.141698) (xy 382.899019 11.186839) (xy 382.83059 11.238515)
			(xy 382.76722 11.296284) (xy 382.709451 11.359654) (xy 382.657775 11.428083) (xy 382.612634 11.500989)
			(xy 382.574412 11.577749) (xy 382.543436 11.657708) (xy 382.519969 11.740184) (xy 382.504213 11.824474)
			(xy 382.496301 11.909857) (xy 332.50079 11.909857) (xy 332.500491 11.883949) (xy 332.492579 11.798566)
			(xy 332.476823 11.714276) (xy 332.453356 11.6318) (xy 332.42238 11.551841) (xy 332.384158 11.475081)
			(xy 332.339017 11.402175) (xy 332.287341 11.333746) (xy 332.229572 11.270376) (xy 332.166202 11.212607)
			(xy 332.097773 11.160931) (xy 332.024867 11.11579) (xy 331.948107 11.077568) (xy 331.868148 11.046592)
			(xy 331.785672 11.023125) (xy 331.701382 11.007369) (xy 331.615999 10.999457) (xy 331.530249 10.999457)
			(xy 331.444866 11.007369) (xy 331.360576 11.023125) (xy 331.2781 11.046592) (xy 331.198141 11.077568)
			(xy 331.121381 11.11579) (xy 331.048475 11.160931) (xy 330.980046 11.212607) (xy 330.916676 11.270376)
			(xy 330.858907 11.333746) (xy 330.807231 11.402175) (xy 330.76209 11.475081) (xy 330.723868 11.551841)
			(xy 330.692892 11.6318) (xy 330.669425 11.714276) (xy 330.653669 11.798566) (xy 330.645757 11.883949)
			(xy 326.150491 11.883949) (xy 326.142579 11.798566) (xy 326.126823 11.714276) (xy 326.103356 11.6318)
			(xy 326.07238 11.551841) (xy 326.034158 11.475081) (xy 325.989017 11.402175) (xy 325.937341 11.333746)
			(xy 325.879572 11.270376) (xy 325.816202 11.212607) (xy 325.747773 11.160931) (xy 325.674867 11.11579)
			(xy 325.598107 11.077568) (xy 325.518148 11.046592) (xy 325.435672 11.023125) (xy 325.351382 11.007369)
			(xy 325.265999 10.999457) (xy 325.180249 10.999457) (xy 325.094866 11.007369) (xy 325.010576 11.023125)
			(xy 324.9281 11.046592) (xy 324.848141 11.077568) (xy 324.771381 11.11579) (xy 324.698475 11.160931)
			(xy 324.630046 11.212607) (xy 324.566676 11.270376) (xy 324.508907 11.333746) (xy 324.457231 11.402175)
			(xy 324.41209 11.475081) (xy 324.373868 11.551841) (xy 324.342892 11.6318) (xy 324.319425 11.714276)
			(xy 324.303669 11.798566) (xy 324.295757 11.883949) (xy 317.930117 11.883949) (xy 317.930035 11.876837)
			(xy 317.922123 11.791454) (xy 317.906367 11.707164) (xy 317.8829 11.624688) (xy 317.851924 11.544729)
			(xy 317.813702 11.467969) (xy 317.768561 11.395063) (xy 317.716885 11.326634) (xy 317.659116 11.263264)
			(xy 317.595746 11.205495) (xy 317.527317 11.153819) (xy 317.454411 11.108678) (xy 317.377651 11.070456)
			(xy 317.297692 11.03948) (xy 317.215216 11.016013) (xy 317.130926 11.000257) (xy 317.045543 10.992345)
			(xy 316.959793 10.992345) (xy 316.87441 11.000257) (xy 316.79012 11.016013) (xy 316.707644 11.03948)
			(xy 316.627685 11.070456) (xy 316.550925 11.108678) (xy 316.478019 11.153819) (xy 316.40959 11.205495)
			(xy 316.34622 11.263264) (xy 316.288451 11.326634) (xy 316.236775 11.395063) (xy 316.191634 11.467969)
			(xy 316.153412 11.544729) (xy 316.122436 11.624688) (xy 316.098969 11.707164) (xy 316.083213 11.791454)
			(xy 316.075301 11.876837) (xy 311.580035 11.876837) (xy 311.572123 11.791454) (xy 311.556367 11.707164)
			(xy 311.5329 11.624688) (xy 311.501924 11.544729) (xy 311.463702 11.467969) (xy 311.418561 11.395063)
			(xy 311.366885 11.326634) (xy 311.309116 11.263264) (xy 311.245746 11.205495) (xy 311.177317 11.153819)
			(xy 311.104411 11.108678) (xy 311.027651 11.070456) (xy 310.947692 11.03948) (xy 310.865216 11.016013)
			(xy 310.780926 11.000257) (xy 310.695543 10.992345) (xy 310.609793 10.992345) (xy 310.52441 11.000257)
			(xy 310.44012 11.016013) (xy 310.357644 11.03948) (xy 310.277685 11.070456) (xy 310.200925 11.108678)
			(xy 310.128019 11.153819) (xy 310.05959 11.205495) (xy 309.99622 11.263264) (xy 309.938451 11.326634)
			(xy 309.886775 11.395063) (xy 309.841634 11.467969) (xy 309.803412 11.544729) (xy 309.772436 11.624688)
			(xy 309.748969 11.707164) (xy 309.733213 11.791454) (xy 309.725301 11.876837) (xy 259.72979 11.876837)
			(xy 259.729491 11.850929) (xy 259.721579 11.765546) (xy 259.705823 11.681256) (xy 259.682356 11.59878)
			(xy 259.65138 11.518821) (xy 259.613158 11.442061) (xy 259.568017 11.369155) (xy 259.516341 11.300726)
			(xy 259.458572 11.237356) (xy 259.395202 11.179587) (xy 259.326773 11.127911) (xy 259.253867 11.08277)
			(xy 259.177107 11.044548) (xy 259.097148 11.013572) (xy 259.014672 10.990105) (xy 258.930382 10.974349)
			(xy 258.844999 10.966437) (xy 258.759249 10.966437) (xy 258.673866 10.974349) (xy 258.589576 10.990105)
			(xy 258.5071 11.013572) (xy 258.427141 11.044548) (xy 258.350381 11.08277) (xy 258.277475 11.127911)
			(xy 258.209046 11.179587) (xy 258.145676 11.237356) (xy 258.087907 11.300726) (xy 258.036231 11.369155)
			(xy 257.99109 11.442061) (xy 257.952868 11.518821) (xy 257.921892 11.59878) (xy 257.898425 11.681256)
			(xy 257.882669 11.765546) (xy 257.874757 11.850929) (xy 253.379491 11.850929) (xy 253.371579 11.765546)
			(xy 253.355823 11.681256) (xy 253.332356 11.59878) (xy 253.30138 11.518821) (xy 253.263158 11.442061)
			(xy 253.218017 11.369155) (xy 253.166341 11.300726) (xy 253.108572 11.237356) (xy 253.045202 11.179587)
			(xy 252.976773 11.127911) (xy 252.903867 11.08277) (xy 252.827107 11.044548) (xy 252.747148 11.013572)
			(xy 252.664672 10.990105) (xy 252.580382 10.974349) (xy 252.494999 10.966437) (xy 252.409249 10.966437)
			(xy 252.323866 10.974349) (xy 252.239576 10.990105) (xy 252.1571 11.013572) (xy 252.077141 11.044548)
			(xy 252.000381 11.08277) (xy 251.927475 11.127911) (xy 251.859046 11.179587) (xy 251.795676 11.237356)
			(xy 251.737907 11.300726) (xy 251.686231 11.369155) (xy 251.64109 11.442061) (xy 251.602868 11.518821)
			(xy 251.571892 11.59878) (xy 251.548425 11.681256) (xy 251.532669 11.765546) (xy 251.524757 11.850929)
			(xy 158.621984 11.850929) (xy 158.621984 9.310929) (xy 179.515757 9.310929) (xy 179.515757 9.396679)
			(xy 179.523669 9.482062) (xy 179.539425 9.566352) (xy 179.562892 9.648828) (xy 179.593868 9.728787)
			(xy 179.63209 9.805547) (xy 179.677231 9.878453) (xy 179.728907 9.946882) (xy 179.786676 10.010252)
			(xy 179.850046 10.068021) (xy 179.918475 10.119697) (xy 179.991381 10.164838) (xy 180.068141 10.20306)
			(xy 180.1481 10.234036) (xy 180.230576 10.257503) (xy 180.314866 10.273259) (xy 180.400249 10.281171)
			(xy 180.485999 10.281171) (xy 180.571382 10.273259) (xy 180.655672 10.257503) (xy 180.738148 10.234036)
			(xy 180.818107 10.20306) (xy 180.894867 10.164838) (xy 180.967773 10.119697) (xy 181.036202 10.068021)
			(xy 181.099572 10.010252) (xy 181.157341 9.946882) (xy 181.209017 9.878453) (xy 181.254158 9.805547)
			(xy 181.29238 9.728787) (xy 181.323356 9.648828) (xy 181.346823 9.566352) (xy 181.362579 9.482062)
			(xy 181.370491 9.396679) (xy 181.370986 9.353804) (xy 181.370491 9.310929) (xy 185.865757 9.310929)
			(xy 185.865757 9.396679) (xy 185.873669 9.482062) (xy 185.889425 9.566352) (xy 185.912892 9.648828)
			(xy 185.943868 9.728787) (xy 185.98209 9.805547) (xy 186.027231 9.878453) (xy 186.078907 9.946882)
			(xy 186.136676 10.010252) (xy 186.200046 10.068021) (xy 186.268475 10.119697) (xy 186.341381 10.164838)
			(xy 186.418141 10.20306) (xy 186.4981 10.234036) (xy 186.580576 10.257503) (xy 186.664866 10.273259)
			(xy 186.750249 10.281171) (xy 186.835999 10.281171) (xy 186.921382 10.273259) (xy 187.005672 10.257503)
			(xy 187.088148 10.234036) (xy 187.168107 10.20306) (xy 187.244867 10.164838) (xy 187.317773 10.119697)
			(xy 187.386202 10.068021) (xy 187.449572 10.010252) (xy 187.507341 9.946882) (xy 187.559017 9.878453)
			(xy 187.604158 9.805547) (xy 187.64238 9.728787) (xy 187.673356 9.648828) (xy 187.696823 9.566352)
			(xy 187.712579 9.482062) (xy 187.720491 9.396679) (xy 187.720986 9.353804) (xy 187.720491 9.310929)
			(xy 187.719832 9.303817) (xy 237.716301 9.303817) (xy 237.716301 9.389567) (xy 237.724213 9.47495)
			(xy 237.739969 9.55924) (xy 237.763436 9.641716) (xy 237.794412 9.721675) (xy 237.832634 9.798435)
			(xy 237.877775 9.871341) (xy 237.929451 9.93977) (xy 237.98722 10.00314) (xy 238.05059 10.060909)
			(xy 238.119019 10.112585) (xy 238.191925 10.157726) (xy 238.268685 10.195948) (xy 238.348644 10.226924)
			(xy 238.43112 10.250391) (xy 238.51541 10.266147) (xy 238.600793 10.274059) (xy 238.686543 10.274059)
			(xy 238.771926 10.266147) (xy 238.856216 10.250391) (xy 238.938692 10.226924) (xy 239.018651 10.195948)
			(xy 239.095411 10.157726) (xy 239.168317 10.112585) (xy 239.236746 10.060909) (xy 239.300116 10.00314)
			(xy 239.357885 9.93977) (xy 239.409561 9.871341) (xy 239.454702 9.798435) (xy 239.492924 9.721675)
			(xy 239.5239 9.641716) (xy 239.547367 9.55924) (xy 239.563123 9.47495) (xy 239.571035 9.389567) (xy 239.57153 9.346692)
			(xy 239.571035 9.303817) (xy 244.066301 9.303817) (xy 244.066301 9.389567) (xy 244.074213 9.47495)
			(xy 244.089969 9.55924) (xy 244.113436 9.641716) (xy 244.144412 9.721675) (xy 244.182634 9.798435)
			(xy 244.227775 9.871341) (xy 244.279451 9.93977) (xy 244.33722 10.00314) (xy 244.40059 10.060909)
			(xy 244.469019 10.112585) (xy 244.541925 10.157726) (xy 244.618685 10.195948) (xy 244.698644 10.226924)
			(xy 244.78112 10.250391) (xy 244.86541 10.266147) (xy 244.950793 10.274059) (xy 245.036543 10.274059)
			(xy 245.121926 10.266147) (xy 245.206216 10.250391) (xy 245.288692 10.226924) (xy 245.368651 10.195948)
			(xy 245.445411 10.157726) (xy 245.518317 10.112585) (xy 245.586746 10.060909) (xy 245.650116 10.00314)
			(xy 245.707885 9.93977) (xy 245.759561 9.871341) (xy 245.804702 9.798435) (xy 245.842924 9.721675)
			(xy 245.8739 9.641716) (xy 245.897367 9.55924) (xy 245.913123 9.47495) (xy 245.921035 9.389567) (xy 245.92153 9.346692)
			(xy 245.921117 9.310929) (xy 251.524757 9.310929) (xy 251.524757 9.396679) (xy 251.532669 9.482062)
			(xy 251.548425 9.566352) (xy 251.571892 9.648828) (xy 251.602868 9.728787) (xy 251.64109 9.805547)
			(xy 251.686231 9.878453) (xy 251.737907 9.946882) (xy 251.795676 10.010252) (xy 251.859046 10.068021)
			(xy 251.927475 10.119697) (xy 252.000381 10.164838) (xy 252.077141 10.20306) (xy 252.1571 10.234036)
			(xy 252.239576 10.257503) (xy 252.323866 10.273259) (xy 252.409249 10.281171) (xy 252.494999 10.281171)
			(xy 252.580382 10.273259) (xy 252.664672 10.257503) (xy 252.747148 10.234036) (xy 252.827107 10.20306)
			(xy 252.84931 10.192004) (xy 256.459736 10.192004) (xy 256.459736 11.055604) (xy 256.460222 11.082873)
			(xy 256.467984 11.136857) (xy 256.483349 11.189187) (xy 256.506006 11.238797) (xy 256.535492 11.284678)
			(xy 256.571207 11.325895) (xy 256.612424 11.36161) (xy 256.658305 11.391096) (xy 256.707915 11.413753)
			(xy 256.760245 11.429118) (xy 256.814229 11.43688) (xy 256.868767 11.43688) (xy 256.922751 11.429118)
			(xy 256.975081 11.413753) (xy 257.024691 11.391096) (xy 257.070572 11.36161) (xy 257.111789 11.325895)
			(xy 257.147504 11.284678) (xy 257.17699 11.238797) (xy 257.199647 11.189187) (xy 257.215012 11.136857)
			(xy 257.222774 11.082873) (xy 257.22326 11.055604) (xy 257.22326 10.192004) (xy 257.222774 10.164735)
			(xy 257.215012 10.110751) (xy 257.199647 10.058421) (xy 257.17699 10.008811) (xy 257.147504 9.96293)
			(xy 257.111789 9.921713) (xy 257.070572 9.885998) (xy 257.024691 9.856512) (xy 256.975081 9.833855)
			(xy 256.922751 9.81849) (xy 256.868767 9.810728) (xy 256.814229 9.810728) (xy 256.760245 9.81849)
			(xy 256.707915 9.833855) (xy 256.658305 9.856512) (xy 256.612424 9.885998) (xy 256.571207 9.921713)
			(xy 256.535492 9.96293) (xy 256.506006 10.008811) (xy 256.483349 10.058421) (xy 256.467984 10.110751)
			(xy 256.460222 10.164735) (xy 256.459736 10.192004) (xy 252.84931 10.192004) (xy 252.903867 10.164838)
			(xy 252.976773 10.119697) (xy 253.045202 10.068021) (xy 253.108572 10.010252) (xy 253.166341 9.946882)
			(xy 253.218017 9.878453) (xy 253.263158 9.805547) (xy 253.30138 9.728787) (xy 253.332356 9.648828)
			(xy 253.355823 9.566352) (xy 253.371579 9.482062) (xy 253.379491 9.396679) (xy 253.379986 9.353804)
			(xy 253.379491 9.310929) (xy 257.874757 9.310929) (xy 257.874757 9.396679) (xy 257.882669 9.482062)
			(xy 257.898425 9.566352) (xy 257.921892 9.648828) (xy 257.952868 9.728787) (xy 257.99109 9.805547)
			(xy 258.036231 9.878453) (xy 258.087907 9.946882) (xy 258.145676 10.010252) (xy 258.209046 10.068021)
			(xy 258.277475 10.119697) (xy 258.350381 10.164838) (xy 258.427141 10.20306) (xy 258.5071 10.234036)
			(xy 258.589576 10.257503) (xy 258.673866 10.273259) (xy 258.759249 10.281171) (xy 258.844999 10.281171)
			(xy 258.930382 10.273259) (xy 259.014672 10.257503) (xy 259.097148 10.234036) (xy 259.177107 10.20306)
			(xy 259.253867 10.164838) (xy 259.326773 10.119697) (xy 259.395202 10.068021) (xy 259.458572 10.010252)
			(xy 259.516341 9.946882) (xy 259.568017 9.878453) (xy 259.613158 9.805547) (xy 259.65138 9.728787)
			(xy 259.682356 9.648828) (xy 259.705823 9.566352) (xy 259.721579 9.482062) (xy 259.729491 9.396679)
			(xy 259.729986 9.353804) (xy 259.72979 9.336837) (xy 309.725301 9.336837) (xy 309.725301 9.422587)
			(xy 309.733213 9.50797) (xy 309.748969 9.59226) (xy 309.772436 9.674736) (xy 309.803412 9.754695)
			(xy 309.841634 9.831455) (xy 309.886775 9.904361) (xy 309.938451 9.97279) (xy 309.99622 10.03616)
			(xy 310.05959 10.093929) (xy 310.128019 10.145605) (xy 310.200925 10.190746) (xy 310.277685 10.228968)
			(xy 310.357644 10.259944) (xy 310.44012 10.283411) (xy 310.52441 10.299167) (xy 310.609793 10.307079)
			(xy 310.695543 10.307079) (xy 310.780926 10.299167) (xy 310.865216 10.283411) (xy 310.947692 10.259944)
			(xy 311.027651 10.228968) (xy 311.049854 10.217912) (xy 312.231532 10.217912) (xy 312.231532 11.081512)
			(xy 312.232018 11.108781) (xy 312.23978 11.162765) (xy 312.255145 11.215095) (xy 312.277802 11.264705)
			(xy 312.307288 11.310586) (xy 312.343003 11.351803) (xy 312.38422 11.387518) (xy 312.430101 11.417004)
			(xy 312.479711 11.439661) (xy 312.532041 11.455026) (xy 312.586025 11.462788) (xy 312.640563 11.462788)
			(xy 312.694547 11.455026) (xy 312.746877 11.439661) (xy 312.796487 11.417004) (xy 312.842368 11.387518)
			(xy 312.883585 11.351803) (xy 312.9193 11.310586) (xy 312.948786 11.264705) (xy 312.971443 11.215095)
			(xy 312.986808 11.162765) (xy 312.99457 11.108781) (xy 312.995056 11.081512) (xy 312.995056 10.217912)
			(xy 312.99457 10.190643) (xy 312.986808 10.136659) (xy 312.971443 10.084329) (xy 312.948786 10.034719)
			(xy 312.9193 9.988838) (xy 312.883585 9.947621) (xy 312.842368 9.911906) (xy 312.796487 9.88242)
			(xy 312.746877 9.859763) (xy 312.694547 9.844398) (xy 312.640563 9.836636) (xy 312.586025 9.836636)
			(xy 312.532041 9.844398) (xy 312.479711 9.859763) (xy 312.430101 9.88242) (xy 312.38422 9.911906)
			(xy 312.343003 9.947621) (xy 312.307288 9.988838) (xy 312.277802 10.034719) (xy 312.255145 10.084329)
			(xy 312.23978 10.136659) (xy 312.232018 10.190643) (xy 312.231532 10.217912) (xy 311.049854 10.217912)
			(xy 311.104411 10.190746) (xy 311.177317 10.145605) (xy 311.245746 10.093929) (xy 311.309116 10.03616)
			(xy 311.366885 9.97279) (xy 311.418561 9.904361) (xy 311.463702 9.831455) (xy 311.501924 9.754695)
			(xy 311.5329 9.674736) (xy 311.556367 9.59226) (xy 311.572123 9.50797) (xy 311.580035 9.422587) (xy 311.58053 9.379712)
			(xy 311.580035 9.336837) (xy 316.075301 9.336837) (xy 316.075301 9.422587) (xy 316.083213 9.50797)
			(xy 316.098969 9.59226) (xy 316.122436 9.674736) (xy 316.153412 9.754695) (xy 316.191634 9.831455)
			(xy 316.236775 9.904361) (xy 316.288451 9.97279) (xy 316.34622 10.03616) (xy 316.40959 10.093929)
			(xy 316.478019 10.145605) (xy 316.550925 10.190746) (xy 316.627685 10.228968) (xy 316.707644 10.259944)
			(xy 316.79012 10.283411) (xy 316.87441 10.299167) (xy 316.959793 10.307079) (xy 317.045543 10.307079)
			(xy 317.130926 10.299167) (xy 317.215216 10.283411) (xy 317.297692 10.259944) (xy 317.377651 10.228968)
			(xy 317.454411 10.190746) (xy 317.527317 10.145605) (xy 317.595746 10.093929) (xy 317.659116 10.03616)
			(xy 317.716885 9.97279) (xy 317.768561 9.904361) (xy 317.813702 9.831455) (xy 317.851924 9.754695)
			(xy 317.8829 9.674736) (xy 317.906367 9.59226) (xy 317.922123 9.50797) (xy 317.930035 9.422587) (xy 317.93053 9.379712)
			(xy 317.930117 9.343949) (xy 324.295757 9.343949) (xy 324.295757 9.429699) (xy 324.303669 9.515082)
			(xy 324.319425 9.599372) (xy 324.342892 9.681848) (xy 324.373868 9.761807) (xy 324.41209 9.838567)
			(xy 324.457231 9.911473) (xy 324.508907 9.979902) (xy 324.566676 10.043272) (xy 324.630046 10.101041)
			(xy 324.698475 10.152717) (xy 324.771381 10.197858) (xy 324.848141 10.23608) (xy 324.9281 10.267056)
			(xy 325.010576 10.290523) (xy 325.094866 10.306279) (xy 325.180249 10.314191) (xy 325.265999 10.314191)
			(xy 325.351382 10.306279) (xy 325.435672 10.290523) (xy 325.518148 10.267056) (xy 325.598107 10.23608)
			(xy 325.62031 10.225024) (xy 329.230736 10.225024) (xy 329.230736 11.088624) (xy 329.231222 11.115893)
			(xy 329.238984 11.169877) (xy 329.254349 11.222207) (xy 329.277006 11.271817) (xy 329.306492 11.317698)
			(xy 329.342207 11.358915) (xy 329.383424 11.39463) (xy 329.429305 11.424116) (xy 329.478915 11.446773)
			(xy 329.531245 11.462138) (xy 329.585229 11.4699) (xy 329.639767 11.4699) (xy 329.693751 11.462138)
			(xy 329.746081 11.446773) (xy 329.795691 11.424116) (xy 329.841572 11.39463) (xy 329.882789 11.358915)
			(xy 329.918504 11.317698) (xy 329.94799 11.271817) (xy 329.970647 11.222207) (xy 329.986012 11.169877)
			(xy 329.993774 11.115893) (xy 329.99426 11.088624) (xy 329.99426 10.225024) (xy 329.993774 10.197755)
			(xy 329.986012 10.143771) (xy 329.970647 10.091441) (xy 329.94799 10.041831) (xy 329.918504 9.99595)
			(xy 329.882789 9.954733) (xy 329.841572 9.919018) (xy 329.795691 9.889532) (xy 329.746081 9.866875)
			(xy 329.693751 9.85151) (xy 329.639767 9.843748) (xy 329.585229 9.843748) (xy 329.531245 9.85151)
			(xy 329.478915 9.866875) (xy 329.429305 9.889532) (xy 329.383424 9.919018) (xy 329.342207 9.954733)
			(xy 329.306492 9.99595) (xy 329.277006 10.041831) (xy 329.254349 10.091441) (xy 329.238984 10.143771)
			(xy 329.231222 10.197755) (xy 329.230736 10.225024) (xy 325.62031 10.225024) (xy 325.674867 10.197858)
			(xy 325.747773 10.152717) (xy 325.816202 10.101041) (xy 325.879572 10.043272) (xy 325.937341 9.979902)
			(xy 325.989017 9.911473) (xy 326.034158 9.838567) (xy 326.07238 9.761807) (xy 326.103356 9.681848)
			(xy 326.126823 9.599372) (xy 326.142579 9.515082) (xy 326.150491 9.429699) (xy 326.150986 9.386824)
			(xy 326.150491 9.343949) (xy 330.645757 9.343949) (xy 330.645757 9.429699) (xy 330.653669 9.515082)
			(xy 330.669425 9.599372) (xy 330.692892 9.681848) (xy 330.723868 9.761807) (xy 330.76209 9.838567)
			(xy 330.807231 9.911473) (xy 330.858907 9.979902) (xy 330.916676 10.043272) (xy 330.980046 10.101041)
			(xy 331.048475 10.152717) (xy 331.121381 10.197858) (xy 331.198141 10.23608) (xy 331.2781 10.267056)
			(xy 331.360576 10.290523) (xy 331.444866 10.306279) (xy 331.530249 10.314191) (xy 331.615999 10.314191)
			(xy 331.701382 10.306279) (xy 331.785672 10.290523) (xy 331.868148 10.267056) (xy 331.948107 10.23608)
			(xy 332.024867 10.197858) (xy 332.097773 10.152717) (xy 332.166202 10.101041) (xy 332.229572 10.043272)
			(xy 332.287341 9.979902) (xy 332.339017 9.911473) (xy 332.384158 9.838567) (xy 332.42238 9.761807)
			(xy 332.453356 9.681848) (xy 332.476823 9.599372) (xy 332.492579 9.515082) (xy 332.500491 9.429699)
			(xy 332.500986 9.386824) (xy 332.50079 9.369857) (xy 382.496301 9.369857) (xy 382.496301 9.455607)
			(xy 382.504213 9.54099) (xy 382.519969 9.62528) (xy 382.543436 9.707756) (xy 382.574412 9.787715)
			(xy 382.612634 9.864475) (xy 382.657775 9.937381) (xy 382.709451 10.00581) (xy 382.76722 10.06918)
			(xy 382.83059 10.126949) (xy 382.899019 10.178625) (xy 382.971925 10.223766) (xy 383.048685 10.261988)
			(xy 383.128644 10.292964) (xy 383.21112 10.316431) (xy 383.29541 10.332187) (xy 383.380793 10.340099)
			(xy 383.466543 10.340099) (xy 383.551926 10.332187) (xy 383.636216 10.316431) (xy 383.718692 10.292964)
			(xy 383.798651 10.261988) (xy 383.820854 10.250932) (xy 385.002532 10.250932) (xy 385.002532 11.114532)
			(xy 385.003018 11.141801) (xy 385.01078 11.195785) (xy 385.026145 11.248115) (xy 385.048802 11.297725)
			(xy 385.078288 11.343606) (xy 385.114003 11.384823) (xy 385.15522 11.420538) (xy 385.201101 11.450024)
			(xy 385.250711 11.472681) (xy 385.303041 11.488046) (xy 385.357025 11.495808) (xy 385.411563 11.495808)
			(xy 385.465547 11.488046) (xy 385.517877 11.472681) (xy 385.567487 11.450024) (xy 385.613368 11.420538)
			(xy 385.654585 11.384823) (xy 385.6903 11.343606) (xy 385.719786 11.297725) (xy 385.742443 11.248115)
			(xy 385.757808 11.195785) (xy 385.76557 11.141801) (xy 385.766056 11.114532) (xy 385.766056 10.250932)
			(xy 385.76557 10.223663) (xy 385.757808 10.169679) (xy 385.742443 10.117349) (xy 385.719786 10.067739)
			(xy 385.6903 10.021858) (xy 385.654585 9.980641) (xy 385.613368 9.944926) (xy 385.567487 9.91544)
			(xy 385.517877 9.892783) (xy 385.465547 9.877418) (xy 385.411563 9.869656) (xy 385.357025 9.869656)
			(xy 385.303041 9.877418) (xy 385.250711 9.892783) (xy 385.201101 9.91544) (xy 385.15522 9.944926)
			(xy 385.114003 9.980641) (xy 385.078288 10.021858) (xy 385.048802 10.067739) (xy 385.026145 10.117349)
			(xy 385.01078 10.169679) (xy 385.003018 10.223663) (xy 385.002532 10.250932) (xy 383.820854 10.250932)
			(xy 383.875411 10.223766) (xy 383.948317 10.178625) (xy 384.016746 10.126949) (xy 384.080116 10.06918)
			(xy 384.137885 10.00581) (xy 384.189561 9.937381) (xy 384.234702 9.864475) (xy 384.272924 9.787715)
			(xy 384.3039 9.707756) (xy 384.327367 9.62528) (xy 384.343123 9.54099) (xy 384.351035 9.455607) (xy 384.35153 9.412732)
			(xy 384.351035 9.369857) (xy 388.846301 9.369857) (xy 388.846301 9.455607) (xy 388.854213 9.54099)
			(xy 388.869969 9.62528) (xy 388.893436 9.707756) (xy 388.924412 9.787715) (xy 388.962634 9.864475)
			(xy 389.007775 9.937381) (xy 389.059451 10.00581) (xy 389.11722 10.06918) (xy 389.18059 10.126949)
			(xy 389.249019 10.178625) (xy 389.321925 10.223766) (xy 389.398685 10.261988) (xy 389.478644 10.292964)
			(xy 389.56112 10.316431) (xy 389.64541 10.332187) (xy 389.730793 10.340099) (xy 389.816543 10.340099)
			(xy 389.901926 10.332187) (xy 389.986216 10.316431) (xy 390.068692 10.292964) (xy 390.148651 10.261988)
			(xy 390.225411 10.223766) (xy 390.298317 10.178625) (xy 390.366746 10.126949) (xy 390.430116 10.06918)
			(xy 390.487885 10.00581) (xy 390.539561 9.937381) (xy 390.584702 9.864475) (xy 390.622924 9.787715)
			(xy 390.6539 9.707756) (xy 390.677367 9.62528) (xy 390.693123 9.54099) (xy 390.701035 9.455607) (xy 390.70153 9.412732)
			(xy 390.701117 9.376969) (xy 396.558757 9.376969) (xy 396.558757 9.462719) (xy 396.566669 9.548102)
			(xy 396.582425 9.632392) (xy 396.605892 9.714868) (xy 396.636868 9.794827) (xy 396.67509 9.871587)
			(xy 396.720231 9.944493) (xy 396.771907 10.012922) (xy 396.829676 10.076292) (xy 396.893046 10.134061)
			(xy 396.961475 10.185737) (xy 397.034381 10.230878) (xy 397.111141 10.2691) (xy 397.1911 10.300076)
			(xy 397.273576 10.323543) (xy 397.357866 10.339299) (xy 397.443249 10.347211) (xy 397.528999 10.347211)
			(xy 397.614382 10.339299) (xy 397.698672 10.323543) (xy 397.781148 10.300076) (xy 397.861107 10.2691)
			(xy 397.88331 10.258044) (xy 401.493736 10.258044) (xy 401.493736 11.121644) (xy 401.494222 11.148913)
			(xy 401.501984 11.202897) (xy 401.517349 11.255227) (xy 401.540006 11.304837) (xy 401.569492 11.350718)
			(xy 401.605207 11.391935) (xy 401.646424 11.42765) (xy 401.692305 11.457136) (xy 401.741915 11.479793)
			(xy 401.794245 11.495158) (xy 401.848229 11.50292) (xy 401.902767 11.50292) (xy 401.956751 11.495158)
			(xy 402.009081 11.479793) (xy 402.058691 11.457136) (xy 402.104572 11.42765) (xy 402.145789 11.391935)
			(xy 402.181504 11.350718) (xy 402.21099 11.304837) (xy 402.233647 11.255227) (xy 402.249012 11.202897)
			(xy 402.256774 11.148913) (xy 402.25726 11.121644) (xy 402.25726 10.258044) (xy 402.256774 10.230775)
			(xy 402.249012 10.176791) (xy 402.233647 10.124461) (xy 402.21099 10.074851) (xy 402.181504 10.02897)
			(xy 402.145789 9.987753) (xy 402.104572 9.952038) (xy 402.058691 9.922552) (xy 402.009081 9.899895)
			(xy 401.956751 9.88453) (xy 401.902767 9.876768) (xy 401.848229 9.876768) (xy 401.794245 9.88453)
			(xy 401.741915 9.899895) (xy 401.692305 9.922552) (xy 401.646424 9.952038) (xy 401.605207 9.987753)
			(xy 401.569492 10.02897) (xy 401.540006 10.074851) (xy 401.517349 10.124461) (xy 401.501984 10.176791)
			(xy 401.494222 10.230775) (xy 401.493736 10.258044) (xy 397.88331 10.258044) (xy 397.937867 10.230878)
			(xy 398.010773 10.185737) (xy 398.079202 10.134061) (xy 398.142572 10.076292) (xy 398.200341 10.012922)
			(xy 398.252017 9.944493) (xy 398.297158 9.871587) (xy 398.33538 9.794827) (xy 398.366356 9.714868)
			(xy 398.389823 9.632392) (xy 398.405579 9.548102) (xy 398.413491 9.462719) (xy 398.413986 9.419844)
			(xy 398.413491 9.376969) (xy 402.908757 9.376969) (xy 402.908757 9.462719) (xy 402.916669 9.548102)
			(xy 402.932425 9.632392) (xy 402.955892 9.714868) (xy 402.986868 9.794827) (xy 403.02509 9.871587)
			(xy 403.070231 9.944493) (xy 403.121907 10.012922) (xy 403.179676 10.076292) (xy 403.243046 10.134061)
			(xy 403.311475 10.185737) (xy 403.384381 10.230878) (xy 403.461141 10.2691) (xy 403.5411 10.300076)
			(xy 403.623576 10.323543) (xy 403.707866 10.339299) (xy 403.793249 10.347211) (xy 403.878999 10.347211)
			(xy 403.964382 10.339299) (xy 404.048672 10.323543) (xy 404.131148 10.300076) (xy 404.211107 10.2691)
			(xy 404.287867 10.230878) (xy 404.360773 10.185737) (xy 404.429202 10.134061) (xy 404.492572 10.076292)
			(xy 404.550341 10.012922) (xy 404.602017 9.944493) (xy 404.647158 9.871587) (xy 404.68538 9.794827)
			(xy 404.716356 9.714868) (xy 404.739823 9.632392) (xy 404.755579 9.548102) (xy 404.763491 9.462719)
			(xy 404.763986 9.419844) (xy 404.76379 9.402877) (xy 454.759301 9.402877) (xy 454.759301 9.488627)
			(xy 454.767213 9.57401) (xy 454.782969 9.6583) (xy 454.806436 9.740776) (xy 454.837412 9.820735)
			(xy 454.875634 9.897495) (xy 454.920775 9.970401) (xy 454.972451 10.03883) (xy 455.03022 10.1022)
			(xy 455.09359 10.159969) (xy 455.162019 10.211645) (xy 455.234925 10.256786) (xy 455.311685 10.295008)
			(xy 455.391644 10.325984) (xy 455.47412 10.349451) (xy 455.55841 10.365207) (xy 455.643793 10.373119)
			(xy 455.729543 10.373119) (xy 455.814926 10.365207) (xy 455.899216 10.349451) (xy 455.981692 10.325984)
			(xy 456.061651 10.295008) (xy 456.083854 10.283952) (xy 457.265532 10.283952) (xy 457.265532 11.147552)
			(xy 457.266018 11.174821) (xy 457.27378 11.228805) (xy 457.289145 11.281135) (xy 457.311802 11.330745)
			(xy 457.341288 11.376626) (xy 457.377003 11.417843) (xy 457.41822 11.453558) (xy 457.464101 11.483044)
			(xy 457.513711 11.505701) (xy 457.566041 11.521066) (xy 457.620025 11.528828) (xy 457.674563 11.528828)
			(xy 457.728547 11.521066) (xy 457.780877 11.505701) (xy 457.830487 11.483044) (xy 457.876368 11.453558)
			(xy 457.917585 11.417843) (xy 457.9533 11.376626) (xy 457.982786 11.330745) (xy 458.005443 11.281135)
			(xy 458.020808 11.228805) (xy 458.02857 11.174821) (xy 458.029056 11.147552) (xy 458.029056 10.283952)
			(xy 458.02857 10.256683) (xy 458.020808 10.202699) (xy 458.005443 10.150369) (xy 457.982786 10.100759)
			(xy 457.9533 10.054878) (xy 457.917585 10.013661) (xy 457.876368 9.977946) (xy 457.830487 9.94846)
			(xy 457.780877 9.925803) (xy 457.728547 9.910438) (xy 457.674563 9.902676) (xy 457.620025 9.902676)
			(xy 457.566041 9.910438) (xy 457.513711 9.925803) (xy 457.464101 9.94846) (xy 457.41822 9.977946)
			(xy 457.377003 10.013661) (xy 457.341288 10.054878) (xy 457.311802 10.100759) (xy 457.289145 10.150369)
			(xy 457.27378 10.202699) (xy 457.266018 10.256683) (xy 457.265532 10.283952) (xy 456.083854 10.283952)
			(xy 456.138411 10.256786) (xy 456.211317 10.211645) (xy 456.279746 10.159969) (xy 456.343116 10.1022)
			(xy 456.400885 10.03883) (xy 456.452561 9.970401) (xy 456.497702 9.897495) (xy 456.535924 9.820735)
			(xy 456.5669 9.740776) (xy 456.590367 9.6583) (xy 456.606123 9.57401) (xy 456.614035 9.488627) (xy 456.61453 9.445752)
			(xy 456.614035 9.402877) (xy 461.109301 9.402877) (xy 461.109301 9.488627) (xy 461.117213 9.57401)
			(xy 461.132969 9.6583) (xy 461.156436 9.740776) (xy 461.187412 9.820735) (xy 461.225634 9.897495)
			(xy 461.270775 9.970401) (xy 461.322451 10.03883) (xy 461.38022 10.1022) (xy 461.44359 10.159969)
			(xy 461.512019 10.211645) (xy 461.584925 10.256786) (xy 461.661685 10.295008) (xy 461.741644 10.325984)
			(xy 461.82412 10.349451) (xy 461.90841 10.365207) (xy 461.993793 10.373119) (xy 462.079543 10.373119)
			(xy 462.164926 10.365207) (xy 462.249216 10.349451) (xy 462.331692 10.325984) (xy 462.411651 10.295008)
			(xy 462.488411 10.256786) (xy 462.561317 10.211645) (xy 462.629746 10.159969) (xy 462.693116 10.1022)
			(xy 462.750885 10.03883) (xy 462.802561 9.970401) (xy 462.847702 9.897495) (xy 462.885924 9.820735)
			(xy 462.9169 9.740776) (xy 462.940367 9.6583) (xy 462.956123 9.57401) (xy 462.964035 9.488627) (xy 462.96453 9.445752)
			(xy 462.964035 9.402877) (xy 462.956123 9.317494) (xy 462.940367 9.233204) (xy 462.9169 9.150728)
			(xy 462.885924 9.070769) (xy 462.847702 8.994009) (xy 462.802561 8.921103) (xy 462.750885 8.852674)
			(xy 462.693116 8.789304) (xy 462.629746 8.731535) (xy 462.561317 8.679859) (xy 462.488411 8.634718)
			(xy 462.411651 8.596496) (xy 462.331692 8.56552) (xy 462.249216 8.542053) (xy 462.164926 8.526297)
			(xy 462.079543 8.518385) (xy 461.993793 8.518385) (xy 461.90841 8.526297) (xy 461.82412 8.542053)
			(xy 461.741644 8.56552) (xy 461.661685 8.596496) (xy 461.584925 8.634718) (xy 461.512019 8.679859)
			(xy 461.44359 8.731535) (xy 461.38022 8.789304) (xy 461.322451 8.852674) (xy 461.270775 8.921103)
			(xy 461.225634 8.994009) (xy 461.187412 9.070769) (xy 461.156436 9.150728) (xy 461.132969 9.233204)
			(xy 461.117213 9.317494) (xy 461.109301 9.402877) (xy 456.614035 9.402877) (xy 456.606123 9.317494)
			(xy 456.590367 9.233204) (xy 456.5669 9.150728) (xy 456.535924 9.070769) (xy 456.497702 8.994009)
			(xy 456.452561 8.921103) (xy 456.400885 8.852674) (xy 456.343116 8.789304) (xy 456.279746 8.731535)
			(xy 456.211317 8.679859) (xy 456.138411 8.634718) (xy 456.061651 8.596496) (xy 455.981692 8.56552)
			(xy 455.899216 8.542053) (xy 455.814926 8.526297) (xy 455.729543 8.518385) (xy 455.643793 8.518385)
			(xy 455.55841 8.526297) (xy 455.47412 8.542053) (xy 455.391644 8.56552) (xy 455.311685 8.596496)
			(xy 455.234925 8.634718) (xy 455.162019 8.679859) (xy 455.09359 8.731535) (xy 455.03022 8.789304)
			(xy 454.972451 8.852674) (xy 454.920775 8.921103) (xy 454.875634 8.994009) (xy 454.837412 9.070769)
			(xy 454.806436 9.150728) (xy 454.782969 9.233204) (xy 454.767213 9.317494) (xy 454.759301 9.402877)
			(xy 404.76379 9.402877) (xy 404.763491 9.376969) (xy 404.755579 9.291586) (xy 404.739823 9.207296)
			(xy 404.716356 9.12482) (xy 404.68538 9.044861) (xy 404.647158 8.968101) (xy 404.602017 8.895195)
			(xy 404.550341 8.826766) (xy 404.492572 8.763396) (xy 404.429202 8.705627) (xy 404.360773 8.653951)
			(xy 404.287867 8.60881) (xy 404.211107 8.570588) (xy 404.131148 8.539612) (xy 404.048672 8.516145)
			(xy 403.964382 8.500389) (xy 403.878999 8.492477) (xy 403.793249 8.492477) (xy 403.707866 8.500389)
			(xy 403.623576 8.516145) (xy 403.5411 8.539612) (xy 403.461141 8.570588) (xy 403.384381 8.60881)
			(xy 403.311475 8.653951) (xy 403.243046 8.705627) (xy 403.179676 8.763396) (xy 403.121907 8.826766)
			(xy 403.070231 8.895195) (xy 403.02509 8.968101) (xy 402.986868 9.044861) (xy 402.955892 9.12482)
			(xy 402.932425 9.207296) (xy 402.916669 9.291586) (xy 402.908757 9.376969) (xy 398.413491 9.376969)
			(xy 398.405579 9.291586) (xy 398.389823 9.207296) (xy 398.366356 9.12482) (xy 398.33538 9.044861)
			(xy 398.297158 8.968101) (xy 398.252017 8.895195) (xy 398.200341 8.826766) (xy 398.142572 8.763396)
			(xy 398.079202 8.705627) (xy 398.010773 8.653951) (xy 397.937867 8.60881) (xy 397.861107 8.570588)
			(xy 397.781148 8.539612) (xy 397.698672 8.516145) (xy 397.614382 8.500389) (xy 397.528999 8.492477)
			(xy 397.443249 8.492477) (xy 397.357866 8.500389) (xy 397.273576 8.516145) (xy 397.1911 8.539612)
			(xy 397.111141 8.570588) (xy 397.034381 8.60881) (xy 396.961475 8.653951) (xy 396.893046 8.705627)
			(xy 396.829676 8.763396) (xy 396.771907 8.826766) (xy 396.720231 8.895195) (xy 396.67509 8.968101)
			(xy 396.636868 9.044861) (xy 396.605892 9.12482) (xy 396.582425 9.207296) (xy 396.566669 9.291586)
			(xy 396.558757 9.376969) (xy 390.701117 9.376969) (xy 390.701035 9.369857) (xy 390.693123 9.284474)
			(xy 390.677367 9.200184) (xy 390.6539 9.117708) (xy 390.622924 9.037749) (xy 390.584702 8.960989)
			(xy 390.539561 8.888083) (xy 390.487885 8.819654) (xy 390.430116 8.756284) (xy 390.366746 8.698515)
			(xy 390.298317 8.646839) (xy 390.225411 8.601698) (xy 390.148651 8.563476) (xy 390.068692 8.5325)
			(xy 389.986216 8.509033) (xy 389.901926 8.493277) (xy 389.816543 8.485365) (xy 389.730793 8.485365)
			(xy 389.64541 8.493277) (xy 389.56112 8.509033) (xy 389.478644 8.5325) (xy 389.398685 8.563476) (xy 389.321925 8.601698)
			(xy 389.249019 8.646839) (xy 389.18059 8.698515) (xy 389.11722 8.756284) (xy 389.059451 8.819654)
			(xy 389.007775 8.888083) (xy 388.962634 8.960989) (xy 388.924412 9.037749) (xy 388.893436 9.117708)
			(xy 388.869969 9.200184) (xy 388.854213 9.284474) (xy 388.846301 9.369857) (xy 384.351035 9.369857)
			(xy 384.343123 9.284474) (xy 384.327367 9.200184) (xy 384.3039 9.117708) (xy 384.272924 9.037749)
			(xy 384.234702 8.960989) (xy 384.189561 8.888083) (xy 384.137885 8.819654) (xy 384.080116 8.756284)
			(xy 384.016746 8.698515) (xy 383.948317 8.646839) (xy 383.875411 8.601698) (xy 383.798651 8.563476)
			(xy 383.718692 8.5325) (xy 383.636216 8.509033) (xy 383.551926 8.493277) (xy 383.466543 8.485365)
			(xy 383.380793 8.485365) (xy 383.29541 8.493277) (xy 383.21112 8.509033) (xy 383.128644 8.5325) (xy 383.048685 8.563476)
			(xy 382.971925 8.601698) (xy 382.899019 8.646839) (xy 382.83059 8.698515) (xy 382.76722 8.756284)
			(xy 382.709451 8.819654) (xy 382.657775 8.888083) (xy 382.612634 8.960989) (xy 382.574412 9.037749)
			(xy 382.543436 9.117708) (xy 382.519969 9.200184) (xy 382.504213 9.284474) (xy 382.496301 9.369857)
			(xy 332.50079 9.369857) (xy 332.500491 9.343949) (xy 332.492579 9.258566) (xy 332.476823 9.174276)
			(xy 332.453356 9.0918) (xy 332.42238 9.011841) (xy 332.384158 8.935081) (xy 332.339017 8.862175)
			(xy 332.287341 8.793746) (xy 332.229572 8.730376) (xy 332.166202 8.672607) (xy 332.097773 8.620931)
			(xy 332.024867 8.57579) (xy 331.948107 8.537568) (xy 331.868148 8.506592) (xy 331.785672 8.483125)
			(xy 331.701382 8.467369) (xy 331.615999 8.459457) (xy 331.530249 8.459457) (xy 331.444866 8.467369)
			(xy 331.360576 8.483125) (xy 331.2781 8.506592) (xy 331.198141 8.537568) (xy 331.121381 8.57579)
			(xy 331.048475 8.620931) (xy 330.980046 8.672607) (xy 330.916676 8.730376) (xy 330.858907 8.793746)
			(xy 330.807231 8.862175) (xy 330.76209 8.935081) (xy 330.723868 9.011841) (xy 330.692892 9.0918)
			(xy 330.669425 9.174276) (xy 330.653669 9.258566) (xy 330.645757 9.343949) (xy 326.150491 9.343949)
			(xy 326.142579 9.258566) (xy 326.126823 9.174276) (xy 326.103356 9.0918) (xy 326.07238 9.011841)
			(xy 326.034158 8.935081) (xy 325.989017 8.862175) (xy 325.937341 8.793746) (xy 325.879572 8.730376)
			(xy 325.816202 8.672607) (xy 325.747773 8.620931) (xy 325.674867 8.57579) (xy 325.598107 8.537568)
			(xy 325.518148 8.506592) (xy 325.435672 8.483125) (xy 325.351382 8.467369) (xy 325.265999 8.459457)
			(xy 325.180249 8.459457) (xy 325.094866 8.467369) (xy 325.010576 8.483125) (xy 324.9281 8.506592)
			(xy 324.848141 8.537568) (xy 324.771381 8.57579) (xy 324.698475 8.620931) (xy 324.630046 8.672607)
			(xy 324.566676 8.730376) (xy 324.508907 8.793746) (xy 324.457231 8.862175) (xy 324.41209 8.935081)
			(xy 324.373868 9.011841) (xy 324.342892 9.0918) (xy 324.319425 9.174276) (xy 324.303669 9.258566)
			(xy 324.295757 9.343949) (xy 317.930117 9.343949) (xy 317.930035 9.336837) (xy 317.922123 9.251454)
			(xy 317.906367 9.167164) (xy 317.8829 9.084688) (xy 317.851924 9.004729) (xy 317.813702 8.927969)
			(xy 317.768561 8.855063) (xy 317.716885 8.786634) (xy 317.659116 8.723264) (xy 317.595746 8.665495)
			(xy 317.527317 8.613819) (xy 317.454411 8.568678) (xy 317.377651 8.530456) (xy 317.297692 8.49948)
			(xy 317.215216 8.476013) (xy 317.130926 8.460257) (xy 317.045543 8.452345) (xy 316.959793 8.452345)
			(xy 316.87441 8.460257) (xy 316.79012 8.476013) (xy 316.707644 8.49948) (xy 316.627685 8.530456)
			(xy 316.550925 8.568678) (xy 316.478019 8.613819) (xy 316.40959 8.665495) (xy 316.34622 8.723264)
			(xy 316.288451 8.786634) (xy 316.236775 8.855063) (xy 316.191634 8.927969) (xy 316.153412 9.004729)
			(xy 316.122436 9.084688) (xy 316.098969 9.167164) (xy 316.083213 9.251454) (xy 316.075301 9.336837)
			(xy 311.580035 9.336837) (xy 311.572123 9.251454) (xy 311.556367 9.167164) (xy 311.5329 9.084688)
			(xy 311.501924 9.004729) (xy 311.463702 8.927969) (xy 311.418561 8.855063) (xy 311.366885 8.786634)
			(xy 311.309116 8.723264) (xy 311.245746 8.665495) (xy 311.177317 8.613819) (xy 311.104411 8.568678)
			(xy 311.027651 8.530456) (xy 310.947692 8.49948) (xy 310.865216 8.476013) (xy 310.780926 8.460257)
			(xy 310.695543 8.452345) (xy 310.609793 8.452345) (xy 310.52441 8.460257) (xy 310.44012 8.476013)
			(xy 310.357644 8.49948) (xy 310.277685 8.530456) (xy 310.200925 8.568678) (xy 310.128019 8.613819)
			(xy 310.05959 8.665495) (xy 309.99622 8.723264) (xy 309.938451 8.786634) (xy 309.886775 8.855063)
			(xy 309.841634 8.927969) (xy 309.803412 9.004729) (xy 309.772436 9.084688) (xy 309.748969 9.167164)
			(xy 309.733213 9.251454) (xy 309.725301 9.336837) (xy 259.72979 9.336837) (xy 259.729491 9.310929)
			(xy 259.721579 9.225546) (xy 259.705823 9.141256) (xy 259.682356 9.05878) (xy 259.65138 8.978821)
			(xy 259.613158 8.902061) (xy 259.568017 8.829155) (xy 259.516341 8.760726) (xy 259.458572 8.697356)
			(xy 259.395202 8.639587) (xy 259.326773 8.587911) (xy 259.253867 8.54277) (xy 259.177107 8.504548)
			(xy 259.097148 8.473572) (xy 259.014672 8.450105) (xy 258.930382 8.434349) (xy 258.844999 8.426437)
			(xy 258.759249 8.426437) (xy 258.673866 8.434349) (xy 258.589576 8.450105) (xy 258.5071 8.473572)
			(xy 258.427141 8.504548) (xy 258.350381 8.54277) (xy 258.277475 8.587911) (xy 258.209046 8.639587)
			(xy 258.145676 8.697356) (xy 258.087907 8.760726) (xy 258.036231 8.829155) (xy 257.99109 8.902061)
			(xy 257.952868 8.978821) (xy 257.921892 9.05878) (xy 257.898425 9.141256) (xy 257.882669 9.225546)
			(xy 257.874757 9.310929) (xy 253.379491 9.310929) (xy 253.371579 9.225546) (xy 253.355823 9.141256)
			(xy 253.332356 9.05878) (xy 253.30138 8.978821) (xy 253.263158 8.902061) (xy 253.218017 8.829155)
			(xy 253.166341 8.760726) (xy 253.108572 8.697356) (xy 253.045202 8.639587) (xy 252.976773 8.587911)
			(xy 252.903867 8.54277) (xy 252.827107 8.504548) (xy 252.747148 8.473572) (xy 252.664672 8.450105)
			(xy 252.580382 8.434349) (xy 252.494999 8.426437) (xy 252.409249 8.426437) (xy 252.323866 8.434349)
			(xy 252.239576 8.450105) (xy 252.1571 8.473572) (xy 252.077141 8.504548) (xy 252.000381 8.54277)
			(xy 251.927475 8.587911) (xy 251.859046 8.639587) (xy 251.795676 8.697356) (xy 251.737907 8.760726)
			(xy 251.686231 8.829155) (xy 251.64109 8.902061) (xy 251.602868 8.978821) (xy 251.571892 9.05878)
			(xy 251.548425 9.141256) (xy 251.532669 9.225546) (xy 251.524757 9.310929) (xy 245.921117 9.310929)
			(xy 245.921035 9.303817) (xy 245.913123 9.218434) (xy 245.897367 9.134144) (xy 245.8739 9.051668)
			(xy 245.842924 8.971709) (xy 245.804702 8.894949) (xy 245.759561 8.822043) (xy 245.707885 8.753614)
			(xy 245.650116 8.690244) (xy 245.586746 8.632475) (xy 245.518317 8.580799) (xy 245.445411 8.535658)
			(xy 245.368651 8.497436) (xy 245.288692 8.46646) (xy 245.206216 8.442993) (xy 245.121926 8.427237)
			(xy 245.036543 8.419325) (xy 244.950793 8.419325) (xy 244.86541 8.427237) (xy 244.78112 8.442993)
			(xy 244.698644 8.46646) (xy 244.618685 8.497436) (xy 244.541925 8.535658) (xy 244.469019 8.580799)
			(xy 244.40059 8.632475) (xy 244.33722 8.690244) (xy 244.279451 8.753614) (xy 244.227775 8.822043)
			(xy 244.182634 8.894949) (xy 244.144412 8.971709) (xy 244.113436 9.051668) (xy 244.089969 9.134144)
			(xy 244.074213 9.218434) (xy 244.066301 9.303817) (xy 239.571035 9.303817) (xy 239.563123 9.218434)
			(xy 239.547367 9.134144) (xy 239.5239 9.051668) (xy 239.492924 8.971709) (xy 239.454702 8.894949)
			(xy 239.409561 8.822043) (xy 239.357885 8.753614) (xy 239.300116 8.690244) (xy 239.236746 8.632475)
			(xy 239.168317 8.580799) (xy 239.095411 8.535658) (xy 239.018651 8.497436) (xy 238.938692 8.46646)
			(xy 238.856216 8.442993) (xy 238.771926 8.427237) (xy 238.686543 8.419325) (xy 238.600793 8.419325)
			(xy 238.51541 8.427237) (xy 238.43112 8.442993) (xy 238.348644 8.46646) (xy 238.268685 8.497436)
			(xy 238.191925 8.535658) (xy 238.119019 8.580799) (xy 238.05059 8.632475) (xy 237.98722 8.690244)
			(xy 237.929451 8.753614) (xy 237.877775 8.822043) (xy 237.832634 8.894949) (xy 237.794412 8.971709)
			(xy 237.763436 9.051668) (xy 237.739969 9.134144) (xy 237.724213 9.218434) (xy 237.716301 9.303817)
			(xy 187.719832 9.303817) (xy 187.712579 9.225546) (xy 187.696823 9.141256) (xy 187.673356 9.05878)
			(xy 187.64238 8.978821) (xy 187.604158 8.902061) (xy 187.559017 8.829155) (xy 187.507341 8.760726)
			(xy 187.449572 8.697356) (xy 187.386202 8.639587) (xy 187.317773 8.587911) (xy 187.244867 8.54277)
			(xy 187.168107 8.504548) (xy 187.088148 8.473572) (xy 187.005672 8.450105) (xy 186.921382 8.434349)
			(xy 186.835999 8.426437) (xy 186.750249 8.426437) (xy 186.664866 8.434349) (xy 186.580576 8.450105)
			(xy 186.4981 8.473572) (xy 186.418141 8.504548) (xy 186.341381 8.54277) (xy 186.268475 8.587911)
			(xy 186.200046 8.639587) (xy 186.136676 8.697356) (xy 186.078907 8.760726) (xy 186.027231 8.829155)
			(xy 185.98209 8.902061) (xy 185.943868 8.978821) (xy 185.912892 9.05878) (xy 185.889425 9.141256)
			(xy 185.873669 9.225546) (xy 185.865757 9.310929) (xy 181.370491 9.310929) (xy 181.362579 9.225546)
			(xy 181.346823 9.141256) (xy 181.323356 9.05878) (xy 181.29238 8.978821) (xy 181.254158 8.902061)
			(xy 181.209017 8.829155) (xy 181.157341 8.760726) (xy 181.099572 8.697356) (xy 181.036202 8.639587)
			(xy 180.967773 8.587911) (xy 180.894867 8.54277) (xy 180.818107 8.504548) (xy 180.738148 8.473572)
			(xy 180.655672 8.450105) (xy 180.571382 8.434349) (xy 180.485999 8.426437) (xy 180.400249 8.426437)
			(xy 180.314866 8.434349) (xy 180.230576 8.450105) (xy 180.1481 8.473572) (xy 180.068141 8.504548)
			(xy 179.991381 8.54277) (xy 179.918475 8.587911) (xy 179.850046 8.639587) (xy 179.786676 8.697356)
			(xy 179.728907 8.760726) (xy 179.677231 8.829155) (xy 179.63209 8.902061) (xy 179.593868 8.978821)
			(xy 179.562892 9.05878) (xy 179.539425 9.141256) (xy 179.523669 9.225546) (xy 179.515757 9.310929)
			(xy 158.621984 9.310929) (xy 158.621984 8.377682) (xy 158.62149 8.307329) (xy 158.6136 8.166844)
			(xy 158.597845 8.027022) (xy 158.574274 7.888303) (xy 158.542963 7.751125) (xy 158.50401 7.615918)
			(xy 158.457537 7.483107) (xy 158.40369 7.353112) (xy 158.342638 7.22634) (xy 158.274575 7.103191)
			(xy 158.199714 6.984051) (xy 158.11829 6.869297) (xy 158.039844 6.770929) (xy 179.515757 6.770929)
			(xy 179.515757 6.856679) (xy 179.523669 6.942062) (xy 179.539425 7.026352) (xy 179.562892 7.108828)
			(xy 179.593868 7.188787) (xy 179.63209 7.265547) (xy 179.677231 7.338453) (xy 179.728907 7.406882)
			(xy 179.786676 7.470252) (xy 179.850046 7.528021) (xy 179.918475 7.579697) (xy 179.991381 7.624838)
			(xy 180.068141 7.66306) (xy 180.1481 7.694036) (xy 180.230576 7.717503) (xy 180.314866 7.733259)
			(xy 180.400249 7.741171) (xy 180.485999 7.741171) (xy 180.571382 7.733259) (xy 180.655672 7.717503)
			(xy 180.738148 7.694036) (xy 180.818107 7.66306) (xy 180.894867 7.624838) (xy 180.967773 7.579697)
			(xy 181.036202 7.528021) (xy 181.099572 7.470252) (xy 181.157341 7.406882) (xy 181.209017 7.338453)
			(xy 181.254158 7.265547) (xy 181.29238 7.188787) (xy 181.323356 7.108828) (xy 181.346823 7.026352)
			(xy 181.362579 6.942062) (xy 181.370491 6.856679) (xy 181.370986 6.813804) (xy 181.370491 6.770929)
			(xy 185.865757 6.770929) (xy 185.865757 6.856679) (xy 185.873669 6.942062) (xy 185.889425 7.026352)
			(xy 185.912892 7.108828) (xy 185.943868 7.188787) (xy 185.98209 7.265547) (xy 186.027231 7.338453)
			(xy 186.078907 7.406882) (xy 186.136676 7.470252) (xy 186.200046 7.528021) (xy 186.268475 7.579697)
			(xy 186.341381 7.624838) (xy 186.418141 7.66306) (xy 186.4981 7.694036) (xy 186.580576 7.717503)
			(xy 186.664866 7.733259) (xy 186.750249 7.741171) (xy 186.835999 7.741171) (xy 186.921382 7.733259)
			(xy 187.005672 7.717503) (xy 187.088148 7.694036) (xy 187.168107 7.66306) (xy 187.244867 7.624838)
			(xy 187.317773 7.579697) (xy 187.386202 7.528021) (xy 187.449572 7.470252) (xy 187.507341 7.406882)
			(xy 187.559017 7.338453) (xy 187.604158 7.265547) (xy 187.64238 7.188787) (xy 187.673356 7.108828)
			(xy 187.696823 7.026352) (xy 187.712579 6.942062) (xy 187.720491 6.856679) (xy 187.720986 6.813804)
			(xy 187.720491 6.770929) (xy 187.719832 6.763817) (xy 237.716301 6.763817) (xy 237.716301 6.849567)
			(xy 237.724213 6.93495) (xy 237.739969 7.01924) (xy 237.763436 7.101716) (xy 237.794412 7.181675)
			(xy 237.832634 7.258435) (xy 237.877775 7.331341) (xy 237.929451 7.39977) (xy 237.98722 7.46314)
			(xy 238.05059 7.520909) (xy 238.119019 7.572585) (xy 238.191925 7.617726) (xy 238.268685 7.655948)
			(xy 238.348644 7.686924) (xy 238.43112 7.710391) (xy 238.51541 7.726147) (xy 238.600793 7.734059)
			(xy 238.686543 7.734059) (xy 238.771926 7.726147) (xy 238.856216 7.710391) (xy 238.938692 7.686924)
			(xy 239.018651 7.655948) (xy 239.095411 7.617726) (xy 239.168317 7.572585) (xy 239.236746 7.520909)
			(xy 239.300116 7.46314) (xy 239.357885 7.39977) (xy 239.409561 7.331341) (xy 239.454702 7.258435)
			(xy 239.492924 7.181675) (xy 239.5239 7.101716) (xy 239.547367 7.01924) (xy 239.563123 6.93495) (xy 239.571035 6.849567)
			(xy 239.57153 6.806692) (xy 239.571035 6.763817) (xy 244.066301 6.763817) (xy 244.066301 6.849567)
			(xy 244.074213 6.93495) (xy 244.089969 7.01924) (xy 244.113436 7.101716) (xy 244.144412 7.181675)
			(xy 244.182634 7.258435) (xy 244.227775 7.331341) (xy 244.279451 7.39977) (xy 244.33722 7.46314)
			(xy 244.40059 7.520909) (xy 244.469019 7.572585) (xy 244.541925 7.617726) (xy 244.618685 7.655948)
			(xy 244.698644 7.686924) (xy 244.78112 7.710391) (xy 244.86541 7.726147) (xy 244.950793 7.734059)
			(xy 245.036543 7.734059) (xy 245.121926 7.726147) (xy 245.206216 7.710391) (xy 245.288692 7.686924)
			(xy 245.368651 7.655948) (xy 245.445411 7.617726) (xy 245.518317 7.572585) (xy 245.586746 7.520909)
			(xy 245.650116 7.46314) (xy 245.707885 7.39977) (xy 245.759561 7.331341) (xy 245.804702 7.258435)
			(xy 245.842924 7.181675) (xy 245.8739 7.101716) (xy 245.897367 7.01924) (xy 245.913123 6.93495) (xy 245.921035 6.849567)
			(xy 245.92153 6.806692) (xy 245.921117 6.770929) (xy 251.524757 6.770929) (xy 251.524757 6.856679)
			(xy 251.532669 6.942062) (xy 251.548425 7.026352) (xy 251.571892 7.108828) (xy 251.602868 7.188787)
			(xy 251.64109 7.265547) (xy 251.686231 7.338453) (xy 251.737907 7.406882) (xy 251.795676 7.470252)
			(xy 251.859046 7.528021) (xy 251.927475 7.579697) (xy 252.000381 7.624838) (xy 252.077141 7.66306)
			(xy 252.1571 7.694036) (xy 252.239576 7.717503) (xy 252.323866 7.733259) (xy 252.409249 7.741171)
			(xy 252.494999 7.741171) (xy 252.580382 7.733259) (xy 252.664672 7.717503) (xy 252.747148 7.694036)
			(xy 252.827107 7.66306) (xy 252.84931 7.652004) (xy 256.459736 7.652004) (xy 256.459736 8.515604)
			(xy 256.460222 8.542873) (xy 256.467984 8.596857) (xy 256.483349 8.649187) (xy 256.506006 8.698797)
			(xy 256.535492 8.744678) (xy 256.571207 8.785895) (xy 256.612424 8.82161) (xy 256.658305 8.851096)
			(xy 256.707915 8.873753) (xy 256.760245 8.889118) (xy 256.814229 8.89688) (xy 256.868767 8.89688)
			(xy 256.922751 8.889118) (xy 256.975081 8.873753) (xy 257.024691 8.851096) (xy 257.070572 8.82161)
			(xy 257.111789 8.785895) (xy 257.147504 8.744678) (xy 257.17699 8.698797) (xy 257.199647 8.649187)
			(xy 257.215012 8.596857) (xy 257.222774 8.542873) (xy 257.22326 8.515604) (xy 257.22326 7.652004)
			(xy 257.222774 7.624735) (xy 257.215012 7.570751) (xy 257.199647 7.518421) (xy 257.17699 7.468811)
			(xy 257.147504 7.42293) (xy 257.111789 7.381713) (xy 257.070572 7.345998) (xy 257.024691 7.316512)
			(xy 256.975081 7.293855) (xy 256.922751 7.27849) (xy 256.868767 7.270728) (xy 256.814229 7.270728)
			(xy 256.760245 7.27849) (xy 256.707915 7.293855) (xy 256.658305 7.316512) (xy 256.612424 7.345998)
			(xy 256.571207 7.381713) (xy 256.535492 7.42293) (xy 256.506006 7.468811) (xy 256.483349 7.518421)
			(xy 256.467984 7.570751) (xy 256.460222 7.624735) (xy 256.459736 7.652004) (xy 252.84931 7.652004)
			(xy 252.903867 7.624838) (xy 252.976773 7.579697) (xy 253.045202 7.528021) (xy 253.108572 7.470252)
			(xy 253.166341 7.406882) (xy 253.218017 7.338453) (xy 253.263158 7.265547) (xy 253.30138 7.188787)
			(xy 253.332356 7.108828) (xy 253.355823 7.026352) (xy 253.371579 6.942062) (xy 253.379491 6.856679)
			(xy 253.379986 6.813804) (xy 253.379491 6.770929) (xy 257.874757 6.770929) (xy 257.874757 6.856679)
			(xy 257.882669 6.942062) (xy 257.898425 7.026352) (xy 257.921892 7.108828) (xy 257.952868 7.188787)
			(xy 257.99109 7.265547) (xy 258.036231 7.338453) (xy 258.087907 7.406882) (xy 258.145676 7.470252)
			(xy 258.209046 7.528021) (xy 258.277475 7.579697) (xy 258.350381 7.624838) (xy 258.427141 7.66306)
			(xy 258.5071 7.694036) (xy 258.589576 7.717503) (xy 258.673866 7.733259) (xy 258.759249 7.741171)
			(xy 258.844999 7.741171) (xy 258.930382 7.733259) (xy 259.014672 7.717503) (xy 259.097148 7.694036)
			(xy 259.177107 7.66306) (xy 259.253867 7.624838) (xy 259.326773 7.579697) (xy 259.395202 7.528021)
			(xy 259.458572 7.470252) (xy 259.516341 7.406882) (xy 259.568017 7.338453) (xy 259.613158 7.265547)
			(xy 259.65138 7.188787) (xy 259.682356 7.108828) (xy 259.705823 7.026352) (xy 259.721579 6.942062)
			(xy 259.729491 6.856679) (xy 259.729986 6.813804) (xy 259.72979 6.796837) (xy 309.725301 6.796837)
			(xy 309.725301 6.882587) (xy 309.733213 6.96797) (xy 309.748969 7.05226) (xy 309.772436 7.134736)
			(xy 309.803412 7.214695) (xy 309.841634 7.291455) (xy 309.886775 7.364361) (xy 309.938451 7.43279)
			(xy 309.99622 7.49616) (xy 310.05959 7.553929) (xy 310.128019 7.605605) (xy 310.200925 7.650746)
			(xy 310.277685 7.688968) (xy 310.357644 7.719944) (xy 310.44012 7.743411) (xy 310.52441 7.759167)
			(xy 310.609793 7.767079) (xy 310.695543 7.767079) (xy 310.780926 7.759167) (xy 310.865216 7.743411)
			(xy 310.947692 7.719944) (xy 311.027651 7.688968) (xy 311.049854 7.677912) (xy 312.231532 7.677912)
			(xy 312.231532 8.541512) (xy 312.232018 8.568781) (xy 312.23978 8.622765) (xy 312.255145 8.675095)
			(xy 312.277802 8.724705) (xy 312.307288 8.770586) (xy 312.343003 8.811803) (xy 312.38422 8.847518)
			(xy 312.430101 8.877004) (xy 312.479711 8.899661) (xy 312.532041 8.915026) (xy 312.586025 8.922788)
			(xy 312.640563 8.922788) (xy 312.694547 8.915026) (xy 312.746877 8.899661) (xy 312.796487 8.877004)
			(xy 312.842368 8.847518) (xy 312.883585 8.811803) (xy 312.9193 8.770586) (xy 312.948786 8.724705)
			(xy 312.971443 8.675095) (xy 312.986808 8.622765) (xy 312.99457 8.568781) (xy 312.995056 8.541512)
			(xy 312.995056 7.677912) (xy 312.99457 7.650643) (xy 312.986808 7.596659) (xy 312.971443 7.544329)
			(xy 312.948786 7.494719) (xy 312.9193 7.448838) (xy 312.883585 7.407621) (xy 312.842368 7.371906)
			(xy 312.796487 7.34242) (xy 312.746877 7.319763) (xy 312.694547 7.304398) (xy 312.640563 7.296636)
			(xy 312.586025 7.296636) (xy 312.532041 7.304398) (xy 312.479711 7.319763) (xy 312.430101 7.34242)
			(xy 312.38422 7.371906) (xy 312.343003 7.407621) (xy 312.307288 7.448838) (xy 312.277802 7.494719)
			(xy 312.255145 7.544329) (xy 312.23978 7.596659) (xy 312.232018 7.650643) (xy 312.231532 7.677912)
			(xy 311.049854 7.677912) (xy 311.104411 7.650746) (xy 311.177317 7.605605) (xy 311.245746 7.553929)
			(xy 311.309116 7.49616) (xy 311.366885 7.43279) (xy 311.418561 7.364361) (xy 311.463702 7.291455)
			(xy 311.501924 7.214695) (xy 311.5329 7.134736) (xy 311.556367 7.05226) (xy 311.572123 6.96797) (xy 311.580035 6.882587)
			(xy 311.58053 6.839712) (xy 311.580035 6.796837) (xy 316.075301 6.796837) (xy 316.075301 6.882587)
			(xy 316.083213 6.96797) (xy 316.098969 7.05226) (xy 316.122436 7.134736) (xy 316.153412 7.214695)
			(xy 316.191634 7.291455) (xy 316.236775 7.364361) (xy 316.288451 7.43279) (xy 316.34622 7.49616)
			(xy 316.40959 7.553929) (xy 316.478019 7.605605) (xy 316.550925 7.650746) (xy 316.627685 7.688968)
			(xy 316.707644 7.719944) (xy 316.79012 7.743411) (xy 316.87441 7.759167) (xy 316.959793 7.767079)
			(xy 317.045543 7.767079) (xy 317.130926 7.759167) (xy 317.215216 7.743411) (xy 317.297692 7.719944)
			(xy 317.377651 7.688968) (xy 317.454411 7.650746) (xy 317.527317 7.605605) (xy 317.595746 7.553929)
			(xy 317.659116 7.49616) (xy 317.716885 7.43279) (xy 317.768561 7.364361) (xy 317.813702 7.291455)
			(xy 317.851924 7.214695) (xy 317.8829 7.134736) (xy 317.906367 7.05226) (xy 317.922123 6.96797) (xy 317.930035 6.882587)
			(xy 317.93053 6.839712) (xy 317.930117 6.803949) (xy 324.295757 6.803949) (xy 324.295757 6.889699)
			(xy 324.303669 6.975082) (xy 324.319425 7.059372) (xy 324.342892 7.141848) (xy 324.373868 7.221807)
			(xy 324.41209 7.298567) (xy 324.457231 7.371473) (xy 324.508907 7.439902) (xy 324.566676 7.503272)
			(xy 324.630046 7.561041) (xy 324.698475 7.612717) (xy 324.771381 7.657858) (xy 324.848141 7.69608)
			(xy 324.9281 7.727056) (xy 325.010576 7.750523) (xy 325.094866 7.766279) (xy 325.180249 7.774191)
			(xy 325.265999 7.774191) (xy 325.351382 7.766279) (xy 325.435672 7.750523) (xy 325.518148 7.727056)
			(xy 325.598107 7.69608) (xy 325.62031 7.685024) (xy 329.230736 7.685024) (xy 329.230736 8.548624)
			(xy 329.231222 8.575893) (xy 329.238984 8.629877) (xy 329.254349 8.682207) (xy 329.277006 8.731817)
			(xy 329.306492 8.777698) (xy 329.342207 8.818915) (xy 329.383424 8.85463) (xy 329.429305 8.884116)
			(xy 329.478915 8.906773) (xy 329.531245 8.922138) (xy 329.585229 8.9299) (xy 329.639767 8.9299) (xy 329.693751 8.922138)
			(xy 329.746081 8.906773) (xy 329.795691 8.884116) (xy 329.841572 8.85463) (xy 329.882789 8.818915)
			(xy 329.918504 8.777698) (xy 329.94799 8.731817) (xy 329.970647 8.682207) (xy 329.986012 8.629877)
			(xy 329.993774 8.575893) (xy 329.99426 8.548624) (xy 329.99426 7.685024) (xy 329.993774 7.657755)
			(xy 329.986012 7.603771) (xy 329.970647 7.551441) (xy 329.94799 7.501831) (xy 329.918504 7.45595)
			(xy 329.882789 7.414733) (xy 329.841572 7.379018) (xy 329.795691 7.349532) (xy 329.746081 7.326875)
			(xy 329.693751 7.31151) (xy 329.639767 7.303748) (xy 329.585229 7.303748) (xy 329.531245 7.31151)
			(xy 329.478915 7.326875) (xy 329.429305 7.349532) (xy 329.383424 7.379018) (xy 329.342207 7.414733)
			(xy 329.306492 7.45595) (xy 329.277006 7.501831) (xy 329.254349 7.551441) (xy 329.238984 7.603771)
			(xy 329.231222 7.657755) (xy 329.230736 7.685024) (xy 325.62031 7.685024) (xy 325.674867 7.657858)
			(xy 325.747773 7.612717) (xy 325.816202 7.561041) (xy 325.879572 7.503272) (xy 325.937341 7.439902)
			(xy 325.989017 7.371473) (xy 326.034158 7.298567) (xy 326.07238 7.221807) (xy 326.103356 7.141848)
			(xy 326.126823 7.059372) (xy 326.142579 6.975082) (xy 326.150491 6.889699) (xy 326.150986 6.846824)
			(xy 326.150491 6.803949) (xy 330.645757 6.803949) (xy 330.645757 6.889699) (xy 330.653669 6.975082)
			(xy 330.669425 7.059372) (xy 330.692892 7.141848) (xy 330.723868 7.221807) (xy 330.76209 7.298567)
			(xy 330.807231 7.371473) (xy 330.858907 7.439902) (xy 330.916676 7.503272) (xy 330.980046 7.561041)
			(xy 331.048475 7.612717) (xy 331.121381 7.657858) (xy 331.198141 7.69608) (xy 331.2781 7.727056)
			(xy 331.360576 7.750523) (xy 331.444866 7.766279) (xy 331.530249 7.774191) (xy 331.615999 7.774191)
			(xy 331.701382 7.766279) (xy 331.785672 7.750523) (xy 331.868148 7.727056) (xy 331.948107 7.69608)
			(xy 332.024867 7.657858) (xy 332.097773 7.612717) (xy 332.166202 7.561041) (xy 332.229572 7.503272)
			(xy 332.287341 7.439902) (xy 332.339017 7.371473) (xy 332.384158 7.298567) (xy 332.42238 7.221807)
			(xy 332.453356 7.141848) (xy 332.476823 7.059372) (xy 332.492579 6.975082) (xy 332.500491 6.889699)
			(xy 332.500986 6.846824) (xy 332.50079 6.829857) (xy 382.496301 6.829857) (xy 382.496301 6.915607)
			(xy 382.504213 7.00099) (xy 382.519969 7.08528) (xy 382.543436 7.167756) (xy 382.574412 7.247715)
			(xy 382.612634 7.324475) (xy 382.657775 7.397381) (xy 382.709451 7.46581) (xy 382.76722 7.52918)
			(xy 382.83059 7.586949) (xy 382.899019 7.638625) (xy 382.971925 7.683766) (xy 383.048685 7.721988)
			(xy 383.128644 7.752964) (xy 383.21112 7.776431) (xy 383.29541 7.792187) (xy 383.380793 7.800099)
			(xy 383.466543 7.800099) (xy 383.551926 7.792187) (xy 383.636216 7.776431) (xy 383.718692 7.752964)
			(xy 383.798651 7.721988) (xy 383.820854 7.710932) (xy 385.002532 7.710932) (xy 385.002532 8.574532)
			(xy 385.003018 8.601801) (xy 385.01078 8.655785) (xy 385.026145 8.708115) (xy 385.048802 8.757725)
			(xy 385.078288 8.803606) (xy 385.114003 8.844823) (xy 385.15522 8.880538) (xy 385.201101 8.910024)
			(xy 385.250711 8.932681) (xy 385.303041 8.948046) (xy 385.357025 8.955808) (xy 385.411563 8.955808)
			(xy 385.465547 8.948046) (xy 385.517877 8.932681) (xy 385.567487 8.910024) (xy 385.613368 8.880538)
			(xy 385.654585 8.844823) (xy 385.6903 8.803606) (xy 385.719786 8.757725) (xy 385.742443 8.708115)
			(xy 385.757808 8.655785) (xy 385.76557 8.601801) (xy 385.766056 8.574532) (xy 385.766056 7.710932)
			(xy 385.76557 7.683663) (xy 385.757808 7.629679) (xy 385.742443 7.577349) (xy 385.719786 7.527739)
			(xy 385.6903 7.481858) (xy 385.654585 7.440641) (xy 385.613368 7.404926) (xy 385.567487 7.37544)
			(xy 385.517877 7.352783) (xy 385.465547 7.337418) (xy 385.411563 7.329656) (xy 385.357025 7.329656)
			(xy 385.303041 7.337418) (xy 385.250711 7.352783) (xy 385.201101 7.37544) (xy 385.15522 7.404926)
			(xy 385.114003 7.440641) (xy 385.078288 7.481858) (xy 385.048802 7.527739) (xy 385.026145 7.577349)
			(xy 385.01078 7.629679) (xy 385.003018 7.683663) (xy 385.002532 7.710932) (xy 383.820854 7.710932)
			(xy 383.875411 7.683766) (xy 383.948317 7.638625) (xy 384.016746 7.586949) (xy 384.080116 7.52918)
			(xy 384.137885 7.46581) (xy 384.189561 7.397381) (xy 384.234702 7.324475) (xy 384.272924 7.247715)
			(xy 384.3039 7.167756) (xy 384.327367 7.08528) (xy 384.343123 7.00099) (xy 384.351035 6.915607) (xy 384.35153 6.872732)
			(xy 384.351035 6.829857) (xy 388.846301 6.829857) (xy 388.846301 6.915607) (xy 388.854213 7.00099)
			(xy 388.869969 7.08528) (xy 388.893436 7.167756) (xy 388.924412 7.247715) (xy 388.962634 7.324475)
			(xy 389.007775 7.397381) (xy 389.059451 7.46581) (xy 389.11722 7.52918) (xy 389.18059 7.586949) (xy 389.249019 7.638625)
			(xy 389.321925 7.683766) (xy 389.398685 7.721988) (xy 389.478644 7.752964) (xy 389.56112 7.776431)
			(xy 389.64541 7.792187) (xy 389.730793 7.800099) (xy 389.816543 7.800099) (xy 389.901926 7.792187)
			(xy 389.986216 7.776431) (xy 390.068692 7.752964) (xy 390.148651 7.721988) (xy 390.225411 7.683766)
			(xy 390.298317 7.638625) (xy 390.366746 7.586949) (xy 390.430116 7.52918) (xy 390.487885 7.46581)
			(xy 390.539561 7.397381) (xy 390.584702 7.324475) (xy 390.622924 7.247715) (xy 390.6539 7.167756)
			(xy 390.677367 7.08528) (xy 390.693123 7.00099) (xy 390.701035 6.915607) (xy 390.70153 6.872732)
			(xy 390.701117 6.836969) (xy 396.558757 6.836969) (xy 396.558757 6.922719) (xy 396.566669 7.008102)
			(xy 396.582425 7.092392) (xy 396.605892 7.174868) (xy 396.636868 7.254827) (xy 396.67509 7.331587)
			(xy 396.720231 7.404493) (xy 396.771907 7.472922) (xy 396.829676 7.536292) (xy 396.893046 7.594061)
			(xy 396.961475 7.645737) (xy 397.034381 7.690878) (xy 397.111141 7.7291) (xy 397.1911 7.760076) (xy 397.273576 7.783543)
			(xy 397.357866 7.799299) (xy 397.443249 7.807211) (xy 397.528999 7.807211) (xy 397.614382 7.799299)
			(xy 397.698672 7.783543) (xy 397.781148 7.760076) (xy 397.861107 7.7291) (xy 397.88331 7.718044)
			(xy 401.493736 7.718044) (xy 401.493736 8.581644) (xy 401.494222 8.608913) (xy 401.501984 8.662897)
			(xy 401.517349 8.715227) (xy 401.540006 8.764837) (xy 401.569492 8.810718) (xy 401.605207 8.851935)
			(xy 401.646424 8.88765) (xy 401.692305 8.917136) (xy 401.741915 8.939793) (xy 401.794245 8.955158)
			(xy 401.848229 8.96292) (xy 401.902767 8.96292) (xy 401.956751 8.955158) (xy 402.009081 8.939793)
			(xy 402.058691 8.917136) (xy 402.104572 8.88765) (xy 402.145789 8.851935) (xy 402.181504 8.810718)
			(xy 402.21099 8.764837) (xy 402.233647 8.715227) (xy 402.249012 8.662897) (xy 402.256774 8.608913)
			(xy 402.25726 8.581644) (xy 402.25726 7.718044) (xy 402.256774 7.690775) (xy 402.249012 7.636791)
			(xy 402.233647 7.584461) (xy 402.21099 7.534851) (xy 402.181504 7.48897) (xy 402.145789 7.447753)
			(xy 402.104572 7.412038) (xy 402.058691 7.382552) (xy 402.009081 7.359895) (xy 401.956751 7.34453)
			(xy 401.902767 7.336768) (xy 401.848229 7.336768) (xy 401.794245 7.34453) (xy 401.741915 7.359895)
			(xy 401.692305 7.382552) (xy 401.646424 7.412038) (xy 401.605207 7.447753) (xy 401.569492 7.48897)
			(xy 401.540006 7.534851) (xy 401.517349 7.584461) (xy 401.501984 7.636791) (xy 401.494222 7.690775)
			(xy 401.493736 7.718044) (xy 397.88331 7.718044) (xy 397.937867 7.690878) (xy 398.010773 7.645737)
			(xy 398.079202 7.594061) (xy 398.142572 7.536292) (xy 398.200341 7.472922) (xy 398.252017 7.404493)
			(xy 398.297158 7.331587) (xy 398.33538 7.254827) (xy 398.366356 7.174868) (xy 398.389823 7.092392)
			(xy 398.405579 7.008102) (xy 398.413491 6.922719) (xy 398.413986 6.879844) (xy 398.413491 6.836969)
			(xy 402.908757 6.836969) (xy 402.908757 6.922719) (xy 402.916669 7.008102) (xy 402.932425 7.092392)
			(xy 402.955892 7.174868) (xy 402.986868 7.254827) (xy 403.02509 7.331587) (xy 403.070231 7.404493)
			(xy 403.121907 7.472922) (xy 403.179676 7.536292) (xy 403.243046 7.594061) (xy 403.311475 7.645737)
			(xy 403.384381 7.690878) (xy 403.461141 7.7291) (xy 403.5411 7.760076) (xy 403.623576 7.783543) (xy 403.707866 7.799299)
			(xy 403.793249 7.807211) (xy 403.878999 7.807211) (xy 403.964382 7.799299) (xy 404.048672 7.783543)
			(xy 404.131148 7.760076) (xy 404.211107 7.7291) (xy 404.287867 7.690878) (xy 404.360773 7.645737)
			(xy 404.429202 7.594061) (xy 404.492572 7.536292) (xy 404.550341 7.472922) (xy 404.602017 7.404493)
			(xy 404.647158 7.331587) (xy 404.68538 7.254827) (xy 404.716356 7.174868) (xy 404.739823 7.092392)
			(xy 404.755579 7.008102) (xy 404.763491 6.922719) (xy 404.763986 6.879844) (xy 404.76379 6.862877)
			(xy 454.759301 6.862877) (xy 454.759301 6.948627) (xy 454.767213 7.03401) (xy 454.782969 7.1183)
			(xy 454.806436 7.200776) (xy 454.837412 7.280735) (xy 454.875634 7.357495) (xy 454.920775 7.430401)
			(xy 454.972451 7.49883) (xy 455.03022 7.5622) (xy 455.09359 7.619969) (xy 455.162019 7.671645) (xy 455.234925 7.716786)
			(xy 455.311685 7.755008) (xy 455.391644 7.785984) (xy 455.47412 7.809451) (xy 455.55841 7.825207)
			(xy 455.643793 7.833119) (xy 455.729543 7.833119) (xy 455.814926 7.825207) (xy 455.899216 7.809451)
			(xy 455.981692 7.785984) (xy 456.061651 7.755008) (xy 456.083854 7.743952) (xy 457.265532 7.743952)
			(xy 457.265532 8.607552) (xy 457.266018 8.634821) (xy 457.27378 8.688805) (xy 457.289145 8.741135)
			(xy 457.311802 8.790745) (xy 457.341288 8.836626) (xy 457.377003 8.877843) (xy 457.41822 8.913558)
			(xy 457.464101 8.943044) (xy 457.513711 8.965701) (xy 457.566041 8.981066) (xy 457.620025 8.988828)
			(xy 457.674563 8.988828) (xy 457.728547 8.981066) (xy 457.780877 8.965701) (xy 457.830487 8.943044)
			(xy 457.876368 8.913558) (xy 457.917585 8.877843) (xy 457.9533 8.836626) (xy 457.982786 8.790745)
			(xy 458.005443 8.741135) (xy 458.020808 8.688805) (xy 458.02857 8.634821) (xy 458.029056 8.607552)
			(xy 458.029056 7.743952) (xy 458.02857 7.716683) (xy 458.020808 7.662699) (xy 458.005443 7.610369)
			(xy 457.982786 7.560759) (xy 457.9533 7.514878) (xy 457.917585 7.473661) (xy 457.876368 7.437946)
			(xy 457.830487 7.40846) (xy 457.780877 7.385803) (xy 457.728547 7.370438) (xy 457.674563 7.362676)
			(xy 457.620025 7.362676) (xy 457.566041 7.370438) (xy 457.513711 7.385803) (xy 457.464101 7.40846)
			(xy 457.41822 7.437946) (xy 457.377003 7.473661) (xy 457.341288 7.514878) (xy 457.311802 7.560759)
			(xy 457.289145 7.610369) (xy 457.27378 7.662699) (xy 457.266018 7.716683) (xy 457.265532 7.743952)
			(xy 456.083854 7.743952) (xy 456.138411 7.716786) (xy 456.211317 7.671645) (xy 456.279746 7.619969)
			(xy 456.343116 7.5622) (xy 456.400885 7.49883) (xy 456.452561 7.430401) (xy 456.497702 7.357495)
			(xy 456.535924 7.280735) (xy 456.5669 7.200776) (xy 456.590367 7.1183) (xy 456.606123 7.03401) (xy 456.614035 6.948627)
			(xy 456.61453 6.905752) (xy 456.614035 6.862877) (xy 461.109301 6.862877) (xy 461.109301 6.948627)
			(xy 461.117213 7.03401) (xy 461.132969 7.1183) (xy 461.156436 7.200776) (xy 461.187412 7.280735)
			(xy 461.225634 7.357495) (xy 461.270775 7.430401) (xy 461.322451 7.49883) (xy 461.38022 7.5622) (xy 461.44359 7.619969)
			(xy 461.512019 7.671645) (xy 461.584925 7.716786) (xy 461.661685 7.755008) (xy 461.741644 7.785984)
			(xy 461.82412 7.809451) (xy 461.90841 7.825207) (xy 461.993793 7.833119) (xy 462.079543 7.833119)
			(xy 462.164926 7.825207) (xy 462.249216 7.809451) (xy 462.331692 7.785984) (xy 462.411651 7.755008)
			(xy 462.488411 7.716786) (xy 462.561317 7.671645) (xy 462.629746 7.619969) (xy 462.693116 7.5622)
			(xy 462.750885 7.49883) (xy 462.802561 7.430401) (xy 462.847702 7.357495) (xy 462.885924 7.280735)
			(xy 462.9169 7.200776) (xy 462.940367 7.1183) (xy 462.956123 7.03401) (xy 462.964035 6.948627) (xy 462.96453 6.905752)
			(xy 462.964035 6.862877) (xy 462.956123 6.777494) (xy 462.940367 6.693204) (xy 462.9169 6.610728)
			(xy 462.885924 6.530769) (xy 462.847702 6.454009) (xy 462.802561 6.381103) (xy 462.750885 6.312674)
			(xy 462.693116 6.249304) (xy 462.629746 6.191535) (xy 462.561317 6.139859) (xy 462.488411 6.094718)
			(xy 462.411651 6.056496) (xy 462.331692 6.02552) (xy 462.249216 6.002053) (xy 462.164926 5.986297)
			(xy 462.079543 5.978385) (xy 461.993793 5.978385) (xy 461.90841 5.986297) (xy 461.82412 6.002053)
			(xy 461.741644 6.02552) (xy 461.661685 6.056496) (xy 461.584925 6.094718) (xy 461.512019 6.139859)
			(xy 461.44359 6.191535) (xy 461.38022 6.249304) (xy 461.322451 6.312674) (xy 461.270775 6.381103)
			(xy 461.225634 6.454009) (xy 461.187412 6.530769) (xy 461.156436 6.610728) (xy 461.132969 6.693204)
			(xy 461.117213 6.777494) (xy 461.109301 6.862877) (xy 456.614035 6.862877) (xy 456.606123 6.777494)
			(xy 456.590367 6.693204) (xy 456.5669 6.610728) (xy 456.535924 6.530769) (xy 456.497702 6.454009)
			(xy 456.452561 6.381103) (xy 456.400885 6.312674) (xy 456.343116 6.249304) (xy 456.279746 6.191535)
			(xy 456.211317 6.139859) (xy 456.138411 6.094718) (xy 456.061651 6.056496) (xy 455.981692 6.02552)
			(xy 455.899216 6.002053) (xy 455.814926 5.986297) (xy 455.729543 5.978385) (xy 455.643793 5.978385)
			(xy 455.55841 5.986297) (xy 455.47412 6.002053) (xy 455.391644 6.02552) (xy 455.311685 6.056496)
			(xy 455.234925 6.094718) (xy 455.162019 6.139859) (xy 455.09359 6.191535) (xy 455.03022 6.249304)
			(xy 454.972451 6.312674) (xy 454.920775 6.381103) (xy 454.875634 6.454009) (xy 454.837412 6.530769)
			(xy 454.806436 6.610728) (xy 454.782969 6.693204) (xy 454.767213 6.777494) (xy 454.759301 6.862877)
			(xy 404.76379 6.862877) (xy 404.763491 6.836969) (xy 404.755579 6.751586) (xy 404.739823 6.667296)
			(xy 404.716356 6.58482) (xy 404.68538 6.504861) (xy 404.647158 6.428101) (xy 404.602017 6.355195)
			(xy 404.550341 6.286766) (xy 404.492572 6.223396) (xy 404.429202 6.165627) (xy 404.360773 6.113951)
			(xy 404.287867 6.06881) (xy 404.211107 6.030588) (xy 404.131148 5.999612) (xy 404.048672 5.976145)
			(xy 403.964382 5.960389) (xy 403.878999 5.952477) (xy 403.793249 5.952477) (xy 403.707866 5.960389)
			(xy 403.623576 5.976145) (xy 403.5411 5.999612) (xy 403.461141 6.030588) (xy 403.384381 6.06881)
			(xy 403.311475 6.113951) (xy 403.243046 6.165627) (xy 403.179676 6.223396) (xy 403.121907 6.286766)
			(xy 403.070231 6.355195) (xy 403.02509 6.428101) (xy 402.986868 6.504861) (xy 402.955892 6.58482)
			(xy 402.932425 6.667296) (xy 402.916669 6.751586) (xy 402.908757 6.836969) (xy 398.413491 6.836969)
			(xy 398.405579 6.751586) (xy 398.389823 6.667296) (xy 398.366356 6.58482) (xy 398.33538 6.504861)
			(xy 398.297158 6.428101) (xy 398.252017 6.355195) (xy 398.200341 6.286766) (xy 398.142572 6.223396)
			(xy 398.079202 6.165627) (xy 398.010773 6.113951) (xy 397.937867 6.06881) (xy 397.861107 6.030588)
			(xy 397.781148 5.999612) (xy 397.698672 5.976145) (xy 397.614382 5.960389) (xy 397.528999 5.952477)
			(xy 397.443249 5.952477) (xy 397.357866 5.960389) (xy 397.273576 5.976145) (xy 397.1911 5.999612)
			(xy 397.111141 6.030588) (xy 397.034381 6.06881) (xy 396.961475 6.113951) (xy 396.893046 6.165627)
			(xy 396.829676 6.223396) (xy 396.771907 6.286766) (xy 396.720231 6.355195) (xy 396.67509 6.428101)
			(xy 396.636868 6.504861) (xy 396.605892 6.58482) (xy 396.582425 6.667296) (xy 396.566669 6.751586)
			(xy 396.558757 6.836969) (xy 390.701117 6.836969) (xy 390.701035 6.829857) (xy 390.693123 6.744474)
			(xy 390.677367 6.660184) (xy 390.6539 6.577708) (xy 390.622924 6.497749) (xy 390.584702 6.420989)
			(xy 390.539561 6.348083) (xy 390.487885 6.279654) (xy 390.430116 6.216284) (xy 390.366746 6.158515)
			(xy 390.298317 6.106839) (xy 390.225411 6.061698) (xy 390.148651 6.023476) (xy 390.068692 5.9925)
			(xy 389.986216 5.969033) (xy 389.901926 5.953277) (xy 389.816543 5.945365) (xy 389.730793 5.945365)
			(xy 389.64541 5.953277) (xy 389.56112 5.969033) (xy 389.478644 5.9925) (xy 389.398685 6.023476) (xy 389.321925 6.061698)
			(xy 389.249019 6.106839) (xy 389.18059 6.158515) (xy 389.11722 6.216284) (xy 389.059451 6.279654)
			(xy 389.007775 6.348083) (xy 388.962634 6.420989) (xy 388.924412 6.497749) (xy 388.893436 6.577708)
			(xy 388.869969 6.660184) (xy 388.854213 6.744474) (xy 388.846301 6.829857) (xy 384.351035 6.829857)
			(xy 384.343123 6.744474) (xy 384.327367 6.660184) (xy 384.3039 6.577708) (xy 384.272924 6.497749)
			(xy 384.234702 6.420989) (xy 384.189561 6.348083) (xy 384.137885 6.279654) (xy 384.080116 6.216284)
			(xy 384.016746 6.158515) (xy 383.948317 6.106839) (xy 383.875411 6.061698) (xy 383.798651 6.023476)
			(xy 383.718692 5.9925) (xy 383.636216 5.969033) (xy 383.551926 5.953277) (xy 383.466543 5.945365)
			(xy 383.380793 5.945365) (xy 383.29541 5.953277) (xy 383.21112 5.969033) (xy 383.128644 5.9925) (xy 383.048685 6.023476)
			(xy 382.971925 6.061698) (xy 382.899019 6.106839) (xy 382.83059 6.158515) (xy 382.76722 6.216284)
			(xy 382.709451 6.279654) (xy 382.657775 6.348083) (xy 382.612634 6.420989) (xy 382.574412 6.497749)
			(xy 382.543436 6.577708) (xy 382.519969 6.660184) (xy 382.504213 6.744474) (xy 382.496301 6.829857)
			(xy 332.50079 6.829857) (xy 332.500491 6.803949) (xy 332.492579 6.718566) (xy 332.476823 6.634276)
			(xy 332.453356 6.5518) (xy 332.42238 6.471841) (xy 332.384158 6.395081) (xy 332.339017 6.322175)
			(xy 332.287341 6.253746) (xy 332.229572 6.190376) (xy 332.166202 6.132607) (xy 332.097773 6.080931)
			(xy 332.024867 6.03579) (xy 331.948107 5.997568) (xy 331.868148 5.966592) (xy 331.785672 5.943125)
			(xy 331.701382 5.927369) (xy 331.615999 5.919457) (xy 331.530249 5.919457) (xy 331.444866 5.927369)
			(xy 331.360576 5.943125) (xy 331.2781 5.966592) (xy 331.198141 5.997568) (xy 331.121381 6.03579)
			(xy 331.048475 6.080931) (xy 330.980046 6.132607) (xy 330.916676 6.190376) (xy 330.858907 6.253746)
			(xy 330.807231 6.322175) (xy 330.76209 6.395081) (xy 330.723868 6.471841) (xy 330.692892 6.5518)
			(xy 330.669425 6.634276) (xy 330.653669 6.718566) (xy 330.645757 6.803949) (xy 326.150491 6.803949)
			(xy 326.142579 6.718566) (xy 326.126823 6.634276) (xy 326.103356 6.5518) (xy 326.07238 6.471841)
			(xy 326.034158 6.395081) (xy 325.989017 6.322175) (xy 325.937341 6.253746) (xy 325.879572 6.190376)
			(xy 325.816202 6.132607) (xy 325.747773 6.080931) (xy 325.674867 6.03579) (xy 325.598107 5.997568)
			(xy 325.518148 5.966592) (xy 325.435672 5.943125) (xy 325.351382 5.927369) (xy 325.265999 5.919457)
			(xy 325.180249 5.919457) (xy 325.094866 5.927369) (xy 325.010576 5.943125) (xy 324.9281 5.966592)
			(xy 324.848141 5.997568) (xy 324.771381 6.03579) (xy 324.698475 6.080931) (xy 324.630046 6.132607)
			(xy 324.566676 6.190376) (xy 324.508907 6.253746) (xy 324.457231 6.322175) (xy 324.41209 6.395081)
			(xy 324.373868 6.471841) (xy 324.342892 6.5518) (xy 324.319425 6.634276) (xy 324.303669 6.718566)
			(xy 324.295757 6.803949) (xy 317.930117 6.803949) (xy 317.930035 6.796837) (xy 317.922123 6.711454)
			(xy 317.906367 6.627164) (xy 317.8829 6.544688) (xy 317.851924 6.464729) (xy 317.813702 6.387969)
			(xy 317.768561 6.315063) (xy 317.716885 6.246634) (xy 317.659116 6.183264) (xy 317.595746 6.125495)
			(xy 317.527317 6.073819) (xy 317.454411 6.028678) (xy 317.377651 5.990456) (xy 317.297692 5.95948)
			(xy 317.215216 5.936013) (xy 317.130926 5.920257) (xy 317.045543 5.912345) (xy 316.959793 5.912345)
			(xy 316.87441 5.920257) (xy 316.79012 5.936013) (xy 316.707644 5.95948) (xy 316.627685 5.990456)
			(xy 316.550925 6.028678) (xy 316.478019 6.073819) (xy 316.40959 6.125495) (xy 316.34622 6.183264)
			(xy 316.288451 6.246634) (xy 316.236775 6.315063) (xy 316.191634 6.387969) (xy 316.153412 6.464729)
			(xy 316.122436 6.544688) (xy 316.098969 6.627164) (xy 316.083213 6.711454) (xy 316.075301 6.796837)
			(xy 311.580035 6.796837) (xy 311.572123 6.711454) (xy 311.556367 6.627164) (xy 311.5329 6.544688)
			(xy 311.501924 6.464729) (xy 311.463702 6.387969) (xy 311.418561 6.315063) (xy 311.366885 6.246634)
			(xy 311.309116 6.183264) (xy 311.245746 6.125495) (xy 311.177317 6.073819) (xy 311.104411 6.028678)
			(xy 311.027651 5.990456) (xy 310.947692 5.95948) (xy 310.865216 5.936013) (xy 310.780926 5.920257)
			(xy 310.695543 5.912345) (xy 310.609793 5.912345) (xy 310.52441 5.920257) (xy 310.44012 5.936013)
			(xy 310.357644 5.95948) (xy 310.277685 5.990456) (xy 310.200925 6.028678) (xy 310.128019 6.073819)
			(xy 310.05959 6.125495) (xy 309.99622 6.183264) (xy 309.938451 6.246634) (xy 309.886775 6.315063)
			(xy 309.841634 6.387969) (xy 309.803412 6.464729) (xy 309.772436 6.544688) (xy 309.748969 6.627164)
			(xy 309.733213 6.711454) (xy 309.725301 6.796837) (xy 259.72979 6.796837) (xy 259.729491 6.770929)
			(xy 259.721579 6.685546) (xy 259.705823 6.601256) (xy 259.682356 6.51878) (xy 259.65138 6.438821)
			(xy 259.613158 6.362061) (xy 259.568017 6.289155) (xy 259.516341 6.220726) (xy 259.458572 6.157356)
			(xy 259.395202 6.099587) (xy 259.326773 6.047911) (xy 259.253867 6.00277) (xy 259.177107 5.964548)
			(xy 259.097148 5.933572) (xy 259.014672 5.910105) (xy 258.930382 5.894349) (xy 258.844999 5.886437)
			(xy 258.759249 5.886437) (xy 258.673866 5.894349) (xy 258.589576 5.910105) (xy 258.5071 5.933572)
			(xy 258.427141 5.964548) (xy 258.350381 6.00277) (xy 258.277475 6.047911) (xy 258.209046 6.099587)
			(xy 258.145676 6.157356) (xy 258.087907 6.220726) (xy 258.036231 6.289155) (xy 257.99109 6.362061)
			(xy 257.952868 6.438821) (xy 257.921892 6.51878) (xy 257.898425 6.601256) (xy 257.882669 6.685546)
			(xy 257.874757 6.770929) (xy 253.379491 6.770929) (xy 253.371579 6.685546) (xy 253.355823 6.601256)
			(xy 253.332356 6.51878) (xy 253.30138 6.438821) (xy 253.263158 6.362061) (xy 253.218017 6.289155)
			(xy 253.166341 6.220726) (xy 253.108572 6.157356) (xy 253.045202 6.099587) (xy 252.976773 6.047911)
			(xy 252.903867 6.00277) (xy 252.827107 5.964548) (xy 252.747148 5.933572) (xy 252.664672 5.910105)
			(xy 252.580382 5.894349) (xy 252.494999 5.886437) (xy 252.409249 5.886437) (xy 252.323866 5.894349)
			(xy 252.239576 5.910105) (xy 252.1571 5.933572) (xy 252.077141 5.964548) (xy 252.000381 6.00277)
			(xy 251.927475 6.047911) (xy 251.859046 6.099587) (xy 251.795676 6.157356) (xy 251.737907 6.220726)
			(xy 251.686231 6.289155) (xy 251.64109 6.362061) (xy 251.602868 6.438821) (xy 251.571892 6.51878)
			(xy 251.548425 6.601256) (xy 251.532669 6.685546) (xy 251.524757 6.770929) (xy 245.921117 6.770929)
			(xy 245.921035 6.763817) (xy 245.913123 6.678434) (xy 245.897367 6.594144) (xy 245.8739 6.511668)
			(xy 245.842924 6.431709) (xy 245.804702 6.354949) (xy 245.759561 6.282043) (xy 245.707885 6.213614)
			(xy 245.650116 6.150244) (xy 245.586746 6.092475) (xy 245.518317 6.040799) (xy 245.445411 5.995658)
			(xy 245.368651 5.957436) (xy 245.288692 5.92646) (xy 245.206216 5.902993) (xy 245.121926 5.887237)
			(xy 245.036543 5.879325) (xy 244.950793 5.879325) (xy 244.86541 5.887237) (xy 244.78112 5.902993)
			(xy 244.698644 5.92646) (xy 244.618685 5.957436) (xy 244.541925 5.995658) (xy 244.469019 6.040799)
			(xy 244.40059 6.092475) (xy 244.33722 6.150244) (xy 244.279451 6.213614) (xy 244.227775 6.282043)
			(xy 244.182634 6.354949) (xy 244.144412 6.431709) (xy 244.113436 6.511668) (xy 244.089969 6.594144)
			(xy 244.074213 6.678434) (xy 244.066301 6.763817) (xy 239.571035 6.763817) (xy 239.563123 6.678434)
			(xy 239.547367 6.594144) (xy 239.5239 6.511668) (xy 239.492924 6.431709) (xy 239.454702 6.354949)
			(xy 239.409561 6.282043) (xy 239.357885 6.213614) (xy 239.300116 6.150244) (xy 239.236746 6.092475)
			(xy 239.168317 6.040799) (xy 239.095411 5.995658) (xy 239.018651 5.957436) (xy 238.938692 5.92646)
			(xy 238.856216 5.902993) (xy 238.771926 5.887237) (xy 238.686543 5.879325) (xy 238.600793 5.879325)
			(xy 238.51541 5.887237) (xy 238.43112 5.902993) (xy 238.348644 5.92646) (xy 238.268685 5.957436)
			(xy 238.191925 5.995658) (xy 238.119019 6.040799) (xy 238.05059 6.092475) (xy 237.98722 6.150244)
			(xy 237.929451 6.213614) (xy 237.877775 6.282043) (xy 237.832634 6.354949) (xy 237.794412 6.431709)
			(xy 237.763436 6.511668) (xy 237.739969 6.594144) (xy 237.724213 6.678434) (xy 237.716301 6.763817)
			(xy 187.719832 6.763817) (xy 187.712579 6.685546) (xy 187.696823 6.601256) (xy 187.673356 6.51878)
			(xy 187.64238 6.438821) (xy 187.604158 6.362061) (xy 187.559017 6.289155) (xy 187.507341 6.220726)
			(xy 187.449572 6.157356) (xy 187.386202 6.099587) (xy 187.317773 6.047911) (xy 187.244867 6.00277)
			(xy 187.168107 5.964548) (xy 187.088148 5.933572) (xy 187.005672 5.910105) (xy 186.921382 5.894349)
			(xy 186.835999 5.886437) (xy 186.750249 5.886437) (xy 186.664866 5.894349) (xy 186.580576 5.910105)
			(xy 186.4981 5.933572) (xy 186.418141 5.964548) (xy 186.341381 6.00277) (xy 186.268475 6.047911)
			(xy 186.200046 6.099587) (xy 186.136676 6.157356) (xy 186.078907 6.220726) (xy 186.027231 6.289155)
			(xy 185.98209 6.362061) (xy 185.943868 6.438821) (xy 185.912892 6.51878) (xy 185.889425 6.601256)
			(xy 185.873669 6.685546) (xy 185.865757 6.770929) (xy 181.370491 6.770929) (xy 181.362579 6.685546)
			(xy 181.346823 6.601256) (xy 181.323356 6.51878) (xy 181.29238 6.438821) (xy 181.254158 6.362061)
			(xy 181.209017 6.289155) (xy 181.157341 6.220726) (xy 181.099572 6.157356) (xy 181.036202 6.099587)
			(xy 180.967773 6.047911) (xy 180.894867 6.00277) (xy 180.818107 5.964548) (xy 180.738148 5.933572)
			(xy 180.655672 5.910105) (xy 180.571382 5.894349) (xy 180.485999 5.886437) (xy 180.400249 5.886437)
			(xy 180.314866 5.894349) (xy 180.230576 5.910105) (xy 180.1481 5.933572) (xy 180.068141 5.964548)
			(xy 179.991381 6.00277) (xy 179.918475 6.047911) (xy 179.850046 6.099587) (xy 179.786676 6.157356)
			(xy 179.728907 6.220726) (xy 179.677231 6.289155) (xy 179.63209 6.362061) (xy 179.593868 6.438821)
			(xy 179.562892 6.51878) (xy 179.539425 6.601256) (xy 179.523669 6.685546) (xy 179.515757 6.770929)
			(xy 158.039844 6.770929) (xy 158.030561 6.759289) (xy 157.936801 6.654373) (xy 157.837306 6.554879)
			(xy 157.732388 6.46112) (xy 157.622379 6.373391) (xy 157.507624 6.291969) (xy 157.388483 6.21711)
			(xy 157.265333 6.149048) (xy 157.138561 6.087998) (xy 157.008565 6.034153) (xy 156.875754 5.987681)
			(xy 156.740546 5.948729) (xy 156.603367 5.91742) (xy 156.464649 5.893851) (xy 156.324827 5.878098)
			(xy 156.184341 5.870209) (xy 156.113988 5.869686) (xy 17.493996 5.869686) (xy 17.423642 5.870179)
			(xy 17.283156 5.878069) (xy 17.143333 5.893824) (xy 17.004613 5.917393) (xy 16.867433 5.948703) (xy 16.732225 5.987656)
			(xy 16.599413 6.034129) (xy 16.469416 6.087976) (xy 16.342643 6.149026) (xy 16.219492 6.217089) (xy 16.100351 6.29195)
			(xy 15.985596 6.373373) (xy 15.875586 6.461103) (xy 15.770668 6.554863) (xy 15.671172 6.654358) (xy 15.577412 6.759275)
			(xy 15.489682 6.869284) (xy 15.408258 6.98404) (xy 15.333396 7.10318) (xy 15.265333 7.22633) (xy 15.204281 7.353103)
			(xy 15.150434 7.4831) (xy 15.103961 7.615912) (xy 15.065007 7.75112) (xy 15.033696 7.8883) (xy 15.010125 8.027019)
			(xy 14.99437 8.166842) (xy 14.98648 8.307328) (xy 14.986 8.377682) (xy 14.986 24.157686) (xy 14.985478 24.213493)
			(xy 14.977137 24.324795) (xy 14.960501 24.435162) (xy 14.935664 24.543977) (xy 14.902765 24.650632)
			(xy 14.861988 24.754531) (xy 14.81356 24.855091) (xy 14.757753 24.951752) (xy 14.694879 25.043971)
			(xy 14.625289 25.131234) (xy 14.549372 25.213053) (xy 14.467553 25.28897) (xy 14.38029 25.35856)
			(xy 14.28807 25.421434) (xy 14.19141 25.477241) (xy 14.090849 25.525669) (xy 13.986951 25.566446)
			(xy 13.880295 25.599345) (xy 13.77148 25.624182) (xy 13.661113 25.640817) (xy 13.549811 25.649158)
			(xy 13.494004 25.649682) (xy 1.999996 25.649682) (xy 1.944189 25.64916) (xy 1.832887 25.640819) (xy 1.72252 25.624184)
			(xy 1.613704 25.599347) (xy 1.507049 25.566448) (xy 1.40315 25.525671) (xy 1.30259 25.477243) (xy 1.205929 25.421436)
			(xy 1.113709 25.358562) (xy 1.026446 25.288971) (xy 0.944627 25.213055) (xy 0.86871 25.131236) (xy 0.79912 25.043972)
			(xy 0.736245 24.951753) (xy 0.680438 24.855092) (xy 0.63201 24.754532) (xy 0.591233 24.650633) (xy 0.558334 24.543978)
			(xy 0.533497 24.435162) (xy 0.516861 24.324795) (xy 0.50852 24.213493) (xy 0.508 24.157686) (xy 0.508 21.093122)
			(xy 2.904225 21.093122) (xy 2.904225 21.222262) (xy 2.912175 21.351157) (xy 2.928045 21.479317) (xy 2.951774 21.606258)
			(xy 2.983273 21.731497) (xy 3.022422 21.85456) (xy 3.069073 21.974979) (xy 3.123048 22.092298) (xy 3.184143 22.206072)
			(xy 3.252126 22.315869) (xy 3.32674 22.421272) (xy 3.407701 22.521882) (xy 3.494701 22.617317) (xy 3.587412 22.707216)
			(xy 3.685482 22.791237) (xy 3.788537 22.869061) (xy 3.896188 22.940393) (xy 4.008027 23.004963) (xy 4.123628 23.062525)
			(xy 4.242553 23.112862) (xy 4.364352 23.155782) (xy 4.488562 23.191123) (xy 4.614711 23.21875) (xy 4.742323 23.238559)
			(xy 4.870912 23.250475) (xy 4.99999 23.254452) (xy 5.129068 23.250475) (xy 5.257657 23.238559) (xy 5.385269 23.21875)
			(xy 5.511418 23.191123) (xy 5.635628 23.155782) (xy 5.757427 23.112862) (xy 5.876352 23.062525) (xy 5.991953 23.004963)
			(xy 6.103792 22.940393) (xy 6.211443 22.869061) (xy 6.314498 22.791237) (xy 6.412568 22.707216) (xy 6.505279 22.617317)
			(xy 6.592279 22.521882) (xy 6.67324 22.421272) (xy 6.747854 22.315869) (xy 6.815837 22.206072) (xy 6.876932 22.092298)
			(xy 6.930907 21.974979) (xy 6.977558 21.85456) (xy 7.016707 21.731497) (xy 7.048206 21.606258) (xy 7.071935 21.479317)
			(xy 7.087805 21.351157) (xy 7.095755 21.222262) (xy 7.096252 21.157692) (xy 7.095755 21.093122) (xy 7.087805 20.964227)
			(xy 7.071935 20.836067) (xy 7.048206 20.709126) (xy 7.016707 20.583887) (xy 6.977558 20.460824) (xy 6.930907 20.340405)
			(xy 6.876932 20.223086) (xy 6.815837 20.109312) (xy 6.747854 19.999515) (xy 6.67324 19.894112) (xy 6.592279 19.793502)
			(xy 6.505279 19.698067) (xy 6.412568 19.608168) (xy 6.314498 19.524147) (xy 6.211443 19.446323) (xy 6.103792 19.374991)
			(xy 5.991953 19.310421) (xy 5.876352 19.252859) (xy 5.757427 19.202522) (xy 5.635628 19.159602) (xy 5.511418 19.124261)
			(xy 5.385269 19.096634) (xy 5.257657 19.076825) (xy 5.129068 19.064909) (xy 4.99999 19.060933) (xy 4.870912 19.064909)
			(xy 4.742323 19.076825) (xy 4.614711 19.096634) (xy 4.488562 19.124261) (xy 4.364352 19.159602) (xy 4.242553 19.202522)
			(xy 4.123628 19.252859) (xy 4.008027 19.310421) (xy 3.896188 19.374991) (xy 3.788537 19.446323) (xy 3.685482 19.524147)
			(xy 3.587412 19.608168) (xy 3.494701 19.698067) (xy 3.407701 19.793502) (xy 3.32674 19.894112) (xy 3.252126 19.999515)
			(xy 3.184143 20.109312) (xy 3.123048 20.223086) (xy 3.069073 20.340405) (xy 3.022422 20.460824) (xy 2.983273 20.583887)
			(xy 2.951774 20.709126) (xy 2.928045 20.836067) (xy 2.912175 20.964227) (xy 2.904225 21.093122) (xy 0.508 21.093122)
			(xy 0.508 3.999992) (xy 0.508522 3.944185) (xy 0.516863 3.832883) (xy 0.533498 3.722516) (xy 0.558335 3.6137)
			(xy 0.591234 3.507045) (xy 0.632011 3.403146) (xy 0.680438 3.302586) (xy 0.736246 3.205925) (xy 0.79912 3.113705)
			(xy 0.86871 3.026442) (xy 0.944627 2.944623) (xy 1.026446 2.868706) (xy 1.113709 2.799116) (xy 1.205929 2.736242)
			(xy 1.30259 2.680434) (xy 1.40315 2.632007) (xy 1.507049 2.59123) (xy 1.613704 2.558331) (xy 1.72252 2.533494)
			(xy 1.832887 2.516859) (xy 1.944189 2.508518) (xy 1.999996 2.507996) (xy 7.964932 2.507996) (xy 8.035286 2.507503)
			(xy 8.175772 2.499613) (xy 8.315594 2.483859) (xy 8.454314 2.460289) (xy 8.591493 2.428979) (xy 8.726701 2.390026)
			(xy 8.859513 2.343553) (xy 8.989509 2.289707) (xy 9.116282 2.228656) (xy 9.239433 2.160593) (xy 9.358573 2.085732)
			(xy 9.473329 2.004309) (xy 9.583338 1.916579) (xy 9.688255 1.822819) (xy 9.78775 1.723324) (xy 9.88151 1.618406)
			(xy 9.96924 1.508397) (xy 10.050663 1.393641) (xy 10.125524 1.274501) (xy 10.193587 1.151351) (xy 10.254637 1.024578)
			(xy 10.308484 0.894581) (xy 10.354957 0.76177) (xy 10.393909 0.626561) (xy 10.42522 0.489382) (xy 10.448789 0.350662)
			(xy 10.464543 0.21084) (xy 10.472433 0.070354) (xy 10.472928 0) (xy 10.472928 -8.850122) (xy 10.47345 -8.905929)
			(xy 10.481791 -9.017231) (xy 10.498426 -9.127599) (xy 10.523263 -9.236414) (xy 10.556162 -9.34307)
			(xy 10.596939 -9.446968) (xy 10.645366 -9.547529) (xy 10.701173 -9.64419) (xy 10.764048 -9.73641)
			(xy 10.833638 -9.823673) (xy 10.909555 -9.905492) (xy 10.991374 -9.981409) (xy 11.078637 -10.051)
			(xy 11.170857 -10.113875) (xy 11.267517 -10.169682) (xy 11.368078 -10.21811) (xy 11.471977 -10.258887)
			(xy 11.578632 -10.291786) (xy 11.687448 -10.316623) (xy 11.797815 -10.333259) (xy 11.909117 -10.3416)
			(xy 11.964924 -10.342118)
		)
		(stroke
			(width 0)
			(type solid)
		)
		(fill yes)
		(layer "In14.Cu")
		(net "COUPON_GND2")
	)
	(gr_poly
		(pts
			(xy 7.987284 -418.080952) (xy 200.481184 -418.080952) (xy 200.53776 -418.08043) (xy 200.650587 -418.071859)
			(xy 200.762439 -418.054758) (xy 200.872672 -418.029225) (xy 200.980652 -417.995406) (xy 201.085757 -417.953498)
			(xy 201.187381 -417.90374) (xy 201.28494 -417.84642) (xy 201.377872 -417.781868) (xy 201.465642 -417.710455)
			(xy 201.547744 -417.632592) (xy 201.586084 -417.590986) (xy 201.633303 -417.539598) (xy 201.732638 -417.441554)
			(xy 201.837271 -417.349184) (xy 201.946878 -417.262774) (xy 202.06112 -417.182592) (xy 202.179643 -417.108886)
			(xy 202.302081 -417.041884) (xy 202.428054 -416.981794) (xy 202.557174 -416.9288) (xy 202.689041 -416.883067)
			(xy 202.823246 -416.844737) (xy 202.959375 -416.813928) (xy 203.097007 -416.790736) (xy 203.235715 -416.775231)
			(xy 203.37507 -416.767463) (xy 203.444856 -416.76701) (xy 271.794986 -416.76701) (xy 271.864771 -416.767495)
			(xy 272.004124 -416.77527) (xy 272.142829 -416.790779) (xy 272.280457 -416.813975) (xy 272.416584 -416.844786)
			(xy 272.550787 -416.883117) (xy 272.682651 -416.92885) (xy 272.811769 -416.981841) (xy 272.937742 -417.041929)
			(xy 273.06018 -417.108927) (xy 273.178704 -417.182628) (xy 273.292947 -417.262803) (xy 273.402557 -417.349206)
			(xy 273.436768 -417.379404) (xy 313.073796 -417.379404) (xy 313.073796 -394.27912) (xy 326.479662 -394.27912)
			(xy 326.525636 -394.325094) (xy 326.525636 -397.823826) (xy 330.929171 -397.823826) (xy 330.929175 -397.756517)
			(xy 330.937223 -397.689692) (xy 330.953201 -397.624307) (xy 330.976879 -397.561301) (xy 331.007918 -397.501576)
			(xy 331.045873 -397.44599) (xy 331.067664 -397.420338) (xy 331.073477 -397.413205) (xy 331.07998 -397.396005)
			(xy 331.080364 -397.38681) (xy 331.080364 -396.893542) (xy 331.079919 -396.884359) (xy 331.073428 -396.867175)
			(xy 331.067664 -396.860014) (xy 331.045866 -396.83437) (xy 331.007916 -396.778783) (xy 330.976881 -396.719059)
			(xy 330.953208 -396.656053) (xy 330.937235 -396.59067) (xy 330.929191 -396.523846) (xy 330.929192 -396.456539)
			(xy 330.937238 -396.389716) (xy 330.953213 -396.324333) (xy 330.976888 -396.261328) (xy 331.007923 -396.201604)
			(xy 331.045875 -396.146018) (xy 331.067664 -396.120366) (xy 331.073465 -396.113225) (xy 331.079975 -396.096031)
			(xy 331.080364 -396.086838) (xy 331.080364 -395.92885) (xy 331.080805 -395.918678) (xy 331.088579 -395.89988)
			(xy 331.10296 -395.885492) (xy 331.121755 -395.87771) (xy 331.131926 -395.877288) (xy 331.848206 -395.877288)
			(xy 331.858384 -395.87766) (xy 331.877189 -395.885456) (xy 331.891575 -395.899859) (xy 331.899351 -395.918671)
			(xy 331.899768 -395.92885) (xy 331.899768 -396.086838) (xy 331.900167 -396.096026) (xy 331.906689 -396.11321)
			(xy 331.912468 -396.120366) (xy 331.934246 -396.146026) (xy 331.972195 -396.201612) (xy 332.003228 -396.261334)
			(xy 332.026901 -396.324338) (xy 332.042874 -396.389719) (xy 332.050919 -396.45654) (xy 332.05092 -396.523845)
			(xy 332.042877 -396.590666) (xy 332.026905 -396.656048) (xy 332.003234 -396.719052) (xy 331.972202 -396.778775)
			(xy 331.934255 -396.834362) (xy 331.912468 -396.860014) (xy 331.906679 -396.867164) (xy 331.90016 -396.884351)
			(xy 331.899768 -396.893542) (xy 331.899768 -397.38681) (xy 331.90018 -397.395997) (xy 331.906693 -397.413181)
			(xy 331.912468 -397.420338) (xy 331.934218 -397.446021) (xy 331.972167 -397.501603) (xy 332.00059 -397.556296)
			(xy 333.128836 -397.556296) (xy 333.136911 -397.489358) (xy 333.152946 -397.423869) (xy 333.17671 -397.360773)
			(xy 333.20786 -397.300977) (xy 333.245948 -397.245343) (xy 333.267812 -397.219678) (xy 333.273602 -397.212528)
			(xy 333.28012 -397.195341) (xy 333.280512 -397.18615) (xy 333.280512 -397.028924) (xy 333.280936 -397.018802)
			(xy 333.288678 -397.000096) (xy 333.302993 -396.985781) (xy 333.321698 -396.978037) (xy 333.33182 -396.977616)
			(xy 334.0481 -396.977616) (xy 334.058224 -396.978016) (xy 334.076931 -396.985768) (xy 334.091246 -397.000089)
			(xy 334.098988 -397.018799) (xy 334.099408 -397.028924) (xy 334.099408 -397.18615) (xy 334.09984 -397.195335)
			(xy 334.106338 -397.21252) (xy 334.112108 -397.219678) (xy 334.133982 -397.245335) (xy 334.172069 -397.300971)
			(xy 334.203219 -397.360769) (xy 334.226982 -397.423866) (xy 334.243017 -397.489356) (xy 334.251092 -397.556295)
			(xy 334.251091 -397.62372) (xy 334.243014 -397.690658) (xy 334.226978 -397.756148) (xy 334.203213 -397.819245)
			(xy 334.200796 -397.823884) (xy 335.328964 -397.823884) (xy 335.328968 -397.756459) (xy 335.337047 -397.689518)
			(xy 335.353085 -397.624028) (xy 335.376852 -397.560929) (xy 335.408005 -397.501132) (xy 335.446095 -397.445496)
			(xy 335.46796 -397.41983) (xy 335.473776 -397.412699) (xy 335.480277 -397.395497) (xy 335.48066 -397.386302)
			(xy 335.48066 -396.89405) (xy 335.480213 -396.884867) (xy 335.473723 -396.867683) (xy 335.46796 -396.860522)
			(xy 335.446088 -396.834864) (xy 335.408002 -396.779228) (xy 335.376854 -396.71943) (xy 335.353092 -396.656332)
			(xy 335.337058 -396.590843) (xy 335.328984 -396.523904) (xy 335.328985 -396.456481) (xy 335.337061 -396.389542)
			(xy 335.353096 -396.324053) (xy 335.37686 -396.260956) (xy 335.40801 -396.201159) (xy 335.446097 -396.145524)
			(xy 335.46796 -396.119858) (xy 335.473764 -396.112719) (xy 335.480273 -396.095523) (xy 335.48066 -396.08633)
			(xy 335.48066 -395.92885) (xy 335.481168 -395.918724) (xy 335.488883 -395.9) (xy 335.503164 -395.885642)
			(xy 335.521845 -395.877824) (xy 335.531968 -395.877288) (xy 336.248248 -395.877288) (xy 336.258404 -395.877682)
			(xy 336.277155 -395.885491) (xy 336.291476 -395.899896) (xy 336.299176 -395.918692) (xy 336.299556 -395.92885)
			(xy 336.299556 -396.08633) (xy 336.299962 -396.095517) (xy 336.30648 -396.112701) (xy 336.312256 -396.119858)
			(xy 336.334112 -396.145531) (xy 336.372204 -396.201163) (xy 336.403357 -396.260958) (xy 336.427124 -396.324054)
			(xy 336.443161 -396.389542) (xy 336.451239 -396.456481) (xy 336.45124 -396.523904) (xy 336.443164 -396.590843)
			(xy 336.427128 -396.656332) (xy 336.403363 -396.719428) (xy 336.372211 -396.779224) (xy 336.334121 -396.834858)
			(xy 336.312256 -396.860522) (xy 336.306462 -396.867669) (xy 336.299947 -396.884858) (xy 336.299556 -396.89405)
			(xy 336.299556 -397.386302) (xy 336.299975 -397.395488) (xy 336.306484 -397.412672) (xy 336.312256 -397.41983)
			(xy 336.334084 -397.445525) (xy 336.372177 -397.501154) (xy 336.40094 -397.556356) (xy 337.529156 -397.556356)
			(xy 337.537198 -397.489535) (xy 337.553169 -397.424153) (xy 337.576839 -397.361149) (xy 337.607869 -397.301426)
			(xy 337.645814 -397.245839) (xy 337.6676 -397.220186) (xy 337.673385 -397.213033) (xy 337.679907 -397.195848)
			(xy 337.6803 -397.186658) (xy 337.6803 -397.028924) (xy 337.680741 -397.018771) (xy 337.688529 -397.000019)
			(xy 337.70292 -396.985695) (xy 337.721708 -396.977995) (xy 337.731862 -396.977616) (xy 338.448142 -396.977616)
			(xy 338.458268 -396.978091) (xy 338.476986 -396.985829) (xy 338.49134 -397.000118) (xy 338.499162 -397.0188)
			(xy 338.499704 -397.028924) (xy 338.499704 -397.186658) (xy 338.500133 -397.195843) (xy 338.506634 -397.213028)
			(xy 338.512404 -397.220186) (xy 338.5342 -397.245831) (xy 338.572146 -397.301419) (xy 338.603176 -397.361144)
			(xy 338.626847 -397.42415) (xy 338.642818 -397.489532) (xy 338.65086 -397.556355) (xy 338.650859 -397.62366)
			(xy 338.642815 -397.690483) (xy 338.626842 -397.755865) (xy 338.60317 -397.81887) (xy 338.600595 -397.823826)
			(xy 339.729259 -397.823826) (xy 339.729263 -397.756517) (xy 339.737311 -397.689692) (xy 339.753288 -397.624308)
			(xy 339.776965 -397.561301) (xy 339.808004 -397.501577) (xy 339.845958 -397.44599) (xy 339.867748 -397.420338)
			(xy 339.873559 -397.413204) (xy 339.880064 -397.396005) (xy 339.880448 -397.38681) (xy 339.880448 -396.893542)
			(xy 339.880007 -396.884358) (xy 339.873513 -396.867174) (xy 339.867748 -396.860014) (xy 339.84595 -396.83437)
			(xy 339.808001 -396.778783) (xy 339.776968 -396.719058) (xy 339.753295 -396.656052) (xy 339.737322 -396.590669)
			(xy 339.729279 -396.523845) (xy 339.72928 -396.456539) (xy 339.737325 -396.389716) (xy 339.753299 -396.324333)
			(xy 339.776974 -396.261328) (xy 339.808009 -396.201604) (xy 339.845959 -396.146018) (xy 339.867748 -396.120366)
			(xy 339.873547 -396.113223) (xy 339.880059 -396.096031) (xy 339.880448 -396.086838) (xy 339.880448 -395.92885)
			(xy 339.880905 -395.91868) (xy 339.888675 -395.899885) (xy 339.903051 -395.885498) (xy 339.921841 -395.877713)
			(xy 339.93201 -395.877288) (xy 340.64829 -395.877288) (xy 340.658467 -395.877673) (xy 340.677271 -395.885464)
			(xy 340.691658 -395.899862) (xy 340.699435 -395.918672) (xy 340.699852 -395.92885) (xy 340.699852 -396.086838)
			(xy 340.700255 -396.096026) (xy 340.706775 -396.113209) (xy 340.712552 -396.120366) (xy 340.73433 -396.146026)
			(xy 340.77228 -396.201611) (xy 340.803314 -396.261334) (xy 340.826988 -396.324337) (xy 340.842962 -396.389718)
			(xy 340.851007 -396.45654) (xy 340.851007 -396.523845) (xy 340.842964 -396.590667) (xy 340.826992 -396.656048)
			(xy 340.80332 -396.719053) (xy 340.772287 -396.778776) (xy 340.734339 -396.834362) (xy 340.712552 -396.860014)
			(xy 340.706761 -396.867163) (xy 340.700244 -396.884351) (xy 340.699852 -396.893542) (xy 340.699852 -397.38681)
			(xy 340.700268 -397.395996) (xy 340.706779 -397.41318) (xy 340.712552 -397.420338) (xy 340.734302 -397.446021)
			(xy 340.772253 -397.501603) (xy 340.800676 -397.556296) (xy 341.928924 -397.556296) (xy 341.936999 -397.489359)
			(xy 341.953033 -397.42387) (xy 341.976796 -397.360774) (xy 342.007946 -397.300978) (xy 342.046033 -397.245343)
			(xy 342.067896 -397.219678) (xy 342.073684 -397.212527) (xy 342.080204 -397.195341) (xy 342.080596 -397.18615)
			(xy 342.080596 -397.028924) (xy 342.081035 -397.018804) (xy 342.088775 -397.000101) (xy 342.103084 -396.985786)
			(xy 342.121784 -396.978039) (xy 342.131904 -396.977616) (xy 342.848184 -396.977616) (xy 342.858307 -396.978029)
			(xy 342.877014 -396.985775) (xy 342.891329 -397.000093) (xy 342.899072 -397.0188) (xy 342.899492 -397.028924)
			(xy 342.899492 -397.18615) (xy 342.899928 -397.195334) (xy 342.906424 -397.212519) (xy 342.912192 -397.219678)
			(xy 342.934066 -397.245335) (xy 342.972155 -397.300971) (xy 343.003306 -397.360768) (xy 343.02707 -397.423866)
			(xy 343.043105 -397.489356) (xy 343.05118 -397.556295) (xy 343.051179 -397.62372) (xy 343.043102 -397.690659)
			(xy 343.027065 -397.756149) (xy 343.0033 -397.819246) (xy 343.000914 -397.823825) (xy 344.12905 -397.823825)
			(xy 344.129054 -397.756517) (xy 344.137101 -397.689692) (xy 344.153078 -397.624308) (xy 344.176755 -397.561302)
			(xy 344.207793 -397.501577) (xy 344.245746 -397.44599) (xy 344.267536 -397.420338) (xy 344.273346 -397.413202)
			(xy 344.279852 -397.396004) (xy 344.280236 -397.38681) (xy 344.280236 -396.893542) (xy 344.279797 -396.884358)
			(xy 344.273303 -396.867174) (xy 344.267536 -396.860014) (xy 344.245738 -396.83437) (xy 344.20779 -396.778782)
			(xy 344.176757 -396.719058) (xy 344.153085 -396.656052) (xy 344.137113 -396.590669) (xy 344.12907 -396.523845)
			(xy 344.129071 -396.45654) (xy 344.137116 -396.389716) (xy 344.15309 -396.324334) (xy 344.176764 -396.261329)
			(xy 344.207798 -396.201605) (xy 344.245748 -396.146018) (xy 344.267536 -396.120366) (xy 344.273334 -396.113222)
			(xy 344.279847 -396.09603) (xy 344.280236 -396.086838) (xy 344.280236 -395.92885) (xy 344.280705 -395.918682)
			(xy 344.288473 -395.899889) (xy 344.302845 -395.885502) (xy 344.32163 -395.877715) (xy 344.331798 -395.877288)
			(xy 345.048078 -395.877288) (xy 345.058254 -395.877683) (xy 345.077058 -395.88547) (xy 345.091445 -395.899866)
			(xy 345.099222 -395.918673) (xy 345.09964 -395.92885) (xy 345.09964 -396.086838) (xy 345.100045 -396.096025)
			(xy 345.106564 -396.113209) (xy 345.11234 -396.120366) (xy 345.134118 -396.146026) (xy 345.172069 -396.201611)
			(xy 345.203104 -396.261333) (xy 345.226778 -396.324337) (xy 345.242752 -396.389718) (xy 345.250798 -396.45654)
			(xy 345.250798 -396.523845) (xy 345.242755 -396.590667) (xy 345.226782 -396.656049) (xy 345.20311 -396.719053)
			(xy 345.172077 -396.778776) (xy 345.134128 -396.834362) (xy 345.11234 -396.860014) (xy 345.106548 -396.867162)
			(xy 345.100032 -396.884351) (xy 345.09964 -396.893542) (xy 345.09964 -397.38681) (xy 345.100059 -397.395996)
			(xy 345.106568 -397.41318) (xy 345.11234 -397.420338) (xy 345.134091 -397.446021) (xy 345.172042 -397.501602)
			(xy 345.200497 -397.556355) (xy 346.32922 -397.556355) (xy 346.337264 -397.489532) (xy 346.353237 -397.42415)
			(xy 346.37691 -397.361146) (xy 346.407945 -397.301423) (xy 346.445896 -397.245838) (xy 346.467684 -397.220186)
			(xy 346.473467 -397.213031) (xy 346.47999 -397.195848) (xy 346.480384 -397.186658) (xy 346.480384 -397.028924)
			(xy 346.480841 -397.018773) (xy 346.488625 -397.000025) (xy 346.503011 -396.985701) (xy 346.521794 -396.977997)
			(xy 346.531946 -396.977616) (xy 347.248226 -396.977616) (xy 347.258351 -396.978104) (xy 347.277069 -396.985836)
			(xy 347.291423 -397.000121) (xy 347.299246 -397.018801) (xy 347.299788 -397.028924) (xy 347.299788 -397.186658)
			(xy 347.300221 -397.195843) (xy 347.306719 -397.213027) (xy 347.312488 -397.220186) (xy 347.334285 -397.24583)
			(xy 347.372232 -397.301419) (xy 347.403263 -397.361143) (xy 347.426934 -397.424149) (xy 347.442905 -397.489532)
			(xy 347.450948 -397.556355) (xy 347.450947 -397.62366) (xy 347.442903 -397.690483) (xy 347.426929 -397.755865)
			(xy 347.403257 -397.81887) (xy 347.400682 -397.823826) (xy 374.92908 -397.823826) (xy 374.929084 -397.756517)
			(xy 374.937132 -397.689691) (xy 374.95311 -397.624306) (xy 374.976789 -397.5613) (xy 375.007829 -397.501576)
			(xy 375.045785 -397.445989) (xy 375.067576 -397.420338) (xy 375.073379 -397.413197) (xy 375.07989 -397.396003)
			(xy 375.080276 -397.38681) (xy 375.080276 -396.893542) (xy 375.079851 -396.884356) (xy 375.073348 -396.867171)
			(xy 375.067576 -396.860014) (xy 375.045777 -396.83437) (xy 375.007826 -396.778784) (xy 374.976792 -396.719059)
			(xy 374.953118 -396.656053) (xy 374.937144 -396.59067) (xy 374.9291 -396.523846) (xy 374.929101 -396.456539)
			(xy 374.937147 -396.389715) (xy 374.953122 -396.324332) (xy 374.976798 -396.261327) (xy 375.007834 -396.201604)
			(xy 375.045787 -396.146018) (xy 375.067576 -396.120366) (xy 375.073367 -396.113216) (xy 375.079886 -396.096029)
			(xy 375.080276 -396.086838) (xy 375.080276 -395.92885) (xy 375.080706 -395.918677) (xy 375.088481 -395.899876)
			(xy 375.102866 -395.885488) (xy 375.121665 -395.877708) (xy 375.131838 -395.877288) (xy 375.848118 -395.877288)
			(xy 375.858297 -395.87765) (xy 375.877102 -395.885451) (xy 375.891487 -395.899856) (xy 375.899263 -395.91867)
			(xy 375.89968 -395.92885) (xy 375.89968 -396.086838) (xy 375.900076 -396.096027) (xy 375.9066 -396.113211)
			(xy 375.91238 -396.120366) (xy 375.934157 -396.146026) (xy 375.972105 -396.201612) (xy 376.003138 -396.261335)
			(xy 376.02681 -396.324338) (xy 376.042784 -396.389719) (xy 376.050828 -396.456541) (xy 376.050829 -396.523844)
			(xy 376.042786 -396.590666) (xy 376.026815 -396.656047) (xy 376.003144 -396.719051) (xy 375.972113 -396.778775)
			(xy 375.934167 -396.834362) (xy 375.91238 -396.860014) (xy 375.906593 -396.867166) (xy 375.900073 -396.884351)
			(xy 375.89968 -396.893542) (xy 375.89968 -397.38681) (xy 375.90009 -397.395997) (xy 375.906604 -397.413181)
			(xy 375.91238 -397.420338) (xy 375.93413 -397.446021) (xy 375.972078 -397.501604) (xy 376.0005 -397.556296)
			(xy 377.128745 -397.556296) (xy 377.136821 -397.489358) (xy 377.152856 -397.423869) (xy 377.17662 -397.360772)
			(xy 377.207771 -397.300977) (xy 377.24586 -397.245343) (xy 377.267724 -397.219678) (xy 377.273515 -397.212529)
			(xy 377.280032 -397.195341) (xy 377.280424 -397.18615) (xy 377.280424 -397.028924) (xy 377.280836 -397.0188)
			(xy 377.288581 -397.000092) (xy 377.302899 -396.985776) (xy 377.321608 -396.978034) (xy 377.331732 -396.977616)
			(xy 378.048012 -396.977616) (xy 378.058137 -396.978006) (xy 378.076844 -396.985761) (xy 378.091159 -397.000086)
			(xy 378.098901 -397.018798) (xy 378.09932 -397.028924) (xy 378.09932 -397.18615) (xy 378.09975 -397.195335)
			(xy 378.10625 -397.21252) (xy 378.11202 -397.219678) (xy 378.133893 -397.245335) (xy 378.17198 -397.300972)
			(xy 378.203129 -397.360769) (xy 378.226892 -397.423867) (xy 378.242926 -397.489357) (xy 378.251001 -397.556295)
			(xy 378.251 -397.62372) (xy 378.242924 -397.690658) (xy 378.226888 -397.756147) (xy 378.203123 -397.819245)
			(xy 378.200706 -397.823885) (xy 379.328873 -397.823885) (xy 379.328877 -397.756458) (xy 379.336956 -397.689518)
			(xy 379.352995 -397.624027) (xy 379.376762 -397.560929) (xy 379.407915 -397.501131) (xy 379.446007 -397.445496)
			(xy 379.467872 -397.41983) (xy 379.47369 -397.4127) (xy 379.48019 -397.395498) (xy 379.480572 -397.386302)
			(xy 379.480572 -396.89405) (xy 379.480144 -396.884865) (xy 379.473643 -396.86768) (xy 379.467872 -396.860522)
			(xy 379.445999 -396.834864) (xy 379.407913 -396.779228) (xy 379.376764 -396.719431) (xy 379.353002 -396.656333)
			(xy 379.336968 -396.590843) (xy 379.328893 -396.523904) (xy 379.328894 -396.456481) (xy 379.33697 -396.389542)
			(xy 379.353006 -396.324053) (xy 379.37677 -396.260956) (xy 379.40792 -396.201159) (xy 379.446008 -396.145524)
			(xy 379.467872 -396.119858) (xy 379.473678 -396.11272) (xy 379.480185 -396.095524) (xy 379.480572 -396.08633)
			(xy 379.480572 -395.92885) (xy 379.481069 -395.918723) (xy 379.488786 -395.899996) (xy 379.50307 -395.885637)
			(xy 379.521755 -395.877822) (xy 379.53188 -395.877288) (xy 380.24816 -395.877288) (xy 380.258278 -395.877749)
			(xy 380.276979 -395.885481) (xy 380.291294 -395.899784) (xy 380.299043 -395.918478) (xy 380.299468 -395.928596)
			(xy 380.299468 -396.08633) (xy 380.299871 -396.095518) (xy 380.30639 -396.112702) (xy 380.312168 -396.119858)
			(xy 380.334023 -396.145531) (xy 380.372114 -396.201163) (xy 380.403267 -396.260958) (xy 380.427033 -396.324054)
			(xy 380.443071 -396.389543) (xy 380.451148 -396.456481) (xy 380.451149 -396.523904) (xy 380.443073 -396.590842)
			(xy 380.427038 -396.656331) (xy 380.403273 -396.719428) (xy 380.372122 -396.779224) (xy 380.334032 -396.834857)
			(xy 380.312168 -396.860522) (xy 380.306375 -396.86767) (xy 380.299859 -396.884858) (xy 380.299468 -396.89405)
			(xy 380.299468 -397.386302) (xy 380.299884 -397.395488) (xy 380.306394 -397.412672) (xy 380.312168 -397.41983)
			(xy 380.333996 -397.445525) (xy 380.372088 -397.501155) (xy 380.40085 -397.556356) (xy 381.529065 -397.556356)
			(xy 381.537108 -397.489534) (xy 381.553079 -397.424153) (xy 381.576749 -397.361149) (xy 381.60778 -397.301425)
			(xy 381.645726 -397.245838) (xy 381.667512 -397.220186) (xy 381.673298 -397.213034) (xy 381.679819 -397.195849)
			(xy 381.680212 -397.186658) (xy 381.680212 -397.028924) (xy 381.680636 -397.018802) (xy 381.688378 -397.000096)
			(xy 381.702693 -396.985781) (xy 381.721398 -396.978037) (xy 381.73152 -396.977616) (xy 382.448054 -396.977616)
			(xy 382.458175 -396.978164) (xy 382.47689 -396.985872) (xy 382.491247 -397.000139) (xy 382.499072 -397.018806)
			(xy 382.499616 -397.028924) (xy 382.499616 -397.186658) (xy 382.500043 -397.195844) (xy 382.506544 -397.213028)
			(xy 382.512316 -397.220186) (xy 382.534115 -397.245829) (xy 382.572066 -397.301416) (xy 382.603102 -397.36114)
			(xy 382.626776 -397.424146) (xy 382.642749 -397.48953) (xy 382.650793 -397.556354) (xy 382.650793 -397.623661)
			(xy 382.642747 -397.690485) (xy 382.626771 -397.755868) (xy 382.603096 -397.818873) (xy 382.600522 -397.823826)
			(xy 383.729168 -397.823826) (xy 383.729172 -397.756517) (xy 383.73722 -397.689692) (xy 383.753198 -397.624307)
			(xy 383.776876 -397.561301) (xy 383.807914 -397.501576) (xy 383.845869 -397.44599) (xy 383.86766 -397.420338)
			(xy 383.873473 -397.413205) (xy 383.879976 -397.396005) (xy 383.88036 -397.38681) (xy 383.88036 -396.893542)
			(xy 383.879916 -396.884359) (xy 383.873425 -396.867175) (xy 383.86766 -396.860014) (xy 383.845862 -396.83437)
			(xy 383.807912 -396.778783) (xy 383.776878 -396.719058) (xy 383.753205 -396.656053) (xy 383.737232 -396.590669)
			(xy 383.729188 -396.523846) (xy 383.729189 -396.456539) (xy 383.737235 -396.389716) (xy 383.753209 -396.324333)
			(xy 383.776884 -396.261328) (xy 383.80792 -396.201604) (xy 383.845871 -396.146018) (xy 383.86766 -396.120366)
			(xy 383.873461 -396.113224) (xy 383.879971 -396.096031) (xy 383.88036 -396.086838) (xy 383.88036 -395.92885)
			(xy 383.880805 -395.918679) (xy 383.888578 -395.899881) (xy 383.902958 -395.885494) (xy 383.921751 -395.877711)
			(xy 383.931922 -395.877288) (xy 384.648202 -395.877288) (xy 384.65838 -395.877663) (xy 384.677184 -395.885458)
			(xy 384.691571 -395.899859) (xy 384.699347 -395.918672) (xy 384.699764 -395.92885) (xy 384.699764 -396.086838)
			(xy 384.700164 -396.096026) (xy 384.706686 -396.11321) (xy 384.712464 -396.120366) (xy 384.734242 -396.146026)
			(xy 384.772191 -396.201612) (xy 384.803224 -396.261334) (xy 384.826898 -396.324337) (xy 384.842871 -396.389719)
			(xy 384.850916 -396.45654) (xy 384.850917 -396.523845) (xy 384.842874 -396.590666) (xy 384.826902 -396.656048)
			(xy 384.803231 -396.719052) (xy 384.772199 -396.778776) (xy 384.734251 -396.834362) (xy 384.712464 -396.860014)
			(xy 384.706674 -396.867164) (xy 384.700156 -396.884351) (xy 384.699764 -396.893542) (xy 384.699764 -397.38681)
			(xy 384.700177 -397.395997) (xy 384.70669 -397.413181) (xy 384.712464 -397.420338) (xy 384.734214 -397.446021)
			(xy 384.772164 -397.501603) (xy 384.800587 -397.556296) (xy 385.928833 -397.556296) (xy 385.936908 -397.489358)
			(xy 385.952943 -397.42387) (xy 385.976706 -397.360773) (xy 386.007856 -397.300977) (xy 386.045944 -397.245343)
			(xy 386.067808 -397.219678) (xy 386.073597 -397.212528) (xy 386.080116 -397.195341) (xy 386.080508 -397.18615)
			(xy 386.080508 -397.028924) (xy 386.080936 -397.018802) (xy 386.088677 -397.000097) (xy 386.102991 -396.985782)
			(xy 386.121694 -396.978037) (xy 386.131816 -396.977616) (xy 386.848096 -396.977616) (xy 386.85822 -396.97802)
			(xy 386.876927 -396.985769) (xy 386.891242 -397.00009) (xy 386.898984 -397.0188) (xy 386.899404 -397.028924)
			(xy 386.899404 -397.18615) (xy 386.899837 -397.195335) (xy 386.906335 -397.212519) (xy 386.912104 -397.219678)
			(xy 386.933978 -397.245335) (xy 386.972066 -397.300971) (xy 387.003216 -397.360768) (xy 387.026979 -397.423866)
			(xy 387.043014 -397.489356) (xy 387.051089 -397.556295) (xy 387.051088 -397.62372) (xy 387.043011 -397.690659)
			(xy 387.026975 -397.756148) (xy 387.00321 -397.819245) (xy 387.000823 -397.823826) (xy 388.128959 -397.823826)
			(xy 388.128963 -397.756517) (xy 388.137011 -397.689692) (xy 388.152988 -397.624308) (xy 388.176665 -397.561301)
			(xy 388.207704 -397.501577) (xy 388.245658 -397.44599) (xy 388.267448 -397.420338) (xy 388.273259 -397.413204)
			(xy 388.279764 -397.396005) (xy 388.280148 -397.38681) (xy 388.280148 -396.893542) (xy 388.279707 -396.884358)
			(xy 388.273213 -396.867174) (xy 388.267448 -396.860014) (xy 388.24565 -396.83437) (xy 388.207701 -396.778783)
			(xy 388.176668 -396.719058) (xy 388.152995 -396.656052) (xy 388.137022 -396.590669) (xy 388.128979 -396.523845)
			(xy 388.12898 -396.456539) (xy 388.137025 -396.389716) (xy 388.152999 -396.324333) (xy 388.176674 -396.261328)
			(xy 388.207709 -396.201604) (xy 388.245659 -396.146018) (xy 388.267448 -396.120366) (xy 388.273247 -396.113223)
			(xy 388.279759 -396.096031) (xy 388.280148 -396.086838) (xy 388.280148 -395.92885) (xy 388.280605 -395.91868)
			(xy 388.288375 -395.899885) (xy 388.302751 -395.885498) (xy 388.321541 -395.877713) (xy 388.33171 -395.877288)
			(xy 389.04799 -395.877288) (xy 389.058167 -395.877673) (xy 389.076971 -395.885464) (xy 389.091358 -395.899862)
			(xy 389.099135 -395.918672) (xy 389.099552 -395.92885) (xy 389.099552 -396.086838) (xy 389.099955 -396.096026)
			(xy 389.106475 -396.113209) (xy 389.112252 -396.120366) (xy 389.13403 -396.146026) (xy 389.17198 -396.201611)
			(xy 389.203014 -396.261334) (xy 389.226688 -396.324337) (xy 389.242662 -396.389718) (xy 389.250707 -396.45654)
			(xy 389.250707 -396.523845) (xy 389.242664 -396.590667) (xy 389.226692 -396.656048) (xy 389.20302 -396.719053)
			(xy 389.171987 -396.778776) (xy 389.134039 -396.834362) (xy 389.112252 -396.860014) (xy 389.106461 -396.867163)
			(xy 389.099944 -396.884351) (xy 389.099552 -396.893542) (xy 389.099552 -397.38681) (xy 389.099968 -397.395996)
			(xy 389.106479 -397.41318) (xy 389.112252 -397.420338) (xy 389.134002 -397.446021) (xy 389.171953 -397.501603)
			(xy 389.200407 -397.556356) (xy 390.329153 -397.556356) (xy 390.337195 -397.489535) (xy 390.353166 -397.424153)
			(xy 390.376836 -397.36115) (xy 390.407865 -397.301426) (xy 390.44581 -397.245839) (xy 390.467596 -397.220186)
			(xy 390.473381 -397.213032) (xy 390.479903 -397.195848) (xy 390.480296 -397.186658) (xy 390.480296 -397.028924)
			(xy 390.480735 -397.018804) (xy 390.488475 -397.000101) (xy 390.502784 -396.985786) (xy 390.521484 -396.978039)
			(xy 390.531604 -396.977616) (xy 391.248138 -396.977616) (xy 391.258264 -396.978095) (xy 391.276982 -396.985831)
			(xy 391.291336 -397.000119) (xy 391.299158 -397.0188) (xy 391.2997 -397.028924) (xy 391.2997 -397.186658)
			(xy 391.30013 -397.195843) (xy 391.30663 -397.213028) (xy 391.3124 -397.220186) (xy 391.334196 -397.245831)
			(xy 391.372142 -397.301419) (xy 391.403173 -397.361144) (xy 391.426844 -397.424149) (xy 391.442815 -397.489532)
			(xy 391.450857 -397.556355) (xy 391.450856 -397.62366) (xy 391.442812 -397.690483) (xy 391.426839 -397.755865)
			(xy 391.403167 -397.81887) (xy 391.372135 -397.878594) (xy 391.334187 -397.934181) (xy 391.3124 -397.959834)
			(xy 391.306606 -397.966981) (xy 391.30009 -397.98417) (xy 391.2997 -397.993362) (xy 391.2997 -398.486884)
			(xy 391.300118 -398.49607) (xy 391.306626 -398.513255) (xy 391.3124 -398.520412) (xy 391.334222 -398.546036)
			(xy 391.372167 -398.601627) (xy 391.403197 -398.661355) (xy 391.426866 -398.724363) (xy 391.442835 -398.789748)
			(xy 391.450876 -398.856574) (xy 391.450872 -398.923881) (xy 391.442825 -398.990705) (xy 391.42685 -399.056089)
			(xy 391.403175 -399.119095) (xy 391.372139 -399.178819) (xy 391.334189 -399.234407) (xy 391.3124 -399.26006)
			(xy 391.306595 -399.2672) (xy 391.300086 -399.284394) (xy 391.2997 -399.293588) (xy 391.2997 -399.451576)
			(xy 391.299265 -399.461697) (xy 391.291524 -399.4804) (xy 391.277214 -399.494715) (xy 391.258513 -399.502461)
			(xy 391.248392 -399.502884) (xy 390.531858 -399.502884) (xy 390.521732 -399.502409) (xy 390.503014 -399.494671)
			(xy 390.48866 -399.480382) (xy 390.480838 -399.4617) (xy 390.480296 -399.451576) (xy 390.480296 -399.293588)
			(xy 390.479892 -399.2844) (xy 390.473374 -399.267216) (xy 390.467596 -399.26006) (xy 390.445845 -399.234378)
			(xy 390.407898 -399.178795) (xy 390.376865 -399.119075) (xy 390.353192 -399.056075) (xy 390.337218 -398.990696)
			(xy 390.329172 -398.923878) (xy 390.329169 -398.856576) (xy 390.337209 -398.789757) (xy 390.353176 -398.724377)
			(xy 390.376843 -398.661374) (xy 390.40787 -398.601652) (xy 390.445812 -398.546065) (xy 390.467596 -398.520412)
			(xy 390.473412 -398.51328) (xy 390.479915 -398.49608) (xy 390.480296 -398.486884) (xy 390.480296 -397.993362)
			(xy 390.479905 -397.984173) (xy 390.473378 -397.966988) (xy 390.467596 -397.959834) (xy 390.445819 -397.934173)
			(xy 390.407873 -397.878587) (xy 390.376842 -397.818864) (xy 390.35317 -397.755861) (xy 390.337198 -397.69048)
			(xy 390.329154 -397.623659) (xy 390.329153 -397.556356) (xy 389.200407 -397.556356) (xy 389.202988 -397.561322)
			(xy 389.226664 -397.624322) (xy 389.24264 -397.689701) (xy 389.250687 -397.75652) (xy 389.25069 -397.823823)
			(xy 389.24265 -397.890643) (xy 389.226681 -397.956023) (xy 389.203012 -398.019026) (xy 389.171982 -398.078748)
			(xy 389.134038 -398.134334) (xy 389.112252 -398.159986) (xy 389.10643 -398.167113) (xy 389.099932 -398.184318)
			(xy 389.099552 -398.193514) (xy 389.099552 -398.351502) (xy 389.099138 -398.361675) (xy 389.09135 -398.380472)
			(xy 389.076962 -398.394857) (xy 389.058163 -398.40264) (xy 389.04799 -398.403064) (xy 388.33171 -398.403064)
			(xy 388.321539 -398.402628) (xy 388.302745 -398.394847) (xy 388.28836 -398.380465) (xy 388.280574 -398.361673)
			(xy 388.280148 -398.351502) (xy 388.280148 -398.193514) (xy 388.27972 -398.184329) (xy 388.273218 -398.167145)
			(xy 388.267448 -398.159986) (xy 388.245622 -398.134365) (xy 388.207674 -398.078774) (xy 388.176642 -398.019046)
			(xy 388.152971 -397.956038) (xy 388.137 -397.890652) (xy 388.128959 -397.823826) (xy 387.000823 -397.823826)
			(xy 386.972058 -397.879042) (xy 386.933968 -397.934677) (xy 386.912104 -397.960342) (xy 386.906308 -397.967487)
			(xy 386.899793 -397.984678) (xy 386.899404 -397.99387) (xy 386.899404 -398.486376) (xy 386.899825 -398.495562)
			(xy 386.906331 -398.512747) (xy 386.912104 -398.519904) (xy 386.934003 -398.54554) (xy 386.972091 -398.601179)
			(xy 387.003239 -398.660979) (xy 387.027001 -398.72408) (xy 387.043034 -398.789572) (xy 387.051107 -398.856514)
			(xy 387.051104 -398.92394) (xy 387.043025 -398.990881) (xy 387.026985 -399.056372) (xy 387.003217 -399.11947)
			(xy 386.972063 -399.179268) (xy 386.93397 -399.234903) (xy 386.912104 -399.260568) (xy 386.906297 -399.267706)
			(xy 386.899788 -399.284902) (xy 386.899404 -399.294096) (xy 386.899404 -399.451576) (xy 386.898965 -399.461696)
			(xy 386.891225 -399.480399) (xy 386.876916 -399.494714) (xy 386.858216 -399.502461) (xy 386.848096 -399.502884)
			(xy 386.131816 -399.502884) (xy 386.121693 -399.502471) (xy 386.102986 -399.494725) (xy 386.088671 -399.480407)
			(xy 386.080928 -399.4617) (xy 386.080508 -399.451576) (xy 386.080508 -399.294096) (xy 386.080098 -399.284909)
			(xy 386.073584 -399.267725) (xy 386.067808 -399.260568) (xy 386.045979 -399.234874) (xy 386.007889 -399.179244)
			(xy 385.976736 -399.119451) (xy 385.95297 -399.056358) (xy 385.936931 -398.990873) (xy 385.928852 -398.923938)
			(xy 385.928849 -398.856517) (xy 385.936922 -398.789581) (xy 385.952954 -398.724093) (xy 385.976714 -398.660998)
			(xy 386.007861 -398.601203) (xy 386.045946 -398.545569) (xy 386.067808 -398.519904) (xy 386.073586 -398.512746)
			(xy 386.080112 -398.495565) (xy 386.080508 -398.486376) (xy 386.080508 -397.99387) (xy 386.080111 -397.984681)
			(xy 386.073588 -397.967497) (xy 386.067808 -397.960342) (xy 386.045954 -397.934669) (xy 386.007864 -397.879036)
			(xy 385.976712 -397.819241) (xy 385.952947 -397.756145) (xy 385.936911 -397.690657) (xy 385.928834 -397.623719)
			(xy 385.928833 -397.556296) (xy 384.800587 -397.556296) (xy 384.803199 -397.561322) (xy 384.826873 -397.624323)
			(xy 384.842849 -397.689701) (xy 384.850896 -397.75652) (xy 384.850899 -397.823822) (xy 384.842859 -397.890642)
			(xy 384.82689 -397.956022) (xy 384.803222 -398.019025) (xy 384.772193 -398.078748) (xy 384.734249 -398.134334)
			(xy 384.712464 -398.159986) (xy 384.706644 -398.167114) (xy 384.700144 -398.184318) (xy 384.699764 -398.193514)
			(xy 384.699764 -398.351502) (xy 384.699268 -398.36166) (xy 384.691494 -398.380428) (xy 384.677128 -398.394794)
			(xy 384.65836 -398.402568) (xy 384.648202 -398.403064) (xy 383.931922 -398.403064) (xy 383.921752 -398.402618)
			(xy 383.902958 -398.394841) (xy 383.888573 -398.380462) (xy 383.880787 -398.361672) (xy 383.88036 -398.351502)
			(xy 383.88036 -398.193514) (xy 383.87993 -398.184329) (xy 383.873429 -398.167145) (xy 383.86766 -398.159986)
			(xy 383.845834 -398.134365) (xy 383.807885 -398.078775) (xy 383.776852 -398.019047) (xy 383.753181 -397.956038)
			(xy 383.73721 -397.890652) (xy 383.729168 -397.823826) (xy 382.600522 -397.823826) (xy 382.572059 -397.878597)
			(xy 382.534106 -397.934182) (xy 382.512316 -397.959834) (xy 382.506524 -397.966983) (xy 382.500006 -397.98417)
			(xy 382.499616 -397.993362) (xy 382.499616 -398.486884) (xy 382.50003 -398.496071) (xy 382.506541 -398.513255)
			(xy 382.512316 -398.520412) (xy 382.53414 -398.546034) (xy 382.572091 -398.601624) (xy 382.603125 -398.661351)
			(xy 382.626798 -398.72436) (xy 382.64277 -398.789746) (xy 382.650812 -398.856573) (xy 382.650808 -398.923881)
			(xy 382.64276 -398.990707) (xy 382.626782 -399.056092) (xy 382.603103 -399.119098) (xy 382.572063 -399.178822)
			(xy 382.534107 -399.234408) (xy 382.512316 -399.26006) (xy 382.506513 -399.267201) (xy 382.500002 -399.284395)
			(xy 382.499616 -399.293588) (xy 382.499616 -399.451576) (xy 382.499165 -399.461695) (xy 382.491428 -399.480395)
			(xy 382.477122 -399.49471) (xy 382.458427 -399.502459) (xy 382.448308 -399.502884) (xy 381.731774 -399.502884)
			(xy 381.721649 -399.502396) (xy 381.702931 -399.494664) (xy 381.688577 -399.480379) (xy 381.680754 -399.461699)
			(xy 381.680212 -399.451576) (xy 381.680212 -399.293588) (xy 381.679805 -399.284401) (xy 381.673289 -399.267216)
			(xy 381.667512 -399.26006) (xy 381.64576 -399.234378) (xy 381.607812 -399.178796) (xy 381.576779 -399.119076)
			(xy 381.553105 -399.056075) (xy 381.537131 -398.990697) (xy 381.529084 -398.923878) (xy 381.529081 -398.856576)
			(xy 381.537121 -398.789757) (xy 381.553089 -398.724377) (xy 381.576757 -398.661374) (xy 381.607784 -398.601651)
			(xy 381.645727 -398.546064) (xy 381.667512 -398.520412) (xy 381.67333 -398.513282) (xy 381.679831 -398.49608)
			(xy 381.680212 -398.486884) (xy 381.680212 -397.993362) (xy 381.679818 -397.984173) (xy 381.673293 -397.966989)
			(xy 381.667512 -397.959834) (xy 381.645735 -397.934173) (xy 381.607788 -397.878588) (xy 381.576755 -397.818865)
			(xy 381.553083 -397.755862) (xy 381.53711 -397.690481) (xy 381.529066 -397.623659) (xy 381.529065 -397.556356)
			(xy 380.40085 -397.556356) (xy 380.403242 -397.560947) (xy 380.42701 -397.62404) (xy 380.443049 -397.689525)
			(xy 380.451128 -397.756461) (xy 380.451131 -397.823882) (xy 380.443059 -397.890818) (xy 380.427026 -397.956306)
			(xy 380.403265 -398.019401) (xy 380.372117 -398.079196) (xy 380.334031 -398.134829) (xy 380.312168 -398.160494)
			(xy 380.306387 -398.16765) (xy 380.299864 -398.184832) (xy 380.299468 -398.194022) (xy 380.299468 -398.351502)
			(xy 380.298975 -398.361628) (xy 380.291248 -398.380347) (xy 380.276964 -398.394703) (xy 380.258283 -398.402524)
			(xy 380.24816 -398.403064) (xy 379.53188 -398.403064) (xy 379.521752 -398.4027) (xy 379.503041 -398.394938)
			(xy 379.488726 -398.380605) (xy 379.480988 -398.361885) (xy 379.480572 -398.351756) (xy 379.480572 -398.194022)
			(xy 379.480158 -398.184835) (xy 379.473648 -398.16765) (xy 379.467872 -398.160494) (xy 379.445972 -398.134859)
			(xy 379.407886 -398.07922) (xy 379.376738 -398.019419) (xy 379.352978 -397.956318) (xy 379.336946 -397.890826)
			(xy 379.328873 -397.823885) (xy 378.200706 -397.823885) (xy 378.171972 -397.879041) (xy 378.133884 -397.934676)
			(xy 378.11202 -397.960342) (xy 378.106225 -397.967489) (xy 378.099709 -397.984678) (xy 378.09932 -397.99387)
			(xy 378.09932 -398.486376) (xy 378.099737 -398.495563) (xy 378.106245 -398.512747) (xy 378.11202 -398.519904)
			(xy 378.133919 -398.54554) (xy 378.172005 -398.60118) (xy 378.203153 -398.66098) (xy 378.226914 -398.724081)
			(xy 378.242947 -398.789573) (xy 378.251019 -398.856514) (xy 378.251016 -398.92394) (xy 378.242937 -398.99088)
			(xy 378.226898 -399.056371) (xy 378.203131 -399.11947) (xy 378.171977 -399.179267) (xy 378.133885 -399.234902)
			(xy 378.11202 -399.260568) (xy 378.106214 -399.267707) (xy 378.099704 -399.284902) (xy 378.09932 -399.294096)
			(xy 378.09932 -399.451576) (xy 378.098865 -399.461694) (xy 378.091128 -399.480394) (xy 378.076824 -399.494708)
			(xy 378.05813 -399.502458) (xy 378.048012 -399.502884) (xy 377.331732 -399.502884) (xy 377.32161 -399.502458)
			(xy 377.302903 -399.494717) (xy 377.288587 -399.480403) (xy 377.280844 -399.461698) (xy 377.280424 -399.451576)
			(xy 377.280424 -399.294096) (xy 377.280011 -399.284909) (xy 377.273499 -399.267725) (xy 377.267724 -399.260568)
			(xy 377.245895 -399.234874) (xy 377.207803 -399.179244) (xy 377.17665 -399.119452) (xy 377.152882 -399.056359)
			(xy 377.136844 -398.990873) (xy 377.128765 -398.923938) (xy 377.128761 -398.856516) (xy 377.136834 -398.78958)
			(xy 377.152866 -398.724093) (xy 377.176627 -398.660997) (xy 377.207775 -398.601202) (xy 377.245861 -398.545569)
			(xy 377.267724 -398.519904) (xy 377.273504 -398.512747) (xy 377.280028 -398.495565) (xy 377.280424 -398.486376)
			(xy 377.280424 -397.99387) (xy 377.280023 -397.984682) (xy 377.273502 -397.967498) (xy 377.267724 -397.960342)
			(xy 377.245869 -397.934669) (xy 377.207778 -397.879036) (xy 377.176626 -397.819241) (xy 377.15286 -397.756145)
			(xy 377.136823 -397.690657) (xy 377.128746 -397.623719) (xy 377.128745 -397.556296) (xy 376.0005 -397.556296)
			(xy 376.003112 -397.561323) (xy 376.026786 -397.624324) (xy 376.042761 -397.689702) (xy 376.050808 -397.756521)
			(xy 376.050811 -397.823822) (xy 376.042771 -397.890642) (xy 376.026803 -397.956022) (xy 376.003135 -398.019025)
			(xy 375.972108 -398.078747) (xy 375.934165 -398.134333) (xy 375.91238 -398.159986) (xy 375.906562 -398.167116)
			(xy 375.900061 -398.184318) (xy 375.89968 -398.193514) (xy 375.89968 -398.351502) (xy 375.899169 -398.361658)
			(xy 375.891397 -398.380423) (xy 375.877037 -398.394788) (xy 375.858274 -398.402565) (xy 375.848118 -398.403064)
			(xy 375.131838 -398.403064) (xy 375.121669 -398.402605) (xy 375.102876 -398.394833) (xy 375.08849 -398.380458)
			(xy 375.080703 -398.361671) (xy 375.080276 -398.351502) (xy 375.080276 -398.193514) (xy 375.079865 -398.184327)
			(xy 375.073352 -398.167142) (xy 375.067576 -398.159986) (xy 375.04575 -398.134365) (xy 375.007799 -398.078775)
			(xy 374.976766 -398.019048) (xy 374.953093 -397.956039) (xy 374.937122 -397.890652) (xy 374.92908 -397.823826)
			(xy 347.400682 -397.823826) (xy 347.372224 -397.878594) (xy 347.334276 -397.934182) (xy 347.312488 -397.959834)
			(xy 347.306693 -397.96698) (xy 347.300178 -397.98417) (xy 347.299788 -397.993362) (xy 347.299788 -398.486884)
			(xy 347.300209 -398.49607) (xy 347.306715 -398.513254) (xy 347.312488 -398.520412) (xy 347.33431 -398.546035)
			(xy 347.372256 -398.601627) (xy 347.403286 -398.661354) (xy 347.426956 -398.724363) (xy 347.442926 -398.789748)
			(xy 347.450967 -398.856573) (xy 347.450963 -398.923881) (xy 347.442916 -398.990705) (xy 347.42694 -399.056089)
			(xy 347.403264 -399.119095) (xy 347.372228 -399.17882) (xy 347.334277 -399.234407) (xy 347.312488 -399.26006)
			(xy 347.306682 -399.267199) (xy 347.300173 -399.284394) (xy 347.299788 -399.293588) (xy 347.299788 -399.451576)
			(xy 347.299359 -399.46173) (xy 347.291569 -399.480484) (xy 347.277174 -399.494809) (xy 347.258382 -399.502507)
			(xy 347.248226 -399.502884) (xy 346.531946 -399.502884) (xy 346.521825 -399.502336) (xy 346.50311 -399.494628)
			(xy 346.488753 -399.480361) (xy 346.480928 -399.461694) (xy 346.480384 -399.451576) (xy 346.480384 -399.293588)
			(xy 346.479983 -399.2844) (xy 346.473463 -399.267215) (xy 346.467684 -399.26006) (xy 346.44593 -399.234379)
			(xy 346.407977 -399.178798) (xy 346.37694 -399.119079) (xy 346.353263 -399.056078) (xy 346.337287 -398.990699)
			(xy 346.329239 -398.923879) (xy 346.329236 -398.856576) (xy 346.337277 -398.789755) (xy 346.353247 -398.724374)
			(xy 346.376918 -398.661371) (xy 346.40795 -398.601648) (xy 346.445897 -398.546064) (xy 346.467684 -398.520412)
			(xy 346.473499 -398.513279) (xy 346.480003 -398.496079) (xy 346.480384 -398.486884) (xy 346.480384 -397.993362)
			(xy 346.479996 -397.984172) (xy 346.473467 -397.966988) (xy 346.467684 -397.959834) (xy 346.445905 -397.934174)
			(xy 346.407953 -397.87859) (xy 346.376917 -397.818868) (xy 346.353241 -397.755864) (xy 346.337266 -397.690483)
			(xy 346.329221 -397.62366) (xy 346.32922 -397.556355) (xy 345.200497 -397.556355) (xy 345.203078 -397.561321)
			(xy 345.226754 -397.624322) (xy 345.24273 -397.689701) (xy 345.250778 -397.75652) (xy 345.250781 -397.823823)
			(xy 345.242741 -397.890643) (xy 345.226771 -397.956023) (xy 345.203102 -398.019026) (xy 345.172072 -398.078749)
			(xy 345.134126 -398.134334) (xy 345.11234 -398.159986) (xy 345.106517 -398.167112) (xy 345.10002 -398.184318)
			(xy 345.09964 -398.193514) (xy 345.09964 -398.351502) (xy 345.099237 -398.361676) (xy 345.091447 -398.380475)
			(xy 345.077055 -398.394861) (xy 345.058253 -398.402642) (xy 345.048078 -398.403064) (xy 344.331798 -398.403064)
			(xy 344.32164 -398.402568) (xy 344.302872 -398.394794) (xy 344.288506 -398.380428) (xy 344.280732 -398.36166)
			(xy 344.280236 -398.351502) (xy 344.280236 -398.193514) (xy 344.279811 -398.184329) (xy 344.273307 -398.167144)
			(xy 344.267536 -398.159986) (xy 344.245711 -398.134365) (xy 344.207763 -398.078774) (xy 344.176732 -398.019046)
			(xy 344.153061 -397.956037) (xy 344.137091 -397.890651) (xy 344.12905 -397.823825) (xy 343.000914 -397.823825)
			(xy 342.972147 -397.879042) (xy 342.934057 -397.934677) (xy 342.912192 -397.960342) (xy 342.906394 -397.967486)
			(xy 342.899881 -397.984678) (xy 342.899492 -397.99387) (xy 342.899492 -398.486376) (xy 342.899916 -398.495562)
			(xy 342.90642 -398.512746) (xy 342.912192 -398.519904) (xy 342.934092 -398.54554) (xy 342.97218 -398.601178)
			(xy 343.003329 -398.660979) (xy 343.027092 -398.724079) (xy 343.043125 -398.789572) (xy 343.051198 -398.856514)
			(xy 343.051195 -398.92394) (xy 343.043115 -398.990881) (xy 343.027076 -399.056372) (xy 343.003307 -399.119471)
			(xy 342.972152 -399.179268) (xy 342.934058 -399.234903) (xy 342.912192 -399.260568) (xy 342.906383 -399.267704)
			(xy 342.899876 -399.284902) (xy 342.899492 -399.294096) (xy 342.899492 -399.451576) (xy 342.899064 -399.461698)
			(xy 342.891323 -399.480403) (xy 342.877009 -399.494718) (xy 342.858306 -399.502463) (xy 342.848184 -399.502884)
			(xy 342.131904 -399.502884) (xy 342.12178 -399.50248) (xy 342.103073 -399.494731) (xy 342.088758 -399.48041)
			(xy 342.081016 -399.4617) (xy 342.080596 -399.451576) (xy 342.080596 -399.294096) (xy 342.080189 -399.284909)
			(xy 342.073673 -399.267724) (xy 342.067896 -399.260568) (xy 342.046068 -399.234874) (xy 342.007978 -399.179243)
			(xy 341.976826 -399.119451) (xy 341.95306 -399.056358) (xy 341.937022 -398.990872) (xy 341.928943 -398.923937)
			(xy 341.92894 -398.856517) (xy 341.937012 -398.789581) (xy 341.953044 -398.724094) (xy 341.976804 -398.660999)
			(xy 342.00795 -398.601203) (xy 342.046034 -398.545569) (xy 342.067896 -398.519904) (xy 342.073673 -398.512745)
			(xy 342.080199 -398.495565) (xy 342.080596 -398.486376) (xy 342.080596 -397.99387) (xy 342.080201 -397.984681)
			(xy 342.073677 -397.967497) (xy 342.067896 -397.960342) (xy 342.046042 -397.934669) (xy 342.007953 -397.879035)
			(xy 341.976802 -397.81924) (xy 341.953038 -397.756144) (xy 341.937002 -397.690656) (xy 341.928925 -397.623719)
			(xy 341.928924 -397.556296) (xy 340.800676 -397.556296) (xy 340.803288 -397.561322) (xy 340.826964 -397.624322)
			(xy 340.84294 -397.689701) (xy 340.850987 -397.75652) (xy 340.85099 -397.823823) (xy 340.84295 -397.890643)
			(xy 340.826981 -397.956023) (xy 340.803312 -398.019026) (xy 340.772282 -398.078748) (xy 340.734338 -398.134334)
			(xy 340.712552 -398.159986) (xy 340.70673 -398.167113) (xy 340.700232 -398.184318) (xy 340.699852 -398.193514)
			(xy 340.699852 -398.351502) (xy 340.699438 -398.361675) (xy 340.69165 -398.380472) (xy 340.677262 -398.394857)
			(xy 340.658463 -398.40264) (xy 340.64829 -398.403064) (xy 339.93201 -398.403064) (xy 339.921839 -398.402628)
			(xy 339.903045 -398.394847) (xy 339.88866 -398.380465) (xy 339.880874 -398.361673) (xy 339.880448 -398.351502)
			(xy 339.880448 -398.193514) (xy 339.88002 -398.184329) (xy 339.873518 -398.167145) (xy 339.867748 -398.159986)
			(xy 339.845922 -398.134365) (xy 339.807974 -398.078774) (xy 339.776942 -398.019046) (xy 339.753271 -397.956038)
			(xy 339.7373 -397.890652) (xy 339.729259 -397.823826) (xy 338.600595 -397.823826) (xy 338.572138 -397.878594)
			(xy 338.534191 -397.934181) (xy 338.512404 -397.959834) (xy 338.506611 -397.966982) (xy 338.500094 -397.98417)
			(xy 338.499704 -397.993362) (xy 338.499704 -398.486884) (xy 338.500121 -398.49607) (xy 338.50663 -398.513255)
			(xy 338.512404 -398.520412) (xy 338.534226 -398.546036) (xy 338.572171 -398.601627) (xy 338.6032 -398.661355)
			(xy 338.626869 -398.724363) (xy 338.642838 -398.789748) (xy 338.650879 -398.856574) (xy 338.650875 -398.923881)
			(xy 338.642828 -398.990705) (xy 338.626853 -399.056089) (xy 338.603178 -399.119094) (xy 338.572143 -399.178819)
			(xy 338.534193 -399.234407) (xy 338.512404 -399.26006) (xy 338.5066 -399.2672) (xy 338.50009 -399.284394)
			(xy 338.499704 -399.293588) (xy 338.499704 -399.451576) (xy 338.499259 -399.461728) (xy 338.491472 -399.480479)
			(xy 338.477082 -399.494803) (xy 338.458296 -399.502505) (xy 338.448142 -399.502884) (xy 337.731862 -399.502884)
			(xy 337.721736 -399.502405) (xy 337.703018 -399.494669) (xy 337.688664 -399.480381) (xy 337.680842 -399.4617)
			(xy 337.6803 -399.451576) (xy 337.6803 -399.293588) (xy 337.679895 -399.2844) (xy 337.673378 -399.267216)
			(xy 337.6676 -399.26006) (xy 337.645849 -399.234378) (xy 337.607901 -399.178795) (xy 337.576869 -399.119075)
			(xy 337.553196 -399.056075) (xy 337.537221 -398.990697) (xy 337.529175 -398.923878) (xy 337.529172 -398.856576)
			(xy 337.537212 -398.789757) (xy 337.55318 -398.724377) (xy 337.576847 -398.661374) (xy 337.607874 -398.601651)
			(xy 337.645816 -398.546065) (xy 337.6676 -398.520412) (xy 337.673416 -398.513281) (xy 337.679919 -398.49608)
			(xy 337.6803 -398.486884) (xy 337.6803 -397.993362) (xy 337.679908 -397.984173) (xy 337.673382 -397.966989)
			(xy 337.6676 -397.959834) (xy 337.645823 -397.934173) (xy 337.607877 -397.878587) (xy 337.576845 -397.818864)
			(xy 337.553174 -397.755861) (xy 337.537201 -397.69048) (xy 337.529157 -397.623659) (xy 337.529156 -397.556356)
			(xy 336.40094 -397.556356) (xy 336.403332 -397.560946) (xy 336.4271 -397.624039) (xy 336.443139 -397.689525)
			(xy 336.451219 -397.756461) (xy 336.451222 -397.823882) (xy 336.44315 -397.890819) (xy 336.427117 -397.956306)
			(xy 336.403355 -398.019402) (xy 336.372206 -398.079196) (xy 336.334119 -398.13483) (xy 336.312256 -398.160494)
			(xy 336.306474 -398.167649) (xy 336.299952 -398.184832) (xy 336.299556 -398.194022) (xy 336.299556 -398.351502)
			(xy 336.299075 -398.361629) (xy 336.291346 -398.380351) (xy 336.277058 -398.394708) (xy 336.258373 -398.402526)
			(xy 336.248248 -398.403064) (xy 335.531968 -398.403064) (xy 335.521807 -398.402704) (xy 335.503047 -398.394891)
			(xy 335.488724 -398.380475) (xy 335.481032 -398.361665) (xy 335.48066 -398.351502) (xy 335.48066 -398.194022)
			(xy 335.480226 -398.184838) (xy 335.473727 -398.167654) (xy 335.46796 -398.160494) (xy 335.44606 -398.134859)
			(xy 335.407975 -398.079219) (xy 335.376828 -398.019418) (xy 335.353068 -397.956318) (xy 335.337036 -397.890825)
			(xy 335.328964 -397.823884) (xy 334.200796 -397.823884) (xy 334.172062 -397.879042) (xy 334.133972 -397.934677)
			(xy 334.112108 -397.960342) (xy 334.106312 -397.967488) (xy 334.099797 -397.984678) (xy 334.099408 -397.99387)
			(xy 334.099408 -398.486376) (xy 334.099828 -398.495562) (xy 334.106335 -398.512747) (xy 334.112108 -398.519904)
			(xy 334.134007 -398.54554) (xy 334.172094 -398.601179) (xy 334.203243 -398.660979) (xy 334.227005 -398.72408)
			(xy 334.243037 -398.789573) (xy 334.25111 -398.856514) (xy 334.251107 -398.92394) (xy 334.243028 -398.990881)
			(xy 334.226989 -399.056372) (xy 334.203221 -399.11947) (xy 334.172066 -399.179267) (xy 334.133974 -399.234903)
			(xy 334.112108 -399.260568) (xy 334.106301 -399.267706) (xy 334.099792 -399.284902) (xy 334.099408 -399.294096)
			(xy 334.099408 -399.451576) (xy 334.098965 -399.461696) (xy 334.091226 -399.480398) (xy 334.076918 -399.494712)
			(xy 334.05822 -399.50246) (xy 334.0481 -399.502884) (xy 333.33182 -399.502884) (xy 333.321697 -399.502467)
			(xy 333.302991 -399.494723) (xy 333.288675 -399.480406) (xy 333.280932 -399.461699) (xy 333.280512 -399.451576)
			(xy 333.280512 -399.294096) (xy 333.280101 -399.284909) (xy 333.273587 -399.267725) (xy 333.267812 -399.260568)
			(xy 333.245983 -399.234874) (xy 333.207892 -399.179244) (xy 333.176739 -399.119452) (xy 333.152973 -399.056358)
			(xy 333.136934 -398.990873) (xy 333.128855 -398.923938) (xy 333.128852 -398.856516) (xy 333.136925 -398.78958)
			(xy 333.152957 -398.724093) (xy 333.176717 -398.660998) (xy 333.207865 -398.601203) (xy 333.24595 -398.545569)
			(xy 333.267812 -398.519904) (xy 333.273591 -398.512746) (xy 333.280116 -398.495565) (xy 333.280512 -398.486376)
			(xy 333.280512 -397.99387) (xy 333.280114 -397.984682) (xy 333.273592 -397.967497) (xy 333.267812 -397.960342)
			(xy 333.245957 -397.934669) (xy 333.207868 -397.879036) (xy 333.176716 -397.819241) (xy 333.152951 -397.756145)
			(xy 333.136914 -397.690657) (xy 333.128837 -397.623719) (xy 333.128836 -397.556296) (xy 332.00059 -397.556296)
			(xy 332.003202 -397.561323) (xy 332.026877 -397.624323) (xy 332.042852 -397.689701) (xy 332.050899 -397.75652)
			(xy 332.050902 -397.823822) (xy 332.042862 -397.890642) (xy 332.026893 -397.956022) (xy 332.003225 -398.019025)
			(xy 331.972197 -398.078748) (xy 331.934253 -398.134334) (xy 331.912468 -398.159986) (xy 331.906648 -398.167115)
			(xy 331.900148 -398.184318) (xy 331.899768 -398.193514) (xy 331.899768 -398.351502) (xy 331.899268 -398.361659)
			(xy 331.891494 -398.380427) (xy 331.877131 -398.394792) (xy 331.858363 -398.402568) (xy 331.848206 -398.403064)
			(xy 331.131926 -398.403064) (xy 331.121756 -398.402615) (xy 331.102963 -398.394839) (xy 331.088577 -398.380461)
			(xy 331.080791 -398.361671) (xy 331.080364 -398.351502) (xy 331.080364 -398.193514) (xy 331.079933 -398.184329)
			(xy 331.073432 -398.167146) (xy 331.067664 -398.159986) (xy 331.045838 -398.134365) (xy 331.007889 -398.078775)
			(xy 330.976856 -398.019047) (xy 330.953184 -397.956038) (xy 330.937213 -397.890652) (xy 330.929171 -397.823826)
			(xy 326.525636 -397.823826) (xy 326.525636 -401.723737) (xy 330.929183 -401.723737) (xy 330.929184 -401.65643)
			(xy 330.937231 -401.589605) (xy 330.953207 -401.524221) (xy 330.976884 -401.461216) (xy 331.007921 -401.401492)
			(xy 331.045874 -401.345906) (xy 331.067664 -401.320254) (xy 331.07347 -401.313116) (xy 331.079977 -401.29592)
			(xy 331.080364 -401.286726) (xy 331.080364 -400.793458) (xy 331.07996 -400.78427) (xy 331.073441 -400.767087)
			(xy 331.067664 -400.75993) (xy 331.045882 -400.734273) (xy 331.007931 -400.678688) (xy 330.976896 -400.618965)
			(xy 330.953222 -400.555961) (xy 330.937248 -400.490579) (xy 330.929203 -400.423757) (xy 330.929202 -400.356452)
			(xy 330.937246 -400.289629) (xy 330.953219 -400.224247) (xy 330.976892 -400.161243) (xy 331.007926 -400.10152)
			(xy 331.045876 -400.045934) (xy 331.067664 -400.020282) (xy 331.073459 -400.013136) (xy 331.079973 -399.995946)
			(xy 331.080364 -399.986754) (xy 331.080364 -399.828766) (xy 331.080806 -399.818603) (xy 331.088597 -399.799828)
			(xy 331.102978 -399.785463) (xy 331.121762 -399.777694) (xy 331.131926 -399.777204) (xy 331.848206 -399.777204)
			(xy 331.85836 -399.777728) (xy 331.877123 -399.785498) (xy 331.891486 -399.799854) (xy 331.899267 -399.818612)
			(xy 331.899768 -399.828766) (xy 331.899768 -399.986754) (xy 331.900208 -399.995938) (xy 331.906702 -400.013122)
			(xy 331.912468 -400.020282) (xy 331.934262 -400.045929) (xy 331.97221 -400.101517) (xy 332.003242 -400.161241)
			(xy 332.026915 -400.224246) (xy 332.042887 -400.289629) (xy 332.05093 -400.356452) (xy 332.05093 -400.423757)
			(xy 332.042885 -400.49058) (xy 332.026912 -400.555963) (xy 332.003239 -400.618967) (xy 331.972205 -400.678691)
			(xy 331.934256 -400.734278) (xy 331.912468 -400.75993) (xy 331.906672 -400.767076) (xy 331.900158 -400.784266)
			(xy 331.899768 -400.793458) (xy 331.899768 -401.286726) (xy 331.900173 -401.295914) (xy 331.906691 -401.313098)
			(xy 331.912468 -401.320254) (xy 331.934234 -401.345924) (xy 331.972183 -401.401508) (xy 332.003216 -401.461229)
			(xy 332.02689 -401.524231) (xy 332.042864 -401.589611) (xy 332.05091 -401.656432) (xy 332.050912 -401.723735)
			(xy 332.04287 -401.790556) (xy 332.0269 -401.855937) (xy 332.00323 -401.91894) (xy 331.9722 -401.978663)
			(xy 331.934254 -402.03425) (xy 331.912468 -402.059902) (xy 331.906684 -402.067056) (xy 331.900163 -402.08424)
			(xy 331.899768 -402.09343) (xy 331.899768 -402.251418) (xy 331.899282 -402.261576) (xy 331.891502 -402.280345)
			(xy 331.877135 -402.294709) (xy 331.858364 -402.302484) (xy 331.848206 -402.30298) (xy 331.131926 -402.30298)
			(xy 331.121758 -402.302515) (xy 331.102968 -402.294742) (xy 331.088583 -402.280369) (xy 331.080794 -402.261585)
			(xy 331.080364 -402.251418) (xy 331.080364 -402.09343) (xy 331.079925 -402.084246) (xy 331.07343 -402.067062)
			(xy 331.067664 -402.059902) (xy 331.045854 -402.034268) (xy 331.007904 -401.97868) (xy 330.97687 -401.918954)
			(xy 330.953197 -401.855947) (xy 330.937225 -401.790562) (xy 330.929183 -401.723737) (xy 326.525636 -401.723737)
			(xy 326.525636 -402.823878) (xy 333.128796 -402.823878) (xy 333.128801 -402.75645) (xy 333.136882 -402.689508)
			(xy 333.152922 -402.624016) (xy 333.176693 -402.560918) (xy 333.20785 -402.50112) (xy 333.245945 -402.445485)
			(xy 333.267812 -402.41982) (xy 333.273626 -402.412687) (xy 333.28013 -402.395487) (xy 333.280512 -402.386292)
			(xy 333.280512 -401.89404) (xy 333.28008 -401.884855) (xy 333.273581 -401.867671) (xy 333.267812 -401.860512)
			(xy 333.245928 -401.834863) (xy 333.207839 -401.779227) (xy 333.176689 -401.719428) (xy 333.152925 -401.656329)
			(xy 333.136891 -401.590838) (xy 333.128816 -401.523898) (xy 333.128818 -401.456472) (xy 333.136896 -401.389532)
			(xy 333.152934 -401.324042) (xy 333.176701 -401.260944) (xy 333.207855 -401.201148) (xy 333.245946 -401.145513)
			(xy 333.267812 -401.119848) (xy 333.273615 -401.112707) (xy 333.280125 -401.095513) (xy 333.280512 -401.08632)
			(xy 333.280512 -400.92884) (xy 333.280949 -400.918719) (xy 333.288686 -400.900014) (xy 333.302997 -400.885698)
			(xy 333.321699 -400.877953) (xy 333.33182 -400.877532) (xy 334.0481 -400.877532) (xy 334.058226 -400.877917)
			(xy 334.076936 -400.885671) (xy 334.091252 -400.899997) (xy 334.098991 -400.918713) (xy 334.099408 -400.92884)
			(xy 334.099408 -401.08632) (xy 334.099807 -401.095508) (xy 334.106328 -401.112693) (xy 334.112108 -401.119848)
			(xy 334.133952 -401.14553) (xy 334.172041 -401.201162) (xy 334.203192 -401.260956) (xy 334.226957 -401.324051)
			(xy 334.242994 -401.389538) (xy 334.251071 -401.456474) (xy 334.251073 -401.523896) (xy 334.242999 -401.590833)
			(xy 334.226966 -401.656321) (xy 334.203204 -401.719417) (xy 334.200923 -401.723796) (xy 335.328975 -401.723796)
			(xy 335.328977 -401.656371) (xy 335.337055 -401.589432) (xy 335.353091 -401.523942) (xy 335.376856 -401.460845)
			(xy 335.408007 -401.401048) (xy 335.446096 -401.345412) (xy 335.46796 -401.319746) (xy 335.473769 -401.31261)
			(xy 335.480275 -401.295412) (xy 335.48066 -401.286218) (xy 335.48066 -400.793966) (xy 335.480253 -400.784779)
			(xy 335.473735 -400.767595) (xy 335.46796 -400.760438) (xy 335.446103 -400.734767) (xy 335.408017 -400.679133)
			(xy 335.376868 -400.619337) (xy 335.353106 -400.556241) (xy 335.337071 -400.490753) (xy 335.328995 -400.423816)
			(xy 335.328995 -400.356393) (xy 335.337069 -400.289456) (xy 335.353103 -400.223968) (xy 335.376865 -400.160872)
			(xy 335.408012 -400.101075) (xy 335.446098 -400.04544) (xy 335.46796 -400.019774) (xy 335.473757 -400.01263)
			(xy 335.48027 -399.995438) (xy 335.48066 -399.986246) (xy 335.48066 -399.828766) (xy 335.481099 -399.818635)
			(xy 335.488842 -399.799909) (xy 335.503143 -399.785553) (xy 335.521839 -399.777739) (xy 335.531968 -399.777204)
			(xy 336.248248 -399.777204) (xy 336.258406 -399.777583) (xy 336.27716 -399.785395) (xy 336.291482 -399.799804)
			(xy 336.299179 -399.818606) (xy 336.299556 -399.828766) (xy 336.299556 -399.986246) (xy 336.300002 -399.995429)
			(xy 336.306492 -400.012613) (xy 336.312256 -400.019774) (xy 336.334127 -400.045434) (xy 336.372219 -400.101068)
			(xy 336.403372 -400.160864) (xy 336.427138 -400.223962) (xy 336.443174 -400.289452) (xy 336.45125 -400.356392)
			(xy 336.451249 -400.423817) (xy 336.443172 -400.490756) (xy 336.427135 -400.556246) (xy 336.403368 -400.619344)
			(xy 336.372214 -400.67914) (xy 336.334122 -400.734774) (xy 336.312256 -400.760438) (xy 336.306455 -400.76758)
			(xy 336.299944 -400.784773) (xy 336.299556 -400.793966) (xy 336.299556 -401.286218) (xy 336.299967 -401.295405)
			(xy 336.306481 -401.312589) (xy 336.312256 -401.319746) (xy 336.3341 -401.345428) (xy 336.372192 -401.401059)
			(xy 336.403346 -401.460853) (xy 336.427114 -401.523948) (xy 336.443152 -401.589435) (xy 336.45123 -401.656372)
			(xy 336.451232 -401.723795) (xy 336.443158 -401.790732) (xy 336.427123 -401.856221) (xy 336.40336 -401.919317)
			(xy 336.372209 -401.979112) (xy 336.33412 -402.034746) (xy 336.312256 -402.06041) (xy 336.306467 -402.06756)
			(xy 336.299949 -402.084747) (xy 336.299556 -402.093938) (xy 336.299556 -402.251418) (xy 336.299088 -402.261546)
			(xy 336.291354 -402.280269) (xy 336.277062 -402.294625) (xy 336.258374 -402.302443) (xy 336.248248 -402.30298)
			(xy 335.531968 -402.30298) (xy 335.521809 -402.302604) (xy 335.503052 -402.294794) (xy 335.488729 -402.280384)
			(xy 335.481034 -402.261579) (xy 335.48066 -402.251418) (xy 335.48066 -402.093938) (xy 335.480218 -402.084754)
			(xy 335.473725 -402.06757) (xy 335.46796 -402.06041) (xy 335.446076 -402.034762) (xy 335.40799 -401.979124)
			(xy 335.376843 -401.919325) (xy 335.353082 -401.856226) (xy 335.337049 -401.790735) (xy 335.328975 -401.723796)
			(xy 334.200923 -401.723796) (xy 334.172056 -401.779212) (xy 334.13397 -401.834847) (xy 334.112108 -401.860512)
			(xy 334.106325 -401.867667) (xy 334.099802 -401.88485) (xy 334.099408 -401.89404) (xy 334.099408 -402.386292)
			(xy 334.09982 -402.395479) (xy 334.106332 -402.412663) (xy 334.112108 -402.41982) (xy 334.133925 -402.445524)
			(xy 334.172014 -402.501153) (xy 334.203166 -402.560944) (xy 334.226933 -402.624036) (xy 334.242972 -402.68952)
			(xy 334.251051 -402.756454) (xy 334.251055 -402.823818) (xy 337.529116 -402.823818) (xy 337.52912 -402.75651)
			(xy 337.537169 -402.689685) (xy 337.553145 -402.6243) (xy 337.576822 -402.561294) (xy 337.607859 -402.501569)
			(xy 337.645811 -402.445981) (xy 337.6676 -402.420328) (xy 337.67341 -402.413192) (xy 337.679917 -402.395994)
			(xy 337.6803 -402.3868) (xy 337.6803 -401.893532) (xy 337.679874 -401.884346) (xy 337.673371 -401.867162)
			(xy 337.6676 -401.860004) (xy 337.645794 -401.834367) (xy 337.607848 -401.778778) (xy 337.576818 -401.719052)
			(xy 337.553148 -401.656045) (xy 337.537178 -401.590662) (xy 337.529136 -401.523838) (xy 337.529137 -401.456532)
			(xy 337.537183 -401.389709) (xy 337.553157 -401.324326) (xy 337.57683 -401.261321) (xy 337.607864 -401.201596)
			(xy 337.645812 -401.146009) (xy 337.6676 -401.120356) (xy 337.673398 -401.113212) (xy 337.679912 -401.09602)
			(xy 337.6803 -401.086828) (xy 337.6803 -400.92884) (xy 337.680755 -400.918688) (xy 337.688537 -400.899937)
			(xy 337.702924 -400.885612) (xy 337.721709 -400.877911) (xy 337.731862 -400.877532) (xy 338.448142 -400.877532)
			(xy 338.45827 -400.877992) (xy 338.476991 -400.885732) (xy 338.491346 -400.900026) (xy 338.499165 -400.918714)
			(xy 338.499704 -400.92884) (xy 338.499704 -401.086828) (xy 338.5001 -401.096017) (xy 338.506623 -401.113201)
			(xy 338.512404 -401.120356) (xy 338.534171 -401.146025) (xy 338.572117 -401.20161) (xy 338.603149 -401.261332)
			(xy 338.626821 -401.324334) (xy 338.642794 -401.389714) (xy 338.650839 -401.456534) (xy 338.650841 -401.523836)
			(xy 338.6428 -401.590657) (xy 338.62683 -401.656037) (xy 338.603161 -401.719041) (xy 338.600721 -401.723737)
			(xy 339.72927 -401.723737) (xy 339.729272 -401.65643) (xy 339.737319 -401.589606) (xy 339.753294 -401.524222)
			(xy 339.77697 -401.461217) (xy 339.808006 -401.401492) (xy 339.845959 -401.345906) (xy 339.867748 -401.320254)
			(xy 339.873553 -401.313115) (xy 339.880061 -401.295919) (xy 339.880448 -401.286726) (xy 339.880448 -400.793458)
			(xy 339.880047 -400.78427) (xy 339.873526 -400.767086) (xy 339.867748 -400.75993) (xy 339.845966 -400.734273)
			(xy 339.808017 -400.678687) (xy 339.776983 -400.618965) (xy 339.753309 -400.555961) (xy 339.737335 -400.490579)
			(xy 339.729291 -400.423757) (xy 339.72929 -400.356452) (xy 339.737334 -400.28963) (xy 339.753306 -400.224248)
			(xy 339.776979 -400.161244) (xy 339.808012 -400.10152) (xy 339.845961 -400.045934) (xy 339.867748 -400.020282)
			(xy 339.873541 -400.013134) (xy 339.880056 -399.995946) (xy 339.880448 -399.986754) (xy 339.880448 -399.828766)
			(xy 339.880906 -399.818605) (xy 339.888693 -399.799833) (xy 339.90307 -399.785469) (xy 339.921848 -399.777697)
			(xy 339.93201 -399.777204) (xy 340.64829 -399.777204) (xy 340.658443 -399.777741) (xy 340.677205 -399.785506)
			(xy 340.69157 -399.799858) (xy 340.699351 -399.818613) (xy 340.699852 -399.828766) (xy 340.699852 -399.986754)
			(xy 340.700295 -399.995937) (xy 340.706787 -400.013121) (xy 340.712552 -400.020282) (xy 340.734346 -400.045929)
			(xy 340.772295 -400.101516) (xy 340.803329 -400.16124) (xy 340.827002 -400.224245) (xy 340.842975 -400.289628)
			(xy 340.851018 -400.356452) (xy 340.851018 -400.423757) (xy 340.842973 -400.490581) (xy 340.826999 -400.555963)
			(xy 340.803325 -400.618968) (xy 340.772291 -400.678692) (xy 340.734341 -400.734278) (xy 340.712552 -400.75993)
			(xy 340.706754 -400.767074) (xy 340.700242 -400.784266) (xy 340.699852 -400.793458) (xy 340.699852 -401.286726)
			(xy 340.70026 -401.295913) (xy 340.706777 -401.313097) (xy 340.712552 -401.320254) (xy 340.734318 -401.345924)
			(xy 340.772268 -401.401508) (xy 340.803303 -401.461229) (xy 340.826977 -401.524231) (xy 340.842952 -401.589611)
			(xy 340.850998 -401.656432) (xy 340.851 -401.723735) (xy 340.842958 -401.790556) (xy 340.826987 -401.855937)
			(xy 340.803316 -401.918941) (xy 340.772285 -401.978664) (xy 340.734338 -402.03425) (xy 340.712552 -402.059902)
			(xy 340.706766 -402.067055) (xy 340.700246 -402.08424) (xy 340.699852 -402.09343) (xy 340.699852 -402.251418)
			(xy 340.699381 -402.261578) (xy 340.691599 -402.28035) (xy 340.677226 -402.294715) (xy 340.65845 -402.302487)
			(xy 340.64829 -402.30298) (xy 339.93201 -402.30298) (xy 339.921855 -402.302459) (xy 339.90309 -402.294691)
			(xy 339.888725 -402.280334) (xy 339.880947 -402.261573) (xy 339.880448 -402.251418) (xy 339.880448 -402.09343)
			(xy 339.880013 -402.084246) (xy 339.873515 -402.067062) (xy 339.867748 -402.059902) (xy 339.845938 -402.034268)
			(xy 339.807989 -401.978679) (xy 339.776957 -401.918953) (xy 339.753285 -401.855946) (xy 339.737313 -401.790562)
			(xy 339.72927 -401.723737) (xy 338.600721 -401.723737) (xy 338.572133 -401.778764) (xy 338.534189 -401.834351)
			(xy 338.512404 -401.860004) (xy 338.506624 -401.867161) (xy 338.500099 -401.884342) (xy 338.499704 -401.893532)
			(xy 338.499704 -402.3868) (xy 338.500113 -402.395987) (xy 338.506628 -402.413172) (xy 338.512404 -402.420328)
			(xy 338.534143 -402.44602) (xy 338.572091 -402.501601) (xy 338.603124 -402.56132) (xy 338.626797 -402.624319)
			(xy 338.642772 -402.689696) (xy 338.65082 -402.756514) (xy 338.650824 -402.823814) (xy 338.650816 -402.823878)
			(xy 341.928884 -402.823878) (xy 341.928889 -402.75645) (xy 341.936969 -402.689509) (xy 341.95301 -402.624017)
			(xy 341.976779 -402.560918) (xy 342.007935 -402.501121) (xy 342.046029 -402.445485) (xy 342.067896 -402.41982)
			(xy 342.073709 -402.412686) (xy 342.080214 -402.395487) (xy 342.080596 -402.386292) (xy 342.080596 -401.89404)
			(xy 342.080168 -401.884855) (xy 342.073667 -401.86767) (xy 342.067896 -401.860512) (xy 342.046013 -401.834863)
			(xy 342.007925 -401.779226) (xy 341.976775 -401.719428) (xy 341.953012 -401.656329) (xy 341.936978 -401.590838)
			(xy 341.928904 -401.523898) (xy 341.928906 -401.456472) (xy 341.936984 -401.389533) (xy 341.953021 -401.324043)
			(xy 341.976787 -401.260945) (xy 342.00794 -401.201148) (xy 342.046031 -401.145513) (xy 342.067896 -401.119848)
			(xy 342.073697 -401.112706) (xy 342.080209 -401.095513) (xy 342.080596 -401.08632) (xy 342.080596 -400.92884)
			(xy 342.081049 -400.918721) (xy 342.088783 -400.900019) (xy 342.103088 -400.885703) (xy 342.121785 -400.877956)
			(xy 342.131904 -400.877532) (xy 342.848184 -400.877532) (xy 342.858309 -400.87793) (xy 342.877019 -400.885679)
			(xy 342.891335 -400.900001) (xy 342.899075 -400.918714) (xy 342.899492 -400.92884) (xy 342.899492 -401.08632)
			(xy 342.899894 -401.095508) (xy 342.906413 -401.112692) (xy 342.912192 -401.119848) (xy 342.934037 -401.145529)
			(xy 342.972126 -401.201161) (xy 343.003278 -401.260955) (xy 343.027044 -401.32405) (xy 343.043081 -401.389537)
			(xy 343.051159 -401.456474) (xy 343.051161 -401.523896) (xy 343.043087 -401.590833) (xy 343.027053 -401.656321)
			(xy 343.003291 -401.719417) (xy 343.001041 -401.723737) (xy 344.129061 -401.723737) (xy 344.129063 -401.65643)
			(xy 344.13711 -401.589606) (xy 344.153085 -401.524223) (xy 344.17676 -401.461217) (xy 344.207796 -401.401493)
			(xy 344.245747 -401.345906) (xy 344.267536 -401.320254) (xy 344.273339 -401.313114) (xy 344.279849 -401.295919)
			(xy 344.280236 -401.286726) (xy 344.280236 -400.793458) (xy 344.279838 -400.78427) (xy 344.273315 -400.767086)
			(xy 344.267536 -400.75993) (xy 344.245754 -400.734273) (xy 344.207805 -400.678687) (xy 344.176772 -400.618964)
			(xy 344.153099 -400.55596) (xy 344.137126 -400.490579) (xy 344.129081 -400.423757) (xy 344.129081 -400.356452)
			(xy 344.137124 -400.28963) (xy 344.153096 -400.224248) (xy 344.176768 -400.161244) (xy 344.207801 -400.101521)
			(xy 344.245749 -400.045934) (xy 344.267536 -400.020282) (xy 344.273327 -400.013133) (xy 344.279844 -399.995945)
			(xy 344.280236 -399.986754) (xy 344.280236 -399.828766) (xy 344.280705 -399.818606) (xy 344.288491 -399.799837)
			(xy 344.302864 -399.785473) (xy 344.321638 -399.777699) (xy 344.331798 -399.777204) (xy 345.048078 -399.777204)
			(xy 345.05823 -399.77775) (xy 345.076992 -399.785511) (xy 345.091357 -399.799861) (xy 345.099139 -399.818614)
			(xy 345.09964 -399.828766) (xy 345.09964 -399.986754) (xy 345.100086 -399.995937) (xy 345.106576 -400.013121)
			(xy 345.11234 -400.020282) (xy 345.134134 -400.045929) (xy 345.172084 -400.101516) (xy 345.203118 -400.16124)
			(xy 345.226792 -400.224245) (xy 345.242765 -400.289628) (xy 345.250809 -400.356452) (xy 345.250808 -400.423757)
			(xy 345.242763 -400.490581) (xy 345.226789 -400.555964) (xy 345.203115 -400.618968) (xy 345.172079 -400.678692)
			(xy 345.134129 -400.734278) (xy 345.11234 -400.75993) (xy 345.106541 -400.767073) (xy 345.100029 -400.784265)
			(xy 345.09964 -400.793458) (xy 345.09964 -401.286726) (xy 345.100051 -401.295913) (xy 345.106566 -401.313096)
			(xy 345.11234 -401.320254) (xy 345.134107 -401.345924) (xy 345.172057 -401.401507) (xy 345.203093 -401.461228)
			(xy 345.226768 -401.52423) (xy 345.242743 -401.589611) (xy 345.250789 -401.656432) (xy 345.250791 -401.723735)
			(xy 345.242749 -401.790557) (xy 345.226778 -401.855938) (xy 345.203106 -401.918942) (xy 345.172074 -401.978664)
			(xy 345.134127 -402.03425) (xy 345.11234 -402.059902) (xy 345.106553 -402.067053) (xy 345.100034 -402.084239)
			(xy 345.09964 -402.09343) (xy 345.09964 -402.251418) (xy 345.09925 -402.261593) (xy 345.091455 -402.280393)
			(xy 345.077059 -402.294778) (xy 345.058254 -402.302558) (xy 345.048078 -402.30298) (xy 344.331798 -402.30298)
			(xy 344.321642 -402.302469) (xy 344.302877 -402.294697) (xy 344.288512 -402.280337) (xy 344.280735 -402.261574)
			(xy 344.280236 -402.251418) (xy 344.280236 -402.09343) (xy 344.279803 -402.084245) (xy 344.273304 -402.067061)
			(xy 344.267536 -402.059902) (xy 344.245727 -402.034268) (xy 344.207779 -401.978679) (xy 344.176746 -401.918953)
			(xy 344.153075 -401.855946) (xy 344.137104 -401.790561) (xy 344.129061 -401.723737) (xy 343.001041 -401.723737)
			(xy 342.972142 -401.779213) (xy 342.934055 -401.834847) (xy 342.912192 -401.860512) (xy 342.906407 -401.867665)
			(xy 342.899886 -401.88485) (xy 342.899492 -401.89404) (xy 342.899492 -402.386292) (xy 342.899908 -402.395479)
			(xy 342.906418 -402.412663) (xy 342.912192 -402.41982) (xy 342.934009 -402.445524) (xy 342.9721 -402.501153)
			(xy 343.003253 -402.560944) (xy 343.02702 -402.624035) (xy 343.043059 -402.68952) (xy 343.051139 -402.756454)
			(xy 343.051143 -402.823819) (xy 346.329179 -402.823819) (xy 346.329184 -402.756509) (xy 346.337233 -402.689682)
			(xy 346.353213 -402.624297) (xy 346.376893 -402.56129) (xy 346.407934 -402.501566) (xy 346.445892 -402.445979)
			(xy 346.467684 -402.420328) (xy 346.473492 -402.413191) (xy 346.48 -402.395994) (xy 346.480384 -402.3868)
			(xy 346.480384 -401.893532) (xy 346.479962 -401.884346) (xy 346.473457 -401.867161) (xy 346.467684 -401.860004)
			(xy 346.445875 -401.834369) (xy 346.407924 -401.778781) (xy 346.376889 -401.719055) (xy 346.353216 -401.656049)
			(xy 346.337243 -401.590664) (xy 346.3292 -401.523839) (xy 346.329201 -401.456531) (xy 346.337248 -401.389707)
			(xy 346.353225 -401.324323) (xy 346.376902 -401.261317) (xy 346.40794 -401.201593) (xy 346.445894 -401.146008)
			(xy 346.467684 -401.120356) (xy 346.47348 -401.11321) (xy 346.479995 -401.09602) (xy 346.480384 -401.086828)
			(xy 346.480384 -400.92884) (xy 346.480854 -400.91869) (xy 346.488634 -400.899942) (xy 346.503015 -400.885618)
			(xy 346.521795 -400.877914) (xy 346.531946 -400.877532) (xy 347.248226 -400.877532) (xy 347.258353 -400.878005)
			(xy 347.277074 -400.88574) (xy 347.291429 -400.90003) (xy 347.299249 -400.918715) (xy 347.299788 -400.92884)
			(xy 347.299788 -401.086828) (xy 347.300187 -401.096016) (xy 347.306709 -401.1132) (xy 347.312488 -401.120356)
			(xy 347.334255 -401.146025) (xy 347.372203 -401.201609) (xy 347.403236 -401.261331) (xy 347.426908 -401.324333)
			(xy 347.442882 -401.389713) (xy 347.450927 -401.456533) (xy 347.450929 -401.523836) (xy 347.442887 -401.590657)
			(xy 347.426917 -401.656038) (xy 347.403248 -401.719042) (xy 347.400809 -401.723737) (xy 374.929092 -401.723737)
			(xy 374.929094 -401.65643) (xy 374.937141 -401.589605) (xy 374.953117 -401.524221) (xy 374.976794 -401.461216)
			(xy 375.007832 -401.401492) (xy 375.045786 -401.345906) (xy 375.067576 -401.320254) (xy 375.073372 -401.313108)
			(xy 375.079888 -401.295918) (xy 375.080276 -401.286726) (xy 375.080276 -400.793458) (xy 375.079891 -400.784268)
			(xy 375.07336 -400.767084) (xy 375.067576 -400.75993) (xy 375.045793 -400.734273) (xy 375.007842 -400.678688)
			(xy 374.976806 -400.618966) (xy 374.953131 -400.555962) (xy 374.937157 -400.49058) (xy 374.929112 -400.423757)
			(xy 374.929111 -400.356452) (xy 374.937155 -400.289629) (xy 374.953129 -400.224247) (xy 374.976802 -400.161242)
			(xy 375.007837 -400.101519) (xy 375.045788 -400.045934) (xy 375.067576 -400.020282) (xy 375.07336 -400.013128)
			(xy 375.079883 -399.995944) (xy 375.080276 -399.986754) (xy 375.080276 -399.828766) (xy 375.080637 -399.818587)
			(xy 375.08844 -399.799785) (xy 375.102845 -399.7854) (xy 375.121659 -399.777623) (xy 375.131838 -399.777204)
			(xy 375.848118 -399.777204) (xy 375.858273 -399.777718) (xy 375.877036 -399.785492) (xy 375.891399 -399.799851)
			(xy 375.899179 -399.818611) (xy 375.89968 -399.828766) (xy 375.89968 -399.986754) (xy 375.900117 -399.995938)
			(xy 375.906612 -400.013123) (xy 375.91238 -400.020282) (xy 375.934173 -400.045929) (xy 375.972121 -400.101517)
			(xy 376.003152 -400.161241) (xy 376.026824 -400.224247) (xy 376.042796 -400.289629) (xy 376.050839 -400.356452)
			(xy 376.050839 -400.423757) (xy 376.042794 -400.49058) (xy 376.026821 -400.555962) (xy 376.003149 -400.618967)
			(xy 375.972116 -400.678691) (xy 375.934168 -400.734278) (xy 375.91238 -400.75993) (xy 375.906586 -400.767077)
			(xy 375.90007 -400.784266) (xy 375.89968 -400.793458) (xy 375.89968 -401.286726) (xy 375.900082 -401.295914)
			(xy 375.906602 -401.313098) (xy 375.91238 -401.320254) (xy 375.934146 -401.345924) (xy 375.972094 -401.401508)
			(xy 376.003127 -401.46123) (xy 376.0268 -401.524232) (xy 376.042774 -401.589612) (xy 376.05082 -401.656432)
			(xy 376.050822 -401.723735) (xy 376.04278 -401.790556) (xy 376.02681 -401.855937) (xy 376.003141 -401.91894)
			(xy 375.972111 -401.978663) (xy 375.934166 -402.03425) (xy 375.91238 -402.059902) (xy 375.906598 -402.067057)
			(xy 375.900075 -402.08424) (xy 375.89968 -402.09343) (xy 375.89968 -402.251418) (xy 375.899182 -402.261575)
			(xy 375.891405 -402.280341) (xy 375.877041 -402.294705) (xy 375.858275 -402.302482) (xy 375.848118 -402.30298)
			(xy 375.131838 -402.30298) (xy 375.121671 -402.302505) (xy 375.102881 -402.294736) (xy 375.088495 -402.280366)
			(xy 375.080706 -402.261584) (xy 375.080276 -402.251418) (xy 375.080276 -402.09343) (xy 375.079857 -402.084244)
			(xy 375.07335 -402.067059) (xy 375.067576 -402.059902) (xy 375.045766 -402.034268) (xy 375.007815 -401.97868)
			(xy 374.976781 -401.918954) (xy 374.953108 -401.855947) (xy 374.937135 -401.790562) (xy 374.929092 -401.723737)
			(xy 347.400809 -401.723737) (xy 347.372218 -401.778765) (xy 347.334274 -401.834352) (xy 347.312488 -401.860004)
			(xy 347.306706 -401.867159) (xy 347.300183 -401.884342) (xy 347.299788 -401.893532) (xy 347.299788 -402.3868)
			(xy 347.300201 -402.395987) (xy 347.306713 -402.413171) (xy 347.312488 -402.420328) (xy 347.334227 -402.44602)
			(xy 347.372176 -402.501601) (xy 347.40321 -402.561319) (xy 347.426884 -402.624319) (xy 347.442859 -402.689696)
			(xy 347.450907 -402.756514) (xy 347.450911 -402.823814) (xy 347.450903 -402.823878) (xy 377.128705 -402.823878)
			(xy 377.12871 -402.75645) (xy 377.136791 -402.689508) (xy 377.152832 -402.624016) (xy 377.176603 -402.560917)
			(xy 377.20776 -402.50112) (xy 377.245856 -402.445485) (xy 377.267724 -402.41982) (xy 377.27354 -402.412689)
			(xy 377.280042 -402.395487) (xy 377.280424 -402.386292) (xy 377.280424 -401.89404) (xy 377.279989 -401.884856)
			(xy 377.273492 -401.867671) (xy 377.267724 -401.860512) (xy 377.24584 -401.834863) (xy 377.20775 -401.779227)
			(xy 377.176599 -401.719429) (xy 377.152835 -401.65633) (xy 377.1368 -401.590838) (xy 377.128725 -401.523898)
			(xy 377.128727 -401.456472) (xy 377.136805 -401.389532) (xy 377.152843 -401.324042) (xy 377.176611 -401.260944)
			(xy 377.207765 -401.201147) (xy 377.245858 -401.145513) (xy 377.267724 -401.119848) (xy 377.273528 -401.112708)
			(xy 377.280037 -401.095513) (xy 377.280424 -401.08632) (xy 377.280424 -400.92884) (xy 377.280849 -400.918717)
			(xy 377.288589 -400.90001) (xy 377.302903 -400.885693) (xy 377.321609 -400.877951) (xy 377.331732 -400.877532)
			(xy 378.048012 -400.877532) (xy 378.058139 -400.877907) (xy 378.076849 -400.885665) (xy 378.091164 -400.899994)
			(xy 378.098904 -400.918712) (xy 378.09932 -400.92884) (xy 378.09932 -401.08632) (xy 378.099716 -401.095509)
			(xy 378.106239 -401.112693) (xy 378.11202 -401.119848) (xy 378.133864 -401.14553) (xy 378.171952 -401.201162)
			(xy 378.203102 -401.260957) (xy 378.226866 -401.324051) (xy 378.242903 -401.389538) (xy 378.25098 -401.456474)
			(xy 378.250982 -401.523896) (xy 378.242908 -401.590832) (xy 378.226875 -401.65632) (xy 378.203114 -401.719416)
			(xy 378.200833 -401.723796) (xy 379.328885 -401.723796) (xy 379.328887 -401.656371) (xy 379.336964 -401.589432)
			(xy 379.353001 -401.523942) (xy 379.376766 -401.460844) (xy 379.407918 -401.401047) (xy 379.446008 -401.345412)
			(xy 379.467872 -401.319746) (xy 379.473683 -401.312611) (xy 379.480187 -401.295412) (xy 379.480572 -401.286218)
			(xy 379.480572 -400.793966) (xy 379.480184 -400.784776) (xy 379.473656 -400.767592) (xy 379.467872 -400.760438)
			(xy 379.446015 -400.734767) (xy 379.407928 -400.679133) (xy 379.376778 -400.619337) (xy 379.353015 -400.556241)
			(xy 379.33698 -400.490753) (xy 379.328904 -400.423816) (xy 379.328904 -400.356393) (xy 379.336979 -400.289456)
			(xy 379.353013 -400.223967) (xy 379.376775 -400.160871) (xy 379.407923 -400.101075) (xy 379.446009 -400.04544)
			(xy 379.467872 -400.019774) (xy 379.473671 -400.012631) (xy 379.480182 -399.995438) (xy 379.480572 -399.986246)
			(xy 379.480572 -399.828766) (xy 379.481 -399.818633) (xy 379.488744 -399.799905) (xy 379.503049 -399.785549)
			(xy 379.521749 -399.777737) (xy 379.53188 -399.777204) (xy 380.24816 -399.777204) (xy 380.25828 -399.777649)
			(xy 380.276984 -399.785385) (xy 380.2913 -399.799693) (xy 380.299045 -399.818392) (xy 380.299468 -399.828512)
			(xy 380.299468 -399.986246) (xy 380.299911 -399.99543) (xy 380.306403 -400.012614) (xy 380.312168 -400.019774)
			(xy 380.334039 -400.045434) (xy 380.37213 -400.101068) (xy 380.403282 -400.160865) (xy 380.427047 -400.223963)
			(xy 380.443083 -400.289453) (xy 380.451159 -400.356392) (xy 380.451158 -400.423817) (xy 380.443082 -400.490756)
			(xy 380.427044 -400.556246) (xy 380.403278 -400.619343) (xy 380.372125 -400.679139) (xy 380.334033 -400.734773)
			(xy 380.312168 -400.760438) (xy 380.306369 -400.767581) (xy 380.299856 -400.784773) (xy 380.299468 -400.793966)
			(xy 380.299468 -401.286218) (xy 380.299877 -401.295405) (xy 380.306392 -401.312589) (xy 380.312168 -401.319746)
			(xy 380.334011 -401.345429) (xy 380.372103 -401.40106) (xy 380.403256 -401.460853) (xy 380.427023 -401.523948)
			(xy 380.443061 -401.589435) (xy 380.451139 -401.656372) (xy 380.451141 -401.723795) (xy 380.443067 -401.790732)
			(xy 380.427033 -401.85622) (xy 380.40327 -401.919316) (xy 380.37212 -401.979112) (xy 380.334032 -402.034745)
			(xy 380.312168 -402.06041) (xy 380.306381 -402.067562) (xy 380.299861 -402.084747) (xy 380.299468 -402.093938)
			(xy 380.299468 -402.251418) (xy 380.298989 -402.261545) (xy 380.291256 -402.280265) (xy 380.276968 -402.29462)
			(xy 380.258284 -402.30244) (xy 380.24816 -402.30298) (xy 379.53188 -402.30298) (xy 379.521754 -402.3026)
			(xy 379.503046 -402.294842) (xy 379.488731 -402.280514) (xy 379.48099 -402.261799) (xy 379.480572 -402.251672)
			(xy 379.480572 -402.093938) (xy 379.48015 -402.084752) (xy 379.473645 -402.067567) (xy 379.467872 -402.06041)
			(xy 379.445987 -402.034762) (xy 379.407901 -401.979124) (xy 379.376753 -401.919326) (xy 379.352991 -401.856227)
			(xy 379.336958 -401.790736) (xy 379.328885 -401.723796) (xy 378.200833 -401.723796) (xy 378.171967 -401.779212)
			(xy 378.133882 -401.834846) (xy 378.11202 -401.860512) (xy 378.106238 -401.867668) (xy 378.099714 -401.88485)
			(xy 378.09932 -401.89404) (xy 378.09932 -402.386292) (xy 378.099729 -402.395479) (xy 378.106243 -402.412664)
			(xy 378.11202 -402.41982) (xy 378.133836 -402.445524) (xy 378.171925 -402.501154) (xy 378.203077 -402.560945)
			(xy 378.226843 -402.624037) (xy 378.242881 -402.689521) (xy 378.25096 -402.756454) (xy 378.250965 -402.823818)
			(xy 381.529025 -402.823818) (xy 381.529029 -402.75651) (xy 381.537078 -402.689684) (xy 381.553055 -402.6243)
			(xy 381.576732 -402.561293) (xy 381.607769 -402.501568) (xy 381.645722 -402.445981) (xy 381.667512 -402.420328)
			(xy 381.673323 -402.413193) (xy 381.679829 -402.395995) (xy 381.680212 -402.3868) (xy 381.680212 -401.893532)
			(xy 381.679784 -401.884347) (xy 381.673282 -401.867162) (xy 381.667512 -401.860004) (xy 381.645705 -401.834368)
			(xy 381.607759 -401.778778) (xy 381.576728 -401.719052) (xy 381.553058 -401.656046) (xy 381.537087 -401.590662)
			(xy 381.529045 -401.523838) (xy 381.529046 -401.456532) (xy 381.537092 -401.389708) (xy 381.553066 -401.324325)
			(xy 381.57674 -401.26132) (xy 381.607774 -401.201596) (xy 381.645724 -401.146009) (xy 381.667512 -401.120356)
			(xy 381.673311 -401.113213) (xy 381.679824 -401.096021) (xy 381.680212 -401.086828) (xy 381.680212 -400.92884)
			(xy 381.680649 -400.918719) (xy 381.688386 -400.900014) (xy 381.702697 -400.885698) (xy 381.721399 -400.877953)
			(xy 381.73152 -400.877532) (xy 382.448054 -400.877532) (xy 382.458177 -400.878064) (xy 382.476895 -400.885775)
			(xy 382.491253 -400.900048) (xy 382.499075 -400.91872) (xy 382.499616 -400.92884) (xy 382.499616 -401.086828)
			(xy 382.500009 -401.096017) (xy 382.506534 -401.113201) (xy 382.512316 -401.120356) (xy 382.534085 -401.146024)
			(xy 382.572038 -401.201607) (xy 382.603074 -401.261328) (xy 382.62675 -401.32433) (xy 382.642726 -401.389711)
			(xy 382.650772 -401.456533) (xy 382.650774 -401.523837) (xy 382.642731 -401.590659) (xy 382.626759 -401.656041)
			(xy 382.603087 -401.719045) (xy 382.600649 -401.723737) (xy 383.729179 -401.723737) (xy 383.729181 -401.65643)
			(xy 383.737228 -401.589605) (xy 383.753204 -401.524222) (xy 383.77688 -401.461216) (xy 383.807917 -401.401492)
			(xy 383.84587 -401.345906) (xy 383.86766 -401.320254) (xy 383.873466 -401.313116) (xy 383.879973 -401.29592)
			(xy 383.88036 -401.286726) (xy 383.88036 -400.793458) (xy 383.879957 -400.78427) (xy 383.873437 -400.767087)
			(xy 383.86766 -400.75993) (xy 383.845878 -400.734273) (xy 383.807927 -400.678688) (xy 383.776893 -400.618965)
			(xy 383.753219 -400.555961) (xy 383.737245 -400.490579) (xy 383.7292 -400.423757) (xy 383.729199 -400.356452)
			(xy 383.737243 -400.28963) (xy 383.753216 -400.224247) (xy 383.776889 -400.161243) (xy 383.807923 -400.10152)
			(xy 383.845872 -400.045934) (xy 383.86766 -400.020282) (xy 383.873454 -400.013135) (xy 383.879969 -399.995946)
			(xy 383.88036 -399.986754) (xy 383.88036 -399.828766) (xy 383.880806 -399.818603) (xy 383.888596 -399.799829)
			(xy 383.902976 -399.785464) (xy 383.921759 -399.777695) (xy 383.931922 -399.777204) (xy 384.648202 -399.777204)
			(xy 384.658356 -399.777731) (xy 384.677118 -399.7855) (xy 384.691482 -399.799855) (xy 384.699263 -399.818613)
			(xy 384.699764 -399.828766) (xy 384.699764 -399.986754) (xy 384.700205 -399.995938) (xy 384.706698 -400.013122)
			(xy 384.712464 -400.020282) (xy 384.734258 -400.045929) (xy 384.772206 -400.101516) (xy 384.803239 -400.161241)
			(xy 384.826911 -400.224246) (xy 384.842884 -400.289629) (xy 384.850927 -400.356452) (xy 384.850927 -400.423757)
			(xy 384.842882 -400.49058) (xy 384.826909 -400.555963) (xy 384.803235 -400.618968) (xy 384.772201 -400.678691)
			(xy 384.734252 -400.734278) (xy 384.712464 -400.75993) (xy 384.706668 -400.767075) (xy 384.700154 -400.784266)
			(xy 384.699764 -400.793458) (xy 384.699764 -401.286726) (xy 384.70017 -401.295913) (xy 384.706687 -401.313097)
			(xy 384.712464 -401.320254) (xy 384.73423 -401.345924) (xy 384.772179 -401.401508) (xy 384.803213 -401.461229)
			(xy 384.826887 -401.524231) (xy 384.842861 -401.589611) (xy 384.850907 -401.656432) (xy 384.850909 -401.723735)
			(xy 384.842867 -401.790556) (xy 384.826897 -401.855937) (xy 384.803227 -401.918941) (xy 384.772196 -401.978663)
			(xy 384.73425 -402.03425) (xy 384.712464 -402.059902) (xy 384.706679 -402.067056) (xy 384.700158 -402.08424)
			(xy 384.699764 -402.09343) (xy 384.699764 -402.251418) (xy 384.699282 -402.261577) (xy 384.691502 -402.280346)
			(xy 384.677133 -402.294711) (xy 384.658361 -402.302485) (xy 384.648202 -402.30298) (xy 383.931922 -402.30298)
			(xy 383.921754 -402.302518) (xy 383.902963 -402.294744) (xy 383.888578 -402.28037) (xy 383.88079 -402.261586)
			(xy 383.88036 -402.251418) (xy 383.88036 -402.09343) (xy 383.879922 -402.084246) (xy 383.873426 -402.067062)
			(xy 383.86766 -402.059902) (xy 383.84585 -402.034268) (xy 383.8079 -401.97868) (xy 383.776867 -401.918954)
			(xy 383.753194 -401.855947) (xy 383.737222 -401.790562) (xy 383.729179 -401.723737) (xy 382.600649 -401.723737)
			(xy 382.572053 -401.778767) (xy 382.534104 -401.834352) (xy 382.512316 -401.860004) (xy 382.506537 -401.867162)
			(xy 382.500011 -401.884343) (xy 382.499616 -401.893532) (xy 382.499616 -402.3868) (xy 382.500023 -402.395988)
			(xy 382.506538 -402.413172) (xy 382.512316 -402.420328) (xy 382.534058 -402.446018) (xy 382.572011 -402.501598)
			(xy 382.603049 -402.561316) (xy 382.626726 -402.624316) (xy 382.642704 -402.689694) (xy 382.650753 -402.756513)
			(xy 382.650757 -402.823815) (xy 382.650749 -402.823878) (xy 385.928793 -402.823878) (xy 385.928798 -402.75645)
			(xy 385.936878 -402.689508) (xy 385.952919 -402.624017) (xy 385.976689 -402.560918) (xy 386.007846 -402.50112)
			(xy 386.045941 -402.445485) (xy 386.067808 -402.41982) (xy 386.073622 -402.412687) (xy 386.080126 -402.395487)
			(xy 386.080508 -402.386292) (xy 386.080508 -401.89404) (xy 386.080077 -401.884855) (xy 386.073578 -401.867671)
			(xy 386.067808 -401.860512) (xy 386.045924 -401.834863) (xy 386.007835 -401.779226) (xy 385.976685 -401.719428)
			(xy 385.952922 -401.656329) (xy 385.936887 -401.590838) (xy 385.928813 -401.523898) (xy 385.928815 -401.456472)
			(xy 385.936893 -401.389533) (xy 385.952931 -401.324042) (xy 385.976697 -401.260944) (xy 386.007851 -401.201148)
			(xy 386.045943 -401.145513) (xy 386.067808 -401.119848) (xy 386.07361 -401.112707) (xy 386.080121 -401.095513)
			(xy 386.080508 -401.08632) (xy 386.080508 -400.92884) (xy 386.080949 -400.918719) (xy 386.088686 -400.900015)
			(xy 386.102995 -400.885699) (xy 386.121695 -400.877954) (xy 386.131816 -400.877532) (xy 386.848096 -400.877532)
			(xy 386.858222 -400.87792) (xy 386.876932 -400.885673) (xy 386.891247 -400.899998) (xy 386.898987 -400.918714)
			(xy 386.899404 -400.92884) (xy 386.899404 -401.08632) (xy 386.899804 -401.095508) (xy 386.906325 -401.112692)
			(xy 386.912104 -401.119848) (xy 386.933948 -401.14553) (xy 386.972037 -401.201162) (xy 387.003189 -401.260956)
			(xy 387.026954 -401.324051) (xy 387.04299 -401.389538) (xy 387.051068 -401.456474) (xy 387.05107 -401.523896)
			(xy 387.042996 -401.590833) (xy 387.026963 -401.656321) (xy 387.003201 -401.719417) (xy 387.000951 -401.723737)
			(xy 388.12897 -401.723737) (xy 388.128972 -401.65643) (xy 388.137019 -401.589606) (xy 388.152994 -401.524222)
			(xy 388.17667 -401.461217) (xy 388.207706 -401.401492) (xy 388.245659 -401.345906) (xy 388.267448 -401.320254)
			(xy 388.273253 -401.313115) (xy 388.279761 -401.295919) (xy 388.280148 -401.286726) (xy 388.280148 -400.793458)
			(xy 388.279747 -400.78427) (xy 388.273226 -400.767086) (xy 388.267448 -400.75993) (xy 388.245666 -400.734273)
			(xy 388.207717 -400.678687) (xy 388.176683 -400.618965) (xy 388.153009 -400.555961) (xy 388.137035 -400.490579)
			(xy 388.128991 -400.423757) (xy 388.12899 -400.356452) (xy 388.137034 -400.28963) (xy 388.153006 -400.224248)
			(xy 388.176679 -400.161244) (xy 388.207712 -400.10152) (xy 388.245661 -400.045934) (xy 388.267448 -400.020282)
			(xy 388.273241 -400.013134) (xy 388.279756 -399.995946) (xy 388.280148 -399.986754) (xy 388.280148 -399.828766)
			(xy 388.280606 -399.818605) (xy 388.288393 -399.799833) (xy 388.30277 -399.785469) (xy 388.321548 -399.777697)
			(xy 388.33171 -399.777204) (xy 389.04799 -399.777204) (xy 389.058143 -399.777741) (xy 389.076905 -399.785506)
			(xy 389.09127 -399.799858) (xy 389.099051 -399.818613) (xy 389.099552 -399.828766) (xy 389.099552 -399.986754)
			(xy 389.099995 -399.995937) (xy 389.106487 -400.013121) (xy 389.112252 -400.020282) (xy 389.134046 -400.045929)
			(xy 389.171995 -400.101516) (xy 389.203029 -400.16124) (xy 389.226702 -400.224245) (xy 389.242675 -400.289628)
			(xy 389.250718 -400.356452) (xy 389.250718 -400.423757) (xy 389.242673 -400.490581) (xy 389.226699 -400.555963)
			(xy 389.203025 -400.618968) (xy 389.171991 -400.678692) (xy 389.134041 -400.734278) (xy 389.112252 -400.75993)
			(xy 389.106454 -400.767074) (xy 389.099942 -400.784266) (xy 389.099552 -400.793458) (xy 389.099552 -401.286726)
			(xy 389.09996 -401.295913) (xy 389.106477 -401.313097) (xy 389.112252 -401.320254) (xy 389.134018 -401.345924)
			(xy 389.171968 -401.401508) (xy 389.203003 -401.461229) (xy 389.226677 -401.524231) (xy 389.242652 -401.589611)
			(xy 389.250698 -401.656432) (xy 389.2507 -401.723735) (xy 389.242658 -401.790556) (xy 389.226687 -401.855937)
			(xy 389.203016 -401.918941) (xy 389.171985 -401.978664) (xy 389.134038 -402.03425) (xy 389.112252 -402.059902)
			(xy 389.106466 -402.067055) (xy 389.099946 -402.08424) (xy 389.099552 -402.09343) (xy 389.099552 -402.251418)
			(xy 389.099081 -402.261578) (xy 389.091299 -402.28035) (xy 389.076926 -402.294715) (xy 389.05815 -402.302487)
			(xy 389.04799 -402.30298) (xy 388.33171 -402.30298) (xy 388.321555 -402.302459) (xy 388.30279 -402.294691)
			(xy 388.288425 -402.280334) (xy 388.280647 -402.261573) (xy 388.280148 -402.251418) (xy 388.280148 -402.09343)
			(xy 388.279713 -402.084246) (xy 388.273215 -402.067062) (xy 388.267448 -402.059902) (xy 388.245638 -402.034268)
			(xy 388.207689 -401.978679) (xy 388.176657 -401.918953) (xy 388.152985 -401.855946) (xy 388.137013 -401.790562)
			(xy 388.12897 -401.723737) (xy 387.000951 -401.723737) (xy 386.972053 -401.779212) (xy 386.933967 -401.834847)
			(xy 386.912104 -401.860512) (xy 386.90632 -401.867666) (xy 386.899798 -401.88485) (xy 386.899404 -401.89404)
			(xy 386.899404 -402.386292) (xy 386.899817 -402.395479) (xy 386.906329 -402.412663) (xy 386.912104 -402.41982)
			(xy 386.933921 -402.445524) (xy 386.972011 -402.501153) (xy 387.003163 -402.560944) (xy 387.02693 -402.624036)
			(xy 387.042968 -402.68952) (xy 387.051048 -402.756454) (xy 387.051052 -402.823818) (xy 390.329113 -402.823818)
			(xy 390.329117 -402.75651) (xy 390.337166 -402.689685) (xy 390.353142 -402.6243) (xy 390.376819 -402.561294)
			(xy 390.407855 -402.501569) (xy 390.445807 -402.445981) (xy 390.467596 -402.420328) (xy 390.473405 -402.413192)
			(xy 390.479912 -402.395994) (xy 390.480296 -402.3868) (xy 390.480296 -401.893532) (xy 390.479871 -401.884346)
			(xy 390.473368 -401.867162) (xy 390.467596 -401.860004) (xy 390.44579 -401.834367) (xy 390.407845 -401.778778)
			(xy 390.376815 -401.719052) (xy 390.353145 -401.656045) (xy 390.337174 -401.590661) (xy 390.329133 -401.523838)
			(xy 390.329134 -401.456532) (xy 390.33718 -401.389709) (xy 390.353154 -401.324326) (xy 390.376827 -401.261321)
			(xy 390.40786 -401.201596) (xy 390.445808 -401.146009) (xy 390.467596 -401.120356) (xy 390.473393 -401.113211)
			(xy 390.479908 -401.09602) (xy 390.480296 -401.086828) (xy 390.480296 -400.92884) (xy 390.480749 -400.918721)
			(xy 390.488483 -400.900019) (xy 390.502788 -400.885703) (xy 390.521485 -400.877956) (xy 390.531604 -400.877532)
			(xy 391.248138 -400.877532) (xy 391.258266 -400.877995) (xy 391.276987 -400.885734) (xy 391.291341 -400.900027)
			(xy 391.299161 -400.918714) (xy 391.2997 -400.92884) (xy 391.2997 -401.086828) (xy 391.300096 -401.096017)
			(xy 391.30662 -401.113201) (xy 391.3124 -401.120356) (xy 391.334167 -401.146025) (xy 391.372114 -401.20161)
			(xy 391.403146 -401.261331) (xy 391.426818 -401.324334) (xy 391.442791 -401.389713) (xy 391.450836 -401.456534)
			(xy 391.450838 -401.523836) (xy 391.442797 -401.590657) (xy 391.426827 -401.656038) (xy 391.403158 -401.719041)
			(xy 391.372129 -401.778764) (xy 391.334185 -401.834351) (xy 391.3124 -401.860004) (xy 391.306619 -401.86716)
			(xy 391.300095 -401.884342) (xy 391.2997 -401.893532) (xy 391.2997 -402.3868) (xy 391.30011 -402.395987)
			(xy 391.306624 -402.413171) (xy 391.3124 -402.420328) (xy 391.334139 -402.446019) (xy 391.372087 -402.501601)
			(xy 391.40312 -402.56132) (xy 391.426794 -402.624319) (xy 391.442769 -402.689696) (xy 391.450817 -402.756514)
			(xy 391.450821 -402.823814) (xy 391.442782 -402.890633) (xy 391.426815 -402.956012) (xy 391.40315 -403.019014)
			(xy 391.372124 -403.078737) (xy 391.334184 -403.134323) (xy 391.3124 -403.159976) (xy 391.306589 -403.167111)
			(xy 391.300083 -403.184309) (xy 391.2997 -403.193504) (xy 391.2997 -403.351492) (xy 391.299277 -403.361614)
			(xy 391.291532 -403.380317) (xy 391.277217 -403.394632) (xy 391.258514 -403.402377) (xy 391.248392 -403.4028)
			(xy 390.531858 -403.4028) (xy 390.521734 -403.402309) (xy 390.503019 -403.394575) (xy 390.488666 -403.380291)
			(xy 390.480841 -403.361614) (xy 390.480296 -403.351492) (xy 390.480296 -403.193504) (xy 390.479885 -403.184317)
			(xy 390.473372 -403.167133) (xy 390.467596 -403.159976) (xy 390.445763 -403.134362) (xy 390.407818 -403.078769)
			(xy 390.376789 -403.01904) (xy 390.353121 -402.95603) (xy 390.337153 -402.890644) (xy 390.329113 -402.823818)
			(xy 387.051052 -402.823818) (xy 387.051052 -402.823874) (xy 387.042981 -402.890809) (xy 387.026951 -402.956295)
			(xy 387.003193 -403.01939) (xy 386.972048 -403.079185) (xy 386.933965 -403.134819) (xy 386.912104 -403.160484)
			(xy 386.90629 -403.167617) (xy 386.899785 -403.184817) (xy 386.899404 -403.194012) (xy 386.899404 -403.351492)
			(xy 386.898978 -403.361613) (xy 386.891233 -403.380316) (xy 386.87692 -403.394631) (xy 386.858217 -403.402377)
			(xy 386.848096 -403.4028) (xy 386.131816 -403.4028) (xy 386.121695 -403.402371) (xy 386.102991 -403.394628)
			(xy 386.088676 -403.380315) (xy 386.080931 -403.361613) (xy 386.080508 -403.351492) (xy 386.080508 -403.194012)
			(xy 386.08009 -403.184826) (xy 386.073582 -403.167641) (xy 386.067808 -403.160484) (xy 386.045897 -403.134858)
			(xy 386.007809 -403.079218) (xy 385.97666 -403.019416) (xy 385.952898 -402.956314) (xy 385.936865 -402.89082)
			(xy 385.928793 -402.823878) (xy 382.650749 -402.823878) (xy 382.642717 -402.890635) (xy 382.626748 -402.956015)
			(xy 382.603078 -403.019018) (xy 382.572048 -403.07874) (xy 382.534102 -403.134324) (xy 382.512316 -403.159976)
			(xy 382.506507 -403.167112) (xy 382.499999 -403.18431) (xy 382.499616 -403.193504) (xy 382.499616 -403.351492)
			(xy 382.499109 -403.361598) (xy 382.491377 -403.380273) (xy 382.477087 -403.394568) (xy 382.458414 -403.402306)
			(xy 382.448308 -403.4028) (xy 381.731774 -403.4028) (xy 381.721651 -403.402296) (xy 381.702936 -403.394567)
			(xy 381.688582 -403.380287) (xy 381.680757 -403.361613) (xy 381.680212 -403.351492) (xy 381.680212 -403.193504)
			(xy 381.679797 -403.184317) (xy 381.673286 -403.167133) (xy 381.667512 -403.159976) (xy 381.645678 -403.134362)
			(xy 381.607732 -403.07877) (xy 381.576703 -403.019041) (xy 381.553034 -402.956031) (xy 381.537065 -402.890644)
			(xy 381.529025 -402.823818) (xy 378.250965 -402.823818) (xy 378.250965 -402.823874) (xy 378.242894 -402.890808)
			(xy 378.226864 -402.956294) (xy 378.203106 -403.019389) (xy 378.171962 -403.079184) (xy 378.13388 -403.134818)
			(xy 378.11202 -403.160484) (xy 378.106208 -403.167618) (xy 378.099702 -403.184817) (xy 378.09932 -403.194012)
			(xy 378.09932 -403.351492) (xy 378.098809 -403.361598) (xy 378.091078 -403.380272) (xy 378.076789 -403.394566)
			(xy 378.058118 -403.402305) (xy 378.048012 -403.4028) (xy 377.331732 -403.4028) (xy 377.321612 -403.402358)
			(xy 377.302909 -403.39462) (xy 377.288593 -403.380312) (xy 377.280847 -403.361612) (xy 377.280424 -403.351492)
			(xy 377.280424 -403.194012) (xy 377.280002 -403.184826) (xy 377.273496 -403.167642) (xy 377.267724 -403.160484)
			(xy 377.245812 -403.134858) (xy 377.207723 -403.079218) (xy 377.176573 -403.019417) (xy 377.152811 -402.956315)
			(xy 377.136778 -402.890821) (xy 377.128705 -402.823878) (xy 347.450903 -402.823878) (xy 347.442872 -402.890633)
			(xy 347.426905 -402.956012) (xy 347.403239 -403.019015) (xy 347.372213 -403.078737) (xy 347.334272 -403.134323)
			(xy 347.312488 -403.159976) (xy 347.306675 -403.16711) (xy 347.300171 -403.184309) (xy 347.299788 -403.193504)
			(xy 347.299788 -403.351492) (xy 347.299372 -403.361647) (xy 347.291576 -403.380402) (xy 347.277178 -403.394726)
			(xy 347.258383 -403.402424) (xy 347.248226 -403.4028) (xy 346.531946 -403.4028) (xy 346.521827 -403.402237)
			(xy 346.503115 -403.394532) (xy 346.488758 -403.380269) (xy 346.48093 -403.361607) (xy 346.480384 -403.351492)
			(xy 346.480384 -403.193504) (xy 346.479975 -403.184317) (xy 346.473461 -403.167132) (xy 346.467684 -403.159976)
			(xy 346.445847 -403.134364) (xy 346.407897 -403.078772) (xy 346.376863 -403.019044) (xy 346.353191 -402.956034)
			(xy 346.33722 -402.890646) (xy 346.329179 -402.823819) (xy 343.051143 -402.823819) (xy 343.051143 -402.823874)
			(xy 343.043072 -402.890809) (xy 343.027042 -402.956296) (xy 343.003282 -403.019391) (xy 342.972137 -403.079185)
			(xy 342.934053 -403.134819) (xy 342.912192 -403.160484) (xy 342.906376 -403.167616) (xy 342.899873 -403.184817)
			(xy 342.899492 -403.194012) (xy 342.899492 -403.351492) (xy 342.899077 -403.361615) (xy 342.89133 -403.38032)
			(xy 342.877013 -403.394635) (xy 342.858307 -403.402379) (xy 342.848184 -403.4028) (xy 342.131904 -403.4028)
			(xy 342.121782 -403.402381) (xy 342.103078 -403.394634) (xy 342.088764 -403.380318) (xy 342.081019 -403.361614)
			(xy 342.080596 -403.351492) (xy 342.080596 -403.194012) (xy 342.080181 -403.184825) (xy 342.073671 -403.167641)
			(xy 342.067896 -403.160484) (xy 342.045985 -403.134858) (xy 342.007898 -403.079217) (xy 341.97675 -403.019416)
			(xy 341.952988 -402.956314) (xy 341.936956 -402.89082) (xy 341.928884 -402.823878) (xy 338.650816 -402.823878)
			(xy 338.642785 -402.890633) (xy 338.626819 -402.956012) (xy 338.603153 -403.019014) (xy 338.572128 -403.078737)
			(xy 338.534188 -403.134323) (xy 338.512404 -403.159976) (xy 338.506593 -403.167111) (xy 338.500087 -403.184309)
			(xy 338.499704 -403.193504) (xy 338.499704 -403.351492) (xy 338.499272 -403.361645) (xy 338.49148 -403.380397)
			(xy 338.477086 -403.39472) (xy 338.458297 -403.402421) (xy 338.448142 -403.4028) (xy 337.731862 -403.4028)
			(xy 337.721738 -403.402306) (xy 337.703023 -403.394573) (xy 337.68867 -403.38029) (xy 337.680845 -403.361614)
			(xy 337.6803 -403.351492) (xy 337.6803 -403.193504) (xy 337.679888 -403.184317) (xy 337.673375 -403.167133)
			(xy 337.6676 -403.159976) (xy 337.645766 -403.134362) (xy 337.607822 -403.078769) (xy 337.576793 -403.01904)
			(xy 337.553124 -402.956031) (xy 337.537156 -402.890644) (xy 337.529116 -402.823818) (xy 334.251055 -402.823818)
			(xy 334.251055 -402.823874) (xy 334.242984 -402.890809) (xy 334.226954 -402.956295) (xy 334.203196 -403.01939)
			(xy 334.172051 -403.079185) (xy 334.133969 -403.134819) (xy 334.112108 -403.160484) (xy 334.106294 -403.167617)
			(xy 334.09979 -403.184817) (xy 334.099408 -403.194012) (xy 334.099408 -403.351492) (xy 334.098978 -403.361613)
			(xy 334.091234 -403.380315) (xy 334.076922 -403.394629) (xy 334.058221 -403.402376) (xy 334.0481 -403.4028)
			(xy 333.33182 -403.4028) (xy 333.321699 -403.402368) (xy 333.302996 -403.394626) (xy 333.288681 -403.380315)
			(xy 333.280935 -403.361613) (xy 333.280512 -403.351492) (xy 333.280512 -403.194012) (xy 333.280093 -403.184826)
			(xy 333.273585 -403.167642) (xy 333.267812 -403.160484) (xy 333.2459 -403.134858) (xy 333.207812 -403.079218)
			(xy 333.176663 -403.019417) (xy 333.152901 -402.956315) (xy 333.136869 -402.890821) (xy 333.128796 -402.823878)
			(xy 326.525636 -402.823878) (xy 326.525636 -405.623648) (xy 330.929194 -405.623648) (xy 330.929195 -405.556343)
			(xy 330.93724 -405.489519) (xy 330.953214 -405.424136) (xy 330.976889 -405.361131) (xy 331.007924 -405.301408)
			(xy 331.045875 -405.245822) (xy 331.067664 -405.22017) (xy 331.073464 -405.213027) (xy 331.079975 -405.195835)
			(xy 331.080364 -405.186642) (xy 331.080364 -404.693374) (xy 331.079952 -404.684187) (xy 331.073438 -404.667004)
			(xy 331.067664 -404.659846) (xy 331.045897 -404.634176) (xy 331.007946 -404.578593) (xy 330.976911 -404.518872)
			(xy 330.953235 -404.45587) (xy 330.93726 -404.390489) (xy 330.929214 -404.323668) (xy 330.929212 -404.256365)
			(xy 330.937254 -404.189543) (xy 330.953226 -404.124162) (xy 330.976897 -404.061158) (xy 331.007929 -404.001435)
			(xy 331.045877 -403.94585) (xy 331.067664 -403.920198) (xy 331.073452 -403.913047) (xy 331.07997 -403.895861)
			(xy 331.080364 -403.88667) (xy 331.080364 -403.728682) (xy 331.08075 -403.718506) (xy 331.088546 -403.699706)
			(xy 331.102943 -403.685321) (xy 331.12175 -403.677541) (xy 331.131926 -403.67712) (xy 331.848206 -403.67712)
			(xy 331.858362 -403.677628) (xy 331.877128 -403.685401) (xy 331.891492 -403.699762) (xy 331.899269 -403.718526)
			(xy 331.899768 -403.728682) (xy 331.899768 -403.88667) (xy 331.9002 -403.895855) (xy 331.906699 -403.913039)
			(xy 331.912468 -403.920198) (xy 331.934277 -403.945832) (xy 331.972225 -404.001422) (xy 332.003257 -404.061148)
			(xy 332.026928 -404.124154) (xy 332.042899 -404.189539) (xy 332.050942 -404.256363) (xy 332.05094 -404.32367)
			(xy 332.042893 -404.390494) (xy 332.026918 -404.455877) (xy 332.003243 -404.518883) (xy 331.972208 -404.578607)
			(xy 331.934257 -404.634194) (xy 331.912468 -404.659846) (xy 331.906665 -404.666987) (xy 331.900155 -404.684181)
			(xy 331.899768 -404.693374) (xy 331.899768 -405.186642) (xy 331.900165 -405.19583) (xy 331.906689 -405.213014)
			(xy 331.912468 -405.22017) (xy 331.93425 -405.245827) (xy 331.972198 -405.301413) (xy 332.003231 -405.361136)
			(xy 332.026904 -405.42414) (xy 332.042877 -405.489521) (xy 332.050922 -405.556343) (xy 332.050923 -405.623648)
			(xy 332.042879 -405.69047) (xy 332.026907 -405.755852) (xy 332.003235 -405.818856) (xy 331.972203 -405.878579)
			(xy 331.934255 -405.934166) (xy 331.912468 -405.959818) (xy 331.906677 -405.966967) (xy 331.90016 -405.984155)
			(xy 331.899768 -405.993346) (xy 331.899768 -406.151334) (xy 331.899295 -406.161493) (xy 331.89151 -406.180262)
			(xy 331.877138 -406.194626) (xy 331.858365 -406.2024) (xy 331.848206 -406.202896) (xy 331.131926 -406.202896)
			(xy 331.121774 -406.202346) (xy 331.103012 -406.194587) (xy 331.088647 -406.180238) (xy 331.080865 -406.161485)
			(xy 331.080364 -406.151334) (xy 331.080364 -405.993346) (xy 331.079918 -405.984163) (xy 331.073428 -405.966979)
			(xy 331.067664 -405.959818) (xy 331.04587 -405.934171) (xy 331.007919 -405.878584) (xy 330.976885 -405.81886)
			(xy 330.953212 -405.755855) (xy 330.937238 -405.690472) (xy 330.929194 -405.623648) (xy 326.525636 -405.623648)
			(xy 326.525636 -406.723789) (xy 333.128808 -406.723789) (xy 333.128811 -406.656363) (xy 333.13689 -406.589422)
			(xy 333.152929 -406.523931) (xy 333.176697 -406.460833) (xy 333.207852 -406.401036) (xy 333.245946 -406.345401)
			(xy 333.267812 -406.319736) (xy 333.27362 -406.312599) (xy 333.280127 -406.295402) (xy 333.280512 -406.286208)
			(xy 333.280512 -405.793956) (xy 333.28012 -405.784767) (xy 333.273594 -405.767583) (xy 333.267812 -405.760428)
			(xy 333.245944 -405.734766) (xy 333.207854 -405.679131) (xy 333.176703 -405.619335) (xy 333.152939 -405.556238)
			(xy 333.136903 -405.490748) (xy 333.128827 -405.423809) (xy 333.128828 -405.356385) (xy 333.136904 -405.289446)
			(xy 333.15294 -405.223957) (xy 333.176706 -405.16086) (xy 333.207857 -405.101063) (xy 333.245947 -405.045429)
			(xy 333.267812 -405.019764) (xy 333.273608 -405.012618) (xy 333.280123 -404.995428) (xy 333.280512 -404.986236)
			(xy 333.280512 -404.828756) (xy 333.280949 -404.818643) (xy 333.288704 -404.799961) (xy 333.303015 -404.785668)
			(xy 333.321706 -404.777937) (xy 333.33182 -404.777448) (xy 334.0481 -404.777448) (xy 334.058202 -404.777984)
			(xy 334.076871 -404.785712) (xy 334.091163 -404.799993) (xy 334.098907 -404.818654) (xy 334.099408 -404.828756)
			(xy 334.099408 -404.986236) (xy 334.099799 -404.995425) (xy 334.106326 -405.01261) (xy 334.112108 -405.019764)
			(xy 334.133968 -405.045433) (xy 334.172056 -405.101067) (xy 334.203206 -405.160863) (xy 334.226971 -405.223959)
			(xy 334.243006 -405.289448) (xy 334.251082 -405.356385) (xy 334.251082 -405.423809) (xy 334.243007 -405.490746)
			(xy 334.226972 -405.556235) (xy 334.203209 -405.619332) (xy 334.20093 -405.623707) (xy 335.328987 -405.623707)
			(xy 335.328987 -405.556284) (xy 335.337063 -405.489346) (xy 335.353098 -405.423857) (xy 335.376861 -405.36076)
			(xy 335.40801 -405.300963) (xy 335.446097 -405.245328) (xy 335.46796 -405.219662) (xy 335.473763 -405.212521)
			(xy 335.480272 -405.195327) (xy 335.48066 -405.186134) (xy 335.48066 -404.693882) (xy 335.480245 -404.684696)
			(xy 335.473733 -404.667512) (xy 335.46796 -404.660354) (xy 335.446119 -404.63467) (xy 335.408032 -404.579037)
			(xy 335.376883 -404.519243) (xy 335.353119 -404.456149) (xy 335.337083 -404.390663) (xy 335.329006 -404.323727)
			(xy 335.329004 -404.256306) (xy 335.337078 -404.18937) (xy 335.353109 -404.123883) (xy 335.376869 -404.060787)
			(xy 335.408015 -404.000991) (xy 335.446099 -403.945356) (xy 335.46796 -403.91969) (xy 335.473751 -403.912541)
			(xy 335.480267 -403.895353) (xy 335.48066 -403.886162) (xy 335.48066 -403.728682) (xy 335.481112 -403.718552)
			(xy 335.48885 -403.699826) (xy 335.503147 -403.68547) (xy 335.52184 -403.677655) (xy 335.531968 -403.67712)
			(xy 336.248248 -403.67712) (xy 336.258408 -403.677483) (xy 336.277165 -403.685298) (xy 336.291487 -403.699713)
			(xy 336.299182 -403.71852) (xy 336.299556 -403.728682) (xy 336.299556 -403.886162) (xy 336.299995 -403.895346)
			(xy 336.30649 -403.91253) (xy 336.312256 -403.91969) (xy 336.334143 -403.945337) (xy 336.372234 -404.000973)
			(xy 336.403386 -404.060771) (xy 336.427151 -404.123871) (xy 336.443186 -404.189362) (xy 336.451261 -404.256303)
			(xy 336.451259 -404.32373) (xy 336.443181 -404.39067) (xy 336.427141 -404.456161) (xy 336.403373 -404.519259)
			(xy 336.372217 -404.579056) (xy 336.334123 -404.634689) (xy 336.312256 -404.660354) (xy 336.306449 -404.667491)
			(xy 336.299941 -404.684688) (xy 336.299556 -404.693882) (xy 336.299556 -405.186134) (xy 336.29996 -405.195322)
			(xy 336.306479 -405.212505) (xy 336.312256 -405.219662) (xy 336.334116 -405.245331) (xy 336.372207 -405.300964)
			(xy 336.403361 -405.360759) (xy 336.427127 -405.423856) (xy 336.443164 -405.489345) (xy 336.451242 -405.556283)
			(xy 336.451242 -405.623708) (xy 336.443166 -405.690646) (xy 336.42713 -405.756135) (xy 336.403365 -405.819232)
			(xy 336.372212 -405.879028) (xy 336.334121 -405.934662) (xy 336.312256 -405.960326) (xy 336.30646 -405.967472)
			(xy 336.299946 -405.984662) (xy 336.299556 -405.993854) (xy 336.299556 -406.151334) (xy 336.299101 -406.161463)
			(xy 336.291362 -406.180186) (xy 336.277066 -406.194541) (xy 336.258375 -406.202359) (xy 336.248248 -406.202896)
			(xy 335.531968 -406.202896) (xy 335.521811 -406.202505) (xy 335.503057 -406.194698) (xy 335.488735 -406.180292)
			(xy 335.481037 -406.161493) (xy 335.48066 -406.151334) (xy 335.48066 -405.993854) (xy 335.48021 -405.984671)
			(xy 335.473722 -405.967487) (xy 335.46796 -405.960326) (xy 335.446092 -405.934665) (xy 335.408006 -405.879029)
			(xy 335.376857 -405.819232) (xy 335.353095 -405.756134) (xy 335.337062 -405.690645) (xy 335.328987 -405.623707)
			(xy 334.20093 -405.623707) (xy 334.172059 -405.679128) (xy 334.133971 -405.734763) (xy 334.112108 -405.760428)
			(xy 334.106318 -405.767578) (xy 334.099799 -405.784765) (xy 334.099408 -405.793956) (xy 334.099408 -406.286208)
			(xy 334.099813 -406.295396) (xy 334.10633 -406.31258) (xy 334.112108 -406.319736) (xy 334.13394 -406.345427)
			(xy 334.172029 -406.401058) (xy 334.203181 -406.460851) (xy 334.226947 -406.523944) (xy 334.242984 -406.58943)
			(xy 334.251062 -406.656365) (xy 334.251065 -406.723729) (xy 337.529127 -406.723729) (xy 337.52913 -406.656423)
			(xy 337.537177 -406.589598) (xy 337.553152 -406.524215) (xy 337.576827 -406.461209) (xy 337.607861 -406.401484)
			(xy 337.645812 -406.345897) (xy 337.6676 -406.320244) (xy 337.673403 -406.313103) (xy 337.679914 -406.295909)
			(xy 337.6803 -406.286716) (xy 337.6803 -405.793448) (xy 337.679867 -405.784263) (xy 337.673369 -405.767079)
			(xy 337.6676 -405.75992) (xy 337.64581 -405.734271) (xy 337.607863 -405.678683) (xy 337.576832 -405.618958)
			(xy 337.553162 -405.555954) (xy 337.53719 -405.490572) (xy 337.529147 -405.423749) (xy 337.529147 -405.356445)
			(xy 337.537191 -405.289622) (xy 337.553163 -405.224241) (xy 337.576835 -405.161236) (xy 337.607866 -405.101512)
			(xy 337.645813 -405.045925) (xy 337.6676 -405.020272) (xy 337.673391 -405.013123) (xy 337.679909 -404.995935)
			(xy 337.6803 -404.986744) (xy 337.6803 -404.828756) (xy 337.680686 -404.818599) (xy 337.688496 -404.799846)
			(xy 337.702903 -404.785524) (xy 337.721703 -404.777826) (xy 337.731862 -404.777448) (xy 338.448142 -404.777448)
			(xy 338.458272 -404.777892) (xy 338.476996 -404.785635) (xy 338.491351 -404.799934) (xy 338.499167 -404.818628)
			(xy 338.499704 -404.828756) (xy 338.499704 -404.986744) (xy 338.500092 -404.995934) (xy 338.506621 -405.013118)
			(xy 338.512404 -405.020272) (xy 338.534186 -405.045928) (xy 338.572133 -405.101515) (xy 338.603164 -405.161238)
			(xy 338.626835 -405.224242) (xy 338.642807 -405.289624) (xy 338.650851 -405.356445) (xy 338.650851 -405.423749)
			(xy 338.642808 -405.490571) (xy 338.626837 -405.555952) (xy 338.603166 -405.618956) (xy 338.600728 -405.623648)
			(xy 339.729282 -405.623648) (xy 339.729282 -405.556343) (xy 339.737327 -405.489519) (xy 339.753301 -405.424137)
			(xy 339.776975 -405.361132) (xy 339.808009 -405.301408) (xy 339.845959 -405.245822) (xy 339.867748 -405.22017)
			(xy 339.873546 -405.213026) (xy 339.880058 -405.195834) (xy 339.880448 -405.186642) (xy 339.880448 -404.693374)
			(xy 339.88004 -404.684187) (xy 339.873523 -404.667003) (xy 339.867748 -404.659846) (xy 339.845982 -404.634176)
			(xy 339.808032 -404.578592) (xy 339.776997 -404.518871) (xy 339.753323 -404.455869) (xy 339.737348 -404.390489)
			(xy 339.729302 -404.323668) (xy 339.7293 -404.256365) (xy 339.737342 -404.189544) (xy 339.753313 -404.124163)
			(xy 339.776984 -404.061159) (xy 339.808015 -404.001436) (xy 339.845962 -403.94585) (xy 339.867748 -403.920198)
			(xy 339.873534 -403.913045) (xy 339.880054 -403.89586) (xy 339.880448 -403.88667) (xy 339.880448 -403.728682)
			(xy 339.880919 -403.718522) (xy 339.888701 -403.69975) (xy 339.903074 -403.685385) (xy 339.92185 -403.677613)
			(xy 339.93201 -403.67712) (xy 340.64829 -403.67712) (xy 340.658445 -403.677641) (xy 340.67721 -403.685409)
			(xy 340.691575 -403.699766) (xy 340.699353 -403.718527) (xy 340.699852 -403.728682) (xy 340.699852 -403.88667)
			(xy 340.700287 -403.895854) (xy 340.706785 -403.913038) (xy 340.712552 -403.920198) (xy 340.734362 -403.945832)
			(xy 340.772311 -404.001421) (xy 340.803343 -404.061147) (xy 340.827015 -404.124154) (xy 340.842987 -404.189538)
			(xy 340.85103 -404.256363) (xy 340.851028 -404.32367) (xy 340.842981 -404.390494) (xy 340.827006 -404.455878)
			(xy 340.80333 -404.518883) (xy 340.772294 -404.578608) (xy 340.734341 -404.634194) (xy 340.712552 -404.659846)
			(xy 340.706747 -404.666985) (xy 340.700239 -404.684181) (xy 340.699852 -404.693374) (xy 340.699852 -405.186642)
			(xy 340.700253 -405.19583) (xy 340.706774 -405.213014) (xy 340.712552 -405.22017) (xy 340.734334 -405.245827)
			(xy 340.772283 -405.301413) (xy 340.803317 -405.361135) (xy 340.826991 -405.424139) (xy 340.842965 -405.489521)
			(xy 340.851009 -405.556343) (xy 340.85101 -405.623648) (xy 340.842966 -405.69047) (xy 340.826994 -405.755852)
			(xy 340.803321 -405.818856) (xy 340.772288 -405.87858) (xy 340.734339 -405.934166) (xy 340.712552 -405.959818)
			(xy 340.706759 -405.966966) (xy 340.700244 -405.984154) (xy 340.699852 -405.993346) (xy 340.699852 -406.151334)
			(xy 340.699394 -406.161495) (xy 340.691607 -406.180267) (xy 340.67723 -406.194631) (xy 340.658452 -406.202403)
			(xy 340.64829 -406.202896) (xy 339.93201 -406.202896) (xy 339.921857 -406.202359) (xy 339.903095 -406.194594)
			(xy 339.88873 -406.180242) (xy 339.880949 -406.161487) (xy 339.880448 -406.151334) (xy 339.880448 -405.993346)
			(xy 339.880005 -405.984163) (xy 339.873513 -405.966979) (xy 339.867748 -405.959818) (xy 339.845954 -405.934171)
			(xy 339.808005 -405.878584) (xy 339.776971 -405.81886) (xy 339.753298 -405.755855) (xy 339.737325 -405.690472)
			(xy 339.729282 -405.623648) (xy 338.600728 -405.623648) (xy 338.572136 -405.67868) (xy 338.53419 -405.734267)
			(xy 338.512404 -405.75992) (xy 338.506617 -405.767072) (xy 338.500096 -405.784257) (xy 338.499704 -405.793448)
			(xy 338.499704 -406.286716) (xy 338.500106 -406.295904) (xy 338.506625 -406.313088) (xy 338.512404 -406.320244)
			(xy 338.534159 -406.345923) (xy 338.572106 -406.401506) (xy 338.603138 -406.461227) (xy 338.626811 -406.524228)
			(xy 338.642785 -406.589606) (xy 338.650831 -406.656425) (xy 338.650834 -406.723727) (xy 338.650827 -406.723789)
			(xy 341.928896 -406.723789) (xy 341.928898 -406.656363) (xy 341.936977 -406.589423) (xy 341.953016 -406.523932)
			(xy 341.976784 -406.460834) (xy 342.007938 -406.401036) (xy 342.04603 -406.345401) (xy 342.067896 -406.319736)
			(xy 342.073702 -406.312597) (xy 342.080211 -406.295402) (xy 342.080596 -406.286208) (xy 342.080596 -405.793956)
			(xy 342.080208 -405.784766) (xy 342.073679 -405.767582) (xy 342.067896 -405.760428) (xy 342.046028 -405.734766)
			(xy 342.00794 -405.679131) (xy 341.97679 -405.619334) (xy 341.953026 -405.556237) (xy 341.936991 -405.490748)
			(xy 341.928915 -405.423809) (xy 341.928916 -405.356385) (xy 341.936992 -405.289447) (xy 341.953028 -405.223957)
			(xy 341.976792 -405.16086) (xy 342.007943 -405.101064) (xy 342.046032 -405.045429) (xy 342.067896 -405.019764)
			(xy 342.07369 -405.012617) (xy 342.080206 -404.995428) (xy 342.080596 -404.986236) (xy 342.080596 -404.828756)
			(xy 342.081049 -404.818645) (xy 342.0888 -404.799967) (xy 342.103107 -404.785673) (xy 342.121793 -404.77794)
			(xy 342.131904 -404.777448) (xy 342.848184 -404.777448) (xy 342.858285 -404.777997) (xy 342.876953 -404.78572)
			(xy 342.891247 -404.799996) (xy 342.898991 -404.818655) (xy 342.899492 -404.828756) (xy 342.899492 -404.986236)
			(xy 342.899886 -404.995425) (xy 342.906411 -405.012609) (xy 342.912192 -405.019764) (xy 342.934052 -405.045432)
			(xy 342.972142 -405.101066) (xy 343.003293 -405.160862) (xy 343.027058 -405.223958) (xy 343.043094 -405.289447)
			(xy 343.05117 -405.356385) (xy 343.05117 -405.423809) (xy 343.043095 -405.490747) (xy 343.02706 -405.556236)
			(xy 343.003295 -405.619333) (xy 343.001047 -405.623648) (xy 344.129073 -405.623648) (xy 344.129073 -405.556343)
			(xy 344.137118 -405.48952) (xy 344.153091 -405.424137) (xy 344.176765 -405.361132) (xy 344.207799 -405.301409)
			(xy 344.245748 -405.245822) (xy 344.267536 -405.22017) (xy 344.273332 -405.213025) (xy 344.279846 -405.195834)
			(xy 344.280236 -405.186642) (xy 344.280236 -404.693374) (xy 344.27983 -404.684187) (xy 344.273313 -404.667003)
			(xy 344.267536 -404.659846) (xy 344.24577 -404.634176) (xy 344.207821 -404.578592) (xy 344.176787 -404.518871)
			(xy 344.153113 -404.455869) (xy 344.137139 -404.390489) (xy 344.129093 -404.323668) (xy 344.129091 -404.256365)
			(xy 344.137133 -404.189544) (xy 344.153103 -404.124163) (xy 344.176773 -404.061159) (xy 344.207804 -404.001437)
			(xy 344.24575 -403.94585) (xy 344.267536 -403.920198) (xy 344.273321 -403.913044) (xy 344.279842 -403.89586)
			(xy 344.280236 -403.88667) (xy 344.280236 -403.728682) (xy 344.280718 -403.718523) (xy 344.288498 -403.699754)
			(xy 344.302867 -403.685389) (xy 344.321639 -403.677615) (xy 344.331798 -403.67712) (xy 345.048078 -403.67712)
			(xy 345.058246 -403.677582) (xy 345.077037 -403.685356) (xy 345.091422 -403.69973) (xy 345.09921 -403.718514)
			(xy 345.09964 -403.728682) (xy 345.09964 -403.88667) (xy 345.100078 -403.895854) (xy 345.106574 -403.913038)
			(xy 345.11234 -403.920198) (xy 345.13415 -403.945832) (xy 345.1721 -404.00142) (xy 345.203133 -404.061146)
			(xy 345.226806 -404.124153) (xy 345.242778 -404.189538) (xy 345.250821 -404.256363) (xy 345.250819 -404.32367)
			(xy 345.242772 -404.390495) (xy 345.226796 -404.455878) (xy 345.20312 -404.518884) (xy 345.172083 -404.578608)
			(xy 345.13413 -404.634194) (xy 345.11234 -404.659846) (xy 345.106534 -404.666984) (xy 345.100027 -404.68418)
			(xy 345.09964 -404.693374) (xy 345.09964 -405.186642) (xy 345.100043 -405.19583) (xy 345.106563 -405.213013)
			(xy 345.11234 -405.22017) (xy 345.134122 -405.245827) (xy 345.172073 -405.301412) (xy 345.203107 -405.361135)
			(xy 345.226781 -405.424139) (xy 345.242755 -405.489521) (xy 345.2508 -405.556343) (xy 345.250801 -405.623648)
			(xy 345.242757 -405.69047) (xy 345.226784 -405.755853) (xy 345.203111 -405.818857) (xy 345.172077 -405.87858)
			(xy 345.134128 -405.934166) (xy 345.11234 -405.959818) (xy 345.106546 -405.966965) (xy 345.100031 -405.984154)
			(xy 345.09964 -405.993346) (xy 345.09964 -406.151334) (xy 345.099194 -406.161497) (xy 345.091404 -406.180271)
			(xy 345.077024 -406.194636) (xy 345.058241 -406.202405) (xy 345.048078 -406.202896) (xy 344.331798 -406.202896)
			(xy 344.321644 -406.202369) (xy 344.302882 -406.1946) (xy 344.288518 -406.180245) (xy 344.280737 -406.161487)
			(xy 344.280236 -406.151334) (xy 344.280236 -405.993346) (xy 344.279795 -405.984162) (xy 344.273302 -405.966978)
			(xy 344.267536 -405.959818) (xy 344.245742 -405.934171) (xy 344.207794 -405.878584) (xy 344.176761 -405.818859)
			(xy 344.153089 -405.755854) (xy 344.137116 -405.690471) (xy 344.129073 -405.623648) (xy 343.001047 -405.623648)
			(xy 342.972145 -405.679129) (xy 342.934056 -405.734763) (xy 342.912192 -405.760428) (xy 342.9064 -405.767576)
			(xy 342.899883 -405.784765) (xy 342.899492 -405.793956) (xy 342.899492 -406.286208) (xy 342.8999 -406.295395)
			(xy 342.906416 -406.312579) (xy 342.912192 -406.319736) (xy 342.934025 -406.345427) (xy 342.972115 -406.401058)
			(xy 343.003268 -406.46085) (xy 343.027034 -406.523944) (xy 343.043072 -406.58943) (xy 343.05115 -406.656365)
			(xy 343.051153 -406.72373) (xy 346.329191 -406.72373) (xy 346.329194 -406.656422) (xy 346.337242 -406.589596)
			(xy 346.35322 -406.524212) (xy 346.376898 -406.461206) (xy 346.407937 -406.401482) (xy 346.445893 -406.345896)
			(xy 346.467684 -406.320244) (xy 346.473485 -406.313102) (xy 346.479998 -406.295909) (xy 346.480384 -406.286716)
			(xy 346.480384 -405.793448) (xy 346.479955 -405.784263) (xy 346.473455 -405.767078) (xy 346.467684 -405.75992)
			(xy 346.445891 -405.734272) (xy 346.407939 -405.678686) (xy 346.376904 -405.618962) (xy 346.353229 -405.555957)
			(xy 346.337255 -405.490574) (xy 346.329211 -405.42375) (xy 346.329211 -405.356444) (xy 346.337256 -405.28962)
			(xy 346.353231 -405.224237) (xy 346.376906 -405.161232) (xy 346.407942 -405.101509) (xy 346.445895 -405.045924)
			(xy 346.467684 -405.020272) (xy 346.473473 -405.013121) (xy 346.479993 -404.995935) (xy 346.480384 -404.986744)
			(xy 346.480384 -404.828756) (xy 346.480785 -404.818601) (xy 346.488592 -404.799851) (xy 346.502995 -404.78553)
			(xy 346.521789 -404.777829) (xy 346.531946 -404.777448) (xy 347.248226 -404.777448) (xy 347.258355 -404.777905)
			(xy 347.277079 -404.785643) (xy 347.291434 -404.799938) (xy 347.299251 -404.818629) (xy 347.299788 -404.828756)
			(xy 347.299788 -404.986744) (xy 347.30018 -404.995933) (xy 347.306706 -405.013117) (xy 347.312488 -405.020272)
			(xy 347.334271 -405.045928) (xy 347.372218 -405.101514) (xy 347.40325 -405.161238) (xy 347.426922 -405.224242)
			(xy 347.442894 -405.289623) (xy 347.450938 -405.356445) (xy 347.450939 -405.423749) (xy 347.442895 -405.490571)
			(xy 347.426924 -405.555953) (xy 347.403253 -405.618957) (xy 347.400815 -405.623649) (xy 374.929103 -405.623649)
			(xy 374.929104 -405.556342) (xy 374.937149 -405.489519) (xy 374.953124 -405.424136) (xy 374.976799 -405.361131)
			(xy 375.007835 -405.301407) (xy 375.045787 -405.245822) (xy 375.067576 -405.22017) (xy 375.073365 -405.213019)
			(xy 375.079885 -405.195833) (xy 375.080276 -405.186642) (xy 375.080276 -404.693374) (xy 375.079884 -404.684185)
			(xy 375.073358 -404.667) (xy 375.067576 -404.659846) (xy 375.045809 -404.634177) (xy 375.007857 -404.578593)
			(xy 374.976821 -404.518873) (xy 374.953145 -404.45587) (xy 374.937169 -404.39049) (xy 374.929123 -404.323669)
			(xy 374.929121 -404.256365) (xy 374.937164 -404.189543) (xy 374.953135 -404.124161) (xy 374.976807 -404.061158)
			(xy 375.00784 -404.001435) (xy 375.045789 -403.94585) (xy 375.067576 -403.920198) (xy 375.073353 -403.913039)
			(xy 375.07988 -403.895859) (xy 375.080276 -403.88667) (xy 375.080276 -403.728682) (xy 375.08065 -403.718505)
			(xy 375.088448 -403.699702) (xy 375.102849 -403.685317) (xy 375.12166 -403.677539) (xy 375.131838 -403.67712)
			(xy 375.848118 -403.67712) (xy 375.858275 -403.677618) (xy 375.877041 -403.685395) (xy 375.891405 -403.699759)
			(xy 375.899182 -403.718525) (xy 375.89968 -403.728682) (xy 375.89968 -403.88667) (xy 375.900109 -403.895855)
			(xy 375.90661 -403.913039) (xy 375.91238 -403.920198) (xy 375.934189 -403.945833) (xy 375.972136 -404.001422)
			(xy 376.003167 -404.061148) (xy 376.026838 -404.124155) (xy 376.042809 -404.189539) (xy 376.050851 -404.256363)
			(xy 376.050849 -404.32367) (xy 376.042803 -404.390494) (xy 376.026828 -404.455877) (xy 376.003154 -404.518882)
			(xy 375.972119 -404.578606) (xy 375.934169 -404.634194) (xy 375.91238 -404.659846) (xy 375.906579 -404.666988)
			(xy 375.900068 -404.684181) (xy 375.89968 -404.693374) (xy 375.89968 -405.186642) (xy 375.900074 -405.195831)
			(xy 375.9066 -405.213015) (xy 375.91238 -405.22017) (xy 375.934161 -405.245827) (xy 375.972109 -405.301413)
			(xy 376.003142 -405.361136) (xy 376.026814 -405.42414) (xy 376.042787 -405.489522) (xy 376.050831 -405.556343)
			(xy 376.050832 -405.623648) (xy 376.042788 -405.690469) (xy 376.026817 -405.755851) (xy 376.003145 -405.818855)
			(xy 375.972114 -405.878579) (xy 375.934167 -405.934166) (xy 375.91238 -405.959818) (xy 375.906591 -405.966968)
			(xy 375.900072 -405.984155) (xy 375.89968 -405.993346) (xy 375.89968 -406.151334) (xy 375.899195 -406.161492)
			(xy 375.891413 -406.180258) (xy 375.877045 -406.194622) (xy 375.858276 -406.202398) (xy 375.848118 -406.202896)
			(xy 375.131838 -406.202896) (xy 375.121673 -406.202406) (xy 375.102886 -406.19464) (xy 375.088501 -406.180275)
			(xy 375.080708 -406.161498) (xy 375.080276 -406.151334) (xy 375.080276 -405.993346) (xy 375.079849 -405.984161)
			(xy 375.073347 -405.966976) (xy 375.067576 -405.959818) (xy 375.045781 -405.934171) (xy 375.00783 -405.878585)
			(xy 374.976795 -405.818861) (xy 374.953121 -405.755856) (xy 374.937148 -405.690472) (xy 374.929103 -405.623649)
			(xy 347.400815 -405.623649) (xy 347.372221 -405.678681) (xy 347.334275 -405.734268) (xy 347.312488 -405.75992)
			(xy 347.306699 -405.767071) (xy 347.30018 -405.784257) (xy 347.299788 -405.793448) (xy 347.299788 -406.286716)
			(xy 347.300193 -406.295904) (xy 347.30671 -406.313088) (xy 347.312488 -406.320244) (xy 347.334244 -406.345922)
			(xy 347.372192 -406.401506) (xy 347.403225 -406.461226) (xy 347.426898 -406.524227) (xy 347.442873 -406.589606)
			(xy 347.450919 -406.656425) (xy 347.450922 -406.723727) (xy 347.450915 -406.723789) (xy 377.128717 -406.723789)
			(xy 377.12872 -406.656363) (xy 377.136799 -406.589422) (xy 377.152839 -406.523931) (xy 377.176607 -406.460832)
			(xy 377.207763 -406.401035) (xy 377.245857 -406.345401) (xy 377.267724 -406.319736) (xy 377.273533 -406.3126)
			(xy 377.280039 -406.295402) (xy 377.280424 -406.286208) (xy 377.280424 -405.793956) (xy 377.28003 -405.784767)
			(xy 377.273504 -405.767583) (xy 377.267724 -405.760428) (xy 377.245855 -405.734766) (xy 377.207765 -405.679132)
			(xy 377.176613 -405.619335) (xy 377.152848 -405.556238) (xy 377.136812 -405.490748) (xy 377.128736 -405.423809)
			(xy 377.128737 -405.356385) (xy 377.136813 -405.289446) (xy 377.15285 -405.223956) (xy 377.176616 -405.160859)
			(xy 377.207768 -405.101063) (xy 377.245859 -405.045429) (xy 377.267724 -405.019764) (xy 377.273521 -405.012619)
			(xy 377.280035 -404.995428) (xy 377.280424 -404.986236) (xy 377.280424 -404.828756) (xy 377.28085 -404.818641)
			(xy 377.288606 -404.799958) (xy 377.302922 -404.785664) (xy 377.321617 -404.777935) (xy 377.331732 -404.777448)
			(xy 378.048012 -404.777448) (xy 378.058115 -404.777974) (xy 378.076783 -404.785706) (xy 378.091076 -404.79999)
			(xy 378.098819 -404.818653) (xy 378.09932 -404.828756) (xy 378.09932 -404.986236) (xy 378.099709 -404.995426)
			(xy 378.106237 -405.01261) (xy 378.11202 -405.019764) (xy 378.133879 -405.045433) (xy 378.171967 -405.101067)
			(xy 378.203117 -405.160863) (xy 378.22688 -405.22396) (xy 378.242915 -405.289448) (xy 378.250991 -405.356386)
			(xy 378.250992 -405.423808) (xy 378.242916 -405.490746) (xy 378.226882 -405.556235) (xy 378.203119 -405.619331)
			(xy 378.200839 -405.623707) (xy 379.328896 -405.623707) (xy 379.328896 -405.556284) (xy 379.336972 -405.489346)
			(xy 379.353008 -405.423856) (xy 379.376771 -405.360759) (xy 379.407921 -405.300963) (xy 379.446009 -405.245328)
			(xy 379.467872 -405.219662) (xy 379.473676 -405.212522) (xy 379.480184 -405.195327) (xy 379.480572 -405.186134)
			(xy 379.480572 -404.693882) (xy 379.480177 -404.684693) (xy 379.473653 -404.667509) (xy 379.467872 -404.660354)
			(xy 379.446031 -404.63467) (xy 379.407943 -404.579038) (xy 379.376793 -404.519244) (xy 379.353029 -404.45615)
			(xy 379.336993 -404.390663) (xy 379.328915 -404.323727) (xy 379.328913 -404.256306) (xy 379.336987 -404.18937)
			(xy 379.353019 -404.123882) (xy 379.376779 -404.060786) (xy 379.407926 -404.00099) (xy 379.44601 -403.945356)
			(xy 379.467872 -403.91969) (xy 379.473664 -403.912542) (xy 379.480179 -403.895353) (xy 379.480572 -403.886162)
			(xy 379.480572 -403.728682) (xy 379.481013 -403.71855) (xy 379.488752 -403.699822) (xy 379.503053 -403.685466)
			(xy 379.52175 -403.677653) (xy 379.53188 -403.67712) (xy 380.24816 -403.67712) (xy 380.258282 -403.677549)
			(xy 380.276989 -403.685288) (xy 380.291305 -403.699601) (xy 380.299048 -403.718306) (xy 380.299468 -403.728428)
			(xy 380.299468 -403.886162) (xy 380.299904 -403.895346) (xy 380.306401 -403.91253) (xy 380.312168 -403.91969)
			(xy 380.334055 -403.945337) (xy 380.372145 -404.000973) (xy 380.403296 -404.060772) (xy 380.427061 -404.123871)
			(xy 380.443096 -404.189363) (xy 380.45117 -404.256303) (xy 380.451168 -404.32373) (xy 380.44309 -404.39067)
			(xy 380.427051 -404.456161) (xy 380.403283 -404.519259) (xy 380.372128 -404.579055) (xy 380.334034 -404.634689)
			(xy 380.312168 -404.660354) (xy 380.306362 -404.667492) (xy 380.299854 -404.684688) (xy 380.299468 -404.693882)
			(xy 380.299468 -405.186134) (xy 380.299869 -405.195322) (xy 380.30639 -405.212506) (xy 380.312168 -405.219662)
			(xy 380.334027 -405.245332) (xy 380.372118 -405.300965) (xy 380.403271 -405.36076) (xy 380.427037 -405.423856)
			(xy 380.443074 -405.489345) (xy 380.451151 -405.556284) (xy 380.451151 -405.623707) (xy 380.443075 -405.690646)
			(xy 380.42704 -405.756135) (xy 380.403275 -405.819232) (xy 380.372123 -405.879028) (xy 380.334033 -405.934661)
			(xy 380.312168 -405.960326) (xy 380.306374 -405.967473) (xy 380.299858 -405.984662) (xy 380.299468 -405.993854)
			(xy 380.299468 -406.151334) (xy 380.299002 -406.161462) (xy 380.291264 -406.180182) (xy 380.276972 -406.194537)
			(xy 380.258286 -406.202357) (xy 380.24816 -406.202896) (xy 379.53188 -406.202896) (xy 379.521769 -406.202431)
			(xy 379.50309 -406.194686) (xy 379.488796 -406.180383) (xy 379.481062 -406.161699) (xy 379.480572 -406.151588)
			(xy 379.480572 -405.993854) (xy 379.480142 -405.984669) (xy 379.473643 -405.967484) (xy 379.467872 -405.960326)
			(xy 379.446003 -405.934665) (xy 379.407916 -405.879029) (xy 379.376768 -405.819232) (xy 379.353005 -405.756135)
			(xy 379.336971 -405.690646) (xy 379.328896 -405.623707) (xy 378.200839 -405.623707) (xy 378.17197 -405.679128)
			(xy 378.133883 -405.734762) (xy 378.11202 -405.760428) (xy 378.106231 -405.767579) (xy 378.099711 -405.784765)
			(xy 378.09932 -405.793956) (xy 378.09932 -406.286208) (xy 378.099722 -406.295396) (xy 378.106241 -406.312581)
			(xy 378.11202 -406.319736) (xy 378.133852 -406.345428) (xy 378.17194 -406.401059) (xy 378.203091 -406.460852)
			(xy 378.226856 -406.523945) (xy 378.242893 -406.589431) (xy 378.250971 -406.656366) (xy 378.250974 -406.723729)
			(xy 381.529036 -406.723729) (xy 381.529039 -406.656422) (xy 381.537086 -406.589598) (xy 381.553062 -406.524214)
			(xy 381.576737 -406.461209) (xy 381.607772 -406.401484) (xy 381.645723 -406.345897) (xy 381.667512 -406.320244)
			(xy 381.673316 -406.313104) (xy 381.679826 -406.29591) (xy 381.680212 -406.286716) (xy 381.680212 -405.793448)
			(xy 381.679776 -405.784264) (xy 381.67328 -405.767079) (xy 381.667512 -405.75992) (xy 381.645721 -405.734271)
			(xy 381.607774 -405.678683) (xy 381.576743 -405.618959) (xy 381.553071 -405.555954) (xy 381.537099 -405.490572)
			(xy 381.529056 -405.423749) (xy 381.529056 -405.356445) (xy 381.5371 -405.289622) (xy 381.553073 -405.22424)
			(xy 381.576745 -405.161235) (xy 381.607777 -405.101512) (xy 381.645725 -405.045924) (xy 381.667512 -405.020272)
			(xy 381.673304 -405.013124) (xy 381.679821 -404.995936) (xy 381.680212 -404.986744) (xy 381.680212 -404.828756)
			(xy 381.680649 -404.818643) (xy 381.688404 -404.799961) (xy 381.702715 -404.785668) (xy 381.721406 -404.777937)
			(xy 381.73152 -404.777448) (xy 382.448054 -404.777448) (xy 382.458179 -404.777965) (xy 382.4769 -404.785679)
			(xy 382.491258 -404.799956) (xy 382.499078 -404.818634) (xy 382.499616 -404.828756) (xy 382.499616 -404.986744)
			(xy 382.500001 -404.995934) (xy 382.506532 -405.013118) (xy 382.512316 -405.020272) (xy 382.534101 -405.045927)
			(xy 382.572053 -405.101512) (xy 382.603089 -405.161235) (xy 382.626764 -405.224239) (xy 382.642738 -405.289621)
			(xy 382.650784 -405.356444) (xy 382.650784 -405.42375) (xy 382.64274 -405.490573) (xy 382.626766 -405.555955)
			(xy 382.603091 -405.61896) (xy 382.600655 -405.623648) (xy 383.729191 -405.623648) (xy 383.729192 -405.556343)
			(xy 383.737237 -405.489519) (xy 383.753211 -405.424136) (xy 383.776885 -405.361132) (xy 383.807921 -405.301408)
			(xy 383.845871 -405.245822) (xy 383.86766 -405.22017) (xy 383.873459 -405.213027) (xy 383.879971 -405.195835)
			(xy 383.88036 -405.186642) (xy 383.88036 -404.693374) (xy 383.879949 -404.684187) (xy 383.873434 -404.667004)
			(xy 383.86766 -404.659846) (xy 383.845893 -404.634176) (xy 383.807943 -404.578593) (xy 383.776907 -404.518872)
			(xy 383.753232 -404.45587) (xy 383.737257 -404.390489) (xy 383.729211 -404.323668) (xy 383.729209 -404.256365)
			(xy 383.737251 -404.189543) (xy 383.753222 -404.124162) (xy 383.776894 -404.061158) (xy 383.807926 -404.001436)
			(xy 383.845873 -403.94585) (xy 383.86766 -403.920198) (xy 383.873447 -403.913047) (xy 383.879966 -403.895861)
			(xy 383.88036 -403.88667) (xy 383.88036 -403.728682) (xy 383.88075 -403.718507) (xy 383.888545 -403.699707)
			(xy 383.902941 -403.685322) (xy 383.921746 -403.677542) (xy 383.931922 -403.67712) (xy 384.648202 -403.67712)
			(xy 384.658358 -403.677631) (xy 384.677123 -403.685403) (xy 384.691488 -403.699763) (xy 384.699265 -403.718526)
			(xy 384.699764 -403.728682) (xy 384.699764 -403.88667) (xy 384.700197 -403.895855) (xy 384.706696 -403.913039)
			(xy 384.712464 -403.920198) (xy 384.734273 -403.945832) (xy 384.772221 -404.001421) (xy 384.803254 -404.061147)
			(xy 384.826925 -404.124154) (xy 384.842896 -404.189539) (xy 384.850939 -404.256363) (xy 384.850937 -404.32367)
			(xy 384.84289 -404.390494) (xy 384.826915 -404.455877) (xy 384.80324 -404.518883) (xy 384.772204 -404.578607)
			(xy 384.734253 -404.634194) (xy 384.712464 -404.659846) (xy 384.706661 -404.666986) (xy 384.700151 -404.684181)
			(xy 384.699764 -404.693374) (xy 384.699764 -405.186642) (xy 384.700162 -405.19583) (xy 384.706685 -405.213014)
			(xy 384.712464 -405.22017) (xy 384.734246 -405.245827) (xy 384.772195 -405.301413) (xy 384.803228 -405.361136)
			(xy 384.826901 -405.42414) (xy 384.842874 -405.489521) (xy 384.850919 -405.556343) (xy 384.850919 -405.623648)
			(xy 384.842876 -405.69047) (xy 384.826904 -405.755852) (xy 384.803232 -405.818856) (xy 384.772199 -405.878579)
			(xy 384.734251 -405.934166) (xy 384.712464 -405.959818) (xy 384.706673 -405.966967) (xy 384.700156 -405.984155)
			(xy 384.699764 -405.993346) (xy 384.699764 -406.151334) (xy 384.699295 -406.161494) (xy 384.691509 -406.180263)
			(xy 384.677136 -406.194627) (xy 384.658362 -406.202401) (xy 384.648202 -406.202896) (xy 383.931922 -406.202896)
			(xy 383.92177 -406.20235) (xy 383.903008 -406.194589) (xy 383.888643 -406.180239) (xy 383.880861 -406.161486)
			(xy 383.88036 -406.151334) (xy 383.88036 -405.993346) (xy 383.879914 -405.984163) (xy 383.873424 -405.966979)
			(xy 383.86766 -405.959818) (xy 383.845866 -405.934171) (xy 383.807916 -405.878584) (xy 383.776882 -405.81886)
			(xy 383.753208 -405.755855) (xy 383.737235 -405.690472) (xy 383.729191 -405.623648) (xy 382.600655 -405.623648)
			(xy 382.572056 -405.678683) (xy 382.534105 -405.734268) (xy 382.512316 -405.75992) (xy 382.50653 -405.767073)
			(xy 382.500009 -405.784257) (xy 382.499616 -405.793448) (xy 382.499616 -406.286716) (xy 382.500015 -406.295904)
			(xy 382.506536 -406.313089) (xy 382.512316 -406.320244) (xy 382.534074 -406.345921) (xy 382.572026 -406.401503)
			(xy 382.603063 -406.461223) (xy 382.62674 -406.524224) (xy 382.642717 -406.589604) (xy 382.650764 -406.656424)
			(xy 382.650767 -406.723728) (xy 382.65076 -406.723789) (xy 385.928805 -406.723789) (xy 385.928807 -406.656363)
			(xy 385.936887 -406.589422) (xy 385.952926 -406.523931) (xy 385.976694 -406.460833) (xy 386.007849 -406.401036)
			(xy 386.045942 -406.345401) (xy 386.067808 -406.319736) (xy 386.073615 -406.312598) (xy 386.080123 -406.295402)
			(xy 386.080508 -406.286208) (xy 386.080508 -405.793956) (xy 386.080117 -405.784767) (xy 386.07359 -405.767583)
			(xy 386.067808 -405.760428) (xy 386.04594 -405.734766) (xy 386.007851 -405.679131) (xy 385.9767 -405.619335)
			(xy 385.952935 -405.556237) (xy 385.9369 -405.490748) (xy 385.928824 -405.423809) (xy 385.928825 -405.356385)
			(xy 385.936901 -405.289446) (xy 385.952937 -405.223957) (xy 385.976702 -405.16086) (xy 386.007854 -405.101064)
			(xy 386.045944 -405.045429) (xy 386.067808 -405.019764) (xy 386.073603 -405.012618) (xy 386.080118 -404.995428)
			(xy 386.080508 -404.986236) (xy 386.080508 -404.828756) (xy 386.080949 -404.818643) (xy 386.088703 -404.799963)
			(xy 386.103013 -404.785669) (xy 386.121703 -404.777938) (xy 386.131816 -404.777448) (xy 386.848096 -404.777448)
			(xy 386.858198 -404.777987) (xy 386.876866 -404.785714) (xy 386.891159 -404.799993) (xy 386.898903 -404.818654)
			(xy 386.899404 -404.828756) (xy 386.899404 -404.986236) (xy 386.899796 -404.995425) (xy 386.906322 -405.012609)
			(xy 386.912104 -405.019764) (xy 386.933964 -405.045433) (xy 386.972052 -405.101067) (xy 387.003203 -405.160862)
			(xy 387.026967 -405.223959) (xy 387.043003 -405.289448) (xy 387.051079 -405.356385) (xy 387.051079 -405.423809)
			(xy 387.043004 -405.490747) (xy 387.026969 -405.556235) (xy 387.003206 -405.619332) (xy 387.000958 -405.623648)
			(xy 388.128982 -405.623648) (xy 388.128982 -405.556343) (xy 388.137027 -405.489519) (xy 388.153001 -405.424137)
			(xy 388.176675 -405.361132) (xy 388.207709 -405.301408) (xy 388.245659 -405.245822) (xy 388.267448 -405.22017)
			(xy 388.273246 -405.213026) (xy 388.279758 -405.195834) (xy 388.280148 -405.186642) (xy 388.280148 -404.693374)
			(xy 388.27974 -404.684187) (xy 388.273223 -404.667003) (xy 388.267448 -404.659846) (xy 388.245682 -404.634176)
			(xy 388.207732 -404.578592) (xy 388.176697 -404.518871) (xy 388.153023 -404.455869) (xy 388.137048 -404.390489)
			(xy 388.129002 -404.323668) (xy 388.129 -404.256365) (xy 388.137042 -404.189544) (xy 388.153013 -404.124163)
			(xy 388.176684 -404.061159) (xy 388.207715 -404.001436) (xy 388.245662 -403.94585) (xy 388.267448 -403.920198)
			(xy 388.273234 -403.913045) (xy 388.279754 -403.89586) (xy 388.280148 -403.88667) (xy 388.280148 -403.728682)
			(xy 388.280619 -403.718522) (xy 388.288401 -403.69975) (xy 388.302774 -403.685385) (xy 388.32155 -403.677613)
			(xy 388.33171 -403.67712) (xy 389.04799 -403.67712) (xy 389.058145 -403.677641) (xy 389.07691 -403.685409)
			(xy 389.091275 -403.699766) (xy 389.099053 -403.718527) (xy 389.099552 -403.728682) (xy 389.099552 -403.88667)
			(xy 389.099987 -403.895854) (xy 389.106485 -403.913038) (xy 389.112252 -403.920198) (xy 389.134062 -403.945832)
			(xy 389.172011 -404.001421) (xy 389.203043 -404.061147) (xy 389.226715 -404.124154) (xy 389.242687 -404.189538)
			(xy 389.25073 -404.256363) (xy 389.250728 -404.32367) (xy 389.242681 -404.390494) (xy 389.226706 -404.455878)
			(xy 389.20303 -404.518883) (xy 389.171994 -404.578608) (xy 389.134041 -404.634194) (xy 389.112252 -404.659846)
			(xy 389.106447 -404.666985) (xy 389.099939 -404.684181) (xy 389.099552 -404.693374) (xy 389.099552 -405.186642)
			(xy 389.099953 -405.19583) (xy 389.106474 -405.213014) (xy 389.112252 -405.22017) (xy 389.134034 -405.245827)
			(xy 389.171983 -405.301413) (xy 389.203017 -405.361135) (xy 389.226691 -405.424139) (xy 389.242665 -405.489521)
			(xy 389.250709 -405.556343) (xy 389.25071 -405.623648) (xy 389.242666 -405.69047) (xy 389.226694 -405.755852)
			(xy 389.203021 -405.818856) (xy 389.171988 -405.87858) (xy 389.134039 -405.934166) (xy 389.112252 -405.959818)
			(xy 389.106459 -405.966966) (xy 389.099944 -405.984154) (xy 389.099552 -405.993346) (xy 389.099552 -406.151334)
			(xy 389.099094 -406.161495) (xy 389.091307 -406.180267) (xy 389.07693 -406.194631) (xy 389.058152 -406.202403)
			(xy 389.04799 -406.202896) (xy 388.33171 -406.202896) (xy 388.321557 -406.202359) (xy 388.302795 -406.194594)
			(xy 388.28843 -406.180242) (xy 388.280649 -406.161487) (xy 388.280148 -406.151334) (xy 388.280148 -405.993346)
			(xy 388.279705 -405.984163) (xy 388.273213 -405.966979) (xy 388.267448 -405.959818) (xy 388.245654 -405.934171)
			(xy 388.207705 -405.878584) (xy 388.176671 -405.81886) (xy 388.152998 -405.755855) (xy 388.137025 -405.690472)
			(xy 388.128982 -405.623648) (xy 387.000958 -405.623648) (xy 386.972056 -405.679128) (xy 386.933968 -405.734763)
			(xy 386.912104 -405.760428) (xy 386.906314 -405.767578) (xy 386.899795 -405.784765) (xy 386.899404 -405.793956)
			(xy 386.899404 -406.286208) (xy 386.89981 -406.295396) (xy 386.906326 -406.31258) (xy 386.912104 -406.319736)
			(xy 386.933936 -406.345427) (xy 386.972026 -406.401058) (xy 387.003178 -406.460851) (xy 387.026943 -406.523944)
			(xy 387.042981 -406.58943) (xy 387.051059 -406.656365) (xy 387.051062 -406.723729) (xy 390.329124 -406.723729)
			(xy 390.329127 -406.656423) (xy 390.337174 -406.589599) (xy 390.353149 -406.524215) (xy 390.376823 -406.461209)
			(xy 390.407858 -406.401485) (xy 390.445808 -406.345897) (xy 390.467596 -406.320244) (xy 390.473398 -406.313103)
			(xy 390.47991 -406.295909) (xy 390.480296 -406.286716) (xy 390.480296 -405.793448) (xy 390.479864 -405.784263)
			(xy 390.473366 -405.767078) (xy 390.467596 -405.75992) (xy 390.445806 -405.73427) (xy 390.40786 -405.678683)
			(xy 390.376829 -405.618958) (xy 390.353158 -405.555954) (xy 390.337187 -405.490571) (xy 390.329144 -405.423749)
			(xy 390.329144 -405.356445) (xy 390.337188 -405.289623) (xy 390.35316 -405.224241) (xy 390.376832 -405.161236)
			(xy 390.407863 -405.101512) (xy 390.445809 -405.045925) (xy 390.467596 -405.020272) (xy 390.473386 -405.013122)
			(xy 390.479905 -404.995935) (xy 390.480296 -404.986744) (xy 390.480296 -404.828756) (xy 390.480749 -404.818645)
			(xy 390.4885 -404.799967) (xy 390.502807 -404.785673) (xy 390.521493 -404.77794) (xy 390.531604 -404.777448)
			(xy 391.248138 -404.777448) (xy 391.258268 -404.777896) (xy 391.276992 -404.785637) (xy 391.291347 -404.799935)
			(xy 391.299163 -404.818628) (xy 391.2997 -404.828756) (xy 391.2997 -404.986744) (xy 391.300089 -404.995933)
			(xy 391.306617 -405.013118) (xy 391.3124 -405.020272) (xy 391.334183 -405.045928) (xy 391.372129 -405.101515)
			(xy 391.40316 -405.161238) (xy 391.426832 -405.224242) (xy 391.442804 -405.289623) (xy 391.450848 -405.356445)
			(xy 391.450848 -405.423749) (xy 391.442805 -405.490571) (xy 391.426833 -405.555952) (xy 391.403163 -405.618956)
			(xy 391.372132 -405.67868) (xy 391.334186 -405.734267) (xy 391.3124 -405.75992) (xy 391.306612 -405.767072)
			(xy 391.300092 -405.784257) (xy 391.2997 -405.793448) (xy 391.2997 -406.286716) (xy 391.300103 -406.295904)
			(xy 391.306622 -406.313088) (xy 391.3124 -406.320244) (xy 391.334155 -406.345923) (xy 391.372102 -406.401506)
			(xy 391.403135 -406.461226) (xy 391.426808 -406.524227) (xy 391.442782 -406.589606) (xy 391.450828 -406.656425)
			(xy 391.450831 -406.723727) (xy 391.44279 -406.790547) (xy 391.426822 -406.855927) (xy 391.403154 -406.91893)
			(xy 391.372127 -406.978653) (xy 391.334185 -407.034239) (xy 391.3124 -407.059892) (xy 391.306624 -407.067052)
			(xy 391.300097 -407.084231) (xy 391.2997 -407.09342) (xy 391.2997 -407.251408) (xy 391.299221 -407.261517)
			(xy 391.291481 -407.280196) (xy 391.277182 -407.29449) (xy 391.258501 -407.302224) (xy 391.248392 -407.302716)
			(xy 390.531858 -407.302716) (xy 390.521723 -407.302307) (xy 390.502993 -407.294557) (xy 390.488636 -407.280247)
			(xy 390.480826 -407.261541) (xy 390.480296 -407.251408) (xy 390.480296 -407.09342) (xy 390.479877 -407.084234)
			(xy 390.47337 -407.067049) (xy 390.467596 -407.059892) (xy 390.445778 -407.034265) (xy 390.407833 -406.978674)
			(xy 390.376804 -406.918947) (xy 390.353135 -406.855939) (xy 390.337165 -406.790554) (xy 390.329124 -406.723729)
			(xy 387.051062 -406.723729) (xy 387.051062 -406.723787) (xy 387.04299 -406.790723) (xy 387.026958 -406.85621)
			(xy 387.003197 -406.919305) (xy 386.972051 -406.979101) (xy 386.933966 -407.034735) (xy 386.912104 -407.0604)
			(xy 386.906325 -407.067558) (xy 386.8998 -407.084739) (xy 386.899404 -407.093928) (xy 386.899404 -407.251408)
			(xy 386.898921 -407.261517) (xy 386.891182 -407.280194) (xy 386.876884 -407.294489) (xy 386.858205 -407.302224)
			(xy 386.848096 -407.302716) (xy 386.131816 -407.302716) (xy 386.121697 -407.302271) (xy 386.102996 -407.294531)
			(xy 386.088682 -407.280224) (xy 386.080933 -407.261527) (xy 386.080508 -407.251408) (xy 386.080508 -407.093928)
			(xy 386.080083 -407.084742) (xy 386.073579 -407.067558) (xy 386.067808 -407.0604) (xy 386.045912 -407.034761)
			(xy 386.007824 -406.979123) (xy 385.976674 -406.919323) (xy 385.952912 -406.856223) (xy 385.936878 -406.79073)
			(xy 385.928805 -406.723789) (xy 382.65076 -406.723789) (xy 382.642725 -406.790549) (xy 382.626754 -406.85593)
			(xy 382.603083 -406.918933) (xy 382.572051 -406.978655) (xy 382.534103 -407.03424) (xy 382.512316 -407.059892)
			(xy 382.506542 -407.067053) (xy 382.500013 -407.084231) (xy 382.499616 -407.09342) (xy 382.499616 -407.251408)
			(xy 382.499122 -407.261515) (xy 382.491384 -407.28019) (xy 382.47709 -407.294484) (xy 382.458415 -407.302222)
			(xy 382.448308 -407.302716) (xy 381.731774 -407.302716) (xy 381.72164 -407.302294) (xy 381.70291 -407.294549)
			(xy 381.688553 -407.280243) (xy 381.680743 -407.26154) (xy 381.680212 -407.251408) (xy 381.680212 -407.09342)
			(xy 381.679789 -407.084234) (xy 381.673284 -407.06705) (xy 381.667512 -407.059892) (xy 381.645694 -407.034265)
			(xy 381.607748 -406.978675) (xy 381.576717 -406.918947) (xy 381.553047 -406.855939) (xy 381.537077 -406.790554)
			(xy 381.529036 -406.723729) (xy 378.250974 -406.723729) (xy 378.250974 -406.723786) (xy 378.242902 -406.790722)
			(xy 378.226871 -406.856209) (xy 378.203111 -406.919305) (xy 378.171965 -406.9791) (xy 378.133881 -407.034734)
			(xy 378.11202 -407.0604) (xy 378.106243 -407.067559) (xy 378.099716 -407.084739) (xy 378.09932 -407.093928)
			(xy 378.09932 -407.251408) (xy 378.098822 -407.261515) (xy 378.091085 -407.280189) (xy 378.076793 -407.294483)
			(xy 378.058119 -407.302221) (xy 378.048012 -407.302716) (xy 377.331732 -407.302716) (xy 377.321614 -407.302258)
			(xy 377.302914 -407.294524) (xy 377.288599 -407.28022) (xy 377.280849 -407.261526) (xy 377.280424 -407.251408)
			(xy 377.280424 -407.093928) (xy 377.279995 -407.084743) (xy 377.273494 -407.067559) (xy 377.267724 -407.0604)
			(xy 377.245828 -407.034761) (xy 377.207738 -406.979123) (xy 377.176588 -406.919324) (xy 377.152824 -406.856223)
			(xy 377.13679 -406.790731) (xy 377.128717 -406.723789) (xy 347.450915 -406.723789) (xy 347.442881 -406.790547)
			(xy 347.426912 -406.855927) (xy 347.403244 -406.91893) (xy 347.372216 -406.978653) (xy 347.334273 -407.03424)
			(xy 347.312488 -407.059892) (xy 347.306711 -407.067051) (xy 347.300185 -407.084231) (xy 347.299788 -407.09342)
			(xy 347.299788 -407.251408) (xy 347.299385 -407.261564) (xy 347.291584 -407.280319) (xy 347.277182 -407.294642)
			(xy 347.258384 -407.30234) (xy 347.248226 -407.302716) (xy 346.531946 -407.302716) (xy 346.521817 -407.302234)
			(xy 346.503088 -407.294514) (xy 346.488729 -407.280225) (xy 346.480916 -407.261535) (xy 346.480384 -407.251408)
			(xy 346.480384 -407.09342) (xy 346.479968 -407.084233) (xy 346.473459 -407.067049) (xy 346.467684 -407.059892)
			(xy 346.445864 -407.034266) (xy 346.407913 -406.978677) (xy 346.376878 -406.91895) (xy 346.353205 -406.855942)
			(xy 346.337233 -406.790556) (xy 346.329191 -406.72373) (xy 343.051153 -406.72373) (xy 343.051153 -406.723787)
			(xy 343.04308 -406.790723) (xy 343.027048 -406.85621) (xy 343.003287 -406.919306) (xy 342.97214 -406.979101)
			(xy 342.934054 -407.034735) (xy 342.912192 -407.0604) (xy 342.906412 -407.067557) (xy 342.899888 -407.084738)
			(xy 342.899492 -407.093928) (xy 342.899492 -407.251408) (xy 342.89909 -407.261532) (xy 342.891338 -407.280237)
			(xy 342.877017 -407.294551) (xy 342.858308 -407.302295) (xy 342.848184 -407.302716) (xy 342.131904 -407.302716)
			(xy 342.121798 -407.302212) (xy 342.103122 -407.294479) (xy 342.088828 -407.280188) (xy 342.08109 -407.261514)
			(xy 342.080596 -407.251408) (xy 342.080596 -407.093928) (xy 342.080173 -407.084742) (xy 342.073668 -407.067558)
			(xy 342.067896 -407.0604) (xy 342.046001 -407.034761) (xy 342.007913 -406.979122) (xy 341.976764 -406.919322)
			(xy 341.953002 -406.856222) (xy 341.936969 -406.79073) (xy 341.928896 -406.723789) (xy 338.650827 -406.723789)
			(xy 338.642793 -406.790546) (xy 338.626825 -406.855926) (xy 338.603158 -406.918929) (xy 338.572131 -406.978652)
			(xy 338.534188 -407.034239) (xy 338.512404 -407.059892) (xy 338.506629 -407.067052) (xy 338.500101 -407.084231)
			(xy 338.499704 -407.09342) (xy 338.499704 -407.251408) (xy 338.499285 -407.261562) (xy 338.491487 -407.280314)
			(xy 338.47709 -407.294637) (xy 338.458298 -407.302337) (xy 338.448142 -407.302716) (xy 337.731862 -407.302716)
			(xy 337.721727 -407.302303) (xy 337.702997 -407.294555) (xy 337.688641 -407.280246) (xy 337.68083 -407.261541)
			(xy 337.6803 -407.251408) (xy 337.6803 -407.09342) (xy 337.67988 -407.084234) (xy 337.673373 -407.067049)
			(xy 337.6676 -407.059892) (xy 337.645782 -407.034265) (xy 337.607837 -406.978674) (xy 337.576807 -406.918947)
			(xy 337.553138 -406.855939) (xy 337.537168 -406.790554) (xy 337.529127 -406.723729) (xy 334.251065 -406.723729)
			(xy 334.251065 -406.723786) (xy 334.242993 -406.790722) (xy 334.226961 -406.85621) (xy 334.203201 -406.919305)
			(xy 334.172054 -406.9791) (xy 334.13397 -407.034735) (xy 334.112108 -407.0604) (xy 334.10633 -407.067558)
			(xy 334.099804 -407.084739) (xy 334.099408 -407.093928) (xy 334.099408 -407.251408) (xy 334.098921 -407.261516)
			(xy 334.091183 -407.280193) (xy 334.076886 -407.294487) (xy 334.058208 -407.302223) (xy 334.0481 -407.302716)
			(xy 333.33182 -407.302716) (xy 333.321701 -407.302268) (xy 333.303001 -407.29453) (xy 333.288686 -407.280223)
			(xy 333.280937 -407.261527) (xy 333.280512 -407.251408) (xy 333.280512 -407.093928) (xy 333.280086 -407.084743)
			(xy 333.273583 -407.067558) (xy 333.267812 -407.0604) (xy 333.245916 -407.034761) (xy 333.207828 -406.979123)
			(xy 333.176678 -406.919323) (xy 333.152915 -406.856223) (xy 333.136881 -406.790731) (xy 333.128808 -406.723789)
			(xy 326.525636 -406.723789) (xy 326.525636 -409.523827) (xy 330.929173 -409.523827) (xy 330.929176 -409.456519)
			(xy 330.937224 -409.389693) (xy 330.953202 -409.324309) (xy 330.976879 -409.261303) (xy 331.007918 -409.201578)
			(xy 331.045873 -409.145992) (xy 331.067664 -409.12034) (xy 331.073476 -409.113206) (xy 331.07998 -409.096007)
			(xy 331.080364 -409.086812) (xy 331.080364 -408.593544) (xy 331.079919 -408.584361) (xy 331.073428 -408.567177)
			(xy 331.067664 -408.560016) (xy 331.045868 -408.534371) (xy 331.007918 -408.478784) (xy 330.976883 -408.419059)
			(xy 330.95321 -408.356054) (xy 330.937237 -408.290671) (xy 330.929193 -408.223847) (xy 330.929194 -408.156541)
			(xy 330.937239 -408.089717) (xy 330.953213 -408.024334) (xy 330.976888 -407.96133) (xy 331.007924 -407.901606)
			(xy 331.045875 -407.84602) (xy 331.067664 -407.820368) (xy 331.073464 -407.813226) (xy 331.079975 -407.796033)
			(xy 331.080364 -407.78684) (xy 331.080364 -407.628852) (xy 331.080782 -407.618699) (xy 331.088586 -407.599953)
			(xy 331.102983 -407.585633) (xy 331.121771 -407.577928) (xy 331.131926 -407.577544) (xy 331.848206 -407.577544)
			(xy 331.858334 -407.578022) (xy 331.877056 -407.585752) (xy 331.891412 -407.600041) (xy 331.89923 -407.618727)
			(xy 331.899768 -407.628852) (xy 331.899768 -407.78684) (xy 331.900166 -407.796028) (xy 331.906689 -407.813212)
			(xy 331.912468 -407.820368) (xy 331.934248 -407.846027) (xy 331.972196 -407.901612) (xy 332.00323 -407.961335)
			(xy 332.026903 -408.024339) (xy 332.042876 -408.08972) (xy 332.050921 -408.156542) (xy 332.050921 -408.223846)
			(xy 332.042878 -408.290668) (xy 332.026906 -408.35605) (xy 332.003235 -408.419054) (xy 331.972203 -408.478777)
			(xy 331.934255 -408.534364) (xy 331.912468 -408.560016) (xy 331.906678 -408.567166) (xy 331.90016 -408.584353)
			(xy 331.899768 -408.593544) (xy 331.899768 -409.086812) (xy 331.900179 -409.095999) (xy 331.906693 -409.113183)
			(xy 331.912468 -409.12034) (xy 331.93422 -409.146022) (xy 331.972169 -409.201604) (xy 332.003204 -409.261323)
			(xy 332.026878 -409.324324) (xy 332.042853 -409.389703) (xy 332.0509 -409.456522) (xy 332.050904 -409.523824)
			(xy 332.042863 -409.590644) (xy 332.026894 -409.656024) (xy 332.003226 -409.719027) (xy 331.972197 -409.77875)
			(xy 331.934253 -409.834336) (xy 331.912468 -409.859988) (xy 331.906647 -409.867116) (xy 331.900148 -409.88432)
			(xy 331.899768 -409.893516) (xy 331.899768 -410.051504) (xy 331.899381 -410.061662) (xy 331.891578 -410.080421)
			(xy 331.87717 -410.094745) (xy 331.858367 -410.102439) (xy 331.848206 -410.102812) (xy 331.131926 -410.102812)
			(xy 331.121807 -410.102254) (xy 331.103097 -410.094544) (xy 331.088741 -410.08028) (xy 331.080912 -410.061619)
			(xy 331.080364 -410.051504) (xy 331.080364 -409.893516) (xy 331.079932 -409.884331) (xy 331.073432 -409.867148)
			(xy 331.067664 -409.859988) (xy 331.04584 -409.834365) (xy 331.007891 -409.778775) (xy 330.976857 -409.719048)
			(xy 330.953186 -409.656039) (xy 330.937214 -409.590653) (xy 330.929173 -409.523827) (xy 326.525636 -409.523827)
			(xy 326.525636 -410.623701) (xy 333.128819 -410.623701) (xy 333.12882 -410.556275) (xy 333.136898 -410.489336)
			(xy 333.152936 -410.423846) (xy 333.176702 -410.360748) (xy 333.207855 -410.300952) (xy 333.245947 -410.245317)
			(xy 333.267812 -410.219652) (xy 333.273613 -410.21251) (xy 333.280125 -410.195317) (xy 333.280512 -410.186124)
			(xy 333.280512 -409.693872) (xy 333.280113 -409.684684) (xy 333.273591 -409.6675) (xy 333.267812 -409.660344)
			(xy 333.245959 -409.634669) (xy 333.20787 -409.579036) (xy 333.176718 -409.519242) (xy 333.152952 -409.456146)
			(xy 333.136916 -409.390658) (xy 333.128839 -409.32372) (xy 333.128837 -409.256298) (xy 333.136912 -409.18936)
			(xy 333.152947 -409.123871) (xy 333.17671 -409.060775) (xy 333.20786 -409.000979) (xy 333.245948 -408.945345)
			(xy 333.267812 -408.91968) (xy 333.273601 -408.912529) (xy 333.28012 -408.895343) (xy 333.280512 -408.886152)
			(xy 333.280512 -408.728672) (xy 333.280962 -408.71856) (xy 333.288711 -408.699879) (xy 333.303019 -408.685585)
			(xy 333.321708 -408.677853) (xy 333.33182 -408.677364) (xy 334.0481 -408.677364) (xy 334.058204 -408.677884)
			(xy 334.076876 -408.685615) (xy 334.091169 -408.699901) (xy 334.09891 -408.718568) (xy 334.099408 -408.728672)
			(xy 334.099408 -408.886152) (xy 334.099839 -408.895337) (xy 334.106338 -408.912522) (xy 334.112108 -408.91968)
			(xy 334.133983 -408.945336) (xy 334.172071 -409.000972) (xy 334.203221 -409.060769) (xy 334.226984 -409.123867)
			(xy 334.243019 -409.189358) (xy 334.251093 -409.256297) (xy 334.251092 -409.323721) (xy 334.243015 -409.39066)
			(xy 334.226979 -409.45615) (xy 334.203214 -409.519247) (xy 334.200797 -409.523886) (xy 335.328966 -409.523886)
			(xy 335.328969 -409.45646) (xy 335.337048 -409.38952) (xy 335.353086 -409.32403) (xy 335.376852 -409.260931)
			(xy 335.408005 -409.201134) (xy 335.446095 -409.145498) (xy 335.46796 -409.119832) (xy 335.473775 -409.1127)
			(xy 335.480277 -409.095499) (xy 335.48066 -409.086304) (xy 335.48066 -408.594052) (xy 335.480211 -408.584869)
			(xy 335.473723 -408.567685) (xy 335.46796 -408.560524) (xy 335.44609 -408.534865) (xy 335.408004 -408.479228)
			(xy 335.376856 -408.419431) (xy 335.353094 -408.356333) (xy 335.33706 -408.290844) (xy 335.328985 -408.223906)
			(xy 335.328986 -408.156482) (xy 335.337062 -408.089544) (xy 335.353097 -408.024055) (xy 335.376861 -407.960958)
			(xy 335.40801 -407.901161) (xy 335.446097 -407.845526) (xy 335.46796 -407.81986) (xy 335.473763 -407.81272)
			(xy 335.480272 -407.795525) (xy 335.48066 -407.786332) (xy 335.48066 -407.628852) (xy 335.481145 -407.618745)
			(xy 335.488891 -407.600074) (xy 335.503187 -407.585782) (xy 335.521861 -407.578042) (xy 335.531968 -407.577544)
			(xy 336.248248 -407.577544) (xy 336.258353 -407.578045) (xy 336.277021 -407.585788) (xy 336.291312 -407.600079)
			(xy 336.299055 -407.618747) (xy 336.299556 -407.628852) (xy 336.299556 -407.786332) (xy 336.299961 -407.79552)
			(xy 336.306479 -407.812703) (xy 336.312256 -407.81986) (xy 336.334114 -407.845531) (xy 336.372205 -407.901164)
			(xy 336.403359 -407.960959) (xy 336.427126 -408.024055) (xy 336.443163 -408.089544) (xy 336.45124 -408.156482)
			(xy 336.451241 -408.223906) (xy 336.443165 -408.290844) (xy 336.427129 -408.356334) (xy 336.403364 -408.41943)
			(xy 336.372212 -408.479226) (xy 336.334121 -408.53486) (xy 336.312256 -408.560524) (xy 336.306461 -408.56767)
			(xy 336.299947 -408.58486) (xy 336.299556 -408.594052) (xy 336.299556 -409.086304) (xy 336.299974 -409.09549)
			(xy 336.306483 -409.112674) (xy 336.312256 -409.119832) (xy 336.334086 -409.145526) (xy 336.372179 -409.201155)
			(xy 336.403334 -409.260947) (xy 336.427102 -409.32404) (xy 336.443141 -409.389526) (xy 336.45122 -409.456462)
			(xy 336.451224 -409.523884) (xy 336.443151 -409.59082) (xy 336.427118 -409.656308) (xy 336.403356 -409.719404)
			(xy 336.372207 -409.779198) (xy 336.334119 -409.834832) (xy 336.312256 -409.860496) (xy 336.306473 -409.867651)
			(xy 336.299951 -409.884834) (xy 336.299556 -409.894024) (xy 336.299556 -410.051504) (xy 336.299019 -410.061606)
			(xy 336.291291 -410.080274) (xy 336.277011 -410.094566) (xy 336.25835 -410.102311) (xy 336.248248 -410.102812)
			(xy 335.531968 -410.102812) (xy 335.521859 -410.102341) (xy 335.503182 -410.094595) (xy 335.488889 -410.080294)
			(xy 335.481153 -410.061614) (xy 335.48066 -410.051504) (xy 335.48066 -409.894024) (xy 335.480225 -409.88484)
			(xy 335.473727 -409.867656) (xy 335.46796 -409.860496) (xy 335.446062 -409.834859) (xy 335.407977 -409.77922)
			(xy 335.37683 -409.719419) (xy 335.35307 -409.656319) (xy 335.337038 -409.590827) (xy 335.328966 -409.523886)
			(xy 334.200797 -409.523886) (xy 334.172062 -409.579044) (xy 334.133972 -409.634679) (xy 334.112108 -409.660344)
			(xy 334.106311 -409.667489) (xy 334.099796 -409.68468) (xy 334.099408 -409.693872) (xy 334.099408 -410.186124)
			(xy 334.099805 -410.195313) (xy 334.106328 -410.212497) (xy 334.112108 -410.219652) (xy 334.133956 -410.24533)
			(xy 334.172045 -410.300963) (xy 334.203196 -410.360758) (xy 334.22696 -410.423853) (xy 334.242997 -410.48934)
			(xy 334.251074 -410.556277) (xy 334.251075 -410.623641) (xy 337.529138 -410.623641) (xy 337.52914 -410.556335)
			(xy 337.537185 -410.489512) (xy 337.553158 -410.42413) (xy 337.576831 -410.361125) (xy 337.607864 -410.3014)
			(xy 337.645813 -410.245813) (xy 337.6676 -410.22016) (xy 337.673396 -410.213014) (xy 337.679911 -410.195824)
			(xy 337.6803 -410.186632) (xy 337.6803 -409.693364) (xy 337.679907 -409.684175) (xy 337.673382 -409.666991)
			(xy 337.6676 -409.659836) (xy 337.645825 -409.634174) (xy 337.607879 -409.578588) (xy 337.576847 -409.518865)
			(xy 337.553175 -409.455862) (xy 337.537203 -409.390482) (xy 337.529158 -409.323661) (xy 337.529157 -409.256357)
			(xy 337.537199 -409.189536) (xy 337.55317 -409.124155) (xy 337.57684 -409.061151) (xy 337.607869 -409.001428)
			(xy 337.645814 -408.945841) (xy 337.6676 -408.920188) (xy 337.673384 -408.913034) (xy 337.679906 -408.89585)
			(xy 337.6803 -408.88666) (xy 337.6803 -408.728672) (xy 337.680699 -408.718516) (xy 337.688503 -408.699763)
			(xy 337.702907 -408.685441) (xy 337.721704 -408.677742) (xy 337.731862 -408.677364) (xy 338.448142 -408.677364)
			(xy 338.458274 -408.677793) (xy 338.477001 -408.685539) (xy 338.491357 -408.699843) (xy 338.49917 -408.718542)
			(xy 338.499704 -408.728672) (xy 338.499704 -408.88666) (xy 338.500132 -408.895845) (xy 338.506633 -408.91303)
			(xy 338.512404 -408.920188) (xy 338.534202 -408.945831) (xy 338.572148 -409.00142) (xy 338.603178 -409.061145)
			(xy 338.626848 -409.124151) (xy 338.642819 -409.189534) (xy 338.650862 -409.256356) (xy 338.650861 -409.323662)
			(xy 338.642816 -409.390484) (xy 338.626843 -409.455867) (xy 338.603171 -409.518871) (xy 338.600596 -409.523827)
			(xy 339.729261 -409.523827) (xy 339.729264 -409.456519) (xy 339.737312 -409.389694) (xy 339.753289 -409.324309)
			(xy 339.776966 -409.261303) (xy 339.808004 -409.201579) (xy 339.845958 -409.145992) (xy 339.867748 -409.12034)
			(xy 339.873559 -409.113205) (xy 339.880064 -409.096006) (xy 339.880448 -409.086812) (xy 339.880448 -408.593544)
			(xy 339.880006 -408.58436) (xy 339.873513 -408.567176) (xy 339.867748 -408.560016) (xy 339.845952 -408.534371)
			(xy 339.808003 -408.478783) (xy 339.776969 -408.419059) (xy 339.753297 -408.356054) (xy 339.737324 -408.29067)
			(xy 339.72928 -408.223847) (xy 339.729281 -408.156541) (xy 339.737326 -408.089718) (xy 339.7533 -408.024335)
			(xy 339.776974 -407.96133) (xy 339.808009 -407.901606) (xy 339.845959 -407.84602) (xy 339.867748 -407.820368)
			(xy 339.873547 -407.813224) (xy 339.880059 -407.796032) (xy 339.880448 -407.78684) (xy 339.880448 -407.628852)
			(xy 339.880881 -407.618701) (xy 339.888683 -407.599958) (xy 339.903075 -407.585638) (xy 339.921857 -407.577931)
			(xy 339.93201 -407.577544) (xy 340.64829 -407.577544) (xy 340.658417 -407.578035) (xy 340.677138 -407.58576)
			(xy 340.691495 -407.600045) (xy 340.699314 -407.618728) (xy 340.699852 -407.628852) (xy 340.699852 -407.78684)
			(xy 340.700254 -407.796028) (xy 340.706775 -407.813211) (xy 340.712552 -407.820368) (xy 340.734332 -407.846027)
			(xy 340.772282 -407.901612) (xy 340.803316 -407.961335) (xy 340.826989 -408.024338) (xy 340.842963 -408.08972)
			(xy 340.851008 -408.156542) (xy 340.851009 -408.223846) (xy 340.842965 -408.290668) (xy 340.826993 -408.35605)
			(xy 340.803321 -408.419054) (xy 340.772288 -408.478778) (xy 340.734339 -408.534364) (xy 340.712552 -408.560016)
			(xy 340.70676 -408.567164) (xy 340.700244 -408.584353) (xy 340.699852 -408.593544) (xy 340.699852 -409.086812)
			(xy 340.700267 -409.095998) (xy 340.706779 -409.113182) (xy 340.712552 -409.12034) (xy 340.734304 -409.146021)
			(xy 340.772255 -409.201603) (xy 340.80329 -409.261323) (xy 340.826965 -409.324323) (xy 340.842941 -409.389702)
			(xy 340.850988 -409.456522) (xy 340.850992 -409.523824) (xy 340.842951 -409.590644) (xy 340.826981 -409.656025)
			(xy 340.803312 -409.719028) (xy 340.772283 -409.77875) (xy 340.734338 -409.834336) (xy 340.712552 -409.859988)
			(xy 340.70673 -409.867115) (xy 340.700232 -409.88432) (xy 340.699852 -409.893516) (xy 340.699852 -410.051504)
			(xy 340.699383 -410.061652) (xy 340.691595 -410.080394) (xy 340.677214 -410.094716) (xy 340.65844 -410.102424)
			(xy 340.64829 -410.102812) (xy 339.93201 -410.102812) (xy 339.92189 -410.102267) (xy 339.903179 -410.094552)
			(xy 339.888824 -410.080284) (xy 339.880996 -410.061621) (xy 339.880448 -410.051504) (xy 339.880448 -409.893516)
			(xy 339.88002 -409.884331) (xy 339.873517 -409.867147) (xy 339.867748 -409.859988) (xy 339.845924 -409.834365)
			(xy 339.807976 -409.778775) (xy 339.776944 -409.719047) (xy 339.753273 -409.656039) (xy 339.737302 -409.590653)
			(xy 339.729261 -409.523827) (xy 338.600596 -409.523827) (xy 338.572139 -409.578596) (xy 338.534191 -409.634183)
			(xy 338.512404 -409.659836) (xy 338.50661 -409.666983) (xy 338.500094 -409.684172) (xy 338.499704 -409.693364)
			(xy 338.499704 -410.186632) (xy 338.500098 -410.195821) (xy 338.506623 -410.213005) (xy 338.512404 -410.22016)
			(xy 338.534175 -410.245826) (xy 338.572121 -410.301411) (xy 338.603153 -410.361133) (xy 338.626825 -410.424136)
			(xy 338.642797 -410.489516) (xy 338.650842 -410.556336) (xy 338.650844 -410.623639) (xy 338.650837 -410.6237)
			(xy 341.928907 -410.6237) (xy 341.928908 -410.556276) (xy 341.936986 -410.489336) (xy 341.953023 -410.423846)
			(xy 341.976789 -410.360749) (xy 342.007941 -410.300952) (xy 342.046031 -410.245317) (xy 342.067896 -410.219652)
			(xy 342.073695 -410.212508) (xy 342.080208 -410.195317) (xy 342.080596 -410.186124) (xy 342.080596 -409.693872)
			(xy 342.0802 -409.684683) (xy 342.073677 -409.667499) (xy 342.067896 -409.660344) (xy 342.046044 -409.634669)
			(xy 342.007955 -409.579036) (xy 341.976804 -409.519241) (xy 341.953039 -409.456145) (xy 341.937003 -409.390657)
			(xy 341.928927 -409.32372) (xy 341.928925 -409.256298) (xy 341.937 -409.18936) (xy 341.953034 -409.123872)
			(xy 341.976797 -409.060776) (xy 342.007946 -409.00098) (xy 342.046033 -408.945345) (xy 342.067896 -408.91968)
			(xy 342.073683 -408.912528) (xy 342.080204 -408.895343) (xy 342.080596 -408.886152) (xy 342.080596 -408.728672)
			(xy 342.081062 -408.718562) (xy 342.088808 -408.699884) (xy 342.103111 -408.68559) (xy 342.121794 -408.677856)
			(xy 342.131904 -408.677364) (xy 342.848184 -408.677364) (xy 342.858287 -408.677897) (xy 342.876958 -408.685623)
			(xy 342.891252 -408.699905) (xy 342.898994 -408.718569) (xy 342.899492 -408.728672) (xy 342.899492 -408.886152)
			(xy 342.899927 -408.895337) (xy 342.906424 -408.912521) (xy 342.912192 -408.91968) (xy 342.934068 -408.945335)
			(xy 342.972157 -409.000971) (xy 343.003308 -409.060769) (xy 343.027071 -409.123867) (xy 343.043106 -409.189357)
			(xy 343.051181 -409.256297) (xy 343.05118 -409.323721) (xy 343.043103 -409.390661) (xy 343.027066 -409.45615)
			(xy 343.0033 -409.519248) (xy 343.000914 -409.523827) (xy 344.129052 -409.523827) (xy 344.129055 -409.456519)
			(xy 344.137102 -409.389694) (xy 344.153079 -409.32431) (xy 344.176756 -409.261304) (xy 344.207793 -409.201579)
			(xy 344.245746 -409.145992) (xy 344.267536 -409.12034) (xy 344.273345 -409.113204) (xy 344.279851 -409.096006)
			(xy 344.280236 -409.086812) (xy 344.280236 -408.593544) (xy 344.279796 -408.58436) (xy 344.273302 -408.567176)
			(xy 344.267536 -408.560016) (xy 344.24574 -408.53437) (xy 344.207792 -408.478783) (xy 344.176759 -408.419058)
			(xy 344.153087 -408.356053) (xy 344.137115 -408.29067) (xy 344.129071 -408.223847) (xy 344.129072 -408.156541)
			(xy 344.137117 -408.089718) (xy 344.153091 -408.024335) (xy 344.176764 -407.961331) (xy 344.207798 -407.901607)
			(xy 344.245748 -407.84602) (xy 344.267536 -407.820368) (xy 344.273333 -407.813223) (xy 344.279847 -407.796032)
			(xy 344.280236 -407.78684) (xy 344.280236 -407.628852) (xy 344.280583 -407.61869) (xy 344.288401 -407.59993)
			(xy 344.302821 -407.585607) (xy 344.321634 -407.577916) (xy 344.331798 -407.577544) (xy 345.048078 -407.577544)
			(xy 345.058204 -407.578045) (xy 345.076925 -407.585766) (xy 345.091283 -407.600048) (xy 345.099102 -407.618729)
			(xy 345.09964 -407.628852) (xy 345.09964 -407.78684) (xy 345.100044 -407.796028) (xy 345.106563 -407.813211)
			(xy 345.11234 -407.820368) (xy 345.13412 -407.846026) (xy 345.172071 -407.901611) (xy 345.203106 -407.961334)
			(xy 345.22678 -408.024338) (xy 345.242754 -408.089719) (xy 345.250799 -408.156542) (xy 345.2508 -408.223846)
			(xy 345.242756 -408.290669) (xy 345.226783 -408.356051) (xy 345.20311 -408.419055) (xy 345.172077 -408.478778)
			(xy 345.134128 -408.534364) (xy 345.11234 -408.560016) (xy 345.106547 -408.567163) (xy 345.100032 -408.584352)
			(xy 345.09964 -408.593544) (xy 345.09964 -409.086812) (xy 345.100058 -409.095998) (xy 345.106568 -409.113182)
			(xy 345.11234 -409.12034) (xy 345.134093 -409.146021) (xy 345.172044 -409.201603) (xy 345.20308 -409.261322)
			(xy 345.226756 -409.324323) (xy 345.242732 -409.389702) (xy 345.250779 -409.456522) (xy 345.250783 -409.523824)
			(xy 345.242742 -409.590645) (xy 345.226772 -409.656025) (xy 345.203102 -409.719028) (xy 345.172072 -409.778751)
			(xy 345.134126 -409.834336) (xy 345.11234 -409.859988) (xy 345.106516 -409.867114) (xy 345.100019 -409.884319)
			(xy 345.09964 -409.893516) (xy 345.09964 -410.051504) (xy 345.099182 -410.061653) (xy 345.091393 -410.080398)
			(xy 345.077008 -410.09472) (xy 345.058229 -410.102427) (xy 345.048078 -410.102812) (xy 344.331798 -410.102812)
			(xy 344.321678 -410.102277) (xy 344.302966 -410.094558) (xy 344.288612 -410.080287) (xy 344.280784 -410.061621)
			(xy 344.280236 -410.051504) (xy 344.280236 -409.893516) (xy 344.27981 -409.884331) (xy 344.273307 -409.867146)
			(xy 344.267536 -409.859988) (xy 344.245713 -409.834365) (xy 344.207765 -409.778774) (xy 344.176734 -409.719047)
			(xy 344.153063 -409.656038) (xy 344.137093 -409.590653) (xy 344.129052 -409.523827) (xy 343.000914 -409.523827)
			(xy 342.972148 -409.579044) (xy 342.934057 -409.634679) (xy 342.912192 -409.660344) (xy 342.906393 -409.667488)
			(xy 342.89988 -409.684679) (xy 342.899492 -409.693872) (xy 342.899492 -410.186124) (xy 342.899892 -410.195312)
			(xy 342.906413 -410.212496) (xy 342.912192 -410.219652) (xy 342.934041 -410.24533) (xy 342.97213 -410.300963)
			(xy 343.003282 -410.360757) (xy 343.027048 -410.423852) (xy 343.043084 -410.48934) (xy 343.051162 -410.556277)
			(xy 343.051163 -410.623642) (xy 346.329202 -410.623642) (xy 346.329204 -410.556334) (xy 346.33725 -410.48951)
			(xy 346.353226 -410.424126) (xy 346.376903 -410.361121) (xy 346.40794 -410.301397) (xy 346.445894 -410.245812)
			(xy 346.467684 -410.22016) (xy 346.473478 -410.213013) (xy 346.479995 -410.195824) (xy 346.480384 -410.186632)
			(xy 346.480384 -409.693364) (xy 346.479995 -409.684175) (xy 346.473467 -409.66699) (xy 346.467684 -409.659836)
			(xy 346.445907 -409.634175) (xy 346.407955 -409.578591) (xy 346.376918 -409.518869) (xy 346.353243 -409.455865)
			(xy 346.337268 -409.390484) (xy 346.329222 -409.323661) (xy 346.329221 -409.256357) (xy 346.337265 -409.189534)
			(xy 346.353238 -409.124152) (xy 346.376911 -409.061148) (xy 346.407945 -409.001425) (xy 346.445896 -408.94584)
			(xy 346.467684 -408.920188) (xy 346.473466 -408.913033) (xy 346.47999 -408.89585) (xy 346.480384 -408.88666)
			(xy 346.480384 -408.728672) (xy 346.480798 -408.718518) (xy 346.4886 -408.699768) (xy 346.502999 -408.685446)
			(xy 346.52179 -408.677745) (xy 346.531946 -408.677364) (xy 347.248226 -408.677364) (xy 347.258357 -408.677806)
			(xy 347.277084 -408.685547) (xy 347.29144 -408.699847) (xy 347.299254 -408.718543) (xy 347.299788 -408.728672)
			(xy 347.299788 -408.88666) (xy 347.30022 -408.895845) (xy 347.306719 -408.913029) (xy 347.312488 -408.920188)
			(xy 347.334287 -408.945831) (xy 347.372233 -409.001419) (xy 347.403265 -409.061144) (xy 347.426936 -409.12415)
			(xy 347.442907 -409.189533) (xy 347.45095 -409.256356) (xy 347.450949 -409.323662) (xy 347.442904 -409.390485)
			(xy 347.42693 -409.455867) (xy 347.403257 -409.518872) (xy 347.400682 -409.523827) (xy 374.929082 -409.523827)
			(xy 374.929085 -409.456519) (xy 374.937133 -409.389693) (xy 374.953111 -409.324308) (xy 374.97679 -409.261302)
			(xy 375.007829 -409.201578) (xy 375.045785 -409.145991) (xy 375.067576 -409.12034) (xy 375.073378 -409.113198)
			(xy 375.07989 -409.096005) (xy 375.080276 -409.086812) (xy 375.080276 -408.593544) (xy 375.07985 -408.584358)
			(xy 375.073348 -408.567174) (xy 375.067576 -408.560016) (xy 375.045779 -408.534371) (xy 375.007828 -408.478784)
			(xy 374.976793 -408.41906) (xy 374.953119 -408.356055) (xy 374.937146 -408.290671) (xy 374.929102 -408.223847)
			(xy 374.929103 -408.156541) (xy 374.937148 -408.089717) (xy 374.953123 -408.024334) (xy 374.976798 -407.961329)
			(xy 375.007835 -407.901605) (xy 375.045787 -407.84602) (xy 375.067576 -407.820368) (xy 375.073366 -407.813218)
			(xy 375.079885 -407.796031) (xy 375.080276 -407.78684) (xy 375.080276 -407.628852) (xy 375.080682 -407.618698)
			(xy 375.088489 -407.599949) (xy 375.10289 -407.585628) (xy 375.121682 -407.577926) (xy 375.131838 -407.577544)
			(xy 375.848118 -407.577544) (xy 375.858246 -407.578012) (xy 375.876969 -407.585746) (xy 375.891325 -407.600038)
			(xy 375.899143 -407.618726) (xy 375.89968 -407.628852) (xy 375.89968 -407.78684) (xy 375.900075 -407.796029)
			(xy 375.9066 -407.813213) (xy 375.91238 -407.820368) (xy 375.934159 -407.846027) (xy 375.972107 -407.901613)
			(xy 376.00314 -407.961336) (xy 376.026812 -408.024339) (xy 376.042785 -408.08972) (xy 376.05083 -408.156542)
			(xy 376.05083 -408.223846) (xy 376.042787 -408.290668) (xy 376.026816 -408.356049) (xy 376.003145 -408.419053)
			(xy 375.972113 -408.478777) (xy 375.934167 -408.534364) (xy 375.91238 -408.560016) (xy 375.906592 -408.567167)
			(xy 375.900073 -408.584353) (xy 375.89968 -408.593544) (xy 375.89968 -409.086812) (xy 375.900089 -409.095999)
			(xy 375.906604 -409.113183) (xy 375.91238 -409.12034) (xy 375.934131 -409.146022) (xy 375.97208 -409.201604)
			(xy 376.003114 -409.261324) (xy 376.026788 -409.324325) (xy 376.042763 -409.389703) (xy 376.050809 -409.456522)
			(xy 376.050813 -409.523824) (xy 376.042772 -409.590644) (xy 376.026804 -409.656024) (xy 376.003136 -409.719026)
			(xy 375.972108 -409.778749) (xy 375.934165 -409.834335) (xy 375.91238 -409.859988) (xy 375.906561 -409.867117)
			(xy 375.90006 -409.88432) (xy 375.89968 -409.893516) (xy 375.89968 -410.051504) (xy 375.899281 -410.061661)
			(xy 375.891481 -410.080417) (xy 375.877077 -410.094741) (xy 375.858277 -410.102437) (xy 375.848118 -410.102812)
			(xy 375.131838 -410.102812) (xy 375.12172 -410.102244) (xy 375.10301 -410.094538) (xy 375.088654 -410.080277)
			(xy 375.080824 -410.061618) (xy 375.080276 -410.051504) (xy 375.080276 -409.893516) (xy 375.079864 -409.884329)
			(xy 375.073352 -409.867144) (xy 375.067576 -409.859988) (xy 375.045751 -409.834366) (xy 375.007801 -409.778776)
			(xy 374.976768 -409.719048) (xy 374.953095 -409.65604) (xy 374.937124 -409.590654) (xy 374.929082 -409.523827)
			(xy 347.400682 -409.523827) (xy 347.372224 -409.578596) (xy 347.334276 -409.634184) (xy 347.312488 -409.659836)
			(xy 347.306692 -409.666982) (xy 347.300177 -409.684172) (xy 347.299788 -409.693364) (xy 347.299788 -410.186632)
			(xy 347.300185 -410.195821) (xy 347.306708 -410.213005) (xy 347.312488 -410.22016) (xy 347.334259 -410.245825)
			(xy 347.372207 -410.301411) (xy 347.403239 -410.361133) (xy 347.426912 -410.424135) (xy 347.442885 -410.489516)
			(xy 347.45093 -410.556336) (xy 347.450931 -410.62364) (xy 347.450924 -410.623701) (xy 377.128728 -410.623701)
			(xy 377.128729 -410.556275) (xy 377.136807 -410.489335) (xy 377.152845 -410.423845) (xy 377.176612 -410.360748)
			(xy 377.207766 -410.300951) (xy 377.245858 -410.245317) (xy 377.267724 -410.219652) (xy 377.273526 -410.212511)
			(xy 377.280037 -410.195317) (xy 377.280424 -410.186124) (xy 377.280424 -409.693872) (xy 377.280022 -409.684684)
			(xy 377.273502 -409.6675) (xy 377.267724 -409.660344) (xy 377.245871 -409.634669) (xy 377.20778 -409.579037)
			(xy 377.176628 -409.519242) (xy 377.152862 -409.456146) (xy 377.136825 -409.390658) (xy 377.128748 -409.323721)
			(xy 377.128747 -409.256297) (xy 377.136822 -409.18936) (xy 377.152857 -409.123871) (xy 377.17662 -409.060774)
			(xy 377.207771 -409.000979) (xy 377.24586 -408.945345) (xy 377.267724 -408.91968) (xy 377.273514 -408.912531)
			(xy 377.280032 -408.895343) (xy 377.280424 -408.886152) (xy 377.280424 -408.728672) (xy 377.280794 -408.718545)
			(xy 377.288555 -408.699836) (xy 377.302886 -408.685522) (xy 377.321604 -408.677782) (xy 377.331732 -408.677364)
			(xy 378.048012 -408.677364) (xy 378.058117 -408.677875) (xy 378.076789 -408.685609) (xy 378.091082 -408.699898)
			(xy 378.098822 -408.718567) (xy 378.09932 -408.728672) (xy 378.09932 -408.886152) (xy 378.099749 -408.895337)
			(xy 378.106249 -408.912522) (xy 378.11202 -408.91968) (xy 378.133895 -408.945336) (xy 378.171982 -409.000972)
			(xy 378.203131 -409.06077) (xy 378.226894 -409.123868) (xy 378.242928 -409.189358) (xy 378.251002 -409.256297)
			(xy 378.251001 -409.323721) (xy 378.242925 -409.39066) (xy 378.226888 -409.456149) (xy 378.203124 -409.519247)
			(xy 378.200707 -409.523886) (xy 379.328875 -409.523886) (xy 379.328878 -409.45646) (xy 379.336957 -409.38952)
			(xy 379.352995 -409.324029) (xy 379.376762 -409.260931) (xy 379.407916 -409.201133) (xy 379.446007 -409.145498)
			(xy 379.467872 -409.119832) (xy 379.473689 -409.112701) (xy 379.480189 -409.095499) (xy 379.480572 -409.086304)
			(xy 379.480572 -408.594052) (xy 379.480143 -408.584867) (xy 379.473643 -408.567682) (xy 379.467872 -408.560524)
			(xy 379.446001 -408.534865) (xy 379.407915 -408.479229) (xy 379.376766 -408.419431) (xy 379.353003 -408.356334)
			(xy 379.336969 -408.290844) (xy 379.328894 -408.223906) (xy 379.328895 -408.156482) (xy 379.336971 -408.089544)
			(xy 379.353007 -408.024055) (xy 379.376771 -407.960958) (xy 379.407921 -407.901161) (xy 379.446009 -407.845526)
			(xy 379.467872 -407.81986) (xy 379.473677 -407.812721) (xy 379.480185 -407.795525) (xy 379.480572 -407.786332)
			(xy 379.480572 -407.628852) (xy 379.481045 -407.618744) (xy 379.488793 -407.60007) (xy 379.503093 -407.585778)
			(xy 379.521771 -407.57804) (xy 379.53188 -407.577544) (xy 380.24816 -407.577544) (xy 380.258259 -407.578117)
			(xy 380.276926 -407.585831) (xy 380.29122 -407.6001) (xy 380.298966 -407.618754) (xy 380.299468 -407.628852)
			(xy 380.299468 -407.786332) (xy 380.29987 -407.79552) (xy 380.30639 -407.812704) (xy 380.312168 -407.81986)
			(xy 380.334025 -407.845531) (xy 380.372116 -407.901164) (xy 380.403269 -407.960959) (xy 380.427035 -408.024055)
			(xy 380.443072 -408.089544) (xy 380.451149 -408.156482) (xy 380.45115 -408.223906) (xy 380.443074 -408.290844)
			(xy 380.427039 -408.356333) (xy 380.403274 -408.41943) (xy 380.372122 -408.479226) (xy 380.334033 -408.534859)
			(xy 380.312168 -408.560524) (xy 380.306375 -408.567671) (xy 380.299859 -408.58486) (xy 380.299468 -408.594052)
			(xy 380.299468 -409.086304) (xy 380.299883 -409.09549) (xy 380.306394 -409.112675) (xy 380.312168 -409.119832)
			(xy 380.333998 -409.145526) (xy 380.37209 -409.201156) (xy 380.403244 -409.260947) (xy 380.427011 -409.324041)
			(xy 380.44305 -409.389527) (xy 380.451129 -409.456462) (xy 380.451133 -409.523884) (xy 380.44306 -409.59082)
			(xy 380.427027 -409.656308) (xy 380.403266 -409.719403) (xy 380.372117 -409.779198) (xy 380.334031 -409.834831)
			(xy 380.312168 -409.860496) (xy 380.306386 -409.867652) (xy 380.299864 -409.884834) (xy 380.299468 -409.894024)
			(xy 380.299468 -410.051504) (xy 380.299086 -410.061631) (xy 380.291331 -410.08034) (xy 380.277003 -410.094656)
			(xy 380.258287 -410.102395) (xy 380.24816 -410.102812) (xy 379.53188 -410.102812) (xy 379.521771 -410.102332)
			(xy 379.503095 -410.09459) (xy 379.488801 -410.080292) (xy 379.481065 -410.061613) (xy 379.480572 -410.051504)
			(xy 379.480572 -409.894024) (xy 379.480157 -409.884837) (xy 379.473647 -409.867652) (xy 379.467872 -409.860496)
			(xy 379.445974 -409.834859) (xy 379.407888 -409.77922) (xy 379.37674 -409.71942) (xy 379.352979 -409.656319)
			(xy 379.336947 -409.590827) (xy 379.328875 -409.523886) (xy 378.200707 -409.523886) (xy 378.171973 -409.579043)
			(xy 378.133884 -409.634678) (xy 378.11202 -409.660344) (xy 378.106225 -409.66749) (xy 378.099709 -409.68468)
			(xy 378.09932 -409.693872) (xy 378.09932 -410.186124) (xy 378.099714 -410.195313) (xy 378.106239 -410.212497)
			(xy 378.11202 -410.219652) (xy 378.133868 -410.245331) (xy 378.171955 -410.300964) (xy 378.203106 -410.360758)
			(xy 378.22687 -410.423853) (xy 378.242906 -410.48934) (xy 378.250983 -410.556277) (xy 378.250984 -410.623641)
			(xy 381.529047 -410.623641) (xy 381.529049 -410.556335) (xy 381.537094 -410.489512) (xy 381.553068 -410.424129)
			(xy 381.576742 -410.361124) (xy 381.607775 -410.3014) (xy 381.645724 -410.245812) (xy 381.667512 -410.22016)
			(xy 381.673309 -410.213015) (xy 381.679823 -410.195824) (xy 381.680212 -410.186632) (xy 381.680212 -409.693364)
			(xy 381.679817 -409.684175) (xy 381.673292 -409.666991) (xy 381.667512 -409.659836) (xy 381.645737 -409.634174)
			(xy 381.607789 -409.578588) (xy 381.576757 -409.518866) (xy 381.553085 -409.455863) (xy 381.537112 -409.390482)
			(xy 381.529067 -409.323661) (xy 381.529066 -409.256357) (xy 381.537109 -409.189536) (xy 381.553079 -409.124155)
			(xy 381.57675 -409.061151) (xy 381.60778 -409.001427) (xy 381.645726 -408.94584) (xy 381.667512 -408.920188)
			(xy 381.673298 -408.913035) (xy 381.679818 -408.89585) (xy 381.680212 -408.88666) (xy 381.680212 -408.728672)
			(xy 381.680662 -408.71856) (xy 381.688411 -408.699879) (xy 381.702719 -408.685585) (xy 381.721408 -408.677853)
			(xy 381.73152 -408.677364) (xy 382.448054 -408.677364) (xy 382.458181 -408.677865) (xy 382.476905 -408.685582)
			(xy 382.491264 -408.699865) (xy 382.499081 -408.718548) (xy 382.499616 -408.728672) (xy 382.499616 -408.88666)
			(xy 382.500042 -408.895846) (xy 382.506544 -408.91303) (xy 382.512316 -408.920188) (xy 382.534117 -408.94583)
			(xy 382.572068 -409.001417) (xy 382.603103 -409.061141) (xy 382.626778 -409.124147) (xy 382.642751 -409.189531)
			(xy 382.650795 -409.256356) (xy 382.650794 -409.323662) (xy 382.642748 -409.390487) (xy 382.626772 -409.45587)
			(xy 382.603096 -409.518875) (xy 382.600523 -409.523827) (xy 383.72917 -409.523827) (xy 383.729173 -409.456519)
			(xy 383.737221 -409.389693) (xy 383.753198 -409.324309) (xy 383.776876 -409.261303) (xy 383.807915 -409.201578)
			(xy 383.845869 -409.145992) (xy 383.86766 -409.12034) (xy 383.873472 -409.113206) (xy 383.879976 -409.096007)
			(xy 383.88036 -409.086812) (xy 383.88036 -408.593544) (xy 383.879915 -408.584361) (xy 383.873424 -408.567177)
			(xy 383.86766 -408.560016) (xy 383.845864 -408.53437) (xy 383.807914 -408.478784) (xy 383.77688 -408.419059)
			(xy 383.753207 -408.356054) (xy 383.737234 -408.290671) (xy 383.72919 -408.223847) (xy 383.729191 -408.156541)
			(xy 383.737236 -408.089717) (xy 383.75321 -408.024335) (xy 383.776885 -407.96133) (xy 383.80792 -407.901606)
			(xy 383.845871 -407.84602) (xy 383.86766 -407.820368) (xy 383.87346 -407.813226) (xy 383.879971 -407.796033)
			(xy 383.88036 -407.78684) (xy 383.88036 -407.628852) (xy 383.880845 -407.618745) (xy 383.888591 -407.600074)
			(xy 383.902887 -407.585782) (xy 383.921561 -407.578042) (xy 383.931668 -407.577544) (xy 384.648202 -407.577544)
			(xy 384.658329 -407.578025) (xy 384.677051 -407.585754) (xy 384.691408 -407.600042) (xy 384.699226 -407.618727)
			(xy 384.699764 -407.628852) (xy 384.699764 -407.78684) (xy 384.700163 -407.796028) (xy 384.706685 -407.813212)
			(xy 384.712464 -407.820368) (xy 384.734244 -407.846027) (xy 384.772193 -407.901612) (xy 384.803226 -407.961335)
			(xy 384.826899 -408.024339) (xy 384.842873 -408.08972) (xy 384.850918 -408.156542) (xy 384.850918 -408.223846)
			(xy 384.842875 -408.290668) (xy 384.826903 -408.35605) (xy 384.803231 -408.419054) (xy 384.772199 -408.478778)
			(xy 384.734251 -408.534364) (xy 384.712464 -408.560016) (xy 384.706674 -408.567165) (xy 384.700156 -408.584353)
			(xy 384.699764 -408.593544) (xy 384.699764 -409.086812) (xy 384.700176 -409.095999) (xy 384.706689 -409.113183)
			(xy 384.712464 -409.12034) (xy 384.734216 -409.146021) (xy 384.772166 -409.201604) (xy 384.8032 -409.261323)
			(xy 384.826875 -409.324324) (xy 384.84285 -409.389703) (xy 384.850897 -409.456522) (xy 384.850901 -409.523824)
			(xy 384.84286 -409.590644) (xy 384.826891 -409.656024) (xy 384.803222 -409.719027) (xy 384.772194 -409.77875)
			(xy 384.734249 -409.834336) (xy 384.712464 -409.859988) (xy 384.706643 -409.867116) (xy 384.700144 -409.88432)
			(xy 384.699764 -409.893516) (xy 384.699764 -410.051504) (xy 384.699386 -410.061631) (xy 384.69163 -410.080342)
			(xy 384.677301 -410.094657) (xy 384.658584 -410.102396) (xy 384.648456 -410.102812) (xy 383.931922 -410.102812)
			(xy 383.921803 -410.102257) (xy 383.903092 -410.094546) (xy 383.888737 -410.080281) (xy 383.880908 -410.06162)
			(xy 383.88036 -410.051504) (xy 383.88036 -409.893516) (xy 383.879929 -409.884331) (xy 383.873428 -409.867147)
			(xy 383.86766 -409.859988) (xy 383.845836 -409.834365) (xy 383.807887 -409.778775) (xy 383.776854 -409.719048)
			(xy 383.753182 -409.656039) (xy 383.737211 -409.590653) (xy 383.72917 -409.523827) (xy 382.600523 -409.523827)
			(xy 382.572059 -409.578599) (xy 382.534106 -409.634184) (xy 382.512316 -409.659836) (xy 382.506523 -409.666984)
			(xy 382.500006 -409.684172) (xy 382.499616 -409.693364) (xy 382.499616 -410.186632) (xy 382.500007 -410.195821)
			(xy 382.506534 -410.213006) (xy 382.512316 -410.22016) (xy 382.534089 -410.245824) (xy 382.572042 -410.301408)
			(xy 382.603078 -410.36113) (xy 382.626754 -410.424133) (xy 382.642729 -410.489514) (xy 382.650775 -410.556336)
			(xy 382.650777 -410.62364) (xy 382.65077 -410.623701) (xy 385.928816 -410.623701) (xy 385.928817 -410.556275)
			(xy 385.936895 -410.489336) (xy 385.952932 -410.423846) (xy 385.976699 -410.360748) (xy 386.007852 -410.300952)
			(xy 386.045943 -410.245317) (xy 386.067808 -410.219652) (xy 386.073608 -410.21251) (xy 386.080121 -410.195317)
			(xy 386.080508 -410.186124) (xy 386.080508 -409.693872) (xy 386.08011 -409.684684) (xy 386.073588 -409.667499)
			(xy 386.067808 -409.660344) (xy 386.045956 -409.634669) (xy 386.007866 -409.579036) (xy 385.976714 -409.519241)
			(xy 385.952949 -409.456146) (xy 385.936913 -409.390658) (xy 385.928836 -409.32372) (xy 385.928834 -409.256298)
			(xy 385.936909 -409.18936) (xy 385.952944 -409.123871) (xy 385.976707 -409.060775) (xy 386.007857 -409.000979)
			(xy 386.045944 -408.945345) (xy 386.067808 -408.91968) (xy 386.073596 -408.912529) (xy 386.080116 -408.895343)
			(xy 386.080508 -408.886152) (xy 386.080508 -408.728672) (xy 386.080962 -408.71856) (xy 386.088711 -408.69988)
			(xy 386.103017 -408.685586) (xy 386.121704 -408.677854) (xy 386.131816 -408.677364) (xy 386.848096 -408.677364)
			(xy 386.8582 -408.677888) (xy 386.876871 -408.685617) (xy 386.891165 -408.699902) (xy 386.898906 -408.718568)
			(xy 386.899404 -408.728672) (xy 386.899404 -408.886152) (xy 386.899836 -408.895337) (xy 386.906334 -408.912522)
			(xy 386.912104 -408.91968) (xy 386.93398 -408.945336) (xy 386.972068 -409.000972) (xy 387.003218 -409.060769)
			(xy 387.026981 -409.123867) (xy 387.043016 -409.189357) (xy 387.05109 -409.256297) (xy 387.051089 -409.323721)
			(xy 387.043012 -409.39066) (xy 387.026976 -409.45615) (xy 387.00321 -409.519247) (xy 387.000824 -409.523827)
			(xy 388.128961 -409.523827) (xy 388.128964 -409.456519) (xy 388.137012 -409.389694) (xy 388.152989 -409.324309)
			(xy 388.176666 -409.261303) (xy 388.207704 -409.201579) (xy 388.245658 -409.145992) (xy 388.267448 -409.12034)
			(xy 388.273259 -409.113205) (xy 388.279764 -409.096006) (xy 388.280148 -409.086812) (xy 388.280148 -408.593544)
			(xy 388.279706 -408.58436) (xy 388.273213 -408.567176) (xy 388.267448 -408.560016) (xy 388.245652 -408.534371)
			(xy 388.207703 -408.478783) (xy 388.176669 -408.419059) (xy 388.152997 -408.356054) (xy 388.137024 -408.29067)
			(xy 388.12898 -408.223847) (xy 388.128981 -408.156541) (xy 388.137026 -408.089718) (xy 388.153 -408.024335)
			(xy 388.176674 -407.96133) (xy 388.207709 -407.901606) (xy 388.245659 -407.84602) (xy 388.267448 -407.820368)
			(xy 388.273247 -407.813224) (xy 388.279759 -407.796032) (xy 388.280148 -407.78684) (xy 388.280148 -407.628852)
			(xy 388.280645 -407.618747) (xy 388.288388 -407.600077) (xy 388.302681 -407.585786) (xy 388.321351 -407.578044)
			(xy 388.331456 -407.577544) (xy 389.04799 -407.577544) (xy 389.058117 -407.578035) (xy 389.076838 -407.58576)
			(xy 389.091195 -407.600045) (xy 389.099014 -407.618728) (xy 389.099552 -407.628852) (xy 389.099552 -407.78684)
			(xy 389.099954 -407.796028) (xy 389.106475 -407.813211) (xy 389.112252 -407.820368) (xy 389.134032 -407.846027)
			(xy 389.171982 -407.901612) (xy 389.203016 -407.961335) (xy 389.226689 -408.024338) (xy 389.242663 -408.08972)
			(xy 389.250708 -408.156542) (xy 389.250709 -408.223846) (xy 389.242665 -408.290668) (xy 389.226693 -408.35605)
			(xy 389.203021 -408.419054) (xy 389.171988 -408.478778) (xy 389.134039 -408.534364) (xy 389.112252 -408.560016)
			(xy 389.10646 -408.567164) (xy 389.099944 -408.584353) (xy 389.099552 -408.593544) (xy 389.099552 -409.086812)
			(xy 389.099967 -409.095998) (xy 389.106479 -409.113182) (xy 389.112252 -409.12034) (xy 389.134004 -409.146021)
			(xy 389.171955 -409.201603) (xy 389.20299 -409.261323) (xy 389.226665 -409.324323) (xy 389.242641 -409.389702)
			(xy 389.250688 -409.456522) (xy 389.250692 -409.523824) (xy 389.242651 -409.590644) (xy 389.226681 -409.656025)
			(xy 389.203012 -409.719028) (xy 389.171983 -409.77875) (xy 389.134038 -409.834336) (xy 389.112252 -409.859988)
			(xy 389.10643 -409.867115) (xy 389.099932 -409.88432) (xy 389.099552 -409.893516) (xy 389.099552 -410.051504)
			(xy 389.099019 -410.061607) (xy 389.09129 -410.080275) (xy 389.077008 -410.094568) (xy 389.058346 -410.102311)
			(xy 389.048244 -410.102812) (xy 388.33171 -410.102812) (xy 388.32159 -410.102267) (xy 388.302879 -410.094552)
			(xy 388.288524 -410.080284) (xy 388.280696 -410.061621) (xy 388.280148 -410.051504) (xy 388.280148 -409.893516)
			(xy 388.27972 -409.884331) (xy 388.273217 -409.867147) (xy 388.267448 -409.859988) (xy 388.245624 -409.834365)
			(xy 388.207676 -409.778775) (xy 388.176644 -409.719047) (xy 388.152973 -409.656039) (xy 388.137002 -409.590653)
			(xy 388.128961 -409.523827) (xy 387.000824 -409.523827) (xy 386.972058 -409.579044) (xy 386.933969 -409.634679)
			(xy 386.912104 -409.660344) (xy 386.906307 -409.667489) (xy 386.899792 -409.68468) (xy 386.899404 -409.693872)
			(xy 386.899404 -410.186124) (xy 386.899801 -410.195313) (xy 386.906324 -410.212497) (xy 386.912104 -410.219652)
			(xy 386.933952 -410.24533) (xy 386.972041 -410.300963) (xy 387.003192 -410.360757) (xy 387.026957 -410.423853)
			(xy 387.042994 -410.48934) (xy 387.051071 -410.556277) (xy 387.051072 -410.623641) (xy 390.329135 -410.623641)
			(xy 390.329137 -410.556335) (xy 390.337182 -410.489512) (xy 390.353155 -410.42413) (xy 390.376828 -410.361125)
			(xy 390.407861 -410.3014) (xy 390.445809 -410.245813) (xy 390.467596 -410.22016) (xy 390.473392 -410.213014)
			(xy 390.479907 -410.195824) (xy 390.480296 -410.186632) (xy 390.480296 -409.693364) (xy 390.479904 -409.684175)
			(xy 390.473378 -409.666991) (xy 390.467596 -409.659836) (xy 390.445821 -409.634174) (xy 390.407875 -409.578588)
			(xy 390.376844 -409.518865) (xy 390.353172 -409.455862) (xy 390.3372 -409.390481) (xy 390.329155 -409.323661)
			(xy 390.329154 -409.256357) (xy 390.337196 -409.189536) (xy 390.353167 -409.124155) (xy 390.376836 -409.061151)
			(xy 390.407866 -409.001428) (xy 390.44581 -408.945841) (xy 390.467596 -408.920188) (xy 390.47338 -408.913034)
			(xy 390.479902 -408.89585) (xy 390.480296 -408.88666) (xy 390.480296 -408.728672) (xy 390.480762 -408.718562)
			(xy 390.488508 -408.699884) (xy 390.502811 -408.68559) (xy 390.521494 -408.677856) (xy 390.531604 -408.677364)
			(xy 391.248138 -408.677364) (xy 391.25827 -408.677796) (xy 391.276997 -408.685541) (xy 391.291352 -408.699844)
			(xy 391.299166 -408.718542) (xy 391.2997 -408.728672) (xy 391.2997 -408.88666) (xy 391.300129 -408.895845)
			(xy 391.30663 -408.91303) (xy 391.3124 -408.920188) (xy 391.334198 -408.945831) (xy 391.372144 -409.00142)
			(xy 391.403175 -409.061145) (xy 391.426845 -409.12415) (xy 391.442816 -409.189533) (xy 391.450859 -409.256356)
			(xy 391.450858 -409.323662) (xy 391.442813 -409.390484) (xy 391.42684 -409.455867) (xy 391.403167 -409.518872)
			(xy 391.372135 -409.578596) (xy 391.334187 -409.634183) (xy 391.3124 -409.659836) (xy 391.306606 -409.666983)
			(xy 391.30009 -409.684172) (xy 391.2997 -409.693364) (xy 391.2997 -410.186632) (xy 391.300095 -410.195821)
			(xy 391.306619 -410.213005) (xy 391.3124 -410.22016) (xy 391.334171 -410.245826) (xy 391.372118 -410.301411)
			(xy 391.403149 -410.361133) (xy 391.426821 -410.424136) (xy 391.442794 -410.489516) (xy 391.450839 -410.556336)
			(xy 391.450841 -410.623639) (xy 391.442799 -410.69046) (xy 391.426828 -410.755841) (xy 391.403159 -410.818845)
			(xy 391.37213 -410.878568) (xy 391.334186 -410.934155) (xy 391.3124 -410.959808) (xy 391.306618 -410.966963)
			(xy 391.300094 -410.984146) (xy 391.2997 -410.993336) (xy 391.2997 -411.151324) (xy 391.299235 -411.161434)
			(xy 391.291489 -411.180113) (xy 391.277186 -411.194407) (xy 391.258503 -411.202141) (xy 391.248392 -411.202632)
			(xy 390.531858 -411.202632) (xy 390.521725 -411.202207) (xy 390.502998 -411.19446) (xy 390.488642 -411.180155)
			(xy 390.480829 -411.161455) (xy 390.480296 -411.151324) (xy 390.480296 -410.993336) (xy 390.479869 -410.984151)
			(xy 390.473367 -410.966966) (xy 390.467596 -410.959808) (xy 390.445794 -410.934168) (xy 390.407848 -410.878579)
			(xy 390.376818 -410.818853) (xy 390.353148 -410.755847) (xy 390.337178 -410.690464) (xy 390.329135 -410.623641)
			(xy 387.051072 -410.623641) (xy 387.051072 -410.623699) (xy 387.042998 -410.690636) (xy 387.026964 -410.756124)
			(xy 387.003202 -410.819221) (xy 386.972053 -410.879016) (xy 386.933967 -410.934651) (xy 386.912104 -410.960316)
			(xy 386.906319 -410.967469) (xy 386.899797 -410.984654) (xy 386.899404 -410.993844) (xy 386.899404 -411.151324)
			(xy 386.898935 -411.161434) (xy 386.89119 -411.180112) (xy 386.876888 -411.194406) (xy 386.858206 -411.20214)
			(xy 386.848096 -411.202632) (xy 386.131816 -411.202632) (xy 386.121712 -411.202103) (xy 386.10304 -411.194376)
			(xy 386.088746 -411.180093) (xy 386.081005 -411.161427) (xy 386.080508 -411.151324) (xy 386.080508 -410.993844)
			(xy 386.080075 -410.984659) (xy 386.073577 -410.967475) (xy 386.067808 -410.960316) (xy 386.045928 -410.934664)
			(xy 386.007839 -410.879028) (xy 385.976689 -410.81923) (xy 385.952925 -410.756131) (xy 385.936891 -410.69064)
			(xy 385.928816 -410.623701) (xy 382.65077 -410.623701) (xy 382.642733 -410.690463) (xy 382.626761 -410.755844)
			(xy 382.603088 -410.818848) (xy 382.572054 -410.878571) (xy 382.534104 -410.934156) (xy 382.512316 -410.959808)
			(xy 382.506535 -410.966965) (xy 382.500011 -410.984146) (xy 382.499616 -410.993336) (xy 382.499616 -411.151324)
			(xy 382.499135 -411.161432) (xy 382.491392 -411.180108) (xy 382.477095 -411.194401) (xy 382.458416 -411.202138)
			(xy 382.448308 -411.202632) (xy 381.731774 -411.202632) (xy 381.721642 -411.202194) (xy 381.702915 -411.194453)
			(xy 381.688559 -411.180151) (xy 381.680745 -411.161454) (xy 381.680212 -411.151324) (xy 381.680212 -410.993336)
			(xy 381.679782 -410.984151) (xy 381.673282 -410.966967) (xy 381.667512 -410.959808) (xy 381.645709 -410.934168)
			(xy 381.607763 -410.87858) (xy 381.576732 -410.818854) (xy 381.553061 -410.755848) (xy 381.53709 -410.690464)
			(xy 381.529047 -410.623641) (xy 378.250984 -410.623641) (xy 378.250984 -410.623699) (xy 378.24291 -410.690636)
			(xy 378.226877 -410.756124) (xy 378.203116 -410.81922) (xy 378.171968 -410.879016) (xy 378.133882 -410.93465)
			(xy 378.11202 -410.960316) (xy 378.106236 -410.967471) (xy 378.099713 -410.984654) (xy 378.09932 -410.993844)
			(xy 378.09932 -411.151324) (xy 378.098835 -411.161432) (xy 378.091093 -411.180107) (xy 378.076797 -411.1944)
			(xy 378.05812 -411.202138) (xy 378.048012 -411.202632) (xy 377.331732 -411.202632) (xy 377.321615 -411.202159)
			(xy 377.302919 -411.194427) (xy 377.288604 -411.180128) (xy 377.280852 -411.16144) (xy 377.280424 -411.151324)
			(xy 377.280424 -410.993844) (xy 377.279987 -410.98466) (xy 377.273491 -410.967475) (xy 377.267724 -410.960316)
			(xy 377.245843 -410.934664) (xy 377.207754 -410.879028) (xy 377.176602 -410.81923) (xy 377.152838 -410.756132)
			(xy 377.136803 -410.690641) (xy 377.128728 -410.623701) (xy 347.450924 -410.623701) (xy 347.442889 -410.690461)
			(xy 347.426919 -410.755842) (xy 347.403249 -410.818845) (xy 347.372219 -410.878569) (xy 347.334274 -410.934156)
			(xy 347.312488 -410.959808) (xy 347.306704 -410.966962) (xy 347.300182 -410.984146) (xy 347.299788 -410.993336)
			(xy 347.299788 -411.151324) (xy 347.299398 -411.161481) (xy 347.291592 -411.180236) (xy 347.277186 -411.194559)
			(xy 347.258386 -411.202256) (xy 347.248226 -411.202632) (xy 346.531946 -411.202632) (xy 346.521819 -411.202135)
			(xy 346.503093 -411.194417) (xy 346.488735 -411.180133) (xy 346.480919 -411.161449) (xy 346.480384 -411.151324)
			(xy 346.480384 -410.993336) (xy 346.47996 -410.98415) (xy 346.473456 -410.966965) (xy 346.467684 -410.959808)
			(xy 346.445879 -410.934169) (xy 346.407928 -410.878582) (xy 346.376893 -410.818857) (xy 346.353219 -410.755851)
			(xy 346.337246 -410.690466) (xy 346.329202 -410.623642) (xy 343.051163 -410.623642) (xy 343.051163 -410.623699)
			(xy 343.043089 -410.690637) (xy 343.027055 -410.756125) (xy 343.003292 -410.819221) (xy 342.972143 -410.879017)
			(xy 342.934055 -410.934651) (xy 342.912192 -410.960316) (xy 342.906405 -410.967468) (xy 342.899885 -410.984653)
			(xy 342.899492 -410.993844) (xy 342.899492 -411.151324) (xy 342.899034 -411.161435) (xy 342.891287 -411.180116)
			(xy 342.876982 -411.19441) (xy 342.858296 -411.202142) (xy 342.848184 -411.202632) (xy 342.131904 -411.202632)
			(xy 342.121799 -411.202112) (xy 342.103128 -411.194382) (xy 342.088834 -411.180096) (xy 342.081093 -411.161428)
			(xy 342.080596 -411.151324) (xy 342.080596 -410.993844) (xy 342.080166 -410.984659) (xy 342.073666 -410.967474)
			(xy 342.067896 -410.960316) (xy 342.046016 -410.934664) (xy 342.007928 -410.879027) (xy 341.976779 -410.819229)
			(xy 341.953016 -410.756131) (xy 341.936981 -410.69064) (xy 341.928907 -410.6237) (xy 338.650837 -410.6237)
			(xy 338.642802 -410.69046) (xy 338.626832 -410.755841) (xy 338.603163 -410.818845) (xy 338.572134 -410.878568)
			(xy 338.534189 -410.934155) (xy 338.512404 -410.959808) (xy 338.506622 -410.966964) (xy 338.500098 -410.984146)
			(xy 338.499704 -410.993336) (xy 338.499704 -411.151324) (xy 338.499298 -411.161479) (xy 338.491495 -411.180231)
			(xy 338.477094 -411.194554) (xy 338.458299 -411.202253) (xy 338.448142 -411.202632) (xy 337.731862 -411.202632)
			(xy 337.721729 -411.202204) (xy 337.703002 -411.194458) (xy 337.688646 -411.180154) (xy 337.680833 -411.161455)
			(xy 337.6803 -411.151324) (xy 337.6803 -410.993336) (xy 337.679873 -410.984151) (xy 337.673371 -410.966966)
			(xy 337.6676 -410.959808) (xy 337.645798 -410.934168) (xy 337.607852 -410.878579) (xy 337.576822 -410.818853)
			(xy 337.553151 -410.755847) (xy 337.537181 -410.690464) (xy 337.529138 -410.623641) (xy 334.251075 -410.623641)
			(xy 334.251075 -410.623699) (xy 334.243001 -410.690636) (xy 334.226967 -410.756124) (xy 334.203205 -410.81922)
			(xy 334.172057 -410.879016) (xy 334.133971 -410.934651) (xy 334.112108 -410.960316) (xy 334.106323 -410.96747)
			(xy 334.099801 -410.984654) (xy 334.099408 -410.993844) (xy 334.099408 -411.151324) (xy 334.098935 -411.161433)
			(xy 334.091191 -411.180111) (xy 334.07689 -411.194404) (xy 334.05821 -411.20214) (xy 334.0481 -411.202632)
			(xy 333.33182 -411.202632) (xy 333.321716 -411.202099) (xy 333.303045 -411.194374) (xy 333.28875 -411.180092)
			(xy 333.281009 -411.161427) (xy 333.280512 -411.151324) (xy 333.280512 -410.993844) (xy 333.280078 -410.984659)
			(xy 333.273581 -410.967475) (xy 333.267812 -410.960316) (xy 333.245932 -410.934664) (xy 333.207843 -410.879028)
			(xy 333.176692 -410.81923) (xy 333.152928 -410.756131) (xy 333.136894 -410.69064) (xy 333.128819 -410.623701)
			(xy 326.525636 -410.623701) (xy 326.525636 -417.379404) (xy 326.525636 -417.533836) (xy 401.074128 -417.533836)
			(xy 401.074128 -417.366196) (xy 401.074128 -394.27912) (xy 414.451292 -394.27912) (xy 414.525968 -394.353542)
			(xy 414.525968 -397.823826) (xy 418.92899 -397.823826) (xy 418.928993 -397.756517) (xy 418.937042 -397.689691)
			(xy 418.95302 -397.624306) (xy 418.9767 -397.5613) (xy 419.00774 -397.501575) (xy 419.045697 -397.44599)
			(xy 419.067488 -397.420338) (xy 419.073292 -397.413198) (xy 419.079803 -397.396004) (xy 419.080188 -397.38681)
			(xy 419.080188 -396.893542) (xy 419.07976 -396.884357) (xy 419.073259 -396.867172) (xy 419.067488 -396.860014)
			(xy 419.045689 -396.834371) (xy 419.007737 -396.778784) (xy 418.976702 -396.71906) (xy 418.953027 -396.656054)
			(xy 418.937054 -396.59067) (xy 418.92901 -396.523846) (xy 418.92901 -396.456539) (xy 418.937056 -396.389715)
			(xy 418.953032 -396.324332) (xy 418.976708 -396.261327) (xy 419.007745 -396.201603) (xy 419.045698 -396.146018)
			(xy 419.067488 -396.120366) (xy 419.07328 -396.113218) (xy 419.079798 -396.09603) (xy 419.080188 -396.086838)
			(xy 419.080188 -395.92885) (xy 419.080606 -395.918675) (xy 419.088384 -395.899872) (xy 419.102772 -395.885484)
			(xy 419.121575 -395.877706) (xy 419.13175 -395.877288) (xy 419.84803 -395.877288) (xy 419.85821 -395.87764)
			(xy 419.877015 -395.885445) (xy 419.8914 -395.899852) (xy 419.899175 -395.91867) (xy 419.899592 -395.92885)
			(xy 419.899592 -396.086838) (xy 419.899986 -396.096027) (xy 419.906511 -396.113211) (xy 419.912292 -396.120366)
			(xy 419.934069 -396.146027) (xy 419.972016 -396.201613) (xy 420.003048 -396.261335) (xy 420.02672 -396.324339)
			(xy 420.042693 -396.389719) (xy 420.050737 -396.456541) (xy 420.050738 -396.523844) (xy 420.042695 -396.590666)
			(xy 420.026725 -396.656047) (xy 420.003054 -396.719051) (xy 419.972024 -396.778774) (xy 419.934078 -396.834361)
			(xy 419.912292 -396.860014) (xy 419.906506 -396.867167) (xy 419.899985 -396.884351) (xy 419.899592 -396.893542)
			(xy 419.899592 -397.38681) (xy 419.899999 -397.395998) (xy 419.906515 -397.413182) (xy 419.912292 -397.420338)
			(xy 419.934041 -397.446021) (xy 419.971989 -397.501604) (xy 420.00041 -397.556296) (xy 421.128654 -397.556296)
			(xy 421.13673 -397.489357) (xy 421.152765 -397.423869) (xy 421.17653 -397.360772) (xy 421.207681 -397.300976)
			(xy 421.245771 -397.245343) (xy 421.267636 -397.219678) (xy 421.273429 -397.21253) (xy 421.279945 -397.195342)
			(xy 421.280336 -397.18615) (xy 421.280336 -397.028924) (xy 421.280736 -397.018799) (xy 421.288483 -397.000089)
			(xy 421.302805 -396.985772) (xy 421.321518 -396.978032) (xy 421.331644 -396.977616) (xy 422.047924 -396.977616)
			(xy 422.058036 -396.978066) (xy 422.076718 -396.985814) (xy 422.091013 -397.000122) (xy 422.098744 -397.018811)
			(xy 422.099232 -397.028924) (xy 422.099232 -397.18615) (xy 422.099681 -397.195333) (xy 422.106169 -397.212517)
			(xy 422.111932 -397.219678) (xy 422.133805 -397.245336) (xy 422.171891 -397.300972) (xy 422.203039 -397.36077)
			(xy 422.226802 -397.423867) (xy 422.242835 -397.489357) (xy 422.25091 -397.556296) (xy 422.250909 -397.623719)
			(xy 422.242833 -397.690658) (xy 422.226797 -397.756147) (xy 422.203033 -397.819244) (xy 422.200615 -397.823885)
			(xy 423.328782 -397.823885) (xy 423.328786 -397.756458) (xy 423.336865 -397.689518) (xy 423.352904 -397.624027)
			(xy 423.376672 -397.560928) (xy 423.407826 -397.501131) (xy 423.445918 -397.445496) (xy 423.467784 -397.41983)
			(xy 423.473591 -397.412692) (xy 423.4801 -397.395496) (xy 423.480484 -397.386302) (xy 423.480484 -396.89405)
			(xy 423.480054 -396.884865) (xy 423.473554 -396.86768) (xy 423.467784 -396.860522) (xy 423.445911 -396.834865)
			(xy 423.407823 -396.779229) (xy 423.376674 -396.719431) (xy 423.352911 -396.656333) (xy 423.336877 -396.590843)
			(xy 423.328802 -396.523905) (xy 423.328803 -396.45648) (xy 423.33688 -396.389542) (xy 423.352916 -396.324052)
			(xy 423.37668 -396.260955) (xy 423.407831 -396.201159) (xy 423.44592 -396.145524) (xy 423.467784 -396.119858)
			(xy 423.473579 -396.112712) (xy 423.480095 -396.095522) (xy 423.480484 -396.08633) (xy 423.480484 -395.92885)
			(xy 423.480969 -395.918721) (xy 423.488688 -395.899993) (xy 423.502976 -395.885633) (xy 423.521666 -395.87782)
			(xy 423.531792 -395.877288) (xy 424.248072 -395.877288) (xy 424.258223 -395.877744) (xy 424.276972 -395.885528)
			(xy 424.291296 -395.899914) (xy 424.298999 -395.918697) (xy 424.29938 -395.92885) (xy 424.29938 -396.08633)
			(xy 424.29978 -396.095518) (xy 424.306301 -396.112702) (xy 424.31208 -396.119858) (xy 424.333935 -396.145531)
			(xy 424.372025 -396.201164) (xy 424.403177 -396.260959) (xy 424.426943 -396.324055) (xy 424.44298 -396.389543)
			(xy 424.451057 -396.456481) (xy 424.451058 -396.523904) (xy 424.442983 -396.590842) (xy 424.426948 -396.656331)
			(xy 424.403184 -396.719427) (xy 424.372033 -396.779223) (xy 424.333944 -396.834857) (xy 424.31208 -396.860522)
			(xy 424.306289 -396.867671) (xy 424.299772 -396.884859) (xy 424.29938 -396.89405) (xy 424.29938 -397.386302)
			(xy 424.299793 -397.395489) (xy 424.306305 -397.412673) (xy 424.31208 -397.41983) (xy 424.333907 -397.445526)
			(xy 424.371998 -397.501155) (xy 424.40076 -397.556356) (xy 425.528974 -397.556356) (xy 425.537017 -397.489534)
			(xy 425.552988 -397.424152) (xy 425.576659 -397.361148) (xy 425.607691 -397.301425) (xy 425.645637 -397.245838)
			(xy 425.667424 -397.220186) (xy 425.673212 -397.213035) (xy 425.679731 -397.195849) (xy 425.680124 -397.186658)
			(xy 425.680124 -397.028924) (xy 425.680542 -397.018768) (xy 425.688334 -397.000012) (xy 425.702732 -396.985687)
			(xy 425.721528 -396.97799) (xy 425.731686 -396.977616) (xy 426.447966 -396.977616) (xy 426.458088 -396.978154)
			(xy 426.476803 -396.985866) (xy 426.49116 -397.000137) (xy 426.498984 -397.018806) (xy 426.499528 -397.028924)
			(xy 426.499528 -397.186658) (xy 426.499952 -397.195844) (xy 426.506456 -397.213029) (xy 426.512228 -397.220186)
			(xy 426.534026 -397.24583) (xy 426.571977 -397.301417) (xy 426.603012 -397.361141) (xy 426.626685 -397.424147)
			(xy 426.642659 -397.48953) (xy 426.650703 -397.556354) (xy 426.650702 -397.623661) (xy 426.642656 -397.690485)
			(xy 426.626681 -397.755868) (xy 426.603006 -397.818873) (xy 426.600432 -397.823826) (xy 427.729077 -397.823826)
			(xy 427.729081 -397.756517) (xy 427.737129 -397.689691) (xy 427.753107 -397.624307) (xy 427.776786 -397.5613)
			(xy 427.807825 -397.501576) (xy 427.845781 -397.44599) (xy 427.867572 -397.420338) (xy 427.873386 -397.413206)
			(xy 427.879888 -397.396005) (xy 427.880272 -397.38681) (xy 427.880272 -396.893542) (xy 427.879848 -396.884356)
			(xy 427.873344 -396.867171) (xy 427.867572 -396.860014) (xy 427.845774 -396.83437) (xy 427.807823 -396.778783)
			(xy 427.776788 -396.719059) (xy 427.753115 -396.656053) (xy 427.737141 -396.59067) (xy 427.729097 -396.523846)
			(xy 427.729098 -396.456539) (xy 427.737144 -396.389715) (xy 427.753119 -396.324332) (xy 427.776794 -396.261327)
			(xy 427.807831 -396.201604) (xy 427.845783 -396.146018) (xy 427.867572 -396.120366) (xy 427.873374 -396.113225)
			(xy 427.879883 -396.096031) (xy 427.880272 -396.086838) (xy 427.880272 -395.92885) (xy 427.880706 -395.918677)
			(xy 427.88848 -395.899877) (xy 427.902864 -395.885489) (xy 427.921662 -395.877709) (xy 427.931834 -395.877288)
			(xy 428.648114 -395.877288) (xy 428.658293 -395.877654) (xy 428.677097 -395.885453) (xy 428.691483 -395.899857)
			(xy 428.699259 -395.918671) (xy 428.699676 -395.92885) (xy 428.699676 -396.086838) (xy 428.700073 -396.096026)
			(xy 428.706596 -396.11321) (xy 428.712376 -396.120366) (xy 428.734154 -396.146026) (xy 428.772102 -396.201612)
			(xy 428.803135 -396.261335) (xy 428.826807 -396.324338) (xy 428.84278 -396.389719) (xy 428.850825 -396.45654)
			(xy 428.850826 -396.523844) (xy 428.842783 -396.590666) (xy 428.826812 -396.656048) (xy 428.803141 -396.719052)
			(xy 428.772109 -396.778775) (xy 428.734163 -396.834362) (xy 428.712376 -396.860014) (xy 428.706588 -396.867165)
			(xy 428.700069 -396.884351) (xy 428.699676 -396.893542) (xy 428.699676 -397.38681) (xy 428.700087 -397.395997)
			(xy 428.7066 -397.413181) (xy 428.712376 -397.420338) (xy 428.734126 -397.446021) (xy 428.772075 -397.501604)
			(xy 428.800497 -397.556296) (xy 429.928742 -397.556296) (xy 429.936817 -397.489358) (xy 429.952852 -397.423869)
			(xy 429.976616 -397.360773) (xy 430.007767 -397.300977) (xy 430.045856 -397.245343) (xy 430.06772 -397.219678)
			(xy 430.073511 -397.212529) (xy 430.080028 -397.195341) (xy 430.08042 -397.18615) (xy 430.08042 -397.028924)
			(xy 430.080836 -397.018801) (xy 430.08858 -397.000094) (xy 430.102897 -396.985778) (xy 430.121605 -396.978035)
			(xy 430.131728 -396.977616) (xy 430.848008 -396.977616) (xy 430.858133 -396.97801) (xy 430.87684 -396.985764)
			(xy 430.891154 -397.000087) (xy 430.898896 -397.018799) (xy 430.899316 -397.028924) (xy 430.899316 -397.18615)
			(xy 430.899746 -397.195335) (xy 430.906246 -397.21252) (xy 430.912016 -397.219678) (xy 430.933889 -397.245335)
			(xy 430.971977 -397.300971) (xy 431.003126 -397.360769) (xy 431.026889 -397.423867) (xy 431.042923 -397.489357)
			(xy 431.050998 -397.556295) (xy 431.050997 -397.62372) (xy 431.04292 -397.690658) (xy 431.026884 -397.756148)
			(xy 431.00312 -397.819245) (xy 431.000734 -397.823826) (xy 432.128868 -397.823826) (xy 432.128872 -397.756517)
			(xy 432.13692 -397.689692) (xy 432.152898 -397.624307) (xy 432.176576 -397.561301) (xy 432.207614 -397.501576)
			(xy 432.245569 -397.44599) (xy 432.26736 -397.420338) (xy 432.273173 -397.413205) (xy 432.279676 -397.396005)
			(xy 432.28006 -397.38681) (xy 432.28006 -396.893542) (xy 432.279616 -396.884359) (xy 432.273125 -396.867175)
			(xy 432.26736 -396.860014) (xy 432.245562 -396.83437) (xy 432.207612 -396.778783) (xy 432.176578 -396.719058)
			(xy 432.152905 -396.656053) (xy 432.136932 -396.590669) (xy 432.128888 -396.523846) (xy 432.128889 -396.456539)
			(xy 432.136935 -396.389716) (xy 432.152909 -396.324333) (xy 432.176584 -396.261328) (xy 432.20762 -396.201604)
			(xy 432.245571 -396.146018) (xy 432.26736 -396.120366) (xy 432.273161 -396.113224) (xy 432.279671 -396.096031)
			(xy 432.28006 -396.086838) (xy 432.28006 -395.92885) (xy 432.280505 -395.918679) (xy 432.288278 -395.899881)
			(xy 432.302658 -395.885494) (xy 432.321451 -395.877711) (xy 432.331622 -395.877288) (xy 433.047902 -395.877288)
			(xy 433.05808 -395.877663) (xy 433.076884 -395.885458) (xy 433.091271 -395.899859) (xy 433.099047 -395.918672)
			(xy 433.099464 -395.92885) (xy 433.099464 -396.086838) (xy 433.099864 -396.096026) (xy 433.106386 -396.11321)
			(xy 433.112164 -396.120366) (xy 433.133942 -396.146026) (xy 433.171891 -396.201612) (xy 433.202924 -396.261334)
			(xy 433.226598 -396.324337) (xy 433.242571 -396.389719) (xy 433.250616 -396.45654) (xy 433.250617 -396.523845)
			(xy 433.242574 -396.590666) (xy 433.226602 -396.656048) (xy 433.202931 -396.719052) (xy 433.171899 -396.778776)
			(xy 433.133951 -396.834362) (xy 433.112164 -396.860014) (xy 433.106374 -396.867164) (xy 433.099856 -396.884351)
			(xy 433.099464 -396.893542) (xy 433.099464 -397.38681) (xy 433.099877 -397.395997) (xy 433.10639 -397.413181)
			(xy 433.112164 -397.420338) (xy 433.133914 -397.446021) (xy 433.171864 -397.501603) (xy 433.200318 -397.556356)
			(xy 434.329062 -397.556356) (xy 434.337105 -397.489534) (xy 434.353075 -397.424153) (xy 434.376746 -397.361149)
			(xy 434.407776 -397.301426) (xy 434.445722 -397.245839) (xy 434.467508 -397.220186) (xy 434.473294 -397.213033)
			(xy 434.479815 -397.195849) (xy 434.480208 -397.186658) (xy 434.480208 -397.028924) (xy 434.480641 -397.01877)
			(xy 434.48843 -397.000017) (xy 434.502824 -396.985692) (xy 434.521614 -396.977993) (xy 434.53177 -396.977616)
			(xy 435.24805 -396.977616) (xy 435.258171 -396.978167) (xy 435.276886 -396.985874) (xy 435.291243 -397.00014)
			(xy 435.299068 -397.018807) (xy 435.299612 -397.028924) (xy 435.299612 -397.186658) (xy 435.30004 -397.195843)
			(xy 435.306541 -397.213028) (xy 435.312312 -397.220186) (xy 435.334111 -397.245829) (xy 435.372063 -397.301416)
			(xy 435.403098 -397.36114) (xy 435.426773 -397.424146) (xy 435.442746 -397.48953) (xy 435.45079 -397.556354)
			(xy 435.45079 -397.623661) (xy 435.442744 -397.690485) (xy 435.426768 -397.755868) (xy 435.403092 -397.818873)
			(xy 435.372055 -397.878597) (xy 435.334102 -397.934182) (xy 435.312312 -397.959834) (xy 435.30652 -397.966982)
			(xy 435.300002 -397.98417) (xy 435.299612 -397.993362) (xy 435.299612 -398.100042) (xy 459.541382 -398.100042)
			(xy 459.545364 -397.972056) (xy 459.557296 -397.844565) (xy 459.57713 -397.718062) (xy 459.604791 -397.593037)
			(xy 459.640171 -397.469974) (xy 459.683133 -397.349348) (xy 459.733511 -397.231627) (xy 459.791111 -397.117265)
			(xy 459.855709 -397.006706) (xy 459.927056 -396.900376) (xy 460.004875 -396.798688) (xy 460.088865 -396.702034)
			(xy 460.178702 -396.610789) (xy 460.274038 -396.525306) (xy 460.374503 -396.445915) (xy 460.479711 -396.372923)
			(xy 460.589252 -396.306614) (xy 460.702704 -396.247243) (xy 460.819628 -396.195039) (xy 460.939571 -396.150206)
			(xy 461.062069 -396.112917) (xy 461.186649 -396.083315) (xy 461.312827 -396.061516) (xy 461.440117 -396.047603)
			(xy 461.568026 -396.041631) (xy 461.696059 -396.043622) (xy 461.82372 -396.05357) (xy 461.950516 -396.071434)
			(xy 462.075955 -396.097147) (xy 462.199554 -396.130609) (xy 462.320833 -396.17169) (xy 462.439324 -396.220232)
			(xy 462.554568 -396.276046) (xy 462.666118 -396.338917) (xy 462.773545 -396.408601) (xy 462.876431 -396.484829)
			(xy 462.974379 -396.567306) (xy 463.06701 -396.655713) (xy 463.153966 -396.749708) (xy 463.23491 -396.848927)
			(xy 463.309529 -396.952986) (xy 463.377534 -397.061483) (xy 463.438662 -397.173998) (xy 463.492677 -397.290096)
			(xy 463.53937 -397.409327) (xy 463.57856 -397.531231) (xy 463.610096 -397.655335) (xy 463.633855 -397.781159)
			(xy 463.649745 -397.908218) (xy 463.657706 -398.036018) (xy 463.658204 -398.100042) (xy 463.657706 -398.164066)
			(xy 463.649745 -398.291866) (xy 463.633855 -398.418925) (xy 463.610096 -398.544749) (xy 463.57856 -398.668853)
			(xy 463.53937 -398.790757) (xy 463.492677 -398.909988) (xy 463.438662 -399.026086) (xy 463.377534 -399.138601)
			(xy 463.309529 -399.247098) (xy 463.23491 -399.351157) (xy 463.153966 -399.450376) (xy 463.06701 -399.544371)
			(xy 462.974379 -399.632778) (xy 462.876431 -399.715255) (xy 462.773545 -399.791483) (xy 462.666118 -399.861167)
			(xy 462.554568 -399.924038) (xy 462.439324 -399.979852) (xy 462.320833 -400.028394) (xy 462.199554 -400.069475)
			(xy 462.075955 -400.102937) (xy 461.950516 -400.12865) (xy 461.82372 -400.146514) (xy 461.696059 -400.156462)
			(xy 461.568026 -400.158453) (xy 461.440117 -400.152481) (xy 461.312827 -400.138568) (xy 461.186649 -400.116769)
			(xy 461.062069 -400.087167) (xy 460.939571 -400.049878) (xy 460.819628 -400.005045) (xy 460.702704 -399.952841)
			(xy 460.589252 -399.89347) (xy 460.479711 -399.827161) (xy 460.374503 -399.754169) (xy 460.274038 -399.674778)
			(xy 460.178702 -399.589295) (xy 460.088865 -399.49805) (xy 460.004875 -399.401396) (xy 459.927056 -399.299708)
			(xy 459.855709 -399.193378) (xy 459.791111 -399.082819) (xy 459.733511 -398.968457) (xy 459.683133 -398.850736)
			(xy 459.640171 -398.73011) (xy 459.604791 -398.607047) (xy 459.57713 -398.482022) (xy 459.557296 -398.355519)
			(xy 459.545364 -398.228028) (xy 459.541382 -398.100042) (xy 435.299612 -398.100042) (xy 435.299612 -398.486884)
			(xy 435.300027 -398.496071) (xy 435.306537 -398.513255) (xy 435.312312 -398.520412) (xy 435.334137 -398.546034)
			(xy 435.372087 -398.601624) (xy 435.403122 -398.661351) (xy 435.426795 -398.72436) (xy 435.442767 -398.789746)
			(xy 435.450809 -398.856573) (xy 435.450805 -398.923881) (xy 435.442757 -398.990707) (xy 435.426779 -399.056092)
			(xy 435.4031 -399.119098) (xy 435.37206 -399.178823) (xy 435.334103 -399.234408) (xy 435.312312 -399.26006)
			(xy 435.306509 -399.267201) (xy 435.299998 -399.284395) (xy 435.299612 -399.293588) (xy 435.299612 -399.451576)
			(xy 435.299159 -399.461727) (xy 435.291374 -399.480477) (xy 435.276987 -399.494801) (xy 435.258203 -399.502503)
			(xy 435.24805 -399.502884) (xy 434.53177 -399.502884) (xy 434.521644 -399.502399) (xy 434.502927 -399.494666)
			(xy 434.488573 -399.480379) (xy 434.48075 -399.461699) (xy 434.480208 -399.451576) (xy 434.480208 -399.293588)
			(xy 434.479802 -399.2844) (xy 434.473285 -399.267216) (xy 434.467508 -399.26006) (xy 434.445757 -399.234378)
			(xy 434.407809 -399.178795) (xy 434.376776 -399.119076) (xy 434.353102 -399.056075) (xy 434.337128 -398.990697)
			(xy 434.329081 -398.923878) (xy 434.329078 -398.856576) (xy 434.337118 -398.789757) (xy 434.353086 -398.724377)
			(xy 434.376753 -398.661374) (xy 434.407781 -398.601651) (xy 434.445723 -398.546064) (xy 434.467508 -398.520412)
			(xy 434.473325 -398.513282) (xy 434.479827 -398.49608) (xy 434.480208 -398.486884) (xy 434.480208 -397.993362)
			(xy 434.479814 -397.984173) (xy 434.473289 -397.966989) (xy 434.467508 -397.959834) (xy 434.445731 -397.934173)
			(xy 434.407784 -397.878587) (xy 434.376752 -397.818865) (xy 434.35308 -397.755861) (xy 434.337107 -397.690481)
			(xy 434.329063 -397.623659) (xy 434.329062 -397.556356) (xy 433.200318 -397.556356) (xy 433.202899 -397.561322)
			(xy 433.226573 -397.624323) (xy 433.242549 -397.689701) (xy 433.250596 -397.75652) (xy 433.250599 -397.823822)
			(xy 433.242559 -397.890642) (xy 433.22659 -397.956022) (xy 433.202922 -398.019025) (xy 433.171893 -398.078748)
			(xy 433.133949 -398.134334) (xy 433.112164 -398.159986) (xy 433.106344 -398.167114) (xy 433.099844 -398.184318)
			(xy 433.099464 -398.193514) (xy 433.099464 -398.351502) (xy 433.098968 -398.36166) (xy 433.091194 -398.380428)
			(xy 433.076828 -398.394794) (xy 433.05806 -398.402568) (xy 433.047902 -398.403064) (xy 432.331622 -398.403064)
			(xy 432.321452 -398.402618) (xy 432.302658 -398.394841) (xy 432.288273 -398.380462) (xy 432.280487 -398.361672)
			(xy 432.28006 -398.351502) (xy 432.28006 -398.193514) (xy 432.27963 -398.184329) (xy 432.273129 -398.167145)
			(xy 432.26736 -398.159986) (xy 432.245534 -398.134365) (xy 432.207585 -398.078775) (xy 432.176552 -398.019047)
			(xy 432.152881 -397.956038) (xy 432.13691 -397.890652) (xy 432.128868 -397.823826) (xy 431.000734 -397.823826)
			(xy 430.971969 -397.879041) (xy 430.93388 -397.934676) (xy 430.912016 -397.960342) (xy 430.906221 -397.967488)
			(xy 430.899705 -397.984678) (xy 430.899316 -397.99387) (xy 430.899316 -398.486376) (xy 430.899734 -398.495562)
			(xy 430.906242 -398.512747) (xy 430.912016 -398.519904) (xy 430.933915 -398.54554) (xy 430.972001 -398.601179)
			(xy 431.00315 -398.66098) (xy 431.026911 -398.72408) (xy 431.042944 -398.789573) (xy 431.051016 -398.856514)
			(xy 431.051013 -398.92394) (xy 431.042934 -398.990881) (xy 431.026895 -399.056371) (xy 431.003128 -399.11947)
			(xy 430.971974 -399.179267) (xy 430.933882 -399.234902) (xy 430.912016 -399.260568) (xy 430.90621 -399.267707)
			(xy 430.8997 -399.284902) (xy 430.899316 -399.294096) (xy 430.899316 -399.451576) (xy 430.898865 -399.461695)
			(xy 430.891128 -399.480395) (xy 430.876822 -399.49471) (xy 430.858127 -399.502459) (xy 430.848008 -399.502884)
			(xy 430.131728 -399.502884) (xy 430.121605 -399.502461) (xy 430.102899 -399.494719) (xy 430.088583 -399.480404)
			(xy 430.08084 -399.461699) (xy 430.08042 -399.451576) (xy 430.08042 -399.294096) (xy 430.080008 -399.284909)
			(xy 430.073495 -399.267725) (xy 430.06772 -399.260568) (xy 430.045891 -399.234874) (xy 430.0078 -399.179244)
			(xy 429.976646 -399.119452) (xy 429.952879 -399.056359) (xy 429.936841 -398.990873) (xy 429.928761 -398.923938)
			(xy 429.928758 -398.856516) (xy 429.936831 -398.78958) (xy 429.952863 -398.724093) (xy 429.976624 -398.660997)
			(xy 430.007772 -398.601202) (xy 430.045857 -398.545569) (xy 430.06772 -398.519904) (xy 430.0735 -398.512747)
			(xy 430.080024 -398.495565) (xy 430.08042 -398.486376) (xy 430.08042 -397.99387) (xy 430.08002 -397.984682)
			(xy 430.073499 -397.967498) (xy 430.06772 -397.960342) (xy 430.045865 -397.934669) (xy 430.007775 -397.879036)
			(xy 429.976623 -397.819241) (xy 429.952857 -397.756145) (xy 429.93682 -397.690657) (xy 429.928743 -397.623719)
			(xy 429.928742 -397.556296) (xy 428.800497 -397.556296) (xy 428.803109 -397.561323) (xy 428.826783 -397.624323)
			(xy 428.842758 -397.689702) (xy 428.850805 -397.756521) (xy 428.850808 -397.823822) (xy 428.842768 -397.890642)
			(xy 428.8268 -397.956022) (xy 428.803132 -398.019025) (xy 428.772104 -398.078747) (xy 428.734161 -398.134333)
			(xy 428.712376 -398.159986) (xy 428.706558 -398.167116) (xy 428.700057 -398.184318) (xy 428.699676 -398.193514)
			(xy 428.699676 -398.351502) (xy 428.699169 -398.361658) (xy 428.691396 -398.380425) (xy 428.677035 -398.394789)
			(xy 428.65827 -398.402566) (xy 428.648114 -398.403064) (xy 427.931834 -398.403064) (xy 427.921665 -398.402608)
			(xy 427.902871 -398.394835) (xy 427.888485 -398.380459) (xy 427.880699 -398.361671) (xy 427.880272 -398.351502)
			(xy 427.880272 -398.193514) (xy 427.879861 -398.184327) (xy 427.873349 -398.167142) (xy 427.867572 -398.159986)
			(xy 427.845746 -398.134365) (xy 427.807796 -398.078775) (xy 427.776762 -398.019047) (xy 427.75309 -397.956039)
			(xy 427.737119 -397.890652) (xy 427.729077 -397.823826) (xy 426.600432 -397.823826) (xy 426.571969 -397.878596)
			(xy 426.534017 -397.934182) (xy 426.512228 -397.959834) (xy 426.506426 -397.966975) (xy 426.499917 -397.984169)
			(xy 426.499528 -397.993362) (xy 426.499528 -398.486884) (xy 426.499939 -398.496071) (xy 426.506451 -398.513256)
			(xy 426.512228 -398.520412) (xy 426.534052 -398.546034) (xy 426.572002 -398.601624) (xy 426.603036 -398.661352)
			(xy 426.626708 -398.72436) (xy 426.64268 -398.789746) (xy 426.650721 -398.856573) (xy 426.650718 -398.923881)
			(xy 426.64267 -398.990707) (xy 426.626692 -399.056092) (xy 426.603014 -399.119098) (xy 426.571974 -399.178822)
			(xy 426.534019 -399.234408) (xy 426.512228 -399.26006) (xy 426.506415 -399.267193) (xy 426.499912 -399.284393)
			(xy 426.499528 -399.293588) (xy 426.499528 -399.451576) (xy 426.499059 -399.461725) (xy 426.491277 -399.480472)
			(xy 426.476895 -399.494795) (xy 426.458117 -399.502501) (xy 426.447966 -399.502884) (xy 425.731686 -399.502884)
			(xy 425.721561 -399.502385) (xy 425.702845 -399.494657) (xy 425.68849 -399.480375) (xy 425.680667 -399.461698)
			(xy 425.680124 -399.451576) (xy 425.680124 -399.293588) (xy 425.679714 -399.284401) (xy 425.6732 -399.267217)
			(xy 425.667424 -399.26006) (xy 425.645672 -399.234378) (xy 425.607723 -399.178796) (xy 425.576689 -399.119076)
			(xy 425.553015 -399.056076) (xy 425.53704 -398.990697) (xy 425.528994 -398.923878) (xy 425.52899 -398.856576)
			(xy 425.537031 -398.789756) (xy 425.552999 -398.724376) (xy 425.576667 -398.661373) (xy 425.607696 -398.601651)
			(xy 425.645639 -398.546065) (xy 425.667424 -398.520412) (xy 425.673243 -398.513283) (xy 425.679744 -398.49608)
			(xy 425.680124 -398.486884) (xy 425.680124 -397.993362) (xy 425.679727 -397.984174) (xy 425.673204 -397.96699)
			(xy 425.667424 -397.959834) (xy 425.645646 -397.934174) (xy 425.607698 -397.878588) (xy 425.576665 -397.818865)
			(xy 425.552993 -397.755862) (xy 425.53702 -397.690481) (xy 425.528975 -397.62366) (xy 425.528974 -397.556356)
			(xy 424.40076 -397.556356) (xy 424.403152 -397.560947) (xy 424.426919 -397.62404) (xy 424.442958 -397.689526)
			(xy 424.451037 -397.756461) (xy 424.451041 -397.823882) (xy 424.442968 -397.890818) (xy 424.426936 -397.956305)
			(xy 424.403175 -398.019401) (xy 424.372028 -398.079196) (xy 424.333942 -398.134829) (xy 424.31208 -398.160494)
			(xy 424.306301 -398.167652) (xy 424.299777 -398.184833) (xy 424.29938 -398.194022) (xy 424.29938 -398.351502)
			(xy 424.298876 -398.361626) (xy 424.291151 -398.380344) (xy 424.27687 -398.394699) (xy 424.258194 -398.402522)
			(xy 424.248072 -398.403064) (xy 423.531792 -398.403064) (xy 423.521633 -398.402684) (xy 423.502873 -398.394879)
			(xy 423.488549 -398.380469) (xy 423.480856 -398.361663) (xy 423.480484 -398.351502) (xy 423.480484 -398.194022)
			(xy 423.480067 -398.184835) (xy 423.473558 -398.167651) (xy 423.467784 -398.160494) (xy 423.445883 -398.134859)
			(xy 423.407797 -398.07922) (xy 423.376649 -398.019419) (xy 423.352887 -397.956319) (xy 423.336855 -397.890826)
			(xy 423.328782 -397.823885) (xy 422.200615 -397.823885) (xy 422.171883 -397.879041) (xy 422.133795 -397.934676)
			(xy 422.111932 -397.960342) (xy 422.106127 -397.967481) (xy 422.099619 -397.984676) (xy 422.099232 -397.99387)
			(xy 422.099232 -398.486376) (xy 422.099669 -398.49556) (xy 422.106166 -398.512744) (xy 422.111932 -398.519904)
			(xy 422.13383 -398.545541) (xy 422.171916 -398.60118) (xy 422.203063 -398.66098) (xy 422.226824 -398.724081)
			(xy 422.242856 -398.789573) (xy 422.250928 -398.856514) (xy 422.250925 -398.92394) (xy 422.242846 -398.99088)
			(xy 422.226808 -399.056371) (xy 422.203041 -399.119469) (xy 422.171888 -399.179266) (xy 422.133797 -399.234902)
			(xy 422.111932 -399.260568) (xy 422.106116 -399.267699) (xy 422.099615 -399.284901) (xy 422.099232 -399.294096)
			(xy 422.099232 -399.451576) (xy 422.098696 -399.461679) (xy 422.090972 -399.480351) (xy 422.076691 -399.494645)
			(xy 422.058027 -399.502387) (xy 422.047924 -399.502884) (xy 421.331644 -399.502884) (xy 421.321522 -399.502447)
			(xy 421.302817 -399.494711) (xy 421.2885 -399.4804) (xy 421.280756 -399.461697) (xy 421.280336 -399.451576)
			(xy 421.280336 -399.294096) (xy 421.27992 -399.28491) (xy 421.27341 -399.267726) (xy 421.267636 -399.260568)
			(xy 421.245806 -399.234874) (xy 421.207714 -399.179245) (xy 421.17656 -399.119453) (xy 421.152792 -399.056359)
			(xy 421.136753 -398.990873) (xy 421.128674 -398.923938) (xy 421.12867 -398.856516) (xy 421.136743 -398.78958)
			(xy 421.152776 -398.724092) (xy 421.176538 -398.660997) (xy 421.207686 -398.601202) (xy 421.245773 -398.545569)
			(xy 421.267636 -398.519904) (xy 421.273418 -398.512749) (xy 421.27994 -398.495566) (xy 421.280336 -398.486376)
			(xy 421.280336 -397.99387) (xy 421.279932 -397.984682) (xy 421.273413 -397.967498) (xy 421.267636 -397.960342)
			(xy 421.245781 -397.934669) (xy 421.207689 -397.879037) (xy 421.176536 -397.819242) (xy 421.15277 -397.756146)
			(xy 421.136732 -397.690657) (xy 421.128655 -397.623719) (xy 421.128654 -397.556296) (xy 420.00041 -397.556296)
			(xy 420.003023 -397.561324) (xy 420.026696 -397.624324) (xy 420.042671 -397.689702) (xy 420.050718 -397.756521)
			(xy 420.050721 -397.823822) (xy 420.042681 -397.890642) (xy 420.026713 -397.956021) (xy 420.003046 -398.019024)
			(xy 419.972019 -398.078747) (xy 419.934077 -398.134334) (xy 419.912292 -398.159986) (xy 419.906475 -398.167117)
			(xy 419.899973 -398.184318) (xy 419.899592 -398.193514) (xy 419.899592 -398.351502) (xy 419.899069 -398.361656)
			(xy 419.891299 -398.38042) (xy 419.876943 -398.394784) (xy 419.858184 -398.402563) (xy 419.84803 -398.403064)
			(xy 419.13175 -398.403064) (xy 419.121582 -398.402595) (xy 419.102789 -398.394827) (xy 419.088402 -398.380455)
			(xy 419.080615 -398.36167) (xy 419.080188 -398.351502) (xy 419.080188 -398.193514) (xy 419.079774 -398.184327)
			(xy 419.073263 -398.167143) (xy 419.067488 -398.159986) (xy 419.045661 -398.134365) (xy 419.007711 -398.078775)
			(xy 418.976676 -398.019048) (xy 418.953004 -397.956039) (xy 418.937032 -397.890653) (xy 418.92899 -397.823826)
			(xy 414.525968 -397.823826) (xy 414.525968 -401.723737) (xy 418.929001 -401.723737) (xy 418.929003 -401.65643)
			(xy 418.93705 -401.589605) (xy 418.953027 -401.524221) (xy 418.976704 -401.461215) (xy 419.007743 -401.401491)
			(xy 419.045697 -401.345906) (xy 419.067488 -401.320254) (xy 419.073285 -401.313109) (xy 419.0798 -401.295918)
			(xy 419.080188 -401.286726) (xy 419.080188 -400.793458) (xy 419.079801 -400.784268) (xy 419.073272 -400.767084)
			(xy 419.067488 -400.75993) (xy 419.045705 -400.734274) (xy 419.007752 -400.678689) (xy 418.976716 -400.618966)
			(xy 418.953041 -400.555962) (xy 418.937066 -400.49058) (xy 418.929021 -400.423757) (xy 418.92902 -400.356452)
			(xy 418.937065 -400.289629) (xy 418.953038 -400.224246) (xy 418.976713 -400.161242) (xy 419.007748 -400.101519)
			(xy 419.045699 -400.045933) (xy 419.067488 -400.020282) (xy 419.073273 -400.013129) (xy 419.079795 -399.995944)
			(xy 419.080188 -399.986754) (xy 419.080188 -399.828766) (xy 419.080537 -399.818586) (xy 419.088343 -399.799781)
			(xy 419.102752 -399.785395) (xy 419.121569 -399.777621) (xy 419.13175 -399.777204) (xy 419.84803 -399.777204)
			(xy 419.858186 -399.777708) (xy 419.876949 -399.785486) (xy 419.891312 -399.799848) (xy 419.899091 -399.818611)
			(xy 419.899592 -399.828766) (xy 419.899592 -399.986754) (xy 419.900026 -399.995939) (xy 419.906523 -400.013123)
			(xy 419.912292 -400.020282) (xy 419.934085 -400.04593) (xy 419.972031 -400.101518) (xy 420.003063 -400.161242)
			(xy 420.026734 -400.224247) (xy 420.042705 -400.289629) (xy 420.050749 -400.356452) (xy 420.050748 -400.423757)
			(xy 420.042704 -400.490579) (xy 420.026731 -400.555962) (xy 420.003059 -400.618966) (xy 419.972027 -400.67869)
			(xy 419.934079 -400.734277) (xy 419.912292 -400.75993) (xy 419.906499 -400.767078) (xy 419.899983 -400.784266)
			(xy 419.899592 -400.793458) (xy 419.899592 -401.286726) (xy 419.899991 -401.295914) (xy 419.906513 -401.313099)
			(xy 419.912292 -401.320254) (xy 419.934057 -401.345924) (xy 419.972005 -401.401509) (xy 420.003037 -401.46123)
			(xy 420.02671 -401.524232) (xy 420.042683 -401.589612) (xy 420.050729 -401.656432) (xy 420.050731 -401.723735)
			(xy 420.042689 -401.790555) (xy 420.02672 -401.855936) (xy 420.003051 -401.918939) (xy 419.972022 -401.978663)
			(xy 419.934077 -402.034249) (xy 419.912292 -402.059902) (xy 419.906511 -402.067058) (xy 419.899987 -402.08424)
			(xy 419.899592 -402.09343) (xy 419.899592 -402.251418) (xy 419.899082 -402.261573) (xy 419.891308 -402.280337)
			(xy 419.876947 -402.294701) (xy 419.858185 -402.30248) (xy 419.84803 -402.30298) (xy 419.13175 -402.30298)
			(xy 419.121584 -402.302496) (xy 419.102794 -402.29473) (xy 419.088408 -402.280363) (xy 419.080618 -402.261584)
			(xy 419.080188 -402.251418) (xy 419.080188 -402.09343) (xy 419.079766 -402.084244) (xy 419.073261 -402.067059)
			(xy 419.067488 -402.059902) (xy 419.045677 -402.034268) (xy 419.007726 -401.97868) (xy 418.976691 -401.918955)
			(xy 418.953017 -401.855948) (xy 418.937044 -401.790563) (xy 418.929001 -401.723737) (xy 414.525968 -401.723737)
			(xy 414.525968 -402.823878) (xy 421.128614 -402.823878) (xy 421.128619 -402.75645) (xy 421.1367 -402.689508)
			(xy 421.152742 -402.624016) (xy 421.176513 -402.560916) (xy 421.207671 -402.501119) (xy 421.245768 -402.445485)
			(xy 421.267636 -402.41982) (xy 421.273454 -402.41269) (xy 421.279955 -402.395488) (xy 421.280336 -402.386292)
			(xy 421.280336 -401.89404) (xy 421.279898 -401.884856) (xy 421.273403 -401.867672) (xy 421.267636 -401.860512)
			(xy 421.245751 -401.834864) (xy 421.207661 -401.779227) (xy 421.176509 -401.719429) (xy 421.152744 -401.65633)
			(xy 421.136709 -401.590839) (xy 421.128634 -401.523898) (xy 421.128636 -401.456472) (xy 421.136714 -401.389532)
			(xy 421.152753 -401.324041) (xy 421.176521 -401.260943) (xy 421.207676 -401.201147) (xy 421.24577 -401.145513)
			(xy 421.267636 -401.119848) (xy 421.273442 -401.112709) (xy 421.27995 -401.095514) (xy 421.280336 -401.08632)
			(xy 421.280336 -400.92884) (xy 421.28075 -400.918716) (xy 421.288491 -400.900006) (xy 421.302809 -400.885689)
			(xy 421.32152 -400.877949) (xy 421.331644 -400.877532) (xy 422.047924 -400.877532) (xy 422.058052 -400.877897)
			(xy 422.076762 -400.885659) (xy 422.091077 -400.899991) (xy 422.098816 -400.918711) (xy 422.099232 -400.92884)
			(xy 422.099232 -401.08632) (xy 422.099648 -401.095506) (xy 422.106159 -401.11269) (xy 422.111932 -401.119848)
			(xy 422.133775 -401.14553) (xy 422.171862 -401.201163) (xy 422.203012 -401.260957) (xy 422.226776 -401.324052)
			(xy 422.242812 -401.389538) (xy 422.250889 -401.456474) (xy 422.250891 -401.523896) (xy 422.242817 -401.590832)
			(xy 422.226785 -401.65632) (xy 422.203024 -401.719415) (xy 422.200742 -401.723796) (xy 423.328794 -401.723796)
			(xy 423.328796 -401.656371) (xy 423.336873 -401.589431) (xy 423.352911 -401.523941) (xy 423.376677 -401.460844)
			(xy 423.407829 -401.401047) (xy 423.445919 -401.345412) (xy 423.467784 -401.319746) (xy 423.473584 -401.312603)
			(xy 423.480097 -401.295411) (xy 423.480484 -401.286218) (xy 423.480484 -400.793966) (xy 423.480094 -400.784777)
			(xy 423.473566 -400.767592) (xy 423.467784 -400.760438) (xy 423.445926 -400.734768) (xy 423.407839 -400.679133)
			(xy 423.376689 -400.619338) (xy 423.352925 -400.556242) (xy 423.336889 -400.490753) (xy 423.328813 -400.423816)
			(xy 423.328813 -400.356393) (xy 423.336888 -400.289455) (xy 423.352922 -400.223967) (xy 423.376685 -400.16087)
			(xy 423.407834 -400.101074) (xy 423.445921 -400.045439) (xy 423.467784 -400.019774) (xy 423.473572 -400.012623)
			(xy 423.480092 -399.995437) (xy 423.480484 -399.986246) (xy 423.480484 -399.828766) (xy 423.4809 -399.818632)
			(xy 423.488647 -399.799901) (xy 423.502955 -399.785545) (xy 423.521659 -399.777735) (xy 423.531792 -399.777204)
			(xy 424.248072 -399.777204) (xy 424.258225 -399.777644) (xy 424.276977 -399.785431) (xy 424.291302 -399.799823)
			(xy 424.299002 -399.818611) (xy 424.29938 -399.828766) (xy 424.29938 -399.986246) (xy 424.299821 -399.99543)
			(xy 424.306314 -400.012614) (xy 424.31208 -400.019774) (xy 424.333951 -400.045434) (xy 424.37204 -400.101069)
			(xy 424.403192 -400.160866) (xy 424.426957 -400.223963) (xy 424.442992 -400.289453) (xy 424.451068 -400.356392)
			(xy 424.451068 -400.423817) (xy 424.442991 -400.490756) (xy 424.426954 -400.556245) (xy 424.403188 -400.619343)
			(xy 424.372036 -400.679139) (xy 424.333945 -400.734773) (xy 424.31208 -400.760438) (xy 424.306282 -400.767582)
			(xy 424.299769 -400.784774) (xy 424.29938 -400.793966) (xy 424.29938 -401.286218) (xy 424.299786 -401.295406)
			(xy 424.306303 -401.31259) (xy 424.31208 -401.319746) (xy 424.333923 -401.345429) (xy 424.372014 -401.40106)
			(xy 424.403167 -401.460854) (xy 424.426933 -401.523949) (xy 424.44297 -401.589436) (xy 424.451048 -401.656372)
			(xy 424.45105 -401.723795) (xy 424.442976 -401.790732) (xy 424.426943 -401.85622) (xy 424.40318 -401.919316)
			(xy 424.372031 -401.979111) (xy 424.333943 -402.034745) (xy 424.31208 -402.06041) (xy 424.306294 -402.067563)
			(xy 424.299774 -402.084748) (xy 424.29938 -402.093938) (xy 424.29938 -402.251418) (xy 424.298889 -402.261543)
			(xy 424.291159 -402.280261) (xy 424.276874 -402.294616) (xy 424.258195 -402.302438) (xy 424.248072 -402.30298)
			(xy 423.531792 -402.30298) (xy 423.521635 -402.302584) (xy 423.502879 -402.294782) (xy 423.488555 -402.280378)
			(xy 423.480859 -402.261577) (xy 423.480484 -402.251418) (xy 423.480484 -402.093938) (xy 423.480059 -402.084752)
			(xy 423.473556 -402.067568) (xy 423.467784 -402.06041) (xy 423.445899 -402.034762) (xy 423.407812 -401.979125)
			(xy 423.376663 -401.919326) (xy 423.352901 -401.856227) (xy 423.336867 -401.790736) (xy 423.328794 -401.723796)
			(xy 422.200742 -401.723796) (xy 422.171878 -401.779211) (xy 422.133794 -401.834846) (xy 422.111932 -401.860512)
			(xy 422.10614 -401.86766) (xy 422.099624 -401.884849) (xy 422.099232 -401.89404) (xy 422.099232 -402.386292)
			(xy 422.099661 -402.395477) (xy 422.106163 -402.412661) (xy 422.111932 -402.41982) (xy 422.133748 -402.445525)
			(xy 422.171836 -402.501154) (xy 422.202987 -402.560945) (xy 422.226752 -402.624037) (xy 422.24279 -402.689521)
			(xy 422.250869 -402.756454) (xy 422.250874 -402.823818) (xy 425.528934 -402.823818) (xy 425.528938 -402.75651)
			(xy 425.536987 -402.689684) (xy 425.552965 -402.624299) (xy 425.576642 -402.561293) (xy 425.60768 -402.501568)
			(xy 425.645634 -402.44598) (xy 425.667424 -402.420328) (xy 425.673236 -402.413194) (xy 425.679741 -402.395995)
			(xy 425.680124 -402.3868) (xy 425.680124 -401.893532) (xy 425.679693 -401.884347) (xy 425.673193 -401.867163)
			(xy 425.667424 -401.860004) (xy 425.645617 -401.834368) (xy 425.60767 -401.778779) (xy 425.576638 -401.719053)
			(xy 425.552967 -401.656046) (xy 425.536996 -401.590662) (xy 425.528954 -401.523838) (xy 425.528956 -401.456532)
			(xy 425.537001 -401.389708) (xy 425.552976 -401.324325) (xy 425.57665 -401.26132) (xy 425.607685 -401.201595)
			(xy 425.645635 -401.146008) (xy 425.667424 -401.120356) (xy 425.673225 -401.113214) (xy 425.679736 -401.096021)
			(xy 425.680124 -401.086828) (xy 425.680124 -400.92884) (xy 425.680555 -400.918686) (xy 425.688342 -400.899929)
			(xy 425.702736 -400.885604) (xy 425.72153 -400.877907) (xy 425.731686 -400.877532) (xy 426.447966 -400.877532)
			(xy 426.45809 -400.878054) (xy 426.476808 -400.88577) (xy 426.491165 -400.900045) (xy 426.498987 -400.918719)
			(xy 426.499528 -400.92884) (xy 426.499528 -401.086828) (xy 426.499918 -401.096017) (xy 426.506445 -401.113202)
			(xy 426.512228 -401.120356) (xy 426.533997 -401.146024) (xy 426.571949 -401.201607) (xy 426.602985 -401.261328)
			(xy 426.62666 -401.324331) (xy 426.642635 -401.389712) (xy 426.650681 -401.456533) (xy 426.650683 -401.523837)
			(xy 426.642641 -401.590659) (xy 426.626669 -401.65604) (xy 426.602997 -401.719044) (xy 426.600558 -401.723737)
			(xy 427.729089 -401.723737) (xy 427.729091 -401.65643) (xy 427.737138 -401.589605) (xy 427.753114 -401.524221)
			(xy 427.776791 -401.461216) (xy 427.807828 -401.401492) (xy 427.845782 -401.345906) (xy 427.867572 -401.320254)
			(xy 427.873379 -401.313117) (xy 427.879886 -401.29592) (xy 427.880272 -401.286726) (xy 427.880272 -400.793458)
			(xy 427.879888 -400.784268) (xy 427.873357 -400.767084) (xy 427.867572 -400.75993) (xy 427.845789 -400.734273)
			(xy 427.807838 -400.678688) (xy 427.776803 -400.618966) (xy 427.753128 -400.555962) (xy 427.737154 -400.49058)
			(xy 427.729109 -400.423757) (xy 427.729108 -400.356452) (xy 427.737152 -400.289629) (xy 427.753126 -400.224247)
			(xy 427.776799 -400.161243) (xy 427.807833 -400.101519) (xy 427.845784 -400.045934) (xy 427.867572 -400.020282)
			(xy 427.873367 -400.013136) (xy 427.879881 -399.995946) (xy 427.880272 -399.986754) (xy 427.880272 -399.828766)
			(xy 427.880706 -399.818602) (xy 427.888498 -399.799825) (xy 427.902883 -399.78546) (xy 427.921669 -399.777693)
			(xy 427.931834 -399.777204) (xy 428.648114 -399.777204) (xy 428.658268 -399.777721) (xy 428.677031 -399.785494)
			(xy 428.691395 -399.799852) (xy 428.699175 -399.818612) (xy 428.699676 -399.828766) (xy 428.699676 -399.986754)
			(xy 428.700114 -399.995938) (xy 428.706609 -400.013122) (xy 428.712376 -400.020282) (xy 428.734169 -400.045929)
			(xy 428.772117 -400.101517) (xy 428.803149 -400.161241) (xy 428.826821 -400.224246) (xy 428.842793 -400.289629)
			(xy 428.850836 -400.356452) (xy 428.850836 -400.423757) (xy 428.842791 -400.49058) (xy 428.826818 -400.555962)
			(xy 428.803145 -400.618967) (xy 428.772112 -400.678691) (xy 428.734164 -400.734278) (xy 428.712376 -400.75993)
			(xy 428.706581 -400.767076) (xy 428.700066 -400.784266) (xy 428.699676 -400.793458) (xy 428.699676 -401.286726)
			(xy 428.700079 -401.295914) (xy 428.706598 -401.313098) (xy 428.712376 -401.320254) (xy 428.734142 -401.345924)
			(xy 428.77209 -401.401508) (xy 428.803124 -401.46123) (xy 428.826797 -401.524232) (xy 428.842771 -401.589612)
			(xy 428.850817 -401.656432) (xy 428.850819 -401.723735) (xy 428.842777 -401.790556) (xy 428.826807 -401.855937)
			(xy 428.803137 -401.91894) (xy 428.772107 -401.978663) (xy 428.734162 -402.03425) (xy 428.712376 -402.059902)
			(xy 428.706593 -402.067057) (xy 428.700071 -402.08424) (xy 428.699676 -402.09343) (xy 428.699676 -402.251418)
			(xy 428.699182 -402.261575) (xy 428.691404 -402.280342) (xy 428.677039 -402.294706) (xy 428.658271 -402.302483)
			(xy 428.648114 -402.30298) (xy 427.931834 -402.30298) (xy 427.921667 -402.302509) (xy 427.902876 -402.294738)
			(xy 427.888491 -402.280367) (xy 427.880702 -402.261585) (xy 427.880272 -402.251418) (xy 427.880272 -402.09343)
			(xy 427.879854 -402.084244) (xy 427.873347 -402.067059) (xy 427.867572 -402.059902) (xy 427.845762 -402.034268)
			(xy 427.807811 -401.97868) (xy 427.776777 -401.918954) (xy 427.753104 -401.855947) (xy 427.737132 -401.790562)
			(xy 427.729089 -401.723737) (xy 426.600558 -401.723737) (xy 426.571964 -401.778767) (xy 426.534015 -401.834352)
			(xy 426.512228 -401.860004) (xy 426.506438 -401.867154) (xy 426.499922 -401.884341) (xy 426.499528 -401.893532)
			(xy 426.499528 -402.3868) (xy 426.499932 -402.395988) (xy 426.506449 -402.413173) (xy 426.512228 -402.420328)
			(xy 426.53397 -402.446019) (xy 426.571922 -402.501599) (xy 426.602959 -402.561317) (xy 426.626636 -402.624316)
			(xy 426.642613 -402.689694) (xy 426.650662 -402.756513) (xy 426.650666 -402.823815) (xy 426.650658 -402.823878)
			(xy 429.928702 -402.823878) (xy 429.928707 -402.75645) (xy 429.936788 -402.689508) (xy 429.952829 -402.624016)
			(xy 429.976599 -402.560917) (xy 430.007757 -402.50112) (xy 430.045852 -402.445485) (xy 430.06772 -402.41982)
			(xy 430.073535 -402.412688) (xy 430.080038 -402.395487) (xy 430.08042 -402.386292) (xy 430.08042 -401.89404)
			(xy 430.079986 -401.884855) (xy 430.073488 -401.867671) (xy 430.06772 -401.860512) (xy 430.045836 -401.834863)
			(xy 430.007746 -401.779227) (xy 429.976595 -401.719429) (xy 429.952831 -401.656329) (xy 429.936797 -401.590838)
			(xy 429.928722 -401.523898) (xy 429.928724 -401.456472) (xy 429.936802 -401.389532) (xy 429.95284 -401.324042)
			(xy 429.976608 -401.260944) (xy 430.007762 -401.201147) (xy 430.045854 -401.145513) (xy 430.06772 -401.119848)
			(xy 430.073523 -401.112708) (xy 430.080033 -401.095513) (xy 430.08042 -401.08632) (xy 430.08042 -400.92884)
			(xy 430.080849 -400.918718) (xy 430.088588 -400.900011) (xy 430.102901 -400.885695) (xy 430.121606 -400.877952)
			(xy 430.131728 -400.877532) (xy 430.848008 -400.877532) (xy 430.858135 -400.87791) (xy 430.876845 -400.885667)
			(xy 430.89116 -400.899996) (xy 430.898899 -400.918713) (xy 430.899316 -400.92884) (xy 430.899316 -401.08632)
			(xy 430.899713 -401.095509) (xy 430.906236 -401.112693) (xy 430.912016 -401.119848) (xy 430.93386 -401.14553)
			(xy 430.971948 -401.201162) (xy 431.003099 -401.260956) (xy 431.026863 -401.324051) (xy 431.0429 -401.389538)
			(xy 431.050977 -401.456474) (xy 431.050979 -401.523896) (xy 431.042905 -401.590832) (xy 431.026872 -401.65632)
			(xy 431.003111 -401.719416) (xy 431.00086 -401.723737) (xy 432.128879 -401.723737) (xy 432.128881 -401.65643)
			(xy 432.136928 -401.589605) (xy 432.152904 -401.524222) (xy 432.17658 -401.461216) (xy 432.207617 -401.401492)
			(xy 432.24557 -401.345906) (xy 432.26736 -401.320254) (xy 432.273166 -401.313116) (xy 432.279673 -401.29592)
			(xy 432.28006 -401.286726) (xy 432.28006 -400.793458) (xy 432.279657 -400.78427) (xy 432.273137 -400.767087)
			(xy 432.26736 -400.75993) (xy 432.245578 -400.734273) (xy 432.207627 -400.678688) (xy 432.176593 -400.618965)
			(xy 432.152919 -400.555961) (xy 432.136945 -400.490579) (xy 432.1289 -400.423757) (xy 432.128899 -400.356452)
			(xy 432.136943 -400.28963) (xy 432.152916 -400.224247) (xy 432.176589 -400.161243) (xy 432.207623 -400.10152)
			(xy 432.245572 -400.045934) (xy 432.26736 -400.020282) (xy 432.273154 -400.013135) (xy 432.279669 -399.995946)
			(xy 432.28006 -399.986754) (xy 432.28006 -399.828766) (xy 432.280506 -399.818603) (xy 432.288296 -399.799829)
			(xy 432.302676 -399.785464) (xy 432.321459 -399.777695) (xy 432.331622 -399.777204) (xy 433.047902 -399.777204)
			(xy 433.058056 -399.777731) (xy 433.076818 -399.7855) (xy 433.091182 -399.799855) (xy 433.098963 -399.818613)
			(xy 433.099464 -399.828766) (xy 433.099464 -399.986754) (xy 433.099905 -399.995938) (xy 433.106398 -400.013122)
			(xy 433.112164 -400.020282) (xy 433.133958 -400.045929) (xy 433.171906 -400.101516) (xy 433.202939 -400.161241)
			(xy 433.226611 -400.224246) (xy 433.242584 -400.289629) (xy 433.250627 -400.356452) (xy 433.250627 -400.423757)
			(xy 433.242582 -400.49058) (xy 433.226609 -400.555963) (xy 433.202935 -400.618968) (xy 433.171901 -400.678691)
			(xy 433.133952 -400.734278) (xy 433.112164 -400.75993) (xy 433.106368 -400.767075) (xy 433.099854 -400.784266)
			(xy 433.099464 -400.793458) (xy 433.099464 -401.286726) (xy 433.09987 -401.295913) (xy 433.106387 -401.313097)
			(xy 433.112164 -401.320254) (xy 433.13393 -401.345924) (xy 433.171879 -401.401508) (xy 433.202913 -401.461229)
			(xy 433.226587 -401.524231) (xy 433.242561 -401.589611) (xy 433.250607 -401.656432) (xy 433.250609 -401.723735)
			(xy 433.242567 -401.790556) (xy 433.226597 -401.855937) (xy 433.202927 -401.918941) (xy 433.171896 -401.978663)
			(xy 433.13395 -402.03425) (xy 433.112164 -402.059902) (xy 433.106379 -402.067056) (xy 433.099858 -402.08424)
			(xy 433.099464 -402.09343) (xy 433.099464 -402.251418) (xy 433.098982 -402.261577) (xy 433.091202 -402.280346)
			(xy 433.076833 -402.294711) (xy 433.058061 -402.302485) (xy 433.047902 -402.30298) (xy 432.331622 -402.30298)
			(xy 432.321454 -402.302518) (xy 432.302663 -402.294744) (xy 432.288278 -402.28037) (xy 432.28049 -402.261586)
			(xy 432.28006 -402.251418) (xy 432.28006 -402.09343) (xy 432.279622 -402.084246) (xy 432.273126 -402.067062)
			(xy 432.26736 -402.059902) (xy 432.24555 -402.034268) (xy 432.2076 -401.97868) (xy 432.176567 -401.918954)
			(xy 432.152894 -401.855947) (xy 432.136922 -401.790562) (xy 432.128879 -401.723737) (xy 431.00086 -401.723737)
			(xy 430.971963 -401.779212) (xy 430.933878 -401.834847) (xy 430.912016 -401.860512) (xy 430.906234 -401.867667)
			(xy 430.89971 -401.88485) (xy 430.899316 -401.89404) (xy 430.899316 -402.386292) (xy 430.899726 -402.395479)
			(xy 430.90624 -402.412664) (xy 430.912016 -402.41982) (xy 430.933832 -402.445524) (xy 430.971921 -402.501154)
			(xy 431.003073 -402.560945) (xy 431.026839 -402.624036) (xy 431.042878 -402.68952) (xy 431.050957 -402.756454)
			(xy 431.050962 -402.823818) (xy 434.329022 -402.823818) (xy 434.329026 -402.75651) (xy 434.337075 -402.689684)
			(xy 434.353052 -402.6243) (xy 434.376729 -402.561294) (xy 434.407766 -402.501568) (xy 434.445718 -402.445981)
			(xy 434.467508 -402.420328) (xy 434.473319 -402.413193) (xy 434.479825 -402.395995) (xy 434.480208 -402.3868)
			(xy 434.480208 -401.893532) (xy 434.479781 -401.884347) (xy 434.473279 -401.867162) (xy 434.467508 -401.860004)
			(xy 434.445702 -401.834368) (xy 434.407755 -401.778778) (xy 434.376725 -401.719052) (xy 434.353054 -401.656046)
			(xy 434.337084 -401.590662) (xy 434.329042 -401.523838) (xy 434.329043 -401.456532) (xy 434.337089 -401.389709)
			(xy 434.353063 -401.324326) (xy 434.376737 -401.26132) (xy 434.407771 -401.201596) (xy 434.44572 -401.146009)
			(xy 434.467508 -401.120356) (xy 434.473307 -401.113212) (xy 434.47982 -401.096021) (xy 434.480208 -401.086828)
			(xy 434.480208 -400.92884) (xy 434.480655 -400.918688) (xy 434.488438 -400.899934) (xy 434.502828 -400.885609)
			(xy 434.521616 -400.87791) (xy 434.53177 -400.877532) (xy 435.24805 -400.877532) (xy 435.258173 -400.878067)
			(xy 435.276891 -400.885777) (xy 435.291249 -400.900049) (xy 435.299071 -400.918721) (xy 435.299612 -400.92884)
			(xy 435.299612 -401.086828) (xy 435.300006 -401.096017) (xy 435.306531 -401.113201) (xy 435.312312 -401.120356)
			(xy 435.334082 -401.146024) (xy 435.372034 -401.201607) (xy 435.403071 -401.261328) (xy 435.426747 -401.32433)
			(xy 435.442723 -401.389711) (xy 435.450769 -401.456533) (xy 435.450771 -401.523837) (xy 435.442728 -401.590659)
			(xy 435.426756 -401.656041) (xy 435.403083 -401.719045) (xy 435.37205 -401.778767) (xy 435.3341 -401.834353)
			(xy 435.312312 -401.860004) (xy 435.306533 -401.867161) (xy 435.300007 -401.884343) (xy 435.299612 -401.893532)
			(xy 435.299612 -402.3868) (xy 435.30002 -402.395988) (xy 435.306535 -402.413172) (xy 435.312312 -402.420328)
			(xy 435.334054 -402.446018) (xy 435.372008 -402.501598) (xy 435.403046 -402.561316) (xy 435.426723 -402.624316)
			(xy 435.442701 -402.689694) (xy 435.45075 -402.756513) (xy 435.450754 -402.823815) (xy 435.442714 -402.890635)
			(xy 435.426745 -402.956015) (xy 435.403075 -403.019018) (xy 435.372045 -403.07874) (xy 435.334098 -403.134325)
			(xy 435.312312 -403.159976) (xy 435.306502 -403.167112) (xy 435.299995 -403.184309) (xy 435.299612 -403.193504)
			(xy 435.299612 -403.351492) (xy 435.299172 -403.361644) (xy 435.291381 -403.380394) (xy 435.27699 -403.394717)
			(xy 435.258204 -403.402419) (xy 435.24805 -403.4028) (xy 434.53177 -403.4028) (xy 434.521646 -403.402299)
			(xy 434.502932 -403.394569) (xy 434.488578 -403.380288) (xy 434.480753 -403.361613) (xy 434.480208 -403.351492)
			(xy 434.480208 -403.193504) (xy 434.479794 -403.184317) (xy 434.473283 -403.167133) (xy 434.467508 -403.159976)
			(xy 434.445674 -403.134362) (xy 434.407729 -403.07877) (xy 434.376699 -403.01904) (xy 434.353031 -402.956031)
			(xy 434.337062 -402.890644) (xy 434.329022 -402.823818) (xy 431.050962 -402.823818) (xy 431.050962 -402.823874)
			(xy 431.042891 -402.890808) (xy 431.026861 -402.956295) (xy 431.003103 -403.019389) (xy 430.971958 -403.079184)
			(xy 430.933877 -403.134819) (xy 430.912016 -403.160484) (xy 430.906203 -403.167618) (xy 430.899698 -403.184817)
			(xy 430.899316 -403.194012) (xy 430.899316 -403.351492) (xy 430.898809 -403.361598) (xy 430.891077 -403.380273)
			(xy 430.876787 -403.394568) (xy 430.858114 -403.402306) (xy 430.848008 -403.4028) (xy 430.131728 -403.4028)
			(xy 430.121607 -403.402361) (xy 430.102904 -403.394622) (xy 430.088589 -403.380313) (xy 430.080843 -403.361613)
			(xy 430.08042 -403.351492) (xy 430.08042 -403.194012) (xy 430.079999 -403.184826) (xy 430.073492 -403.167642)
			(xy 430.06772 -403.160484) (xy 430.045808 -403.134858) (xy 430.00772 -403.079218) (xy 429.97657 -403.019417)
			(xy 429.952807 -402.956315) (xy 429.936775 -402.890821) (xy 429.928702 -402.823878) (xy 426.650658 -402.823878)
			(xy 426.642626 -402.890635) (xy 426.626657 -402.956015) (xy 426.602989 -403.019017) (xy 426.571959 -403.078739)
			(xy 426.534014 -403.134324) (xy 426.512228 -403.159976) (xy 426.506408 -403.167104) (xy 426.499909 -403.184308)
			(xy 426.499528 -403.193504) (xy 426.499528 -403.351492) (xy 426.499072 -403.361642) (xy 426.491285 -403.380389)
			(xy 426.476899 -403.394712) (xy 426.458118 -403.402417) (xy 426.447966 -403.4028) (xy 425.731686 -403.4028)
			(xy 425.721563 -403.402286) (xy 425.70285 -403.394561) (xy 425.688495 -403.380284) (xy 425.68067 -403.361612)
			(xy 425.680124 -403.351492) (xy 425.680124 -403.193504) (xy 425.679707 -403.184318) (xy 425.673198 -403.167133)
			(xy 425.667424 -403.159976) (xy 425.64559 -403.134362) (xy 425.607643 -403.07877) (xy 425.576613 -403.019041)
			(xy 425.552943 -402.956032) (xy 425.536974 -402.890645) (xy 425.528934 -402.823818) (xy 422.250874 -402.823818)
			(xy 422.250874 -402.823874) (xy 422.242803 -402.890808) (xy 422.226774 -402.956294) (xy 422.203016 -403.019389)
			(xy 422.171873 -403.079184) (xy 422.133792 -403.134818) (xy 422.111932 -403.160484) (xy 422.106109 -403.16761)
			(xy 422.099612 -403.184816) (xy 422.099232 -403.194012) (xy 422.099232 -403.351492) (xy 422.098709 -403.361596)
			(xy 422.09098 -403.380268) (xy 422.076695 -403.394562) (xy 422.058028 -403.402303) (xy 422.047924 -403.4028)
			(xy 421.331644 -403.4028) (xy 421.321524 -403.402348) (xy 421.302822 -403.394614) (xy 421.288506 -403.380308)
			(xy 421.280759 -403.361611) (xy 421.280336 -403.351492) (xy 421.280336 -403.194012) (xy 421.279912 -403.184826)
			(xy 421.273407 -403.167642) (xy 421.267636 -403.160484) (xy 421.245724 -403.134858) (xy 421.207634 -403.079219)
			(xy 421.176483 -403.019418) (xy 421.15272 -402.956315) (xy 421.136687 -402.890821) (xy 421.128614 -402.823878)
			(xy 414.525968 -402.823878) (xy 414.525968 -405.623649) (xy 418.929012 -405.623649) (xy 418.929013 -405.556342)
			(xy 418.937058 -405.489518) (xy 418.953033 -405.424135) (xy 418.976709 -405.36113) (xy 419.007746 -405.301407)
			(xy 419.045698 -405.245822) (xy 419.067488 -405.22017) (xy 419.073278 -405.21302) (xy 419.079797 -405.195833)
			(xy 419.080188 -405.186642) (xy 419.080188 -404.693374) (xy 419.079793 -404.684185) (xy 419.073269 -404.667001)
			(xy 419.067488 -404.659846) (xy 419.04572 -404.634177) (xy 419.007768 -404.578594) (xy 418.976731 -404.518873)
			(xy 418.953055 -404.455871) (xy 418.937079 -404.39049) (xy 418.929032 -404.323669) (xy 418.92903 -404.256364)
			(xy 418.937073 -404.189542) (xy 418.953045 -404.124161) (xy 418.976717 -404.061157) (xy 419.007751 -404.001435)
			(xy 419.0457 -403.945849) (xy 419.067488 -403.920198) (xy 419.073267 -403.91304) (xy 419.079792 -403.895859)
			(xy 419.080188 -403.88667) (xy 419.080188 -403.728682) (xy 419.08055 -403.718503) (xy 419.088351 -403.699698)
			(xy 419.102756 -403.685313) (xy 419.12157 -403.677537) (xy 419.13175 -403.67712) (xy 419.84803 -403.67712)
			(xy 419.858187 -403.677608) (xy 419.876954 -403.685389) (xy 419.891317 -403.699756) (xy 419.899094 -403.718524)
			(xy 419.899592 -403.728682) (xy 419.899592 -403.88667) (xy 419.900018 -403.895855) (xy 419.906521 -403.91304)
			(xy 419.912292 -403.920198) (xy 419.9341 -403.945833) (xy 419.972047 -404.001422) (xy 420.003077 -404.061149)
			(xy 420.026747 -404.124155) (xy 420.042718 -404.189539) (xy 420.05076 -404.256363) (xy 420.050758 -404.32367)
			(xy 420.042712 -404.390493) (xy 420.026738 -404.455876) (xy 420.003064 -404.518882) (xy 419.97203 -404.578606)
			(xy 419.93408 -404.634193) (xy 419.912292 -404.659846) (xy 419.906492 -404.666989) (xy 419.89998 -404.684181)
			(xy 419.899592 -404.693374) (xy 419.899592 -405.186642) (xy 419.899984 -405.195831) (xy 419.90651 -405.213015)
			(xy 419.912292 -405.22017) (xy 419.934073 -405.245827) (xy 419.97202 -405.301414) (xy 420.003052 -405.361137)
			(xy 420.026723 -405.424141) (xy 420.042696 -405.489522) (xy 420.05074 -405.556343) (xy 420.050741 -405.623647)
			(xy 420.042698 -405.690469) (xy 420.026726 -405.755851) (xy 420.003055 -405.818855) (xy 419.972025 -405.878578)
			(xy 419.934078 -405.934165) (xy 419.912292 -405.959818) (xy 419.906504 -405.96697) (xy 419.899985 -405.984155)
			(xy 419.899592 -405.993346) (xy 419.899592 -406.151334) (xy 419.899095 -406.16149) (xy 419.891315 -406.180254)
			(xy 419.876951 -406.194617) (xy 419.858186 -406.202396) (xy 419.84803 -406.202896) (xy 419.13175 -406.202896)
			(xy 419.121586 -406.202396) (xy 419.102799 -406.194634) (xy 419.088413 -406.180272) (xy 419.08062 -406.161497)
			(xy 419.080188 -406.151334) (xy 419.080188 -405.993346) (xy 419.079759 -405.984161) (xy 419.073259 -405.966976)
			(xy 419.067488 -405.959818) (xy 419.045693 -405.934171) (xy 419.007741 -405.878585) (xy 418.976705 -405.818861)
			(xy 418.953031 -405.755856) (xy 418.937057 -405.690473) (xy 418.929012 -405.623649) (xy 414.525968 -405.623649)
			(xy 414.525968 -406.723789) (xy 421.128626 -406.723789) (xy 421.128629 -406.656363) (xy 421.136708 -406.589421)
			(xy 421.152748 -406.52393) (xy 421.176518 -406.460832) (xy 421.207674 -406.401035) (xy 421.245769 -406.345401)
			(xy 421.267636 -406.319736) (xy 421.273447 -406.312601) (xy 421.279952 -406.295403) (xy 421.280336 -406.286208)
			(xy 421.280336 -405.793956) (xy 421.279939 -405.784768) (xy 421.273415 -405.767584) (xy 421.267636 -405.760428)
			(xy 421.245767 -405.734767) (xy 421.207676 -405.679132) (xy 421.176523 -405.619336) (xy 421.152758 -405.556239)
			(xy 421.136722 -405.490749) (xy 421.128645 -405.423809) (xy 421.128646 -405.356385) (xy 421.136723 -405.289445)
			(xy 421.15276 -405.223956) (xy 421.176526 -405.160859) (xy 421.207679 -405.101062) (xy 421.245771 -405.045429)
			(xy 421.267636 -405.019764) (xy 421.273435 -405.012621) (xy 421.279947 -404.995429) (xy 421.280336 -404.986236)
			(xy 421.280336 -404.828756) (xy 421.28075 -404.81864) (xy 421.288509 -404.799954) (xy 421.302828 -404.785659)
			(xy 421.321527 -404.777933) (xy 421.331644 -404.777448) (xy 422.047924 -404.777448) (xy 422.058028 -404.777964)
			(xy 422.076697 -404.7857) (xy 422.090989 -404.799986) (xy 422.098732 -404.818652) (xy 422.099232 -404.828756)
			(xy 422.099232 -404.986236) (xy 422.09964 -404.995423) (xy 422.106157 -405.012607) (xy 422.111932 -405.019764)
			(xy 422.133791 -405.045433) (xy 422.171878 -405.101068) (xy 422.203027 -405.160864) (xy 422.22679 -405.22396)
			(xy 422.242825 -405.289448) (xy 422.2509 -405.356386) (xy 422.250901 -405.423808) (xy 422.242826 -405.490746)
			(xy 422.226792 -405.556234) (xy 422.203029 -405.619331) (xy 422.20075 -405.623707) (xy 423.328805 -405.623707)
			(xy 423.328805 -405.556284) (xy 423.336882 -405.489345) (xy 423.352917 -405.423856) (xy 423.376681 -405.360759)
			(xy 423.407832 -405.300962) (xy 423.44592 -405.245328) (xy 423.467784 -405.219662) (xy 423.473577 -405.212514)
			(xy 423.480094 -405.195326) (xy 423.480484 -405.186134) (xy 423.480484 -404.693882) (xy 423.480086 -404.684693)
			(xy 423.473564 -404.667509) (xy 423.467784 -404.660354) (xy 423.445942 -404.634671) (xy 423.407854 -404.579038)
			(xy 423.376703 -404.519245) (xy 423.352938 -404.45615) (xy 423.336902 -404.390663) (xy 423.328825 -404.323727)
			(xy 423.328823 -404.256306) (xy 423.336896 -404.189369) (xy 423.352929 -404.123882) (xy 423.37669 -404.060786)
			(xy 423.407837 -404.00099) (xy 423.445922 -403.945355) (xy 423.467784 -403.91969) (xy 423.473565 -403.912534)
			(xy 423.48009 -403.895352) (xy 423.480484 -403.886162) (xy 423.480484 -403.728682) (xy 423.480913 -403.718549)
			(xy 423.488655 -403.699819) (xy 423.502959 -403.685461) (xy 423.521661 -403.677651) (xy 423.531792 -403.67712)
			(xy 424.248072 -403.67712) (xy 424.258227 -403.677545) (xy 424.276983 -403.685335) (xy 424.291308 -403.699731)
			(xy 424.299005 -403.718525) (xy 424.29938 -403.728682) (xy 424.29938 -403.886162) (xy 424.299813 -403.895347)
			(xy 424.306311 -403.912531) (xy 424.31208 -403.91969) (xy 424.333966 -403.945337) (xy 424.372056 -404.000974)
			(xy 424.403207 -404.060772) (xy 424.42697 -404.123872) (xy 424.443005 -404.189363) (xy 424.451079 -404.256304)
			(xy 424.451077 -404.323729) (xy 424.442999 -404.39067) (xy 424.426961 -404.45616) (xy 424.403193 -404.519258)
			(xy 424.372039 -404.579055) (xy 424.333946 -404.634689) (xy 424.31208 -404.660354) (xy 424.306276 -404.667494)
			(xy 424.299766 -404.684688) (xy 424.29938 -404.693882) (xy 424.29938 -405.186134) (xy 424.299778 -405.195322)
			(xy 424.306301 -405.212506) (xy 424.31208 -405.219662) (xy 424.333939 -405.245332) (xy 424.372029 -405.300965)
			(xy 424.403181 -405.360761) (xy 424.426946 -405.423857) (xy 424.442983 -405.489346) (xy 424.45106 -405.556284)
			(xy 424.45106 -405.623707) (xy 424.442985 -405.690646) (xy 424.426949 -405.756134) (xy 424.403185 -405.819231)
			(xy 424.372034 -405.879027) (xy 424.333944 -405.934661) (xy 424.31208 -405.960326) (xy 424.306288 -405.967474)
			(xy 424.299771 -405.984662) (xy 424.29938 -405.993854) (xy 424.29938 -406.151334) (xy 424.298902 -406.16146)
			(xy 424.291167 -406.180179) (xy 424.276878 -406.194533) (xy 424.258196 -406.202355) (xy 424.248072 -406.202896)
			(xy 423.531792 -406.202896) (xy 423.521637 -406.202485) (xy 423.502884 -406.194686) (xy 423.48856 -406.180286)
			(xy 423.480862 -406.161491) (xy 423.480484 -406.151334) (xy 423.480484 -405.993854) (xy 423.480051 -405.984669)
			(xy 423.473553 -405.967484) (xy 423.467784 -405.960326) (xy 423.445915 -405.934665) (xy 423.407827 -405.87903)
			(xy 423.376678 -405.819233) (xy 423.352915 -405.756135) (xy 423.33688 -405.690646) (xy 423.328805 -405.623707)
			(xy 422.20075 -405.623707) (xy 422.171881 -405.679127) (xy 422.133795 -405.734762) (xy 422.111932 -405.760428)
			(xy 422.106133 -405.767571) (xy 422.099622 -405.784763) (xy 422.099232 -405.793956) (xy 422.099232 -406.286208)
			(xy 422.099654 -406.295394) (xy 422.106161 -406.312577) (xy 422.111932 -406.319736) (xy 422.133763 -406.345428)
			(xy 422.171851 -406.401059) (xy 422.203001 -406.460852) (xy 422.226766 -406.523945) (xy 422.242803 -406.589431)
			(xy 422.250881 -406.656366) (xy 422.250883 -406.72373) (xy 425.528945 -406.72373) (xy 425.528948 -406.656422)
			(xy 425.536995 -406.589598) (xy 425.552971 -406.524214) (xy 425.576647 -406.461208) (xy 425.607683 -406.401484)
			(xy 425.645635 -406.345896) (xy 425.667424 -406.320244) (xy 425.67323 -406.313105) (xy 425.679738 -406.29591)
			(xy 425.680124 -406.286716) (xy 425.680124 -405.793448) (xy 425.679685 -405.784264) (xy 425.673191 -405.76708)
			(xy 425.667424 -405.75992) (xy 425.645633 -405.734271) (xy 425.607685 -405.678684) (xy 425.576653 -405.61896)
			(xy 425.552981 -405.555955) (xy 425.537009 -405.490572) (xy 425.528965 -405.42375) (xy 425.528965 -405.356444)
			(xy 425.53701 -405.289622) (xy 425.552983 -405.22424) (xy 425.576655 -405.161235) (xy 425.607688 -405.101511)
			(xy 425.645636 -405.045924) (xy 425.667424 -405.020272) (xy 425.673218 -405.013125) (xy 425.679733 -404.995936)
			(xy 425.680124 -404.986744) (xy 425.680124 -404.828756) (xy 425.680486 -404.818596) (xy 425.688301 -404.799838)
			(xy 425.702716 -404.785515) (xy 425.721523 -404.777822) (xy 425.731686 -404.777448) (xy 426.447966 -404.777448)
			(xy 426.458091 -404.777955) (xy 426.476813 -404.785673) (xy 426.491171 -404.799953) (xy 426.49899 -404.818633)
			(xy 426.499528 -404.828756) (xy 426.499528 -404.986744) (xy 426.499911 -404.995934) (xy 426.506443 -405.013119)
			(xy 426.512228 -405.020272) (xy 426.534013 -405.045927) (xy 426.571964 -405.101512) (xy 426.602999 -405.161235)
			(xy 426.626674 -405.224239) (xy 426.642648 -405.289622) (xy 426.650693 -405.356444) (xy 426.650693 -405.42375)
			(xy 426.642649 -405.490573) (xy 426.626675 -405.555955) (xy 426.603002 -405.618959) (xy 426.600565 -405.623649)
			(xy 427.7291 -405.623649) (xy 427.729101 -405.556342) (xy 427.737146 -405.489519) (xy 427.753121 -405.424136)
			(xy 427.776796 -405.361131) (xy 427.807831 -405.301408) (xy 427.845783 -405.245822) (xy 427.867572 -405.22017)
			(xy 427.873373 -405.213028) (xy 427.879883 -405.195835) (xy 427.880272 -405.186642) (xy 427.880272 -404.693374)
			(xy 427.879881 -404.684185) (xy 427.873355 -404.667) (xy 427.867572 -404.659846) (xy 427.845805 -404.634176)
			(xy 427.807853 -404.578593) (xy 427.776817 -404.518872) (xy 427.753142 -404.45587) (xy 427.737166 -404.39049)
			(xy 427.72912 -404.323668) (xy 427.729118 -404.256365) (xy 427.73716 -404.189543) (xy 427.753132 -404.124162)
			(xy 427.776804 -404.061158) (xy 427.807836 -404.001435) (xy 427.845785 -403.94585) (xy 427.867572 -403.920198)
			(xy 427.873361 -403.913048) (xy 427.879878 -403.895861) (xy 427.880272 -403.88667) (xy 427.880272 -403.728682)
			(xy 427.88065 -403.718505) (xy 427.888447 -403.699703) (xy 427.902847 -403.685318) (xy 427.921657 -403.67754)
			(xy 427.931834 -403.67712) (xy 428.648114 -403.67712) (xy 428.65827 -403.677622) (xy 428.677036 -403.685397)
			(xy 428.6914 -403.69976) (xy 428.699178 -403.718526) (xy 428.699676 -403.728682) (xy 428.699676 -403.88667)
			(xy 428.700106 -403.895855) (xy 428.706607 -403.913039) (xy 428.712376 -403.920198) (xy 428.734185 -403.945833)
			(xy 428.772132 -404.001422) (xy 428.803164 -404.061148) (xy 428.826835 -404.124155) (xy 428.842806 -404.189539)
			(xy 428.850848 -404.256363) (xy 428.850846 -404.32367) (xy 428.8428 -404.390494) (xy 428.826825 -404.455877)
			(xy 428.80315 -404.518882) (xy 428.772115 -404.578607) (xy 428.734165 -404.634194) (xy 428.712376 -404.659846)
			(xy 428.706575 -404.666988) (xy 428.700064 -404.684181) (xy 428.699676 -404.693374) (xy 428.699676 -405.186642)
			(xy 428.700071 -405.195831) (xy 428.706596 -405.213015) (xy 428.712376 -405.22017) (xy 428.734157 -405.245827)
			(xy 428.772106 -405.301413) (xy 428.803138 -405.361136) (xy 428.826811 -405.42414) (xy 428.842784 -405.489522)
			(xy 428.850828 -405.556343) (xy 428.850829 -405.623648) (xy 428.842785 -405.69047) (xy 428.826813 -405.755851)
			(xy 428.803142 -405.818856) (xy 428.77211 -405.878579) (xy 428.734163 -405.934166) (xy 428.712376 -405.959818)
			(xy 428.706587 -405.966968) (xy 428.700068 -405.984155) (xy 428.699676 -405.993346) (xy 428.699676 -406.151334)
			(xy 428.699195 -406.161492) (xy 428.691412 -406.180259) (xy 428.677043 -406.194623) (xy 428.658272 -406.202399)
			(xy 428.648114 -406.202896) (xy 427.931834 -406.202896) (xy 427.921683 -406.202339) (xy 427.902921 -406.194583)
			(xy 427.888556 -406.180236) (xy 427.880774 -406.161485) (xy 427.880272 -406.151334) (xy 427.880272 -405.993346)
			(xy 427.879846 -405.98416) (xy 427.873344 -405.966976) (xy 427.867572 -405.959818) (xy 427.845777 -405.934171)
			(xy 427.807827 -405.878585) (xy 427.776792 -405.818861) (xy 427.753118 -405.755855) (xy 427.737144 -405.690472)
			(xy 427.7291 -405.623649) (xy 426.600565 -405.623649) (xy 426.571967 -405.678683) (xy 426.534016 -405.734268)
			(xy 426.512228 -405.75992) (xy 426.506432 -405.767065) (xy 426.499919 -405.784256) (xy 426.499528 -405.793448)
			(xy 426.499528 -406.286716) (xy 426.499924 -406.295905) (xy 426.506447 -406.313089) (xy 426.512228 -406.320244)
			(xy 426.533985 -406.345922) (xy 426.571937 -406.401504) (xy 426.602974 -406.461223) (xy 426.62665 -406.524225)
			(xy 426.642626 -406.589604) (xy 426.650673 -406.656424) (xy 426.650676 -406.723728) (xy 426.650669 -406.723789)
			(xy 429.928714 -406.723789) (xy 429.928717 -406.656363) (xy 429.936796 -406.589422) (xy 429.952835 -406.523931)
			(xy 429.976604 -406.460832) (xy 430.00776 -406.401036) (xy 430.045853 -406.345401) (xy 430.06772 -406.319736)
			(xy 430.073529 -406.312599) (xy 430.080035 -406.295402) (xy 430.08042 -406.286208) (xy 430.08042 -405.793956)
			(xy 430.080027 -405.784767) (xy 430.073501 -405.767583) (xy 430.06772 -405.760428) (xy 430.045851 -405.734766)
			(xy 430.007761 -405.679132) (xy 429.97661 -405.619335) (xy 429.952845 -405.556238) (xy 429.936809 -405.490748)
			(xy 429.928733 -405.423809) (xy 429.928734 -405.356385) (xy 429.93681 -405.289446) (xy 429.952847 -405.223956)
			(xy 429.976612 -405.160859) (xy 430.007765 -405.101063) (xy 430.045855 -405.045429) (xy 430.06772 -405.019764)
			(xy 430.073517 -405.012619) (xy 430.080031 -404.995428) (xy 430.08042 -404.986236) (xy 430.08042 -404.828756)
			(xy 430.08085 -404.818642) (xy 430.088605 -404.799959) (xy 430.102919 -404.785665) (xy 430.121613 -404.777935)
			(xy 430.131728 -404.777448) (xy 430.848008 -404.777448) (xy 430.858111 -404.777977) (xy 430.876779 -404.785708)
			(xy 430.891072 -404.799991) (xy 430.898815 -404.818654) (xy 430.899316 -404.828756) (xy 430.899316 -404.986236)
			(xy 430.899705 -404.995425) (xy 430.906233 -405.01261) (xy 430.912016 -405.019764) (xy 430.933875 -405.045433)
			(xy 430.971963 -405.101067) (xy 431.003113 -405.160863) (xy 431.026877 -405.223959) (xy 431.042912 -405.289448)
			(xy 431.050988 -405.356385) (xy 431.050989 -405.423809) (xy 431.042913 -405.490746) (xy 431.026879 -405.556235)
			(xy 431.003116 -405.619331) (xy 431.000867 -405.623648) (xy 432.128891 -405.623648) (xy 432.128892 -405.556343)
			(xy 432.136937 -405.489519) (xy 432.152911 -405.424136) (xy 432.176585 -405.361132) (xy 432.207621 -405.301408)
			(xy 432.245571 -405.245822) (xy 432.26736 -405.22017) (xy 432.273159 -405.213027) (xy 432.279671 -405.195835)
			(xy 432.28006 -405.186642) (xy 432.28006 -404.693374) (xy 432.279649 -404.684187) (xy 432.273134 -404.667004)
			(xy 432.26736 -404.659846) (xy 432.245593 -404.634176) (xy 432.207643 -404.578593) (xy 432.176607 -404.518872)
			(xy 432.152932 -404.45587) (xy 432.136957 -404.390489) (xy 432.128911 -404.323668) (xy 432.128909 -404.256365)
			(xy 432.136951 -404.189543) (xy 432.152922 -404.124162) (xy 432.176594 -404.061158) (xy 432.207626 -404.001436)
			(xy 432.245573 -403.94585) (xy 432.26736 -403.920198) (xy 432.273147 -403.913047) (xy 432.279666 -403.895861)
			(xy 432.28006 -403.88667) (xy 432.28006 -403.728682) (xy 432.28045 -403.718507) (xy 432.288245 -403.699707)
			(xy 432.302641 -403.685322) (xy 432.321446 -403.677542) (xy 432.331622 -403.67712) (xy 433.047902 -403.67712)
			(xy 433.058058 -403.677631) (xy 433.076823 -403.685403) (xy 433.091188 -403.699763) (xy 433.098965 -403.718526)
			(xy 433.099464 -403.728682) (xy 433.099464 -403.88667) (xy 433.099897 -403.895855) (xy 433.106396 -403.913039)
			(xy 433.112164 -403.920198) (xy 433.133973 -403.945832) (xy 433.171921 -404.001421) (xy 433.202954 -404.061147)
			(xy 433.226625 -404.124154) (xy 433.242596 -404.189539) (xy 433.250639 -404.256363) (xy 433.250637 -404.32367)
			(xy 433.24259 -404.390494) (xy 433.226615 -404.455877) (xy 433.20294 -404.518883) (xy 433.171904 -404.578607)
			(xy 433.133953 -404.634194) (xy 433.112164 -404.659846) (xy 433.106361 -404.666986) (xy 433.099851 -404.684181)
			(xy 433.099464 -404.693374) (xy 433.099464 -405.186642) (xy 433.099862 -405.19583) (xy 433.106385 -405.213014)
			(xy 433.112164 -405.22017) (xy 433.133946 -405.245827) (xy 433.171895 -405.301413) (xy 433.202928 -405.361136)
			(xy 433.226601 -405.42414) (xy 433.242574 -405.489521) (xy 433.250619 -405.556343) (xy 433.250619 -405.623648)
			(xy 433.242576 -405.69047) (xy 433.226604 -405.755852) (xy 433.202932 -405.818856) (xy 433.171899 -405.878579)
			(xy 433.133951 -405.934166) (xy 433.112164 -405.959818) (xy 433.106373 -405.966967) (xy 433.099856 -405.984155)
			(xy 433.099464 -405.993346) (xy 433.099464 -406.151334) (xy 433.098995 -406.161494) (xy 433.091209 -406.180263)
			(xy 433.076836 -406.194627) (xy 433.058062 -406.202401) (xy 433.047902 -406.202896) (xy 432.331622 -406.202896)
			(xy 432.32147 -406.20235) (xy 432.302708 -406.194589) (xy 432.288343 -406.180239) (xy 432.280561 -406.161486)
			(xy 432.28006 -406.151334) (xy 432.28006 -405.993346) (xy 432.279614 -405.984163) (xy 432.273124 -405.966979)
			(xy 432.26736 -405.959818) (xy 432.245566 -405.934171) (xy 432.207616 -405.878584) (xy 432.176582 -405.81886)
			(xy 432.152908 -405.755855) (xy 432.136935 -405.690472) (xy 432.128891 -405.623648) (xy 431.000867 -405.623648)
			(xy 430.971966 -405.679128) (xy 430.933879 -405.734762) (xy 430.912016 -405.760428) (xy 430.906227 -405.767579)
			(xy 430.899707 -405.784765) (xy 430.899316 -405.793956) (xy 430.899316 -406.286208) (xy 430.899719 -406.295396)
			(xy 430.906237 -406.31258) (xy 430.912016 -406.319736) (xy 430.933848 -406.345427) (xy 430.971937 -406.401059)
			(xy 431.003088 -406.460851) (xy 431.026853 -406.523945) (xy 431.04289 -406.58943) (xy 431.050968 -406.656366)
			(xy 431.050971 -406.723729) (xy 434.329033 -406.723729) (xy 434.329036 -406.656422) (xy 434.337083 -406.589598)
			(xy 434.353058 -406.524215) (xy 434.376733 -406.461209) (xy 434.407769 -406.401484) (xy 434.445719 -406.345897)
			(xy 434.467508 -406.320244) (xy 434.473312 -406.313104) (xy 434.479822 -406.295909) (xy 434.480208 -406.286716)
			(xy 434.480208 -405.793448) (xy 434.479773 -405.784263) (xy 434.473276 -405.767079) (xy 434.467508 -405.75992)
			(xy 434.445717 -405.734271) (xy 434.407771 -405.678683) (xy 434.376739 -405.618959) (xy 434.353068 -405.555954)
			(xy 434.337096 -405.490572) (xy 434.329053 -405.423749) (xy 434.329053 -405.356445) (xy 434.337097 -405.289622)
			(xy 434.35307 -405.22424) (xy 434.376742 -405.161236) (xy 434.407774 -405.101512) (xy 434.445721 -405.045925)
			(xy 434.467508 -405.020272) (xy 434.4733 -405.013124) (xy 434.479817 -404.995935) (xy 434.480208 -404.986744)
			(xy 434.480208 -404.828756) (xy 434.480586 -404.818598) (xy 434.488397 -404.799843) (xy 434.502807 -404.785521)
			(xy 434.52161 -404.777824) (xy 434.53177 -404.777448) (xy 435.24805 -404.777448) (xy 435.258175 -404.777968)
			(xy 435.276896 -404.785681) (xy 435.291254 -404.799957) (xy 435.299074 -404.818634) (xy 435.299612 -404.828756)
			(xy 435.299612 -404.986744) (xy 435.299998 -404.995934) (xy 435.306528 -405.013118) (xy 435.312312 -405.020272)
			(xy 435.334097 -405.045927) (xy 435.372049 -405.101512) (xy 435.403086 -405.161234) (xy 435.426761 -405.224239)
			(xy 435.442735 -405.289621) (xy 435.450781 -405.356444) (xy 435.450781 -405.42375) (xy 435.442736 -405.490573)
			(xy 435.426762 -405.555956) (xy 435.403088 -405.61896) (xy 435.372052 -405.678683) (xy 435.334101 -405.734269)
			(xy 435.312312 -405.75992) (xy 435.306526 -405.767073) (xy 435.300005 -405.784257) (xy 435.299612 -405.793448)
			(xy 435.299612 -406.286716) (xy 435.300012 -406.295904) (xy 435.306532 -406.313089) (xy 435.312312 -406.320244)
			(xy 435.33407 -406.345921) (xy 435.372023 -406.401503) (xy 435.40306 -406.461223) (xy 435.426737 -406.524224)
			(xy 435.442713 -406.589604) (xy 435.450761 -406.656424) (xy 435.450764 -406.723728) (xy 435.442722 -406.790549)
			(xy 435.426751 -406.85593) (xy 435.40308 -406.918933) (xy 435.372048 -406.978656) (xy 435.334099 -407.034241)
			(xy 435.312312 -407.059892) (xy 435.306538 -407.067053) (xy 435.300009 -407.084231) (xy 435.299612 -407.09342)
			(xy 435.299612 -407.251408) (xy 435.299185 -407.261561) (xy 435.291389 -407.280311) (xy 435.276994 -407.294634)
			(xy 435.258205 -407.302335) (xy 435.24805 -407.302716) (xy 434.53177 -407.302716) (xy 434.521636 -407.302297)
			(xy 434.502906 -407.294551) (xy 434.488549 -407.280244) (xy 434.480739 -407.26154) (xy 434.480208 -407.251408)
			(xy 434.480208 -407.09342) (xy 434.479786 -407.084234) (xy 434.47328 -407.06705) (xy 434.467508 -407.059892)
			(xy 434.44569 -407.034265) (xy 434.407744 -406.978674) (xy 434.376714 -406.918947) (xy 434.353044 -406.855939)
			(xy 434.337074 -406.790554) (xy 434.329033 -406.723729) (xy 431.050971 -406.723729) (xy 431.050971 -406.723786)
			(xy 431.042899 -406.790722) (xy 431.026867 -406.856209) (xy 431.003107 -406.919305) (xy 430.971961 -406.9791)
			(xy 430.933877 -407.034735) (xy 430.912016 -407.0604) (xy 430.906239 -407.067559) (xy 430.899712 -407.084739)
			(xy 430.899316 -407.093928) (xy 430.899316 -407.251408) (xy 430.898822 -407.261515) (xy 430.891084 -407.28019)
			(xy 430.87679 -407.294484) (xy 430.858115 -407.302222) (xy 430.848008 -407.302716) (xy 430.131728 -407.302716)
			(xy 430.121609 -407.302262) (xy 430.102909 -407.294526) (xy 430.088595 -407.280221) (xy 430.080845 -407.261526)
			(xy 430.08042 -407.251408) (xy 430.08042 -407.093928) (xy 430.079992 -407.084743) (xy 430.07349 -407.067559)
			(xy 430.06772 -407.0604) (xy 430.045824 -407.034761) (xy 430.007735 -406.979123) (xy 429.976584 -406.919324)
			(xy 429.952821 -406.856223) (xy 429.936787 -406.790731) (xy 429.928714 -406.723789) (xy 426.650669 -406.723789)
			(xy 426.642634 -406.790548) (xy 426.626664 -406.855929) (xy 426.602993 -406.918933) (xy 426.571962 -406.978655)
			(xy 426.534015 -407.03424) (xy 426.512228 -407.059892) (xy 426.506444 -407.067045) (xy 426.499924 -407.08423)
			(xy 426.499528 -407.09342) (xy 426.499528 -407.251408) (xy 426.499085 -407.261559) (xy 426.491292 -407.280306)
			(xy 426.476903 -407.294628) (xy 426.458119 -407.302333) (xy 426.447966 -407.302716) (xy 425.731686 -407.302716)
			(xy 425.721553 -407.302283) (xy 425.702823 -407.294543) (xy 425.688466 -407.28024) (xy 425.680655 -407.261539)
			(xy 425.680124 -407.251408) (xy 425.680124 -407.09342) (xy 425.679699 -407.084235) (xy 425.673195 -407.06705)
			(xy 425.667424 -407.059892) (xy 425.645605 -407.034266) (xy 425.607658 -406.978675) (xy 425.576627 -406.918948)
			(xy 425.552957 -406.85594) (xy 425.536987 -406.790555) (xy 425.528945 -406.72373) (xy 422.250883 -406.72373)
			(xy 422.250883 -406.723786) (xy 422.242811 -406.790722) (xy 422.22678 -406.856209) (xy 422.203021 -406.919304)
			(xy 422.171876 -406.9791) (xy 422.133793 -407.034734) (xy 422.111932 -407.0604) (xy 422.106145 -407.067551)
			(xy 422.099626 -407.084737) (xy 422.099232 -407.093928) (xy 422.099232 -407.251408) (xy 422.098722 -407.261513)
			(xy 422.090988 -407.280185) (xy 422.076699 -407.294479) (xy 422.058029 -407.302219) (xy 422.047924 -407.302716)
			(xy 421.331644 -407.302716) (xy 421.321526 -407.302248) (xy 421.302827 -407.294518) (xy 421.288512 -407.280217)
			(xy 421.280762 -407.261525) (xy 421.280336 -407.251408) (xy 421.280336 -407.093928) (xy 421.279904 -407.084743)
			(xy 421.273405 -407.067559) (xy 421.267636 -407.0604) (xy 421.245739 -407.034761) (xy 421.207649 -406.979124)
			(xy 421.176498 -406.919324) (xy 421.152734 -406.856224) (xy 421.1367 -406.790731) (xy 421.128626 -406.723789)
			(xy 414.525968 -406.723789) (xy 414.525968 -409.523827) (xy 418.928991 -409.523827) (xy 418.928995 -409.456519)
			(xy 418.937043 -409.389693) (xy 418.953021 -409.324308) (xy 418.9767 -409.261302) (xy 419.00774 -409.201577)
			(xy 419.045697 -409.145992) (xy 419.067488 -409.12034) (xy 419.073291 -409.113199) (xy 419.079802 -409.096005)
			(xy 419.080188 -409.086812) (xy 419.080188 -408.593544) (xy 419.079759 -408.584359) (xy 419.073259 -408.567174)
			(xy 419.067488 -408.560016) (xy 419.045691 -408.534371) (xy 419.007739 -408.478785) (xy 418.976704 -408.419061)
			(xy 418.953029 -408.356055) (xy 418.937055 -408.290671) (xy 418.929011 -408.223847) (xy 418.929012 -408.156541)
			(xy 418.937057 -408.089717) (xy 418.953033 -408.024333) (xy 418.976708 -407.961328) (xy 419.007745 -407.901605)
			(xy 419.045698 -407.84602) (xy 419.067488 -407.820368) (xy 419.073279 -407.813219) (xy 419.079797 -407.796031)
			(xy 419.080188 -407.78684) (xy 419.080188 -407.628852) (xy 419.080582 -407.618696) (xy 419.088391 -407.599945)
			(xy 419.102796 -407.585624) (xy 419.121592 -407.577924) (xy 419.13175 -407.577544) (xy 419.84803 -407.577544)
			(xy 419.858159 -407.578002) (xy 419.876882 -407.58574) (xy 419.891237 -407.600035) (xy 419.899055 -407.618725)
			(xy 419.899592 -407.628852) (xy 419.899592 -407.78684) (xy 419.899985 -407.796029) (xy 419.906511 -407.813213)
			(xy 419.912292 -407.820368) (xy 419.934071 -407.846027) (xy 419.972018 -407.901613) (xy 420.00305 -407.961336)
			(xy 420.026722 -408.02434) (xy 420.042694 -408.089721) (xy 420.050739 -408.156542) (xy 420.050739 -408.223846)
			(xy 420.042697 -408.290667) (xy 420.026725 -408.356049) (xy 420.003055 -408.419053) (xy 419.972024 -408.478776)
			(xy 419.934078 -408.534363) (xy 419.912292 -408.560016) (xy 419.906505 -408.567168) (xy 419.899985 -408.584353)
			(xy 419.899592 -408.593544) (xy 419.899592 -409.086812) (xy 419.899998 -409.096) (xy 419.906515 -409.113184)
			(xy 419.912292 -409.12034) (xy 419.934043 -409.146022) (xy 419.971991 -409.201605) (xy 420.003024 -409.261324)
			(xy 420.026698 -409.324325) (xy 420.042672 -409.389703) (xy 420.050719 -409.456522) (xy 420.050722 -409.523824)
			(xy 420.042682 -409.590643) (xy 420.026714 -409.656023) (xy 420.003047 -409.719026) (xy 419.972019 -409.778749)
			(xy 419.934077 -409.834336) (xy 419.912292 -409.859988) (xy 419.906475 -409.867118) (xy 419.899973 -409.88432)
			(xy 419.899592 -409.893516) (xy 419.899592 -410.051504) (xy 419.899181 -410.061659) (xy 419.891383 -410.080413)
			(xy 419.876983 -410.094737) (xy 419.858187 -410.102435) (xy 419.84803 -410.102812) (xy 419.13175 -410.102812)
			(xy 419.121633 -410.102234) (xy 419.102923 -410.094532) (xy 419.088567 -410.080274) (xy 419.080736 -410.061618)
			(xy 419.080188 -410.051504) (xy 419.080188 -409.893516) (xy 419.079773 -409.884329) (xy 419.073263 -409.867145)
			(xy 419.067488 -409.859988) (xy 419.045663 -409.834366) (xy 419.007713 -409.778776) (xy 418.976678 -409.719049)
			(xy 418.953005 -409.65604) (xy 418.937033 -409.590654) (xy 418.928991 -409.523827) (xy 414.525968 -409.523827)
			(xy 414.525968 -410.623701) (xy 421.128637 -410.623701) (xy 421.128638 -410.556275) (xy 421.136716 -410.489335)
			(xy 421.152755 -410.423845) (xy 421.176522 -410.360747) (xy 421.207677 -410.300951) (xy 421.24577 -410.245317)
			(xy 421.267636 -410.219652) (xy 421.27344 -410.212512) (xy 421.279949 -410.195317) (xy 421.280336 -410.186124)
			(xy 421.280336 -409.693872) (xy 421.279931 -409.684684) (xy 421.273413 -409.667501) (xy 421.267636 -409.660344)
			(xy 421.245783 -409.63467) (xy 421.207691 -409.579037) (xy 421.176538 -409.519243) (xy 421.152771 -409.456147)
			(xy 421.136734 -409.390659) (xy 421.128657 -409.323721) (xy 421.128656 -409.256297) (xy 421.136731 -409.189359)
			(xy 421.152766 -409.12387) (xy 421.176531 -409.060774) (xy 421.207682 -409.000978) (xy 421.245771 -408.945345)
			(xy 421.267636 -408.91968) (xy 421.273428 -408.912532) (xy 421.279945 -408.895343) (xy 421.280336 -408.886152)
			(xy 421.280336 -408.728672) (xy 421.280694 -408.718543) (xy 421.288458 -408.699832) (xy 421.302793 -408.685517)
			(xy 421.321515 -408.67778) (xy 421.331644 -408.677364) (xy 422.047924 -408.677364) (xy 422.05803 -408.677864)
			(xy 422.076702 -408.685603) (xy 422.090994 -408.699895) (xy 422.098735 -408.718566) (xy 422.099232 -408.728672)
			(xy 422.099232 -408.886152) (xy 422.09968 -408.895335) (xy 422.106169 -408.912519) (xy 422.111932 -408.91968)
			(xy 422.133807 -408.945336) (xy 422.171893 -409.000973) (xy 422.203041 -409.06077) (xy 422.226803 -409.123868)
			(xy 422.242837 -409.189358) (xy 422.250911 -409.256297) (xy 422.25091 -409.323721) (xy 422.242834 -409.39066)
			(xy 422.226798 -409.456149) (xy 422.203034 -409.519246) (xy 422.200617 -409.523886) (xy 423.328784 -409.523886)
			(xy 423.328787 -409.45646) (xy 423.336866 -409.389519) (xy 423.352905 -409.324029) (xy 423.376672 -409.26093)
			(xy 423.407826 -409.201133) (xy 423.445918 -409.145498) (xy 423.467784 -409.119832) (xy 423.47359 -409.112693)
			(xy 423.4801 -409.095498) (xy 423.480484 -409.086304) (xy 423.480484 -408.594052) (xy 423.480052 -408.584867)
			(xy 423.473554 -408.567682) (xy 423.467784 -408.560524) (xy 423.445913 -408.534865) (xy 423.407825 -408.479229)
			(xy 423.376676 -408.419432) (xy 423.352913 -408.356334) (xy 423.336878 -408.290845) (xy 423.328803 -408.223906)
			(xy 423.328804 -408.156482) (xy 423.336881 -408.089543) (xy 423.352916 -408.024054) (xy 423.376681 -407.960957)
			(xy 423.407832 -407.901161) (xy 423.44592 -407.845526) (xy 423.467784 -407.81986) (xy 423.473578 -407.812713)
			(xy 423.480095 -407.795524) (xy 423.480484 -407.786332) (xy 423.480484 -407.628852) (xy 423.480946 -407.618742)
			(xy 423.488696 -407.600066) (xy 423.503 -407.585774) (xy 423.521682 -407.578038) (xy 423.531792 -407.577544)
			(xy 424.248072 -407.577544) (xy 424.258172 -407.578106) (xy 424.276839 -407.585825) (xy 424.291133 -407.600097)
			(xy 424.298879 -407.618753) (xy 424.29938 -407.628852) (xy 424.29938 -407.786332) (xy 424.299779 -407.79552)
			(xy 424.306301 -407.812704) (xy 424.31208 -407.81986) (xy 424.333937 -407.845531) (xy 424.372027 -407.901165)
			(xy 424.403179 -407.96096) (xy 424.426945 -408.024056) (xy 424.442981 -408.089544) (xy 424.451058 -408.156482)
			(xy 424.451059 -408.223906) (xy 424.442984 -408.290844) (xy 424.426948 -408.356333) (xy 424.403184 -408.419429)
			(xy 424.372033 -408.479225) (xy 424.333944 -408.534859) (xy 424.31208 -408.560524) (xy 424.306288 -408.567673)
			(xy 424.299771 -408.584861) (xy 424.29938 -408.594052) (xy 424.29938 -409.086304) (xy 424.299792 -409.095491)
			(xy 424.306305 -409.112675) (xy 424.31208 -409.119832) (xy 424.333909 -409.145526) (xy 424.372 -409.201156)
			(xy 424.403154 -409.260948) (xy 424.426921 -409.324041) (xy 424.442959 -409.389527) (xy 424.451039 -409.456462)
			(xy 424.451042 -409.523884) (xy 424.442969 -409.59082) (xy 424.426937 -409.656307) (xy 424.403176 -409.719403)
			(xy 424.372028 -409.779198) (xy 424.333943 -409.834831) (xy 424.31208 -409.860496) (xy 424.3063 -409.867653)
			(xy 424.299776 -409.884835) (xy 424.29938 -409.894024) (xy 424.29938 -410.051504) (xy 424.298987 -410.061629)
			(xy 424.291234 -410.080337) (xy 424.27691 -410.094651) (xy 424.258197 -410.102393) (xy 424.248072 -410.102812)
			(xy 423.531792 -410.102812) (xy 423.521684 -410.102322) (xy 423.503008 -410.094584) (xy 423.488714 -410.080288)
			(xy 423.480978 -410.061612) (xy 423.480484 -410.051504) (xy 423.480484 -409.894024) (xy 423.480066 -409.884838)
			(xy 423.473558 -409.867653) (xy 423.467784 -409.860496) (xy 423.445885 -409.83486) (xy 423.407799 -409.779221)
			(xy 423.37665 -409.71942) (xy 423.352889 -409.65632) (xy 423.336856 -409.590827) (xy 423.328784 -409.523886)
			(xy 422.200617 -409.523886) (xy 422.171884 -409.579043) (xy 422.133796 -409.634678) (xy 422.111932 -409.660344)
			(xy 422.106126 -409.667482) (xy 422.099619 -409.684678) (xy 422.099232 -409.693872) (xy 422.099232 -410.186124)
			(xy 422.099646 -410.19531) (xy 422.106159 -410.212494) (xy 422.111932 -410.219652) (xy 422.133779 -410.245331)
			(xy 422.171866 -410.300964) (xy 422.203016 -410.360759) (xy 422.22678 -410.423854) (xy 422.242815 -410.489341)
			(xy 422.250892 -410.556277) (xy 422.250893 -410.623641) (xy 425.528957 -410.623641) (xy 425.528958 -410.556335)
			(xy 425.537003 -410.489512) (xy 425.552978 -410.424129) (xy 425.576652 -410.361123) (xy 425.607686 -410.301399)
			(xy 425.645636 -410.245812) (xy 425.667424 -410.22016) (xy 425.673223 -410.213017) (xy 425.679735 -410.195825)
			(xy 425.680124 -410.186632) (xy 425.680124 -409.693364) (xy 425.679726 -409.684176) (xy 425.673203 -409.666992)
			(xy 425.667424 -409.659836) (xy 425.645648 -409.634174) (xy 425.6077 -409.578589) (xy 425.576667 -409.518866)
			(xy 425.552994 -409.455863) (xy 425.537021 -409.390482) (xy 425.528976 -409.323661) (xy 425.528975 -409.256357)
			(xy 425.537018 -409.189536) (xy 425.552989 -409.124154) (xy 425.57666 -409.06115) (xy 425.607691 -409.001427)
			(xy 425.645637 -408.94584) (xy 425.667424 -408.920188) (xy 425.673211 -408.913036) (xy 425.679731 -408.895851)
			(xy 425.680124 -408.88666) (xy 425.680124 -408.728672) (xy 425.680499 -408.718513) (xy 425.688308 -408.699755)
			(xy 425.70272 -408.685432) (xy 425.721525 -408.677738) (xy 425.731686 -408.677364) (xy 426.447966 -408.677364)
			(xy 426.458093 -408.677855) (xy 426.476818 -408.685576) (xy 426.491177 -408.699862) (xy 426.498993 -408.718547)
			(xy 426.499528 -408.728672) (xy 426.499528 -408.88666) (xy 426.499951 -408.895846) (xy 426.506455 -408.913031)
			(xy 426.512228 -408.920188) (xy 426.534028 -408.94583) (xy 426.571979 -409.001417) (xy 426.603014 -409.061142)
			(xy 426.626687 -409.124148) (xy 426.64266 -409.189532) (xy 426.650704 -409.256356) (xy 426.650703 -409.323662)
			(xy 426.642657 -409.390486) (xy 426.626682 -409.45587) (xy 426.603006 -409.518875) (xy 426.600433 -409.523827)
			(xy 427.729079 -409.523827) (xy 427.729082 -409.456519) (xy 427.73713 -409.389693) (xy 427.753108 -409.324308)
			(xy 427.776786 -409.261302) (xy 427.807826 -409.201578) (xy 427.845781 -409.145992) (xy 427.867572 -409.12034)
			(xy 427.873385 -409.113207) (xy 427.879888 -409.096007) (xy 427.880272 -409.086812) (xy 427.880272 -408.593544)
			(xy 427.879847 -408.584358) (xy 427.873344 -408.567174) (xy 427.867572 -408.560016) (xy 427.845776 -408.534371)
			(xy 427.807825 -408.478784) (xy 427.77679 -408.41906) (xy 427.753116 -408.356054) (xy 427.737143 -408.290671)
			(xy 427.729099 -408.223847) (xy 427.7291 -408.156541) (xy 427.737145 -408.089717) (xy 427.75312 -408.024334)
			(xy 427.776795 -407.961329) (xy 427.807831 -407.901606) (xy 427.845783 -407.84602) (xy 427.867572 -407.820368)
			(xy 427.873373 -407.813227) (xy 427.879883 -407.796033) (xy 427.880272 -407.78684) (xy 427.880272 -407.628852)
			(xy 427.880682 -407.618698) (xy 427.888488 -407.59995) (xy 427.902887 -407.58563) (xy 427.921678 -407.577927)
			(xy 427.931834 -407.577544) (xy 428.648114 -407.577544) (xy 428.658242 -407.578015) (xy 428.676964 -407.585749)
			(xy 428.69132 -407.600039) (xy 428.699138 -407.618726) (xy 428.699676 -407.628852) (xy 428.699676 -407.78684)
			(xy 428.700072 -407.796029) (xy 428.706596 -407.813212) (xy 428.712376 -407.820368) (xy 428.734155 -407.846027)
			(xy 428.772104 -407.901613) (xy 428.803136 -407.961335) (xy 428.826809 -408.024339) (xy 428.842782 -408.08972)
			(xy 428.850827 -408.156542) (xy 428.850827 -408.223846) (xy 428.842784 -408.290668) (xy 428.826813 -408.356049)
			(xy 428.803141 -408.419054) (xy 428.77211 -408.478777) (xy 428.734163 -408.534364) (xy 428.712376 -408.560016)
			(xy 428.706587 -408.567167) (xy 428.700069 -408.584353) (xy 428.699676 -408.593544) (xy 428.699676 -409.086812)
			(xy 428.700086 -409.095999) (xy 428.7066 -409.113183) (xy 428.712376 -409.12034) (xy 428.734128 -409.146022)
			(xy 428.772077 -409.201604) (xy 428.803111 -409.261324) (xy 428.826785 -409.324324) (xy 428.84276 -409.389703)
			(xy 428.850806 -409.456522) (xy 428.85081 -409.523824) (xy 428.842769 -409.590644) (xy 428.826801 -409.656024)
			(xy 428.803133 -409.719027) (xy 428.772104 -409.778749) (xy 428.734161 -409.834335) (xy 428.712376 -409.859988)
			(xy 428.706557 -409.867117) (xy 428.700056 -409.88432) (xy 428.699676 -409.893516) (xy 428.699676 -410.051504)
			(xy 428.699281 -410.061661) (xy 428.69148 -410.080418) (xy 428.677074 -410.094742) (xy 428.658274 -410.102438)
			(xy 428.648114 -410.102812) (xy 427.931834 -410.102812) (xy 427.921716 -410.102247) (xy 427.903005 -410.09454)
			(xy 427.88865 -410.080278) (xy 427.88082 -410.061619) (xy 427.880272 -410.051504) (xy 427.880272 -409.893516)
			(xy 427.879861 -409.884329) (xy 427.873349 -409.867144) (xy 427.867572 -409.859988) (xy 427.845748 -409.834366)
			(xy 427.807798 -409.778776) (xy 427.776764 -409.719048) (xy 427.753092 -409.65604) (xy 427.73712 -409.590654)
			(xy 427.729079 -409.523827) (xy 426.600433 -409.523827) (xy 426.57197 -409.578598) (xy 426.534017 -409.634184)
			(xy 426.512228 -409.659836) (xy 426.506425 -409.666976) (xy 426.499916 -409.684171) (xy 426.499528 -409.693364)
			(xy 426.499528 -410.186632) (xy 426.499917 -410.195822) (xy 426.506445 -410.213006) (xy 426.512228 -410.22016)
			(xy 426.534001 -410.245825) (xy 426.571952 -410.301409) (xy 426.602988 -410.36113) (xy 426.626663 -410.424133)
			(xy 426.642638 -410.489514) (xy 426.650684 -410.556336) (xy 426.650686 -410.62364) (xy 426.650679 -410.623701)
			(xy 429.928725 -410.623701) (xy 429.928726 -410.556275) (xy 429.936804 -410.489336) (xy 429.952842 -410.423845)
			(xy 429.976609 -410.360748) (xy 430.007762 -410.300951) (xy 430.045854 -410.245317) (xy 430.06772 -410.219652)
			(xy 430.073522 -410.212511) (xy 430.080033 -410.195317) (xy 430.08042 -410.186124) (xy 430.08042 -409.693872)
			(xy 430.080019 -409.684684) (xy 430.073498 -409.6675) (xy 430.06772 -409.660344) (xy 430.045867 -409.634669)
			(xy 430.007777 -409.579037) (xy 429.976624 -409.519242) (xy 429.952859 -409.456146) (xy 429.936822 -409.390658)
			(xy 429.928745 -409.323721) (xy 429.928744 -409.256297) (xy 429.936819 -409.18936) (xy 429.952853 -409.123871)
			(xy 429.976617 -409.060775) (xy 430.007767 -409.000979) (xy 430.045856 -408.945345) (xy 430.06772 -408.91968)
			(xy 430.07351 -408.91253) (xy 430.080028 -408.895343) (xy 430.08042 -408.886152) (xy 430.08042 -408.728672)
			(xy 430.080863 -408.718559) (xy 430.088613 -408.699876) (xy 430.102923 -408.685582) (xy 430.121614 -408.677852)
			(xy 430.131728 -408.677364) (xy 430.848008 -408.677364) (xy 430.858113 -408.677878) (xy 430.876784 -408.685611)
			(xy 430.891077 -408.699899) (xy 430.898818 -408.718567) (xy 430.899316 -408.728672) (xy 430.899316 -408.886152)
			(xy 430.899745 -408.895337) (xy 430.906245 -408.912522) (xy 430.912016 -408.91968) (xy 430.933891 -408.945336)
			(xy 430.971979 -409.000972) (xy 431.003128 -409.06077) (xy 431.026891 -409.123868) (xy 431.042925 -409.189358)
			(xy 431.050999 -409.256297) (xy 431.050998 -409.323721) (xy 431.042922 -409.39066) (xy 431.026885 -409.456149)
			(xy 431.00312 -409.519247) (xy 431.000734 -409.523827) (xy 432.12887 -409.523827) (xy 432.128873 -409.456519)
			(xy 432.136921 -409.389693) (xy 432.152898 -409.324309) (xy 432.176576 -409.261303) (xy 432.207615 -409.201578)
			(xy 432.245569 -409.145992) (xy 432.26736 -409.12034) (xy 432.273172 -409.113206) (xy 432.279676 -409.096007)
			(xy 432.28006 -409.086812) (xy 432.28006 -408.593544) (xy 432.279615 -408.584361) (xy 432.273124 -408.567177)
			(xy 432.26736 -408.560016) (xy 432.245564 -408.53437) (xy 432.207614 -408.478784) (xy 432.17658 -408.419059)
			(xy 432.152907 -408.356054) (xy 432.136934 -408.290671) (xy 432.12889 -408.223847) (xy 432.128891 -408.156541)
			(xy 432.136936 -408.089717) (xy 432.15291 -408.024335) (xy 432.176585 -407.96133) (xy 432.20762 -407.901606)
			(xy 432.245571 -407.84602) (xy 432.26736 -407.820368) (xy 432.27316 -407.813226) (xy 432.279671 -407.796033)
			(xy 432.28006 -407.78684) (xy 432.28006 -407.628852) (xy 432.280482 -407.6187) (xy 432.288286 -407.599954)
			(xy 432.302681 -407.585634) (xy 432.321468 -407.577929) (xy 432.331622 -407.577544) (xy 433.047902 -407.577544)
			(xy 433.058029 -407.578025) (xy 433.076751 -407.585754) (xy 433.091108 -407.600042) (xy 433.098926 -407.618727)
			(xy 433.099464 -407.628852) (xy 433.099464 -407.78684) (xy 433.099863 -407.796028) (xy 433.106385 -407.813212)
			(xy 433.112164 -407.820368) (xy 433.133944 -407.846027) (xy 433.171893 -407.901612) (xy 433.202926 -407.961335)
			(xy 433.226599 -408.024339) (xy 433.242573 -408.08972) (xy 433.250618 -408.156542) (xy 433.250618 -408.223846)
			(xy 433.242575 -408.290668) (xy 433.226603 -408.35605) (xy 433.202931 -408.419054) (xy 433.171899 -408.478778)
			(xy 433.133951 -408.534364) (xy 433.112164 -408.560016) (xy 433.106374 -408.567165) (xy 433.099856 -408.584353)
			(xy 433.099464 -408.593544) (xy 433.099464 -409.086812) (xy 433.099876 -409.095999) (xy 433.106389 -409.113183)
			(xy 433.112164 -409.12034) (xy 433.133916 -409.146021) (xy 433.171866 -409.201604) (xy 433.2029 -409.261323)
			(xy 433.226575 -409.324324) (xy 433.24255 -409.389703) (xy 433.250597 -409.456522) (xy 433.250601 -409.523824)
			(xy 433.24256 -409.590644) (xy 433.226591 -409.656024) (xy 433.202922 -409.719027) (xy 433.171894 -409.77875)
			(xy 433.133949 -409.834336) (xy 433.112164 -409.859988) (xy 433.106343 -409.867116) (xy 433.099844 -409.88432)
			(xy 433.099464 -409.893516) (xy 433.099464 -410.051504) (xy 433.099081 -410.061663) (xy 433.091277 -410.080422)
			(xy 433.076868 -410.094747) (xy 433.058063 -410.10244) (xy 433.047902 -410.102812) (xy 432.331622 -410.102812)
			(xy 432.321503 -410.102257) (xy 432.302792 -410.094546) (xy 432.288437 -410.080281) (xy 432.280608 -410.06162)
			(xy 432.28006 -410.051504) (xy 432.28006 -409.893516) (xy 432.279629 -409.884331) (xy 432.273128 -409.867147)
			(xy 432.26736 -409.859988) (xy 432.245536 -409.834365) (xy 432.207587 -409.778775) (xy 432.176554 -409.719048)
			(xy 432.152882 -409.656039) (xy 432.136911 -409.590653) (xy 432.12887 -409.523827) (xy 431.000734 -409.523827)
			(xy 430.971969 -409.579043) (xy 430.93388 -409.634678) (xy 430.912016 -409.660344) (xy 430.90622 -409.66749)
			(xy 430.899705 -409.68468) (xy 430.899316 -409.693872) (xy 430.899316 -410.186124) (xy 430.899711 -410.195313)
			(xy 430.906235 -410.212497) (xy 430.912016 -410.219652) (xy 430.933864 -410.24533) (xy 430.971952 -410.300963)
			(xy 431.003102 -410.360758) (xy 431.026867 -410.423853) (xy 431.042903 -410.48934) (xy 431.05098 -410.556277)
			(xy 431.050981 -410.623641) (xy 434.329044 -410.623641) (xy 434.329046 -410.556335) (xy 434.337091 -410.489512)
			(xy 434.353065 -410.424129) (xy 434.376738 -410.361124) (xy 434.407772 -410.3014) (xy 434.44572 -410.245813)
			(xy 434.467508 -410.22016) (xy 434.473305 -410.213015) (xy 434.479819 -410.195824) (xy 434.480208 -410.186632)
			(xy 434.480208 -409.693364) (xy 434.479814 -409.684175) (xy 434.473289 -409.666991) (xy 434.467508 -409.659836)
			(xy 434.445733 -409.634174) (xy 434.407786 -409.578588) (xy 434.376754 -409.518866) (xy 434.353082 -409.455862)
			(xy 434.337109 -409.390482) (xy 434.329064 -409.323661) (xy 434.329063 -409.256357) (xy 434.337106 -409.189536)
			(xy 434.353076 -409.124155) (xy 434.376746 -409.061151) (xy 434.407777 -409.001427) (xy 434.445722 -408.945841)
			(xy 434.467508 -408.920188) (xy 434.473293 -408.913035) (xy 434.479814 -408.89585) (xy 434.480208 -408.88666)
			(xy 434.480208 -408.728672) (xy 434.480599 -408.718515) (xy 434.488405 -408.69976) (xy 434.502811 -408.685438)
			(xy 434.521611 -408.67774) (xy 434.53177 -408.677364) (xy 435.24805 -408.677364) (xy 435.258176 -408.677868)
			(xy 435.276901 -408.685584) (xy 435.29126 -408.699866) (xy 435.299077 -408.718548) (xy 435.299612 -408.728672)
			(xy 435.299612 -408.88666) (xy 435.300039 -408.895846) (xy 435.30654 -408.91303) (xy 435.312312 -408.920188)
			(xy 435.334113 -408.94583) (xy 435.372065 -409.001417) (xy 435.4031 -409.061141) (xy 435.426774 -409.124147)
			(xy 435.442748 -409.189531) (xy 435.450792 -409.256356) (xy 435.450791 -409.323662) (xy 435.442745 -409.390487)
			(xy 435.426769 -409.45587) (xy 435.403093 -409.518875) (xy 435.372055 -409.578599) (xy 435.334102 -409.634184)
			(xy 435.312312 -409.659836) (xy 435.306519 -409.666984) (xy 435.300002 -409.684172) (xy 435.299612 -409.693364)
			(xy 435.299612 -410.186632) (xy 435.300004 -410.195821) (xy 435.30653 -410.213006) (xy 435.312312 -410.22016)
			(xy 435.334085 -410.245824) (xy 435.372038 -410.301408) (xy 435.403075 -410.361129) (xy 435.42675 -410.424132)
			(xy 435.442726 -410.489514) (xy 435.450772 -410.556336) (xy 435.450774 -410.62364) (xy 435.44273 -410.690463)
			(xy 435.426758 -410.755845) (xy 435.403084 -410.818849) (xy 435.37205 -410.878571) (xy 435.3341 -410.934157)
			(xy 435.312312 -410.959808) (xy 435.306531 -410.966964) (xy 435.300007 -410.984146) (xy 435.299612 -410.993336)
			(xy 435.299612 -411.151324) (xy 435.299198 -411.161478) (xy 435.291397 -411.180229) (xy 435.276998 -411.194551)
			(xy 435.258206 -411.202252) (xy 435.24805 -411.202632) (xy 434.53177 -411.202632) (xy 434.521638 -411.202197)
			(xy 434.502911 -411.194454) (xy 434.488554 -411.180152) (xy 434.480741 -411.161454) (xy 434.480208 -411.151324)
			(xy 434.480208 -410.993336) (xy 434.479779 -410.984151) (xy 434.473278 -410.966966) (xy 434.467508 -410.959808)
			(xy 434.445706 -410.934168) (xy 434.407759 -410.878579) (xy 434.376728 -410.818854) (xy 434.353058 -410.755848)
			(xy 434.337087 -410.690464) (xy 434.329044 -410.623641) (xy 431.050981 -410.623641) (xy 431.050981 -410.623699)
			(xy 431.042907 -410.690636) (xy 431.026874 -410.756124) (xy 431.003112 -410.81922) (xy 430.971964 -410.879016)
			(xy 430.933878 -410.934651) (xy 430.912016 -410.960316) (xy 430.906232 -410.96747) (xy 430.899709 -410.984654)
			(xy 430.899316 -410.993844) (xy 430.899316 -411.151324) (xy 430.898835 -411.161432) (xy 430.891092 -411.180108)
			(xy 430.876795 -411.194401) (xy 430.858116 -411.202138) (xy 430.848008 -411.202632) (xy 430.131728 -411.202632)
			(xy 430.121611 -411.202162) (xy 430.102914 -411.194429) (xy 430.0886 -411.180129) (xy 430.080848 -411.16144)
			(xy 430.08042 -411.151324) (xy 430.08042 -410.993844) (xy 430.079984 -410.98466) (xy 430.073488 -410.967475)
			(xy 430.06772 -410.960316) (xy 430.04584 -410.934664) (xy 430.00775 -410.879028) (xy 429.976599 -410.81923)
			(xy 429.952835 -410.756132) (xy 429.9368 -410.690641) (xy 429.928725 -410.623701) (xy 426.650679 -410.623701)
			(xy 426.642643 -410.690462) (xy 426.62667 -410.755844) (xy 426.602998 -410.818848) (xy 426.571965 -410.878571)
			(xy 426.534016 -410.934156) (xy 426.512228 -410.959808) (xy 426.506437 -410.966957) (xy 426.499921 -410.984145)
			(xy 426.499528 -410.993336) (xy 426.499528 -411.151324) (xy 426.499099 -411.161476) (xy 426.4913 -411.180224)
			(xy 426.476907 -411.194545) (xy 426.45812 -411.202249) (xy 426.447966 -411.202632) (xy 425.731686 -411.202632)
			(xy 425.721555 -411.202184) (xy 425.702828 -411.194446) (xy 425.688472 -411.180148) (xy 425.680658 -411.161453)
			(xy 425.680124 -411.151324) (xy 425.680124 -410.993336) (xy 425.679691 -410.984151) (xy 425.673193 -410.966967)
			(xy 425.667424 -410.959808) (xy 425.645621 -410.934169) (xy 425.607674 -410.87858) (xy 425.576642 -410.818855)
			(xy 425.552971 -410.755848) (xy 425.536999 -410.690465) (xy 425.528957 -410.623641) (xy 422.250893 -410.623641)
			(xy 422.250893 -410.623699) (xy 422.242819 -410.690635) (xy 422.226787 -410.756123) (xy 422.203026 -410.819219)
			(xy 422.171879 -410.879015) (xy 422.133794 -410.93465) (xy 422.111932 -410.960316) (xy 422.106138 -410.967463)
			(xy 422.099624 -410.984652) (xy 422.099232 -410.993844) (xy 422.099232 -411.151324) (xy 422.098735 -411.16143)
			(xy 422.090996 -411.180103) (xy 422.076703 -411.194396) (xy 422.05803 -411.202135) (xy 422.047924 -411.202632)
			(xy 421.331644 -411.202632) (xy 421.321528 -411.202149) (xy 421.302832 -411.194421) (xy 421.288517 -411.180125)
			(xy 421.280765 -411.161439) (xy 421.280336 -411.151324) (xy 421.280336 -410.993844) (xy 421.279896 -410.98466)
			(xy 421.273402 -410.967476) (xy 421.267636 -410.960316) (xy 421.245755 -410.934664) (xy 421.207664 -410.879029)
			(xy 421.176512 -410.819231) (xy 421.152748 -410.756132) (xy 421.136712 -410.690641) (xy 421.128637 -410.623701)
			(xy 414.525968 -410.623701) (xy 414.525968 -417.366196) (xy 414.52546 -417.366196) (xy 414.52546 -417.533836)
			(xy 414.525117 -417.545925) (xy 414.517634 -417.568917) (xy 414.503411 -417.588471) (xy 414.483842 -417.602672)
			(xy 414.460842 -417.61013) (xy 414.448752 -417.610544) (xy 401.15109 -417.610544) (xy 401.138998 -417.610101)
			(xy 401.115995 -417.602639) (xy 401.096414 -417.588447) (xy 401.082164 -417.568908) (xy 401.074635 -417.545926)
			(xy 401.074128 -417.533836) (xy 326.525636 -417.533836) (xy 326.525172 -417.545885) (xy 326.517733 -417.568805)
			(xy 326.503592 -417.588317) (xy 326.484126 -417.602521) (xy 326.461229 -417.610032) (xy 326.449182 -417.610544)
			(xy 313.151012 -417.610544) (xy 313.138942 -417.610026) (xy 313.115981 -417.602571) (xy 313.096447 -417.588387)
			(xy 313.082251 -417.568862) (xy 313.074781 -417.545906) (xy 313.074304 -417.533836) (xy 313.074304 -417.379404)
			(xy 313.073796 -417.379404) (xy 273.436768 -417.379404) (xy 273.507194 -417.441568) (xy 273.606535 -417.539604)
			(xy 273.653758 -417.590986) (xy 273.692133 -417.632558) (xy 273.77424 -417.71041) (xy 273.862012 -417.781815)
			(xy 273.954943 -417.846362) (xy 274.052499 -417.90368) (xy 274.154119 -417.95344) (xy 274.259218 -417.995354)
			(xy 274.367191 -418.029182) (xy 274.477417 -418.05473) (xy 274.589263 -418.07185) (xy 274.702084 -418.080444)
			(xy 274.758658 -418.080952) (xy 465.600034 -418.080952) (xy 465.655802 -418.080429) (xy 465.767025 -418.072092)
			(xy 465.877315 -418.055466) (xy 465.986054 -418.030644) (xy 466.092633 -417.997766) (xy 466.196458 -417.957015)
			(xy 466.296947 -417.90862) (xy 466.393539 -417.85285) (xy 466.485692 -417.790018) (xy 466.572893 -417.720474)
			(xy 466.654653 -417.644609) (xy 466.730515 -417.562846) (xy 466.800054 -417.475643) (xy 466.862883 -417.383486)
			(xy 466.918649 -417.286892) (xy 466.96704 -417.186401) (xy 467.007787 -417.082575) (xy 467.04066 -416.975994)
			(xy 467.065477 -416.867254) (xy 467.082099 -416.756964) (xy 467.090432 -416.64574) (xy 467.091014 -416.589972)
			(xy 467.09203 -388.238238) (xy 467.09203 -246.488458) (xy 467.091578 -246.436469) (xy 467.084337 -246.332743)
			(xy 467.069893 -246.229773) (xy 467.048316 -246.128058) (xy 467.019711 -246.028092) (xy 466.984216 -245.930359)
			(xy 466.942005 -245.835335) (xy 466.91804 -245.789196) (xy 466.891385 -245.740526) (xy 466.831932 -245.646816)
			(xy 466.765775 -245.557714) (xy 466.693268 -245.473697) (xy 466.654388 -245.434104) (xy 464.025996 -242.805712)
			(xy 463.976572 -242.755595) (xy 463.882762 -242.650635) (xy 463.794985 -242.54058) (xy 463.713516 -242.425777)
			(xy 463.638613 -242.306586) (xy 463.57051 -242.183384) (xy 463.509422 -242.056557) (xy 463.455541 -241.926504)
			(xy 463.409037 -241.793634) (xy 463.370056 -241.658367) (xy 463.33872 -241.521126) (xy 463.315128 -241.382345)
			(xy 463.299355 -241.242459) (xy 463.291449 -241.101908) (xy 463.29092 -241.031522) (xy 463.29092 -87.588344)
			(xy 463.291412 -87.517965) (xy 463.29932 -87.377431) (xy 463.315095 -87.23756) (xy 463.33869 -87.098795)
			(xy 463.370029 -86.961571) (xy 463.409014 -86.82632) (xy 463.455522 -86.693468) (xy 463.509407 -86.563433)
			(xy 463.570498 -86.436625) (xy 463.638605 -86.313442) (xy 463.713512 -86.194272) (xy 463.794985 -86.07949)
			(xy 463.882765 -85.969457) (xy 463.976578 -85.86452) (xy 464.025996 -85.814408) (xy 466.654388 -83.185762)
			(xy 466.691681 -83.1478) (xy 466.76138 -83.067371) (xy 466.825166 -82.982176) (xy 466.882712 -82.892649)
			(xy 466.933726 -82.799245) (xy 466.977949 -82.70244) (xy 467.015155 -82.602728) (xy 467.045154 -82.500617)
			(xy 467.067793 -82.396625) (xy 467.082959 -82.291284) (xy 467.090572 -82.18513) (xy 467.091014 -82.131916)
			(xy 467.091014 -1.999996) (xy 467.090492 -1.944227) (xy 467.082157 -1.833) (xy 467.065533 -1.722707)
			(xy 467.040713 -1.613964) (xy 467.007837 -1.507381) (xy 466.967088 -1.403552) (xy 466.918693 -1.303059)
			(xy 466.862924 -1.206463) (xy 466.800093 -1.114305) (xy 466.73055 -1.0271) (xy 466.654685 -0.945336)
			(xy 466.572923 -0.869469) (xy 466.485719 -0.799925) (xy 466.393562 -0.737092) (xy 466.296967 -0.681321)
			(xy 466.196475 -0.632924) (xy 466.092647 -0.592173) (xy 465.986065 -0.559295) (xy 465.877323 -0.534473)
			(xy 465.76703 -0.517846) (xy 465.655803 -0.509509) (xy 465.600034 -0.509016) (xy 446.265046 -0.509016)
			(xy 446.209275 -0.509523) (xy 446.098046 -0.517855) (xy 445.98775 -0.534476) (xy 445.879004 -0.559294)
			(xy 445.772418 -0.592168) (xy 445.668586 -0.632916) (xy 445.568089 -0.68131) (xy 445.471491 -0.737079)
			(xy 445.37933 -0.79991) (xy 445.292122 -0.869454) (xy 445.210355 -0.945319) (xy 445.134486 -1.027084)
			(xy 445.06494 -1.114289) (xy 445.002105 -1.206448) (xy 444.946333 -1.303045) (xy 444.897936 -1.40354)
			(xy 444.857185 -1.50737) (xy 444.824307 -1.613956) (xy 444.799486 -1.722701) (xy 444.782861 -1.832996)
			(xy 444.774525 -1.944225) (xy 444.774066 -1.999996) (xy 444.774066 -11.850116) (xy 444.773596 -11.903993)
			(xy 444.765907 -12.011472) (xy 444.750571 -12.118128) (xy 444.727665 -12.223419) (xy 444.697306 -12.326808)
			(xy 444.659648 -12.427767) (xy 444.614884 -12.525782) (xy 444.563242 -12.620354) (xy 444.504984 -12.711001)
			(xy 444.440408 -12.797261) (xy 444.369843 -12.878695) (xy 444.293648 -12.954886) (xy 444.212211 -13.025448)
			(xy 444.125949 -13.09002) (xy 444.035299 -13.148274) (xy 443.940725 -13.199913) (xy 443.842708 -13.244673)
			(xy 443.741747 -13.282326) (xy 443.638357 -13.312681) (xy 443.533065 -13.335582) (xy 443.426408 -13.350914)
			(xy 443.318929 -13.358598) (xy 443.265052 -13.35913) (xy 435.265068 -13.35913) (xy 435.211191 -13.358648)
			(xy 435.103712 -13.350959) (xy 434.997055 -13.335622) (xy 434.891765 -13.312715) (xy 434.788376 -13.282356)
			(xy 434.687417 -13.244699) (xy 434.589401 -13.199935) (xy 434.494828 -13.148293) (xy 434.404181 -13.090036)
			(xy 434.31792 -13.025461) (xy 434.236485 -12.954897) (xy 434.160292 -12.878703) (xy 434.089729 -12.797268)
			(xy 434.025155 -12.711006) (xy 433.966899 -12.620358) (xy 433.915258 -12.525785) (xy 433.870495 -12.427769)
			(xy 433.832839 -12.326809) (xy 433.802481 -12.22342) (xy 433.779575 -12.118129) (xy 433.764239 -12.011472)
			(xy 433.756551 -11.903993) (xy 433.756054 -11.850116) (xy 433.756054 -1.999996) (xy 433.755545 -1.944227)
			(xy 433.74721 -1.833001) (xy 433.730585 -1.722708) (xy 433.705765 -1.613967) (xy 433.672888 -1.507384)
			(xy 433.632138 -1.403557) (xy 433.583743 -1.303065) (xy 433.527973 -1.20647) (xy 433.465141 -1.114314)
			(xy 433.395597 -1.02711) (xy 433.319731 -0.945348) (xy 433.237967 -0.869483) (xy 433.150762 -0.799942)
			(xy 433.058604 -0.737111) (xy 432.962009 -0.681343) (xy 432.861516 -0.63295) (xy 432.757687 -0.592202)
			(xy 432.651104 -0.559327) (xy 432.542362 -0.534509) (xy 432.432069 -0.517887) (xy 432.320843 -0.509554)
			(xy 432.265074 -0.509016) (xy 420.265098 -0.509016) (xy 420.209329 -0.509538) (xy 420.098103 -0.517873)
			(xy 419.987811 -0.534497) (xy 419.879069 -0.559317) (xy 419.772486 -0.592193) (xy 419.668658 -0.632943)
			(xy 419.568166 -0.681337) (xy 419.471571 -0.737106) (xy 419.379414 -0.799938) (xy 419.29221 -0.869481)
			(xy 419.210447 -0.945346) (xy 419.134582 -1.027109) (xy 419.065039 -1.114313) (xy 419.002207 -1.20647)
			(xy 418.946438 -1.303064) (xy 418.898043 -1.403557) (xy 418.857294 -1.507384) (xy 418.824417 -1.613967)
			(xy 418.799597 -1.722709) (xy 418.782973 -1.833001) (xy 418.774638 -1.944227) (xy 418.774118 -1.999996)
			(xy 418.774118 -11.850116) (xy 418.773637 -11.903993) (xy 418.765948 -12.011473) (xy 418.750612 -12.11813)
			(xy 418.727707 -12.223421) (xy 418.697348 -12.32681) (xy 418.659691 -12.42777) (xy 418.614928 -12.525787)
			(xy 418.563286 -12.62036) (xy 418.505029 -12.711008) (xy 418.440454 -12.79727) (xy 418.36989 -12.878704)
			(xy 418.293696 -12.954898) (xy 418.21226 -13.025462) (xy 418.125998 -13.090036) (xy 418.03535 -13.148292)
			(xy 417.940776 -13.199933) (xy 417.842759 -13.244696) (xy 417.741799 -13.282352) (xy 417.63841 -13.31271)
			(xy 417.533118 -13.335615) (xy 417.426461 -13.35095) (xy 417.318981 -13.358637) (xy 417.265104 -13.35913)
			(xy 409.26512 -13.35913) (xy 409.211242 -13.358661) (xy 409.103759 -13.350975) (xy 408.997099 -13.335641)
			(xy 408.891804 -13.312737) (xy 408.788412 -13.28238) (xy 408.687448 -13.244724) (xy 408.589429 -13.199961)
			(xy 408.494852 -13.14832) (xy 408.404201 -13.090063) (xy 408.317936 -13.025488) (xy 408.236498 -12.954923)
			(xy 408.160301 -12.878728) (xy 408.089735 -12.797292) (xy 408.025157 -12.711029) (xy 407.966898 -12.620379)
			(xy 407.915255 -12.525803) (xy 407.87049 -12.427785) (xy 407.832832 -12.326822) (xy 407.802472 -12.223431)
			(xy 407.779565 -12.118137) (xy 407.764229 -12.011477) (xy 407.75654 -11.903994) (xy 407.756106 -11.850116)
			(xy 407.756106 -1.999996) (xy 407.755584 -1.944227) (xy 407.747249 -1.833) (xy 407.730625 -1.722707)
			(xy 407.705805 -1.613965) (xy 407.672929 -1.507382) (xy 407.632179 -1.403554) (xy 407.583785 -1.303061)
			(xy 407.528016 -1.206465) (xy 407.465185 -1.114307) (xy 407.395642 -1.027103) (xy 407.319777 -0.945339)
			(xy 407.238014 -0.869472) (xy 407.15081 -0.799929) (xy 407.058653 -0.737096) (xy 406.962059 -0.681325)
			(xy 406.861567 -0.632929) (xy 406.757739 -0.592179) (xy 406.651156 -0.559301) (xy 406.542414 -0.534479)
			(xy 406.432122 -0.517854) (xy 406.320895 -0.509516) (xy 406.265126 -0.509016) (xy 394.264896 -0.509016)
			(xy 394.209127 -0.509538) (xy 394.097901 -0.517873) (xy 393.987609 -0.534497) (xy 393.878867 -0.559317)
			(xy 393.772285 -0.592194) (xy 393.668457 -0.632943) (xy 393.567965 -0.681338) (xy 393.47137 -0.737107)
			(xy 393.379213 -0.799938) (xy 393.292009 -0.869481) (xy 393.210246 -0.945346) (xy 393.134381 -1.027109)
			(xy 393.064838 -1.114313) (xy 393.002007 -1.20647) (xy 392.946238 -1.303065) (xy 392.897843 -1.403557)
			(xy 392.857094 -1.507385) (xy 392.824217 -1.613967) (xy 392.799397 -1.722709) (xy 392.782773 -1.833001)
			(xy 392.774438 -1.944227) (xy 392.773916 -1.999996) (xy 392.773916 -11.850116) (xy 392.773435 -11.903993)
			(xy 392.765746 -12.011473) (xy 392.75041 -12.11813) (xy 392.727505 -12.223421) (xy 392.697146 -12.32681)
			(xy 392.659489 -12.42777) (xy 392.614726 -12.525786) (xy 392.563084 -12.62036) (xy 392.504827 -12.711008)
			(xy 392.440252 -12.797269) (xy 392.369688 -12.878704) (xy 392.293494 -12.954897) (xy 392.212058 -13.025461)
			(xy 392.125796 -13.090035) (xy 392.035148 -13.148291) (xy 391.940574 -13.199932) (xy 391.842557 -13.244694)
			(xy 391.741597 -13.28235) (xy 391.638208 -13.312708) (xy 391.532916 -13.335613) (xy 391.426259 -13.350948)
			(xy 391.318779 -13.358635) (xy 391.264902 -13.35913) (xy 383.264918 -13.35913) (xy 383.21104 -13.358661)
			(xy 383.103557 -13.350975) (xy 382.996897 -13.335641) (xy 382.891603 -13.312737) (xy 382.78821 -13.282379)
			(xy 382.687247 -13.244723) (xy 382.589228 -13.199961) (xy 382.494651 -13.148319) (xy 382.404 -13.090063)
			(xy 382.317735 -13.025487) (xy 382.236297 -12.954923) (xy 382.160101 -12.878728) (xy 382.089534 -12.797291)
			(xy 382.024957 -12.711028) (xy 381.966698 -12.620378) (xy 381.915055 -12.525803) (xy 381.87029 -12.427784)
			(xy 381.832632 -12.326822) (xy 381.802272 -12.22343) (xy 381.779365 -12.118136) (xy 381.764029 -12.011477)
			(xy 381.75634 -11.903994) (xy 381.755904 -11.850116) (xy 381.755904 -1.999996) (xy 381.755382 -1.944227)
			(xy 381.747047 -1.833) (xy 381.730423 -1.722707) (xy 381.705603 -1.613965) (xy 381.672727 -1.507382)
			(xy 381.631977 -1.403554) (xy 381.583583 -1.303061) (xy 381.527814 -1.206466) (xy 381.464982 -1.114308)
			(xy 381.39544 -1.027103) (xy 381.319575 -0.945339) (xy 381.237812 -0.869473) (xy 381.150608 -0.799929)
			(xy 381.058451 -0.737097) (xy 380.961857 -0.681327) (xy 380.861364 -0.632931) (xy 380.757537 -0.59218)
			(xy 380.650954 -0.559302) (xy 380.542212 -0.534481) (xy 380.43192 -0.517855) (xy 380.320693 -0.509518)
			(xy 380.264924 -0.509016) (xy 368.264948 -0.509016) (xy 368.209177 -0.509523) (xy 368.097948 -0.517855)
			(xy 367.987651 -0.534476) (xy 367.878906 -0.559293) (xy 367.772319 -0.592168) (xy 367.668487 -0.632916)
			(xy 367.567991 -0.681309) (xy 367.471392 -0.737078) (xy 367.379231 -0.79991) (xy 367.292023 -0.869453)
			(xy 367.210256 -0.945319) (xy 367.134387 -1.027083) (xy 367.06484 -1.114289) (xy 367.002006 -1.206448)
			(xy 366.946234 -1.303045) (xy 366.897837 -1.403539) (xy 366.857085 -1.50737) (xy 366.824207 -1.613956)
			(xy 366.799386 -1.7227) (xy 366.782761 -1.832996) (xy 366.774425 -1.944225) (xy 366.773968 -1.999996)
			(xy 366.773968 -11.850116) (xy 366.773498 -11.903993) (xy 366.765809 -12.011472) (xy 366.750473 -12.118129)
			(xy 366.727567 -12.223419) (xy 366.697208 -12.326808) (xy 366.65955 -12.427767) (xy 366.614786 -12.525783)
			(xy 366.563144 -12.620355) (xy 366.504886 -12.711002) (xy 366.44031 -12.797262) (xy 366.369745 -12.878695)
			(xy 366.29355 -12.954887) (xy 366.212114 -13.025449) (xy 366.125851 -13.090021) (xy 366.035201 -13.148275)
			(xy 365.940627 -13.199914) (xy 365.84261 -13.244674) (xy 365.741649 -13.282327) (xy 365.638259 -13.312682)
			(xy 365.532968 -13.335584) (xy 365.42631 -13.350916) (xy 365.318831 -13.3586) (xy 365.264954 -13.35913)
			(xy 357.26497 -13.35913) (xy 357.211093 -13.358648) (xy 357.103614 -13.350959) (xy 356.996957 -13.335622)
			(xy 356.891666 -13.312716) (xy 356.788278 -13.282357) (xy 356.687318 -13.244699) (xy 356.589302 -13.199936)
			(xy 356.494729 -13.148294) (xy 356.404082 -13.090037) (xy 356.317821 -13.025462) (xy 356.236386 -12.954897)
			(xy 356.160193 -12.878704) (xy 356.08963 -12.797268) (xy 356.025055 -12.711007) (xy 355.966799 -12.620359)
			(xy 355.915158 -12.525785) (xy 355.870395 -12.427769) (xy 355.832739 -12.326809) (xy 355.802381 -12.22342)
			(xy 355.779475 -12.118129) (xy 355.764139 -12.011472) (xy 355.756451 -11.903993) (xy 355.755956 -11.850116)
			(xy 355.755956 -1.999996) (xy 355.755447 -1.944227) (xy 355.747112 -1.833001) (xy 355.730487 -1.722708)
			(xy 355.705667 -1.613967) (xy 355.67279 -1.507384) (xy 355.63204 -1.403556) (xy 355.583645 -1.303064)
			(xy 355.527875 -1.20647) (xy 355.465043 -1.114313) (xy 355.395499 -1.02711) (xy 355.319633 -0.945347)
			(xy 355.237869 -0.869483) (xy 355.150664 -0.799941) (xy 355.058507 -0.73711) (xy 354.961911 -0.681342)
			(xy 354.861418 -0.632949) (xy 354.757589 -0.5922) (xy 354.651006 -0.559325) (xy 354.542264 -0.534507)
			(xy 354.431972 -0.517885) (xy 354.320745 -0.509552) (xy 354.264976 -0.509016) (xy 330.164948 -0.509016)
			(xy 330.109177 -0.509523) (xy 329.997948 -0.517855) (xy 329.887651 -0.534476) (xy 329.778906 -0.559293)
			(xy 329.672319 -0.592168) (xy 329.568487 -0.632916) (xy 329.467991 -0.681309) (xy 329.371392 -0.737078)
			(xy 329.279231 -0.79991) (xy 329.192023 -0.869453) (xy 329.110256 -0.945319) (xy 329.034387 -1.027083)
			(xy 328.96484 -1.114289) (xy 328.902006 -1.206448) (xy 328.846234 -1.303045) (xy 328.797837 -1.403539)
			(xy 328.757085 -1.50737) (xy 328.724207 -1.613956) (xy 328.699386 -1.7227) (xy 328.682761 -1.832996)
			(xy 328.674425 -1.944225) (xy 328.673968 -1.999996) (xy 328.673968 -11.850116) (xy 328.673498 -11.903993)
			(xy 328.665809 -12.011472) (xy 328.650473 -12.118129) (xy 328.627567 -12.223419) (xy 328.597208 -12.326808)
			(xy 328.55955 -12.427767) (xy 328.514786 -12.525783) (xy 328.463144 -12.620355) (xy 328.404886 -12.711002)
			(xy 328.34031 -12.797262) (xy 328.269745 -12.878695) (xy 328.19355 -12.954887) (xy 328.112114 -13.025449)
			(xy 328.025851 -13.090021) (xy 327.935201 -13.148275) (xy 327.840627 -13.199914) (xy 327.74261 -13.244674)
			(xy 327.641649 -13.282327) (xy 327.538259 -13.312682) (xy 327.432968 -13.335584) (xy 327.32631 -13.350916)
			(xy 327.218831 -13.3586) (xy 327.164954 -13.35913) (xy 319.16497 -13.35913) (xy 319.111093 -13.358648)
			(xy 319.003614 -13.350959) (xy 318.896957 -13.335622) (xy 318.791666 -13.312716) (xy 318.688278 -13.282357)
			(xy 318.587318 -13.244699) (xy 318.489302 -13.199936) (xy 318.394729 -13.148294) (xy 318.304082 -13.090037)
			(xy 318.217821 -13.025462) (xy 318.136386 -12.954897) (xy 318.060193 -12.878704) (xy 317.98963 -12.797268)
			(xy 317.925055 -12.711007) (xy 317.866799 -12.620359) (xy 317.815158 -12.525785) (xy 317.770395 -12.427769)
			(xy 317.732739 -12.326809) (xy 317.702381 -12.22342) (xy 317.679475 -12.118129) (xy 317.664139 -12.011472)
			(xy 317.656451 -11.903993) (xy 317.655956 -11.850116) (xy 317.655956 -1.999996) (xy 317.655447 -1.944227)
			(xy 317.647112 -1.833001) (xy 317.630487 -1.722708) (xy 317.605667 -1.613967) (xy 317.57279 -1.507384)
			(xy 317.53204 -1.403556) (xy 317.483645 -1.303064) (xy 317.427875 -1.20647) (xy 317.365043 -1.114313)
			(xy 317.295499 -1.02711) (xy 317.219633 -0.945347) (xy 317.137869 -0.869483) (xy 317.050664 -0.799941)
			(xy 316.958507 -0.73711) (xy 316.861911 -0.681342) (xy 316.761418 -0.632949) (xy 316.657589 -0.5922)
			(xy 316.551006 -0.559325) (xy 316.442264 -0.534507) (xy 316.331972 -0.517885) (xy 316.220745 -0.509552)
			(xy 316.164976 -0.509016) (xy 304.165 -0.509016) (xy 304.109231 -0.509537) (xy 303.998005 -0.517873)
			(xy 303.887712 -0.534497) (xy 303.778971 -0.559316) (xy 303.672388 -0.592193) (xy 303.56856 -0.632942)
			(xy 303.468067 -0.681336) (xy 303.371472 -0.737105) (xy 303.279315 -0.799937) (xy 303.192111 -0.86948)
			(xy 303.110348 -0.945345) (xy 303.034482 -1.027108) (xy 302.964939 -1.114312) (xy 302.902108 -1.206469)
			(xy 302.846338 -1.303064) (xy 302.797944 -1.403556) (xy 302.757194 -1.507384) (xy 302.724317 -1.613967)
			(xy 302.699497 -1.722708) (xy 302.682873 -1.833001) (xy 302.674538 -1.944227) (xy 302.67402 -1.999996)
			(xy 302.67402 -11.850116) (xy 302.673539 -11.903993) (xy 302.66585 -12.011473) (xy 302.650514 -12.11813)
			(xy 302.627609 -12.223422) (xy 302.59725 -12.326811) (xy 302.559593 -12.427771) (xy 302.51483 -12.525787)
			(xy 302.463188 -12.62036) (xy 302.404931 -12.711009) (xy 302.340356 -12.79727) (xy 302.269792 -12.878705)
			(xy 302.193598 -12.954899) (xy 302.112162 -13.025462) (xy 302.025901 -13.090037) (xy 301.935252 -13.148293)
			(xy 301.840678 -13.199934) (xy 301.742661 -13.244697) (xy 301.641701 -13.282353) (xy 301.538312 -13.312711)
			(xy 301.43302 -13.335616) (xy 301.326363 -13.350952) (xy 301.218883 -13.358639) (xy 301.165006 -13.35913)
			(xy 293.165022 -13.35913) (xy 293.111143 -13.358661) (xy 293.003661 -13.350975) (xy 292.897001 -13.335641)
			(xy 292.791706 -13.312737) (xy 292.688313 -13.28238) (xy 292.58735 -13.244724) (xy 292.48933 -13.199962)
			(xy 292.394753 -13.148321) (xy 292.304102 -13.090064) (xy 292.217837 -13.025489) (xy 292.136399 -12.954924)
			(xy 292.060202 -12.878729) (xy 291.989635 -12.797293) (xy 291.925058 -12.71103) (xy 291.866799 -12.620379)
			(xy 291.815155 -12.525804) (xy 291.77039 -12.427785) (xy 291.732732 -12.326823) (xy 291.702372 -12.223431)
			(xy 291.679465 -12.118137) (xy 291.664129 -12.011477) (xy 291.65644 -11.903994) (xy 291.656008 -11.850116)
			(xy 291.656008 -1.999996) (xy 291.655486 -1.944227) (xy 291.647151 -1.833) (xy 291.630527 -1.722707)
			(xy 291.605707 -1.613965) (xy 291.572831 -1.507382) (xy 291.532081 -1.403553) (xy 291.483687 -1.30306)
			(xy 291.427918 -1.206465) (xy 291.365087 -1.114307) (xy 291.295544 -1.027102) (xy 291.219679 -0.945338)
			(xy 291.137916 -0.869472) (xy 291.050712 -0.799928) (xy 290.958556 -0.737095) (xy 290.861961 -0.681324)
			(xy 290.761469 -0.632928) (xy 290.657641 -0.592177) (xy 290.551058 -0.559299) (xy 290.442316 -0.534478)
			(xy 290.332024 -0.517852) (xy 290.220797 -0.509515) (xy 290.165028 -0.509016) (xy 278.165052 -0.509016)
			(xy 278.109284 -0.509539) (xy 277.99806 -0.517878) (xy 277.887771 -0.534504) (xy 277.779032 -0.559327)
			(xy 277.672452 -0.592205) (xy 277.568627 -0.632956) (xy 277.468138 -0.681352) (xy 277.371546 -0.737122)
			(xy 277.279392 -0.799954) (xy 277.192191 -0.869497) (xy 277.110431 -0.945362) (xy 277.034568 -1.027125)
			(xy 276.965028 -1.114328) (xy 276.902198 -1.206484) (xy 276.846431 -1.303077) (xy 276.798039 -1.403568)
			(xy 276.75729 -1.507394) (xy 276.724415 -1.613974) (xy 276.699596 -1.722714) (xy 276.682973 -1.833004)
			(xy 276.674638 -1.944228) (xy 276.674072 -1.999996) (xy 276.674072 -11.850116) (xy 276.673602 -11.903993)
			(xy 276.665913 -12.011472) (xy 276.650577 -12.118129) (xy 276.627671 -12.22342) (xy 276.597312 -12.326808)
			(xy 276.559654 -12.427768) (xy 276.51489 -12.525783) (xy 276.463248 -12.620356) (xy 276.40499 -12.711003)
			(xy 276.340414 -12.797263) (xy 276.269849 -12.878697) (xy 276.193654 -12.954889) (xy 276.112218 -13.025451)
			(xy 276.025955 -13.090023) (xy 275.935306 -13.148277) (xy 275.840731 -13.199916) (xy 275.742714 -13.244676)
			(xy 275.641753 -13.28233) (xy 275.538364 -13.312685) (xy 275.433072 -13.335587) (xy 275.326414 -13.35092)
			(xy 275.218935 -13.358604) (xy 275.165058 -13.35913) (xy 267.165074 -13.35913) (xy 267.111197 -13.358648)
			(xy 267.003718 -13.350959) (xy 266.897061 -13.335623) (xy 266.791769 -13.312717) (xy 266.688381 -13.282358)
			(xy 266.587421 -13.2447) (xy 266.489405 -13.199937) (xy 266.394832 -13.148295) (xy 266.304184 -13.090038)
			(xy 266.217923 -13.025463) (xy 266.136488 -12.954899) (xy 266.060294 -12.878705) (xy 265.989731 -12.79727)
			(xy 265.925156 -12.711008) (xy 265.8669 -12.62036) (xy 265.815259 -12.525786) (xy 265.770496 -12.42777)
			(xy 265.732839 -12.32681) (xy 265.702481 -12.223421) (xy 265.679575 -12.11813) (xy 265.664239 -12.011472)
			(xy 265.656551 -11.903993) (xy 265.65606 -11.850116) (xy 265.65606 -1.999996) (xy 265.655551 -1.944227)
			(xy 265.647216 -1.833) (xy 265.630591 -1.722708) (xy 265.605771 -1.613966) (xy 265.572894 -1.507384)
			(xy 265.532144 -1.403556) (xy 265.483749 -1.303063) (xy 265.427979 -1.206469) (xy 265.365147 -1.114312)
			(xy 265.295603 -1.027108) (xy 265.219737 -0.945346) (xy 265.137973 -0.869481) (xy 265.050769 -0.799939)
			(xy 264.958611 -0.737108) (xy 264.862015 -0.68134) (xy 264.761522 -0.632946) (xy 264.657694 -0.592198)
			(xy 264.55111 -0.559322) (xy 264.442368 -0.534504) (xy 264.332076 -0.517882) (xy 264.220849 -0.509548)
			(xy 264.16508 -0.509016) (xy 252.165104 -0.509016) (xy 252.109335 -0.509537) (xy 251.998108 -0.517872)
			(xy 251.887816 -0.534496) (xy 251.779074 -0.559315) (xy 251.672491 -0.592191) (xy 251.568663 -0.632941)
			(xy 251.46817 -0.681335) (xy 251.371575 -0.737104) (xy 251.279417 -0.799936) (xy 251.192213 -0.869478)
			(xy 251.110449 -0.945344) (xy 251.034584 -1.027107) (xy 250.96504 -1.114311) (xy 250.902208 -1.206468)
			(xy 250.846439 -1.303063) (xy 250.798044 -1.403555) (xy 250.757294 -1.507383) (xy 250.724417 -1.613966)
			(xy 250.699597 -1.722708) (xy 250.682973 -1.833) (xy 250.674638 -1.944227) (xy 250.674124 -1.999996)
			(xy 250.674124 -11.850116) (xy 250.673643 -11.903993) (xy 250.665954 -12.011473) (xy 250.650618 -12.11813)
			(xy 250.627713 -12.223422) (xy 250.597354 -12.326811) (xy 250.559697 -12.427771) (xy 250.514934 -12.525788)
			(xy 250.463292 -12.620361) (xy 250.405035 -12.71101) (xy 250.34046 -12.797271) (xy 250.269896 -12.878706)
			(xy 250.193702 -12.9549) (xy 250.112267 -13.025464) (xy 250.026005 -13.090039) (xy 249.935356 -13.148295)
			(xy 249.840782 -13.199936) (xy 249.742766 -13.244699) (xy 249.641806 -13.282356) (xy 249.538416 -13.312714)
			(xy 249.433124 -13.33562) (xy 249.326467 -13.350955) (xy 249.218987 -13.358643) (xy 249.16511 -13.35913)
			(xy 241.164872 -13.35913) (xy 241.110999 -13.358634) (xy 241.003529 -13.35092) (xy 240.896884 -13.335561)
			(xy 240.791604 -13.312636) (xy 240.688228 -13.282262) (xy 240.587282 -13.244593) (xy 240.489278 -13.199821)
			(xy 240.394717 -13.148173) (xy 240.30408 -13.089914) (xy 240.217828 -13.02534) (xy 240.136401 -12.954778)
			(xy 240.060213 -12.87859) (xy 239.989653 -12.797163) (xy 239.925079 -12.71091) (xy 239.86682 -12.620273)
			(xy 239.815174 -12.525711) (xy 239.770403 -12.427707) (xy 239.732734 -12.32676) (xy 239.702361 -12.223384)
			(xy 239.679436 -12.118105) (xy 239.664079 -12.011459) (xy 239.656365 -11.903989) (xy 239.655858 -11.850116)
			(xy 239.655858 -1.999996) (xy 239.655349 -1.944227) (xy 239.647014 -1.833001) (xy 239.630389 -1.722708)
			(xy 239.605569 -1.613967) (xy 239.572692 -1.507384) (xy 239.531942 -1.403556) (xy 239.483547 -1.303064)
			(xy 239.427777 -1.206469) (xy 239.364945 -1.114313) (xy 239.295401 -1.027109) (xy 239.219535 -0.945346)
			(xy 239.137771 -0.869482) (xy 239.050567 -0.79994) (xy 238.958409 -0.737109) (xy 238.861813 -0.681341)
			(xy 238.76132 -0.632947) (xy 238.657492 -0.592199) (xy 238.550908 -0.559324) (xy 238.442166 -0.534506)
			(xy 238.331874 -0.517883) (xy 238.220647 -0.50955) (xy 238.164878 -0.509016) (xy 214.065104 -0.509016)
			(xy 214.009335 -0.509537) (xy 213.898108 -0.517872) (xy 213.787816 -0.534496) (xy 213.679074 -0.559315)
			(xy 213.572491 -0.592191) (xy 213.468663 -0.632941) (xy 213.36817 -0.681335) (xy 213.271575 -0.737104)
			(xy 213.179417 -0.799936) (xy 213.092213 -0.869478) (xy 213.010449 -0.945344) (xy 212.934584 -1.027107)
			(xy 212.86504 -1.114311) (xy 212.802208 -1.206468) (xy 212.746439 -1.303063) (xy 212.698044 -1.403555)
			(xy 212.657294 -1.507383) (xy 212.624417 -1.613966) (xy 212.599597 -1.722708) (xy 212.582973 -1.833)
			(xy 212.574638 -1.944227) (xy 212.574124 -1.999996) (xy 212.574124 -11.850116) (xy 212.573643 -11.903993)
			(xy 212.565954 -12.011473) (xy 212.550618 -12.11813) (xy 212.527713 -12.223422) (xy 212.497354 -12.326811)
			(xy 212.459697 -12.427771) (xy 212.414934 -12.525788) (xy 212.363292 -12.620361) (xy 212.305035 -12.71101)
			(xy 212.24046 -12.797271) (xy 212.169896 -12.878706) (xy 212.093702 -12.9549) (xy 212.012267 -13.025464)
			(xy 211.926005 -13.090039) (xy 211.835356 -13.148295) (xy 211.740782 -13.199936) (xy 211.642766 -13.244699)
			(xy 211.541806 -13.282356) (xy 211.438416 -13.312714) (xy 211.333124 -13.33562) (xy 211.226467 -13.350955)
			(xy 211.118987 -13.358643) (xy 211.06511 -13.35913) (xy 203.064872 -13.35913) (xy 203.010999 -13.358634)
			(xy 202.903529 -13.35092) (xy 202.796884 -13.335561) (xy 202.691604 -13.312636) (xy 202.588228 -13.282262)
			(xy 202.487282 -13.244593) (xy 202.389278 -13.199821) (xy 202.294717 -13.148173) (xy 202.20408 -13.089914)
			(xy 202.117828 -13.02534) (xy 202.036401 -12.954778) (xy 201.960213 -12.87859) (xy 201.889653 -12.797163)
			(xy 201.825079 -12.71091) (xy 201.76682 -12.620273) (xy 201.715174 -12.525711) (xy 201.670403 -12.427707)
			(xy 201.632734 -12.32676) (xy 201.602361 -12.223384) (xy 201.579436 -12.118105) (xy 201.564079 -12.011459)
			(xy 201.556365 -11.903989) (xy 201.555858 -11.850116) (xy 201.555858 -1.999996) (xy 201.555349 -1.944227)
			(xy 201.547014 -1.833001) (xy 201.530389 -1.722708) (xy 201.505569 -1.613967) (xy 201.472692 -1.507384)
			(xy 201.431942 -1.403556) (xy 201.383547 -1.303064) (xy 201.327777 -1.206469) (xy 201.264945 -1.114313)
			(xy 201.195401 -1.027109) (xy 201.119535 -0.945346) (xy 201.037771 -0.869482) (xy 200.950567 -0.79994)
			(xy 200.858409 -0.737109) (xy 200.761813 -0.681341) (xy 200.66132 -0.632947) (xy 200.557492 -0.592199)
			(xy 200.450908 -0.559324) (xy 200.342166 -0.534506) (xy 200.231874 -0.517883) (xy 200.120647 -0.50955)
			(xy 200.064878 -0.509016) (xy 188.064902 -0.509016) (xy 188.009133 -0.509537) (xy 187.897906 -0.517873)
			(xy 187.787614 -0.534496) (xy 187.678872 -0.559316) (xy 187.572289 -0.592192) (xy 187.468461 -0.632941)
			(xy 187.367969 -0.681336) (xy 187.271374 -0.737105) (xy 187.179216 -0.799936) (xy 187.092012 -0.869479)
			(xy 187.010248 -0.945344) (xy 186.934383 -1.027107) (xy 186.86484 -1.114311) (xy 186.802008 -1.206468)
			(xy 186.746239 -1.303063) (xy 186.697844 -1.403556) (xy 186.657094 -1.507384) (xy 186.624217 -1.613966)
			(xy 186.599397 -1.722708) (xy 186.582773 -1.833001) (xy 186.574438 -1.944227) (xy 186.573922 -1.999996)
			(xy 186.573922 -11.850116) (xy 186.573441 -11.903993) (xy 186.565752 -12.011473) (xy 186.550416 -12.11813)
			(xy 186.527511 -12.223422) (xy 186.497152 -12.326811) (xy 186.459495 -12.427771) (xy 186.414732 -12.525787)
			(xy 186.36309 -12.620361) (xy 186.304833 -12.711009) (xy 186.240258 -12.797271) (xy 186.169694 -12.878706)
			(xy 186.0935 -12.954899) (xy 186.012065 -13.025463) (xy 185.925803 -13.090038) (xy 185.835154 -13.148294)
			(xy 185.74058 -13.199935) (xy 185.642564 -13.244698) (xy 185.541603 -13.282355) (xy 185.438214 -13.312713)
			(xy 185.332922 -13.335618) (xy 185.226265 -13.350953) (xy 185.118785 -13.358641) (xy 185.064908 -13.35913)
			(xy 177.064924 -13.35913) (xy 177.011045 -13.358661) (xy 176.903563 -13.350975) (xy 176.796902 -13.335642)
			(xy 176.691607 -13.312738) (xy 176.588215 -13.282381) (xy 176.487251 -13.244725) (xy 176.389231 -13.199962)
			(xy 176.294654 -13.148321) (xy 176.204003 -13.090065) (xy 176.117738 -13.025489) (xy 176.036299 -12.954925)
			(xy 175.960103 -12.87873) (xy 175.889536 -12.797293) (xy 175.824958 -12.71103) (xy 175.766699 -12.62038)
			(xy 175.715056 -12.525804) (xy 175.67029 -12.427786) (xy 175.632632 -12.326823) (xy 175.602272 -12.223431)
			(xy 175.579365 -12.118137) (xy 175.564029 -12.011477) (xy 175.55634 -11.903995) (xy 175.55591 -11.850116)
			(xy 175.55591 -1.999996) (xy 175.555388 -1.944227) (xy 175.547053 -1.833) (xy 175.530429 -1.722707)
			(xy 175.505609 -1.613965) (xy 175.472733 -1.507381) (xy 175.431983 -1.403553) (xy 175.383589 -1.30306)
			(xy 175.32782 -1.206464) (xy 175.264989 -1.114306) (xy 175.195446 -1.027101) (xy 175.119581 -0.945337)
			(xy 175.037818 -0.869471) (xy 174.950615 -0.799927) (xy 174.858458 -0.737094) (xy 174.761863 -0.681323)
			(xy 174.661371 -0.632927) (xy 174.557543 -0.592176) (xy 174.45096 -0.559298) (xy 174.342219 -0.534476)
			(xy 174.231926 -0.51785) (xy 174.120699 -0.509513) (xy 174.06493 -0.509016) (xy 162.064954 -0.509016)
			(xy 162.009186 -0.509539) (xy 161.897962 -0.517878) (xy 161.787672 -0.534504) (xy 161.678934 -0.559326)
			(xy 161.572354 -0.592204) (xy 161.468529 -0.632956) (xy 161.368039 -0.681351) (xy 161.271447 -0.737121)
			(xy 161.179293 -0.799953) (xy 161.092092 -0.869496) (xy 161.010331 -0.945361) (xy 160.934469 -1.027124)
			(xy 160.864928 -1.114327) (xy 160.802099 -1.206483) (xy 160.746332 -1.303076) (xy 160.697939 -1.403567)
			(xy 160.657191 -1.507393) (xy 160.624315 -1.613974) (xy 160.599496 -1.722714) (xy 160.582873 -1.833004)
			(xy 160.574538 -1.944228) (xy 160.573974 -1.999996) (xy 160.573974 -11.850116) (xy 160.573504 -11.903993)
			(xy 160.565815 -12.011472) (xy 160.550479 -12.118129) (xy 160.527573 -12.22342) (xy 160.497214 -12.326809)
			(xy 160.459556 -12.427768) (xy 160.414792 -12.525784) (xy 160.36315 -12.620356) (xy 160.304892 -12.711003)
			(xy 160.240316 -12.797264) (xy 160.169751 -12.878697) (xy 160.093556 -12.954889) (xy 160.01212 -13.025452)
			(xy 159.925857 -13.090024) (xy 159.835208 -13.148278) (xy 159.740634 -13.199917) (xy 159.642616 -13.244678)
			(xy 159.541655 -13.282332) (xy 159.438266 -13.312687) (xy 159.332974 -13.335589) (xy 159.226316 -13.350921)
			(xy 159.118837 -13.358606) (xy 159.06496 -13.35913) (xy 151.064976 -13.35913) (xy 151.011099 -13.358648)
			(xy 150.903619 -13.35096) (xy 150.796962 -13.335623) (xy 150.691671 -13.312717) (xy 150.588282 -13.282358)
			(xy 150.487322 -13.244701) (xy 150.389306 -13.199937) (xy 150.294733 -13.148296) (xy 150.204085 -13.090039)
			(xy 150.117823 -13.025464) (xy 150.036389 -12.954899) (xy 149.960195 -12.878706) (xy 149.889631 -12.79727)
			(xy 149.825057 -12.711009) (xy 149.7668 -12.62036) (xy 149.715159 -12.525787) (xy 149.670396 -12.42777)
			(xy 149.632739 -12.32681) (xy 149.602381 -12.223421) (xy 149.579475 -12.11813) (xy 149.564139 -12.011473)
			(xy 149.556451 -11.903993) (xy 149.555962 -11.850116) (xy 149.555962 -1.999996) (xy 149.555453 -1.944227)
			(xy 149.547118 -1.833) (xy 149.530493 -1.722708) (xy 149.505673 -1.613966) (xy 149.472796 -1.507383)
			(xy 149.432046 -1.403555) (xy 149.383651 -1.303063) (xy 149.327881 -1.206468) (xy 149.265049 -1.114311)
			(xy 149.195505 -1.027108) (xy 149.11964 -0.945345) (xy 149.037876 -0.86948) (xy 148.950671 -0.799938)
			(xy 148.858513 -0.737107) (xy 148.761917 -0.681339) (xy 148.661424 -0.632945) (xy 148.557596 -0.592196)
			(xy 148.451013 -0.559321) (xy 148.34227 -0.534503) (xy 148.231978 -0.51788) (xy 148.120751 -0.509546)
			(xy 148.064982 -0.509016) (xy 136.065006 -0.509016) (xy 136.009236 -0.509524) (xy 135.898009 -0.517859)
			(xy 135.787715 -0.534483) (xy 135.678972 -0.559302) (xy 135.572388 -0.592179) (xy 135.468559 -0.632928)
			(xy 135.368065 -0.681323) (xy 135.271469 -0.737092) (xy 135.17931 -0.799924) (xy 135.092105 -0.869468)
			(xy 135.010341 -0.945334) (xy 134.934474 -1.027098) (xy 134.86493 -1.114302) (xy 134.802098 -1.20646)
			(xy 134.746328 -1.303056) (xy 134.697932 -1.403549) (xy 134.657182 -1.507378) (xy 134.624305 -1.613962)
			(xy 134.599485 -1.722705) (xy 134.58286 -1.832999) (xy 134.574525 -1.944226) (xy 134.574026 -1.999996)
			(xy 134.574026 -11.850116) (xy 134.573545 -11.903993) (xy 134.565856 -12.011473) (xy 134.55052 -12.11813)
			(xy 134.527615 -12.223422) (xy 134.497256 -12.326811) (xy 134.459599 -12.427772) (xy 134.414836 -12.525788)
			(xy 134.363194 -12.620362) (xy 134.304937 -12.71101) (xy 134.240362 -12.797272) (xy 134.169798 -12.878707)
			(xy 134.093604 -12.954901) (xy 134.012169 -13.025465) (xy 133.925907 -13.09004) (xy 133.835258 -13.148296)
			(xy 133.740685 -13.199938) (xy 133.642668 -13.244701) (xy 133.541708 -13.282357) (xy 133.438318 -13.312716)
			(xy 133.333026 -13.335621) (xy 133.226369 -13.350957) (xy 133.118889 -13.358645) (xy 133.065012 -13.35913)
			(xy 125.065028 -13.35913) (xy 125.011149 -13.358661) (xy 124.903666 -13.350976) (xy 124.797006 -13.335642)
			(xy 124.691711 -13.312739) (xy 124.588318 -13.282382) (xy 124.487354 -13.244726) (xy 124.389334 -13.199964)
			(xy 124.294757 -13.148323) (xy 124.204105 -13.090066) (xy 124.11784 -13.025491) (xy 124.036401 -12.954926)
			(xy 123.960204 -12.878731) (xy 123.889637 -12.797295) (xy 123.825059 -12.711032) (xy 123.7668 -12.620381)
			(xy 123.715156 -12.525806) (xy 123.670391 -12.427787) (xy 123.632732 -12.326824) (xy 123.602372 -12.223432)
			(xy 123.579466 -12.118138) (xy 123.564129 -12.011477) (xy 123.55644 -11.903995) (xy 123.556014 -11.850116)
			(xy 123.556014 -1.999996) (xy 123.555492 -1.944227) (xy 123.547157 -1.833) (xy 123.530533 -1.722707)
			(xy 123.505713 -1.613964) (xy 123.472837 -1.507381) (xy 123.432088 -1.403552) (xy 123.383693 -1.303059)
			(xy 123.327924 -1.206463) (xy 123.265093 -1.114305) (xy 123.19555 -1.0271) (xy 123.119685 -0.945336)
			(xy 123.037923 -0.869469) (xy 122.950719 -0.799925) (xy 122.858562 -0.737092) (xy 122.761967 -0.681321)
			(xy 122.661475 -0.632924) (xy 122.557647 -0.592173) (xy 122.451065 -0.559295) (xy 122.342323 -0.534473)
			(xy 122.23203 -0.517846) (xy 122.120803 -0.509509) (xy 122.065034 -0.509016) (xy 97.965006 -0.509016)
			(xy 97.909236 -0.509524) (xy 97.798009 -0.517859) (xy 97.687715 -0.534483) (xy 97.578972 -0.559302)
			(xy 97.472388 -0.592179) (xy 97.368559 -0.632928) (xy 97.268065 -0.681323) (xy 97.171469 -0.737092)
			(xy 97.07931 -0.799924) (xy 96.992105 -0.869468) (xy 96.910341 -0.945334) (xy 96.834474 -1.027098)
			(xy 96.76493 -1.114302) (xy 96.702098 -1.20646) (xy 96.646328 -1.303056) (xy 96.597932 -1.403549)
			(xy 96.557182 -1.507378) (xy 96.524305 -1.613962) (xy 96.499485 -1.722705) (xy 96.48286 -1.832999)
			(xy 96.474525 -1.944226) (xy 96.474026 -1.999996) (xy 96.474026 -11.850116) (xy 96.473545 -11.903993)
			(xy 96.465856 -12.011473) (xy 96.45052 -12.11813) (xy 96.427615 -12.223422) (xy 96.397256 -12.326811)
			(xy 96.359599 -12.427772) (xy 96.314836 -12.525788) (xy 96.263194 -12.620362) (xy 96.204937 -12.71101)
			(xy 96.140362 -12.797272) (xy 96.069798 -12.878707) (xy 95.993604 -12.954901) (xy 95.912169 -13.025465)
			(xy 95.825907 -13.09004) (xy 95.735258 -13.148296) (xy 95.640685 -13.199938) (xy 95.542668 -13.244701)
			(xy 95.441708 -13.282357) (xy 95.338318 -13.312716) (xy 95.233026 -13.335621) (xy 95.126369 -13.350957)
			(xy 95.018889 -13.358645) (xy 94.965012 -13.35913) (xy 86.965028 -13.35913) (xy 86.911149 -13.358661)
			(xy 86.803666 -13.350976) (xy 86.697006 -13.335642) (xy 86.591711 -13.312739) (xy 86.488318 -13.282382)
			(xy 86.387354 -13.244726) (xy 86.289334 -13.199964) (xy 86.194757 -13.148323) (xy 86.104105 -13.090066)
			(xy 86.01784 -13.025491) (xy 85.936401 -12.954926) (xy 85.860204 -12.878731) (xy 85.789637 -12.797295)
			(xy 85.725059 -12.711032) (xy 85.6668 -12.620381) (xy 85.615156 -12.525806) (xy 85.570391 -12.427787)
			(xy 85.532732 -12.326824) (xy 85.502372 -12.223432) (xy 85.479466 -12.118138) (xy 85.464129 -12.011477)
			(xy 85.45644 -11.903995) (xy 85.456014 -11.850116) (xy 85.456014 -1.999996) (xy 85.455492 -1.944227)
			(xy 85.447157 -1.833) (xy 85.430533 -1.722707) (xy 85.405713 -1.613964) (xy 85.372837 -1.507381)
			(xy 85.332088 -1.403552) (xy 85.283693 -1.303059) (xy 85.227924 -1.206463) (xy 85.165093 -1.114305)
			(xy 85.09555 -1.0271) (xy 85.019685 -0.945336) (xy 84.937923 -0.869469) (xy 84.850719 -0.799925)
			(xy 84.758562 -0.737092) (xy 84.661967 -0.681321) (xy 84.561475 -0.632924) (xy 84.457647 -0.592173)
			(xy 84.351065 -0.559295) (xy 84.242323 -0.534473) (xy 84.13203 -0.517846) (xy 84.020803 -0.509509)
			(xy 83.965034 -0.509016) (xy 71.965058 -0.509016) (xy 71.90929 -0.509539) (xy 71.798066 -0.517877)
			(xy 71.687776 -0.534503) (xy 71.579037 -0.559325) (xy 71.472457 -0.592203) (xy 71.368631 -0.632954)
			(xy 71.268142 -0.68135) (xy 71.17155 -0.73712) (xy 71.079395 -0.799952) (xy 70.992194 -0.869495)
			(xy 70.910433 -0.94536) (xy 70.83457 -1.027122) (xy 70.765029 -1.114326) (xy 70.7022 -1.206482) (xy 70.646432 -1.303075)
			(xy 70.598039 -1.403566) (xy 70.557291 -1.507392) (xy 70.524415 -1.613974) (xy 70.499596 -1.722713)
			(xy 70.482973 -1.833004) (xy 70.474638 -1.944228) (xy 70.474078 -1.999996) (xy 70.474078 -11.850116)
			(xy 70.473608 -11.903993) (xy 70.465919 -12.011472) (xy 70.450583 -12.118129) (xy 70.427677 -12.22342)
			(xy 70.397318 -12.326809) (xy 70.35966 -12.427769) (xy 70.314896 -12.525784) (xy 70.263254 -12.620357)
			(xy 70.204996 -12.711004) (xy 70.140421 -12.797265) (xy 70.069855 -12.878699) (xy 69.993661 -12.954891)
			(xy 69.912224 -13.025453) (xy 69.825962 -13.090026) (xy 69.735312 -13.148281) (xy 69.640738 -13.19992)
			(xy 69.542721 -13.24468) (xy 69.44176 -13.282334) (xy 69.33837 -13.31269) (xy 69.233078 -13.335592)
			(xy 69.126421 -13.350925) (xy 69.018941 -13.358609) (xy 68.965064 -13.35913) (xy 60.96508 -13.35913)
			(xy 60.911203 -13.358648) (xy 60.803723 -13.35096) (xy 60.697066 -13.335624) (xy 60.591774 -13.312718)
			(xy 60.488385 -13.282359) (xy 60.387425 -13.244702) (xy 60.289409 -13.199939) (xy 60.194835 -13.148297)
			(xy 60.104187 -13.09004) (xy 60.017925 -13.025465) (xy 59.93649 -12.954901) (xy 59.860296 -12.878707)
			(xy 59.789732 -12.797272) (xy 59.725157 -12.71101) (xy 59.666901 -12.620361) (xy 59.61526 -12.525788)
			(xy 59.570496 -12.427771) (xy 59.53284 -12.326811) (xy 59.502481 -12.223422) (xy 59.479575 -12.11813)
			(xy 59.464239 -12.011473) (xy 59.456551 -11.903993) (xy 59.456066 -11.850116) (xy 59.456066 -1.999996)
			(xy 59.455557 -1.944227) (xy 59.447222 -1.833) (xy 59.430597 -1.722708) (xy 59.405777 -1.613966)
			(xy 59.3729 -1.507383) (xy 59.33215 -1.403555) (xy 59.283755 -1.303062) (xy 59.227986 -1.206467)
			(xy 59.165153 -1.11431) (xy 59.09561 -1.027107) (xy 59.019744 -0.945344) (xy 58.93798 -0.869479)
			(xy 58.850775 -0.799936) (xy 58.758617 -0.737105) (xy 58.662022 -0.681336) (xy 58.561529 -0.632942)
			(xy 58.4577 -0.592194) (xy 58.351117 -0.559318) (xy 58.242375 -0.534499) (xy 58.132082 -0.517876)
			(xy 58.020855 -0.509542) (xy 57.965086 -0.509016) (xy 45.96511 -0.509016) (xy 45.90934 -0.509524)
			(xy 45.798112 -0.517859) (xy 45.687819 -0.534482) (xy 45.579075 -0.559301) (xy 45.472491 -0.592178)
			(xy 45.368661 -0.632927) (xy 45.268167 -0.681322) (xy 45.171571 -0.737091) (xy 45.079412 -0.799923)
			(xy 44.992207 -0.869466) (xy 44.910442 -0.945332) (xy 44.834576 -1.027096) (xy 44.765031 -1.114301)
			(xy 44.702198 -1.206459) (xy 44.646428 -1.303055) (xy 44.598033 -1.403549) (xy 44.557282 -1.507378)
			(xy 44.524405 -1.613962) (xy 44.499585 -1.722705) (xy 44.48296 -1.832999) (xy 44.474625 -1.944226)
			(xy 44.47413 -1.999996) (xy 44.47413 -11.850116) (xy 44.473649 -11.903993) (xy 44.46596 -12.011473)
			(xy 44.450624 -12.118131) (xy 44.427719 -12.223422) (xy 44.39736 -12.326812) (xy 44.359703 -12.427772)
			(xy 44.31494 -12.525789) (xy 44.263298 -12.620363) (xy 44.205042 -12.711011) (xy 44.140467 -12.797273)
			(xy 44.069902 -12.878708) (xy 43.993708 -12.954902) (xy 43.912273 -13.025467) (xy 43.826011 -13.090042)
			(xy 43.735363 -13.148298) (xy 43.640789 -13.19994) (xy 43.542772 -13.244703) (xy 43.441812 -13.28236)
			(xy 43.338422 -13.312719) (xy 43.233131 -13.335624) (xy 43.126473 -13.35096) (xy 43.018993 -13.358649)
			(xy 42.965116 -13.35913) (xy 34.964878 -13.35913) (xy 34.911001 -13.358648) (xy 34.803521 -13.35096)
			(xy 34.696864 -13.335624) (xy 34.591573 -13.312718) (xy 34.488184 -13.282359) (xy 34.387224 -13.244702)
			(xy 34.289207 -13.199938) (xy 34.194634 -13.148296) (xy 34.103986 -13.09004) (xy 34.017724 -13.025464)
			(xy 33.936289 -12.9549) (xy 33.860096 -12.878706) (xy 33.789532 -12.797271) (xy 33.724957 -12.711009)
			(xy 33.666701 -12.620361) (xy 33.615059 -12.525787) (xy 33.570296 -12.427771) (xy 33.532639 -12.326811)
			(xy 33.502281 -12.223422) (xy 33.479375 -12.11813) (xy 33.464039 -12.011473) (xy 33.456351 -11.903993)
			(xy 33.455864 -11.850116) (xy 33.455864 -1.999996) (xy 33.455355 -1.944227) (xy 33.44702 -1.833)
			(xy 33.430395 -1.722708) (xy 33.405575 -1.613966) (xy 33.372698 -1.507383) (xy 33.331948 -1.403555)
			(xy 33.283553 -1.303063) (xy 33.227783 -1.206468) (xy 33.164951 -1.114311) (xy 33.095408 -1.027107)
			(xy 33.019542 -0.945344) (xy 32.937778 -0.869479) (xy 32.850573 -0.799937) (xy 32.758415 -0.737106)
			(xy 32.66182 -0.681337) (xy 32.561327 -0.632944) (xy 32.457498 -0.592195) (xy 32.350915 -0.559319)
			(xy 32.242173 -0.534501) (xy 32.13188 -0.517878) (xy 32.020653 -0.509544) (xy 31.964884 -0.509016)
			(xy 19.964908 -0.509016) (xy 19.909138 -0.509524) (xy 19.797911 -0.517859) (xy 19.687617 -0.534483)
			(xy 19.578874 -0.559302) (xy 19.472289 -0.592178) (xy 19.36846 -0.632928) (xy 19.267966 -0.681322)
			(xy 19.17137 -0.737092) (xy 19.079211 -0.799924) (xy 18.992006 -0.869467) (xy 18.910241 -0.945333)
			(xy 18.834375 -1.027097) (xy 18.764831 -1.114302) (xy 18.701998 -1.20646) (xy 18.646228 -1.303056)
			(xy 18.597832 -1.403549) (xy 18.557082 -1.507378) (xy 18.524205 -1.613962) (xy 18.499385 -1.722705)
			(xy 18.48276 -1.832999) (xy 18.474425 -1.944226) (xy 18.473928 -1.999996) (xy 18.473928 -11.850116)
			(xy 18.473447 -11.903994) (xy 18.46576 -12.011474) (xy 18.450426 -12.118132) (xy 18.427521 -12.223425)
			(xy 18.397163 -12.326815) (xy 18.359507 -12.427777) (xy 18.314744 -12.525794) (xy 18.263103 -12.620369)
			(xy 18.204846 -12.711018) (xy 18.140271 -12.797281) (xy 18.069707 -12.878717) (xy 17.993513 -12.954911)
			(xy 17.912077 -13.025476) (xy 17.825815 -13.090052) (xy 17.735166 -13.148309) (xy 17.640591 -13.19995)
			(xy 17.542574 -13.244714) (xy 17.441613 -13.282371) (xy 17.338223 -13.312729) (xy 17.23293 -13.335634)
			(xy 17.126272 -13.35097) (xy 17.018792 -13.358657) (xy 16.964914 -13.35913) (xy 8.96493 -13.35913)
			(xy 8.911052 -13.35866) (xy 8.803571 -13.350973) (xy 8.696913 -13.335638) (xy 8.59162 -13.312733)
			(xy 8.488229 -13.282374) (xy 8.387268 -13.244718) (xy 8.28925 -13.199954) (xy 8.194675 -13.148313)
			(xy 8.104026 -13.090055) (xy 8.017763 -13.02548) (xy 7.936327 -12.954915) (xy 7.860132 -12.87872)
			(xy 7.789568 -12.797284) (xy 7.724992 -12.711021) (xy 7.666735 -12.620371) (xy 7.615094 -12.525797)
			(xy 7.570331 -12.427779) (xy 7.532674 -12.326817) (xy 7.502316 -12.223426) (xy 7.479412 -12.118133)
			(xy 7.464077 -12.011475) (xy 7.45639 -11.903994) (xy 7.455916 -11.850116) (xy 7.455916 -1.999996)
			(xy 7.455394 -1.944227) (xy 7.447059 -1.833001) (xy 7.430435 -1.722709) (xy 7.405615 -1.613968) (xy 7.372738 -1.507386)
			(xy 7.331989 -1.403558) (xy 7.283594 -1.303066) (xy 7.227825 -1.206472) (xy 7.164993 -1.114315) (xy 7.09545 -1.027112)
			(xy 7.019585 -0.945349) (xy 6.937822 -0.869484) (xy 6.850618 -0.799942) (xy 6.758461 -0.737111) (xy 6.661866 -0.681342)
			(xy 6.561374 -0.632948) (xy 6.457547 -0.592199) (xy 6.350964 -0.559323) (xy 6.242223 -0.534504) (xy 6.131931 -0.51788)
			(xy 6.020705 -0.509545) (xy 5.964936 -0.509016) (xy 4.689348 -0.509016) (xy 4.688332 -0.508) (xy 3.140456 -0.508)
			(xy 3.13944 -0.509016) (xy 1.999996 -0.509016) (xy 1.944227 -0.509538) (xy 1.833001 -0.517873) (xy 1.722709 -0.534497)
			(xy 1.613967 -0.559317) (xy 1.507385 -0.592194) (xy 1.403557 -0.632943) (xy 1.303065 -0.681338) (xy 1.20647 -0.737107)
			(xy 1.114313 -0.799938) (xy 1.027109 -0.869481) (xy 0.945346 -0.945346) (xy 0.869481 -1.027109) (xy 0.799938 -1.114313)
			(xy 0.737107 -1.20647) (xy 0.681338 -1.303065) (xy 0.632943 -1.403557) (xy 0.592194 -1.507385) (xy 0.559317 -1.613967)
			(xy 0.534497 -1.722709) (xy 0.517873 -1.833001) (xy 0.509538 -1.944227) (xy 0.509016 -1.999996) (xy 0.509016 -15.200122)
			(xy 459.541372 -15.200122) (xy 459.541372 -13.599922) (xy 459.54188 -13.535242) (xy 459.550003 -13.406136)
			(xy 459.566216 -13.277796) (xy 459.590456 -13.150726) (xy 459.622626 -13.02543) (xy 459.662601 -12.9024)
			(xy 459.710222 -12.782124) (xy 459.765301 -12.665075) (xy 459.827621 -12.551715) (xy 459.896936 -12.442492)
			(xy 459.972972 -12.337837) (xy 460.05543 -12.238163) (xy 460.143983 -12.143863) (xy 460.238283 -12.05531)
			(xy 460.337957 -11.972852) (xy 460.442612 -11.896816) (xy 460.551835 -11.827501) (xy 460.665195 -11.765181)
			(xy 460.782244 -11.710102) (xy 460.90252 -11.662481) (xy 461.02555 -11.622506) (xy 461.150846 -11.590336)
			(xy 461.277916 -11.566096) (xy 461.406256 -11.549883) (xy 461.535362 -11.54176) (xy 461.664722 -11.54176)
			(xy 461.793828 -11.549883) (xy 461.922168 -11.566096) (xy 462.049238 -11.590336) (xy 462.174534 -11.622506)
			(xy 462.297564 -11.662481) (xy 462.41784 -11.710102) (xy 462.534889 -11.765181) (xy 462.648249 -11.827501)
			(xy 462.757472 -11.896816) (xy 462.862127 -11.972852) (xy 462.961801 -12.05531) (xy 463.056101 -12.143863)
			(xy 463.144654 -12.238163) (xy 463.227112 -12.337837) (xy 463.303148 -12.442492) (xy 463.372463 -12.551715)
			(xy 463.434783 -12.665075) (xy 463.489862 -12.782124) (xy 463.537483 -12.9024) (xy 463.577458 -13.02543)
			(xy 463.609628 -13.150726) (xy 463.633868 -13.277796) (xy 463.650081 -13.406136) (xy 463.658204 -13.535242)
			(xy 463.658712 -13.599922) (xy 463.658712 -15.200122) (xy 463.658204 -15.264802) (xy 463.650081 -15.393908)
			(xy 463.633868 -15.522248) (xy 463.609628 -15.649318) (xy 463.577458 -15.774614) (xy 463.537483 -15.897644)
			(xy 463.489862 -16.01792) (xy 463.434783 -16.134969) (xy 463.372463 -16.248329) (xy 463.303148 -16.357552)
			(xy 463.227112 -16.462207) (xy 463.144654 -16.561881) (xy 463.056101 -16.656181) (xy 462.961801 -16.744734)
			(xy 462.862127 -16.827192) (xy 462.757472 -16.903228) (xy 462.648249 -16.972543) (xy 462.534889 -17.034863)
			(xy 462.41784 -17.089942) (xy 462.297564 -17.137563) (xy 462.174534 -17.177538) (xy 462.049238 -17.209708)
			(xy 461.922168 -17.233948) (xy 461.793828 -17.250161) (xy 461.664722 -17.258284) (xy 461.535362 -17.258284)
			(xy 461.406256 -17.250161) (xy 461.277916 -17.233948) (xy 461.150846 -17.209708) (xy 461.02555 -17.177538)
			(xy 460.90252 -17.137563) (xy 460.782244 -17.089942) (xy 460.665195 -17.034863) (xy 460.551835 -16.972543)
			(xy 460.442612 -16.903228) (xy 460.337957 -16.827192) (xy 460.238283 -16.744734) (xy 460.143983 -16.656181)
			(xy 460.05543 -16.561881) (xy 459.972972 -16.462207) (xy 459.896936 -16.357552) (xy 459.827621 -16.248329)
			(xy 459.765301 -16.134969) (xy 459.710222 -16.01792) (xy 459.662601 -15.897644) (xy 459.622626 -15.774614)
			(xy 459.590456 -15.649318) (xy 459.566216 -15.522248) (xy 459.550003 -15.393908) (xy 459.54188 -15.264802)
			(xy 459.541372 -15.200122) (xy 0.509016 -15.200122) (xy 0.509016 -16.969994) (xy 13.748265 -16.969994)
			(xy 13.75227 -16.882086) (xy 13.764253 -16.794906) (xy 13.784113 -16.709177) (xy 13.811688 -16.625609)
			(xy 13.846747 -16.544895) (xy 13.889 -16.467703) (xy 13.938098 -16.394674) (xy 13.993634 -16.326412)
			(xy 14.055146 -16.263482) (xy 14.122127 -16.206408) (xy 14.19402 -16.15566) (xy 14.270229 -16.11166)
			(xy 14.350124 -16.074773) (xy 14.433043 -16.045304) (xy 14.518298 -16.023497) (xy 14.605182 -16.009533)
			(xy 14.692976 -16.003527) (xy 14.780953 -16.005531) (xy 14.868383 -16.015526) (xy 14.954542 -16.03343)
			(xy 15.038716 -16.059094) (xy 15.120207 -16.092307) (xy 15.198341 -16.132793) (xy 15.272469 -16.180215)
			(xy 15.341977 -16.234182) (xy 15.406291 -16.294247) (xy 15.464875 -16.359911) (xy 15.517246 -16.43063)
			(xy 15.562969 -16.505818) (xy 15.601666 -16.584853) (xy 15.633015 -16.667079) (xy 15.656757 -16.751815)
			(xy 15.672695 -16.838359) (xy 15.680697 -16.925994) (xy 15.681198 -16.969994) (xy 39.748213 -16.969994)
			(xy 39.752218 -16.882086) (xy 39.764201 -16.794906) (xy 39.784061 -16.709177) (xy 39.811636 -16.625609)
			(xy 39.846695 -16.544895) (xy 39.888948 -16.467703) (xy 39.938046 -16.394674) (xy 39.993582 -16.326412)
			(xy 40.055094 -16.263482) (xy 40.122075 -16.206408) (xy 40.193968 -16.15566) (xy 40.270177 -16.11166)
			(xy 40.350072 -16.074773) (xy 40.432991 -16.045304) (xy 40.518246 -16.023497) (xy 40.60513 -16.009533)
			(xy 40.692924 -16.003527) (xy 40.780901 -16.005531) (xy 40.868331 -16.015526) (xy 40.95449 -16.03343)
			(xy 41.038664 -16.059094) (xy 41.120155 -16.092307) (xy 41.198289 -16.132793) (xy 41.272417 -16.180215)
			(xy 41.341925 -16.234182) (xy 41.406239 -16.294247) (xy 41.464823 -16.359911) (xy 41.517194 -16.43063)
			(xy 41.562917 -16.505818) (xy 41.601614 -16.584853) (xy 41.632963 -16.667079) (xy 41.656705 -16.751815)
			(xy 41.672643 -16.838359) (xy 41.680645 -16.925994) (xy 41.681146 -16.969994) (xy 65.748161 -16.969994)
			(xy 65.752166 -16.882086) (xy 65.764149 -16.794906) (xy 65.784009 -16.709177) (xy 65.811584 -16.625609)
			(xy 65.846643 -16.544895) (xy 65.888896 -16.467703) (xy 65.937994 -16.394674) (xy 65.99353 -16.326412)
			(xy 66.055042 -16.263482) (xy 66.122023 -16.206408) (xy 66.193916 -16.15566) (xy 66.270125 -16.11166)
			(xy 66.35002 -16.074773) (xy 66.432939 -16.045304) (xy 66.518194 -16.023497) (xy 66.605078 -16.009533)
			(xy 66.692872 -16.003527) (xy 66.780849 -16.005531) (xy 66.868279 -16.015526) (xy 66.954438 -16.03343)
			(xy 67.038612 -16.059094) (xy 67.120103 -16.092307) (xy 67.198237 -16.132793) (xy 67.272365 -16.180215)
			(xy 67.341873 -16.234182) (xy 67.406187 -16.294247) (xy 67.464771 -16.359911) (xy 67.517142 -16.43063)
			(xy 67.562865 -16.505818) (xy 67.601562 -16.584853) (xy 67.632911 -16.667079) (xy 67.656653 -16.751815)
			(xy 67.672591 -16.838359) (xy 67.680593 -16.925994) (xy 67.681094 -16.969994) (xy 91.748109 -16.969994)
			(xy 91.752114 -16.882086) (xy 91.764097 -16.794906) (xy 91.783957 -16.709177) (xy 91.811532 -16.625609)
			(xy 91.846591 -16.544895) (xy 91.888844 -16.467703) (xy 91.937942 -16.394674) (xy 91.993478 -16.326412)
			(xy 92.05499 -16.263482) (xy 92.121971 -16.206408) (xy 92.193864 -16.15566) (xy 92.270073 -16.11166)
			(xy 92.349968 -16.074773) (xy 92.432887 -16.045304) (xy 92.518142 -16.023497) (xy 92.605026 -16.009533)
			(xy 92.69282 -16.003527) (xy 92.780797 -16.005531) (xy 92.868227 -16.015526) (xy 92.954386 -16.03343)
			(xy 93.03856 -16.059094) (xy 93.120051 -16.092307) (xy 93.198185 -16.132793) (xy 93.272313 -16.180215)
			(xy 93.341821 -16.234182) (xy 93.406135 -16.294247) (xy 93.464719 -16.359911) (xy 93.51709 -16.43063)
			(xy 93.562813 -16.505818) (xy 93.60151 -16.584853) (xy 93.632859 -16.667079) (xy 93.656601 -16.751815)
			(xy 93.672539 -16.838359) (xy 93.680541 -16.925994) (xy 93.681042 -16.969994) (xy 129.848363 -16.969994)
			(xy 129.852368 -16.882086) (xy 129.864351 -16.794906) (xy 129.884211 -16.709177) (xy 129.911786 -16.625609)
			(xy 129.946845 -16.544895) (xy 129.989098 -16.467703) (xy 130.038196 -16.394674) (xy 130.093732 -16.326412)
			(xy 130.155244 -16.263482) (xy 130.222225 -16.206408) (xy 130.294118 -16.15566) (xy 130.370327 -16.11166)
			(xy 130.450222 -16.074773) (xy 130.533141 -16.045304) (xy 130.618396 -16.023497) (xy 130.70528 -16.009533)
			(xy 130.793074 -16.003527) (xy 130.881051 -16.005531) (xy 130.968481 -16.015526) (xy 131.05464 -16.03343)
			(xy 131.138814 -16.059094) (xy 131.220305 -16.092307) (xy 131.298439 -16.132793) (xy 131.372567 -16.180215)
			(xy 131.442075 -16.234182) (xy 131.506389 -16.294247) (xy 131.564973 -16.359911) (xy 131.617344 -16.43063)
			(xy 131.663067 -16.505818) (xy 131.701764 -16.584853) (xy 131.733113 -16.667079) (xy 131.756855 -16.751815)
			(xy 131.772793 -16.838359) (xy 131.780795 -16.925994) (xy 131.781296 -16.969994) (xy 155.848311 -16.969994)
			(xy 155.852316 -16.882086) (xy 155.864299 -16.794906) (xy 155.884159 -16.709177) (xy 155.911734 -16.625609)
			(xy 155.946793 -16.544895) (xy 155.989046 -16.467703) (xy 156.038144 -16.394674) (xy 156.09368 -16.326412)
			(xy 156.155192 -16.263482) (xy 156.222173 -16.206408) (xy 156.294066 -16.15566) (xy 156.370275 -16.11166)
			(xy 156.45017 -16.074773) (xy 156.533089 -16.045304) (xy 156.618344 -16.023497) (xy 156.705228 -16.009533)
			(xy 156.793022 -16.003527) (xy 156.880999 -16.005531) (xy 156.968429 -16.015526) (xy 157.054588 -16.03343)
			(xy 157.138762 -16.059094) (xy 157.220253 -16.092307) (xy 157.298387 -16.132793) (xy 157.372515 -16.180215)
			(xy 157.442023 -16.234182) (xy 157.506337 -16.294247) (xy 157.564921 -16.359911) (xy 157.617292 -16.43063)
			(xy 157.663015 -16.505818) (xy 157.701712 -16.584853) (xy 157.733061 -16.667079) (xy 157.756803 -16.751815)
			(xy 157.772741 -16.838359) (xy 157.780743 -16.925994) (xy 157.781244 -16.969994) (xy 181.848259 -16.969994)
			(xy 181.852264 -16.882086) (xy 181.864247 -16.794906) (xy 181.884107 -16.709177) (xy 181.911682 -16.625609)
			(xy 181.946741 -16.544895) (xy 181.988994 -16.467703) (xy 182.038092 -16.394674) (xy 182.093628 -16.326412)
			(xy 182.15514 -16.263482) (xy 182.222121 -16.206408) (xy 182.294014 -16.15566) (xy 182.370223 -16.11166)
			(xy 182.450118 -16.074773) (xy 182.533037 -16.045304) (xy 182.618292 -16.023497) (xy 182.705176 -16.009533)
			(xy 182.79297 -16.003527) (xy 182.880947 -16.005531) (xy 182.968377 -16.015526) (xy 183.054536 -16.03343)
			(xy 183.13871 -16.059094) (xy 183.220201 -16.092307) (xy 183.298335 -16.132793) (xy 183.372463 -16.180215)
			(xy 183.441971 -16.234182) (xy 183.506285 -16.294247) (xy 183.564869 -16.359911) (xy 183.61724 -16.43063)
			(xy 183.662963 -16.505818) (xy 183.70166 -16.584853) (xy 183.733009 -16.667079) (xy 183.756751 -16.751815)
			(xy 183.772689 -16.838359) (xy 183.780691 -16.925994) (xy 183.781192 -16.969994) (xy 207.848207 -16.969994)
			(xy 207.852212 -16.882086) (xy 207.864195 -16.794906) (xy 207.884055 -16.709177) (xy 207.91163 -16.625609)
			(xy 207.946689 -16.544895) (xy 207.988942 -16.467703) (xy 208.03804 -16.394674) (xy 208.093576 -16.326412)
			(xy 208.155088 -16.263482) (xy 208.222069 -16.206408) (xy 208.293962 -16.15566) (xy 208.370171 -16.11166)
			(xy 208.450066 -16.074773) (xy 208.532985 -16.045304) (xy 208.61824 -16.023497) (xy 208.705124 -16.009533)
			(xy 208.792918 -16.003527) (xy 208.880895 -16.005531) (xy 208.968325 -16.015526) (xy 209.054484 -16.03343)
			(xy 209.138658 -16.059094) (xy 209.220149 -16.092307) (xy 209.298283 -16.132793) (xy 209.372411 -16.180215)
			(xy 209.441919 -16.234182) (xy 209.506233 -16.294247) (xy 209.564817 -16.359911) (xy 209.617188 -16.43063)
			(xy 209.662911 -16.505818) (xy 209.701608 -16.584853) (xy 209.732957 -16.667079) (xy 209.756699 -16.751815)
			(xy 209.772637 -16.838359) (xy 209.780639 -16.925994) (xy 209.78114 -16.969994) (xy 245.948207 -16.969994)
			(xy 245.952212 -16.882086) (xy 245.964195 -16.794906) (xy 245.984055 -16.709177) (xy 246.01163 -16.625609)
			(xy 246.046689 -16.544895) (xy 246.088942 -16.467703) (xy 246.13804 -16.394674) (xy 246.193576 -16.326412)
			(xy 246.255088 -16.263482) (xy 246.322069 -16.206408) (xy 246.393962 -16.15566) (xy 246.470171 -16.11166)
			(xy 246.550066 -16.074773) (xy 246.632985 -16.045304) (xy 246.71824 -16.023497) (xy 246.805124 -16.009533)
			(xy 246.892918 -16.003527) (xy 246.980895 -16.005531) (xy 247.068325 -16.015526) (xy 247.154484 -16.03343)
			(xy 247.238658 -16.059094) (xy 247.320149 -16.092307) (xy 247.398283 -16.132793) (xy 247.472411 -16.180215)
			(xy 247.541919 -16.234182) (xy 247.606233 -16.294247) (xy 247.664817 -16.359911) (xy 247.717188 -16.43063)
			(xy 247.762911 -16.505818) (xy 247.801608 -16.584853) (xy 247.832957 -16.667079) (xy 247.856699 -16.751815)
			(xy 247.872637 -16.838359) (xy 247.880639 -16.925994) (xy 247.88114 -16.969994) (xy 271.948155 -16.969994)
			(xy 271.95216 -16.882086) (xy 271.964143 -16.794906) (xy 271.984003 -16.709177) (xy 272.011578 -16.625609)
			(xy 272.046637 -16.544895) (xy 272.08889 -16.467703) (xy 272.137988 -16.394674) (xy 272.193524 -16.326412)
			(xy 272.255036 -16.263482) (xy 272.322017 -16.206408) (xy 272.39391 -16.15566) (xy 272.470119 -16.11166)
			(xy 272.550014 -16.074773) (xy 272.632933 -16.045304) (xy 272.718188 -16.023497) (xy 272.805072 -16.009533)
			(xy 272.892866 -16.003527) (xy 272.980843 -16.005531) (xy 273.068273 -16.015526) (xy 273.154432 -16.03343)
			(xy 273.238606 -16.059094) (xy 273.320097 -16.092307) (xy 273.398231 -16.132793) (xy 273.472359 -16.180215)
			(xy 273.541867 -16.234182) (xy 273.606181 -16.294247) (xy 273.664765 -16.359911) (xy 273.717136 -16.43063)
			(xy 273.762859 -16.505818) (xy 273.801556 -16.584853) (xy 273.832905 -16.667079) (xy 273.856647 -16.751815)
			(xy 273.872585 -16.838359) (xy 273.880587 -16.925994) (xy 273.881088 -16.969994) (xy 297.948103 -16.969994)
			(xy 297.952108 -16.882086) (xy 297.964091 -16.794906) (xy 297.983951 -16.709177) (xy 298.011526 -16.625609)
			(xy 298.046585 -16.544895) (xy 298.088838 -16.467703) (xy 298.137936 -16.394674) (xy 298.193472 -16.326412)
			(xy 298.254984 -16.263482) (xy 298.321965 -16.206408) (xy 298.393858 -16.15566) (xy 298.470067 -16.11166)
			(xy 298.549962 -16.074773) (xy 298.632881 -16.045304) (xy 298.718136 -16.023497) (xy 298.80502 -16.009533)
			(xy 298.892814 -16.003527) (xy 298.980791 -16.005531) (xy 299.068221 -16.015526) (xy 299.15438 -16.03343)
			(xy 299.238554 -16.059094) (xy 299.320045 -16.092307) (xy 299.398179 -16.132793) (xy 299.472307 -16.180215)
			(xy 299.541815 -16.234182) (xy 299.606129 -16.294247) (xy 299.664713 -16.359911) (xy 299.717084 -16.43063)
			(xy 299.762807 -16.505818) (xy 299.801504 -16.584853) (xy 299.832853 -16.667079) (xy 299.856595 -16.751815)
			(xy 299.872533 -16.838359) (xy 299.880535 -16.925994) (xy 299.881036 -16.969994) (xy 323.948051 -16.969994)
			(xy 323.952056 -16.882086) (xy 323.964039 -16.794906) (xy 323.983899 -16.709177) (xy 324.011474 -16.625609)
			(xy 324.046533 -16.544895) (xy 324.088786 -16.467703) (xy 324.137884 -16.394674) (xy 324.19342 -16.326412)
			(xy 324.254932 -16.263482) (xy 324.321913 -16.206408) (xy 324.393806 -16.15566) (xy 324.470015 -16.11166)
			(xy 324.54991 -16.074773) (xy 324.632829 -16.045304) (xy 324.718084 -16.023497) (xy 324.804968 -16.009533)
			(xy 324.892762 -16.003527) (xy 324.980739 -16.005531) (xy 325.068169 -16.015526) (xy 325.154328 -16.03343)
			(xy 325.238502 -16.059094) (xy 325.319993 -16.092307) (xy 325.398127 -16.132793) (xy 325.472255 -16.180215)
			(xy 325.541763 -16.234182) (xy 325.606077 -16.294247) (xy 325.664661 -16.359911) (xy 325.717032 -16.43063)
			(xy 325.762755 -16.505818) (xy 325.801452 -16.584853) (xy 325.832801 -16.667079) (xy 325.856543 -16.751815)
			(xy 325.872481 -16.838359) (xy 325.880483 -16.925994) (xy 325.880984 -16.969994) (xy 362.048305 -16.969994)
			(xy 362.05231 -16.882086) (xy 362.064293 -16.794906) (xy 362.084153 -16.709177) (xy 362.111728 -16.625609)
			(xy 362.146787 -16.544895) (xy 362.18904 -16.467703) (xy 362.238138 -16.394674) (xy 362.293674 -16.326412)
			(xy 362.355186 -16.263482) (xy 362.422167 -16.206408) (xy 362.49406 -16.15566) (xy 362.570269 -16.11166)
			(xy 362.650164 -16.074773) (xy 362.733083 -16.045304) (xy 362.818338 -16.023497) (xy 362.905222 -16.009533)
			(xy 362.993016 -16.003527) (xy 363.080993 -16.005531) (xy 363.168423 -16.015526) (xy 363.254582 -16.03343)
			(xy 363.338756 -16.059094) (xy 363.420247 -16.092307) (xy 363.498381 -16.132793) (xy 363.572509 -16.180215)
			(xy 363.642017 -16.234182) (xy 363.706331 -16.294247) (xy 363.764915 -16.359911) (xy 363.817286 -16.43063)
			(xy 363.863009 -16.505818) (xy 363.901706 -16.584853) (xy 363.933055 -16.667079) (xy 363.956797 -16.751815)
			(xy 363.972735 -16.838359) (xy 363.980737 -16.925994) (xy 363.981238 -16.969994) (xy 388.048253 -16.969994)
			(xy 388.052258 -16.882086) (xy 388.064241 -16.794906) (xy 388.084101 -16.709177) (xy 388.111676 -16.625609)
			(xy 388.146735 -16.544895) (xy 388.188988 -16.467703) (xy 388.238086 -16.394674) (xy 388.293622 -16.326412)
			(xy 388.355134 -16.263482) (xy 388.422115 -16.206408) (xy 388.494008 -16.15566) (xy 388.570217 -16.11166)
			(xy 388.650112 -16.074773) (xy 388.733031 -16.045304) (xy 388.818286 -16.023497) (xy 388.90517 -16.009533)
			(xy 388.992964 -16.003527) (xy 389.080941 -16.005531) (xy 389.168371 -16.015526) (xy 389.25453 -16.03343)
			(xy 389.338704 -16.059094) (xy 389.420195 -16.092307) (xy 389.498329 -16.132793) (xy 389.572457 -16.180215)
			(xy 389.641965 -16.234182) (xy 389.706279 -16.294247) (xy 389.764863 -16.359911) (xy 389.817234 -16.43063)
			(xy 389.862957 -16.505818) (xy 389.901654 -16.584853) (xy 389.933003 -16.667079) (xy 389.956745 -16.751815)
			(xy 389.972683 -16.838359) (xy 389.980685 -16.925994) (xy 389.981186 -16.969994) (xy 414.048201 -16.969994)
			(xy 414.052206 -16.882086) (xy 414.064189 -16.794906) (xy 414.084049 -16.709177) (xy 414.111624 -16.625609)
			(xy 414.146683 -16.544895) (xy 414.188936 -16.467703) (xy 414.238034 -16.394674) (xy 414.29357 -16.326412)
			(xy 414.355082 -16.263482) (xy 414.422063 -16.206408) (xy 414.493956 -16.15566) (xy 414.570165 -16.11166)
			(xy 414.65006 -16.074773) (xy 414.732979 -16.045304) (xy 414.818234 -16.023497) (xy 414.905118 -16.009533)
			(xy 414.992912 -16.003527) (xy 415.080889 -16.005531) (xy 415.168319 -16.015526) (xy 415.254478 -16.03343)
			(xy 415.338652 -16.059094) (xy 415.420143 -16.092307) (xy 415.498277 -16.132793) (xy 415.572405 -16.180215)
			(xy 415.641913 -16.234182) (xy 415.706227 -16.294247) (xy 415.764811 -16.359911) (xy 415.817182 -16.43063)
			(xy 415.862905 -16.505818) (xy 415.901602 -16.584853) (xy 415.932951 -16.667079) (xy 415.956693 -16.751815)
			(xy 415.972631 -16.838359) (xy 415.980633 -16.925994) (xy 415.981134 -16.969994) (xy 440.048149 -16.969994)
			(xy 440.052154 -16.882086) (xy 440.064137 -16.794906) (xy 440.083997 -16.709177) (xy 440.111572 -16.625609)
			(xy 440.146631 -16.544895) (xy 440.188884 -16.467703) (xy 440.237982 -16.394674) (xy 440.293518 -16.326412)
			(xy 440.35503 -16.263482) (xy 440.422011 -16.206408) (xy 440.493904 -16.15566) (xy 440.570113 -16.11166)
			(xy 440.650008 -16.074773) (xy 440.732927 -16.045304) (xy 440.818182 -16.023497) (xy 440.905066 -16.009533)
			(xy 440.99286 -16.003527) (xy 441.080837 -16.005531) (xy 441.168267 -16.015526) (xy 441.254426 -16.03343)
			(xy 441.3386 -16.059094) (xy 441.420091 -16.092307) (xy 441.498225 -16.132793) (xy 441.572353 -16.180215)
			(xy 441.641861 -16.234182) (xy 441.706175 -16.294247) (xy 441.764759 -16.359911) (xy 441.81713 -16.43063)
			(xy 441.862853 -16.505818) (xy 441.90155 -16.584853) (xy 441.932899 -16.667079) (xy 441.956641 -16.751815)
			(xy 441.972579 -16.838359) (xy 441.980581 -16.925994) (xy 441.981082 -16.969994) (xy 441.980581 -17.013994)
			(xy 441.972579 -17.101629) (xy 441.956641 -17.188173) (xy 441.932899 -17.272909) (xy 441.90155 -17.355135)
			(xy 441.862853 -17.43417) (xy 441.81713 -17.509358) (xy 441.764759 -17.580077) (xy 441.706175 -17.645741)
			(xy 441.641861 -17.705806) (xy 441.572353 -17.759773) (xy 441.498225 -17.807195) (xy 441.420091 -17.847681)
			(xy 441.3386 -17.880894) (xy 441.254426 -17.906558) (xy 441.168267 -17.924462) (xy 441.080837 -17.934457)
			(xy 440.99286 -17.936461) (xy 440.905066 -17.930455) (xy 440.818182 -17.916491) (xy 440.732927 -17.894684)
			(xy 440.650008 -17.865215) (xy 440.570113 -17.828328) (xy 440.493904 -17.784328) (xy 440.422011 -17.73358)
			(xy 440.35503 -17.676506) (xy 440.293518 -17.613576) (xy 440.237982 -17.545314) (xy 440.188884 -17.472285)
			(xy 440.146631 -17.395093) (xy 440.111572 -17.314379) (xy 440.083997 -17.230811) (xy 440.064137 -17.145082)
			(xy 440.052154 -17.057902) (xy 440.048149 -16.969994) (xy 415.981134 -16.969994) (xy 415.980633 -17.013994)
			(xy 415.972631 -17.101629) (xy 415.956693 -17.188173) (xy 415.932951 -17.272909) (xy 415.901602 -17.355135)
			(xy 415.862905 -17.43417) (xy 415.817182 -17.509358) (xy 415.764811 -17.580077) (xy 415.706227 -17.645741)
			(xy 415.641913 -17.705806) (xy 415.572405 -17.759773) (xy 415.498277 -17.807195) (xy 415.420143 -17.847681)
			(xy 415.338652 -17.880894) (xy 415.254478 -17.906558) (xy 415.168319 -17.924462) (xy 415.080889 -17.934457)
			(xy 414.992912 -17.936461) (xy 414.905118 -17.930455) (xy 414.818234 -17.916491) (xy 414.732979 -17.894684)
			(xy 414.65006 -17.865215) (xy 414.570165 -17.828328) (xy 414.493956 -17.784328) (xy 414.422063 -17.73358)
			(xy 414.355082 -17.676506) (xy 414.29357 -17.613576) (xy 414.238034 -17.545314) (xy 414.188936 -17.472285)
			(xy 414.146683 -17.395093) (xy 414.111624 -17.314379) (xy 414.084049 -17.230811) (xy 414.064189 -17.145082)
			(xy 414.052206 -17.057902) (xy 414.048201 -16.969994) (xy 389.981186 -16.969994) (xy 389.980685 -17.013994)
			(xy 389.972683 -17.101629) (xy 389.956745 -17.188173) (xy 389.933003 -17.272909) (xy 389.901654 -17.355135)
			(xy 389.862957 -17.43417) (xy 389.817234 -17.509358) (xy 389.764863 -17.580077) (xy 389.706279 -17.645741)
			(xy 389.641965 -17.705806) (xy 389.572457 -17.759773) (xy 389.498329 -17.807195) (xy 389.420195 -17.847681)
			(xy 389.338704 -17.880894) (xy 389.25453 -17.906558) (xy 389.168371 -17.924462) (xy 389.080941 -17.934457)
			(xy 388.992964 -17.936461) (xy 388.90517 -17.930455) (xy 388.818286 -17.916491) (xy 388.733031 -17.894684)
			(xy 388.650112 -17.865215) (xy 388.570217 -17.828328) (xy 388.494008 -17.784328) (xy 388.422115 -17.73358)
			(xy 388.355134 -17.676506) (xy 388.293622 -17.613576) (xy 388.238086 -17.545314) (xy 388.188988 -17.472285)
			(xy 388.146735 -17.395093) (xy 388.111676 -17.314379) (xy 388.084101 -17.230811) (xy 388.064241 -17.145082)
			(xy 388.052258 -17.057902) (xy 388.048253 -16.969994) (xy 363.981238 -16.969994) (xy 363.980737 -17.013994)
			(xy 363.972735 -17.101629) (xy 363.956797 -17.188173) (xy 363.933055 -17.272909) (xy 363.901706 -17.355135)
			(xy 363.863009 -17.43417) (xy 363.817286 -17.509358) (xy 363.764915 -17.580077) (xy 363.706331 -17.645741)
			(xy 363.642017 -17.705806) (xy 363.572509 -17.759773) (xy 363.498381 -17.807195) (xy 363.420247 -17.847681)
			(xy 363.338756 -17.880894) (xy 363.254582 -17.906558) (xy 363.168423 -17.924462) (xy 363.080993 -17.934457)
			(xy 362.993016 -17.936461) (xy 362.905222 -17.930455) (xy 362.818338 -17.916491) (xy 362.733083 -17.894684)
			(xy 362.650164 -17.865215) (xy 362.570269 -17.828328) (xy 362.49406 -17.784328) (xy 362.422167 -17.73358)
			(xy 362.355186 -17.676506) (xy 362.293674 -17.613576) (xy 362.238138 -17.545314) (xy 362.18904 -17.472285)
			(xy 362.146787 -17.395093) (xy 362.111728 -17.314379) (xy 362.084153 -17.230811) (xy 362.064293 -17.145082)
			(xy 362.05231 -17.057902) (xy 362.048305 -16.969994) (xy 325.880984 -16.969994) (xy 325.880483 -17.013994)
			(xy 325.872481 -17.101629) (xy 325.856543 -17.188173) (xy 325.832801 -17.272909) (xy 325.801452 -17.355135)
			(xy 325.762755 -17.43417) (xy 325.717032 -17.509358) (xy 325.664661 -17.580077) (xy 325.606077 -17.645741)
			(xy 325.541763 -17.705806) (xy 325.472255 -17.759773) (xy 325.398127 -17.807195) (xy 325.319993 -17.847681)
			(xy 325.238502 -17.880894) (xy 325.154328 -17.906558) (xy 325.068169 -17.924462) (xy 324.980739 -17.934457)
			(xy 324.892762 -17.936461) (xy 324.804968 -17.930455) (xy 324.718084 -17.916491) (xy 324.632829 -17.894684)
			(xy 324.54991 -17.865215) (xy 324.470015 -17.828328) (xy 324.393806 -17.784328) (xy 324.321913 -17.73358)
			(xy 324.254932 -17.676506) (xy 324.19342 -17.613576) (xy 324.137884 -17.545314) (xy 324.088786 -17.472285)
			(xy 324.046533 -17.395093) (xy 324.011474 -17.314379) (xy 323.983899 -17.230811) (xy 323.964039 -17.145082)
			(xy 323.952056 -17.057902) (xy 323.948051 -16.969994) (xy 299.881036 -16.969994) (xy 299.880535 -17.013994)
			(xy 299.872533 -17.101629) (xy 299.856595 -17.188173) (xy 299.832853 -17.272909) (xy 299.801504 -17.355135)
			(xy 299.762807 -17.43417) (xy 299.717084 -17.509358) (xy 299.664713 -17.580077) (xy 299.606129 -17.645741)
			(xy 299.541815 -17.705806) (xy 299.472307 -17.759773) (xy 299.398179 -17.807195) (xy 299.320045 -17.847681)
			(xy 299.238554 -17.880894) (xy 299.15438 -17.906558) (xy 299.068221 -17.924462) (xy 298.980791 -17.934457)
			(xy 298.892814 -17.936461) (xy 298.80502 -17.930455) (xy 298.718136 -17.916491) (xy 298.632881 -17.894684)
			(xy 298.549962 -17.865215) (xy 298.470067 -17.828328) (xy 298.393858 -17.784328) (xy 298.321965 -17.73358)
			(xy 298.254984 -17.676506) (xy 298.193472 -17.613576) (xy 298.137936 -17.545314) (xy 298.088838 -17.472285)
			(xy 298.046585 -17.395093) (xy 298.011526 -17.314379) (xy 297.983951 -17.230811) (xy 297.964091 -17.145082)
			(xy 297.952108 -17.057902) (xy 297.948103 -16.969994) (xy 273.881088 -16.969994) (xy 273.880587 -17.013994)
			(xy 273.872585 -17.101629) (xy 273.856647 -17.188173) (xy 273.832905 -17.272909) (xy 273.801556 -17.355135)
			(xy 273.762859 -17.43417) (xy 273.717136 -17.509358) (xy 273.664765 -17.580077) (xy 273.606181 -17.645741)
			(xy 273.541867 -17.705806) (xy 273.472359 -17.759773) (xy 273.398231 -17.807195) (xy 273.320097 -17.847681)
			(xy 273.238606 -17.880894) (xy 273.154432 -17.906558) (xy 273.068273 -17.924462) (xy 272.980843 -17.934457)
			(xy 272.892866 -17.936461) (xy 272.805072 -17.930455) (xy 272.718188 -17.916491) (xy 272.632933 -17.894684)
			(xy 272.550014 -17.865215) (xy 272.470119 -17.828328) (xy 272.39391 -17.784328) (xy 272.322017 -17.73358)
			(xy 272.255036 -17.676506) (xy 272.193524 -17.613576) (xy 272.137988 -17.545314) (xy 272.08889 -17.472285)
			(xy 272.046637 -17.395093) (xy 272.011578 -17.314379) (xy 271.984003 -17.230811) (xy 271.964143 -17.145082)
			(xy 271.95216 -17.057902) (xy 271.948155 -16.969994) (xy 247.88114 -16.969994) (xy 247.880639 -17.013994)
			(xy 247.872637 -17.101629) (xy 247.856699 -17.188173) (xy 247.832957 -17.272909) (xy 247.801608 -17.355135)
			(xy 247.762911 -17.43417) (xy 247.717188 -17.509358) (xy 247.664817 -17.580077) (xy 247.606233 -17.645741)
			(xy 247.541919 -17.705806) (xy 247.472411 -17.759773) (xy 247.398283 -17.807195) (xy 247.320149 -17.847681)
			(xy 247.238658 -17.880894) (xy 247.154484 -17.906558) (xy 247.068325 -17.924462) (xy 246.980895 -17.934457)
			(xy 246.892918 -17.936461) (xy 246.805124 -17.930455) (xy 246.71824 -17.916491) (xy 246.632985 -17.894684)
			(xy 246.550066 -17.865215) (xy 246.470171 -17.828328) (xy 246.393962 -17.784328) (xy 246.322069 -17.73358)
			(xy 246.255088 -17.676506) (xy 246.193576 -17.613576) (xy 246.13804 -17.545314) (xy 246.088942 -17.472285)
			(xy 246.046689 -17.395093) (xy 246.01163 -17.314379) (xy 245.984055 -17.230811) (xy 245.964195 -17.145082)
			(xy 245.952212 -17.057902) (xy 245.948207 -16.969994) (xy 209.78114 -16.969994) (xy 209.780639 -17.013994)
			(xy 209.772637 -17.101629) (xy 209.756699 -17.188173) (xy 209.732957 -17.272909) (xy 209.701608 -17.355135)
			(xy 209.662911 -17.43417) (xy 209.617188 -17.509358) (xy 209.564817 -17.580077) (xy 209.506233 -17.645741)
			(xy 209.441919 -17.705806) (xy 209.372411 -17.759773) (xy 209.298283 -17.807195) (xy 209.220149 -17.847681)
			(xy 209.138658 -17.880894) (xy 209.054484 -17.906558) (xy 208.968325 -17.924462) (xy 208.880895 -17.934457)
			(xy 208.792918 -17.936461) (xy 208.705124 -17.930455) (xy 208.61824 -17.916491) (xy 208.532985 -17.894684)
			(xy 208.450066 -17.865215) (xy 208.370171 -17.828328) (xy 208.293962 -17.784328) (xy 208.222069 -17.73358)
			(xy 208.155088 -17.676506) (xy 208.093576 -17.613576) (xy 208.03804 -17.545314) (xy 207.988942 -17.472285)
			(xy 207.946689 -17.395093) (xy 207.91163 -17.314379) (xy 207.884055 -17.230811) (xy 207.864195 -17.145082)
			(xy 207.852212 -17.057902) (xy 207.848207 -16.969994) (xy 183.781192 -16.969994) (xy 183.780691 -17.013994)
			(xy 183.772689 -17.101629) (xy 183.756751 -17.188173) (xy 183.733009 -17.272909) (xy 183.70166 -17.355135)
			(xy 183.662963 -17.43417) (xy 183.61724 -17.509358) (xy 183.564869 -17.580077) (xy 183.506285 -17.645741)
			(xy 183.441971 -17.705806) (xy 183.372463 -17.759773) (xy 183.298335 -17.807195) (xy 183.220201 -17.847681)
			(xy 183.13871 -17.880894) (xy 183.054536 -17.906558) (xy 182.968377 -17.924462) (xy 182.880947 -17.934457)
			(xy 182.79297 -17.936461) (xy 182.705176 -17.930455) (xy 182.618292 -17.916491) (xy 182.533037 -17.894684)
			(xy 182.450118 -17.865215) (xy 182.370223 -17.828328) (xy 182.294014 -17.784328) (xy 182.222121 -17.73358)
			(xy 182.15514 -17.676506) (xy 182.093628 -17.613576) (xy 182.038092 -17.545314) (xy 181.988994 -17.472285)
			(xy 181.946741 -17.395093) (xy 181.911682 -17.314379) (xy 181.884107 -17.230811) (xy 181.864247 -17.145082)
			(xy 181.852264 -17.057902) (xy 181.848259 -16.969994) (xy 157.781244 -16.969994) (xy 157.780743 -17.013994)
			(xy 157.772741 -17.101629) (xy 157.756803 -17.188173) (xy 157.733061 -17.272909) (xy 157.701712 -17.355135)
			(xy 157.663015 -17.43417) (xy 157.617292 -17.509358) (xy 157.564921 -17.580077) (xy 157.506337 -17.645741)
			(xy 157.442023 -17.705806) (xy 157.372515 -17.759773) (xy 157.298387 -17.807195) (xy 157.220253 -17.847681)
			(xy 157.138762 -17.880894) (xy 157.054588 -17.906558) (xy 156.968429 -17.924462) (xy 156.880999 -17.934457)
			(xy 156.793022 -17.936461) (xy 156.705228 -17.930455) (xy 156.618344 -17.916491) (xy 156.533089 -17.894684)
			(xy 156.45017 -17.865215) (xy 156.370275 -17.828328) (xy 156.294066 -17.784328) (xy 156.222173 -17.73358)
			(xy 156.155192 -17.676506) (xy 156.09368 -17.613576) (xy 156.038144 -17.545314) (xy 155.989046 -17.472285)
			(xy 155.946793 -17.395093) (xy 155.911734 -17.314379) (xy 155.884159 -17.230811) (xy 155.864299 -17.145082)
			(xy 155.852316 -17.057902) (xy 155.848311 -16.969994) (xy 131.781296 -16.969994) (xy 131.780795 -17.013994)
			(xy 131.772793 -17.101629) (xy 131.756855 -17.188173) (xy 131.733113 -17.272909) (xy 131.701764 -17.355135)
			(xy 131.663067 -17.43417) (xy 131.617344 -17.509358) (xy 131.564973 -17.580077) (xy 131.506389 -17.645741)
			(xy 131.442075 -17.705806) (xy 131.372567 -17.759773) (xy 131.298439 -17.807195) (xy 131.220305 -17.847681)
			(xy 131.138814 -17.880894) (xy 131.05464 -17.906558) (xy 130.968481 -17.924462) (xy 130.881051 -17.934457)
			(xy 130.793074 -17.936461) (xy 130.70528 -17.930455) (xy 130.618396 -17.916491) (xy 130.533141 -17.894684)
			(xy 130.450222 -17.865215) (xy 130.370327 -17.828328) (xy 130.294118 -17.784328) (xy 130.222225 -17.73358)
			(xy 130.155244 -17.676506) (xy 130.093732 -17.613576) (xy 130.038196 -17.545314) (xy 129.989098 -17.472285)
			(xy 129.946845 -17.395093) (xy 129.911786 -17.314379) (xy 129.884211 -17.230811) (xy 129.864351 -17.145082)
			(xy 129.852368 -17.057902) (xy 129.848363 -16.969994) (xy 93.681042 -16.969994) (xy 93.680541 -17.013994)
			(xy 93.672539 -17.101629) (xy 93.656601 -17.188173) (xy 93.632859 -17.272909) (xy 93.60151 -17.355135)
			(xy 93.562813 -17.43417) (xy 93.51709 -17.509358) (xy 93.464719 -17.580077) (xy 93.406135 -17.645741)
			(xy 93.341821 -17.705806) (xy 93.272313 -17.759773) (xy 93.198185 -17.807195) (xy 93.120051 -17.847681)
			(xy 93.03856 -17.880894) (xy 92.954386 -17.906558) (xy 92.868227 -17.924462) (xy 92.780797 -17.934457)
			(xy 92.69282 -17.936461) (xy 92.605026 -17.930455) (xy 92.518142 -17.916491) (xy 92.432887 -17.894684)
			(xy 92.349968 -17.865215) (xy 92.270073 -17.828328) (xy 92.193864 -17.784328) (xy 92.121971 -17.73358)
			(xy 92.05499 -17.676506) (xy 91.993478 -17.613576) (xy 91.937942 -17.545314) (xy 91.888844 -17.472285)
			(xy 91.846591 -17.395093) (xy 91.811532 -17.314379) (xy 91.783957 -17.230811) (xy 91.764097 -17.145082)
			(xy 91.752114 -17.057902) (xy 91.748109 -16.969994) (xy 67.681094 -16.969994) (xy 67.680593 -17.013994)
			(xy 67.672591 -17.101629) (xy 67.656653 -17.188173) (xy 67.632911 -17.272909) (xy 67.601562 -17.355135)
			(xy 67.562865 -17.43417) (xy 67.517142 -17.509358) (xy 67.464771 -17.580077) (xy 67.406187 -17.645741)
			(xy 67.341873 -17.705806) (xy 67.272365 -17.759773) (xy 67.198237 -17.807195) (xy 67.120103 -17.847681)
			(xy 67.038612 -17.880894) (xy 66.954438 -17.906558) (xy 66.868279 -17.924462) (xy 66.780849 -17.934457)
			(xy 66.692872 -17.936461) (xy 66.605078 -17.930455) (xy 66.518194 -17.916491) (xy 66.432939 -17.894684)
			(xy 66.35002 -17.865215) (xy 66.270125 -17.828328) (xy 66.193916 -17.784328) (xy 66.122023 -17.73358)
			(xy 66.055042 -17.676506) (xy 65.99353 -17.613576) (xy 65.937994 -17.545314) (xy 65.888896 -17.472285)
			(xy 65.846643 -17.395093) (xy 65.811584 -17.314379) (xy 65.784009 -17.230811) (xy 65.764149 -17.145082)
			(xy 65.752166 -17.057902) (xy 65.748161 -16.969994) (xy 41.681146 -16.969994) (xy 41.680645 -17.013994)
			(xy 41.672643 -17.101629) (xy 41.656705 -17.188173) (xy 41.632963 -17.272909) (xy 41.601614 -17.355135)
			(xy 41.562917 -17.43417) (xy 41.517194 -17.509358) (xy 41.464823 -17.580077) (xy 41.406239 -17.645741)
			(xy 41.341925 -17.705806) (xy 41.272417 -17.759773) (xy 41.198289 -17.807195) (xy 41.120155 -17.847681)
			(xy 41.038664 -17.880894) (xy 40.95449 -17.906558) (xy 40.868331 -17.924462) (xy 40.780901 -17.934457)
			(xy 40.692924 -17.936461) (xy 40.60513 -17.930455) (xy 40.518246 -17.916491) (xy 40.432991 -17.894684)
			(xy 40.350072 -17.865215) (xy 40.270177 -17.828328) (xy 40.193968 -17.784328) (xy 40.122075 -17.73358)
			(xy 40.055094 -17.676506) (xy 39.993582 -17.613576) (xy 39.938046 -17.545314) (xy 39.888948 -17.472285)
			(xy 39.846695 -17.395093) (xy 39.811636 -17.314379) (xy 39.784061 -17.230811) (xy 39.764201 -17.145082)
			(xy 39.752218 -17.057902) (xy 39.748213 -16.969994) (xy 15.681198 -16.969994) (xy 15.680697 -17.013994)
			(xy 15.672695 -17.101629) (xy 15.656757 -17.188173) (xy 15.633015 -17.272909) (xy 15.601666 -17.355135)
			(xy 15.562969 -17.43417) (xy 15.517246 -17.509358) (xy 15.464875 -17.580077) (xy 15.406291 -17.645741)
			(xy 15.341977 -17.705806) (xy 15.272469 -17.759773) (xy 15.198341 -17.807195) (xy 15.120207 -17.847681)
			(xy 15.038716 -17.880894) (xy 14.954542 -17.906558) (xy 14.868383 -17.924462) (xy 14.780953 -17.934457)
			(xy 14.692976 -17.936461) (xy 14.605182 -17.930455) (xy 14.518298 -17.916491) (xy 14.433043 -17.894684)
			(xy 14.350124 -17.865215) (xy 14.270229 -17.828328) (xy 14.19402 -17.784328) (xy 14.122127 -17.73358)
			(xy 14.055146 -17.676506) (xy 13.993634 -17.613576) (xy 13.938098 -17.545314) (xy 13.889 -17.472285)
			(xy 13.846747 -17.395093) (xy 13.811688 -17.314379) (xy 13.784113 -17.230811) (xy 13.764253 -17.145082)
			(xy 13.75227 -17.057902) (xy 13.748265 -16.969994) (xy 0.509016 -16.969994) (xy 0.509016 -27.342846)
			(xy 16.523716 -27.342846) (xy 16.523716 -26.479246) (xy 16.524206 -26.449278) (xy 16.532029 -26.389856)
			(xy 16.547542 -26.331963) (xy 16.570478 -26.27659) (xy 16.600445 -26.224684) (xy 16.636932 -26.177134)
			(xy 16.679312 -26.134754) (xy 16.726862 -26.098267) (xy 16.778768 -26.0683) (xy 16.834141 -26.045364)
			(xy 16.892034 -26.029851) (xy 16.951456 -26.022028) (xy 17.011392 -26.022028) (xy 17.070814 -26.029851)
			(xy 17.128707 -26.045364) (xy 17.18408 -26.0683) (xy 17.235986 -26.098267) (xy 17.283536 -26.134754)
			(xy 17.325916 -26.177134) (xy 17.362403 -26.224684) (xy 17.39237 -26.27659) (xy 17.415306 -26.331963)
			(xy 17.430819 -26.389856) (xy 17.438642 -26.449278) (xy 17.439132 -26.479246) (xy 17.439132 -27.342846)
			(xy 42.523664 -27.342846) (xy 42.523664 -26.479246) (xy 42.524154 -26.449278) (xy 42.531977 -26.389856)
			(xy 42.54749 -26.331963) (xy 42.570426 -26.27659) (xy 42.600393 -26.224684) (xy 42.63688 -26.177134)
			(xy 42.67926 -26.134754) (xy 42.72681 -26.098267) (xy 42.778716 -26.0683) (xy 42.834089 -26.045364)
			(xy 42.891982 -26.029851) (xy 42.951404 -26.022028) (xy 43.01134 -26.022028) (xy 43.070762 -26.029851)
			(xy 43.128655 -26.045364) (xy 43.184028 -26.0683) (xy 43.235934 -26.098267) (xy 43.283484 -26.134754)
			(xy 43.325864 -26.177134) (xy 43.362351 -26.224684) (xy 43.392318 -26.27659) (xy 43.415254 -26.331963)
			(xy 43.430767 -26.389856) (xy 43.43859 -26.449278) (xy 43.43908 -26.479246) (xy 43.43908 -27.342846)
			(xy 68.523612 -27.342846) (xy 68.523612 -26.479246) (xy 68.524102 -26.449278) (xy 68.531925 -26.389856)
			(xy 68.547438 -26.331963) (xy 68.570374 -26.27659) (xy 68.600341 -26.224684) (xy 68.636828 -26.177134)
			(xy 68.679208 -26.134754) (xy 68.726758 -26.098267) (xy 68.778664 -26.0683) (xy 68.834037 -26.045364)
			(xy 68.89193 -26.029851) (xy 68.951352 -26.022028) (xy 69.011288 -26.022028) (xy 69.07071 -26.029851)
			(xy 69.128603 -26.045364) (xy 69.183976 -26.0683) (xy 69.235882 -26.098267) (xy 69.283432 -26.134754)
			(xy 69.325812 -26.177134) (xy 69.362299 -26.224684) (xy 69.392266 -26.27659) (xy 69.415202 -26.331963)
			(xy 69.430715 -26.389856) (xy 69.438538 -26.449278) (xy 69.439028 -26.479246) (xy 69.439028 -27.342846)
			(xy 94.52356 -27.342846) (xy 94.52356 -26.479246) (xy 94.52405 -26.449278) (xy 94.531873 -26.389856)
			(xy 94.547386 -26.331963) (xy 94.570322 -26.27659) (xy 94.600289 -26.224684) (xy 94.636776 -26.177134)
			(xy 94.679156 -26.134754) (xy 94.726706 -26.098267) (xy 94.778612 -26.0683) (xy 94.833985 -26.045364)
			(xy 94.891878 -26.029851) (xy 94.9513 -26.022028) (xy 95.011236 -26.022028) (xy 95.070658 -26.029851)
			(xy 95.128551 -26.045364) (xy 95.183924 -26.0683) (xy 95.23583 -26.098267) (xy 95.28338 -26.134754)
			(xy 95.32576 -26.177134) (xy 95.362247 -26.224684) (xy 95.392214 -26.27659) (xy 95.41515 -26.331963)
			(xy 95.430663 -26.389856) (xy 95.438486 -26.449278) (xy 95.438976 -26.479246) (xy 95.438976 -27.342846)
			(xy 132.62356 -27.342846) (xy 132.62356 -26.479246) (xy 132.62405 -26.449262) (xy 132.631878 -26.389806)
			(xy 132.647399 -26.331881) (xy 132.670348 -26.276477) (xy 132.700332 -26.224543) (xy 132.736838 -26.176967)
			(xy 132.779243 -26.134562) (xy 132.826819 -26.098056) (xy 132.878753 -26.068072) (xy 132.934157 -26.045123)
			(xy 132.992082 -26.029602) (xy 133.051538 -26.021774) (xy 133.111506 -26.021774) (xy 133.170962 -26.029602)
			(xy 133.228887 -26.045123) (xy 133.284291 -26.068072) (xy 133.336225 -26.098056) (xy 133.383801 -26.134562)
			(xy 133.426206 -26.176967) (xy 133.462712 -26.224543) (xy 133.492696 -26.276477) (xy 133.515645 -26.331881)
			(xy 133.531166 -26.389806) (xy 133.538994 -26.449262) (xy 133.539484 -26.479246) (xy 133.539484 -27.342846)
			(xy 158.623508 -27.342846) (xy 158.623508 -26.479246) (xy 158.623998 -26.449262) (xy 158.631826 -26.389806)
			(xy 158.647347 -26.331881) (xy 158.670296 -26.276477) (xy 158.70028 -26.224543) (xy 158.736786 -26.176967)
			(xy 158.779191 -26.134562) (xy 158.826767 -26.098056) (xy 158.878701 -26.068072) (xy 158.934105 -26.045123)
			(xy 158.99203 -26.029602) (xy 159.051486 -26.021774) (xy 159.111454 -26.021774) (xy 159.17091 -26.029602)
			(xy 159.228835 -26.045123) (xy 159.284239 -26.068072) (xy 159.336173 -26.098056) (xy 159.383749 -26.134562)
			(xy 159.426154 -26.176967) (xy 159.46266 -26.224543) (xy 159.492644 -26.276477) (xy 159.515593 -26.331881)
			(xy 159.531114 -26.389806) (xy 159.538942 -26.449262) (xy 159.539432 -26.479246) (xy 159.539432 -27.342846)
			(xy 184.623456 -27.342846) (xy 184.623456 -26.479246) (xy 184.623946 -26.449262) (xy 184.631774 -26.389806)
			(xy 184.647295 -26.331881) (xy 184.670244 -26.276477) (xy 184.700228 -26.224543) (xy 184.736734 -26.176967)
			(xy 184.779139 -26.134562) (xy 184.826715 -26.098056) (xy 184.878649 -26.068072) (xy 184.934053 -26.045123)
			(xy 184.991978 -26.029602) (xy 185.051434 -26.021774) (xy 185.111402 -26.021774) (xy 185.170858 -26.029602)
			(xy 185.228783 -26.045123) (xy 185.284187 -26.068072) (xy 185.336121 -26.098056) (xy 185.383697 -26.134562)
			(xy 185.426102 -26.176967) (xy 185.462608 -26.224543) (xy 185.492592 -26.276477) (xy 185.515541 -26.331881)
			(xy 185.531062 -26.389806) (xy 185.53889 -26.449262) (xy 185.53938 -26.479246) (xy 185.53938 -27.342846)
			(xy 210.623404 -27.342846) (xy 210.623404 -26.479246) (xy 210.623894 -26.449262) (xy 210.631722 -26.389806)
			(xy 210.647243 -26.331881) (xy 210.670192 -26.276477) (xy 210.700176 -26.224543) (xy 210.736682 -26.176967)
			(xy 210.779087 -26.134562) (xy 210.826663 -26.098056) (xy 210.878597 -26.068072) (xy 210.934001 -26.045123)
			(xy 210.991926 -26.029602) (xy 211.051382 -26.021774) (xy 211.11135 -26.021774) (xy 211.170806 -26.029602)
			(xy 211.228731 -26.045123) (xy 211.284135 -26.068072) (xy 211.336069 -26.098056) (xy 211.383645 -26.134562)
			(xy 211.42605 -26.176967) (xy 211.462556 -26.224543) (xy 211.49254 -26.276477) (xy 211.515489 -26.331881)
			(xy 211.53101 -26.389806) (xy 211.538838 -26.449262) (xy 211.539328 -26.479246) (xy 211.539328 -27.342846)
			(xy 248.723404 -27.342846) (xy 248.723404 -26.479246) (xy 248.723894 -26.449262) (xy 248.731722 -26.389806)
			(xy 248.747243 -26.331881) (xy 248.770192 -26.276477) (xy 248.800176 -26.224543) (xy 248.836682 -26.176967)
			(xy 248.879087 -26.134562) (xy 248.926663 -26.098056) (xy 248.978597 -26.068072) (xy 249.034001 -26.045123)
			(xy 249.091926 -26.029602) (xy 249.151382 -26.021774) (xy 249.21135 -26.021774) (xy 249.270806 -26.029602)
			(xy 249.328731 -26.045123) (xy 249.384135 -26.068072) (xy 249.436069 -26.098056) (xy 249.483645 -26.134562)
			(xy 249.52605 -26.176967) (xy 249.562556 -26.224543) (xy 249.59254 -26.276477) (xy 249.615489 -26.331881)
			(xy 249.63101 -26.389806) (xy 249.638838 -26.449262) (xy 249.639328 -26.479246) (xy 249.639328 -27.342846)
			(xy 274.723352 -27.342846) (xy 274.723352 -26.479246) (xy 274.723842 -26.449262) (xy 274.73167 -26.389806)
			(xy 274.747191 -26.331881) (xy 274.77014 -26.276477) (xy 274.800124 -26.224543) (xy 274.83663 -26.176967)
			(xy 274.879035 -26.134562) (xy 274.926611 -26.098056) (xy 274.978545 -26.068072) (xy 275.033949 -26.045123)
			(xy 275.091874 -26.029602) (xy 275.15133 -26.021774) (xy 275.211298 -26.021774) (xy 275.270754 -26.029602)
			(xy 275.328679 -26.045123) (xy 275.384083 -26.068072) (xy 275.436017 -26.098056) (xy 275.483593 -26.134562)
			(xy 275.525998 -26.176967) (xy 275.562504 -26.224543) (xy 275.592488 -26.276477) (xy 275.615437 -26.331881)
			(xy 275.630958 -26.389806) (xy 275.638786 -26.449262) (xy 275.639276 -26.479246) (xy 275.639276 -27.342846)
			(xy 300.7233 -27.342846) (xy 300.7233 -26.479246) (xy 300.72379 -26.449262) (xy 300.731618 -26.389806)
			(xy 300.747139 -26.331881) (xy 300.770088 -26.276477) (xy 300.800072 -26.224543) (xy 300.836578 -26.176967)
			(xy 300.878983 -26.134562) (xy 300.926559 -26.098056) (xy 300.978493 -26.068072) (xy 301.033897 -26.045123)
			(xy 301.091822 -26.029602) (xy 301.151278 -26.021774) (xy 301.211246 -26.021774) (xy 301.270702 -26.029602)
			(xy 301.328627 -26.045123) (xy 301.384031 -26.068072) (xy 301.435965 -26.098056) (xy 301.483541 -26.134562)
			(xy 301.525946 -26.176967) (xy 301.562452 -26.224543) (xy 301.592436 -26.276477) (xy 301.615385 -26.331881)
			(xy 301.630906 -26.389806) (xy 301.638734 -26.449262) (xy 301.639224 -26.479246) (xy 301.639224 -27.342846)
			(xy 326.723248 -27.342846) (xy 326.723248 -26.479246) (xy 326.723738 -26.449262) (xy 326.731566 -26.389806)
			(xy 326.747087 -26.331881) (xy 326.770036 -26.276477) (xy 326.80002 -26.224543) (xy 326.836526 -26.176967)
			(xy 326.878931 -26.134562) (xy 326.926507 -26.098056) (xy 326.978441 -26.068072) (xy 327.033845 -26.045123)
			(xy 327.09177 -26.029602) (xy 327.151226 -26.021774) (xy 327.211194 -26.021774) (xy 327.27065 -26.029602)
			(xy 327.328575 -26.045123) (xy 327.383979 -26.068072) (xy 327.435913 -26.098056) (xy 327.483489 -26.134562)
			(xy 327.525894 -26.176967) (xy 327.5624 -26.224543) (xy 327.592384 -26.276477) (xy 327.615333 -26.331881)
			(xy 327.630854 -26.389806) (xy 327.638682 -26.449262) (xy 327.639172 -26.479246) (xy 327.639172 -27.342846)
			(xy 364.823756 -27.342846) (xy 364.823756 -26.479246) (xy 364.824246 -26.449278) (xy 364.832069 -26.389856)
			(xy 364.847582 -26.331963) (xy 364.870518 -26.27659) (xy 364.900485 -26.224684) (xy 364.936972 -26.177134)
			(xy 364.979352 -26.134754) (xy 365.026902 -26.098267) (xy 365.078808 -26.0683) (xy 365.134181 -26.045364)
			(xy 365.192074 -26.029851) (xy 365.251496 -26.022028) (xy 365.311432 -26.022028) (xy 365.370854 -26.029851)
			(xy 365.428747 -26.045364) (xy 365.48412 -26.0683) (xy 365.536026 -26.098267) (xy 365.583576 -26.134754)
			(xy 365.625956 -26.177134) (xy 365.662443 -26.224684) (xy 365.69241 -26.27659) (xy 365.715346 -26.331963)
			(xy 365.730859 -26.389856) (xy 365.738682 -26.449278) (xy 365.739172 -26.479246) (xy 365.739172 -27.342846)
			(xy 390.823704 -27.342846) (xy 390.823704 -26.479246) (xy 390.824194 -26.449278) (xy 390.832017 -26.389856)
			(xy 390.84753 -26.331963) (xy 390.870466 -26.27659) (xy 390.900433 -26.224684) (xy 390.93692 -26.177134)
			(xy 390.9793 -26.134754) (xy 391.02685 -26.098267) (xy 391.078756 -26.0683) (xy 391.134129 -26.045364)
			(xy 391.192022 -26.029851) (xy 391.251444 -26.022028) (xy 391.31138 -26.022028) (xy 391.370802 -26.029851)
			(xy 391.428695 -26.045364) (xy 391.484068 -26.0683) (xy 391.535974 -26.098267) (xy 391.583524 -26.134754)
			(xy 391.625904 -26.177134) (xy 391.662391 -26.224684) (xy 391.692358 -26.27659) (xy 391.715294 -26.331963)
			(xy 391.730807 -26.389856) (xy 391.73863 -26.449278) (xy 391.73912 -26.479246) (xy 391.73912 -27.342846)
			(xy 416.823652 -27.342846) (xy 416.823652 -26.479246) (xy 416.824142 -26.449278) (xy 416.831965 -26.389856)
			(xy 416.847478 -26.331963) (xy 416.870414 -26.27659) (xy 416.900381 -26.224684) (xy 416.936868 -26.177134)
			(xy 416.979248 -26.134754) (xy 417.026798 -26.098267) (xy 417.078704 -26.0683) (xy 417.134077 -26.045364)
			(xy 417.19197 -26.029851) (xy 417.251392 -26.022028) (xy 417.311328 -26.022028) (xy 417.37075 -26.029851)
			(xy 417.428643 -26.045364) (xy 417.484016 -26.0683) (xy 417.535922 -26.098267) (xy 417.583472 -26.134754)
			(xy 417.625852 -26.177134) (xy 417.662339 -26.224684) (xy 417.692306 -26.27659) (xy 417.715242 -26.331963)
			(xy 417.730755 -26.389856) (xy 417.738578 -26.449278) (xy 417.739068 -26.479246) (xy 417.739068 -27.342846)
			(xy 442.8236 -27.342846) (xy 442.8236 -26.479246) (xy 442.82409 -26.449278) (xy 442.831913 -26.389856)
			(xy 442.847426 -26.331963) (xy 442.870362 -26.27659) (xy 442.900329 -26.224684) (xy 442.936816 -26.177134)
			(xy 442.979196 -26.134754) (xy 443.026746 -26.098267) (xy 443.078652 -26.0683) (xy 443.134025 -26.045364)
			(xy 443.191918 -26.029851) (xy 443.25134 -26.022028) (xy 443.311276 -26.022028) (xy 443.370698 -26.029851)
			(xy 443.428591 -26.045364) (xy 443.483964 -26.0683) (xy 443.53587 -26.098267) (xy 443.58342 -26.134754)
			(xy 443.6258 -26.177134) (xy 443.662287 -26.224684) (xy 443.692254 -26.27659) (xy 443.71519 -26.331963)
			(xy 443.730703 -26.389856) (xy 443.738526 -26.449278) (xy 443.739016 -26.479246) (xy 443.739016 -27.342846)
			(xy 443.738526 -27.372814) (xy 443.730703 -27.432236) (xy 443.71519 -27.490129) (xy 443.692254 -27.545502)
			(xy 443.662287 -27.597408) (xy 443.6258 -27.644958) (xy 443.58342 -27.687338) (xy 443.53587 -27.723825)
			(xy 443.483964 -27.753792) (xy 443.428591 -27.776728) (xy 443.370698 -27.792241) (xy 443.311276 -27.800064)
			(xy 443.25134 -27.800064) (xy 443.191918 -27.792241) (xy 443.134025 -27.776728) (xy 443.078652 -27.753792)
			(xy 443.026746 -27.723825) (xy 442.979196 -27.687338) (xy 442.936816 -27.644958) (xy 442.900329 -27.597408)
			(xy 442.870362 -27.545502) (xy 442.847426 -27.490129) (xy 442.831913 -27.432236) (xy 442.82409 -27.372814)
			(xy 442.8236 -27.342846) (xy 417.739068 -27.342846) (xy 417.738578 -27.372814) (xy 417.730755 -27.432236)
			(xy 417.715242 -27.490129) (xy 417.692306 -27.545502) (xy 417.662339 -27.597408) (xy 417.625852 -27.644958)
			(xy 417.583472 -27.687338) (xy 417.535922 -27.723825) (xy 417.484016 -27.753792) (xy 417.428643 -27.776728)
			(xy 417.37075 -27.792241) (xy 417.311328 -27.800064) (xy 417.251392 -27.800064) (xy 417.19197 -27.792241)
			(xy 417.134077 -27.776728) (xy 417.078704 -27.753792) (xy 417.026798 -27.723825) (xy 416.979248 -27.687338)
			(xy 416.936868 -27.644958) (xy 416.900381 -27.597408) (xy 416.870414 -27.545502) (xy 416.847478 -27.490129)
			(xy 416.831965 -27.432236) (xy 416.824142 -27.372814) (xy 416.823652 -27.342846) (xy 391.73912 -27.342846)
			(xy 391.73863 -27.372814) (xy 391.730807 -27.432236) (xy 391.715294 -27.490129) (xy 391.692358 -27.545502)
			(xy 391.662391 -27.597408) (xy 391.625904 -27.644958) (xy 391.583524 -27.687338) (xy 391.535974 -27.723825)
			(xy 391.484068 -27.753792) (xy 391.428695 -27.776728) (xy 391.370802 -27.792241) (xy 391.31138 -27.800064)
			(xy 391.251444 -27.800064) (xy 391.192022 -27.792241) (xy 391.134129 -27.776728) (xy 391.078756 -27.753792)
			(xy 391.02685 -27.723825) (xy 390.9793 -27.687338) (xy 390.93692 -27.644958) (xy 390.900433 -27.597408)
			(xy 390.870466 -27.545502) (xy 390.84753 -27.490129) (xy 390.832017 -27.432236) (xy 390.824194 -27.372814)
			(xy 390.823704 -27.342846) (xy 365.739172 -27.342846) (xy 365.738682 -27.372814) (xy 365.730859 -27.432236)
			(xy 365.715346 -27.490129) (xy 365.69241 -27.545502) (xy 365.662443 -27.597408) (xy 365.625956 -27.644958)
			(xy 365.583576 -27.687338) (xy 365.536026 -27.723825) (xy 365.48412 -27.753792) (xy 365.428747 -27.776728)
			(xy 365.370854 -27.792241) (xy 365.311432 -27.800064) (xy 365.251496 -27.800064) (xy 365.192074 -27.792241)
			(xy 365.134181 -27.776728) (xy 365.078808 -27.753792) (xy 365.026902 -27.723825) (xy 364.979352 -27.687338)
			(xy 364.936972 -27.644958) (xy 364.900485 -27.597408) (xy 364.870518 -27.545502) (xy 364.847582 -27.490129)
			(xy 364.832069 -27.432236) (xy 364.824246 -27.372814) (xy 364.823756 -27.342846) (xy 327.639172 -27.342846)
			(xy 327.638682 -27.37283) (xy 327.630854 -27.432286) (xy 327.615333 -27.490211) (xy 327.592384 -27.545615)
			(xy 327.5624 -27.597549) (xy 327.525894 -27.645125) (xy 327.483489 -27.68753) (xy 327.435913 -27.724036)
			(xy 327.383979 -27.75402) (xy 327.328575 -27.776969) (xy 327.27065 -27.79249) (xy 327.211194 -27.800318)
			(xy 327.151226 -27.800318) (xy 327.09177 -27.79249) (xy 327.033845 -27.776969) (xy 326.978441 -27.75402)
			(xy 326.926507 -27.724036) (xy 326.878931 -27.68753) (xy 326.836526 -27.645125) (xy 326.80002 -27.597549)
			(xy 326.770036 -27.545615) (xy 326.747087 -27.490211) (xy 326.731566 -27.432286) (xy 326.723738 -27.37283)
			(xy 326.723248 -27.342846) (xy 301.639224 -27.342846) (xy 301.638734 -27.37283) (xy 301.630906 -27.432286)
			(xy 301.615385 -27.490211) (xy 301.592436 -27.545615) (xy 301.562452 -27.597549) (xy 301.525946 -27.645125)
			(xy 301.483541 -27.68753) (xy 301.435965 -27.724036) (xy 301.384031 -27.75402) (xy 301.328627 -27.776969)
			(xy 301.270702 -27.79249) (xy 301.211246 -27.800318) (xy 301.151278 -27.800318) (xy 301.091822 -27.79249)
			(xy 301.033897 -27.776969) (xy 300.978493 -27.75402) (xy 300.926559 -27.724036) (xy 300.878983 -27.68753)
			(xy 300.836578 -27.645125) (xy 300.800072 -27.597549) (xy 300.770088 -27.545615) (xy 300.747139 -27.490211)
			(xy 300.731618 -27.432286) (xy 300.72379 -27.37283) (xy 300.7233 -27.342846) (xy 275.639276 -27.342846)
			(xy 275.638786 -27.37283) (xy 275.630958 -27.432286) (xy 275.615437 -27.490211) (xy 275.592488 -27.545615)
			(xy 275.562504 -27.597549) (xy 275.525998 -27.645125) (xy 275.483593 -27.68753) (xy 275.436017 -27.724036)
			(xy 275.384083 -27.75402) (xy 275.328679 -27.776969) (xy 275.270754 -27.79249) (xy 275.211298 -27.800318)
			(xy 275.15133 -27.800318) (xy 275.091874 -27.79249) (xy 275.033949 -27.776969) (xy 274.978545 -27.75402)
			(xy 274.926611 -27.724036) (xy 274.879035 -27.68753) (xy 274.83663 -27.645125) (xy 274.800124 -27.597549)
			(xy 274.77014 -27.545615) (xy 274.747191 -27.490211) (xy 274.73167 -27.432286) (xy 274.723842 -27.37283)
			(xy 274.723352 -27.342846) (xy 249.639328 -27.342846) (xy 249.638838 -27.37283) (xy 249.63101 -27.432286)
			(xy 249.615489 -27.490211) (xy 249.59254 -27.545615) (xy 249.562556 -27.597549) (xy 249.52605 -27.645125)
			(xy 249.483645 -27.68753) (xy 249.436069 -27.724036) (xy 249.384135 -27.75402) (xy 249.328731 -27.776969)
			(xy 249.270806 -27.79249) (xy 249.21135 -27.800318) (xy 249.151382 -27.800318) (xy 249.091926 -27.79249)
			(xy 249.034001 -27.776969) (xy 248.978597 -27.75402) (xy 248.926663 -27.724036) (xy 248.879087 -27.68753)
			(xy 248.836682 -27.645125) (xy 248.800176 -27.597549) (xy 248.770192 -27.545615) (xy 248.747243 -27.490211)
			(xy 248.731722 -27.432286) (xy 248.723894 -27.37283) (xy 248.723404 -27.342846) (xy 211.539328 -27.342846)
			(xy 211.538838 -27.37283) (xy 211.53101 -27.432286) (xy 211.515489 -27.490211) (xy 211.49254 -27.545615)
			(xy 211.462556 -27.597549) (xy 211.42605 -27.645125) (xy 211.383645 -27.68753) (xy 211.336069 -27.724036)
			(xy 211.284135 -27.75402) (xy 211.228731 -27.776969) (xy 211.170806 -27.79249) (xy 211.11135 -27.800318)
			(xy 211.051382 -27.800318) (xy 210.991926 -27.79249) (xy 210.934001 -27.776969) (xy 210.878597 -27.75402)
			(xy 210.826663 -27.724036) (xy 210.779087 -27.68753) (xy 210.736682 -27.645125) (xy 210.700176 -27.597549)
			(xy 210.670192 -27.545615) (xy 210.647243 -27.490211) (xy 210.631722 -27.432286) (xy 210.623894 -27.37283)
			(xy 210.623404 -27.342846) (xy 185.53938 -27.342846) (xy 185.53889 -27.37283) (xy 185.531062 -27.432286)
			(xy 185.515541 -27.490211) (xy 185.492592 -27.545615) (xy 185.462608 -27.597549) (xy 185.426102 -27.645125)
			(xy 185.383697 -27.68753) (xy 185.336121 -27.724036) (xy 185.284187 -27.75402) (xy 185.228783 -27.776969)
			(xy 185.170858 -27.79249) (xy 185.111402 -27.800318) (xy 185.051434 -27.800318) (xy 184.991978 -27.79249)
			(xy 184.934053 -27.776969) (xy 184.878649 -27.75402) (xy 184.826715 -27.724036) (xy 184.779139 -27.68753)
			(xy 184.736734 -27.645125) (xy 184.700228 -27.597549) (xy 184.670244 -27.545615) (xy 184.647295 -27.490211)
			(xy 184.631774 -27.432286) (xy 184.623946 -27.37283) (xy 184.623456 -27.342846) (xy 159.539432 -27.342846)
			(xy 159.538942 -27.37283) (xy 159.531114 -27.432286) (xy 159.515593 -27.490211) (xy 159.492644 -27.545615)
			(xy 159.46266 -27.597549) (xy 159.426154 -27.645125) (xy 159.383749 -27.68753) (xy 159.336173 -27.724036)
			(xy 159.284239 -27.75402) (xy 159.228835 -27.776969) (xy 159.17091 -27.79249) (xy 159.111454 -27.800318)
			(xy 159.051486 -27.800318) (xy 158.99203 -27.79249) (xy 158.934105 -27.776969) (xy 158.878701 -27.75402)
			(xy 158.826767 -27.724036) (xy 158.779191 -27.68753) (xy 158.736786 -27.645125) (xy 158.70028 -27.597549)
			(xy 158.670296 -27.545615) (xy 158.647347 -27.490211) (xy 158.631826 -27.432286) (xy 158.623998 -27.37283)
			(xy 158.623508 -27.342846) (xy 133.539484 -27.342846) (xy 133.538994 -27.37283) (xy 133.531166 -27.432286)
			(xy 133.515645 -27.490211) (xy 133.492696 -27.545615) (xy 133.462712 -27.597549) (xy 133.426206 -27.645125)
			(xy 133.383801 -27.68753) (xy 133.336225 -27.724036) (xy 133.284291 -27.75402) (xy 133.228887 -27.776969)
			(xy 133.170962 -27.79249) (xy 133.111506 -27.800318) (xy 133.051538 -27.800318) (xy 132.992082 -27.79249)
			(xy 132.934157 -27.776969) (xy 132.878753 -27.75402) (xy 132.826819 -27.724036) (xy 132.779243 -27.68753)
			(xy 132.736838 -27.645125) (xy 132.700332 -27.597549) (xy 132.670348 -27.545615) (xy 132.647399 -27.490211)
			(xy 132.631878 -27.432286) (xy 132.62405 -27.37283) (xy 132.62356 -27.342846) (xy 95.438976 -27.342846)
			(xy 95.438486 -27.372814) (xy 95.430663 -27.432236) (xy 95.41515 -27.490129) (xy 95.392214 -27.545502)
			(xy 95.362247 -27.597408) (xy 95.32576 -27.644958) (xy 95.28338 -27.687338) (xy 95.23583 -27.723825)
			(xy 95.183924 -27.753792) (xy 95.128551 -27.776728) (xy 95.070658 -27.792241) (xy 95.011236 -27.800064)
			(xy 94.9513 -27.800064) (xy 94.891878 -27.792241) (xy 94.833985 -27.776728) (xy 94.778612 -27.753792)
			(xy 94.726706 -27.723825) (xy 94.679156 -27.687338) (xy 94.636776 -27.644958) (xy 94.600289 -27.597408)
			(xy 94.570322 -27.545502) (xy 94.547386 -27.490129) (xy 94.531873 -27.432236) (xy 94.52405 -27.372814)
			(xy 94.52356 -27.342846) (xy 69.439028 -27.342846) (xy 69.438538 -27.372814) (xy 69.430715 -27.432236)
			(xy 69.415202 -27.490129) (xy 69.392266 -27.545502) (xy 69.362299 -27.597408) (xy 69.325812 -27.644958)
			(xy 69.283432 -27.687338) (xy 69.235882 -27.723825) (xy 69.183976 -27.753792) (xy 69.128603 -27.776728)
			(xy 69.07071 -27.792241) (xy 69.011288 -27.800064) (xy 68.951352 -27.800064) (xy 68.89193 -27.792241)
			(xy 68.834037 -27.776728) (xy 68.778664 -27.753792) (xy 68.726758 -27.723825) (xy 68.679208 -27.687338)
			(xy 68.636828 -27.644958) (xy 68.600341 -27.597408) (xy 68.570374 -27.545502) (xy 68.547438 -27.490129)
			(xy 68.531925 -27.432236) (xy 68.524102 -27.372814) (xy 68.523612 -27.342846) (xy 43.43908 -27.342846)
			(xy 43.43859 -27.372814) (xy 43.430767 -27.432236) (xy 43.415254 -27.490129) (xy 43.392318 -27.545502)
			(xy 43.362351 -27.597408) (xy 43.325864 -27.644958) (xy 43.283484 -27.687338) (xy 43.235934 -27.723825)
			(xy 43.184028 -27.753792) (xy 43.128655 -27.776728) (xy 43.070762 -27.792241) (xy 43.01134 -27.800064)
			(xy 42.951404 -27.800064) (xy 42.891982 -27.792241) (xy 42.834089 -27.776728) (xy 42.778716 -27.753792)
			(xy 42.72681 -27.723825) (xy 42.67926 -27.687338) (xy 42.63688 -27.644958) (xy 42.600393 -27.597408)
			(xy 42.570426 -27.545502) (xy 42.54749 -27.490129) (xy 42.531977 -27.432236) (xy 42.524154 -27.372814)
			(xy 42.523664 -27.342846) (xy 17.439132 -27.342846) (xy 17.438642 -27.372814) (xy 17.430819 -27.432236)
			(xy 17.415306 -27.490129) (xy 17.39237 -27.545502) (xy 17.362403 -27.597408) (xy 17.325916 -27.644958)
			(xy 17.283536 -27.687338) (xy 17.235986 -27.723825) (xy 17.18408 -27.753792) (xy 17.128707 -27.776728)
			(xy 17.070814 -27.792241) (xy 17.011392 -27.800064) (xy 16.951456 -27.800064) (xy 16.892034 -27.792241)
			(xy 16.834141 -27.776728) (xy 16.778768 -27.753792) (xy 16.726862 -27.723825) (xy 16.679312 -27.687338)
			(xy 16.636932 -27.644958) (xy 16.600445 -27.597408) (xy 16.570478 -27.545502) (xy 16.547542 -27.490129)
			(xy 16.532029 -27.432236) (xy 16.524206 -27.372814) (xy 16.523716 -27.342846) (xy 0.509016 -27.342846)
			(xy 0.509016 -29.12237) (xy 8.607044 -29.12237) (xy 8.607044 -28.25877) (xy 8.607534 -28.228802)
			(xy 8.615357 -28.16938) (xy 8.63087 -28.111487) (xy 8.653806 -28.056114) (xy 8.683773 -28.004208)
			(xy 8.72026 -27.956658) (xy 8.76264 -27.914278) (xy 8.81019 -27.877791) (xy 8.862096 -27.847824)
			(xy 8.917469 -27.824888) (xy 8.975362 -27.809375) (xy 9.034784 -27.801552) (xy 9.09472 -27.801552)
			(xy 9.154142 -27.809375) (xy 9.212035 -27.824888) (xy 9.267408 -27.847824) (xy 9.319314 -27.877791)
			(xy 9.366864 -27.914278) (xy 9.409244 -27.956658) (xy 9.445731 -28.004208) (xy 9.475698 -28.056114)
			(xy 9.498634 -28.111487) (xy 9.514147 -28.16938) (xy 9.52197 -28.228802) (xy 9.52246 -28.25877) (xy 9.52246 -29.114242)
			(xy 18.847308 -29.114242) (xy 18.847308 -28.250642) (xy 18.847798 -28.220658) (xy 18.855626 -28.161202)
			(xy 18.871147 -28.103277) (xy 18.894096 -28.047873) (xy 18.92408 -27.995939) (xy 18.960586 -27.948363)
			(xy 19.002991 -27.905958) (xy 19.050567 -27.869452) (xy 19.102501 -27.839468) (xy 19.157905 -27.816519)
			(xy 19.21583 -27.800998) (xy 19.275286 -27.79317) (xy 19.335254 -27.79317) (xy 19.39471 -27.800998)
			(xy 19.452635 -27.816519) (xy 19.508039 -27.839468) (xy 19.559973 -27.869452) (xy 19.607549 -27.905958)
			(xy 19.649954 -27.948363) (xy 19.68646 -27.995939) (xy 19.716444 -28.047873) (xy 19.739393 -28.103277)
			(xy 19.754914 -28.161202) (xy 19.762742 -28.220658) (xy 19.763232 -28.250642) (xy 19.763232 -29.114242)
			(xy 19.763099 -29.12237) (xy 34.606992 -29.12237) (xy 34.606992 -28.25877) (xy 34.607482 -28.228802)
			(xy 34.615305 -28.16938) (xy 34.630818 -28.111487) (xy 34.653754 -28.056114) (xy 34.683721 -28.004208)
			(xy 34.720208 -27.956658) (xy 34.762588 -27.914278) (xy 34.810138 -27.877791) (xy 34.862044 -27.847824)
			(xy 34.917417 -27.824888) (xy 34.97531 -27.809375) (xy 35.034732 -27.801552) (xy 35.094668 -27.801552)
			(xy 35.15409 -27.809375) (xy 35.211983 -27.824888) (xy 35.267356 -27.847824) (xy 35.319262 -27.877791)
			(xy 35.366812 -27.914278) (xy 35.409192 -27.956658) (xy 35.445679 -28.004208) (xy 35.475646 -28.056114)
			(xy 35.498582 -28.111487) (xy 35.514095 -28.16938) (xy 35.521918 -28.228802) (xy 35.522408 -28.25877)
			(xy 35.522408 -29.114242) (xy 44.847256 -29.114242) (xy 44.847256 -28.250642) (xy 44.847746 -28.220658)
			(xy 44.855574 -28.161202) (xy 44.871095 -28.103277) (xy 44.894044 -28.047873) (xy 44.924028 -27.995939)
			(xy 44.960534 -27.948363) (xy 45.002939 -27.905958) (xy 45.050515 -27.869452) (xy 45.102449 -27.839468)
			(xy 45.157853 -27.816519) (xy 45.215778 -27.800998) (xy 45.275234 -27.79317) (xy 45.335202 -27.79317)
			(xy 45.394658 -27.800998) (xy 45.452583 -27.816519) (xy 45.507987 -27.839468) (xy 45.559921 -27.869452)
			(xy 45.607497 -27.905958) (xy 45.649902 -27.948363) (xy 45.686408 -27.995939) (xy 45.716392 -28.047873)
			(xy 45.739341 -28.103277) (xy 45.754862 -28.161202) (xy 45.76269 -28.220658) (xy 45.76318 -28.250642)
			(xy 45.76318 -29.114242) (xy 45.763047 -29.12237) (xy 60.60694 -29.12237) (xy 60.60694 -28.25877)
			(xy 60.60743 -28.228802) (xy 60.615253 -28.16938) (xy 60.630766 -28.111487) (xy 60.653702 -28.056114)
			(xy 60.683669 -28.004208) (xy 60.720156 -27.956658) (xy 60.762536 -27.914278) (xy 60.810086 -27.877791)
			(xy 60.861992 -27.847824) (xy 60.917365 -27.824888) (xy 60.975258 -27.809375) (xy 61.03468 -27.801552)
			(xy 61.094616 -27.801552) (xy 61.154038 -27.809375) (xy 61.211931 -27.824888) (xy 61.267304 -27.847824)
			(xy 61.31921 -27.877791) (xy 61.36676 -27.914278) (xy 61.40914 -27.956658) (xy 61.445627 -28.004208)
			(xy 61.475594 -28.056114) (xy 61.49853 -28.111487) (xy 61.514043 -28.16938) (xy 61.521866 -28.228802)
			(xy 61.522356 -28.25877) (xy 61.522356 -29.114242) (xy 70.847204 -29.114242) (xy 70.847204 -28.250642)
			(xy 70.847694 -28.220658) (xy 70.855522 -28.161202) (xy 70.871043 -28.103277) (xy 70.893992 -28.047873)
			(xy 70.923976 -27.995939) (xy 70.960482 -27.948363) (xy 71.002887 -27.905958) (xy 71.050463 -27.869452)
			(xy 71.102397 -27.839468) (xy 71.157801 -27.816519) (xy 71.215726 -27.800998) (xy 71.275182 -27.79317)
			(xy 71.33515 -27.79317) (xy 71.394606 -27.800998) (xy 71.452531 -27.816519) (xy 71.507935 -27.839468)
			(xy 71.559869 -27.869452) (xy 71.607445 -27.905958) (xy 71.64985 -27.948363) (xy 71.686356 -27.995939)
			(xy 71.71634 -28.047873) (xy 71.739289 -28.103277) (xy 71.75481 -28.161202) (xy 71.762638 -28.220658)
			(xy 71.763128 -28.250642) (xy 71.763128 -29.114242) (xy 71.762995 -29.12237) (xy 86.606888 -29.12237)
			(xy 86.606888 -28.25877) (xy 86.607378 -28.228802) (xy 86.615201 -28.16938) (xy 86.630714 -28.111487)
			(xy 86.65365 -28.056114) (xy 86.683617 -28.004208) (xy 86.720104 -27.956658) (xy 86.762484 -27.914278)
			(xy 86.810034 -27.877791) (xy 86.86194 -27.847824) (xy 86.917313 -27.824888) (xy 86.975206 -27.809375)
			(xy 87.034628 -27.801552) (xy 87.094564 -27.801552) (xy 87.153986 -27.809375) (xy 87.211879 -27.824888)
			(xy 87.267252 -27.847824) (xy 87.319158 -27.877791) (xy 87.366708 -27.914278) (xy 87.409088 -27.956658)
			(xy 87.445575 -28.004208) (xy 87.475542 -28.056114) (xy 87.498478 -28.111487) (xy 87.513991 -28.16938)
			(xy 87.521814 -28.228802) (xy 87.522304 -28.25877) (xy 87.522304 -29.114242) (xy 96.847152 -29.114242)
			(xy 96.847152 -28.250642) (xy 96.847642 -28.220658) (xy 96.85547 -28.161202) (xy 96.870991 -28.103277)
			(xy 96.89394 -28.047873) (xy 96.923924 -27.995939) (xy 96.96043 -27.948363) (xy 97.002835 -27.905958)
			(xy 97.050411 -27.869452) (xy 97.102345 -27.839468) (xy 97.157749 -27.816519) (xy 97.215674 -27.800998)
			(xy 97.27513 -27.79317) (xy 97.335098 -27.79317) (xy 97.394554 -27.800998) (xy 97.452479 -27.816519)
			(xy 97.507883 -27.839468) (xy 97.559817 -27.869452) (xy 97.607393 -27.905958) (xy 97.649798 -27.948363)
			(xy 97.686304 -27.995939) (xy 97.716288 -28.047873) (xy 97.739237 -28.103277) (xy 97.754758 -28.161202)
			(xy 97.762586 -28.220658) (xy 97.763076 -28.250642) (xy 97.763076 -29.114242) (xy 97.762943 -29.12237)
			(xy 124.706888 -29.12237) (xy 124.706888 -28.25877) (xy 124.707378 -28.228786) (xy 124.715206 -28.16933)
			(xy 124.730727 -28.111405) (xy 124.753676 -28.056001) (xy 124.78366 -28.004067) (xy 124.820166 -27.956491)
			(xy 124.862571 -27.914086) (xy 124.910147 -27.87758) (xy 124.962081 -27.847596) (xy 125.017485 -27.824647)
			(xy 125.07541 -27.809126) (xy 125.134866 -27.801298) (xy 125.194834 -27.801298) (xy 125.25429 -27.809126)
			(xy 125.312215 -27.824647) (xy 125.367619 -27.847596) (xy 125.419553 -27.87758) (xy 125.467129 -27.914086)
			(xy 125.509534 -27.956491) (xy 125.54604 -28.004067) (xy 125.576024 -28.056001) (xy 125.598973 -28.111405)
			(xy 125.614494 -28.16933) (xy 125.622322 -28.228786) (xy 125.622812 -28.25877) (xy 125.622812 -29.114242)
			(xy 134.94766 -29.114242) (xy 134.94766 -28.250642) (xy 134.94815 -28.220674) (xy 134.955973 -28.161252)
			(xy 134.971486 -28.103359) (xy 134.994422 -28.047986) (xy 135.024389 -27.99608) (xy 135.060876 -27.94853)
			(xy 135.103256 -27.90615) (xy 135.150806 -27.869663) (xy 135.202712 -27.839696) (xy 135.258085 -27.81676)
			(xy 135.315978 -27.801247) (xy 135.3754 -27.793424) (xy 135.435336 -27.793424) (xy 135.494758 -27.801247)
			(xy 135.552651 -27.81676) (xy 135.608024 -27.839696) (xy 135.65993 -27.869663) (xy 135.70748 -27.90615)
			(xy 135.74986 -27.94853) (xy 135.786347 -27.99608) (xy 135.816314 -28.047986) (xy 135.83925 -28.103359)
			(xy 135.854763 -28.161252) (xy 135.862586 -28.220674) (xy 135.863076 -28.250642) (xy 135.863076 -29.114242)
			(xy 135.862943 -29.12237) (xy 150.706836 -29.12237) (xy 150.706836 -28.25877) (xy 150.707326 -28.228786)
			(xy 150.715154 -28.16933) (xy 150.730675 -28.111405) (xy 150.753624 -28.056001) (xy 150.783608 -28.004067)
			(xy 150.820114 -27.956491) (xy 150.862519 -27.914086) (xy 150.910095 -27.87758) (xy 150.962029 -27.847596)
			(xy 151.017433 -27.824647) (xy 151.075358 -27.809126) (xy 151.134814 -27.801298) (xy 151.194782 -27.801298)
			(xy 151.254238 -27.809126) (xy 151.312163 -27.824647) (xy 151.367567 -27.847596) (xy 151.419501 -27.87758)
			(xy 151.467077 -27.914086) (xy 151.509482 -27.956491) (xy 151.545988 -28.004067) (xy 151.575972 -28.056001)
			(xy 151.598921 -28.111405) (xy 151.614442 -28.16933) (xy 151.62227 -28.228786) (xy 151.62276 -28.25877)
			(xy 151.62276 -29.114242) (xy 160.947608 -29.114242) (xy 160.947608 -28.250642) (xy 160.948098 -28.220674)
			(xy 160.955921 -28.161252) (xy 160.971434 -28.103359) (xy 160.99437 -28.047986) (xy 161.024337 -27.99608)
			(xy 161.060824 -27.94853) (xy 161.103204 -27.90615) (xy 161.150754 -27.869663) (xy 161.20266 -27.839696)
			(xy 161.258033 -27.81676) (xy 161.315926 -27.801247) (xy 161.375348 -27.793424) (xy 161.435284 -27.793424)
			(xy 161.494706 -27.801247) (xy 161.552599 -27.81676) (xy 161.607972 -27.839696) (xy 161.659878 -27.869663)
			(xy 161.707428 -27.90615) (xy 161.749808 -27.94853) (xy 161.786295 -27.99608) (xy 161.816262 -28.047986)
			(xy 161.839198 -28.103359) (xy 161.854711 -28.161252) (xy 161.862534 -28.220674) (xy 161.863024 -28.250642)
			(xy 161.863024 -29.114242) (xy 161.862891 -29.12237) (xy 176.706784 -29.12237) (xy 176.706784 -28.25877)
			(xy 176.707274 -28.228786) (xy 176.715102 -28.16933) (xy 176.730623 -28.111405) (xy 176.753572 -28.056001)
			(xy 176.783556 -28.004067) (xy 176.820062 -27.956491) (xy 176.862467 -27.914086) (xy 176.910043 -27.87758)
			(xy 176.961977 -27.847596) (xy 177.017381 -27.824647) (xy 177.075306 -27.809126) (xy 177.134762 -27.801298)
			(xy 177.19473 -27.801298) (xy 177.254186 -27.809126) (xy 177.312111 -27.824647) (xy 177.367515 -27.847596)
			(xy 177.419449 -27.87758) (xy 177.467025 -27.914086) (xy 177.50943 -27.956491) (xy 177.545936 -28.004067)
			(xy 177.57592 -28.056001) (xy 177.598869 -28.111405) (xy 177.61439 -28.16933) (xy 177.622218 -28.228786)
			(xy 177.622708 -28.25877) (xy 177.622708 -29.114242) (xy 186.947556 -29.114242) (xy 186.947556 -28.250642)
			(xy 186.948046 -28.220674) (xy 186.955869 -28.161252) (xy 186.971382 -28.103359) (xy 186.994318 -28.047986)
			(xy 187.024285 -27.99608) (xy 187.060772 -27.94853) (xy 187.103152 -27.90615) (xy 187.150702 -27.869663)
			(xy 187.202608 -27.839696) (xy 187.257981 -27.81676) (xy 187.315874 -27.801247) (xy 187.375296 -27.793424)
			(xy 187.435232 -27.793424) (xy 187.494654 -27.801247) (xy 187.552547 -27.81676) (xy 187.60792 -27.839696)
			(xy 187.659826 -27.869663) (xy 187.707376 -27.90615) (xy 187.749756 -27.94853) (xy 187.786243 -27.99608)
			(xy 187.81621 -28.047986) (xy 187.839146 -28.103359) (xy 187.854659 -28.161252) (xy 187.862482 -28.220674)
			(xy 187.862972 -28.250642) (xy 187.862972 -29.114242) (xy 187.862839 -29.12237) (xy 202.706732 -29.12237)
			(xy 202.706732 -28.25877) (xy 202.707222 -28.228786) (xy 202.71505 -28.16933) (xy 202.730571 -28.111405)
			(xy 202.75352 -28.056001) (xy 202.783504 -28.004067) (xy 202.82001 -27.956491) (xy 202.862415 -27.914086)
			(xy 202.909991 -27.87758) (xy 202.961925 -27.847596) (xy 203.017329 -27.824647) (xy 203.075254 -27.809126)
			(xy 203.13471 -27.801298) (xy 203.194678 -27.801298) (xy 203.254134 -27.809126) (xy 203.312059 -27.824647)
			(xy 203.367463 -27.847596) (xy 203.419397 -27.87758) (xy 203.466973 -27.914086) (xy 203.509378 -27.956491)
			(xy 203.545884 -28.004067) (xy 203.575868 -28.056001) (xy 203.598817 -28.111405) (xy 203.614338 -28.16933)
			(xy 203.622166 -28.228786) (xy 203.622656 -28.25877) (xy 203.622656 -29.114242) (xy 212.947504 -29.114242)
			(xy 212.947504 -28.250642) (xy 212.947994 -28.220674) (xy 212.955817 -28.161252) (xy 212.97133 -28.103359)
			(xy 212.994266 -28.047986) (xy 213.024233 -27.99608) (xy 213.06072 -27.94853) (xy 213.1031 -27.90615)
			(xy 213.15065 -27.869663) (xy 213.202556 -27.839696) (xy 213.257929 -27.81676) (xy 213.315822 -27.801247)
			(xy 213.375244 -27.793424) (xy 213.43518 -27.793424) (xy 213.494602 -27.801247) (xy 213.552495 -27.81676)
			(xy 213.607868 -27.839696) (xy 213.659774 -27.869663) (xy 213.707324 -27.90615) (xy 213.749704 -27.94853)
			(xy 213.786191 -27.99608) (xy 213.816158 -28.047986) (xy 213.839094 -28.103359) (xy 213.854607 -28.161252)
			(xy 213.86243 -28.220674) (xy 213.86292 -28.250642) (xy 213.86292 -29.114242) (xy 213.862787 -29.12237)
			(xy 240.806732 -29.12237) (xy 240.806732 -28.25877) (xy 240.807222 -28.228786) (xy 240.81505 -28.16933)
			(xy 240.830571 -28.111405) (xy 240.85352 -28.056001) (xy 240.883504 -28.004067) (xy 240.92001 -27.956491)
			(xy 240.962415 -27.914086) (xy 241.009991 -27.87758) (xy 241.061925 -27.847596) (xy 241.117329 -27.824647)
			(xy 241.175254 -27.809126) (xy 241.23471 -27.801298) (xy 241.294678 -27.801298) (xy 241.354134 -27.809126)
			(xy 241.412059 -27.824647) (xy 241.467463 -27.847596) (xy 241.519397 -27.87758) (xy 241.566973 -27.914086)
			(xy 241.609378 -27.956491) (xy 241.645884 -28.004067) (xy 241.675868 -28.056001) (xy 241.698817 -28.111405)
			(xy 241.714338 -28.16933) (xy 241.722166 -28.228786) (xy 241.722656 -28.25877) (xy 241.722656 -29.114242)
			(xy 251.047504 -29.114242) (xy 251.047504 -28.250642) (xy 251.047994 -28.220674) (xy 251.055817 -28.161252)
			(xy 251.07133 -28.103359) (xy 251.094266 -28.047986) (xy 251.124233 -27.99608) (xy 251.16072 -27.94853)
			(xy 251.2031 -27.90615) (xy 251.25065 -27.869663) (xy 251.302556 -27.839696) (xy 251.357929 -27.81676)
			(xy 251.415822 -27.801247) (xy 251.475244 -27.793424) (xy 251.53518 -27.793424) (xy 251.594602 -27.801247)
			(xy 251.652495 -27.81676) (xy 251.707868 -27.839696) (xy 251.759774 -27.869663) (xy 251.807324 -27.90615)
			(xy 251.849704 -27.94853) (xy 251.886191 -27.99608) (xy 251.916158 -28.047986) (xy 251.939094 -28.103359)
			(xy 251.954607 -28.161252) (xy 251.96243 -28.220674) (xy 251.96292 -28.250642) (xy 251.96292 -29.114242)
			(xy 251.962787 -29.12237) (xy 266.80668 -29.12237) (xy 266.80668 -28.25877) (xy 266.80717 -28.228786)
			(xy 266.814998 -28.16933) (xy 266.830519 -28.111405) (xy 266.853468 -28.056001) (xy 266.883452 -28.004067)
			(xy 266.919958 -27.956491) (xy 266.962363 -27.914086) (xy 267.009939 -27.87758) (xy 267.061873 -27.847596)
			(xy 267.117277 -27.824647) (xy 267.175202 -27.809126) (xy 267.234658 -27.801298) (xy 267.294626 -27.801298)
			(xy 267.354082 -27.809126) (xy 267.412007 -27.824647) (xy 267.467411 -27.847596) (xy 267.519345 -27.87758)
			(xy 267.566921 -27.914086) (xy 267.609326 -27.956491) (xy 267.645832 -28.004067) (xy 267.675816 -28.056001)
			(xy 267.698765 -28.111405) (xy 267.714286 -28.16933) (xy 267.722114 -28.228786) (xy 267.722604 -28.25877)
			(xy 267.722604 -29.114242) (xy 277.047452 -29.114242) (xy 277.047452 -28.250642) (xy 277.047942 -28.220674)
			(xy 277.055765 -28.161252) (xy 277.071278 -28.103359) (xy 277.094214 -28.047986) (xy 277.124181 -27.99608)
			(xy 277.160668 -27.94853) (xy 277.203048 -27.90615) (xy 277.250598 -27.869663) (xy 277.302504 -27.839696)
			(xy 277.357877 -27.81676) (xy 277.41577 -27.801247) (xy 277.475192 -27.793424) (xy 277.535128 -27.793424)
			(xy 277.59455 -27.801247) (xy 277.652443 -27.81676) (xy 277.707816 -27.839696) (xy 277.759722 -27.869663)
			(xy 277.807272 -27.90615) (xy 277.849652 -27.94853) (xy 277.886139 -27.99608) (xy 277.916106 -28.047986)
			(xy 277.939042 -28.103359) (xy 277.954555 -28.161252) (xy 277.962378 -28.220674) (xy 277.962868 -28.250642)
			(xy 277.962868 -29.114242) (xy 277.962735 -29.12237) (xy 292.806628 -29.12237) (xy 292.806628 -28.25877)
			(xy 292.807118 -28.228786) (xy 292.814946 -28.16933) (xy 292.830467 -28.111405) (xy 292.853416 -28.056001)
			(xy 292.8834 -28.004067) (xy 292.919906 -27.956491) (xy 292.962311 -27.914086) (xy 293.009887 -27.87758)
			(xy 293.061821 -27.847596) (xy 293.117225 -27.824647) (xy 293.17515 -27.809126) (xy 293.234606 -27.801298)
			(xy 293.294574 -27.801298) (xy 293.35403 -27.809126) (xy 293.411955 -27.824647) (xy 293.467359 -27.847596)
			(xy 293.519293 -27.87758) (xy 293.566869 -27.914086) (xy 293.609274 -27.956491) (xy 293.64578 -28.004067)
			(xy 293.675764 -28.056001) (xy 293.698713 -28.111405) (xy 293.714234 -28.16933) (xy 293.722062 -28.228786)
			(xy 293.722552 -28.25877) (xy 293.722552 -29.114242) (xy 303.0474 -29.114242) (xy 303.0474 -28.250642)
			(xy 303.04789 -28.220674) (xy 303.055713 -28.161252) (xy 303.071226 -28.103359) (xy 303.094162 -28.047986)
			(xy 303.124129 -27.99608) (xy 303.160616 -27.94853) (xy 303.202996 -27.90615) (xy 303.250546 -27.869663)
			(xy 303.302452 -27.839696) (xy 303.357825 -27.81676) (xy 303.415718 -27.801247) (xy 303.47514 -27.793424)
			(xy 303.535076 -27.793424) (xy 303.594498 -27.801247) (xy 303.652391 -27.81676) (xy 303.707764 -27.839696)
			(xy 303.75967 -27.869663) (xy 303.80722 -27.90615) (xy 303.8496 -27.94853) (xy 303.886087 -27.99608)
			(xy 303.916054 -28.047986) (xy 303.93899 -28.103359) (xy 303.954503 -28.161252) (xy 303.962326 -28.220674)
			(xy 303.962816 -28.250642) (xy 303.962816 -29.114242) (xy 303.962683 -29.12237) (xy 318.806576 -29.12237)
			(xy 318.806576 -28.25877) (xy 318.807066 -28.228786) (xy 318.814894 -28.16933) (xy 318.830415 -28.111405)
			(xy 318.853364 -28.056001) (xy 318.883348 -28.004067) (xy 318.919854 -27.956491) (xy 318.962259 -27.914086)
			(xy 319.009835 -27.87758) (xy 319.061769 -27.847596) (xy 319.117173 -27.824647) (xy 319.175098 -27.809126)
			(xy 319.234554 -27.801298) (xy 319.294522 -27.801298) (xy 319.353978 -27.809126) (xy 319.411903 -27.824647)
			(xy 319.467307 -27.847596) (xy 319.519241 -27.87758) (xy 319.566817 -27.914086) (xy 319.609222 -27.956491)
			(xy 319.645728 -28.004067) (xy 319.675712 -28.056001) (xy 319.698661 -28.111405) (xy 319.714182 -28.16933)
			(xy 319.72201 -28.228786) (xy 319.7225 -28.25877) (xy 319.7225 -29.114242) (xy 329.047348 -29.114242)
			(xy 329.047348 -28.250642) (xy 329.047838 -28.220674) (xy 329.055661 -28.161252) (xy 329.071174 -28.103359)
			(xy 329.09411 -28.047986) (xy 329.124077 -27.99608) (xy 329.160564 -27.94853) (xy 329.202944 -27.90615)
			(xy 329.250494 -27.869663) (xy 329.3024 -27.839696) (xy 329.357773 -27.81676) (xy 329.415666 -27.801247)
			(xy 329.475088 -27.793424) (xy 329.535024 -27.793424) (xy 329.594446 -27.801247) (xy 329.652339 -27.81676)
			(xy 329.707712 -27.839696) (xy 329.759618 -27.869663) (xy 329.807168 -27.90615) (xy 329.849548 -27.94853)
			(xy 329.886035 -27.99608) (xy 329.916002 -28.047986) (xy 329.938938 -28.103359) (xy 329.954451 -28.161252)
			(xy 329.962274 -28.220674) (xy 329.962764 -28.250642) (xy 329.962764 -29.114242) (xy 329.962631 -29.12237)
			(xy 356.907084 -29.12237) (xy 356.907084 -28.25877) (xy 356.907574 -28.228802) (xy 356.915397 -28.16938)
			(xy 356.93091 -28.111487) (xy 356.953846 -28.056114) (xy 356.983813 -28.004208) (xy 357.0203 -27.956658)
			(xy 357.06268 -27.914278) (xy 357.11023 -27.877791) (xy 357.162136 -27.847824) (xy 357.217509 -27.824888)
			(xy 357.275402 -27.809375) (xy 357.334824 -27.801552) (xy 357.39476 -27.801552) (xy 357.454182 -27.809375)
			(xy 357.512075 -27.824888) (xy 357.567448 -27.847824) (xy 357.619354 -27.877791) (xy 357.666904 -27.914278)
			(xy 357.709284 -27.956658) (xy 357.745771 -28.004208) (xy 357.775738 -28.056114) (xy 357.798674 -28.111487)
			(xy 357.814187 -28.16938) (xy 357.82201 -28.228802) (xy 357.8225 -28.25877) (xy 357.8225 -29.114242)
			(xy 367.147348 -29.114242) (xy 367.147348 -28.250642) (xy 367.147838 -28.220658) (xy 367.155666 -28.161202)
			(xy 367.171187 -28.103277) (xy 367.194136 -28.047873) (xy 367.22412 -27.995939) (xy 367.260626 -27.948363)
			(xy 367.303031 -27.905958) (xy 367.350607 -27.869452) (xy 367.402541 -27.839468) (xy 367.457945 -27.816519)
			(xy 367.51587 -27.800998) (xy 367.575326 -27.79317) (xy 367.635294 -27.79317) (xy 367.69475 -27.800998)
			(xy 367.752675 -27.816519) (xy 367.808079 -27.839468) (xy 367.860013 -27.869452) (xy 367.907589 -27.905958)
			(xy 367.949994 -27.948363) (xy 367.9865 -27.995939) (xy 368.016484 -28.047873) (xy 368.039433 -28.103277)
			(xy 368.054954 -28.161202) (xy 368.062782 -28.220658) (xy 368.063272 -28.250642) (xy 368.063272 -29.114242)
			(xy 368.063139 -29.12237) (xy 382.907032 -29.12237) (xy 382.907032 -28.25877) (xy 382.907522 -28.228802)
			(xy 382.915345 -28.16938) (xy 382.930858 -28.111487) (xy 382.953794 -28.056114) (xy 382.983761 -28.004208)
			(xy 383.020248 -27.956658) (xy 383.062628 -27.914278) (xy 383.110178 -27.877791) (xy 383.162084 -27.847824)
			(xy 383.217457 -27.824888) (xy 383.27535 -27.809375) (xy 383.334772 -27.801552) (xy 383.394708 -27.801552)
			(xy 383.45413 -27.809375) (xy 383.512023 -27.824888) (xy 383.567396 -27.847824) (xy 383.619302 -27.877791)
			(xy 383.666852 -27.914278) (xy 383.709232 -27.956658) (xy 383.745719 -28.004208) (xy 383.775686 -28.056114)
			(xy 383.798622 -28.111487) (xy 383.814135 -28.16938) (xy 383.821958 -28.228802) (xy 383.822448 -28.25877)
			(xy 383.822448 -29.114242) (xy 393.147296 -29.114242) (xy 393.147296 -28.250642) (xy 393.147786 -28.220658)
			(xy 393.155614 -28.161202) (xy 393.171135 -28.103277) (xy 393.194084 -28.047873) (xy 393.224068 -27.995939)
			(xy 393.260574 -27.948363) (xy 393.302979 -27.905958) (xy 393.350555 -27.869452) (xy 393.402489 -27.839468)
			(xy 393.457893 -27.816519) (xy 393.515818 -27.800998) (xy 393.575274 -27.79317) (xy 393.635242 -27.79317)
			(xy 393.694698 -27.800998) (xy 393.752623 -27.816519) (xy 393.808027 -27.839468) (xy 393.859961 -27.869452)
			(xy 393.907537 -27.905958) (xy 393.949942 -27.948363) (xy 393.986448 -27.995939) (xy 394.016432 -28.047873)
			(xy 394.039381 -28.103277) (xy 394.054902 -28.161202) (xy 394.06273 -28.220658) (xy 394.06322 -28.250642)
			(xy 394.06322 -29.114242) (xy 394.063087 -29.12237) (xy 408.90698 -29.12237) (xy 408.90698 -28.25877)
			(xy 408.90747 -28.228802) (xy 408.915293 -28.16938) (xy 408.930806 -28.111487) (xy 408.953742 -28.056114)
			(xy 408.983709 -28.004208) (xy 409.020196 -27.956658) (xy 409.062576 -27.914278) (xy 409.110126 -27.877791)
			(xy 409.162032 -27.847824) (xy 409.217405 -27.824888) (xy 409.275298 -27.809375) (xy 409.33472 -27.801552)
			(xy 409.394656 -27.801552) (xy 409.454078 -27.809375) (xy 409.511971 -27.824888) (xy 409.567344 -27.847824)
			(xy 409.61925 -27.877791) (xy 409.6668 -27.914278) (xy 409.70918 -27.956658) (xy 409.745667 -28.004208)
			(xy 409.775634 -28.056114) (xy 409.79857 -28.111487) (xy 409.814083 -28.16938) (xy 409.821906 -28.228802)
			(xy 409.822396 -28.25877) (xy 409.822396 -29.114242) (xy 419.147244 -29.114242) (xy 419.147244 -28.250642)
			(xy 419.147734 -28.220658) (xy 419.155562 -28.161202) (xy 419.171083 -28.103277) (xy 419.194032 -28.047873)
			(xy 419.224016 -27.995939) (xy 419.260522 -27.948363) (xy 419.302927 -27.905958) (xy 419.350503 -27.869452)
			(xy 419.402437 -27.839468) (xy 419.457841 -27.816519) (xy 419.515766 -27.800998) (xy 419.575222 -27.79317)
			(xy 419.63519 -27.79317) (xy 419.694646 -27.800998) (xy 419.752571 -27.816519) (xy 419.807975 -27.839468)
			(xy 419.859909 -27.869452) (xy 419.907485 -27.905958) (xy 419.94989 -27.948363) (xy 419.986396 -27.995939)
			(xy 420.01638 -28.047873) (xy 420.039329 -28.103277) (xy 420.05485 -28.161202) (xy 420.062678 -28.220658)
			(xy 420.063168 -28.250642) (xy 420.063168 -29.114242) (xy 420.063035 -29.12237) (xy 434.906928 -29.12237)
			(xy 434.906928 -28.25877) (xy 434.907418 -28.228802) (xy 434.915241 -28.16938) (xy 434.930754 -28.111487)
			(xy 434.95369 -28.056114) (xy 434.983657 -28.004208) (xy 435.020144 -27.956658) (xy 435.062524 -27.914278)
			(xy 435.110074 -27.877791) (xy 435.16198 -27.847824) (xy 435.217353 -27.824888) (xy 435.275246 -27.809375)
			(xy 435.334668 -27.801552) (xy 435.394604 -27.801552) (xy 435.454026 -27.809375) (xy 435.511919 -27.824888)
			(xy 435.567292 -27.847824) (xy 435.619198 -27.877791) (xy 435.666748 -27.914278) (xy 435.709128 -27.956658)
			(xy 435.745615 -28.004208) (xy 435.775582 -28.056114) (xy 435.798518 -28.111487) (xy 435.814031 -28.16938)
			(xy 435.821854 -28.228802) (xy 435.822344 -28.25877) (xy 435.822344 -29.114242) (xy 445.147192 -29.114242)
			(xy 445.147192 -28.250642) (xy 445.147682 -28.220658) (xy 445.15551 -28.161202) (xy 445.171031 -28.103277)
			(xy 445.19398 -28.047873) (xy 445.223964 -27.995939) (xy 445.26047 -27.948363) (xy 445.302875 -27.905958)
			(xy 445.350451 -27.869452) (xy 445.402385 -27.839468) (xy 445.457789 -27.816519) (xy 445.515714 -27.800998)
			(xy 445.57517 -27.79317) (xy 445.635138 -27.79317) (xy 445.694594 -27.800998) (xy 445.752519 -27.816519)
			(xy 445.807923 -27.839468) (xy 445.859857 -27.869452) (xy 445.907433 -27.905958) (xy 445.949838 -27.948363)
			(xy 445.986344 -27.995939) (xy 446.016328 -28.047873) (xy 446.039277 -28.103277) (xy 446.054798 -28.161202)
			(xy 446.062626 -28.220658) (xy 446.063116 -28.250642) (xy 446.063116 -29.114242) (xy 446.062626 -29.144226)
			(xy 446.054798 -29.203682) (xy 446.039277 -29.261607) (xy 446.016328 -29.317011) (xy 445.986344 -29.368945)
			(xy 445.949838 -29.416521) (xy 445.907433 -29.458926) (xy 445.859857 -29.495432) (xy 445.807923 -29.525416)
			(xy 445.752519 -29.548365) (xy 445.694594 -29.563886) (xy 445.635138 -29.571714) (xy 445.57517 -29.571714)
			(xy 445.515714 -29.563886) (xy 445.457789 -29.548365) (xy 445.402385 -29.525416) (xy 445.350451 -29.495432)
			(xy 445.302875 -29.458926) (xy 445.26047 -29.416521) (xy 445.223964 -29.368945) (xy 445.19398 -29.317011)
			(xy 445.171031 -29.261607) (xy 445.15551 -29.203682) (xy 445.147682 -29.144226) (xy 445.147192 -29.114242)
			(xy 435.822344 -29.114242) (xy 435.822344 -29.12237) (xy 435.821854 -29.152338) (xy 435.814031 -29.21176)
			(xy 435.798518 -29.269653) (xy 435.775582 -29.325026) (xy 435.745615 -29.376932) (xy 435.709128 -29.424482)
			(xy 435.666748 -29.466862) (xy 435.619198 -29.503349) (xy 435.567292 -29.533316) (xy 435.511919 -29.556252)
			(xy 435.454026 -29.571765) (xy 435.394604 -29.579588) (xy 435.334668 -29.579588) (xy 435.275246 -29.571765)
			(xy 435.217353 -29.556252) (xy 435.16198 -29.533316) (xy 435.110074 -29.503349) (xy 435.062524 -29.466862)
			(xy 435.020144 -29.424482) (xy 434.983657 -29.376932) (xy 434.95369 -29.325026) (xy 434.930754 -29.269653)
			(xy 434.915241 -29.21176) (xy 434.907418 -29.152338) (xy 434.906928 -29.12237) (xy 420.063035 -29.12237)
			(xy 420.062678 -29.144226) (xy 420.05485 -29.203682) (xy 420.039329 -29.261607) (xy 420.01638 -29.317011)
			(xy 419.986396 -29.368945) (xy 419.94989 -29.416521) (xy 419.907485 -29.458926) (xy 419.859909 -29.495432)
			(xy 419.807975 -29.525416) (xy 419.752571 -29.548365) (xy 419.694646 -29.563886) (xy 419.63519 -29.571714)
			(xy 419.575222 -29.571714) (xy 419.515766 -29.563886) (xy 419.457841 -29.548365) (xy 419.402437 -29.525416)
			(xy 419.350503 -29.495432) (xy 419.302927 -29.458926) (xy 419.260522 -29.416521) (xy 419.224016 -29.368945)
			(xy 419.194032 -29.317011) (xy 419.171083 -29.261607) (xy 419.155562 -29.203682) (xy 419.147734 -29.144226)
			(xy 419.147244 -29.114242) (xy 409.822396 -29.114242) (xy 409.822396 -29.12237) (xy 409.821906 -29.152338)
			(xy 409.814083 -29.21176) (xy 409.79857 -29.269653) (xy 409.775634 -29.325026) (xy 409.745667 -29.376932)
			(xy 409.70918 -29.424482) (xy 409.6668 -29.466862) (xy 409.61925 -29.503349) (xy 409.567344 -29.533316)
			(xy 409.511971 -29.556252) (xy 409.454078 -29.571765) (xy 409.394656 -29.579588) (xy 409.33472 -29.579588)
			(xy 409.275298 -29.571765) (xy 409.217405 -29.556252) (xy 409.162032 -29.533316) (xy 409.110126 -29.503349)
			(xy 409.062576 -29.466862) (xy 409.020196 -29.424482) (xy 408.983709 -29.376932) (xy 408.953742 -29.325026)
			(xy 408.930806 -29.269653) (xy 408.915293 -29.21176) (xy 408.90747 -29.152338) (xy 408.90698 -29.12237)
			(xy 394.063087 -29.12237) (xy 394.06273 -29.144226) (xy 394.054902 -29.203682) (xy 394.039381 -29.261607)
			(xy 394.016432 -29.317011) (xy 393.986448 -29.368945) (xy 393.949942 -29.416521) (xy 393.907537 -29.458926)
			(xy 393.859961 -29.495432) (xy 393.808027 -29.525416) (xy 393.752623 -29.548365) (xy 393.694698 -29.563886)
			(xy 393.635242 -29.571714) (xy 393.575274 -29.571714) (xy 393.515818 -29.563886) (xy 393.457893 -29.548365)
			(xy 393.402489 -29.525416) (xy 393.350555 -29.495432) (xy 393.302979 -29.458926) (xy 393.260574 -29.416521)
			(xy 393.224068 -29.368945) (xy 393.194084 -29.317011) (xy 393.171135 -29.261607) (xy 393.155614 -29.203682)
			(xy 393.147786 -29.144226) (xy 393.147296 -29.114242) (xy 383.822448 -29.114242) (xy 383.822448 -29.12237)
			(xy 383.821958 -29.152338) (xy 383.814135 -29.21176) (xy 383.798622 -29.269653) (xy 383.775686 -29.325026)
			(xy 383.745719 -29.376932) (xy 383.709232 -29.424482) (xy 383.666852 -29.466862) (xy 383.619302 -29.503349)
			(xy 383.567396 -29.533316) (xy 383.512023 -29.556252) (xy 383.45413 -29.571765) (xy 383.394708 -29.579588)
			(xy 383.334772 -29.579588) (xy 383.27535 -29.571765) (xy 383.217457 -29.556252) (xy 383.162084 -29.533316)
			(xy 383.110178 -29.503349) (xy 383.062628 -29.466862) (xy 383.020248 -29.424482) (xy 382.983761 -29.376932)
			(xy 382.953794 -29.325026) (xy 382.930858 -29.269653) (xy 382.915345 -29.21176) (xy 382.907522 -29.152338)
			(xy 382.907032 -29.12237) (xy 368.063139 -29.12237) (xy 368.062782 -29.144226) (xy 368.054954 -29.203682)
			(xy 368.039433 -29.261607) (xy 368.016484 -29.317011) (xy 367.9865 -29.368945) (xy 367.949994 -29.416521)
			(xy 367.907589 -29.458926) (xy 367.860013 -29.495432) (xy 367.808079 -29.525416) (xy 367.752675 -29.548365)
			(xy 367.69475 -29.563886) (xy 367.635294 -29.571714) (xy 367.575326 -29.571714) (xy 367.51587 -29.563886)
			(xy 367.457945 -29.548365) (xy 367.402541 -29.525416) (xy 367.350607 -29.495432) (xy 367.303031 -29.458926)
			(xy 367.260626 -29.416521) (xy 367.22412 -29.368945) (xy 367.194136 -29.317011) (xy 367.171187 -29.261607)
			(xy 367.155666 -29.203682) (xy 367.147838 -29.144226) (xy 367.147348 -29.114242) (xy 357.8225 -29.114242)
			(xy 357.8225 -29.12237) (xy 357.82201 -29.152338) (xy 357.814187 -29.21176) (xy 357.798674 -29.269653)
			(xy 357.775738 -29.325026) (xy 357.745771 -29.376932) (xy 357.709284 -29.424482) (xy 357.666904 -29.466862)
			(xy 357.619354 -29.503349) (xy 357.567448 -29.533316) (xy 357.512075 -29.556252) (xy 357.454182 -29.571765)
			(xy 357.39476 -29.579588) (xy 357.334824 -29.579588) (xy 357.275402 -29.571765) (xy 357.217509 -29.556252)
			(xy 357.162136 -29.533316) (xy 357.11023 -29.503349) (xy 357.06268 -29.466862) (xy 357.0203 -29.424482)
			(xy 356.983813 -29.376932) (xy 356.953846 -29.325026) (xy 356.93091 -29.269653) (xy 356.915397 -29.21176)
			(xy 356.907574 -29.152338) (xy 356.907084 -29.12237) (xy 329.962631 -29.12237) (xy 329.962274 -29.14421)
			(xy 329.954451 -29.203632) (xy 329.938938 -29.261525) (xy 329.916002 -29.316898) (xy 329.886035 -29.368804)
			(xy 329.849548 -29.416354) (xy 329.807168 -29.458734) (xy 329.759618 -29.495221) (xy 329.707712 -29.525188)
			(xy 329.652339 -29.548124) (xy 329.594446 -29.563637) (xy 329.535024 -29.57146) (xy 329.475088 -29.57146)
			(xy 329.415666 -29.563637) (xy 329.357773 -29.548124) (xy 329.3024 -29.525188) (xy 329.250494 -29.495221)
			(xy 329.202944 -29.458734) (xy 329.160564 -29.416354) (xy 329.124077 -29.368804) (xy 329.09411 -29.316898)
			(xy 329.071174 -29.261525) (xy 329.055661 -29.203632) (xy 329.047838 -29.14421) (xy 329.047348 -29.114242)
			(xy 319.7225 -29.114242) (xy 319.7225 -29.12237) (xy 319.72201 -29.152354) (xy 319.714182 -29.21181)
			(xy 319.698661 -29.269735) (xy 319.675712 -29.325139) (xy 319.645728 -29.377073) (xy 319.609222 -29.424649)
			(xy 319.566817 -29.467054) (xy 319.519241 -29.50356) (xy 319.467307 -29.533544) (xy 319.411903 -29.556493)
			(xy 319.353978 -29.572014) (xy 319.294522 -29.579842) (xy 319.234554 -29.579842) (xy 319.175098 -29.572014)
			(xy 319.117173 -29.556493) (xy 319.061769 -29.533544) (xy 319.009835 -29.50356) (xy 318.962259 -29.467054)
			(xy 318.919854 -29.424649) (xy 318.883348 -29.377073) (xy 318.853364 -29.325139) (xy 318.830415 -29.269735)
			(xy 318.814894 -29.21181) (xy 318.807066 -29.152354) (xy 318.806576 -29.12237) (xy 303.962683 -29.12237)
			(xy 303.962326 -29.14421) (xy 303.954503 -29.203632) (xy 303.93899 -29.261525) (xy 303.916054 -29.316898)
			(xy 303.886087 -29.368804) (xy 303.8496 -29.416354) (xy 303.80722 -29.458734) (xy 303.75967 -29.495221)
			(xy 303.707764 -29.525188) (xy 303.652391 -29.548124) (xy 303.594498 -29.563637) (xy 303.535076 -29.57146)
			(xy 303.47514 -29.57146) (xy 303.415718 -29.563637) (xy 303.357825 -29.548124) (xy 303.302452 -29.525188)
			(xy 303.250546 -29.495221) (xy 303.202996 -29.458734) (xy 303.160616 -29.416354) (xy 303.124129 -29.368804)
			(xy 303.094162 -29.316898) (xy 303.071226 -29.261525) (xy 303.055713 -29.203632) (xy 303.04789 -29.14421)
			(xy 303.0474 -29.114242) (xy 293.722552 -29.114242) (xy 293.722552 -29.12237) (xy 293.722062 -29.152354)
			(xy 293.714234 -29.21181) (xy 293.698713 -29.269735) (xy 293.675764 -29.325139) (xy 293.64578 -29.377073)
			(xy 293.609274 -29.424649) (xy 293.566869 -29.467054) (xy 293.519293 -29.50356) (xy 293.467359 -29.533544)
			(xy 293.411955 -29.556493) (xy 293.35403 -29.572014) (xy 293.294574 -29.579842) (xy 293.234606 -29.579842)
			(xy 293.17515 -29.572014) (xy 293.117225 -29.556493) (xy 293.061821 -29.533544) (xy 293.009887 -29.50356)
			(xy 292.962311 -29.467054) (xy 292.919906 -29.424649) (xy 292.8834 -29.377073) (xy 292.853416 -29.325139)
			(xy 292.830467 -29.269735) (xy 292.814946 -29.21181) (xy 292.807118 -29.152354) (xy 292.806628 -29.12237)
			(xy 277.962735 -29.12237) (xy 277.962378 -29.14421) (xy 277.954555 -29.203632) (xy 277.939042 -29.261525)
			(xy 277.916106 -29.316898) (xy 277.886139 -29.368804) (xy 277.849652 -29.416354) (xy 277.807272 -29.458734)
			(xy 277.759722 -29.495221) (xy 277.707816 -29.525188) (xy 277.652443 -29.548124) (xy 277.59455 -29.563637)
			(xy 277.535128 -29.57146) (xy 277.475192 -29.57146) (xy 277.41577 -29.563637) (xy 277.357877 -29.548124)
			(xy 277.302504 -29.525188) (xy 277.250598 -29.495221) (xy 277.203048 -29.458734) (xy 277.160668 -29.416354)
			(xy 277.124181 -29.368804) (xy 277.094214 -29.316898) (xy 277.071278 -29.261525) (xy 277.055765 -29.203632)
			(xy 277.047942 -29.14421) (xy 277.047452 -29.114242) (xy 267.722604 -29.114242) (xy 267.722604 -29.12237)
			(xy 267.722114 -29.152354) (xy 267.714286 -29.21181) (xy 267.698765 -29.269735) (xy 267.675816 -29.325139)
			(xy 267.645832 -29.377073) (xy 267.609326 -29.424649) (xy 267.566921 -29.467054) (xy 267.519345 -29.50356)
			(xy 267.467411 -29.533544) (xy 267.412007 -29.556493) (xy 267.354082 -29.572014) (xy 267.294626 -29.579842)
			(xy 267.234658 -29.579842) (xy 267.175202 -29.572014) (xy 267.117277 -29.556493) (xy 267.061873 -29.533544)
			(xy 267.009939 -29.50356) (xy 266.962363 -29.467054) (xy 266.919958 -29.424649) (xy 266.883452 -29.377073)
			(xy 266.853468 -29.325139) (xy 266.830519 -29.269735) (xy 266.814998 -29.21181) (xy 266.80717 -29.152354)
			(xy 266.80668 -29.12237) (xy 251.962787 -29.12237) (xy 251.96243 -29.14421) (xy 251.954607 -29.203632)
			(xy 251.939094 -29.261525) (xy 251.916158 -29.316898) (xy 251.886191 -29.368804) (xy 251.849704 -29.416354)
			(xy 251.807324 -29.458734) (xy 251.759774 -29.495221) (xy 251.707868 -29.525188) (xy 251.652495 -29.548124)
			(xy 251.594602 -29.563637) (xy 251.53518 -29.57146) (xy 251.475244 -29.57146) (xy 251.415822 -29.563637)
			(xy 251.357929 -29.548124) (xy 251.302556 -29.525188) (xy 251.25065 -29.495221) (xy 251.2031 -29.458734)
			(xy 251.16072 -29.416354) (xy 251.124233 -29.368804) (xy 251.094266 -29.316898) (xy 251.07133 -29.261525)
			(xy 251.055817 -29.203632) (xy 251.047994 -29.14421) (xy 251.047504 -29.114242) (xy 241.722656 -29.114242)
			(xy 241.722656 -29.12237) (xy 241.722166 -29.152354) (xy 241.714338 -29.21181) (xy 241.698817 -29.269735)
			(xy 241.675868 -29.325139) (xy 241.645884 -29.377073) (xy 241.609378 -29.424649) (xy 241.566973 -29.467054)
			(xy 241.519397 -29.50356) (xy 241.467463 -29.533544) (xy 241.412059 -29.556493) (xy 241.354134 -29.572014)
			(xy 241.294678 -29.579842) (xy 241.23471 -29.579842) (xy 241.175254 -29.572014) (xy 241.117329 -29.556493)
			(xy 241.061925 -29.533544) (xy 241.009991 -29.50356) (xy 240.962415 -29.467054) (xy 240.92001 -29.424649)
			(xy 240.883504 -29.377073) (xy 240.85352 -29.325139) (xy 240.830571 -29.269735) (xy 240.81505 -29.21181)
			(xy 240.807222 -29.152354) (xy 240.806732 -29.12237) (xy 213.862787 -29.12237) (xy 213.86243 -29.14421)
			(xy 213.854607 -29.203632) (xy 213.839094 -29.261525) (xy 213.816158 -29.316898) (xy 213.786191 -29.368804)
			(xy 213.749704 -29.416354) (xy 213.707324 -29.458734) (xy 213.659774 -29.495221) (xy 213.607868 -29.525188)
			(xy 213.552495 -29.548124) (xy 213.494602 -29.563637) (xy 213.43518 -29.57146) (xy 213.375244 -29.57146)
			(xy 213.315822 -29.563637) (xy 213.257929 -29.548124) (xy 213.202556 -29.525188) (xy 213.15065 -29.495221)
			(xy 213.1031 -29.458734) (xy 213.06072 -29.416354) (xy 213.024233 -29.368804) (xy 212.994266 -29.316898)
			(xy 212.97133 -29.261525) (xy 212.955817 -29.203632) (xy 212.947994 -29.14421) (xy 212.947504 -29.114242)
			(xy 203.622656 -29.114242) (xy 203.622656 -29.12237) (xy 203.622166 -29.152354) (xy 203.614338 -29.21181)
			(xy 203.598817 -29.269735) (xy 203.575868 -29.325139) (xy 203.545884 -29.377073) (xy 203.509378 -29.424649)
			(xy 203.466973 -29.467054) (xy 203.419397 -29.50356) (xy 203.367463 -29.533544) (xy 203.312059 -29.556493)
			(xy 203.254134 -29.572014) (xy 203.194678 -29.579842) (xy 203.13471 -29.579842) (xy 203.075254 -29.572014)
			(xy 203.017329 -29.556493) (xy 202.961925 -29.533544) (xy 202.909991 -29.50356) (xy 202.862415 -29.467054)
			(xy 202.82001 -29.424649) (xy 202.783504 -29.377073) (xy 202.75352 -29.325139) (xy 202.730571 -29.269735)
			(xy 202.71505 -29.21181) (xy 202.707222 -29.152354) (xy 202.706732 -29.12237) (xy 187.862839 -29.12237)
			(xy 187.862482 -29.14421) (xy 187.854659 -29.203632) (xy 187.839146 -29.261525) (xy 187.81621 -29.316898)
			(xy 187.786243 -29.368804) (xy 187.749756 -29.416354) (xy 187.707376 -29.458734) (xy 187.659826 -29.495221)
			(xy 187.60792 -29.525188) (xy 187.552547 -29.548124) (xy 187.494654 -29.563637) (xy 187.435232 -29.57146)
			(xy 187.375296 -29.57146) (xy 187.315874 -29.563637) (xy 187.257981 -29.548124) (xy 187.202608 -29.525188)
			(xy 187.150702 -29.495221) (xy 187.103152 -29.458734) (xy 187.060772 -29.416354) (xy 187.024285 -29.368804)
			(xy 186.994318 -29.316898) (xy 186.971382 -29.261525) (xy 186.955869 -29.203632) (xy 186.948046 -29.14421)
			(xy 186.947556 -29.114242) (xy 177.622708 -29.114242) (xy 177.622708 -29.12237) (xy 177.622218 -29.152354)
			(xy 177.61439 -29.21181) (xy 177.598869 -29.269735) (xy 177.57592 -29.325139) (xy 177.545936 -29.377073)
			(xy 177.50943 -29.424649) (xy 177.467025 -29.467054) (xy 177.419449 -29.50356) (xy 177.367515 -29.533544)
			(xy 177.312111 -29.556493) (xy 177.254186 -29.572014) (xy 177.19473 -29.579842) (xy 177.134762 -29.579842)
			(xy 177.075306 -29.572014) (xy 177.017381 -29.556493) (xy 176.961977 -29.533544) (xy 176.910043 -29.50356)
			(xy 176.862467 -29.467054) (xy 176.820062 -29.424649) (xy 176.783556 -29.377073) (xy 176.753572 -29.325139)
			(xy 176.730623 -29.269735) (xy 176.715102 -29.21181) (xy 176.707274 -29.152354) (xy 176.706784 -29.12237)
			(xy 161.862891 -29.12237) (xy 161.862534 -29.14421) (xy 161.854711 -29.203632) (xy 161.839198 -29.261525)
			(xy 161.816262 -29.316898) (xy 161.786295 -29.368804) (xy 161.749808 -29.416354) (xy 161.707428 -29.458734)
			(xy 161.659878 -29.495221) (xy 161.607972 -29.525188) (xy 161.552599 -29.548124) (xy 161.494706 -29.563637)
			(xy 161.435284 -29.57146) (xy 161.375348 -29.57146) (xy 161.315926 -29.563637) (xy 161.258033 -29.548124)
			(xy 161.20266 -29.525188) (xy 161.150754 -29.495221) (xy 161.103204 -29.458734) (xy 161.060824 -29.416354)
			(xy 161.024337 -29.368804) (xy 160.99437 -29.316898) (xy 160.971434 -29.261525) (xy 160.955921 -29.203632)
			(xy 160.948098 -29.14421) (xy 160.947608 -29.114242) (xy 151.62276 -29.114242) (xy 151.62276 -29.12237)
			(xy 151.62227 -29.152354) (xy 151.614442 -29.21181) (xy 151.598921 -29.269735) (xy 151.575972 -29.325139)
			(xy 151.545988 -29.377073) (xy 151.509482 -29.424649) (xy 151.467077 -29.467054) (xy 151.419501 -29.50356)
			(xy 151.367567 -29.533544) (xy 151.312163 -29.556493) (xy 151.254238 -29.572014) (xy 151.194782 -29.579842)
			(xy 151.134814 -29.579842) (xy 151.075358 -29.572014) (xy 151.017433 -29.556493) (xy 150.962029 -29.533544)
			(xy 150.910095 -29.50356) (xy 150.862519 -29.467054) (xy 150.820114 -29.424649) (xy 150.783608 -29.377073)
			(xy 150.753624 -29.325139) (xy 150.730675 -29.269735) (xy 150.715154 -29.21181) (xy 150.707326 -29.152354)
			(xy 150.706836 -29.12237) (xy 135.862943 -29.12237) (xy 135.862586 -29.14421) (xy 135.854763 -29.203632)
			(xy 135.83925 -29.261525) (xy 135.816314 -29.316898) (xy 135.786347 -29.368804) (xy 135.74986 -29.416354)
			(xy 135.70748 -29.458734) (xy 135.65993 -29.495221) (xy 135.608024 -29.525188) (xy 135.552651 -29.548124)
			(xy 135.494758 -29.563637) (xy 135.435336 -29.57146) (xy 135.3754 -29.57146) (xy 135.315978 -29.563637)
			(xy 135.258085 -29.548124) (xy 135.202712 -29.525188) (xy 135.150806 -29.495221) (xy 135.103256 -29.458734)
			(xy 135.060876 -29.416354) (xy 135.024389 -29.368804) (xy 134.994422 -29.316898) (xy 134.971486 -29.261525)
			(xy 134.955973 -29.203632) (xy 134.94815 -29.14421) (xy 134.94766 -29.114242) (xy 125.622812 -29.114242)
			(xy 125.622812 -29.12237) (xy 125.622322 -29.152354) (xy 125.614494 -29.21181) (xy 125.598973 -29.269735)
			(xy 125.576024 -29.325139) (xy 125.54604 -29.377073) (xy 125.509534 -29.424649) (xy 125.467129 -29.467054)
			(xy 125.419553 -29.50356) (xy 125.367619 -29.533544) (xy 125.312215 -29.556493) (xy 125.25429 -29.572014)
			(xy 125.194834 -29.579842) (xy 125.134866 -29.579842) (xy 125.07541 -29.572014) (xy 125.017485 -29.556493)
			(xy 124.962081 -29.533544) (xy 124.910147 -29.50356) (xy 124.862571 -29.467054) (xy 124.820166 -29.424649)
			(xy 124.78366 -29.377073) (xy 124.753676 -29.325139) (xy 124.730727 -29.269735) (xy 124.715206 -29.21181)
			(xy 124.707378 -29.152354) (xy 124.706888 -29.12237) (xy 97.762943 -29.12237) (xy 97.762586 -29.144226)
			(xy 97.754758 -29.203682) (xy 97.739237 -29.261607) (xy 97.716288 -29.317011) (xy 97.686304 -29.368945)
			(xy 97.649798 -29.416521) (xy 97.607393 -29.458926) (xy 97.559817 -29.495432) (xy 97.507883 -29.525416)
			(xy 97.452479 -29.548365) (xy 97.394554 -29.563886) (xy 97.335098 -29.571714) (xy 97.27513 -29.571714)
			(xy 97.215674 -29.563886) (xy 97.157749 -29.548365) (xy 97.102345 -29.525416) (xy 97.050411 -29.495432)
			(xy 97.002835 -29.458926) (xy 96.96043 -29.416521) (xy 96.923924 -29.368945) (xy 96.89394 -29.317011)
			(xy 96.870991 -29.261607) (xy 96.85547 -29.203682) (xy 96.847642 -29.144226) (xy 96.847152 -29.114242)
			(xy 87.522304 -29.114242) (xy 87.522304 -29.12237) (xy 87.521814 -29.152338) (xy 87.513991 -29.21176)
			(xy 87.498478 -29.269653) (xy 87.475542 -29.325026) (xy 87.445575 -29.376932) (xy 87.409088 -29.424482)
			(xy 87.366708 -29.466862) (xy 87.319158 -29.503349) (xy 87.267252 -29.533316) (xy 87.211879 -29.556252)
			(xy 87.153986 -29.571765) (xy 87.094564 -29.579588) (xy 87.034628 -29.579588) (xy 86.975206 -29.571765)
			(xy 86.917313 -29.556252) (xy 86.86194 -29.533316) (xy 86.810034 -29.503349) (xy 86.762484 -29.466862)
			(xy 86.720104 -29.424482) (xy 86.683617 -29.376932) (xy 86.65365 -29.325026) (xy 86.630714 -29.269653)
			(xy 86.615201 -29.21176) (xy 86.607378 -29.152338) (xy 86.606888 -29.12237) (xy 71.762995 -29.12237)
			(xy 71.762638 -29.144226) (xy 71.75481 -29.203682) (xy 71.739289 -29.261607) (xy 71.71634 -29.317011)
			(xy 71.686356 -29.368945) (xy 71.64985 -29.416521) (xy 71.607445 -29.458926) (xy 71.559869 -29.495432)
			(xy 71.507935 -29.525416) (xy 71.452531 -29.548365) (xy 71.394606 -29.563886) (xy 71.33515 -29.571714)
			(xy 71.275182 -29.571714) (xy 71.215726 -29.563886) (xy 71.157801 -29.548365) (xy 71.102397 -29.525416)
			(xy 71.050463 -29.495432) (xy 71.002887 -29.458926) (xy 70.960482 -29.416521) (xy 70.923976 -29.368945)
			(xy 70.893992 -29.317011) (xy 70.871043 -29.261607) (xy 70.855522 -29.203682) (xy 70.847694 -29.144226)
			(xy 70.847204 -29.114242) (xy 61.522356 -29.114242) (xy 61.522356 -29.12237) (xy 61.521866 -29.152338)
			(xy 61.514043 -29.21176) (xy 61.49853 -29.269653) (xy 61.475594 -29.325026) (xy 61.445627 -29.376932)
			(xy 61.40914 -29.424482) (xy 61.36676 -29.466862) (xy 61.31921 -29.503349) (xy 61.267304 -29.533316)
			(xy 61.211931 -29.556252) (xy 61.154038 -29.571765) (xy 61.094616 -29.579588) (xy 61.03468 -29.579588)
			(xy 60.975258 -29.571765) (xy 60.917365 -29.556252) (xy 60.861992 -29.533316) (xy 60.810086 -29.503349)
			(xy 60.762536 -29.466862) (xy 60.720156 -29.424482) (xy 60.683669 -29.376932) (xy 60.653702 -29.325026)
			(xy 60.630766 -29.269653) (xy 60.615253 -29.21176) (xy 60.60743 -29.152338) (xy 60.60694 -29.12237)
			(xy 45.763047 -29.12237) (xy 45.76269 -29.144226) (xy 45.754862 -29.203682) (xy 45.739341 -29.261607)
			(xy 45.716392 -29.317011) (xy 45.686408 -29.368945) (xy 45.649902 -29.416521) (xy 45.607497 -29.458926)
			(xy 45.559921 -29.495432) (xy 45.507987 -29.525416) (xy 45.452583 -29.548365) (xy 45.394658 -29.563886)
			(xy 45.335202 -29.571714) (xy 45.275234 -29.571714) (xy 45.215778 -29.563886) (xy 45.157853 -29.548365)
			(xy 45.102449 -29.525416) (xy 45.050515 -29.495432) (xy 45.002939 -29.458926) (xy 44.960534 -29.416521)
			(xy 44.924028 -29.368945) (xy 44.894044 -29.317011) (xy 44.871095 -29.261607) (xy 44.855574 -29.203682)
			(xy 44.847746 -29.144226) (xy 44.847256 -29.114242) (xy 35.522408 -29.114242) (xy 35.522408 -29.12237)
			(xy 35.521918 -29.152338) (xy 35.514095 -29.21176) (xy 35.498582 -29.269653) (xy 35.475646 -29.325026)
			(xy 35.445679 -29.376932) (xy 35.409192 -29.424482) (xy 35.366812 -29.466862) (xy 35.319262 -29.503349)
			(xy 35.267356 -29.533316) (xy 35.211983 -29.556252) (xy 35.15409 -29.571765) (xy 35.094668 -29.579588)
			(xy 35.034732 -29.579588) (xy 34.97531 -29.571765) (xy 34.917417 -29.556252) (xy 34.862044 -29.533316)
			(xy 34.810138 -29.503349) (xy 34.762588 -29.466862) (xy 34.720208 -29.424482) (xy 34.683721 -29.376932)
			(xy 34.653754 -29.325026) (xy 34.630818 -29.269653) (xy 34.615305 -29.21176) (xy 34.607482 -29.152338)
			(xy 34.606992 -29.12237) (xy 19.763099 -29.12237) (xy 19.762742 -29.144226) (xy 19.754914 -29.203682)
			(xy 19.739393 -29.261607) (xy 19.716444 -29.317011) (xy 19.68646 -29.368945) (xy 19.649954 -29.416521)
			(xy 19.607549 -29.458926) (xy 19.559973 -29.495432) (xy 19.508039 -29.525416) (xy 19.452635 -29.548365)
			(xy 19.39471 -29.563886) (xy 19.335254 -29.571714) (xy 19.275286 -29.571714) (xy 19.21583 -29.563886)
			(xy 19.157905 -29.548365) (xy 19.102501 -29.525416) (xy 19.050567 -29.495432) (xy 19.002991 -29.458926)
			(xy 18.960586 -29.416521) (xy 18.92408 -29.368945) (xy 18.894096 -29.317011) (xy 18.871147 -29.261607)
			(xy 18.855626 -29.203682) (xy 18.847798 -29.144226) (xy 18.847308 -29.114242) (xy 9.52246 -29.114242)
			(xy 9.52246 -29.12237) (xy 9.52197 -29.152338) (xy 9.514147 -29.21176) (xy 9.498634 -29.269653) (xy 9.475698 -29.325026)
			(xy 9.445731 -29.376932) (xy 9.409244 -29.424482) (xy 9.366864 -29.466862) (xy 9.319314 -29.503349)
			(xy 9.267408 -29.533316) (xy 9.212035 -29.556252) (xy 9.154142 -29.571765) (xy 9.09472 -29.579588)
			(xy 9.034784 -29.579588) (xy 8.975362 -29.571765) (xy 8.917469 -29.556252) (xy 8.862096 -29.533316)
			(xy 8.81019 -29.503349) (xy 8.76264 -29.466862) (xy 8.72026 -29.424482) (xy 8.683773 -29.376932)
			(xy 8.653806 -29.325026) (xy 8.63087 -29.269653) (xy 8.615357 -29.21176) (xy 8.607534 -29.152338)
			(xy 8.607044 -29.12237) (xy 0.509016 -29.12237) (xy 0.509016 -30.922468) (xy 6.752844 -30.922468)
			(xy 6.752844 -30.058868) (xy 6.753334 -30.0289) (xy 6.761157 -29.969478) (xy 6.77667 -29.911585)
			(xy 6.799606 -29.856212) (xy 6.829573 -29.804306) (xy 6.86606 -29.756756) (xy 6.90844 -29.714376)
			(xy 6.95599 -29.677889) (xy 7.007896 -29.647922) (xy 7.063269 -29.624986) (xy 7.121162 -29.609473)
			(xy 7.180584 -29.60165) (xy 7.24052 -29.60165) (xy 7.299942 -29.609473) (xy 7.357835 -29.624986)
			(xy 7.413208 -29.647922) (xy 7.465114 -29.677889) (xy 7.512664 -29.714376) (xy 7.555044 -29.756756)
			(xy 7.591531 -29.804306) (xy 7.621498 -29.856212) (xy 7.644434 -29.911585) (xy 7.659947 -29.969478)
			(xy 7.66777 -30.0289) (xy 7.66826 -30.058868) (xy 7.66826 -30.92069) (xy 21.489416 -30.92069) (xy 21.489416 -30.05709)
			(xy 21.489906 -30.027106) (xy 21.497734 -29.96765) (xy 21.513255 -29.909725) (xy 21.536204 -29.854321)
			(xy 21.566188 -29.802387) (xy 21.602694 -29.754811) (xy 21.645099 -29.712406) (xy 21.692675 -29.6759)
			(xy 21.744609 -29.645916) (xy 21.800013 -29.622967) (xy 21.857938 -29.607446) (xy 21.917394 -29.599618)
			(xy 21.977362 -29.599618) (xy 22.036818 -29.607446) (xy 22.094743 -29.622967) (xy 22.150147 -29.645916)
			(xy 22.202081 -29.6759) (xy 22.249657 -29.712406) (xy 22.292062 -29.754811) (xy 22.328568 -29.802387)
			(xy 22.358552 -29.854321) (xy 22.381501 -29.909725) (xy 22.397022 -29.96765) (xy 22.40485 -30.027106)
			(xy 22.40534 -30.05709) (xy 22.40534 -30.92069) (xy 22.405311 -30.922468) (xy 32.752792 -30.922468)
			(xy 32.752792 -30.058868) (xy 32.753282 -30.0289) (xy 32.761105 -29.969478) (xy 32.776618 -29.911585)
			(xy 32.799554 -29.856212) (xy 32.829521 -29.804306) (xy 32.866008 -29.756756) (xy 32.908388 -29.714376)
			(xy 32.955938 -29.677889) (xy 33.007844 -29.647922) (xy 33.063217 -29.624986) (xy 33.12111 -29.609473)
			(xy 33.180532 -29.60165) (xy 33.240468 -29.60165) (xy 33.29989 -29.609473) (xy 33.357783 -29.624986)
			(xy 33.413156 -29.647922) (xy 33.465062 -29.677889) (xy 33.512612 -29.714376) (xy 33.554992 -29.756756)
			(xy 33.591479 -29.804306) (xy 33.621446 -29.856212) (xy 33.644382 -29.911585) (xy 33.659895 -29.969478)
			(xy 33.667718 -30.0289) (xy 33.668208 -30.058868) (xy 33.668208 -30.92069) (xy 47.489364 -30.92069)
			(xy 47.489364 -30.05709) (xy 47.489854 -30.027106) (xy 47.497682 -29.96765) (xy 47.513203 -29.909725)
			(xy 47.536152 -29.854321) (xy 47.566136 -29.802387) (xy 47.602642 -29.754811) (xy 47.645047 -29.712406)
			(xy 47.692623 -29.6759) (xy 47.744557 -29.645916) (xy 47.799961 -29.622967) (xy 47.857886 -29.607446)
			(xy 47.917342 -29.599618) (xy 47.97731 -29.599618) (xy 48.036766 -29.607446) (xy 48.094691 -29.622967)
			(xy 48.150095 -29.645916) (xy 48.202029 -29.6759) (xy 48.249605 -29.712406) (xy 48.29201 -29.754811)
			(xy 48.328516 -29.802387) (xy 48.3585 -29.854321) (xy 48.381449 -29.909725) (xy 48.39697 -29.96765)
			(xy 48.404798 -30.027106) (xy 48.405288 -30.05709) (xy 48.405288 -30.92069) (xy 48.405259 -30.922468)
			(xy 58.75274 -30.922468) (xy 58.75274 -30.058868) (xy 58.75323 -30.0289) (xy 58.761053 -29.969478)
			(xy 58.776566 -29.911585) (xy 58.799502 -29.856212) (xy 58.829469 -29.804306) (xy 58.865956 -29.756756)
			(xy 58.908336 -29.714376) (xy 58.955886 -29.677889) (xy 59.007792 -29.647922) (xy 59.063165 -29.624986)
			(xy 59.121058 -29.609473) (xy 59.18048 -29.60165) (xy 59.240416 -29.60165) (xy 59.299838 -29.609473)
			(xy 59.357731 -29.624986) (xy 59.413104 -29.647922) (xy 59.46501 -29.677889) (xy 59.51256 -29.714376)
			(xy 59.55494 -29.756756) (xy 59.591427 -29.804306) (xy 59.621394 -29.856212) (xy 59.64433 -29.911585)
			(xy 59.659843 -29.969478) (xy 59.667666 -30.0289) (xy 59.668156 -30.058868) (xy 59.668156 -30.92069)
			(xy 73.489312 -30.92069) (xy 73.489312 -30.05709) (xy 73.489802 -30.027106) (xy 73.49763 -29.96765)
			(xy 73.513151 -29.909725) (xy 73.5361 -29.854321) (xy 73.566084 -29.802387) (xy 73.60259 -29.754811)
			(xy 73.644995 -29.712406) (xy 73.692571 -29.6759) (xy 73.744505 -29.645916) (xy 73.799909 -29.622967)
			(xy 73.857834 -29.607446) (xy 73.91729 -29.599618) (xy 73.977258 -29.599618) (xy 74.036714 -29.607446)
			(xy 74.094639 -29.622967) (xy 74.150043 -29.645916) (xy 74.201977 -29.6759) (xy 74.249553 -29.712406)
			(xy 74.291958 -29.754811) (xy 74.328464 -29.802387) (xy 74.358448 -29.854321) (xy 74.381397 -29.909725)
			(xy 74.396918 -29.96765) (xy 74.404746 -30.027106) (xy 74.405236 -30.05709) (xy 74.405236 -30.92069)
			(xy 74.405207 -30.922468) (xy 84.752688 -30.922468) (xy 84.752688 -30.058868) (xy 84.753178 -30.0289)
			(xy 84.761001 -29.969478) (xy 84.776514 -29.911585) (xy 84.79945 -29.856212) (xy 84.829417 -29.804306)
			(xy 84.865904 -29.756756) (xy 84.908284 -29.714376) (xy 84.955834 -29.677889) (xy 85.00774 -29.647922)
			(xy 85.063113 -29.624986) (xy 85.121006 -29.609473) (xy 85.180428 -29.60165) (xy 85.240364 -29.60165)
			(xy 85.299786 -29.609473) (xy 85.357679 -29.624986) (xy 85.413052 -29.647922) (xy 85.464958 -29.677889)
			(xy 85.512508 -29.714376) (xy 85.554888 -29.756756) (xy 85.591375 -29.804306) (xy 85.621342 -29.856212)
			(xy 85.644278 -29.911585) (xy 85.659791 -29.969478) (xy 85.667614 -30.0289) (xy 85.668104 -30.058868)
			(xy 85.668104 -30.92069) (xy 99.48926 -30.92069) (xy 99.48926 -30.05709) (xy 99.48975 -30.027106)
			(xy 99.497578 -29.96765) (xy 99.513099 -29.909725) (xy 99.536048 -29.854321) (xy 99.566032 -29.802387)
			(xy 99.602538 -29.754811) (xy 99.644943 -29.712406) (xy 99.692519 -29.6759) (xy 99.744453 -29.645916)
			(xy 99.799857 -29.622967) (xy 99.857782 -29.607446) (xy 99.917238 -29.599618) (xy 99.977206 -29.599618)
			(xy 100.036662 -29.607446) (xy 100.094587 -29.622967) (xy 100.149991 -29.645916) (xy 100.201925 -29.6759)
			(xy 100.249501 -29.712406) (xy 100.291906 -29.754811) (xy 100.328412 -29.802387) (xy 100.358396 -29.854321)
			(xy 100.381345 -29.909725) (xy 100.396866 -29.96765) (xy 100.404694 -30.027106) (xy 100.405184 -30.05709)
			(xy 100.405184 -30.92069) (xy 100.405155 -30.922468) (xy 122.852688 -30.922468) (xy 122.852688 -30.058868)
			(xy 122.853178 -30.028884) (xy 122.861006 -29.969428) (xy 122.876527 -29.911503) (xy 122.899476 -29.856099)
			(xy 122.92946 -29.804165) (xy 122.965966 -29.756589) (xy 123.008371 -29.714184) (xy 123.055947 -29.677678)
			(xy 123.107881 -29.647694) (xy 123.163285 -29.624745) (xy 123.22121 -29.609224) (xy 123.280666 -29.601396)
			(xy 123.340634 -29.601396) (xy 123.40009 -29.609224) (xy 123.458015 -29.624745) (xy 123.513419 -29.647694)
			(xy 123.565353 -29.677678) (xy 123.612929 -29.714184) (xy 123.655334 -29.756589) (xy 123.69184 -29.804165)
			(xy 123.721824 -29.856099) (xy 123.744773 -29.911503) (xy 123.760294 -29.969428) (xy 123.768122 -30.028884)
			(xy 123.768612 -30.058868) (xy 123.768612 -30.92069) (xy 137.589768 -30.92069) (xy 137.589768 -30.05709)
			(xy 137.590258 -30.027122) (xy 137.598081 -29.9677) (xy 137.613594 -29.909807) (xy 137.63653 -29.854434)
			(xy 137.666497 -29.802528) (xy 137.702984 -29.754978) (xy 137.745364 -29.712598) (xy 137.792914 -29.676111)
			(xy 137.84482 -29.646144) (xy 137.900193 -29.623208) (xy 137.958086 -29.607695) (xy 138.017508 -29.599872)
			(xy 138.077444 -29.599872) (xy 138.136866 -29.607695) (xy 138.194759 -29.623208) (xy 138.250132 -29.646144)
			(xy 138.302038 -29.676111) (xy 138.349588 -29.712598) (xy 138.391968 -29.754978) (xy 138.428455 -29.802528)
			(xy 138.458422 -29.854434) (xy 138.481358 -29.909807) (xy 138.496871 -29.9677) (xy 138.504694 -30.027122)
			(xy 138.505184 -30.05709) (xy 138.505184 -30.92069) (xy 138.505155 -30.922468) (xy 148.852636 -30.922468)
			(xy 148.852636 -30.058868) (xy 148.853126 -30.028884) (xy 148.860954 -29.969428) (xy 148.876475 -29.911503)
			(xy 148.899424 -29.856099) (xy 148.929408 -29.804165) (xy 148.965914 -29.756589) (xy 149.008319 -29.714184)
			(xy 149.055895 -29.677678) (xy 149.107829 -29.647694) (xy 149.163233 -29.624745) (xy 149.221158 -29.609224)
			(xy 149.280614 -29.601396) (xy 149.340582 -29.601396) (xy 149.400038 -29.609224) (xy 149.457963 -29.624745)
			(xy 149.513367 -29.647694) (xy 149.565301 -29.677678) (xy 149.612877 -29.714184) (xy 149.655282 -29.756589)
			(xy 149.691788 -29.804165) (xy 149.721772 -29.856099) (xy 149.744721 -29.911503) (xy 149.760242 -29.969428)
			(xy 149.76807 -30.028884) (xy 149.76856 -30.058868) (xy 149.76856 -30.92069) (xy 163.589716 -30.92069)
			(xy 163.589716 -30.05709) (xy 163.590206 -30.027122) (xy 163.598029 -29.9677) (xy 163.613542 -29.909807)
			(xy 163.636478 -29.854434) (xy 163.666445 -29.802528) (xy 163.702932 -29.754978) (xy 163.745312 -29.712598)
			(xy 163.792862 -29.676111) (xy 163.844768 -29.646144) (xy 163.900141 -29.623208) (xy 163.958034 -29.607695)
			(xy 164.017456 -29.599872) (xy 164.077392 -29.599872) (xy 164.136814 -29.607695) (xy 164.194707 -29.623208)
			(xy 164.25008 -29.646144) (xy 164.301986 -29.676111) (xy 164.349536 -29.712598) (xy 164.391916 -29.754978)
			(xy 164.428403 -29.802528) (xy 164.45837 -29.854434) (xy 164.481306 -29.909807) (xy 164.496819 -29.9677)
			(xy 164.504642 -30.027122) (xy 164.505132 -30.05709) (xy 164.505132 -30.92069) (xy 164.505103 -30.922468)
			(xy 174.852584 -30.922468) (xy 174.852584 -30.058868) (xy 174.853074 -30.028884) (xy 174.860902 -29.969428)
			(xy 174.876423 -29.911503) (xy 174.899372 -29.856099) (xy 174.929356 -29.804165) (xy 174.965862 -29.756589)
			(xy 175.008267 -29.714184) (xy 175.055843 -29.677678) (xy 175.107777 -29.647694) (xy 175.163181 -29.624745)
			(xy 175.221106 -29.609224) (xy 175.280562 -29.601396) (xy 175.34053 -29.601396) (xy 175.399986 -29.609224)
			(xy 175.457911 -29.624745) (xy 175.513315 -29.647694) (xy 175.565249 -29.677678) (xy 175.612825 -29.714184)
			(xy 175.65523 -29.756589) (xy 175.691736 -29.804165) (xy 175.72172 -29.856099) (xy 175.744669 -29.911503)
			(xy 175.76019 -29.969428) (xy 175.768018 -30.028884) (xy 175.768508 -30.058868) (xy 175.768508 -30.92069)
			(xy 189.589664 -30.92069) (xy 189.589664 -30.05709) (xy 189.590154 -30.027122) (xy 189.597977 -29.9677)
			(xy 189.61349 -29.909807) (xy 189.636426 -29.854434) (xy 189.666393 -29.802528) (xy 189.70288 -29.754978)
			(xy 189.74526 -29.712598) (xy 189.79281 -29.676111) (xy 189.844716 -29.646144) (xy 189.900089 -29.623208)
			(xy 189.957982 -29.607695) (xy 190.017404 -29.599872) (xy 190.07734 -29.599872) (xy 190.136762 -29.607695)
			(xy 190.194655 -29.623208) (xy 190.250028 -29.646144) (xy 190.301934 -29.676111) (xy 190.349484 -29.712598)
			(xy 190.391864 -29.754978) (xy 190.428351 -29.802528) (xy 190.458318 -29.854434) (xy 190.481254 -29.909807)
			(xy 190.496767 -29.9677) (xy 190.50459 -30.027122) (xy 190.50508 -30.05709) (xy 190.50508 -30.92069)
			(xy 190.505051 -30.922468) (xy 200.852532 -30.922468) (xy 200.852532 -30.058868) (xy 200.853022 -30.028884)
			(xy 200.86085 -29.969428) (xy 200.876371 -29.911503) (xy 200.89932 -29.856099) (xy 200.929304 -29.804165)
			(xy 200.96581 -29.756589) (xy 201.008215 -29.714184) (xy 201.055791 -29.677678) (xy 201.107725 -29.647694)
			(xy 201.163129 -29.624745) (xy 201.221054 -29.609224) (xy 201.28051 -29.601396) (xy 201.340478 -29.601396)
			(xy 201.399934 -29.609224) (xy 201.457859 -29.624745) (xy 201.513263 -29.647694) (xy 201.565197 -29.677678)
			(xy 201.612773 -29.714184) (xy 201.655178 -29.756589) (xy 201.691684 -29.804165) (xy 201.721668 -29.856099)
			(xy 201.744617 -29.911503) (xy 201.760138 -29.969428) (xy 201.767966 -30.028884) (xy 201.768456 -30.058868)
			(xy 201.768456 -30.92069) (xy 215.589612 -30.92069) (xy 215.589612 -30.05709) (xy 215.590102 -30.027122)
			(xy 215.597925 -29.9677) (xy 215.613438 -29.909807) (xy 215.636374 -29.854434) (xy 215.666341 -29.802528)
			(xy 215.702828 -29.754978) (xy 215.745208 -29.712598) (xy 215.792758 -29.676111) (xy 215.844664 -29.646144)
			(xy 215.900037 -29.623208) (xy 215.95793 -29.607695) (xy 216.017352 -29.599872) (xy 216.077288 -29.599872)
			(xy 216.13671 -29.607695) (xy 216.194603 -29.623208) (xy 216.249976 -29.646144) (xy 216.301882 -29.676111)
			(xy 216.349432 -29.712598) (xy 216.391812 -29.754978) (xy 216.428299 -29.802528) (xy 216.458266 -29.854434)
			(xy 216.481202 -29.909807) (xy 216.496715 -29.9677) (xy 216.504538 -30.027122) (xy 216.505028 -30.05709)
			(xy 216.505028 -30.92069) (xy 216.504999 -30.922468) (xy 238.952532 -30.922468) (xy 238.952532 -30.058868)
			(xy 238.953022 -30.028884) (xy 238.96085 -29.969428) (xy 238.976371 -29.911503) (xy 238.99932 -29.856099)
			(xy 239.029304 -29.804165) (xy 239.06581 -29.756589) (xy 239.108215 -29.714184) (xy 239.155791 -29.677678)
			(xy 239.207725 -29.647694) (xy 239.263129 -29.624745) (xy 239.321054 -29.609224) (xy 239.38051 -29.601396)
			(xy 239.440478 -29.601396) (xy 239.499934 -29.609224) (xy 239.557859 -29.624745) (xy 239.613263 -29.647694)
			(xy 239.665197 -29.677678) (xy 239.712773 -29.714184) (xy 239.755178 -29.756589) (xy 239.791684 -29.804165)
			(xy 239.821668 -29.856099) (xy 239.844617 -29.911503) (xy 239.860138 -29.969428) (xy 239.867966 -30.028884)
			(xy 239.868456 -30.058868) (xy 239.868456 -30.92069) (xy 253.689612 -30.92069) (xy 253.689612 -30.05709)
			(xy 253.690102 -30.027122) (xy 253.697925 -29.9677) (xy 253.713438 -29.909807) (xy 253.736374 -29.854434)
			(xy 253.766341 -29.802528) (xy 253.802828 -29.754978) (xy 253.845208 -29.712598) (xy 253.892758 -29.676111)
			(xy 253.944664 -29.646144) (xy 254.000037 -29.623208) (xy 254.05793 -29.607695) (xy 254.117352 -29.599872)
			(xy 254.177288 -29.599872) (xy 254.23671 -29.607695) (xy 254.294603 -29.623208) (xy 254.349976 -29.646144)
			(xy 254.401882 -29.676111) (xy 254.449432 -29.712598) (xy 254.491812 -29.754978) (xy 254.528299 -29.802528)
			(xy 254.558266 -29.854434) (xy 254.581202 -29.909807) (xy 254.596715 -29.9677) (xy 254.604538 -30.027122)
			(xy 254.605028 -30.05709) (xy 254.605028 -30.92069) (xy 254.604999 -30.922468) (xy 264.95248 -30.922468)
			(xy 264.95248 -30.058868) (xy 264.95297 -30.028884) (xy 264.960798 -29.969428) (xy 264.976319 -29.911503)
			(xy 264.999268 -29.856099) (xy 265.029252 -29.804165) (xy 265.065758 -29.756589) (xy 265.108163 -29.714184)
			(xy 265.155739 -29.677678) (xy 265.207673 -29.647694) (xy 265.263077 -29.624745) (xy 265.321002 -29.609224)
			(xy 265.380458 -29.601396) (xy 265.440426 -29.601396) (xy 265.499882 -29.609224) (xy 265.557807 -29.624745)
			(xy 265.613211 -29.647694) (xy 265.665145 -29.677678) (xy 265.712721 -29.714184) (xy 265.755126 -29.756589)
			(xy 265.791632 -29.804165) (xy 265.821616 -29.856099) (xy 265.844565 -29.911503) (xy 265.860086 -29.969428)
			(xy 265.867914 -30.028884) (xy 265.868404 -30.058868) (xy 265.868404 -30.92069) (xy 279.68956 -30.92069)
			(xy 279.68956 -30.05709) (xy 279.69005 -30.027122) (xy 279.697873 -29.9677) (xy 279.713386 -29.909807)
			(xy 279.736322 -29.854434) (xy 279.766289 -29.802528) (xy 279.802776 -29.754978) (xy 279.845156 -29.712598)
			(xy 279.892706 -29.676111) (xy 279.944612 -29.646144) (xy 279.999985 -29.623208) (xy 280.057878 -29.607695)
			(xy 280.1173 -29.599872) (xy 280.177236 -29.599872) (xy 280.236658 -29.607695) (xy 280.294551 -29.623208)
			(xy 280.349924 -29.646144) (xy 280.40183 -29.676111) (xy 280.44938 -29.712598) (xy 280.49176 -29.754978)
			(xy 280.528247 -29.802528) (xy 280.558214 -29.854434) (xy 280.58115 -29.909807) (xy 280.596663 -29.9677)
			(xy 280.604486 -30.027122) (xy 280.604976 -30.05709) (xy 280.604976 -30.92069) (xy 280.604947 -30.922468)
			(xy 290.952428 -30.922468) (xy 290.952428 -30.058868) (xy 290.952918 -30.028884) (xy 290.960746 -29.969428)
			(xy 290.976267 -29.911503) (xy 290.999216 -29.856099) (xy 291.0292 -29.804165) (xy 291.065706 -29.756589)
			(xy 291.108111 -29.714184) (xy 291.155687 -29.677678) (xy 291.207621 -29.647694) (xy 291.263025 -29.624745)
			(xy 291.32095 -29.609224) (xy 291.380406 -29.601396) (xy 291.440374 -29.601396) (xy 291.49983 -29.609224)
			(xy 291.557755 -29.624745) (xy 291.613159 -29.647694) (xy 291.665093 -29.677678) (xy 291.712669 -29.714184)
			(xy 291.755074 -29.756589) (xy 291.79158 -29.804165) (xy 291.821564 -29.856099) (xy 291.844513 -29.911503)
			(xy 291.860034 -29.969428) (xy 291.867862 -30.028884) (xy 291.868352 -30.058868) (xy 291.868352 -30.92069)
			(xy 305.689508 -30.92069) (xy 305.689508 -30.05709) (xy 305.689998 -30.027122) (xy 305.697821 -29.9677)
			(xy 305.713334 -29.909807) (xy 305.73627 -29.854434) (xy 305.766237 -29.802528) (xy 305.802724 -29.754978)
			(xy 305.845104 -29.712598) (xy 305.892654 -29.676111) (xy 305.94456 -29.646144) (xy 305.999933 -29.623208)
			(xy 306.057826 -29.607695) (xy 306.117248 -29.599872) (xy 306.177184 -29.599872) (xy 306.236606 -29.607695)
			(xy 306.294499 -29.623208) (xy 306.349872 -29.646144) (xy 306.401778 -29.676111) (xy 306.449328 -29.712598)
			(xy 306.491708 -29.754978) (xy 306.528195 -29.802528) (xy 306.558162 -29.854434) (xy 306.581098 -29.909807)
			(xy 306.596611 -29.9677) (xy 306.604434 -30.027122) (xy 306.604924 -30.05709) (xy 306.604924 -30.92069)
			(xy 306.604895 -30.922468) (xy 316.952376 -30.922468) (xy 316.952376 -30.058868) (xy 316.952866 -30.028884)
			(xy 316.960694 -29.969428) (xy 316.976215 -29.911503) (xy 316.999164 -29.856099) (xy 317.029148 -29.804165)
			(xy 317.065654 -29.756589) (xy 317.108059 -29.714184) (xy 317.155635 -29.677678) (xy 317.207569 -29.647694)
			(xy 317.262973 -29.624745) (xy 317.320898 -29.609224) (xy 317.380354 -29.601396) (xy 317.440322 -29.601396)
			(xy 317.499778 -29.609224) (xy 317.557703 -29.624745) (xy 317.613107 -29.647694) (xy 317.665041 -29.677678)
			(xy 317.712617 -29.714184) (xy 317.755022 -29.756589) (xy 317.791528 -29.804165) (xy 317.821512 -29.856099)
			(xy 317.844461 -29.911503) (xy 317.859982 -29.969428) (xy 317.86781 -30.028884) (xy 317.8683 -30.058868)
			(xy 317.8683 -30.92069) (xy 331.689456 -30.92069) (xy 331.689456 -30.05709) (xy 331.689946 -30.027122)
			(xy 331.697769 -29.9677) (xy 331.713282 -29.909807) (xy 331.736218 -29.854434) (xy 331.766185 -29.802528)
			(xy 331.802672 -29.754978) (xy 331.845052 -29.712598) (xy 331.892602 -29.676111) (xy 331.944508 -29.646144)
			(xy 331.999881 -29.623208) (xy 332.057774 -29.607695) (xy 332.117196 -29.599872) (xy 332.177132 -29.599872)
			(xy 332.236554 -29.607695) (xy 332.294447 -29.623208) (xy 332.34982 -29.646144) (xy 332.401726 -29.676111)
			(xy 332.449276 -29.712598) (xy 332.491656 -29.754978) (xy 332.528143 -29.802528) (xy 332.55811 -29.854434)
			(xy 332.581046 -29.909807) (xy 332.596559 -29.9677) (xy 332.604382 -30.027122) (xy 332.604872 -30.05709)
			(xy 332.604872 -30.92069) (xy 332.604843 -30.922468) (xy 355.052884 -30.922468) (xy 355.052884 -30.058868)
			(xy 355.053374 -30.0289) (xy 355.061197 -29.969478) (xy 355.07671 -29.911585) (xy 355.099646 -29.856212)
			(xy 355.129613 -29.804306) (xy 355.1661 -29.756756) (xy 355.20848 -29.714376) (xy 355.25603 -29.677889)
			(xy 355.307936 -29.647922) (xy 355.363309 -29.624986) (xy 355.421202 -29.609473) (xy 355.480624 -29.60165)
			(xy 355.54056 -29.60165) (xy 355.599982 -29.609473) (xy 355.657875 -29.624986) (xy 355.713248 -29.647922)
			(xy 355.765154 -29.677889) (xy 355.812704 -29.714376) (xy 355.855084 -29.756756) (xy 355.891571 -29.804306)
			(xy 355.921538 -29.856212) (xy 355.944474 -29.911585) (xy 355.959987 -29.969478) (xy 355.96781 -30.0289)
			(xy 355.9683 -30.058868) (xy 355.9683 -30.92069) (xy 369.789456 -30.92069) (xy 369.789456 -30.05709)
			(xy 369.789946 -30.027106) (xy 369.797774 -29.96765) (xy 369.813295 -29.909725) (xy 369.836244 -29.854321)
			(xy 369.866228 -29.802387) (xy 369.902734 -29.754811) (xy 369.945139 -29.712406) (xy 369.992715 -29.6759)
			(xy 370.044649 -29.645916) (xy 370.100053 -29.622967) (xy 370.157978 -29.607446) (xy 370.217434 -29.599618)
			(xy 370.277402 -29.599618) (xy 370.336858 -29.607446) (xy 370.394783 -29.622967) (xy 370.450187 -29.645916)
			(xy 370.502121 -29.6759) (xy 370.549697 -29.712406) (xy 370.592102 -29.754811) (xy 370.628608 -29.802387)
			(xy 370.658592 -29.854321) (xy 370.681541 -29.909725) (xy 370.697062 -29.96765) (xy 370.70489 -30.027106)
			(xy 370.70538 -30.05709) (xy 370.70538 -30.92069) (xy 370.705351 -30.922468) (xy 381.052832 -30.922468)
			(xy 381.052832 -30.058868) (xy 381.053322 -30.0289) (xy 381.061145 -29.969478) (xy 381.076658 -29.911585)
			(xy 381.099594 -29.856212) (xy 381.129561 -29.804306) (xy 381.166048 -29.756756) (xy 381.208428 -29.714376)
			(xy 381.255978 -29.677889) (xy 381.307884 -29.647922) (xy 381.363257 -29.624986) (xy 381.42115 -29.609473)
			(xy 381.480572 -29.60165) (xy 381.540508 -29.60165) (xy 381.59993 -29.609473) (xy 381.657823 -29.624986)
			(xy 381.713196 -29.647922) (xy 381.765102 -29.677889) (xy 381.812652 -29.714376) (xy 381.855032 -29.756756)
			(xy 381.891519 -29.804306) (xy 381.921486 -29.856212) (xy 381.944422 -29.911585) (xy 381.959935 -29.969478)
			(xy 381.967758 -30.0289) (xy 381.968248 -30.058868) (xy 381.968248 -30.92069) (xy 395.789404 -30.92069)
			(xy 395.789404 -30.05709) (xy 395.789894 -30.027106) (xy 395.797722 -29.96765) (xy 395.813243 -29.909725)
			(xy 395.836192 -29.854321) (xy 395.866176 -29.802387) (xy 395.902682 -29.754811) (xy 395.945087 -29.712406)
			(xy 395.992663 -29.6759) (xy 396.044597 -29.645916) (xy 396.100001 -29.622967) (xy 396.157926 -29.607446)
			(xy 396.217382 -29.599618) (xy 396.27735 -29.599618) (xy 396.336806 -29.607446) (xy 396.394731 -29.622967)
			(xy 396.450135 -29.645916) (xy 396.502069 -29.6759) (xy 396.549645 -29.712406) (xy 396.59205 -29.754811)
			(xy 396.628556 -29.802387) (xy 396.65854 -29.854321) (xy 396.681489 -29.909725) (xy 396.69701 -29.96765)
			(xy 396.704838 -30.027106) (xy 396.705328 -30.05709) (xy 396.705328 -30.92069) (xy 396.705299 -30.922468)
			(xy 407.05278 -30.922468) (xy 407.05278 -30.058868) (xy 407.05327 -30.0289) (xy 407.061093 -29.969478)
			(xy 407.076606 -29.911585) (xy 407.099542 -29.856212) (xy 407.129509 -29.804306) (xy 407.165996 -29.756756)
			(xy 407.208376 -29.714376) (xy 407.255926 -29.677889) (xy 407.307832 -29.647922) (xy 407.363205 -29.624986)
			(xy 407.421098 -29.609473) (xy 407.48052 -29.60165) (xy 407.540456 -29.60165) (xy 407.599878 -29.609473)
			(xy 407.657771 -29.624986) (xy 407.713144 -29.647922) (xy 407.76505 -29.677889) (xy 407.8126 -29.714376)
			(xy 407.85498 -29.756756) (xy 407.891467 -29.804306) (xy 407.921434 -29.856212) (xy 407.94437 -29.911585)
			(xy 407.959883 -29.969478) (xy 407.967706 -30.0289) (xy 407.968196 -30.058868) (xy 407.968196 -30.92069)
			(xy 421.789352 -30.92069) (xy 421.789352 -30.05709) (xy 421.789842 -30.027106) (xy 421.79767 -29.96765)
			(xy 421.813191 -29.909725) (xy 421.83614 -29.854321) (xy 421.866124 -29.802387) (xy 421.90263 -29.754811)
			(xy 421.945035 -29.712406) (xy 421.992611 -29.6759) (xy 422.044545 -29.645916) (xy 422.099949 -29.622967)
			(xy 422.157874 -29.607446) (xy 422.21733 -29.599618) (xy 422.277298 -29.599618) (xy 422.336754 -29.607446)
			(xy 422.394679 -29.622967) (xy 422.450083 -29.645916) (xy 422.502017 -29.6759) (xy 422.549593 -29.712406)
			(xy 422.591998 -29.754811) (xy 422.628504 -29.802387) (xy 422.658488 -29.854321) (xy 422.681437 -29.909725)
			(xy 422.696958 -29.96765) (xy 422.704786 -30.027106) (xy 422.705276 -30.05709) (xy 422.705276 -30.92069)
			(xy 422.705247 -30.922468) (xy 433.052728 -30.922468) (xy 433.052728 -30.058868) (xy 433.053218 -30.0289)
			(xy 433.061041 -29.969478) (xy 433.076554 -29.911585) (xy 433.09949 -29.856212) (xy 433.129457 -29.804306)
			(xy 433.165944 -29.756756) (xy 433.208324 -29.714376) (xy 433.255874 -29.677889) (xy 433.30778 -29.647922)
			(xy 433.363153 -29.624986) (xy 433.421046 -29.609473) (xy 433.480468 -29.60165) (xy 433.540404 -29.60165)
			(xy 433.599826 -29.609473) (xy 433.657719 -29.624986) (xy 433.713092 -29.647922) (xy 433.764998 -29.677889)
			(xy 433.812548 -29.714376) (xy 433.854928 -29.756756) (xy 433.891415 -29.804306) (xy 433.921382 -29.856212)
			(xy 433.944318 -29.911585) (xy 433.959831 -29.969478) (xy 433.967654 -30.0289) (xy 433.968144 -30.058868)
			(xy 433.968144 -30.92069) (xy 447.7893 -30.92069) (xy 447.7893 -30.05709) (xy 447.78979 -30.027106)
			(xy 447.797618 -29.96765) (xy 447.813139 -29.909725) (xy 447.836088 -29.854321) (xy 447.866072 -29.802387)
			(xy 447.902578 -29.754811) (xy 447.944983 -29.712406) (xy 447.992559 -29.6759) (xy 448.044493 -29.645916)
			(xy 448.099897 -29.622967) (xy 448.157822 -29.607446) (xy 448.217278 -29.599618) (xy 448.277246 -29.599618)
			(xy 448.336702 -29.607446) (xy 448.394627 -29.622967) (xy 448.450031 -29.645916) (xy 448.501965 -29.6759)
			(xy 448.549541 -29.712406) (xy 448.591946 -29.754811) (xy 448.628452 -29.802387) (xy 448.658436 -29.854321)
			(xy 448.681385 -29.909725) (xy 448.696906 -29.96765) (xy 448.704734 -30.027106) (xy 448.705224 -30.05709)
			(xy 448.705224 -30.745738) (xy 457.614517 -30.745738) (xy 457.614517 -30.616598) (xy 457.622467 -30.487703)
			(xy 457.638337 -30.359543) (xy 457.662066 -30.232602) (xy 457.693565 -30.107363) (xy 457.732714 -29.9843)
			(xy 457.779365 -29.863881) (xy 457.83334 -29.746562) (xy 457.894435 -29.632788) (xy 457.962418 -29.522991)
			(xy 458.037032 -29.417588) (xy 458.117993 -29.316978) (xy 458.204993 -29.221543) (xy 458.297704 -29.131644)
			(xy 458.395774 -29.047623) (xy 458.498829 -28.969799) (xy 458.60648 -28.898467) (xy 458.718319 -28.833897)
			(xy 458.83392 -28.776335) (xy 458.952845 -28.725998) (xy 459.074644 -28.683078) (xy 459.198854 -28.647737)
			(xy 459.325003 -28.62011) (xy 459.452615 -28.600301) (xy 459.581204 -28.588385) (xy 459.710282 -28.584409)
			(xy 459.83936 -28.588385) (xy 459.967949 -28.600301) (xy 460.095561 -28.62011) (xy 460.22171 -28.647737)
			(xy 460.34592 -28.683078) (xy 460.467719 -28.725998) (xy 460.586644 -28.776335) (xy 460.702245 -28.833897)
			(xy 460.814084 -28.898467) (xy 460.921735 -28.969799) (xy 461.02479 -29.047623) (xy 461.12286 -29.131644)
			(xy 461.215571 -29.221543) (xy 461.302571 -29.316978) (xy 461.383532 -29.417588) (xy 461.458146 -29.522991)
			(xy 461.526129 -29.632788) (xy 461.587224 -29.746562) (xy 461.641199 -29.863881) (xy 461.68785 -29.9843)
			(xy 461.726999 -30.107363) (xy 461.758498 -30.232602) (xy 461.782227 -30.359543) (xy 461.798097 -30.487703)
			(xy 461.806047 -30.616598) (xy 461.806544 -30.681168) (xy 461.806047 -30.745738) (xy 461.798097 -30.874633)
			(xy 461.782227 -31.002793) (xy 461.758498 -31.129734) (xy 461.726999 -31.254973) (xy 461.68785 -31.378036)
			(xy 461.641199 -31.498455) (xy 461.587224 -31.615774) (xy 461.526129 -31.729548) (xy 461.458146 -31.839345)
			(xy 461.383532 -31.944748) (xy 461.302571 -32.045358) (xy 461.215571 -32.140793) (xy 461.12286 -32.230692)
			(xy 461.02479 -32.314713) (xy 460.921735 -32.392537) (xy 460.814084 -32.463869) (xy 460.702245 -32.528439)
			(xy 460.586644 -32.586001) (xy 460.467719 -32.636338) (xy 460.34592 -32.679258) (xy 460.22171 -32.714599)
			(xy 460.095561 -32.742226) (xy 459.967949 -32.762035) (xy 459.83936 -32.773951) (xy 459.710282 -32.777928)
			(xy 459.581204 -32.773951) (xy 459.452615 -32.762035) (xy 459.325003 -32.742226) (xy 459.198854 -32.714599)
			(xy 459.074644 -32.679258) (xy 458.952845 -32.636338) (xy 458.83392 -32.586001) (xy 458.718319 -32.528439)
			(xy 458.60648 -32.463869) (xy 458.498829 -32.392537) (xy 458.395774 -32.314713) (xy 458.297704 -32.230692)
			(xy 458.204993 -32.140793) (xy 458.117993 -32.045358) (xy 458.037032 -31.944748) (xy 457.962418 -31.839345)
			(xy 457.894435 -31.729548) (xy 457.83334 -31.615774) (xy 457.779365 -31.498455) (xy 457.732714 -31.378036)
			(xy 457.693565 -31.254973) (xy 457.662066 -31.129734) (xy 457.638337 -31.002793) (xy 457.622467 -30.874633)
			(xy 457.614517 -30.745738) (xy 448.705224 -30.745738) (xy 448.705224 -30.92069) (xy 448.704734 -30.950674)
			(xy 448.696906 -31.01013) (xy 448.681385 -31.068055) (xy 448.658436 -31.123459) (xy 448.628452 -31.175393)
			(xy 448.591946 -31.222969) (xy 448.549541 -31.265374) (xy 448.501965 -31.30188) (xy 448.450031 -31.331864)
			(xy 448.394627 -31.354813) (xy 448.336702 -31.370334) (xy 448.277246 -31.378162) (xy 448.217278 -31.378162)
			(xy 448.157822 -31.370334) (xy 448.099897 -31.354813) (xy 448.044493 -31.331864) (xy 447.992559 -31.30188)
			(xy 447.944983 -31.265374) (xy 447.902578 -31.222969) (xy 447.866072 -31.175393) (xy 447.836088 -31.123459)
			(xy 447.813139 -31.068055) (xy 447.797618 -31.01013) (xy 447.78979 -30.950674) (xy 447.7893 -30.92069)
			(xy 433.968144 -30.92069) (xy 433.968144 -30.922468) (xy 433.967654 -30.952436) (xy 433.959831 -31.011858)
			(xy 433.944318 -31.069751) (xy 433.921382 -31.125124) (xy 433.891415 -31.17703) (xy 433.854928 -31.22458)
			(xy 433.812548 -31.26696) (xy 433.764998 -31.303447) (xy 433.713092 -31.333414) (xy 433.657719 -31.35635)
			(xy 433.599826 -31.371863) (xy 433.540404 -31.379686) (xy 433.480468 -31.379686) (xy 433.421046 -31.371863)
			(xy 433.363153 -31.35635) (xy 433.30778 -31.333414) (xy 433.255874 -31.303447) (xy 433.208324 -31.26696)
			(xy 433.165944 -31.22458) (xy 433.129457 -31.17703) (xy 433.09949 -31.125124) (xy 433.076554 -31.069751)
			(xy 433.061041 -31.011858) (xy 433.053218 -30.952436) (xy 433.052728 -30.922468) (xy 422.705247 -30.922468)
			(xy 422.704786 -30.950674) (xy 422.696958 -31.01013) (xy 422.681437 -31.068055) (xy 422.658488 -31.123459)
			(xy 422.628504 -31.175393) (xy 422.591998 -31.222969) (xy 422.549593 -31.265374) (xy 422.502017 -31.30188)
			(xy 422.450083 -31.331864) (xy 422.394679 -31.354813) (xy 422.336754 -31.370334) (xy 422.277298 -31.378162)
			(xy 422.21733 -31.378162) (xy 422.157874 -31.370334) (xy 422.099949 -31.354813) (xy 422.044545 -31.331864)
			(xy 421.992611 -31.30188) (xy 421.945035 -31.265374) (xy 421.90263 -31.222969) (xy 421.866124 -31.175393)
			(xy 421.83614 -31.123459) (xy 421.813191 -31.068055) (xy 421.79767 -31.01013) (xy 421.789842 -30.950674)
			(xy 421.789352 -30.92069) (xy 407.968196 -30.92069) (xy 407.968196 -30.922468) (xy 407.967706 -30.952436)
			(xy 407.959883 -31.011858) (xy 407.94437 -31.069751) (xy 407.921434 -31.125124) (xy 407.891467 -31.17703)
			(xy 407.85498 -31.22458) (xy 407.8126 -31.26696) (xy 407.76505 -31.303447) (xy 407.713144 -31.333414)
			(xy 407.657771 -31.35635) (xy 407.599878 -31.371863) (xy 407.540456 -31.379686) (xy 407.48052 -31.379686)
			(xy 407.421098 -31.371863) (xy 407.363205 -31.35635) (xy 407.307832 -31.333414) (xy 407.255926 -31.303447)
			(xy 407.208376 -31.26696) (xy 407.165996 -31.22458) (xy 407.129509 -31.17703) (xy 407.099542 -31.125124)
			(xy 407.076606 -31.069751) (xy 407.061093 -31.011858) (xy 407.05327 -30.952436) (xy 407.05278 -30.922468)
			(xy 396.705299 -30.922468) (xy 396.704838 -30.950674) (xy 396.69701 -31.01013) (xy 396.681489 -31.068055)
			(xy 396.65854 -31.123459) (xy 396.628556 -31.175393) (xy 396.59205 -31.222969) (xy 396.549645 -31.265374)
			(xy 396.502069 -31.30188) (xy 396.450135 -31.331864) (xy 396.394731 -31.354813) (xy 396.336806 -31.370334)
			(xy 396.27735 -31.378162) (xy 396.217382 -31.378162) (xy 396.157926 -31.370334) (xy 396.100001 -31.354813)
			(xy 396.044597 -31.331864) (xy 395.992663 -31.30188) (xy 395.945087 -31.265374) (xy 395.902682 -31.222969)
			(xy 395.866176 -31.175393) (xy 395.836192 -31.123459) (xy 395.813243 -31.068055) (xy 395.797722 -31.01013)
			(xy 395.789894 -30.950674) (xy 395.789404 -30.92069) (xy 381.968248 -30.92069) (xy 381.968248 -30.922468)
			(xy 381.967758 -30.952436) (xy 381.959935 -31.011858) (xy 381.944422 -31.069751) (xy 381.921486 -31.125124)
			(xy 381.891519 -31.17703) (xy 381.855032 -31.22458) (xy 381.812652 -31.26696) (xy 381.765102 -31.303447)
			(xy 381.713196 -31.333414) (xy 381.657823 -31.35635) (xy 381.59993 -31.371863) (xy 381.540508 -31.379686)
			(xy 381.480572 -31.379686) (xy 381.42115 -31.371863) (xy 381.363257 -31.35635) (xy 381.307884 -31.333414)
			(xy 381.255978 -31.303447) (xy 381.208428 -31.26696) (xy 381.166048 -31.22458) (xy 381.129561 -31.17703)
			(xy 381.099594 -31.125124) (xy 381.076658 -31.069751) (xy 381.061145 -31.011858) (xy 381.053322 -30.952436)
			(xy 381.052832 -30.922468) (xy 370.705351 -30.922468) (xy 370.70489 -30.950674) (xy 370.697062 -31.01013)
			(xy 370.681541 -31.068055) (xy 370.658592 -31.123459) (xy 370.628608 -31.175393) (xy 370.592102 -31.222969)
			(xy 370.549697 -31.265374) (xy 370.502121 -31.30188) (xy 370.450187 -31.331864) (xy 370.394783 -31.354813)
			(xy 370.336858 -31.370334) (xy 370.277402 -31.378162) (xy 370.217434 -31.378162) (xy 370.157978 -31.370334)
			(xy 370.100053 -31.354813) (xy 370.044649 -31.331864) (xy 369.992715 -31.30188) (xy 369.945139 -31.265374)
			(xy 369.902734 -31.222969) (xy 369.866228 -31.175393) (xy 369.836244 -31.123459) (xy 369.813295 -31.068055)
			(xy 369.797774 -31.01013) (xy 369.789946 -30.950674) (xy 369.789456 -30.92069) (xy 355.9683 -30.92069)
			(xy 355.9683 -30.922468) (xy 355.96781 -30.952436) (xy 355.959987 -31.011858) (xy 355.944474 -31.069751)
			(xy 355.921538 -31.125124) (xy 355.891571 -31.17703) (xy 355.855084 -31.22458) (xy 355.812704 -31.26696)
			(xy 355.765154 -31.303447) (xy 355.713248 -31.333414) (xy 355.657875 -31.35635) (xy 355.599982 -31.371863)
			(xy 355.54056 -31.379686) (xy 355.480624 -31.379686) (xy 355.421202 -31.371863) (xy 355.363309 -31.35635)
			(xy 355.307936 -31.333414) (xy 355.25603 -31.303447) (xy 355.20848 -31.26696) (xy 355.1661 -31.22458)
			(xy 355.129613 -31.17703) (xy 355.099646 -31.125124) (xy 355.07671 -31.069751) (xy 355.061197 -31.011858)
			(xy 355.053374 -30.952436) (xy 355.052884 -30.922468) (xy 332.604843 -30.922468) (xy 332.604382 -30.950658)
			(xy 332.596559 -31.01008) (xy 332.581046 -31.067973) (xy 332.55811 -31.123346) (xy 332.528143 -31.175252)
			(xy 332.491656 -31.222802) (xy 332.449276 -31.265182) (xy 332.401726 -31.301669) (xy 332.34982 -31.331636)
			(xy 332.294447 -31.354572) (xy 332.236554 -31.370085) (xy 332.177132 -31.377908) (xy 332.117196 -31.377908)
			(xy 332.057774 -31.370085) (xy 331.999881 -31.354572) (xy 331.944508 -31.331636) (xy 331.892602 -31.301669)
			(xy 331.845052 -31.265182) (xy 331.802672 -31.222802) (xy 331.766185 -31.175252) (xy 331.736218 -31.123346)
			(xy 331.713282 -31.067973) (xy 331.697769 -31.01008) (xy 331.689946 -30.950658) (xy 331.689456 -30.92069)
			(xy 317.8683 -30.92069) (xy 317.8683 -30.922468) (xy 317.86781 -30.952452) (xy 317.859982 -31.011908)
			(xy 317.844461 -31.069833) (xy 317.821512 -31.125237) (xy 317.791528 -31.177171) (xy 317.755022 -31.224747)
			(xy 317.712617 -31.267152) (xy 317.665041 -31.303658) (xy 317.613107 -31.333642) (xy 317.557703 -31.356591)
			(xy 317.499778 -31.372112) (xy 317.440322 -31.37994) (xy 317.380354 -31.37994) (xy 317.320898 -31.372112)
			(xy 317.262973 -31.356591) (xy 317.207569 -31.333642) (xy 317.155635 -31.303658) (xy 317.108059 -31.267152)
			(xy 317.065654 -31.224747) (xy 317.029148 -31.177171) (xy 316.999164 -31.125237) (xy 316.976215 -31.069833)
			(xy 316.960694 -31.011908) (xy 316.952866 -30.952452) (xy 316.952376 -30.922468) (xy 306.604895 -30.922468)
			(xy 306.604434 -30.950658) (xy 306.596611 -31.01008) (xy 306.581098 -31.067973) (xy 306.558162 -31.123346)
			(xy 306.528195 -31.175252) (xy 306.491708 -31.222802) (xy 306.449328 -31.265182) (xy 306.401778 -31.301669)
			(xy 306.349872 -31.331636) (xy 306.294499 -31.354572) (xy 306.236606 -31.370085) (xy 306.177184 -31.377908)
			(xy 306.117248 -31.377908) (xy 306.057826 -31.370085) (xy 305.999933 -31.354572) (xy 305.94456 -31.331636)
			(xy 305.892654 -31.301669) (xy 305.845104 -31.265182) (xy 305.802724 -31.222802) (xy 305.766237 -31.175252)
			(xy 305.73627 -31.123346) (xy 305.713334 -31.067973) (xy 305.697821 -31.01008) (xy 305.689998 -30.950658)
			(xy 305.689508 -30.92069) (xy 291.868352 -30.92069) (xy 291.868352 -30.922468) (xy 291.867862 -30.952452)
			(xy 291.860034 -31.011908) (xy 291.844513 -31.069833) (xy 291.821564 -31.125237) (xy 291.79158 -31.177171)
			(xy 291.755074 -31.224747) (xy 291.712669 -31.267152) (xy 291.665093 -31.303658) (xy 291.613159 -31.333642)
			(xy 291.557755 -31.356591) (xy 291.49983 -31.372112) (xy 291.440374 -31.37994) (xy 291.380406 -31.37994)
			(xy 291.32095 -31.372112) (xy 291.263025 -31.356591) (xy 291.207621 -31.333642) (xy 291.155687 -31.303658)
			(xy 291.108111 -31.267152) (xy 291.065706 -31.224747) (xy 291.0292 -31.177171) (xy 290.999216 -31.125237)
			(xy 290.976267 -31.069833) (xy 290.960746 -31.011908) (xy 290.952918 -30.952452) (xy 290.952428 -30.922468)
			(xy 280.604947 -30.922468) (xy 280.604486 -30.950658) (xy 280.596663 -31.01008) (xy 280.58115 -31.067973)
			(xy 280.558214 -31.123346) (xy 280.528247 -31.175252) (xy 280.49176 -31.222802) (xy 280.44938 -31.265182)
			(xy 280.40183 -31.301669) (xy 280.349924 -31.331636) (xy 280.294551 -31.354572) (xy 280.236658 -31.370085)
			(xy 280.177236 -31.377908) (xy 280.1173 -31.377908) (xy 280.057878 -31.370085) (xy 279.999985 -31.354572)
			(xy 279.944612 -31.331636) (xy 279.892706 -31.301669) (xy 279.845156 -31.265182) (xy 279.802776 -31.222802)
			(xy 279.766289 -31.175252) (xy 279.736322 -31.123346) (xy 279.713386 -31.067973) (xy 279.697873 -31.01008)
			(xy 279.69005 -30.950658) (xy 279.68956 -30.92069) (xy 265.868404 -30.92069) (xy 265.868404 -30.922468)
			(xy 265.867914 -30.952452) (xy 265.860086 -31.011908) (xy 265.844565 -31.069833) (xy 265.821616 -31.125237)
			(xy 265.791632 -31.177171) (xy 265.755126 -31.224747) (xy 265.712721 -31.267152) (xy 265.665145 -31.303658)
			(xy 265.613211 -31.333642) (xy 265.557807 -31.356591) (xy 265.499882 -31.372112) (xy 265.440426 -31.37994)
			(xy 265.380458 -31.37994) (xy 265.321002 -31.372112) (xy 265.263077 -31.356591) (xy 265.207673 -31.333642)
			(xy 265.155739 -31.303658) (xy 265.108163 -31.267152) (xy 265.065758 -31.224747) (xy 265.029252 -31.177171)
			(xy 264.999268 -31.125237) (xy 264.976319 -31.069833) (xy 264.960798 -31.011908) (xy 264.95297 -30.952452)
			(xy 264.95248 -30.922468) (xy 254.604999 -30.922468) (xy 254.604538 -30.950658) (xy 254.596715 -31.01008)
			(xy 254.581202 -31.067973) (xy 254.558266 -31.123346) (xy 254.528299 -31.175252) (xy 254.491812 -31.222802)
			(xy 254.449432 -31.265182) (xy 254.401882 -31.301669) (xy 254.349976 -31.331636) (xy 254.294603 -31.354572)
			(xy 254.23671 -31.370085) (xy 254.177288 -31.377908) (xy 254.117352 -31.377908) (xy 254.05793 -31.370085)
			(xy 254.000037 -31.354572) (xy 253.944664 -31.331636) (xy 253.892758 -31.301669) (xy 253.845208 -31.265182)
			(xy 253.802828 -31.222802) (xy 253.766341 -31.175252) (xy 253.736374 -31.123346) (xy 253.713438 -31.067973)
			(xy 253.697925 -31.01008) (xy 253.690102 -30.950658) (xy 253.689612 -30.92069) (xy 239.868456 -30.92069)
			(xy 239.868456 -30.922468) (xy 239.867966 -30.952452) (xy 239.860138 -31.011908) (xy 239.844617 -31.069833)
			(xy 239.821668 -31.125237) (xy 239.791684 -31.177171) (xy 239.755178 -31.224747) (xy 239.712773 -31.267152)
			(xy 239.665197 -31.303658) (xy 239.613263 -31.333642) (xy 239.557859 -31.356591) (xy 239.499934 -31.372112)
			(xy 239.440478 -31.37994) (xy 239.38051 -31.37994) (xy 239.321054 -31.372112) (xy 239.263129 -31.356591)
			(xy 239.207725 -31.333642) (xy 239.155791 -31.303658) (xy 239.108215 -31.267152) (xy 239.06581 -31.224747)
			(xy 239.029304 -31.177171) (xy 238.99932 -31.125237) (xy 238.976371 -31.069833) (xy 238.96085 -31.011908)
			(xy 238.953022 -30.952452) (xy 238.952532 -30.922468) (xy 216.504999 -30.922468) (xy 216.504538 -30.950658)
			(xy 216.496715 -31.01008) (xy 216.481202 -31.067973) (xy 216.458266 -31.123346) (xy 216.428299 -31.175252)
			(xy 216.391812 -31.222802) (xy 216.349432 -31.265182) (xy 216.301882 -31.301669) (xy 216.249976 -31.331636)
			(xy 216.194603 -31.354572) (xy 216.13671 -31.370085) (xy 216.077288 -31.377908) (xy 216.017352 -31.377908)
			(xy 215.95793 -31.370085) (xy 215.900037 -31.354572) (xy 215.844664 -31.331636) (xy 215.792758 -31.301669)
			(xy 215.745208 -31.265182) (xy 215.702828 -31.222802) (xy 215.666341 -31.175252) (xy 215.636374 -31.123346)
			(xy 215.613438 -31.067973) (xy 215.597925 -31.01008) (xy 215.590102 -30.950658) (xy 215.589612 -30.92069)
			(xy 201.768456 -30.92069) (xy 201.768456 -30.922468) (xy 201.767966 -30.952452) (xy 201.760138 -31.011908)
			(xy 201.744617 -31.069833) (xy 201.721668 -31.125237) (xy 201.691684 -31.177171) (xy 201.655178 -31.224747)
			(xy 201.612773 -31.267152) (xy 201.565197 -31.303658) (xy 201.513263 -31.333642) (xy 201.457859 -31.356591)
			(xy 201.399934 -31.372112) (xy 201.340478 -31.37994) (xy 201.28051 -31.37994) (xy 201.221054 -31.372112)
			(xy 201.163129 -31.356591) (xy 201.107725 -31.333642) (xy 201.055791 -31.303658) (xy 201.008215 -31.267152)
			(xy 200.96581 -31.224747) (xy 200.929304 -31.177171) (xy 200.89932 -31.125237) (xy 200.876371 -31.069833)
			(xy 200.86085 -31.011908) (xy 200.853022 -30.952452) (xy 200.852532 -30.922468) (xy 190.505051 -30.922468)
			(xy 190.50459 -30.950658) (xy 190.496767 -31.01008) (xy 190.481254 -31.067973) (xy 190.458318 -31.123346)
			(xy 190.428351 -31.175252) (xy 190.391864 -31.222802) (xy 190.349484 -31.265182) (xy 190.301934 -31.301669)
			(xy 190.250028 -31.331636) (xy 190.194655 -31.354572) (xy 190.136762 -31.370085) (xy 190.07734 -31.377908)
			(xy 190.017404 -31.377908) (xy 189.957982 -31.370085) (xy 189.900089 -31.354572) (xy 189.844716 -31.331636)
			(xy 189.79281 -31.301669) (xy 189.74526 -31.265182) (xy 189.70288 -31.222802) (xy 189.666393 -31.175252)
			(xy 189.636426 -31.123346) (xy 189.61349 -31.067973) (xy 189.597977 -31.01008) (xy 189.590154 -30.950658)
			(xy 189.589664 -30.92069) (xy 175.768508 -30.92069) (xy 175.768508 -30.922468) (xy 175.768018 -30.952452)
			(xy 175.76019 -31.011908) (xy 175.744669 -31.069833) (xy 175.72172 -31.125237) (xy 175.691736 -31.177171)
			(xy 175.65523 -31.224747) (xy 175.612825 -31.267152) (xy 175.565249 -31.303658) (xy 175.513315 -31.333642)
			(xy 175.457911 -31.356591) (xy 175.399986 -31.372112) (xy 175.34053 -31.37994) (xy 175.280562 -31.37994)
			(xy 175.221106 -31.372112) (xy 175.163181 -31.356591) (xy 175.107777 -31.333642) (xy 175.055843 -31.303658)
			(xy 175.008267 -31.267152) (xy 174.965862 -31.224747) (xy 174.929356 -31.177171) (xy 174.899372 -31.125237)
			(xy 174.876423 -31.069833) (xy 174.860902 -31.011908) (xy 174.853074 -30.952452) (xy 174.852584 -30.922468)
			(xy 164.505103 -30.922468) (xy 164.504642 -30.950658) (xy 164.496819 -31.01008) (xy 164.481306 -31.067973)
			(xy 164.45837 -31.123346) (xy 164.428403 -31.175252) (xy 164.391916 -31.222802) (xy 164.349536 -31.265182)
			(xy 164.301986 -31.301669) (xy 164.25008 -31.331636) (xy 164.194707 -31.354572) (xy 164.136814 -31.370085)
			(xy 164.077392 -31.377908) (xy 164.017456 -31.377908) (xy 163.958034 -31.370085) (xy 163.900141 -31.354572)
			(xy 163.844768 -31.331636) (xy 163.792862 -31.301669) (xy 163.745312 -31.265182) (xy 163.702932 -31.222802)
			(xy 163.666445 -31.175252) (xy 163.636478 -31.123346) (xy 163.613542 -31.067973) (xy 163.598029 -31.01008)
			(xy 163.590206 -30.950658) (xy 163.589716 -30.92069) (xy 149.76856 -30.92069) (xy 149.76856 -30.922468)
			(xy 149.76807 -30.952452) (xy 149.760242 -31.011908) (xy 149.744721 -31.069833) (xy 149.721772 -31.125237)
			(xy 149.691788 -31.177171) (xy 149.655282 -31.224747) (xy 149.612877 -31.267152) (xy 149.565301 -31.303658)
			(xy 149.513367 -31.333642) (xy 149.457963 -31.356591) (xy 149.400038 -31.372112) (xy 149.340582 -31.37994)
			(xy 149.280614 -31.37994) (xy 149.221158 -31.372112) (xy 149.163233 -31.356591) (xy 149.107829 -31.333642)
			(xy 149.055895 -31.303658) (xy 149.008319 -31.267152) (xy 148.965914 -31.224747) (xy 148.929408 -31.177171)
			(xy 148.899424 -31.125237) (xy 148.876475 -31.069833) (xy 148.860954 -31.011908) (xy 148.853126 -30.952452)
			(xy 148.852636 -30.922468) (xy 138.505155 -30.922468) (xy 138.504694 -30.950658) (xy 138.496871 -31.01008)
			(xy 138.481358 -31.067973) (xy 138.458422 -31.123346) (xy 138.428455 -31.175252) (xy 138.391968 -31.222802)
			(xy 138.349588 -31.265182) (xy 138.302038 -31.301669) (xy 138.250132 -31.331636) (xy 138.194759 -31.354572)
			(xy 138.136866 -31.370085) (xy 138.077444 -31.377908) (xy 138.017508 -31.377908) (xy 137.958086 -31.370085)
			(xy 137.900193 -31.354572) (xy 137.84482 -31.331636) (xy 137.792914 -31.301669) (xy 137.745364 -31.265182)
			(xy 137.702984 -31.222802) (xy 137.666497 -31.175252) (xy 137.63653 -31.123346) (xy 137.613594 -31.067973)
			(xy 137.598081 -31.01008) (xy 137.590258 -30.950658) (xy 137.589768 -30.92069) (xy 123.768612 -30.92069)
			(xy 123.768612 -30.922468) (xy 123.768122 -30.952452) (xy 123.760294 -31.011908) (xy 123.744773 -31.069833)
			(xy 123.721824 -31.125237) (xy 123.69184 -31.177171) (xy 123.655334 -31.224747) (xy 123.612929 -31.267152)
			(xy 123.565353 -31.303658) (xy 123.513419 -31.333642) (xy 123.458015 -31.356591) (xy 123.40009 -31.372112)
			(xy 123.340634 -31.37994) (xy 123.280666 -31.37994) (xy 123.22121 -31.372112) (xy 123.163285 -31.356591)
			(xy 123.107881 -31.333642) (xy 123.055947 -31.303658) (xy 123.008371 -31.267152) (xy 122.965966 -31.224747)
			(xy 122.92946 -31.177171) (xy 122.899476 -31.125237) (xy 122.876527 -31.069833) (xy 122.861006 -31.011908)
			(xy 122.853178 -30.952452) (xy 122.852688 -30.922468) (xy 100.405155 -30.922468) (xy 100.404694 -30.950674)
			(xy 100.396866 -31.01013) (xy 100.381345 -31.068055) (xy 100.358396 -31.123459) (xy 100.328412 -31.175393)
			(xy 100.291906 -31.222969) (xy 100.249501 -31.265374) (xy 100.201925 -31.30188) (xy 100.149991 -31.331864)
			(xy 100.094587 -31.354813) (xy 100.036662 -31.370334) (xy 99.977206 -31.378162) (xy 99.917238 -31.378162)
			(xy 99.857782 -31.370334) (xy 99.799857 -31.354813) (xy 99.744453 -31.331864) (xy 99.692519 -31.30188)
			(xy 99.644943 -31.265374) (xy 99.602538 -31.222969) (xy 99.566032 -31.175393) (xy 99.536048 -31.123459)
			(xy 99.513099 -31.068055) (xy 99.497578 -31.01013) (xy 99.48975 -30.950674) (xy 99.48926 -30.92069)
			(xy 85.668104 -30.92069) (xy 85.668104 -30.922468) (xy 85.667614 -30.952436) (xy 85.659791 -31.011858)
			(xy 85.644278 -31.069751) (xy 85.621342 -31.125124) (xy 85.591375 -31.17703) (xy 85.554888 -31.22458)
			(xy 85.512508 -31.26696) (xy 85.464958 -31.303447) (xy 85.413052 -31.333414) (xy 85.357679 -31.35635)
			(xy 85.299786 -31.371863) (xy 85.240364 -31.379686) (xy 85.180428 -31.379686) (xy 85.121006 -31.371863)
			(xy 85.063113 -31.35635) (xy 85.00774 -31.333414) (xy 84.955834 -31.303447) (xy 84.908284 -31.26696)
			(xy 84.865904 -31.22458) (xy 84.829417 -31.17703) (xy 84.79945 -31.125124) (xy 84.776514 -31.069751)
			(xy 84.761001 -31.011858) (xy 84.753178 -30.952436) (xy 84.752688 -30.922468) (xy 74.405207 -30.922468)
			(xy 74.404746 -30.950674) (xy 74.396918 -31.01013) (xy 74.381397 -31.068055) (xy 74.358448 -31.123459)
			(xy 74.328464 -31.175393) (xy 74.291958 -31.222969) (xy 74.249553 -31.265374) (xy 74.201977 -31.30188)
			(xy 74.150043 -31.331864) (xy 74.094639 -31.354813) (xy 74.036714 -31.370334) (xy 73.977258 -31.378162)
			(xy 73.91729 -31.378162) (xy 73.857834 -31.370334) (xy 73.799909 -31.354813) (xy 73.744505 -31.331864)
			(xy 73.692571 -31.30188) (xy 73.644995 -31.265374) (xy 73.60259 -31.222969) (xy 73.566084 -31.175393)
			(xy 73.5361 -31.123459) (xy 73.513151 -31.068055) (xy 73.49763 -31.01013) (xy 73.489802 -30.950674)
			(xy 73.489312 -30.92069) (xy 59.668156 -30.92069) (xy 59.668156 -30.922468) (xy 59.667666 -30.952436)
			(xy 59.659843 -31.011858) (xy 59.64433 -31.069751) (xy 59.621394 -31.125124) (xy 59.591427 -31.17703)
			(xy 59.55494 -31.22458) (xy 59.51256 -31.26696) (xy 59.46501 -31.303447) (xy 59.413104 -31.333414)
			(xy 59.357731 -31.35635) (xy 59.299838 -31.371863) (xy 59.240416 -31.379686) (xy 59.18048 -31.379686)
			(xy 59.121058 -31.371863) (xy 59.063165 -31.35635) (xy 59.007792 -31.333414) (xy 58.955886 -31.303447)
			(xy 58.908336 -31.26696) (xy 58.865956 -31.22458) (xy 58.829469 -31.17703) (xy 58.799502 -31.125124)
			(xy 58.776566 -31.069751) (xy 58.761053 -31.011858) (xy 58.75323 -30.952436) (xy 58.75274 -30.922468)
			(xy 48.405259 -30.922468) (xy 48.404798 -30.950674) (xy 48.39697 -31.01013) (xy 48.381449 -31.068055)
			(xy 48.3585 -31.123459) (xy 48.328516 -31.175393) (xy 48.29201 -31.222969) (xy 48.249605 -31.265374)
			(xy 48.202029 -31.30188) (xy 48.150095 -31.331864) (xy 48.094691 -31.354813) (xy 48.036766 -31.370334)
			(xy 47.97731 -31.378162) (xy 47.917342 -31.378162) (xy 47.857886 -31.370334) (xy 47.799961 -31.354813)
			(xy 47.744557 -31.331864) (xy 47.692623 -31.30188) (xy 47.645047 -31.265374) (xy 47.602642 -31.222969)
			(xy 47.566136 -31.175393) (xy 47.536152 -31.123459) (xy 47.513203 -31.068055) (xy 47.497682 -31.01013)
			(xy 47.489854 -30.950674) (xy 47.489364 -30.92069) (xy 33.668208 -30.92069) (xy 33.668208 -30.922468)
			(xy 33.667718 -30.952436) (xy 33.659895 -31.011858) (xy 33.644382 -31.069751) (xy 33.621446 -31.125124)
			(xy 33.591479 -31.17703) (xy 33.554992 -31.22458) (xy 33.512612 -31.26696) (xy 33.465062 -31.303447)
			(xy 33.413156 -31.333414) (xy 33.357783 -31.35635) (xy 33.29989 -31.371863) (xy 33.240468 -31.379686)
			(xy 33.180532 -31.379686) (xy 33.12111 -31.371863) (xy 33.063217 -31.35635) (xy 33.007844 -31.333414)
			(xy 32.955938 -31.303447) (xy 32.908388 -31.26696) (xy 32.866008 -31.22458) (xy 32.829521 -31.17703)
			(xy 32.799554 -31.125124) (xy 32.776618 -31.069751) (xy 32.761105 -31.011858) (xy 32.753282 -30.952436)
			(xy 32.752792 -30.922468) (xy 22.405311 -30.922468) (xy 22.40485 -30.950674) (xy 22.397022 -31.01013)
			(xy 22.381501 -31.068055) (xy 22.358552 -31.123459) (xy 22.328568 -31.175393) (xy 22.292062 -31.222969)
			(xy 22.249657 -31.265374) (xy 22.202081 -31.30188) (xy 22.150147 -31.331864) (xy 22.094743 -31.354813)
			(xy 22.036818 -31.370334) (xy 21.977362 -31.378162) (xy 21.917394 -31.378162) (xy 21.857938 -31.370334)
			(xy 21.800013 -31.354813) (xy 21.744609 -31.331864) (xy 21.692675 -31.30188) (xy 21.645099 -31.265374)
			(xy 21.602694 -31.222969) (xy 21.566188 -31.175393) (xy 21.536204 -31.123459) (xy 21.513255 -31.068055)
			(xy 21.497734 -31.01013) (xy 21.489906 -30.950674) (xy 21.489416 -30.92069) (xy 7.66826 -30.92069)
			(xy 7.66826 -30.922468) (xy 7.66777 -30.952436) (xy 7.659947 -31.011858) (xy 7.644434 -31.069751)
			(xy 7.621498 -31.125124) (xy 7.591531 -31.17703) (xy 7.555044 -31.22458) (xy 7.512664 -31.26696)
			(xy 7.465114 -31.303447) (xy 7.413208 -31.333414) (xy 7.357835 -31.35635) (xy 7.299942 -31.371863)
			(xy 7.24052 -31.379686) (xy 7.180584 -31.379686) (xy 7.121162 -31.371863) (xy 7.063269 -31.35635)
			(xy 7.007896 -31.333414) (xy 6.95599 -31.303447) (xy 6.90844 -31.26696) (xy 6.86606 -31.22458) (xy 6.829573 -31.17703)
			(xy 6.799606 -31.125124) (xy 6.77667 -31.069751) (xy 6.761157 -31.011858) (xy 6.753334 -30.952436)
			(xy 6.752844 -30.922468) (xy 0.509016 -30.922468) (xy 0.509016 -32.722312) (xy 8.607044 -32.722312)
			(xy 8.607044 -31.858712) (xy 8.607534 -31.828744) (xy 8.615357 -31.769322) (xy 8.63087 -31.711429)
			(xy 8.653806 -31.656056) (xy 8.683773 -31.60415) (xy 8.72026 -31.5566) (xy 8.76264 -31.51422) (xy 8.81019 -31.477733)
			(xy 8.862096 -31.447766) (xy 8.917469 -31.42483) (xy 8.975362 -31.409317) (xy 9.034784 -31.401494)
			(xy 9.09472 -31.401494) (xy 9.154142 -31.409317) (xy 9.212035 -31.42483) (xy 9.267408 -31.447766)
			(xy 9.319314 -31.477733) (xy 9.366864 -31.51422) (xy 9.409244 -31.5566) (xy 9.445731 -31.60415) (xy 9.475698 -31.656056)
			(xy 9.498634 -31.711429) (xy 9.514147 -31.769322) (xy 9.52197 -31.828744) (xy 9.52246 -31.858712)
			(xy 9.52246 -32.714184) (xy 18.847308 -32.714184) (xy 18.847308 -31.850584) (xy 18.847798 -31.8206)
			(xy 18.855626 -31.761144) (xy 18.871147 -31.703219) (xy 18.894096 -31.647815) (xy 18.92408 -31.595881)
			(xy 18.960586 -31.548305) (xy 19.002991 -31.5059) (xy 19.050567 -31.469394) (xy 19.102501 -31.43941)
			(xy 19.157905 -31.416461) (xy 19.21583 -31.40094) (xy 19.275286 -31.393112) (xy 19.335254 -31.393112)
			(xy 19.39471 -31.40094) (xy 19.452635 -31.416461) (xy 19.508039 -31.43941) (xy 19.559973 -31.469394)
			(xy 19.607549 -31.5059) (xy 19.649954 -31.548305) (xy 19.68646 -31.595881) (xy 19.716444 -31.647815)
			(xy 19.739393 -31.703219) (xy 19.754914 -31.761144) (xy 19.762742 -31.8206) (xy 19.763232 -31.850584)
			(xy 19.763232 -32.714184) (xy 19.763099 -32.722312) (xy 34.606992 -32.722312) (xy 34.606992 -31.858712)
			(xy 34.607482 -31.828744) (xy 34.615305 -31.769322) (xy 34.630818 -31.711429) (xy 34.653754 -31.656056)
			(xy 34.683721 -31.60415) (xy 34.720208 -31.5566) (xy 34.762588 -31.51422) (xy 34.810138 -31.477733)
			(xy 34.862044 -31.447766) (xy 34.917417 -31.42483) (xy 34.97531 -31.409317) (xy 35.034732 -31.401494)
			(xy 35.094668 -31.401494) (xy 35.15409 -31.409317) (xy 35.211983 -31.42483) (xy 35.267356 -31.447766)
			(xy 35.319262 -31.477733) (xy 35.366812 -31.51422) (xy 35.409192 -31.5566) (xy 35.445679 -31.60415)
			(xy 35.475646 -31.656056) (xy 35.498582 -31.711429) (xy 35.514095 -31.769322) (xy 35.521918 -31.828744)
			(xy 35.522408 -31.858712) (xy 35.522408 -32.714184) (xy 44.847256 -32.714184) (xy 44.847256 -31.850584)
			(xy 44.847746 -31.8206) (xy 44.855574 -31.761144) (xy 44.871095 -31.703219) (xy 44.894044 -31.647815)
			(xy 44.924028 -31.595881) (xy 44.960534 -31.548305) (xy 45.002939 -31.5059) (xy 45.050515 -31.469394)
			(xy 45.102449 -31.43941) (xy 45.157853 -31.416461) (xy 45.215778 -31.40094) (xy 45.275234 -31.393112)
			(xy 45.335202 -31.393112) (xy 45.394658 -31.40094) (xy 45.452583 -31.416461) (xy 45.507987 -31.43941)
			(xy 45.559921 -31.469394) (xy 45.607497 -31.5059) (xy 45.649902 -31.548305) (xy 45.686408 -31.595881)
			(xy 45.716392 -31.647815) (xy 45.739341 -31.703219) (xy 45.754862 -31.761144) (xy 45.76269 -31.8206)
			(xy 45.76318 -31.850584) (xy 45.76318 -32.714184) (xy 45.763047 -32.722312) (xy 60.60694 -32.722312)
			(xy 60.60694 -31.858712) (xy 60.60743 -31.828744) (xy 60.615253 -31.769322) (xy 60.630766 -31.711429)
			(xy 60.653702 -31.656056) (xy 60.683669 -31.60415) (xy 60.720156 -31.5566) (xy 60.762536 -31.51422)
			(xy 60.810086 -31.477733) (xy 60.861992 -31.447766) (xy 60.917365 -31.42483) (xy 60.975258 -31.409317)
			(xy 61.03468 -31.401494) (xy 61.094616 -31.401494) (xy 61.154038 -31.409317) (xy 61.211931 -31.42483)
			(xy 61.267304 -31.447766) (xy 61.31921 -31.477733) (xy 61.36676 -31.51422) (xy 61.40914 -31.5566)
			(xy 61.445627 -31.60415) (xy 61.475594 -31.656056) (xy 61.49853 -31.711429) (xy 61.514043 -31.769322)
			(xy 61.521866 -31.828744) (xy 61.522356 -31.858712) (xy 61.522356 -32.714184) (xy 70.847204 -32.714184)
			(xy 70.847204 -31.850584) (xy 70.847694 -31.8206) (xy 70.855522 -31.761144) (xy 70.871043 -31.703219)
			(xy 70.893992 -31.647815) (xy 70.923976 -31.595881) (xy 70.960482 -31.548305) (xy 71.002887 -31.5059)
			(xy 71.050463 -31.469394) (xy 71.102397 -31.43941) (xy 71.157801 -31.416461) (xy 71.215726 -31.40094)
			(xy 71.275182 -31.393112) (xy 71.33515 -31.393112) (xy 71.394606 -31.40094) (xy 71.452531 -31.416461)
			(xy 71.507935 -31.43941) (xy 71.559869 -31.469394) (xy 71.607445 -31.5059) (xy 71.64985 -31.548305)
			(xy 71.686356 -31.595881) (xy 71.71634 -31.647815) (xy 71.739289 -31.703219) (xy 71.75481 -31.761144)
			(xy 71.762638 -31.8206) (xy 71.763128 -31.850584) (xy 71.763128 -32.714184) (xy 71.762995 -32.722312)
			(xy 86.606888 -32.722312) (xy 86.606888 -31.858712) (xy 86.607378 -31.828744) (xy 86.615201 -31.769322)
			(xy 86.630714 -31.711429) (xy 86.65365 -31.656056) (xy 86.683617 -31.60415) (xy 86.720104 -31.5566)
			(xy 86.762484 -31.51422) (xy 86.810034 -31.477733) (xy 86.86194 -31.447766) (xy 86.917313 -31.42483)
			(xy 86.975206 -31.409317) (xy 87.034628 -31.401494) (xy 87.094564 -31.401494) (xy 87.153986 -31.409317)
			(xy 87.211879 -31.42483) (xy 87.267252 -31.447766) (xy 87.319158 -31.477733) (xy 87.366708 -31.51422)
			(xy 87.409088 -31.5566) (xy 87.445575 -31.60415) (xy 87.475542 -31.656056) (xy 87.498478 -31.711429)
			(xy 87.513991 -31.769322) (xy 87.521814 -31.828744) (xy 87.522304 -31.858712) (xy 87.522304 -32.714184)
			(xy 96.847152 -32.714184) (xy 96.847152 -31.850584) (xy 96.847642 -31.8206) (xy 96.85547 -31.761144)
			(xy 96.870991 -31.703219) (xy 96.89394 -31.647815) (xy 96.923924 -31.595881) (xy 96.96043 -31.548305)
			(xy 97.002835 -31.5059) (xy 97.050411 -31.469394) (xy 97.102345 -31.43941) (xy 97.157749 -31.416461)
			(xy 97.215674 -31.40094) (xy 97.27513 -31.393112) (xy 97.335098 -31.393112) (xy 97.394554 -31.40094)
			(xy 97.452479 -31.416461) (xy 97.507883 -31.43941) (xy 97.559817 -31.469394) (xy 97.607393 -31.5059)
			(xy 97.649798 -31.548305) (xy 97.686304 -31.595881) (xy 97.716288 -31.647815) (xy 97.739237 -31.703219)
			(xy 97.754758 -31.761144) (xy 97.762586 -31.8206) (xy 97.763076 -31.850584) (xy 97.763076 -32.714184)
			(xy 97.762943 -32.722312) (xy 124.706888 -32.722312) (xy 124.706888 -31.858712) (xy 124.707378 -31.828728)
			(xy 124.715206 -31.769272) (xy 124.730727 -31.711347) (xy 124.753676 -31.655943) (xy 124.78366 -31.604009)
			(xy 124.820166 -31.556433) (xy 124.862571 -31.514028) (xy 124.910147 -31.477522) (xy 124.962081 -31.447538)
			(xy 125.017485 -31.424589) (xy 125.07541 -31.409068) (xy 125.134866 -31.40124) (xy 125.194834 -31.40124)
			(xy 125.25429 -31.409068) (xy 125.312215 -31.424589) (xy 125.367619 -31.447538) (xy 125.419553 -31.477522)
			(xy 125.467129 -31.514028) (xy 125.509534 -31.556433) (xy 125.54604 -31.604009) (xy 125.576024 -31.655943)
			(xy 125.598973 -31.711347) (xy 125.614494 -31.769272) (xy 125.622322 -31.828728) (xy 125.622812 -31.858712)
			(xy 125.622812 -32.714184) (xy 134.94766 -32.714184) (xy 134.94766 -31.850584) (xy 134.94815 -31.820616)
			(xy 134.955973 -31.761194) (xy 134.971486 -31.703301) (xy 134.994422 -31.647928) (xy 135.024389 -31.596022)
			(xy 135.060876 -31.548472) (xy 135.103256 -31.506092) (xy 135.150806 -31.469605) (xy 135.202712 -31.439638)
			(xy 135.258085 -31.416702) (xy 135.315978 -31.401189) (xy 135.3754 -31.393366) (xy 135.435336 -31.393366)
			(xy 135.494758 -31.401189) (xy 135.552651 -31.416702) (xy 135.608024 -31.439638) (xy 135.65993 -31.469605)
			(xy 135.70748 -31.506092) (xy 135.74986 -31.548472) (xy 135.786347 -31.596022) (xy 135.816314 -31.647928)
			(xy 135.83925 -31.703301) (xy 135.854763 -31.761194) (xy 135.862586 -31.820616) (xy 135.863076 -31.850584)
			(xy 135.863076 -32.714184) (xy 135.862943 -32.722312) (xy 150.706836 -32.722312) (xy 150.706836 -31.858712)
			(xy 150.707326 -31.828728) (xy 150.715154 -31.769272) (xy 150.730675 -31.711347) (xy 150.753624 -31.655943)
			(xy 150.783608 -31.604009) (xy 150.820114 -31.556433) (xy 150.862519 -31.514028) (xy 150.910095 -31.477522)
			(xy 150.962029 -31.447538) (xy 151.017433 -31.424589) (xy 151.075358 -31.409068) (xy 151.134814 -31.40124)
			(xy 151.194782 -31.40124) (xy 151.254238 -31.409068) (xy 151.312163 -31.424589) (xy 151.367567 -31.447538)
			(xy 151.419501 -31.477522) (xy 151.467077 -31.514028) (xy 151.509482 -31.556433) (xy 151.545988 -31.604009)
			(xy 151.575972 -31.655943) (xy 151.598921 -31.711347) (xy 151.614442 -31.769272) (xy 151.62227 -31.828728)
			(xy 151.62276 -31.858712) (xy 151.62276 -32.714184) (xy 160.947608 -32.714184) (xy 160.947608 -31.850584)
			(xy 160.948098 -31.820616) (xy 160.955921 -31.761194) (xy 160.971434 -31.703301) (xy 160.99437 -31.647928)
			(xy 161.024337 -31.596022) (xy 161.060824 -31.548472) (xy 161.103204 -31.506092) (xy 161.150754 -31.469605)
			(xy 161.20266 -31.439638) (xy 161.258033 -31.416702) (xy 161.315926 -31.401189) (xy 161.375348 -31.393366)
			(xy 161.435284 -31.393366) (xy 161.494706 -31.401189) (xy 161.552599 -31.416702) (xy 161.607972 -31.439638)
			(xy 161.659878 -31.469605) (xy 161.707428 -31.506092) (xy 161.749808 -31.548472) (xy 161.786295 -31.596022)
			(xy 161.816262 -31.647928) (xy 161.839198 -31.703301) (xy 161.854711 -31.761194) (xy 161.862534 -31.820616)
			(xy 161.863024 -31.850584) (xy 161.863024 -32.714184) (xy 161.862891 -32.722312) (xy 176.706784 -32.722312)
			(xy 176.706784 -31.858712) (xy 176.707274 -31.828728) (xy 176.715102 -31.769272) (xy 176.730623 -31.711347)
			(xy 176.753572 -31.655943) (xy 176.783556 -31.604009) (xy 176.820062 -31.556433) (xy 176.862467 -31.514028)
			(xy 176.910043 -31.477522) (xy 176.961977 -31.447538) (xy 177.017381 -31.424589) (xy 177.075306 -31.409068)
			(xy 177.134762 -31.40124) (xy 177.19473 -31.40124) (xy 177.254186 -31.409068) (xy 177.312111 -31.424589)
			(xy 177.367515 -31.447538) (xy 177.419449 -31.477522) (xy 177.467025 -31.514028) (xy 177.50943 -31.556433)
			(xy 177.545936 -31.604009) (xy 177.57592 -31.655943) (xy 177.598869 -31.711347) (xy 177.61439 -31.769272)
			(xy 177.622218 -31.828728) (xy 177.622708 -31.858712) (xy 177.622708 -32.714184) (xy 186.947556 -32.714184)
			(xy 186.947556 -31.850584) (xy 186.948046 -31.820616) (xy 186.955869 -31.761194) (xy 186.971382 -31.703301)
			(xy 186.994318 -31.647928) (xy 187.024285 -31.596022) (xy 187.060772 -31.548472) (xy 187.103152 -31.506092)
			(xy 187.150702 -31.469605) (xy 187.202608 -31.439638) (xy 187.257981 -31.416702) (xy 187.315874 -31.401189)
			(xy 187.375296 -31.393366) (xy 187.435232 -31.393366) (xy 187.494654 -31.401189) (xy 187.552547 -31.416702)
			(xy 187.60792 -31.439638) (xy 187.659826 -31.469605) (xy 187.707376 -31.506092) (xy 187.749756 -31.548472)
			(xy 187.786243 -31.596022) (xy 187.81621 -31.647928) (xy 187.839146 -31.703301) (xy 187.854659 -31.761194)
			(xy 187.862482 -31.820616) (xy 187.862972 -31.850584) (xy 187.862972 -32.714184) (xy 187.862839 -32.722312)
			(xy 202.706732 -32.722312) (xy 202.706732 -31.858712) (xy 202.707222 -31.828728) (xy 202.71505 -31.769272)
			(xy 202.730571 -31.711347) (xy 202.75352 -31.655943) (xy 202.783504 -31.604009) (xy 202.82001 -31.556433)
			(xy 202.862415 -31.514028) (xy 202.909991 -31.477522) (xy 202.961925 -31.447538) (xy 203.017329 -31.424589)
			(xy 203.075254 -31.409068) (xy 203.13471 -31.40124) (xy 203.194678 -31.40124) (xy 203.254134 -31.409068)
			(xy 203.312059 -31.424589) (xy 203.367463 -31.447538) (xy 203.419397 -31.477522) (xy 203.466973 -31.514028)
			(xy 203.509378 -31.556433) (xy 203.545884 -31.604009) (xy 203.575868 -31.655943) (xy 203.598817 -31.711347)
			(xy 203.614338 -31.769272) (xy 203.622166 -31.828728) (xy 203.622656 -31.858712) (xy 203.622656 -32.714184)
			(xy 212.947504 -32.714184) (xy 212.947504 -31.850584) (xy 212.947994 -31.820616) (xy 212.955817 -31.761194)
			(xy 212.97133 -31.703301) (xy 212.994266 -31.647928) (xy 213.024233 -31.596022) (xy 213.06072 -31.548472)
			(xy 213.1031 -31.506092) (xy 213.15065 -31.469605) (xy 213.202556 -31.439638) (xy 213.257929 -31.416702)
			(xy 213.315822 -31.401189) (xy 213.375244 -31.393366) (xy 213.43518 -31.393366) (xy 213.494602 -31.401189)
			(xy 213.552495 -31.416702) (xy 213.607868 -31.439638) (xy 213.659774 -31.469605) (xy 213.707324 -31.506092)
			(xy 213.749704 -31.548472) (xy 213.786191 -31.596022) (xy 213.816158 -31.647928) (xy 213.839094 -31.703301)
			(xy 213.854607 -31.761194) (xy 213.86243 -31.820616) (xy 213.86292 -31.850584) (xy 213.86292 -32.714184)
			(xy 213.862787 -32.722312) (xy 240.806732 -32.722312) (xy 240.806732 -31.858712) (xy 240.807222 -31.828728)
			(xy 240.81505 -31.769272) (xy 240.830571 -31.711347) (xy 240.85352 -31.655943) (xy 240.883504 -31.604009)
			(xy 240.92001 -31.556433) (xy 240.962415 -31.514028) (xy 241.009991 -31.477522) (xy 241.061925 -31.447538)
			(xy 241.117329 -31.424589) (xy 241.175254 -31.409068) (xy 241.23471 -31.40124) (xy 241.294678 -31.40124)
			(xy 241.354134 -31.409068) (xy 241.412059 -31.424589) (xy 241.467463 -31.447538) (xy 241.519397 -31.477522)
			(xy 241.566973 -31.514028) (xy 241.609378 -31.556433) (xy 241.645884 -31.604009) (xy 241.675868 -31.655943)
			(xy 241.698817 -31.711347) (xy 241.714338 -31.769272) (xy 241.722166 -31.828728) (xy 241.722656 -31.858712)
			(xy 241.722656 -32.714184) (xy 251.047504 -32.714184) (xy 251.047504 -31.850584) (xy 251.047994 -31.820616)
			(xy 251.055817 -31.761194) (xy 251.07133 -31.703301) (xy 251.094266 -31.647928) (xy 251.124233 -31.596022)
			(xy 251.16072 -31.548472) (xy 251.2031 -31.506092) (xy 251.25065 -31.469605) (xy 251.302556 -31.439638)
			(xy 251.357929 -31.416702) (xy 251.415822 -31.401189) (xy 251.475244 -31.393366) (xy 251.53518 -31.393366)
			(xy 251.594602 -31.401189) (xy 251.652495 -31.416702) (xy 251.707868 -31.439638) (xy 251.759774 -31.469605)
			(xy 251.807324 -31.506092) (xy 251.849704 -31.548472) (xy 251.886191 -31.596022) (xy 251.916158 -31.647928)
			(xy 251.939094 -31.703301) (xy 251.954607 -31.761194) (xy 251.96243 -31.820616) (xy 251.96292 -31.850584)
			(xy 251.96292 -32.714184) (xy 251.962787 -32.722312) (xy 266.80668 -32.722312) (xy 266.80668 -31.858712)
			(xy 266.80717 -31.828728) (xy 266.814998 -31.769272) (xy 266.830519 -31.711347) (xy 266.853468 -31.655943)
			(xy 266.883452 -31.604009) (xy 266.919958 -31.556433) (xy 266.962363 -31.514028) (xy 267.009939 -31.477522)
			(xy 267.061873 -31.447538) (xy 267.117277 -31.424589) (xy 267.175202 -31.409068) (xy 267.234658 -31.40124)
			(xy 267.294626 -31.40124) (xy 267.354082 -31.409068) (xy 267.412007 -31.424589) (xy 267.467411 -31.447538)
			(xy 267.519345 -31.477522) (xy 267.566921 -31.514028) (xy 267.609326 -31.556433) (xy 267.645832 -31.604009)
			(xy 267.675816 -31.655943) (xy 267.698765 -31.711347) (xy 267.714286 -31.769272) (xy 267.722114 -31.828728)
			(xy 267.722604 -31.858712) (xy 267.722604 -32.714184) (xy 277.047452 -32.714184) (xy 277.047452 -31.850584)
			(xy 277.047942 -31.820616) (xy 277.055765 -31.761194) (xy 277.071278 -31.703301) (xy 277.094214 -31.647928)
			(xy 277.124181 -31.596022) (xy 277.160668 -31.548472) (xy 277.203048 -31.506092) (xy 277.250598 -31.469605)
			(xy 277.302504 -31.439638) (xy 277.357877 -31.416702) (xy 277.41577 -31.401189) (xy 277.475192 -31.393366)
			(xy 277.535128 -31.393366) (xy 277.59455 -31.401189) (xy 277.652443 -31.416702) (xy 277.707816 -31.439638)
			(xy 277.759722 -31.469605) (xy 277.807272 -31.506092) (xy 277.849652 -31.548472) (xy 277.886139 -31.596022)
			(xy 277.916106 -31.647928) (xy 277.939042 -31.703301) (xy 277.954555 -31.761194) (xy 277.962378 -31.820616)
			(xy 277.962868 -31.850584) (xy 277.962868 -32.714184) (xy 277.962735 -32.722312) (xy 292.806628 -32.722312)
			(xy 292.806628 -31.858712) (xy 292.807118 -31.828728) (xy 292.814946 -31.769272) (xy 292.830467 -31.711347)
			(xy 292.853416 -31.655943) (xy 292.8834 -31.604009) (xy 292.919906 -31.556433) (xy 292.962311 -31.514028)
			(xy 293.009887 -31.477522) (xy 293.061821 -31.447538) (xy 293.117225 -31.424589) (xy 293.17515 -31.409068)
			(xy 293.234606 -31.40124) (xy 293.294574 -31.40124) (xy 293.35403 -31.409068) (xy 293.411955 -31.424589)
			(xy 293.467359 -31.447538) (xy 293.519293 -31.477522) (xy 293.566869 -31.514028) (xy 293.609274 -31.556433)
			(xy 293.64578 -31.604009) (xy 293.675764 -31.655943) (xy 293.698713 -31.711347) (xy 293.714234 -31.769272)
			(xy 293.722062 -31.828728) (xy 293.722552 -31.858712) (xy 293.722552 -32.714184) (xy 303.0474 -32.714184)
			(xy 303.0474 -31.850584) (xy 303.04789 -31.820616) (xy 303.055713 -31.761194) (xy 303.071226 -31.703301)
			(xy 303.094162 -31.647928) (xy 303.124129 -31.596022) (xy 303.160616 -31.548472) (xy 303.202996 -31.506092)
			(xy 303.250546 -31.469605) (xy 303.302452 -31.439638) (xy 303.357825 -31.416702) (xy 303.415718 -31.401189)
			(xy 303.47514 -31.393366) (xy 303.535076 -31.393366) (xy 303.594498 -31.401189) (xy 303.652391 -31.416702)
			(xy 303.707764 -31.439638) (xy 303.75967 -31.469605) (xy 303.80722 -31.506092) (xy 303.8496 -31.548472)
			(xy 303.886087 -31.596022) (xy 303.916054 -31.647928) (xy 303.93899 -31.703301) (xy 303.954503 -31.761194)
			(xy 303.962326 -31.820616) (xy 303.962816 -31.850584) (xy 303.962816 -32.714184) (xy 303.962683 -32.722312)
			(xy 318.806576 -32.722312) (xy 318.806576 -31.858712) (xy 318.807066 -31.828728) (xy 318.814894 -31.769272)
			(xy 318.830415 -31.711347) (xy 318.853364 -31.655943) (xy 318.883348 -31.604009) (xy 318.919854 -31.556433)
			(xy 318.962259 -31.514028) (xy 319.009835 -31.477522) (xy 319.061769 -31.447538) (xy 319.117173 -31.424589)
			(xy 319.175098 -31.409068) (xy 319.234554 -31.40124) (xy 319.294522 -31.40124) (xy 319.353978 -31.409068)
			(xy 319.411903 -31.424589) (xy 319.467307 -31.447538) (xy 319.519241 -31.477522) (xy 319.566817 -31.514028)
			(xy 319.609222 -31.556433) (xy 319.645728 -31.604009) (xy 319.675712 -31.655943) (xy 319.698661 -31.711347)
			(xy 319.714182 -31.769272) (xy 319.72201 -31.828728) (xy 319.7225 -31.858712) (xy 319.7225 -32.714184)
			(xy 329.047348 -32.714184) (xy 329.047348 -31.850584) (xy 329.047838 -31.820616) (xy 329.055661 -31.761194)
			(xy 329.071174 -31.703301) (xy 329.09411 -31.647928) (xy 329.124077 -31.596022) (xy 329.160564 -31.548472)
			(xy 329.202944 -31.506092) (xy 329.250494 -31.469605) (xy 329.3024 -31.439638) (xy 329.357773 -31.416702)
			(xy 329.415666 -31.401189) (xy 329.475088 -31.393366) (xy 329.535024 -31.393366) (xy 329.594446 -31.401189)
			(xy 329.652339 -31.416702) (xy 329.707712 -31.439638) (xy 329.759618 -31.469605) (xy 329.807168 -31.506092)
			(xy 329.849548 -31.548472) (xy 329.886035 -31.596022) (xy 329.916002 -31.647928) (xy 329.938938 -31.703301)
			(xy 329.954451 -31.761194) (xy 329.962274 -31.820616) (xy 329.962764 -31.850584) (xy 329.962764 -32.714184)
			(xy 329.962631 -32.722312) (xy 356.907084 -32.722312) (xy 356.907084 -31.858712) (xy 356.907574 -31.828744)
			(xy 356.915397 -31.769322) (xy 356.93091 -31.711429) (xy 356.953846 -31.656056) (xy 356.983813 -31.60415)
			(xy 357.0203 -31.5566) (xy 357.06268 -31.51422) (xy 357.11023 -31.477733) (xy 357.162136 -31.447766)
			(xy 357.217509 -31.42483) (xy 357.275402 -31.409317) (xy 357.334824 -31.401494) (xy 357.39476 -31.401494)
			(xy 357.454182 -31.409317) (xy 357.512075 -31.42483) (xy 357.567448 -31.447766) (xy 357.619354 -31.477733)
			(xy 357.666904 -31.51422) (xy 357.709284 -31.5566) (xy 357.745771 -31.60415) (xy 357.775738 -31.656056)
			(xy 357.798674 -31.711429) (xy 357.814187 -31.769322) (xy 357.82201 -31.828744) (xy 357.8225 -31.858712)
			(xy 357.8225 -32.714184) (xy 367.147348 -32.714184) (xy 367.147348 -31.850584) (xy 367.147838 -31.8206)
			(xy 367.155666 -31.761144) (xy 367.171187 -31.703219) (xy 367.194136 -31.647815) (xy 367.22412 -31.595881)
			(xy 367.260626 -31.548305) (xy 367.303031 -31.5059) (xy 367.350607 -31.469394) (xy 367.402541 -31.43941)
			(xy 367.457945 -31.416461) (xy 367.51587 -31.40094) (xy 367.575326 -31.393112) (xy 367.635294 -31.393112)
			(xy 367.69475 -31.40094) (xy 367.752675 -31.416461) (xy 367.808079 -31.43941) (xy 367.860013 -31.469394)
			(xy 367.907589 -31.5059) (xy 367.949994 -31.548305) (xy 367.9865 -31.595881) (xy 368.016484 -31.647815)
			(xy 368.039433 -31.703219) (xy 368.054954 -31.761144) (xy 368.062782 -31.8206) (xy 368.063272 -31.850584)
			(xy 368.063272 -32.714184) (xy 368.063139 -32.722312) (xy 382.907032 -32.722312) (xy 382.907032 -31.858712)
			(xy 382.907522 -31.828744) (xy 382.915345 -31.769322) (xy 382.930858 -31.711429) (xy 382.953794 -31.656056)
			(xy 382.983761 -31.60415) (xy 383.020248 -31.5566) (xy 383.062628 -31.51422) (xy 383.110178 -31.477733)
			(xy 383.162084 -31.447766) (xy 383.217457 -31.42483) (xy 383.27535 -31.409317) (xy 383.334772 -31.401494)
			(xy 383.394708 -31.401494) (xy 383.45413 -31.409317) (xy 383.512023 -31.42483) (xy 383.567396 -31.447766)
			(xy 383.619302 -31.477733) (xy 383.666852 -31.51422) (xy 383.709232 -31.5566) (xy 383.745719 -31.60415)
			(xy 383.775686 -31.656056) (xy 383.798622 -31.711429) (xy 383.814135 -31.769322) (xy 383.821958 -31.828744)
			(xy 383.822448 -31.858712) (xy 383.822448 -32.714184) (xy 393.147296 -32.714184) (xy 393.147296 -31.850584)
			(xy 393.147786 -31.8206) (xy 393.155614 -31.761144) (xy 393.171135 -31.703219) (xy 393.194084 -31.647815)
			(xy 393.224068 -31.595881) (xy 393.260574 -31.548305) (xy 393.302979 -31.5059) (xy 393.350555 -31.469394)
			(xy 393.402489 -31.43941) (xy 393.457893 -31.416461) (xy 393.515818 -31.40094) (xy 393.575274 -31.393112)
			(xy 393.635242 -31.393112) (xy 393.694698 -31.40094) (xy 393.752623 -31.416461) (xy 393.808027 -31.43941)
			(xy 393.859961 -31.469394) (xy 393.907537 -31.5059) (xy 393.949942 -31.548305) (xy 393.986448 -31.595881)
			(xy 394.016432 -31.647815) (xy 394.039381 -31.703219) (xy 394.054902 -31.761144) (xy 394.06273 -31.8206)
			(xy 394.06322 -31.850584) (xy 394.06322 -32.714184) (xy 394.063087 -32.722312) (xy 408.90698 -32.722312)
			(xy 408.90698 -31.858712) (xy 408.90747 -31.828744) (xy 408.915293 -31.769322) (xy 408.930806 -31.711429)
			(xy 408.953742 -31.656056) (xy 408.983709 -31.60415) (xy 409.020196 -31.5566) (xy 409.062576 -31.51422)
			(xy 409.110126 -31.477733) (xy 409.162032 -31.447766) (xy 409.217405 -31.42483) (xy 409.275298 -31.409317)
			(xy 409.33472 -31.401494) (xy 409.394656 -31.401494) (xy 409.454078 -31.409317) (xy 409.511971 -31.42483)
			(xy 409.567344 -31.447766) (xy 409.61925 -31.477733) (xy 409.6668 -31.51422) (xy 409.70918 -31.5566)
			(xy 409.745667 -31.60415) (xy 409.775634 -31.656056) (xy 409.79857 -31.711429) (xy 409.814083 -31.769322)
			(xy 409.821906 -31.828744) (xy 409.822396 -31.858712) (xy 409.822396 -32.714184) (xy 419.147244 -32.714184)
			(xy 419.147244 -31.850584) (xy 419.147734 -31.8206) (xy 419.155562 -31.761144) (xy 419.171083 -31.703219)
			(xy 419.194032 -31.647815) (xy 419.224016 -31.595881) (xy 419.260522 -31.548305) (xy 419.302927 -31.5059)
			(xy 419.350503 -31.469394) (xy 419.402437 -31.43941) (xy 419.457841 -31.416461) (xy 419.515766 -31.40094)
			(xy 419.575222 -31.393112) (xy 419.63519 -31.393112) (xy 419.694646 -31.40094) (xy 419.752571 -31.416461)
			(xy 419.807975 -31.43941) (xy 419.859909 -31.469394) (xy 419.907485 -31.5059) (xy 419.94989 -31.548305)
			(xy 419.986396 -31.595881) (xy 420.01638 -31.647815) (xy 420.039329 -31.703219) (xy 420.05485 -31.761144)
			(xy 420.062678 -31.8206) (xy 420.063168 -31.850584) (xy 420.063168 -32.714184) (xy 420.063035 -32.722312)
			(xy 434.906928 -32.722312) (xy 434.906928 -31.858712) (xy 434.907418 -31.828744) (xy 434.915241 -31.769322)
			(xy 434.930754 -31.711429) (xy 434.95369 -31.656056) (xy 434.983657 -31.60415) (xy 435.020144 -31.5566)
			(xy 435.062524 -31.51422) (xy 435.110074 -31.477733) (xy 435.16198 -31.447766) (xy 435.217353 -31.42483)
			(xy 435.275246 -31.409317) (xy 435.334668 -31.401494) (xy 435.394604 -31.401494) (xy 435.454026 -31.409317)
			(xy 435.511919 -31.42483) (xy 435.567292 -31.447766) (xy 435.619198 -31.477733) (xy 435.666748 -31.51422)
			(xy 435.709128 -31.5566) (xy 435.745615 -31.60415) (xy 435.775582 -31.656056) (xy 435.798518 -31.711429)
			(xy 435.814031 -31.769322) (xy 435.821854 -31.828744) (xy 435.822344 -31.858712) (xy 435.822344 -32.714184)
			(xy 445.147192 -32.714184) (xy 445.147192 -31.850584) (xy 445.147682 -31.8206) (xy 445.15551 -31.761144)
			(xy 445.171031 -31.703219) (xy 445.19398 -31.647815) (xy 445.223964 -31.595881) (xy 445.26047 -31.548305)
			(xy 445.302875 -31.5059) (xy 445.350451 -31.469394) (xy 445.402385 -31.43941) (xy 445.457789 -31.416461)
			(xy 445.515714 -31.40094) (xy 445.57517 -31.393112) (xy 445.635138 -31.393112) (xy 445.694594 -31.40094)
			(xy 445.752519 -31.416461) (xy 445.807923 -31.43941) (xy 445.859857 -31.469394) (xy 445.907433 -31.5059)
			(xy 445.949838 -31.548305) (xy 445.986344 -31.595881) (xy 446.016328 -31.647815) (xy 446.039277 -31.703219)
			(xy 446.054798 -31.761144) (xy 446.062626 -31.8206) (xy 446.063116 -31.850584) (xy 446.063116 -32.714184)
			(xy 446.062626 -32.744168) (xy 446.054798 -32.803624) (xy 446.039277 -32.861549) (xy 446.016328 -32.916953)
			(xy 445.986344 -32.968887) (xy 445.949838 -33.016463) (xy 445.907433 -33.058868) (xy 445.859857 -33.095374)
			(xy 445.807923 -33.125358) (xy 445.752519 -33.148307) (xy 445.694594 -33.163828) (xy 445.635138 -33.171656)
			(xy 445.57517 -33.171656) (xy 445.515714 -33.163828) (xy 445.457789 -33.148307) (xy 445.402385 -33.125358)
			(xy 445.350451 -33.095374) (xy 445.302875 -33.058868) (xy 445.26047 -33.016463) (xy 445.223964 -32.968887)
			(xy 445.19398 -32.916953) (xy 445.171031 -32.861549) (xy 445.15551 -32.803624) (xy 445.147682 -32.744168)
			(xy 445.147192 -32.714184) (xy 435.822344 -32.714184) (xy 435.822344 -32.722312) (xy 435.821854 -32.75228)
			(xy 435.814031 -32.811702) (xy 435.798518 -32.869595) (xy 435.775582 -32.924968) (xy 435.745615 -32.976874)
			(xy 435.709128 -33.024424) (xy 435.666748 -33.066804) (xy 435.619198 -33.103291) (xy 435.567292 -33.133258)
			(xy 435.511919 -33.156194) (xy 435.454026 -33.171707) (xy 435.394604 -33.17953) (xy 435.334668 -33.17953)
			(xy 435.275246 -33.171707) (xy 435.217353 -33.156194) (xy 435.16198 -33.133258) (xy 435.110074 -33.103291)
			(xy 435.062524 -33.066804) (xy 435.020144 -33.024424) (xy 434.983657 -32.976874) (xy 434.95369 -32.924968)
			(xy 434.930754 -32.869595) (xy 434.915241 -32.811702) (xy 434.907418 -32.75228) (xy 434.906928 -32.722312)
			(xy 420.063035 -32.722312) (xy 420.062678 -32.744168) (xy 420.05485 -32.803624) (xy 420.039329 -32.861549)
			(xy 420.01638 -32.916953) (xy 419.986396 -32.968887) (xy 419.94989 -33.016463) (xy 419.907485 -33.058868)
			(xy 419.859909 -33.095374) (xy 419.807975 -33.125358) (xy 419.752571 -33.148307) (xy 419.694646 -33.163828)
			(xy 419.63519 -33.171656) (xy 419.575222 -33.171656) (xy 419.515766 -33.163828) (xy 419.457841 -33.148307)
			(xy 419.402437 -33.125358) (xy 419.350503 -33.095374) (xy 419.302927 -33.058868) (xy 419.260522 -33.016463)
			(xy 419.224016 -32.968887) (xy 419.194032 -32.916953) (xy 419.171083 -32.861549) (xy 419.155562 -32.803624)
			(xy 419.147734 -32.744168) (xy 419.147244 -32.714184) (xy 409.822396 -32.714184) (xy 409.822396 -32.722312)
			(xy 409.821906 -32.75228) (xy 409.814083 -32.811702) (xy 409.79857 -32.869595) (xy 409.775634 -32.924968)
			(xy 409.745667 -32.976874) (xy 409.70918 -33.024424) (xy 409.6668 -33.066804) (xy 409.61925 -33.103291)
			(xy 409.567344 -33.133258) (xy 409.511971 -33.156194) (xy 409.454078 -33.171707) (xy 409.394656 -33.17953)
			(xy 409.33472 -33.17953) (xy 409.275298 -33.171707) (xy 409.217405 -33.156194) (xy 409.162032 -33.133258)
			(xy 409.110126 -33.103291) (xy 409.062576 -33.066804) (xy 409.020196 -33.024424) (xy 408.983709 -32.976874)
			(xy 408.953742 -32.924968) (xy 408.930806 -32.869595) (xy 408.915293 -32.811702) (xy 408.90747 -32.75228)
			(xy 408.90698 -32.722312) (xy 394.063087 -32.722312) (xy 394.06273 -32.744168) (xy 394.054902 -32.803624)
			(xy 394.039381 -32.861549) (xy 394.016432 -32.916953) (xy 393.986448 -32.968887) (xy 393.949942 -33.016463)
			(xy 393.907537 -33.058868) (xy 393.859961 -33.095374) (xy 393.808027 -33.125358) (xy 393.752623 -33.148307)
			(xy 393.694698 -33.163828) (xy 393.635242 -33.171656) (xy 393.575274 -33.171656) (xy 393.515818 -33.163828)
			(xy 393.457893 -33.148307) (xy 393.402489 -33.125358) (xy 393.350555 -33.095374) (xy 393.302979 -33.058868)
			(xy 393.260574 -33.016463) (xy 393.224068 -32.968887) (xy 393.194084 -32.916953) (xy 393.171135 -32.861549)
			(xy 393.155614 -32.803624) (xy 393.147786 -32.744168) (xy 393.147296 -32.714184) (xy 383.822448 -32.714184)
			(xy 383.822448 -32.722312) (xy 383.821958 -32.75228) (xy 383.814135 -32.811702) (xy 383.798622 -32.869595)
			(xy 383.775686 -32.924968) (xy 383.745719 -32.976874) (xy 383.709232 -33.024424) (xy 383.666852 -33.066804)
			(xy 383.619302 -33.103291) (xy 383.567396 -33.133258) (xy 383.512023 -33.156194) (xy 383.45413 -33.171707)
			(xy 383.394708 -33.17953) (xy 383.334772 -33.17953) (xy 383.27535 -33.171707) (xy 383.217457 -33.156194)
			(xy 383.162084 -33.133258) (xy 383.110178 -33.103291) (xy 383.062628 -33.066804) (xy 383.020248 -33.024424)
			(xy 382.983761 -32.976874) (xy 382.953794 -32.924968) (xy 382.930858 -32.869595) (xy 382.915345 -32.811702)
			(xy 382.907522 -32.75228) (xy 382.907032 -32.722312) (xy 368.063139 -32.722312) (xy 368.062782 -32.744168)
			(xy 368.054954 -32.803624) (xy 368.039433 -32.861549) (xy 368.016484 -32.916953) (xy 367.9865 -32.968887)
			(xy 367.949994 -33.016463) (xy 367.907589 -33.058868) (xy 367.860013 -33.095374) (xy 367.808079 -33.125358)
			(xy 367.752675 -33.148307) (xy 367.69475 -33.163828) (xy 367.635294 -33.171656) (xy 367.575326 -33.171656)
			(xy 367.51587 -33.163828) (xy 367.457945 -33.148307) (xy 367.402541 -33.125358) (xy 367.350607 -33.095374)
			(xy 367.303031 -33.058868) (xy 367.260626 -33.016463) (xy 367.22412 -32.968887) (xy 367.194136 -32.916953)
			(xy 367.171187 -32.861549) (xy 367.155666 -32.803624) (xy 367.147838 -32.744168) (xy 367.147348 -32.714184)
			(xy 357.8225 -32.714184) (xy 357.8225 -32.722312) (xy 357.82201 -32.75228) (xy 357.814187 -32.811702)
			(xy 357.798674 -32.869595) (xy 357.775738 -32.924968) (xy 357.745771 -32.976874) (xy 357.709284 -33.024424)
			(xy 357.666904 -33.066804) (xy 357.619354 -33.103291) (xy 357.567448 -33.133258) (xy 357.512075 -33.156194)
			(xy 357.454182 -33.171707) (xy 357.39476 -33.17953) (xy 357.334824 -33.17953) (xy 357.275402 -33.171707)
			(xy 357.217509 -33.156194) (xy 357.162136 -33.133258) (xy 357.11023 -33.103291) (xy 357.06268 -33.066804)
			(xy 357.0203 -33.024424) (xy 356.983813 -32.976874) (xy 356.953846 -32.924968) (xy 356.93091 -32.869595)
			(xy 356.915397 -32.811702) (xy 356.907574 -32.75228) (xy 356.907084 -32.722312) (xy 329.962631 -32.722312)
			(xy 329.962274 -32.744152) (xy 329.954451 -32.803574) (xy 329.938938 -32.861467) (xy 329.916002 -32.91684)
			(xy 329.886035 -32.968746) (xy 329.849548 -33.016296) (xy 329.807168 -33.058676) (xy 329.759618 -33.095163)
			(xy 329.707712 -33.12513) (xy 329.652339 -33.148066) (xy 329.594446 -33.163579) (xy 329.535024 -33.171402)
			(xy 329.475088 -33.171402) (xy 329.415666 -33.163579) (xy 329.357773 -33.148066) (xy 329.3024 -33.12513)
			(xy 329.250494 -33.095163) (xy 329.202944 -33.058676) (xy 329.160564 -33.016296) (xy 329.124077 -32.968746)
			(xy 329.09411 -32.91684) (xy 329.071174 -32.861467) (xy 329.055661 -32.803574) (xy 329.047838 -32.744152)
			(xy 329.047348 -32.714184) (xy 319.7225 -32.714184) (xy 319.7225 -32.722312) (xy 319.72201 -32.752296)
			(xy 319.714182 -32.811752) (xy 319.698661 -32.869677) (xy 319.675712 -32.925081) (xy 319.645728 -32.977015)
			(xy 319.609222 -33.024591) (xy 319.566817 -33.066996) (xy 319.519241 -33.103502) (xy 319.467307 -33.133486)
			(xy 319.411903 -33.156435) (xy 319.353978 -33.171956) (xy 319.294522 -33.179784) (xy 319.234554 -33.179784)
			(xy 319.175098 -33.171956) (xy 319.117173 -33.156435) (xy 319.061769 -33.133486) (xy 319.009835 -33.103502)
			(xy 318.962259 -33.066996) (xy 318.919854 -33.024591) (xy 318.883348 -32.977015) (xy 318.853364 -32.925081)
			(xy 318.830415 -32.869677) (xy 318.814894 -32.811752) (xy 318.807066 -32.752296) (xy 318.806576 -32.722312)
			(xy 303.962683 -32.722312) (xy 303.962326 -32.744152) (xy 303.954503 -32.803574) (xy 303.93899 -32.861467)
			(xy 303.916054 -32.91684) (xy 303.886087 -32.968746) (xy 303.8496 -33.016296) (xy 303.80722 -33.058676)
			(xy 303.75967 -33.095163) (xy 303.707764 -33.12513) (xy 303.652391 -33.148066) (xy 303.594498 -33.163579)
			(xy 303.535076 -33.171402) (xy 303.47514 -33.171402) (xy 303.415718 -33.163579) (xy 303.357825 -33.148066)
			(xy 303.302452 -33.12513) (xy 303.250546 -33.095163) (xy 303.202996 -33.058676) (xy 303.160616 -33.016296)
			(xy 303.124129 -32.968746) (xy 303.094162 -32.91684) (xy 303.071226 -32.861467) (xy 303.055713 -32.803574)
			(xy 303.04789 -32.744152) (xy 303.0474 -32.714184) (xy 293.722552 -32.714184) (xy 293.722552 -32.722312)
			(xy 293.722062 -32.752296) (xy 293.714234 -32.811752) (xy 293.698713 -32.869677) (xy 293.675764 -32.925081)
			(xy 293.64578 -32.977015) (xy 293.609274 -33.024591) (xy 293.566869 -33.066996) (xy 293.519293 -33.103502)
			(xy 293.467359 -33.133486) (xy 293.411955 -33.156435) (xy 293.35403 -33.171956) (xy 293.294574 -33.179784)
			(xy 293.234606 -33.179784) (xy 293.17515 -33.171956) (xy 293.117225 -33.156435) (xy 293.061821 -33.133486)
			(xy 293.009887 -33.103502) (xy 292.962311 -33.066996) (xy 292.919906 -33.024591) (xy 292.8834 -32.977015)
			(xy 292.853416 -32.925081) (xy 292.830467 -32.869677) (xy 292.814946 -32.811752) (xy 292.807118 -32.752296)
			(xy 292.806628 -32.722312) (xy 277.962735 -32.722312) (xy 277.962378 -32.744152) (xy 277.954555 -32.803574)
			(xy 277.939042 -32.861467) (xy 277.916106 -32.91684) (xy 277.886139 -32.968746) (xy 277.849652 -33.016296)
			(xy 277.807272 -33.058676) (xy 277.759722 -33.095163) (xy 277.707816 -33.12513) (xy 277.652443 -33.148066)
			(xy 277.59455 -33.163579) (xy 277.535128 -33.171402) (xy 277.475192 -33.171402) (xy 277.41577 -33.163579)
			(xy 277.357877 -33.148066) (xy 277.302504 -33.12513) (xy 277.250598 -33.095163) (xy 277.203048 -33.058676)
			(xy 277.160668 -33.016296) (xy 277.124181 -32.968746) (xy 277.094214 -32.91684) (xy 277.071278 -32.861467)
			(xy 277.055765 -32.803574) (xy 277.047942 -32.744152) (xy 277.047452 -32.714184) (xy 267.722604 -32.714184)
			(xy 267.722604 -32.722312) (xy 267.722114 -32.752296) (xy 267.714286 -32.811752) (xy 267.698765 -32.869677)
			(xy 267.675816 -32.925081) (xy 267.645832 -32.977015) (xy 267.609326 -33.024591) (xy 267.566921 -33.066996)
			(xy 267.519345 -33.103502) (xy 267.467411 -33.133486) (xy 267.412007 -33.156435) (xy 267.354082 -33.171956)
			(xy 267.294626 -33.179784) (xy 267.234658 -33.179784) (xy 267.175202 -33.171956) (xy 267.117277 -33.156435)
			(xy 267.061873 -33.133486) (xy 267.009939 -33.103502) (xy 266.962363 -33.066996) (xy 266.919958 -33.024591)
			(xy 266.883452 -32.977015) (xy 266.853468 -32.925081) (xy 266.830519 -32.869677) (xy 266.814998 -32.811752)
			(xy 266.80717 -32.752296) (xy 266.80668 -32.722312) (xy 251.962787 -32.722312) (xy 251.96243 -32.744152)
			(xy 251.954607 -32.803574) (xy 251.939094 -32.861467) (xy 251.916158 -32.91684) (xy 251.886191 -32.968746)
			(xy 251.849704 -33.016296) (xy 251.807324 -33.058676) (xy 251.759774 -33.095163) (xy 251.707868 -33.12513)
			(xy 251.652495 -33.148066) (xy 251.594602 -33.163579) (xy 251.53518 -33.171402) (xy 251.475244 -33.171402)
			(xy 251.415822 -33.163579) (xy 251.357929 -33.148066) (xy 251.302556 -33.12513) (xy 251.25065 -33.095163)
			(xy 251.2031 -33.058676) (xy 251.16072 -33.016296) (xy 251.124233 -32.968746) (xy 251.094266 -32.91684)
			(xy 251.07133 -32.861467) (xy 251.055817 -32.803574) (xy 251.047994 -32.744152) (xy 251.047504 -32.714184)
			(xy 241.722656 -32.714184) (xy 241.722656 -32.722312) (xy 241.722166 -32.752296) (xy 241.714338 -32.811752)
			(xy 241.698817 -32.869677) (xy 241.675868 -32.925081) (xy 241.645884 -32.977015) (xy 241.609378 -33.024591)
			(xy 241.566973 -33.066996) (xy 241.519397 -33.103502) (xy 241.467463 -33.133486) (xy 241.412059 -33.156435)
			(xy 241.354134 -33.171956) (xy 241.294678 -33.179784) (xy 241.23471 -33.179784) (xy 241.175254 -33.171956)
			(xy 241.117329 -33.156435) (xy 241.061925 -33.133486) (xy 241.009991 -33.103502) (xy 240.962415 -33.066996)
			(xy 240.92001 -33.024591) (xy 240.883504 -32.977015) (xy 240.85352 -32.925081) (xy 240.830571 -32.869677)
			(xy 240.81505 -32.811752) (xy 240.807222 -32.752296) (xy 240.806732 -32.722312) (xy 213.862787 -32.722312)
			(xy 213.86243 -32.744152) (xy 213.854607 -32.803574) (xy 213.839094 -32.861467) (xy 213.816158 -32.91684)
			(xy 213.786191 -32.968746) (xy 213.749704 -33.016296) (xy 213.707324 -33.058676) (xy 213.659774 -33.095163)
			(xy 213.607868 -33.12513) (xy 213.552495 -33.148066) (xy 213.494602 -33.163579) (xy 213.43518 -33.171402)
			(xy 213.375244 -33.171402) (xy 213.315822 -33.163579) (xy 213.257929 -33.148066) (xy 213.202556 -33.12513)
			(xy 213.15065 -33.095163) (xy 213.1031 -33.058676) (xy 213.06072 -33.016296) (xy 213.024233 -32.968746)
			(xy 212.994266 -32.91684) (xy 212.97133 -32.861467) (xy 212.955817 -32.803574) (xy 212.947994 -32.744152)
			(xy 212.947504 -32.714184) (xy 203.622656 -32.714184) (xy 203.622656 -32.722312) (xy 203.622166 -32.752296)
			(xy 203.614338 -32.811752) (xy 203.598817 -32.869677) (xy 203.575868 -32.925081) (xy 203.545884 -32.977015)
			(xy 203.509378 -33.024591) (xy 203.466973 -33.066996) (xy 203.419397 -33.103502) (xy 203.367463 -33.133486)
			(xy 203.312059 -33.156435) (xy 203.254134 -33.171956) (xy 203.194678 -33.179784) (xy 203.13471 -33.179784)
			(xy 203.075254 -33.171956) (xy 203.017329 -33.156435) (xy 202.961925 -33.133486) (xy 202.909991 -33.103502)
			(xy 202.862415 -33.066996) (xy 202.82001 -33.024591) (xy 202.783504 -32.977015) (xy 202.75352 -32.925081)
			(xy 202.730571 -32.869677) (xy 202.71505 -32.811752) (xy 202.707222 -32.752296) (xy 202.706732 -32.722312)
			(xy 187.862839 -32.722312) (xy 187.862482 -32.744152) (xy 187.854659 -32.803574) (xy 187.839146 -32.861467)
			(xy 187.81621 -32.91684) (xy 187.786243 -32.968746) (xy 187.749756 -33.016296) (xy 187.707376 -33.058676)
			(xy 187.659826 -33.095163) (xy 187.60792 -33.12513) (xy 187.552547 -33.148066) (xy 187.494654 -33.163579)
			(xy 187.435232 -33.171402) (xy 187.375296 -33.171402) (xy 187.315874 -33.163579) (xy 187.257981 -33.148066)
			(xy 187.202608 -33.12513) (xy 187.150702 -33.095163) (xy 187.103152 -33.058676) (xy 187.060772 -33.016296)
			(xy 187.024285 -32.968746) (xy 186.994318 -32.91684) (xy 186.971382 -32.861467) (xy 186.955869 -32.803574)
			(xy 186.948046 -32.744152) (xy 186.947556 -32.714184) (xy 177.622708 -32.714184) (xy 177.622708 -32.722312)
			(xy 177.622218 -32.752296) (xy 177.61439 -32.811752) (xy 177.598869 -32.869677) (xy 177.57592 -32.925081)
			(xy 177.545936 -32.977015) (xy 177.50943 -33.024591) (xy 177.467025 -33.066996) (xy 177.419449 -33.103502)
			(xy 177.367515 -33.133486) (xy 177.312111 -33.156435) (xy 177.254186 -33.171956) (xy 177.19473 -33.179784)
			(xy 177.134762 -33.179784) (xy 177.075306 -33.171956) (xy 177.017381 -33.156435) (xy 176.961977 -33.133486)
			(xy 176.910043 -33.103502) (xy 176.862467 -33.066996) (xy 176.820062 -33.024591) (xy 176.783556 -32.977015)
			(xy 176.753572 -32.925081) (xy 176.730623 -32.869677) (xy 176.715102 -32.811752) (xy 176.707274 -32.752296)
			(xy 176.706784 -32.722312) (xy 161.862891 -32.722312) (xy 161.862534 -32.744152) (xy 161.854711 -32.803574)
			(xy 161.839198 -32.861467) (xy 161.816262 -32.91684) (xy 161.786295 -32.968746) (xy 161.749808 -33.016296)
			(xy 161.707428 -33.058676) (xy 161.659878 -33.095163) (xy 161.607972 -33.12513) (xy 161.552599 -33.148066)
			(xy 161.494706 -33.163579) (xy 161.435284 -33.171402) (xy 161.375348 -33.171402) (xy 161.315926 -33.163579)
			(xy 161.258033 -33.148066) (xy 161.20266 -33.12513) (xy 161.150754 -33.095163) (xy 161.103204 -33.058676)
			(xy 161.060824 -33.016296) (xy 161.024337 -32.968746) (xy 160.99437 -32.91684) (xy 160.971434 -32.861467)
			(xy 160.955921 -32.803574) (xy 160.948098 -32.744152) (xy 160.947608 -32.714184) (xy 151.62276 -32.714184)
			(xy 151.62276 -32.722312) (xy 151.62227 -32.752296) (xy 151.614442 -32.811752) (xy 151.598921 -32.869677)
			(xy 151.575972 -32.925081) (xy 151.545988 -32.977015) (xy 151.509482 -33.024591) (xy 151.467077 -33.066996)
			(xy 151.419501 -33.103502) (xy 151.367567 -33.133486) (xy 151.312163 -33.156435) (xy 151.254238 -33.171956)
			(xy 151.194782 -33.179784) (xy 151.134814 -33.179784) (xy 151.075358 -33.171956) (xy 151.017433 -33.156435)
			(xy 150.962029 -33.133486) (xy 150.910095 -33.103502) (xy 150.862519 -33.066996) (xy 150.820114 -33.024591)
			(xy 150.783608 -32.977015) (xy 150.753624 -32.925081) (xy 150.730675 -32.869677) (xy 150.715154 -32.811752)
			(xy 150.707326 -32.752296) (xy 150.706836 -32.722312) (xy 135.862943 -32.722312) (xy 135.862586 -32.744152)
			(xy 135.854763 -32.803574) (xy 135.83925 -32.861467) (xy 135.816314 -32.91684) (xy 135.786347 -32.968746)
			(xy 135.74986 -33.016296) (xy 135.70748 -33.058676) (xy 135.65993 -33.095163) (xy 135.608024 -33.12513)
			(xy 135.552651 -33.148066) (xy 135.494758 -33.163579) (xy 135.435336 -33.171402) (xy 135.3754 -33.171402)
			(xy 135.315978 -33.163579) (xy 135.258085 -33.148066) (xy 135.202712 -33.12513) (xy 135.150806 -33.095163)
			(xy 135.103256 -33.058676) (xy 135.060876 -33.016296) (xy 135.024389 -32.968746) (xy 134.994422 -32.91684)
			(xy 134.971486 -32.861467) (xy 134.955973 -32.803574) (xy 134.94815 -32.744152) (xy 134.94766 -32.714184)
			(xy 125.622812 -32.714184) (xy 125.622812 -32.722312) (xy 125.622322 -32.752296) (xy 125.614494 -32.811752)
			(xy 125.598973 -32.869677) (xy 125.576024 -32.925081) (xy 125.54604 -32.977015) (xy 125.509534 -33.024591)
			(xy 125.467129 -33.066996) (xy 125.419553 -33.103502) (xy 125.367619 -33.133486) (xy 125.312215 -33.156435)
			(xy 125.25429 -33.171956) (xy 125.194834 -33.179784) (xy 125.134866 -33.179784) (xy 125.07541 -33.171956)
			(xy 125.017485 -33.156435) (xy 124.962081 -33.133486) (xy 124.910147 -33.103502) (xy 124.862571 -33.066996)
			(xy 124.820166 -33.024591) (xy 124.78366 -32.977015) (xy 124.753676 -32.925081) (xy 124.730727 -32.869677)
			(xy 124.715206 -32.811752) (xy 124.707378 -32.752296) (xy 124.706888 -32.722312) (xy 97.762943 -32.722312)
			(xy 97.762586 -32.744168) (xy 97.754758 -32.803624) (xy 97.739237 -32.861549) (xy 97.716288 -32.916953)
			(xy 97.686304 -32.968887) (xy 97.649798 -33.016463) (xy 97.607393 -33.058868) (xy 97.559817 -33.095374)
			(xy 97.507883 -33.125358) (xy 97.452479 -33.148307) (xy 97.394554 -33.163828) (xy 97.335098 -33.171656)
			(xy 97.27513 -33.171656) (xy 97.215674 -33.163828) (xy 97.157749 -33.148307) (xy 97.102345 -33.125358)
			(xy 97.050411 -33.095374) (xy 97.002835 -33.058868) (xy 96.96043 -33.016463) (xy 96.923924 -32.968887)
			(xy 96.89394 -32.916953) (xy 96.870991 -32.861549) (xy 96.85547 -32.803624) (xy 96.847642 -32.744168)
			(xy 96.847152 -32.714184) (xy 87.522304 -32.714184) (xy 87.522304 -32.722312) (xy 87.521814 -32.75228)
			(xy 87.513991 -32.811702) (xy 87.498478 -32.869595) (xy 87.475542 -32.924968) (xy 87.445575 -32.976874)
			(xy 87.409088 -33.024424) (xy 87.366708 -33.066804) (xy 87.319158 -33.103291) (xy 87.267252 -33.133258)
			(xy 87.211879 -33.156194) (xy 87.153986 -33.171707) (xy 87.094564 -33.17953) (xy 87.034628 -33.17953)
			(xy 86.975206 -33.171707) (xy 86.917313 -33.156194) (xy 86.86194 -33.133258) (xy 86.810034 -33.103291)
			(xy 86.762484 -33.066804) (xy 86.720104 -33.024424) (xy 86.683617 -32.976874) (xy 86.65365 -32.924968)
			(xy 86.630714 -32.869595) (xy 86.615201 -32.811702) (xy 86.607378 -32.75228) (xy 86.606888 -32.722312)
			(xy 71.762995 -32.722312) (xy 71.762638 -32.744168) (xy 71.75481 -32.803624) (xy 71.739289 -32.861549)
			(xy 71.71634 -32.916953) (xy 71.686356 -32.968887) (xy 71.64985 -33.016463) (xy 71.607445 -33.058868)
			(xy 71.559869 -33.095374) (xy 71.507935 -33.125358) (xy 71.452531 -33.148307) (xy 71.394606 -33.163828)
			(xy 71.33515 -33.171656) (xy 71.275182 -33.171656) (xy 71.215726 -33.163828) (xy 71.157801 -33.148307)
			(xy 71.102397 -33.125358) (xy 71.050463 -33.095374) (xy 71.002887 -33.058868) (xy 70.960482 -33.016463)
			(xy 70.923976 -32.968887) (xy 70.893992 -32.916953) (xy 70.871043 -32.861549) (xy 70.855522 -32.803624)
			(xy 70.847694 -32.744168) (xy 70.847204 -32.714184) (xy 61.522356 -32.714184) (xy 61.522356 -32.722312)
			(xy 61.521866 -32.75228) (xy 61.514043 -32.811702) (xy 61.49853 -32.869595) (xy 61.475594 -32.924968)
			(xy 61.445627 -32.976874) (xy 61.40914 -33.024424) (xy 61.36676 -33.066804) (xy 61.31921 -33.103291)
			(xy 61.267304 -33.133258) (xy 61.211931 -33.156194) (xy 61.154038 -33.171707) (xy 61.094616 -33.17953)
			(xy 61.03468 -33.17953) (xy 60.975258 -33.171707) (xy 60.917365 -33.156194) (xy 60.861992 -33.133258)
			(xy 60.810086 -33.103291) (xy 60.762536 -33.066804) (xy 60.720156 -33.024424) (xy 60.683669 -32.976874)
			(xy 60.653702 -32.924968) (xy 60.630766 -32.869595) (xy 60.615253 -32.811702) (xy 60.60743 -32.75228)
			(xy 60.60694 -32.722312) (xy 45.763047 -32.722312) (xy 45.76269 -32.744168) (xy 45.754862 -32.803624)
			(xy 45.739341 -32.861549) (xy 45.716392 -32.916953) (xy 45.686408 -32.968887) (xy 45.649902 -33.016463)
			(xy 45.607497 -33.058868) (xy 45.559921 -33.095374) (xy 45.507987 -33.125358) (xy 45.452583 -33.148307)
			(xy 45.394658 -33.163828) (xy 45.335202 -33.171656) (xy 45.275234 -33.171656) (xy 45.215778 -33.163828)
			(xy 45.157853 -33.148307) (xy 45.102449 -33.125358) (xy 45.050515 -33.095374) (xy 45.002939 -33.058868)
			(xy 44.960534 -33.016463) (xy 44.924028 -32.968887) (xy 44.894044 -32.916953) (xy 44.871095 -32.861549)
			(xy 44.855574 -32.803624) (xy 44.847746 -32.744168) (xy 44.847256 -32.714184) (xy 35.522408 -32.714184)
			(xy 35.522408 -32.722312) (xy 35.521918 -32.75228) (xy 35.514095 -32.811702) (xy 35.498582 -32.869595)
			(xy 35.475646 -32.924968) (xy 35.445679 -32.976874) (xy 35.409192 -33.024424) (xy 35.366812 -33.066804)
			(xy 35.319262 -33.103291) (xy 35.267356 -33.133258) (xy 35.211983 -33.156194) (xy 35.15409 -33.171707)
			(xy 35.094668 -33.17953) (xy 35.034732 -33.17953) (xy 34.97531 -33.171707) (xy 34.917417 -33.156194)
			(xy 34.862044 -33.133258) (xy 34.810138 -33.103291) (xy 34.762588 -33.066804) (xy 34.720208 -33.024424)
			(xy 34.683721 -32.976874) (xy 34.653754 -32.924968) (xy 34.630818 -32.869595) (xy 34.615305 -32.811702)
			(xy 34.607482 -32.75228) (xy 34.606992 -32.722312) (xy 19.763099 -32.722312) (xy 19.762742 -32.744168)
			(xy 19.754914 -32.803624) (xy 19.739393 -32.861549) (xy 19.716444 -32.916953) (xy 19.68646 -32.968887)
			(xy 19.649954 -33.016463) (xy 19.607549 -33.058868) (xy 19.559973 -33.095374) (xy 19.508039 -33.125358)
			(xy 19.452635 -33.148307) (xy 19.39471 -33.163828) (xy 19.335254 -33.171656) (xy 19.275286 -33.171656)
			(xy 19.21583 -33.163828) (xy 19.157905 -33.148307) (xy 19.102501 -33.125358) (xy 19.050567 -33.095374)
			(xy 19.002991 -33.058868) (xy 18.960586 -33.016463) (xy 18.92408 -32.968887) (xy 18.894096 -32.916953)
			(xy 18.871147 -32.861549) (xy 18.855626 -32.803624) (xy 18.847798 -32.744168) (xy 18.847308 -32.714184)
			(xy 9.52246 -32.714184) (xy 9.52246 -32.722312) (xy 9.52197 -32.75228) (xy 9.514147 -32.811702) (xy 9.498634 -32.869595)
			(xy 9.475698 -32.924968) (xy 9.445731 -32.976874) (xy 9.409244 -33.024424) (xy 9.366864 -33.066804)
			(xy 9.319314 -33.103291) (xy 9.267408 -33.133258) (xy 9.212035 -33.156194) (xy 9.154142 -33.171707)
			(xy 9.09472 -33.17953) (xy 9.034784 -33.17953) (xy 8.975362 -33.171707) (xy 8.917469 -33.156194)
			(xy 8.862096 -33.133258) (xy 8.81019 -33.103291) (xy 8.76264 -33.066804) (xy 8.72026 -33.024424)
			(xy 8.683773 -32.976874) (xy 8.653806 -32.924968) (xy 8.63087 -32.869595) (xy 8.615357 -32.811702)
			(xy 8.607534 -32.75228) (xy 8.607044 -32.722312) (xy 0.509016 -32.722312) (xy 0.509016 -34.52241)
			(xy 6.752844 -34.52241) (xy 6.752844 -33.65881) (xy 6.753334 -33.628842) (xy 6.761157 -33.56942)
			(xy 6.77667 -33.511527) (xy 6.799606 -33.456154) (xy 6.829573 -33.404248) (xy 6.86606 -33.356698)
			(xy 6.90844 -33.314318) (xy 6.95599 -33.277831) (xy 7.007896 -33.247864) (xy 7.063269 -33.224928)
			(xy 7.121162 -33.209415) (xy 7.180584 -33.201592) (xy 7.24052 -33.201592) (xy 7.299942 -33.209415)
			(xy 7.357835 -33.224928) (xy 7.413208 -33.247864) (xy 7.465114 -33.277831) (xy 7.512664 -33.314318)
			(xy 7.555044 -33.356698) (xy 7.591531 -33.404248) (xy 7.621498 -33.456154) (xy 7.644434 -33.511527)
			(xy 7.659947 -33.56942) (xy 7.66777 -33.628842) (xy 7.66826 -33.65881) (xy 7.66826 -34.520886) (xy 21.489416 -34.520886)
			(xy 21.489416 -33.657286) (xy 21.489906 -33.627302) (xy 21.497734 -33.567846) (xy 21.513255 -33.509921)
			(xy 21.536204 -33.454517) (xy 21.566188 -33.402583) (xy 21.602694 -33.355007) (xy 21.645099 -33.312602)
			(xy 21.692675 -33.276096) (xy 21.744609 -33.246112) (xy 21.800013 -33.223163) (xy 21.857938 -33.207642)
			(xy 21.917394 -33.199814) (xy 21.977362 -33.199814) (xy 22.036818 -33.207642) (xy 22.094743 -33.223163)
			(xy 22.150147 -33.246112) (xy 22.202081 -33.276096) (xy 22.249657 -33.312602) (xy 22.292062 -33.355007)
			(xy 22.328568 -33.402583) (xy 22.358552 -33.454517) (xy 22.381501 -33.509921) (xy 22.397022 -33.567846)
			(xy 22.40485 -33.627302) (xy 22.40534 -33.657286) (xy 22.40534 -34.520886) (xy 22.405315 -34.52241)
			(xy 32.752792 -34.52241) (xy 32.752792 -33.65881) (xy 32.753282 -33.628842) (xy 32.761105 -33.56942)
			(xy 32.776618 -33.511527) (xy 32.799554 -33.456154) (xy 32.829521 -33.404248) (xy 32.866008 -33.356698)
			(xy 32.908388 -33.314318) (xy 32.955938 -33.277831) (xy 33.007844 -33.247864) (xy 33.063217 -33.224928)
			(xy 33.12111 -33.209415) (xy 33.180532 -33.201592) (xy 33.240468 -33.201592) (xy 33.29989 -33.209415)
			(xy 33.357783 -33.224928) (xy 33.413156 -33.247864) (xy 33.465062 -33.277831) (xy 33.512612 -33.314318)
			(xy 33.554992 -33.356698) (xy 33.591479 -33.404248) (xy 33.621446 -33.456154) (xy 33.644382 -33.511527)
			(xy 33.659895 -33.56942) (xy 33.667718 -33.628842) (xy 33.668208 -33.65881) (xy 33.668208 -34.520886)
			(xy 47.489364 -34.520886) (xy 47.489364 -33.657286) (xy 47.489854 -33.627302) (xy 47.497682 -33.567846)
			(xy 47.513203 -33.509921) (xy 47.536152 -33.454517) (xy 47.566136 -33.402583) (xy 47.602642 -33.355007)
			(xy 47.645047 -33.312602) (xy 47.692623 -33.276096) (xy 47.744557 -33.246112) (xy 47.799961 -33.223163)
			(xy 47.857886 -33.207642) (xy 47.917342 -33.199814) (xy 47.97731 -33.199814) (xy 48.036766 -33.207642)
			(xy 48.094691 -33.223163) (xy 48.150095 -33.246112) (xy 48.202029 -33.276096) (xy 48.249605 -33.312602)
			(xy 48.29201 -33.355007) (xy 48.328516 -33.402583) (xy 48.3585 -33.454517) (xy 48.381449 -33.509921)
			(xy 48.39697 -33.567846) (xy 48.404798 -33.627302) (xy 48.405288 -33.657286) (xy 48.405288 -34.520886)
			(xy 48.405263 -34.52241) (xy 58.75274 -34.52241) (xy 58.75274 -33.65881) (xy 58.75323 -33.628842)
			(xy 58.761053 -33.56942) (xy 58.776566 -33.511527) (xy 58.799502 -33.456154) (xy 58.829469 -33.404248)
			(xy 58.865956 -33.356698) (xy 58.908336 -33.314318) (xy 58.955886 -33.277831) (xy 59.007792 -33.247864)
			(xy 59.063165 -33.224928) (xy 59.121058 -33.209415) (xy 59.18048 -33.201592) (xy 59.240416 -33.201592)
			(xy 59.299838 -33.209415) (xy 59.357731 -33.224928) (xy 59.413104 -33.247864) (xy 59.46501 -33.277831)
			(xy 59.51256 -33.314318) (xy 59.55494 -33.356698) (xy 59.591427 -33.404248) (xy 59.621394 -33.456154)
			(xy 59.64433 -33.511527) (xy 59.659843 -33.56942) (xy 59.667666 -33.628842) (xy 59.668156 -33.65881)
			(xy 59.668156 -34.520886) (xy 73.489312 -34.520886) (xy 73.489312 -33.657286) (xy 73.489802 -33.627302)
			(xy 73.49763 -33.567846) (xy 73.513151 -33.509921) (xy 73.5361 -33.454517) (xy 73.566084 -33.402583)
			(xy 73.60259 -33.355007) (xy 73.644995 -33.312602) (xy 73.692571 -33.276096) (xy 73.744505 -33.246112)
			(xy 73.799909 -33.223163) (xy 73.857834 -33.207642) (xy 73.91729 -33.199814) (xy 73.977258 -33.199814)
			(xy 74.036714 -33.207642) (xy 74.094639 -33.223163) (xy 74.150043 -33.246112) (xy 74.201977 -33.276096)
			(xy 74.249553 -33.312602) (xy 74.291958 -33.355007) (xy 74.328464 -33.402583) (xy 74.358448 -33.454517)
			(xy 74.381397 -33.509921) (xy 74.396918 -33.567846) (xy 74.404746 -33.627302) (xy 74.405236 -33.657286)
			(xy 74.405236 -34.520886) (xy 74.405211 -34.52241) (xy 84.752688 -34.52241) (xy 84.752688 -33.65881)
			(xy 84.753178 -33.628842) (xy 84.761001 -33.56942) (xy 84.776514 -33.511527) (xy 84.79945 -33.456154)
			(xy 84.829417 -33.404248) (xy 84.865904 -33.356698) (xy 84.908284 -33.314318) (xy 84.955834 -33.277831)
			(xy 85.00774 -33.247864) (xy 85.063113 -33.224928) (xy 85.121006 -33.209415) (xy 85.180428 -33.201592)
			(xy 85.240364 -33.201592) (xy 85.299786 -33.209415) (xy 85.357679 -33.224928) (xy 85.413052 -33.247864)
			(xy 85.464958 -33.277831) (xy 85.512508 -33.314318) (xy 85.554888 -33.356698) (xy 85.591375 -33.404248)
			(xy 85.621342 -33.456154) (xy 85.644278 -33.511527) (xy 85.659791 -33.56942) (xy 85.667614 -33.628842)
			(xy 85.668104 -33.65881) (xy 85.668104 -34.520886) (xy 99.48926 -34.520886) (xy 99.48926 -33.657286)
			(xy 99.48975 -33.627302) (xy 99.497578 -33.567846) (xy 99.513099 -33.509921) (xy 99.536048 -33.454517)
			(xy 99.566032 -33.402583) (xy 99.602538 -33.355007) (xy 99.644943 -33.312602) (xy 99.692519 -33.276096)
			(xy 99.744453 -33.246112) (xy 99.799857 -33.223163) (xy 99.857782 -33.207642) (xy 99.917238 -33.199814)
			(xy 99.977206 -33.199814) (xy 100.036662 -33.207642) (xy 100.094587 -33.223163) (xy 100.149991 -33.246112)
			(xy 100.201925 -33.276096) (xy 100.249501 -33.312602) (xy 100.291906 -33.355007) (xy 100.328412 -33.402583)
			(xy 100.358396 -33.454517) (xy 100.381345 -33.509921) (xy 100.396866 -33.567846) (xy 100.404694 -33.627302)
			(xy 100.405184 -33.657286) (xy 100.405184 -34.520886) (xy 100.405159 -34.52241) (xy 122.852688 -34.52241)
			(xy 122.852688 -33.65881) (xy 122.853178 -33.628826) (xy 122.861006 -33.56937) (xy 122.876527 -33.511445)
			(xy 122.899476 -33.456041) (xy 122.92946 -33.404107) (xy 122.965966 -33.356531) (xy 123.008371 -33.314126)
			(xy 123.055947 -33.27762) (xy 123.107881 -33.247636) (xy 123.163285 -33.224687) (xy 123.22121 -33.209166)
			(xy 123.280666 -33.201338) (xy 123.340634 -33.201338) (xy 123.40009 -33.209166) (xy 123.458015 -33.224687)
			(xy 123.513419 -33.247636) (xy 123.565353 -33.27762) (xy 123.612929 -33.314126) (xy 123.655334 -33.356531)
			(xy 123.69184 -33.404107) (xy 123.721824 -33.456041) (xy 123.744773 -33.511445) (xy 123.760294 -33.56937)
			(xy 123.768122 -33.628826) (xy 123.768612 -33.65881) (xy 123.768612 -34.520886) (xy 137.589768 -34.520886)
			(xy 137.589768 -33.657286) (xy 137.590258 -33.627318) (xy 137.598081 -33.567896) (xy 137.613594 -33.510003)
			(xy 137.63653 -33.45463) (xy 137.666497 -33.402724) (xy 137.702984 -33.355174) (xy 137.745364 -33.312794)
			(xy 137.792914 -33.276307) (xy 137.84482 -33.24634) (xy 137.900193 -33.223404) (xy 137.958086 -33.207891)
			(xy 138.017508 -33.200068) (xy 138.077444 -33.200068) (xy 138.136866 -33.207891) (xy 138.194759 -33.223404)
			(xy 138.250132 -33.24634) (xy 138.302038 -33.276307) (xy 138.349588 -33.312794) (xy 138.391968 -33.355174)
			(xy 138.428455 -33.402724) (xy 138.458422 -33.45463) (xy 138.481358 -33.510003) (xy 138.496871 -33.567896)
			(xy 138.504694 -33.627318) (xy 138.505184 -33.657286) (xy 138.505184 -34.520886) (xy 138.505159 -34.52241)
			(xy 148.852636 -34.52241) (xy 148.852636 -33.65881) (xy 148.853126 -33.628826) (xy 148.860954 -33.56937)
			(xy 148.876475 -33.511445) (xy 148.899424 -33.456041) (xy 148.929408 -33.404107) (xy 148.965914 -33.356531)
			(xy 149.008319 -33.314126) (xy 149.055895 -33.27762) (xy 149.107829 -33.247636) (xy 149.163233 -33.224687)
			(xy 149.221158 -33.209166) (xy 149.280614 -33.201338) (xy 149.340582 -33.201338) (xy 149.400038 -33.209166)
			(xy 149.457963 -33.224687) (xy 149.513367 -33.247636) (xy 149.565301 -33.27762) (xy 149.612877 -33.314126)
			(xy 149.655282 -33.356531) (xy 149.691788 -33.404107) (xy 149.721772 -33.456041) (xy 149.744721 -33.511445)
			(xy 149.760242 -33.56937) (xy 149.76807 -33.628826) (xy 149.76856 -33.65881) (xy 149.76856 -34.520886)
			(xy 163.589716 -34.520886) (xy 163.589716 -33.657286) (xy 163.590206 -33.627318) (xy 163.598029 -33.567896)
			(xy 163.613542 -33.510003) (xy 163.636478 -33.45463) (xy 163.666445 -33.402724) (xy 163.702932 -33.355174)
			(xy 163.745312 -33.312794) (xy 163.792862 -33.276307) (xy 163.844768 -33.24634) (xy 163.900141 -33.223404)
			(xy 163.958034 -33.207891) (xy 164.017456 -33.200068) (xy 164.077392 -33.200068) (xy 164.136814 -33.207891)
			(xy 164.194707 -33.223404) (xy 164.25008 -33.24634) (xy 164.301986 -33.276307) (xy 164.349536 -33.312794)
			(xy 164.391916 -33.355174) (xy 164.428403 -33.402724) (xy 164.45837 -33.45463) (xy 164.481306 -33.510003)
			(xy 164.496819 -33.567896) (xy 164.504642 -33.627318) (xy 164.505132 -33.657286) (xy 164.505132 -34.520886)
			(xy 164.505107 -34.52241) (xy 174.852584 -34.52241) (xy 174.852584 -33.65881) (xy 174.853074 -33.628826)
			(xy 174.860902 -33.56937) (xy 174.876423 -33.511445) (xy 174.899372 -33.456041) (xy 174.929356 -33.404107)
			(xy 174.965862 -33.356531) (xy 175.008267 -33.314126) (xy 175.055843 -33.27762) (xy 175.107777 -33.247636)
			(xy 175.163181 -33.224687) (xy 175.221106 -33.209166) (xy 175.280562 -33.201338) (xy 175.34053 -33.201338)
			(xy 175.399986 -33.209166) (xy 175.457911 -33.224687) (xy 175.513315 -33.247636) (xy 175.565249 -33.27762)
			(xy 175.612825 -33.314126) (xy 175.65523 -33.356531) (xy 175.691736 -33.404107) (xy 175.72172 -33.456041)
			(xy 175.744669 -33.511445) (xy 175.76019 -33.56937) (xy 175.768018 -33.628826) (xy 175.768508 -33.65881)
			(xy 175.768508 -34.520886) (xy 189.589664 -34.520886) (xy 189.589664 -33.657286) (xy 189.590154 -33.627318)
			(xy 189.597977 -33.567896) (xy 189.61349 -33.510003) (xy 189.636426 -33.45463) (xy 189.666393 -33.402724)
			(xy 189.70288 -33.355174) (xy 189.74526 -33.312794) (xy 189.79281 -33.276307) (xy 189.844716 -33.24634)
			(xy 189.900089 -33.223404) (xy 189.957982 -33.207891) (xy 190.017404 -33.200068) (xy 190.07734 -33.200068)
			(xy 190.136762 -33.207891) (xy 190.194655 -33.223404) (xy 190.250028 -33.24634) (xy 190.301934 -33.276307)
			(xy 190.349484 -33.312794) (xy 190.391864 -33.355174) (xy 190.428351 -33.402724) (xy 190.458318 -33.45463)
			(xy 190.481254 -33.510003) (xy 190.496767 -33.567896) (xy 190.50459 -33.627318) (xy 190.50508 -33.657286)
			(xy 190.50508 -34.520886) (xy 190.505055 -34.52241) (xy 200.852532 -34.52241) (xy 200.852532 -33.65881)
			(xy 200.853022 -33.628826) (xy 200.86085 -33.56937) (xy 200.876371 -33.511445) (xy 200.89932 -33.456041)
			(xy 200.929304 -33.404107) (xy 200.96581 -33.356531) (xy 201.008215 -33.314126) (xy 201.055791 -33.27762)
			(xy 201.107725 -33.247636) (xy 201.163129 -33.224687) (xy 201.221054 -33.209166) (xy 201.28051 -33.201338)
			(xy 201.340478 -33.201338) (xy 201.399934 -33.209166) (xy 201.457859 -33.224687) (xy 201.513263 -33.247636)
			(xy 201.565197 -33.27762) (xy 201.612773 -33.314126) (xy 201.655178 -33.356531) (xy 201.691684 -33.404107)
			(xy 201.721668 -33.456041) (xy 201.744617 -33.511445) (xy 201.760138 -33.56937) (xy 201.767966 -33.628826)
			(xy 201.768456 -33.65881) (xy 201.768456 -34.520886) (xy 215.589612 -34.520886) (xy 215.589612 -33.657286)
			(xy 215.590102 -33.627318) (xy 215.597925 -33.567896) (xy 215.613438 -33.510003) (xy 215.636374 -33.45463)
			(xy 215.666341 -33.402724) (xy 215.702828 -33.355174) (xy 215.745208 -33.312794) (xy 215.792758 -33.276307)
			(xy 215.844664 -33.24634) (xy 215.900037 -33.223404) (xy 215.95793 -33.207891) (xy 216.017352 -33.200068)
			(xy 216.077288 -33.200068) (xy 216.13671 -33.207891) (xy 216.194603 -33.223404) (xy 216.249976 -33.24634)
			(xy 216.301882 -33.276307) (xy 216.349432 -33.312794) (xy 216.391812 -33.355174) (xy 216.428299 -33.402724)
			(xy 216.458266 -33.45463) (xy 216.481202 -33.510003) (xy 216.496715 -33.567896) (xy 216.504538 -33.627318)
			(xy 216.505028 -33.657286) (xy 216.505028 -34.520886) (xy 216.505003 -34.52241) (xy 238.952532 -34.52241)
			(xy 238.952532 -33.65881) (xy 238.953022 -33.628826) (xy 238.96085 -33.56937) (xy 238.976371 -33.511445)
			(xy 238.99932 -33.456041) (xy 239.029304 -33.404107) (xy 239.06581 -33.356531) (xy 239.108215 -33.314126)
			(xy 239.155791 -33.27762) (xy 239.207725 -33.247636) (xy 239.263129 -33.224687) (xy 239.321054 -33.209166)
			(xy 239.38051 -33.201338) (xy 239.440478 -33.201338) (xy 239.499934 -33.209166) (xy 239.557859 -33.224687)
			(xy 239.613263 -33.247636) (xy 239.665197 -33.27762) (xy 239.712773 -33.314126) (xy 239.755178 -33.356531)
			(xy 239.791684 -33.404107) (xy 239.821668 -33.456041) (xy 239.844617 -33.511445) (xy 239.860138 -33.56937)
			(xy 239.867966 -33.628826) (xy 239.868456 -33.65881) (xy 239.868456 -34.520886) (xy 253.689612 -34.520886)
			(xy 253.689612 -33.657286) (xy 253.690102 -33.627318) (xy 253.697925 -33.567896) (xy 253.713438 -33.510003)
			(xy 253.736374 -33.45463) (xy 253.766341 -33.402724) (xy 253.802828 -33.355174) (xy 253.845208 -33.312794)
			(xy 253.892758 -33.276307) (xy 253.944664 -33.24634) (xy 254.000037 -33.223404) (xy 254.05793 -33.207891)
			(xy 254.117352 -33.200068) (xy 254.177288 -33.200068) (xy 254.23671 -33.207891) (xy 254.294603 -33.223404)
			(xy 254.349976 -33.24634) (xy 254.401882 -33.276307) (xy 254.449432 -33.312794) (xy 254.491812 -33.355174)
			(xy 254.528299 -33.402724) (xy 254.558266 -33.45463) (xy 254.581202 -33.510003) (xy 254.596715 -33.567896)
			(xy 254.604538 -33.627318) (xy 254.605028 -33.657286) (xy 254.605028 -34.520886) (xy 254.605003 -34.52241)
			(xy 264.95248 -34.52241) (xy 264.95248 -33.65881) (xy 264.95297 -33.628826) (xy 264.960798 -33.56937)
			(xy 264.976319 -33.511445) (xy 264.999268 -33.456041) (xy 265.029252 -33.404107) (xy 265.065758 -33.356531)
			(xy 265.108163 -33.314126) (xy 265.155739 -33.27762) (xy 265.207673 -33.247636) (xy 265.263077 -33.224687)
			(xy 265.321002 -33.209166) (xy 265.380458 -33.201338) (xy 265.440426 -33.201338) (xy 265.499882 -33.209166)
			(xy 265.557807 -33.224687) (xy 265.613211 -33.247636) (xy 265.665145 -33.27762) (xy 265.712721 -33.314126)
			(xy 265.755126 -33.356531) (xy 265.791632 -33.404107) (xy 265.821616 -33.456041) (xy 265.844565 -33.511445)
			(xy 265.860086 -33.56937) (xy 265.867914 -33.628826) (xy 265.868404 -33.65881) (xy 265.868404 -34.520886)
			(xy 279.68956 -34.520886) (xy 279.68956 -33.657286) (xy 279.69005 -33.627318) (xy 279.697873 -33.567896)
			(xy 279.713386 -33.510003) (xy 279.736322 -33.45463) (xy 279.766289 -33.402724) (xy 279.802776 -33.355174)
			(xy 279.845156 -33.312794) (xy 279.892706 -33.276307) (xy 279.944612 -33.24634) (xy 279.999985 -33.223404)
			(xy 280.057878 -33.207891) (xy 280.1173 -33.200068) (xy 280.177236 -33.200068) (xy 280.236658 -33.207891)
			(xy 280.294551 -33.223404) (xy 280.349924 -33.24634) (xy 280.40183 -33.276307) (xy 280.44938 -33.312794)
			(xy 280.49176 -33.355174) (xy 280.528247 -33.402724) (xy 280.558214 -33.45463) (xy 280.58115 -33.510003)
			(xy 280.596663 -33.567896) (xy 280.604486 -33.627318) (xy 280.604976 -33.657286) (xy 280.604976 -34.520886)
			(xy 280.604951 -34.52241) (xy 290.952428 -34.52241) (xy 290.952428 -33.65881) (xy 290.952918 -33.628826)
			(xy 290.960746 -33.56937) (xy 290.976267 -33.511445) (xy 290.999216 -33.456041) (xy 291.0292 -33.404107)
			(xy 291.065706 -33.356531) (xy 291.108111 -33.314126) (xy 291.155687 -33.27762) (xy 291.207621 -33.247636)
			(xy 291.263025 -33.224687) (xy 291.32095 -33.209166) (xy 291.380406 -33.201338) (xy 291.440374 -33.201338)
			(xy 291.49983 -33.209166) (xy 291.557755 -33.224687) (xy 291.613159 -33.247636) (xy 291.665093 -33.27762)
			(xy 291.712669 -33.314126) (xy 291.755074 -33.356531) (xy 291.79158 -33.404107) (xy 291.821564 -33.456041)
			(xy 291.844513 -33.511445) (xy 291.860034 -33.56937) (xy 291.867862 -33.628826) (xy 291.868352 -33.65881)
			(xy 291.868352 -34.520886) (xy 305.689508 -34.520886) (xy 305.689508 -33.657286) (xy 305.689998 -33.627318)
			(xy 305.697821 -33.567896) (xy 305.713334 -33.510003) (xy 305.73627 -33.45463) (xy 305.766237 -33.402724)
			(xy 305.802724 -33.355174) (xy 305.845104 -33.312794) (xy 305.892654 -33.276307) (xy 305.94456 -33.24634)
			(xy 305.999933 -33.223404) (xy 306.057826 -33.207891) (xy 306.117248 -33.200068) (xy 306.177184 -33.200068)
			(xy 306.236606 -33.207891) (xy 306.294499 -33.223404) (xy 306.349872 -33.24634) (xy 306.401778 -33.276307)
			(xy 306.449328 -33.312794) (xy 306.491708 -33.355174) (xy 306.528195 -33.402724) (xy 306.558162 -33.45463)
			(xy 306.581098 -33.510003) (xy 306.596611 -33.567896) (xy 306.604434 -33.627318) (xy 306.604924 -33.657286)
			(xy 306.604924 -34.520886) (xy 306.604899 -34.52241) (xy 316.952376 -34.52241) (xy 316.952376 -33.65881)
			(xy 316.952866 -33.628826) (xy 316.960694 -33.56937) (xy 316.976215 -33.511445) (xy 316.999164 -33.456041)
			(xy 317.029148 -33.404107) (xy 317.065654 -33.356531) (xy 317.108059 -33.314126) (xy 317.155635 -33.27762)
			(xy 317.207569 -33.247636) (xy 317.262973 -33.224687) (xy 317.320898 -33.209166) (xy 317.380354 -33.201338)
			(xy 317.440322 -33.201338) (xy 317.499778 -33.209166) (xy 317.557703 -33.224687) (xy 317.613107 -33.247636)
			(xy 317.665041 -33.27762) (xy 317.712617 -33.314126) (xy 317.755022 -33.356531) (xy 317.791528 -33.404107)
			(xy 317.821512 -33.456041) (xy 317.844461 -33.511445) (xy 317.859982 -33.56937) (xy 317.86781 -33.628826)
			(xy 317.8683 -33.65881) (xy 317.8683 -34.520886) (xy 331.689456 -34.520886) (xy 331.689456 -33.657286)
			(xy 331.689946 -33.627318) (xy 331.697769 -33.567896) (xy 331.713282 -33.510003) (xy 331.736218 -33.45463)
			(xy 331.766185 -33.402724) (xy 331.802672 -33.355174) (xy 331.845052 -33.312794) (xy 331.892602 -33.276307)
			(xy 331.944508 -33.24634) (xy 331.999881 -33.223404) (xy 332.057774 -33.207891) (xy 332.117196 -33.200068)
			(xy 332.177132 -33.200068) (xy 332.236554 -33.207891) (xy 332.294447 -33.223404) (xy 332.34982 -33.24634)
			(xy 332.401726 -33.276307) (xy 332.449276 -33.312794) (xy 332.491656 -33.355174) (xy 332.528143 -33.402724)
			(xy 332.55811 -33.45463) (xy 332.581046 -33.510003) (xy 332.596559 -33.567896) (xy 332.604382 -33.627318)
			(xy 332.604872 -33.657286) (xy 332.604872 -34.520886) (xy 332.604847 -34.52241) (xy 355.052884 -34.52241)
			(xy 355.052884 -33.65881) (xy 355.053374 -33.628842) (xy 355.061197 -33.56942) (xy 355.07671 -33.511527)
			(xy 355.099646 -33.456154) (xy 355.129613 -33.404248) (xy 355.1661 -33.356698) (xy 355.20848 -33.314318)
			(xy 355.25603 -33.277831) (xy 355.307936 -33.247864) (xy 355.363309 -33.224928) (xy 355.421202 -33.209415)
			(xy 355.480624 -33.201592) (xy 355.54056 -33.201592) (xy 355.599982 -33.209415) (xy 355.657875 -33.224928)
			(xy 355.713248 -33.247864) (xy 355.765154 -33.277831) (xy 355.812704 -33.314318) (xy 355.855084 -33.356698)
			(xy 355.891571 -33.404248) (xy 355.921538 -33.456154) (xy 355.944474 -33.511527) (xy 355.959987 -33.56942)
			(xy 355.96781 -33.628842) (xy 355.9683 -33.65881) (xy 355.9683 -34.520886) (xy 369.789456 -34.520886)
			(xy 369.789456 -33.657286) (xy 369.789946 -33.627302) (xy 369.797774 -33.567846) (xy 369.813295 -33.509921)
			(xy 369.836244 -33.454517) (xy 369.866228 -33.402583) (xy 369.902734 -33.355007) (xy 369.945139 -33.312602)
			(xy 369.992715 -33.276096) (xy 370.044649 -33.246112) (xy 370.100053 -33.223163) (xy 370.157978 -33.207642)
			(xy 370.217434 -33.199814) (xy 370.277402 -33.199814) (xy 370.336858 -33.207642) (xy 370.394783 -33.223163)
			(xy 370.450187 -33.246112) (xy 370.502121 -33.276096) (xy 370.549697 -33.312602) (xy 370.592102 -33.355007)
			(xy 370.628608 -33.402583) (xy 370.658592 -33.454517) (xy 370.681541 -33.509921) (xy 370.697062 -33.567846)
			(xy 370.70489 -33.627302) (xy 370.70538 -33.657286) (xy 370.70538 -34.520886) (xy 370.705355 -34.52241)
			(xy 381.052832 -34.52241) (xy 381.052832 -33.65881) (xy 381.053322 -33.628842) (xy 381.061145 -33.56942)
			(xy 381.076658 -33.511527) (xy 381.099594 -33.456154) (xy 381.129561 -33.404248) (xy 381.166048 -33.356698)
			(xy 381.208428 -33.314318) (xy 381.255978 -33.277831) (xy 381.307884 -33.247864) (xy 381.363257 -33.224928)
			(xy 381.42115 -33.209415) (xy 381.480572 -33.201592) (xy 381.540508 -33.201592) (xy 381.59993 -33.209415)
			(xy 381.657823 -33.224928) (xy 381.713196 -33.247864) (xy 381.765102 -33.277831) (xy 381.812652 -33.314318)
			(xy 381.855032 -33.356698) (xy 381.891519 -33.404248) (xy 381.921486 -33.456154) (xy 381.944422 -33.511527)
			(xy 381.959935 -33.56942) (xy 381.967758 -33.628842) (xy 381.968248 -33.65881) (xy 381.968248 -34.520886)
			(xy 395.789404 -34.520886) (xy 395.789404 -33.657286) (xy 395.789894 -33.627302) (xy 395.797722 -33.567846)
			(xy 395.813243 -33.509921) (xy 395.836192 -33.454517) (xy 395.866176 -33.402583) (xy 395.902682 -33.355007)
			(xy 395.945087 -33.312602) (xy 395.992663 -33.276096) (xy 396.044597 -33.246112) (xy 396.100001 -33.223163)
			(xy 396.157926 -33.207642) (xy 396.217382 -33.199814) (xy 396.27735 -33.199814) (xy 396.336806 -33.207642)
			(xy 396.394731 -33.223163) (xy 396.450135 -33.246112) (xy 396.502069 -33.276096) (xy 396.549645 -33.312602)
			(xy 396.59205 -33.355007) (xy 396.628556 -33.402583) (xy 396.65854 -33.454517) (xy 396.681489 -33.509921)
			(xy 396.69701 -33.567846) (xy 396.704838 -33.627302) (xy 396.705328 -33.657286) (xy 396.705328 -34.520886)
			(xy 396.705303 -34.52241) (xy 407.05278 -34.52241) (xy 407.05278 -33.65881) (xy 407.05327 -33.628842)
			(xy 407.061093 -33.56942) (xy 407.076606 -33.511527) (xy 407.099542 -33.456154) (xy 407.129509 -33.404248)
			(xy 407.165996 -33.356698) (xy 407.208376 -33.314318) (xy 407.255926 -33.277831) (xy 407.307832 -33.247864)
			(xy 407.363205 -33.224928) (xy 407.421098 -33.209415) (xy 407.48052 -33.201592) (xy 407.540456 -33.201592)
			(xy 407.599878 -33.209415) (xy 407.657771 -33.224928) (xy 407.713144 -33.247864) (xy 407.76505 -33.277831)
			(xy 407.8126 -33.314318) (xy 407.85498 -33.356698) (xy 407.891467 -33.404248) (xy 407.921434 -33.456154)
			(xy 407.94437 -33.511527) (xy 407.959883 -33.56942) (xy 407.967706 -33.628842) (xy 407.968196 -33.65881)
			(xy 407.968196 -34.520886) (xy 421.789352 -34.520886) (xy 421.789352 -33.657286) (xy 421.789842 -33.627302)
			(xy 421.79767 -33.567846) (xy 421.813191 -33.509921) (xy 421.83614 -33.454517) (xy 421.866124 -33.402583)
			(xy 421.90263 -33.355007) (xy 421.945035 -33.312602) (xy 421.992611 -33.276096) (xy 422.044545 -33.246112)
			(xy 422.099949 -33.223163) (xy 422.157874 -33.207642) (xy 422.21733 -33.199814) (xy 422.277298 -33.199814)
			(xy 422.336754 -33.207642) (xy 422.394679 -33.223163) (xy 422.450083 -33.246112) (xy 422.502017 -33.276096)
			(xy 422.549593 -33.312602) (xy 422.591998 -33.355007) (xy 422.628504 -33.402583) (xy 422.658488 -33.454517)
			(xy 422.681437 -33.509921) (xy 422.696958 -33.567846) (xy 422.704786 -33.627302) (xy 422.705276 -33.657286)
			(xy 422.705276 -34.520886) (xy 422.705251 -34.52241) (xy 433.052728 -34.52241) (xy 433.052728 -33.65881)
			(xy 433.053218 -33.628842) (xy 433.061041 -33.56942) (xy 433.076554 -33.511527) (xy 433.09949 -33.456154)
			(xy 433.129457 -33.404248) (xy 433.165944 -33.356698) (xy 433.208324 -33.314318) (xy 433.255874 -33.277831)
			(xy 433.30778 -33.247864) (xy 433.363153 -33.224928) (xy 433.421046 -33.209415) (xy 433.480468 -33.201592)
			(xy 433.540404 -33.201592) (xy 433.599826 -33.209415) (xy 433.657719 -33.224928) (xy 433.713092 -33.247864)
			(xy 433.764998 -33.277831) (xy 433.812548 -33.314318) (xy 433.854928 -33.356698) (xy 433.891415 -33.404248)
			(xy 433.921382 -33.456154) (xy 433.944318 -33.511527) (xy 433.959831 -33.56942) (xy 433.967654 -33.628842)
			(xy 433.968144 -33.65881) (xy 433.968144 -34.520886) (xy 447.7893 -34.520886) (xy 447.7893 -33.657286)
			(xy 447.78979 -33.627302) (xy 447.797618 -33.567846) (xy 447.813139 -33.509921) (xy 447.836088 -33.454517)
			(xy 447.866072 -33.402583) (xy 447.902578 -33.355007) (xy 447.944983 -33.312602) (xy 447.992559 -33.276096)
			(xy 448.044493 -33.246112) (xy 448.099897 -33.223163) (xy 448.157822 -33.207642) (xy 448.217278 -33.199814)
			(xy 448.277246 -33.199814) (xy 448.336702 -33.207642) (xy 448.394627 -33.223163) (xy 448.450031 -33.246112)
			(xy 448.501965 -33.276096) (xy 448.549541 -33.312602) (xy 448.591946 -33.355007) (xy 448.628452 -33.402583)
			(xy 448.658436 -33.454517) (xy 448.681385 -33.509921) (xy 448.696906 -33.567846) (xy 448.704734 -33.627302)
			(xy 448.705224 -33.657286) (xy 448.705224 -34.520886) (xy 448.704734 -34.55087) (xy 448.696906 -34.610326)
			(xy 448.681385 -34.668251) (xy 448.658436 -34.723655) (xy 448.628452 -34.775589) (xy 448.591946 -34.823165)
			(xy 448.549541 -34.86557) (xy 448.501965 -34.902076) (xy 448.450031 -34.93206) (xy 448.394627 -34.955009)
			(xy 448.336702 -34.97053) (xy 448.277246 -34.978358) (xy 448.217278 -34.978358) (xy 448.157822 -34.97053)
			(xy 448.099897 -34.955009) (xy 448.044493 -34.93206) (xy 447.992559 -34.902076) (xy 447.944983 -34.86557)
			(xy 447.902578 -34.823165) (xy 447.866072 -34.775589) (xy 447.836088 -34.723655) (xy 447.813139 -34.668251)
			(xy 447.797618 -34.610326) (xy 447.78979 -34.55087) (xy 447.7893 -34.520886) (xy 433.968144 -34.520886)
			(xy 433.968144 -34.52241) (xy 433.967654 -34.552378) (xy 433.959831 -34.6118) (xy 433.944318 -34.669693)
			(xy 433.921382 -34.725066) (xy 433.891415 -34.776972) (xy 433.854928 -34.824522) (xy 433.812548 -34.866902)
			(xy 433.764998 -34.903389) (xy 433.713092 -34.933356) (xy 433.657719 -34.956292) (xy 433.599826 -34.971805)
			(xy 433.540404 -34.979628) (xy 433.480468 -34.979628) (xy 433.421046 -34.971805) (xy 433.363153 -34.956292)
			(xy 433.30778 -34.933356) (xy 433.255874 -34.903389) (xy 433.208324 -34.866902) (xy 433.165944 -34.824522)
			(xy 433.129457 -34.776972) (xy 433.09949 -34.725066) (xy 433.076554 -34.669693) (xy 433.061041 -34.6118)
			(xy 433.053218 -34.552378) (xy 433.052728 -34.52241) (xy 422.705251 -34.52241) (xy 422.704786 -34.55087)
			(xy 422.696958 -34.610326) (xy 422.681437 -34.668251) (xy 422.658488 -34.723655) (xy 422.628504 -34.775589)
			(xy 422.591998 -34.823165) (xy 422.549593 -34.86557) (xy 422.502017 -34.902076) (xy 422.450083 -34.93206)
			(xy 422.394679 -34.955009) (xy 422.336754 -34.97053) (xy 422.277298 -34.978358) (xy 422.21733 -34.978358)
			(xy 422.157874 -34.97053) (xy 422.099949 -34.955009) (xy 422.044545 -34.93206) (xy 421.992611 -34.902076)
			(xy 421.945035 -34.86557) (xy 421.90263 -34.823165) (xy 421.866124 -34.775589) (xy 421.83614 -34.723655)
			(xy 421.813191 -34.668251) (xy 421.79767 -34.610326) (xy 421.789842 -34.55087) (xy 421.789352 -34.520886)
			(xy 407.968196 -34.520886) (xy 407.968196 -34.52241) (xy 407.967706 -34.552378) (xy 407.959883 -34.6118)
			(xy 407.94437 -34.669693) (xy 407.921434 -34.725066) (xy 407.891467 -34.776972) (xy 407.85498 -34.824522)
			(xy 407.8126 -34.866902) (xy 407.76505 -34.903389) (xy 407.713144 -34.933356) (xy 407.657771 -34.956292)
			(xy 407.599878 -34.971805) (xy 407.540456 -34.979628) (xy 407.48052 -34.979628) (xy 407.421098 -34.971805)
			(xy 407.363205 -34.956292) (xy 407.307832 -34.933356) (xy 407.255926 -34.903389) (xy 407.208376 -34.866902)
			(xy 407.165996 -34.824522) (xy 407.129509 -34.776972) (xy 407.099542 -34.725066) (xy 407.076606 -34.669693)
			(xy 407.061093 -34.6118) (xy 407.05327 -34.552378) (xy 407.05278 -34.52241) (xy 396.705303 -34.52241)
			(xy 396.704838 -34.55087) (xy 396.69701 -34.610326) (xy 396.681489 -34.668251) (xy 396.65854 -34.723655)
			(xy 396.628556 -34.775589) (xy 396.59205 -34.823165) (xy 396.549645 -34.86557) (xy 396.502069 -34.902076)
			(xy 396.450135 -34.93206) (xy 396.394731 -34.955009) (xy 396.336806 -34.97053) (xy 396.27735 -34.978358)
			(xy 396.217382 -34.978358) (xy 396.157926 -34.97053) (xy 396.100001 -34.955009) (xy 396.044597 -34.93206)
			(xy 395.992663 -34.902076) (xy 395.945087 -34.86557) (xy 395.902682 -34.823165) (xy 395.866176 -34.775589)
			(xy 395.836192 -34.723655) (xy 395.813243 -34.668251) (xy 395.797722 -34.610326) (xy 395.789894 -34.55087)
			(xy 395.789404 -34.520886) (xy 381.968248 -34.520886) (xy 381.968248 -34.52241) (xy 381.967758 -34.552378)
			(xy 381.959935 -34.6118) (xy 381.944422 -34.669693) (xy 381.921486 -34.725066) (xy 381.891519 -34.776972)
			(xy 381.855032 -34.824522) (xy 381.812652 -34.866902) (xy 381.765102 -34.903389) (xy 381.713196 -34.933356)
			(xy 381.657823 -34.956292) (xy 381.59993 -34.971805) (xy 381.540508 -34.979628) (xy 381.480572 -34.979628)
			(xy 381.42115 -34.971805) (xy 381.363257 -34.956292) (xy 381.307884 -34.933356) (xy 381.255978 -34.903389)
			(xy 381.208428 -34.866902) (xy 381.166048 -34.824522) (xy 381.129561 -34.776972) (xy 381.099594 -34.725066)
			(xy 381.076658 -34.669693) (xy 381.061145 -34.6118) (xy 381.053322 -34.552378) (xy 381.052832 -34.52241)
			(xy 370.705355 -34.52241) (xy 370.70489 -34.55087) (xy 370.697062 -34.610326) (xy 370.681541 -34.668251)
			(xy 370.658592 -34.723655) (xy 370.628608 -34.775589) (xy 370.592102 -34.823165) (xy 370.549697 -34.86557)
			(xy 370.502121 -34.902076) (xy 370.450187 -34.93206) (xy 370.394783 -34.955009) (xy 370.336858 -34.97053)
			(xy 370.277402 -34.978358) (xy 370.217434 -34.978358) (xy 370.157978 -34.97053) (xy 370.100053 -34.955009)
			(xy 370.044649 -34.93206) (xy 369.992715 -34.902076) (xy 369.945139 -34.86557) (xy 369.902734 -34.823165)
			(xy 369.866228 -34.775589) (xy 369.836244 -34.723655) (xy 369.813295 -34.668251) (xy 369.797774 -34.610326)
			(xy 369.789946 -34.55087) (xy 369.789456 -34.520886) (xy 355.9683 -34.520886) (xy 355.9683 -34.52241)
			(xy 355.96781 -34.552378) (xy 355.959987 -34.6118) (xy 355.944474 -34.669693) (xy 355.921538 -34.725066)
			(xy 355.891571 -34.776972) (xy 355.855084 -34.824522) (xy 355.812704 -34.866902) (xy 355.765154 -34.903389)
			(xy 355.713248 -34.933356) (xy 355.657875 -34.956292) (xy 355.599982 -34.971805) (xy 355.54056 -34.979628)
			(xy 355.480624 -34.979628) (xy 355.421202 -34.971805) (xy 355.363309 -34.956292) (xy 355.307936 -34.933356)
			(xy 355.25603 -34.903389) (xy 355.20848 -34.866902) (xy 355.1661 -34.824522) (xy 355.129613 -34.776972)
			(xy 355.099646 -34.725066) (xy 355.07671 -34.669693) (xy 355.061197 -34.6118) (xy 355.053374 -34.552378)
			(xy 355.052884 -34.52241) (xy 332.604847 -34.52241) (xy 332.604382 -34.550854) (xy 332.596559 -34.610276)
			(xy 332.581046 -34.668169) (xy 332.55811 -34.723542) (xy 332.528143 -34.775448) (xy 332.491656 -34.822998)
			(xy 332.449276 -34.865378) (xy 332.401726 -34.901865) (xy 332.34982 -34.931832) (xy 332.294447 -34.954768)
			(xy 332.236554 -34.970281) (xy 332.177132 -34.978104) (xy 332.117196 -34.978104) (xy 332.057774 -34.970281)
			(xy 331.999881 -34.954768) (xy 331.944508 -34.931832) (xy 331.892602 -34.901865) (xy 331.845052 -34.865378)
			(xy 331.802672 -34.822998) (xy 331.766185 -34.775448) (xy 331.736218 -34.723542) (xy 331.713282 -34.668169)
			(xy 331.697769 -34.610276) (xy 331.689946 -34.550854) (xy 331.689456 -34.520886) (xy 317.8683 -34.520886)
			(xy 317.8683 -34.52241) (xy 317.86781 -34.552394) (xy 317.859982 -34.61185) (xy 317.844461 -34.669775)
			(xy 317.821512 -34.725179) (xy 317.791528 -34.777113) (xy 317.755022 -34.824689) (xy 317.712617 -34.867094)
			(xy 317.665041 -34.9036) (xy 317.613107 -34.933584) (xy 317.557703 -34.956533) (xy 317.499778 -34.972054)
			(xy 317.440322 -34.979882) (xy 317.380354 -34.979882) (xy 317.320898 -34.972054) (xy 317.262973 -34.956533)
			(xy 317.207569 -34.933584) (xy 317.155635 -34.9036) (xy 317.108059 -34.867094) (xy 317.065654 -34.824689)
			(xy 317.029148 -34.777113) (xy 316.999164 -34.725179) (xy 316.976215 -34.669775) (xy 316.960694 -34.61185)
			(xy 316.952866 -34.552394) (xy 316.952376 -34.52241) (xy 306.604899 -34.52241) (xy 306.604434 -34.550854)
			(xy 306.596611 -34.610276) (xy 306.581098 -34.668169) (xy 306.558162 -34.723542) (xy 306.528195 -34.775448)
			(xy 306.491708 -34.822998) (xy 306.449328 -34.865378) (xy 306.401778 -34.901865) (xy 306.349872 -34.931832)
			(xy 306.294499 -34.954768) (xy 306.236606 -34.970281) (xy 306.177184 -34.978104) (xy 306.117248 -34.978104)
			(xy 306.057826 -34.970281) (xy 305.999933 -34.954768) (xy 305.94456 -34.931832) (xy 305.892654 -34.901865)
			(xy 305.845104 -34.865378) (xy 305.802724 -34.822998) (xy 305.766237 -34.775448) (xy 305.73627 -34.723542)
			(xy 305.713334 -34.668169) (xy 305.697821 -34.610276) (xy 305.689998 -34.550854) (xy 305.689508 -34.520886)
			(xy 291.868352 -34.520886) (xy 291.868352 -34.52241) (xy 291.867862 -34.552394) (xy 291.860034 -34.61185)
			(xy 291.844513 -34.669775) (xy 291.821564 -34.725179) (xy 291.79158 -34.777113) (xy 291.755074 -34.824689)
			(xy 291.712669 -34.867094) (xy 291.665093 -34.9036) (xy 291.613159 -34.933584) (xy 291.557755 -34.956533)
			(xy 291.49983 -34.972054) (xy 291.440374 -34.979882) (xy 291.380406 -34.979882) (xy 291.32095 -34.972054)
			(xy 291.263025 -34.956533) (xy 291.207621 -34.933584) (xy 291.155687 -34.9036) (xy 291.108111 -34.867094)
			(xy 291.065706 -34.824689) (xy 291.0292 -34.777113) (xy 290.999216 -34.725179) (xy 290.976267 -34.669775)
			(xy 290.960746 -34.61185) (xy 290.952918 -34.552394) (xy 290.952428 -34.52241) (xy 280.604951 -34.52241)
			(xy 280.604486 -34.550854) (xy 280.596663 -34.610276) (xy 280.58115 -34.668169) (xy 280.558214 -34.723542)
			(xy 280.528247 -34.775448) (xy 280.49176 -34.822998) (xy 280.44938 -34.865378) (xy 280.40183 -34.901865)
			(xy 280.349924 -34.931832) (xy 280.294551 -34.954768) (xy 280.236658 -34.970281) (xy 280.177236 -34.978104)
			(xy 280.1173 -34.978104) (xy 280.057878 -34.970281) (xy 279.999985 -34.954768) (xy 279.944612 -34.931832)
			(xy 279.892706 -34.901865) (xy 279.845156 -34.865378) (xy 279.802776 -34.822998) (xy 279.766289 -34.775448)
			(xy 279.736322 -34.723542) (xy 279.713386 -34.668169) (xy 279.697873 -34.610276) (xy 279.69005 -34.550854)
			(xy 279.68956 -34.520886) (xy 265.868404 -34.520886) (xy 265.868404 -34.52241) (xy 265.867914 -34.552394)
			(xy 265.860086 -34.61185) (xy 265.844565 -34.669775) (xy 265.821616 -34.725179) (xy 265.791632 -34.777113)
			(xy 265.755126 -34.824689) (xy 265.712721 -34.867094) (xy 265.665145 -34.9036) (xy 265.613211 -34.933584)
			(xy 265.557807 -34.956533) (xy 265.499882 -34.972054) (xy 265.440426 -34.979882) (xy 265.380458 -34.979882)
			(xy 265.321002 -34.972054) (xy 265.263077 -34.956533) (xy 265.207673 -34.933584) (xy 265.155739 -34.9036)
			(xy 265.108163 -34.867094) (xy 265.065758 -34.824689) (xy 265.029252 -34.777113) (xy 264.999268 -34.725179)
			(xy 264.976319 -34.669775) (xy 264.960798 -34.61185) (xy 264.95297 -34.552394) (xy 264.95248 -34.52241)
			(xy 254.605003 -34.52241) (xy 254.604538 -34.550854) (xy 254.596715 -34.610276) (xy 254.581202 -34.668169)
			(xy 254.558266 -34.723542) (xy 254.528299 -34.775448) (xy 254.491812 -34.822998) (xy 254.449432 -34.865378)
			(xy 254.401882 -34.901865) (xy 254.349976 -34.931832) (xy 254.294603 -34.954768) (xy 254.23671 -34.970281)
			(xy 254.177288 -34.978104) (xy 254.117352 -34.978104) (xy 254.05793 -34.970281) (xy 254.000037 -34.954768)
			(xy 253.944664 -34.931832) (xy 253.892758 -34.901865) (xy 253.845208 -34.865378) (xy 253.802828 -34.822998)
			(xy 253.766341 -34.775448) (xy 253.736374 -34.723542) (xy 253.713438 -34.668169) (xy 253.697925 -34.610276)
			(xy 253.690102 -34.550854) (xy 253.689612 -34.520886) (xy 239.868456 -34.520886) (xy 239.868456 -34.52241)
			(xy 239.867966 -34.552394) (xy 239.860138 -34.61185) (xy 239.844617 -34.669775) (xy 239.821668 -34.725179)
			(xy 239.791684 -34.777113) (xy 239.755178 -34.824689) (xy 239.712773 -34.867094) (xy 239.665197 -34.9036)
			(xy 239.613263 -34.933584) (xy 239.557859 -34.956533) (xy 239.499934 -34.972054) (xy 239.440478 -34.979882)
			(xy 239.38051 -34.979882) (xy 239.321054 -34.972054) (xy 239.263129 -34.956533) (xy 239.207725 -34.933584)
			(xy 239.155791 -34.9036) (xy 239.108215 -34.867094) (xy 239.06581 -34.824689) (xy 239.029304 -34.777113)
			(xy 238.99932 -34.725179) (xy 238.976371 -34.669775) (xy 238.96085 -34.61185) (xy 238.953022 -34.552394)
			(xy 238.952532 -34.52241) (xy 216.505003 -34.52241) (xy 216.504538 -34.550854) (xy 216.496715 -34.610276)
			(xy 216.481202 -34.668169) (xy 216.458266 -34.723542) (xy 216.428299 -34.775448) (xy 216.391812 -34.822998)
			(xy 216.349432 -34.865378) (xy 216.301882 -34.901865) (xy 216.249976 -34.931832) (xy 216.194603 -34.954768)
			(xy 216.13671 -34.970281) (xy 216.077288 -34.978104) (xy 216.017352 -34.978104) (xy 215.95793 -34.970281)
			(xy 215.900037 -34.954768) (xy 215.844664 -34.931832) (xy 215.792758 -34.901865) (xy 215.745208 -34.865378)
			(xy 215.702828 -34.822998) (xy 215.666341 -34.775448) (xy 215.636374 -34.723542) (xy 215.613438 -34.668169)
			(xy 215.597925 -34.610276) (xy 215.590102 -34.550854) (xy 215.589612 -34.520886) (xy 201.768456 -34.520886)
			(xy 201.768456 -34.52241) (xy 201.767966 -34.552394) (xy 201.760138 -34.61185) (xy 201.744617 -34.669775)
			(xy 201.721668 -34.725179) (xy 201.691684 -34.777113) (xy 201.655178 -34.824689) (xy 201.612773 -34.867094)
			(xy 201.565197 -34.9036) (xy 201.513263 -34.933584) (xy 201.457859 -34.956533) (xy 201.399934 -34.972054)
			(xy 201.340478 -34.979882) (xy 201.28051 -34.979882) (xy 201.221054 -34.972054) (xy 201.163129 -34.956533)
			(xy 201.107725 -34.933584) (xy 201.055791 -34.9036) (xy 201.008215 -34.867094) (xy 200.96581 -34.824689)
			(xy 200.929304 -34.777113) (xy 200.89932 -34.725179) (xy 200.876371 -34.669775) (xy 200.86085 -34.61185)
			(xy 200.853022 -34.552394) (xy 200.852532 -34.52241) (xy 190.505055 -34.52241) (xy 190.50459 -34.550854)
			(xy 190.496767 -34.610276) (xy 190.481254 -34.668169) (xy 190.458318 -34.723542) (xy 190.428351 -34.775448)
			(xy 190.391864 -34.822998) (xy 190.349484 -34.865378) (xy 190.301934 -34.901865) (xy 190.250028 -34.931832)
			(xy 190.194655 -34.954768) (xy 190.136762 -34.970281) (xy 190.07734 -34.978104) (xy 190.017404 -34.978104)
			(xy 189.957982 -34.970281) (xy 189.900089 -34.954768) (xy 189.844716 -34.931832) (xy 189.79281 -34.901865)
			(xy 189.74526 -34.865378) (xy 189.70288 -34.822998) (xy 189.666393 -34.775448) (xy 189.636426 -34.723542)
			(xy 189.61349 -34.668169) (xy 189.597977 -34.610276) (xy 189.590154 -34.550854) (xy 189.589664 -34.520886)
			(xy 175.768508 -34.520886) (xy 175.768508 -34.52241) (xy 175.768018 -34.552394) (xy 175.76019 -34.61185)
			(xy 175.744669 -34.669775) (xy 175.72172 -34.725179) (xy 175.691736 -34.777113) (xy 175.65523 -34.824689)
			(xy 175.612825 -34.867094) (xy 175.565249 -34.9036) (xy 175.513315 -34.933584) (xy 175.457911 -34.956533)
			(xy 175.399986 -34.972054) (xy 175.34053 -34.979882) (xy 175.280562 -34.979882) (xy 175.221106 -34.972054)
			(xy 175.163181 -34.956533) (xy 175.107777 -34.933584) (xy 175.055843 -34.9036) (xy 175.008267 -34.867094)
			(xy 174.965862 -34.824689) (xy 174.929356 -34.777113) (xy 174.899372 -34.725179) (xy 174.876423 -34.669775)
			(xy 174.860902 -34.61185) (xy 174.853074 -34.552394) (xy 174.852584 -34.52241) (xy 164.505107 -34.52241)
			(xy 164.504642 -34.550854) (xy 164.496819 -34.610276) (xy 164.481306 -34.668169) (xy 164.45837 -34.723542)
			(xy 164.428403 -34.775448) (xy 164.391916 -34.822998) (xy 164.349536 -34.865378) (xy 164.301986 -34.901865)
			(xy 164.25008 -34.931832) (xy 164.194707 -34.954768) (xy 164.136814 -34.970281) (xy 164.077392 -34.978104)
			(xy 164.017456 -34.978104) (xy 163.958034 -34.970281) (xy 163.900141 -34.954768) (xy 163.844768 -34.931832)
			(xy 163.792862 -34.901865) (xy 163.745312 -34.865378) (xy 163.702932 -34.822998) (xy 163.666445 -34.775448)
			(xy 163.636478 -34.723542) (xy 163.613542 -34.668169) (xy 163.598029 -34.610276) (xy 163.590206 -34.550854)
			(xy 163.589716 -34.520886) (xy 149.76856 -34.520886) (xy 149.76856 -34.52241) (xy 149.76807 -34.552394)
			(xy 149.760242 -34.61185) (xy 149.744721 -34.669775) (xy 149.721772 -34.725179) (xy 149.691788 -34.777113)
			(xy 149.655282 -34.824689) (xy 149.612877 -34.867094) (xy 149.565301 -34.9036) (xy 149.513367 -34.933584)
			(xy 149.457963 -34.956533) (xy 149.400038 -34.972054) (xy 149.340582 -34.979882) (xy 149.280614 -34.979882)
			(xy 149.221158 -34.972054) (xy 149.163233 -34.956533) (xy 149.107829 -34.933584) (xy 149.055895 -34.9036)
			(xy 149.008319 -34.867094) (xy 148.965914 -34.824689) (xy 148.929408 -34.777113) (xy 148.899424 -34.725179)
			(xy 148.876475 -34.669775) (xy 148.860954 -34.61185) (xy 148.853126 -34.552394) (xy 148.852636 -34.52241)
			(xy 138.505159 -34.52241) (xy 138.504694 -34.550854) (xy 138.496871 -34.610276) (xy 138.481358 -34.668169)
			(xy 138.458422 -34.723542) (xy 138.428455 -34.775448) (xy 138.391968 -34.822998) (xy 138.349588 -34.865378)
			(xy 138.302038 -34.901865) (xy 138.250132 -34.931832) (xy 138.194759 -34.954768) (xy 138.136866 -34.970281)
			(xy 138.077444 -34.978104) (xy 138.017508 -34.978104) (xy 137.958086 -34.970281) (xy 137.900193 -34.954768)
			(xy 137.84482 -34.931832) (xy 137.792914 -34.901865) (xy 137.745364 -34.865378) (xy 137.702984 -34.822998)
			(xy 137.666497 -34.775448) (xy 137.63653 -34.723542) (xy 137.613594 -34.668169) (xy 137.598081 -34.610276)
			(xy 137.590258 -34.550854) (xy 137.589768 -34.520886) (xy 123.768612 -34.520886) (xy 123.768612 -34.52241)
			(xy 123.768122 -34.552394) (xy 123.760294 -34.61185) (xy 123.744773 -34.669775) (xy 123.721824 -34.725179)
			(xy 123.69184 -34.777113) (xy 123.655334 -34.824689) (xy 123.612929 -34.867094) (xy 123.565353 -34.9036)
			(xy 123.513419 -34.933584) (xy 123.458015 -34.956533) (xy 123.40009 -34.972054) (xy 123.340634 -34.979882)
			(xy 123.280666 -34.979882) (xy 123.22121 -34.972054) (xy 123.163285 -34.956533) (xy 123.107881 -34.933584)
			(xy 123.055947 -34.9036) (xy 123.008371 -34.867094) (xy 122.965966 -34.824689) (xy 122.92946 -34.777113)
			(xy 122.899476 -34.725179) (xy 122.876527 -34.669775) (xy 122.861006 -34.61185) (xy 122.853178 -34.552394)
			(xy 122.852688 -34.52241) (xy 100.405159 -34.52241) (xy 100.404694 -34.55087) (xy 100.396866 -34.610326)
			(xy 100.381345 -34.668251) (xy 100.358396 -34.723655) (xy 100.328412 -34.775589) (xy 100.291906 -34.823165)
			(xy 100.249501 -34.86557) (xy 100.201925 -34.902076) (xy 100.149991 -34.93206) (xy 100.094587 -34.955009)
			(xy 100.036662 -34.97053) (xy 99.977206 -34.978358) (xy 99.917238 -34.978358) (xy 99.857782 -34.97053)
			(xy 99.799857 -34.955009) (xy 99.744453 -34.93206) (xy 99.692519 -34.902076) (xy 99.644943 -34.86557)
			(xy 99.602538 -34.823165) (xy 99.566032 -34.775589) (xy 99.536048 -34.723655) (xy 99.513099 -34.668251)
			(xy 99.497578 -34.610326) (xy 99.48975 -34.55087) (xy 99.48926 -34.520886) (xy 85.668104 -34.520886)
			(xy 85.668104 -34.52241) (xy 85.667614 -34.552378) (xy 85.659791 -34.6118) (xy 85.644278 -34.669693)
			(xy 85.621342 -34.725066) (xy 85.591375 -34.776972) (xy 85.554888 -34.824522) (xy 85.512508 -34.866902)
			(xy 85.464958 -34.903389) (xy 85.413052 -34.933356) (xy 85.357679 -34.956292) (xy 85.299786 -34.971805)
			(xy 85.240364 -34.979628) (xy 85.180428 -34.979628) (xy 85.121006 -34.971805) (xy 85.063113 -34.956292)
			(xy 85.00774 -34.933356) (xy 84.955834 -34.903389) (xy 84.908284 -34.866902) (xy 84.865904 -34.824522)
			(xy 84.829417 -34.776972) (xy 84.79945 -34.725066) (xy 84.776514 -34.669693) (xy 84.761001 -34.6118)
			(xy 84.753178 -34.552378) (xy 84.752688 -34.52241) (xy 74.405211 -34.52241) (xy 74.404746 -34.55087)
			(xy 74.396918 -34.610326) (xy 74.381397 -34.668251) (xy 74.358448 -34.723655) (xy 74.328464 -34.775589)
			(xy 74.291958 -34.823165) (xy 74.249553 -34.86557) (xy 74.201977 -34.902076) (xy 74.150043 -34.93206)
			(xy 74.094639 -34.955009) (xy 74.036714 -34.97053) (xy 73.977258 -34.978358) (xy 73.91729 -34.978358)
			(xy 73.857834 -34.97053) (xy 73.799909 -34.955009) (xy 73.744505 -34.93206) (xy 73.692571 -34.902076)
			(xy 73.644995 -34.86557) (xy 73.60259 -34.823165) (xy 73.566084 -34.775589) (xy 73.5361 -34.723655)
			(xy 73.513151 -34.668251) (xy 73.49763 -34.610326) (xy 73.489802 -34.55087) (xy 73.489312 -34.520886)
			(xy 59.668156 -34.520886) (xy 59.668156 -34.52241) (xy 59.667666 -34.552378) (xy 59.659843 -34.6118)
			(xy 59.64433 -34.669693) (xy 59.621394 -34.725066) (xy 59.591427 -34.776972) (xy 59.55494 -34.824522)
			(xy 59.51256 -34.866902) (xy 59.46501 -34.903389) (xy 59.413104 -34.933356) (xy 59.357731 -34.956292)
			(xy 59.299838 -34.971805) (xy 59.240416 -34.979628) (xy 59.18048 -34.979628) (xy 59.121058 -34.971805)
			(xy 59.063165 -34.956292) (xy 59.007792 -34.933356) (xy 58.955886 -34.903389) (xy 58.908336 -34.866902)
			(xy 58.865956 -34.824522) (xy 58.829469 -34.776972) (xy 58.799502 -34.725066) (xy 58.776566 -34.669693)
			(xy 58.761053 -34.6118) (xy 58.75323 -34.552378) (xy 58.75274 -34.52241) (xy 48.405263 -34.52241)
			(xy 48.404798 -34.55087) (xy 48.39697 -34.610326) (xy 48.381449 -34.668251) (xy 48.3585 -34.723655)
			(xy 48.328516 -34.775589) (xy 48.29201 -34.823165) (xy 48.249605 -34.86557) (xy 48.202029 -34.902076)
			(xy 48.150095 -34.93206) (xy 48.094691 -34.955009) (xy 48.036766 -34.97053) (xy 47.97731 -34.978358)
			(xy 47.917342 -34.978358) (xy 47.857886 -34.97053) (xy 47.799961 -34.955009) (xy 47.744557 -34.93206)
			(xy 47.692623 -34.902076) (xy 47.645047 -34.86557) (xy 47.602642 -34.823165) (xy 47.566136 -34.775589)
			(xy 47.536152 -34.723655) (xy 47.513203 -34.668251) (xy 47.497682 -34.610326) (xy 47.489854 -34.55087)
			(xy 47.489364 -34.520886) (xy 33.668208 -34.520886) (xy 33.668208 -34.52241) (xy 33.667718 -34.552378)
			(xy 33.659895 -34.6118) (xy 33.644382 -34.669693) (xy 33.621446 -34.725066) (xy 33.591479 -34.776972)
			(xy 33.554992 -34.824522) (xy 33.512612 -34.866902) (xy 33.465062 -34.903389) (xy 33.413156 -34.933356)
			(xy 33.357783 -34.956292) (xy 33.29989 -34.971805) (xy 33.240468 -34.979628) (xy 33.180532 -34.979628)
			(xy 33.12111 -34.971805) (xy 33.063217 -34.956292) (xy 33.007844 -34.933356) (xy 32.955938 -34.903389)
			(xy 32.908388 -34.866902) (xy 32.866008 -34.824522) (xy 32.829521 -34.776972) (xy 32.799554 -34.725066)
			(xy 32.776618 -34.669693) (xy 32.761105 -34.6118) (xy 32.753282 -34.552378) (xy 32.752792 -34.52241)
			(xy 22.405315 -34.52241) (xy 22.40485 -34.55087) (xy 22.397022 -34.610326) (xy 22.381501 -34.668251)
			(xy 22.358552 -34.723655) (xy 22.328568 -34.775589) (xy 22.292062 -34.823165) (xy 22.249657 -34.86557)
			(xy 22.202081 -34.902076) (xy 22.150147 -34.93206) (xy 22.094743 -34.955009) (xy 22.036818 -34.97053)
			(xy 21.977362 -34.978358) (xy 21.917394 -34.978358) (xy 21.857938 -34.97053) (xy 21.800013 -34.955009)
			(xy 21.744609 -34.93206) (xy 21.692675 -34.902076) (xy 21.645099 -34.86557) (xy 21.602694 -34.823165)
			(xy 21.566188 -34.775589) (xy 21.536204 -34.723655) (xy 21.513255 -34.668251) (xy 21.497734 -34.610326)
			(xy 21.489906 -34.55087) (xy 21.489416 -34.520886) (xy 7.66826 -34.520886) (xy 7.66826 -34.52241)
			(xy 7.66777 -34.552378) (xy 7.659947 -34.6118) (xy 7.644434 -34.669693) (xy 7.621498 -34.725066)
			(xy 7.591531 -34.776972) (xy 7.555044 -34.824522) (xy 7.512664 -34.866902) (xy 7.465114 -34.903389)
			(xy 7.413208 -34.933356) (xy 7.357835 -34.956292) (xy 7.299942 -34.971805) (xy 7.24052 -34.979628)
			(xy 7.180584 -34.979628) (xy 7.121162 -34.971805) (xy 7.063269 -34.956292) (xy 7.007896 -34.933356)
			(xy 6.95599 -34.903389) (xy 6.90844 -34.866902) (xy 6.86606 -34.824522) (xy 6.829573 -34.776972)
			(xy 6.799606 -34.725066) (xy 6.77667 -34.669693) (xy 6.761157 -34.6118) (xy 6.753334 -34.552378)
			(xy 6.752844 -34.52241) (xy 0.509016 -34.52241) (xy 0.509016 -36.60013) (xy 11.998205 -36.60013)
			(xy 12.00221 -36.512222) (xy 12.014193 -36.425042) (xy 12.034053 -36.339313) (xy 12.061628 -36.255745)
			(xy 12.096687 -36.175031) (xy 12.13894 -36.097839) (xy 12.188038 -36.02481) (xy 12.243574 -35.956548)
			(xy 12.305086 -35.893618) (xy 12.372067 -35.836544) (xy 12.44396 -35.785796) (xy 12.520169 -35.741796)
			(xy 12.600064 -35.704909) (xy 12.682983 -35.67544) (xy 12.768238 -35.653633) (xy 12.855122 -35.639669)
			(xy 12.942916 -35.633663) (xy 13.030893 -35.635667) (xy 13.118323 -35.645662) (xy 13.204482 -35.663566)
			(xy 13.288656 -35.68923) (xy 13.370147 -35.722443) (xy 13.448281 -35.762929) (xy 13.522409 -35.810351)
			(xy 13.591917 -35.864318) (xy 13.656231 -35.924383) (xy 13.714815 -35.990047) (xy 13.767186 -36.060766)
			(xy 13.812909 -36.135954) (xy 13.851606 -36.214989) (xy 13.882955 -36.297215) (xy 13.906697 -36.381951)
			(xy 13.922635 -36.468495) (xy 13.930637 -36.55613) (xy 13.931138 -36.60013) (xy 37.998153 -36.60013)
			(xy 38.002158 -36.512222) (xy 38.014141 -36.425042) (xy 38.034001 -36.339313) (xy 38.061576 -36.255745)
			(xy 38.096635 -36.175031) (xy 38.138888 -36.097839) (xy 38.187986 -36.02481) (xy 38.243522 -35.956548)
			(xy 38.305034 -35.893618) (xy 38.372015 -35.836544) (xy 38.443908 -35.785796) (xy 38.520117 -35.741796)
			(xy 38.600012 -35.704909) (xy 38.682931 -35.67544) (xy 38.768186 -35.653633) (xy 38.85507 -35.639669)
			(xy 38.942864 -35.633663) (xy 39.030841 -35.635667) (xy 39.118271 -35.645662) (xy 39.20443 -35.663566)
			(xy 39.288604 -35.68923) (xy 39.370095 -35.722443) (xy 39.448229 -35.762929) (xy 39.522357 -35.810351)
			(xy 39.591865 -35.864318) (xy 39.656179 -35.924383) (xy 39.714763 -35.990047) (xy 39.767134 -36.060766)
			(xy 39.812857 -36.135954) (xy 39.851554 -36.214989) (xy 39.882903 -36.297215) (xy 39.906645 -36.381951)
			(xy 39.922583 -36.468495) (xy 39.930585 -36.55613) (xy 39.931086 -36.60013) (xy 63.998101 -36.60013)
			(xy 64.002106 -36.512222) (xy 64.014089 -36.425042) (xy 64.033949 -36.339313) (xy 64.061524 -36.255745)
			(xy 64.096583 -36.175031) (xy 64.138836 -36.097839) (xy 64.187934 -36.02481) (xy 64.24347 -35.956548)
			(xy 64.304982 -35.893618) (xy 64.371963 -35.836544) (xy 64.443856 -35.785796) (xy 64.520065 -35.741796)
			(xy 64.59996 -35.704909) (xy 64.682879 -35.67544) (xy 64.768134 -35.653633) (xy 64.855018 -35.639669)
			(xy 64.942812 -35.633663) (xy 65.030789 -35.635667) (xy 65.118219 -35.645662) (xy 65.204378 -35.663566)
			(xy 65.288552 -35.68923) (xy 65.370043 -35.722443) (xy 65.448177 -35.762929) (xy 65.522305 -35.810351)
			(xy 65.591813 -35.864318) (xy 65.656127 -35.924383) (xy 65.714711 -35.990047) (xy 65.767082 -36.060766)
			(xy 65.812805 -36.135954) (xy 65.851502 -36.214989) (xy 65.882851 -36.297215) (xy 65.906593 -36.381951)
			(xy 65.922531 -36.468495) (xy 65.930533 -36.55613) (xy 65.931034 -36.60013) (xy 89.998049 -36.60013)
			(xy 90.002054 -36.512222) (xy 90.014037 -36.425042) (xy 90.033897 -36.339313) (xy 90.061472 -36.255745)
			(xy 90.096531 -36.175031) (xy 90.138784 -36.097839) (xy 90.187882 -36.02481) (xy 90.243418 -35.956548)
			(xy 90.30493 -35.893618) (xy 90.371911 -35.836544) (xy 90.443804 -35.785796) (xy 90.520013 -35.741796)
			(xy 90.599908 -35.704909) (xy 90.682827 -35.67544) (xy 90.768082 -35.653633) (xy 90.854966 -35.639669)
			(xy 90.94276 -35.633663) (xy 91.030737 -35.635667) (xy 91.118167 -35.645662) (xy 91.204326 -35.663566)
			(xy 91.2885 -35.68923) (xy 91.369991 -35.722443) (xy 91.448125 -35.762929) (xy 91.522253 -35.810351)
			(xy 91.591761 -35.864318) (xy 91.656075 -35.924383) (xy 91.714659 -35.990047) (xy 91.76703 -36.060766)
			(xy 91.812753 -36.135954) (xy 91.85145 -36.214989) (xy 91.882799 -36.297215) (xy 91.906541 -36.381951)
			(xy 91.922479 -36.468495) (xy 91.930481 -36.55613) (xy 91.930982 -36.60013) (xy 128.098303 -36.60013)
			(xy 128.102308 -36.512222) (xy 128.114291 -36.425042) (xy 128.134151 -36.339313) (xy 128.161726 -36.255745)
			(xy 128.196785 -36.175031) (xy 128.239038 -36.097839) (xy 128.288136 -36.02481) (xy 128.343672 -35.956548)
			(xy 128.405184 -35.893618) (xy 128.472165 -35.836544) (xy 128.544058 -35.785796) (xy 128.620267 -35.741796)
			(xy 128.700162 -35.704909) (xy 128.783081 -35.67544) (xy 128.868336 -35.653633) (xy 128.95522 -35.639669)
			(xy 129.043014 -35.633663) (xy 129.130991 -35.635667) (xy 129.218421 -35.645662) (xy 129.30458 -35.663566)
			(xy 129.388754 -35.68923) (xy 129.470245 -35.722443) (xy 129.548379 -35.762929) (xy 129.622507 -35.810351)
			(xy 129.692015 -35.864318) (xy 129.756329 -35.924383) (xy 129.814913 -35.990047) (xy 129.867284 -36.060766)
			(xy 129.913007 -36.135954) (xy 129.951704 -36.214989) (xy 129.983053 -36.297215) (xy 130.006795 -36.381951)
			(xy 130.022733 -36.468495) (xy 130.030735 -36.55613) (xy 130.031236 -36.60013) (xy 154.098251 -36.60013)
			(xy 154.102256 -36.512222) (xy 154.114239 -36.425042) (xy 154.134099 -36.339313) (xy 154.161674 -36.255745)
			(xy 154.196733 -36.175031) (xy 154.238986 -36.097839) (xy 154.288084 -36.02481) (xy 154.34362 -35.956548)
			(xy 154.405132 -35.893618) (xy 154.472113 -35.836544) (xy 154.544006 -35.785796) (xy 154.620215 -35.741796)
			(xy 154.70011 -35.704909) (xy 154.783029 -35.67544) (xy 154.868284 -35.653633) (xy 154.955168 -35.639669)
			(xy 155.042962 -35.633663) (xy 155.130939 -35.635667) (xy 155.218369 -35.645662) (xy 155.304528 -35.663566)
			(xy 155.388702 -35.68923) (xy 155.470193 -35.722443) (xy 155.548327 -35.762929) (xy 155.622455 -35.810351)
			(xy 155.691963 -35.864318) (xy 155.756277 -35.924383) (xy 155.814861 -35.990047) (xy 155.867232 -36.060766)
			(xy 155.912955 -36.135954) (xy 155.951652 -36.214989) (xy 155.983001 -36.297215) (xy 156.006743 -36.381951)
			(xy 156.022681 -36.468495) (xy 156.030683 -36.55613) (xy 156.031184 -36.60013) (xy 180.098199 -36.60013)
			(xy 180.102204 -36.512222) (xy 180.114187 -36.425042) (xy 180.134047 -36.339313) (xy 180.161622 -36.255745)
			(xy 180.196681 -36.175031) (xy 180.238934 -36.097839) (xy 180.288032 -36.02481) (xy 180.343568 -35.956548)
			(xy 180.40508 -35.893618) (xy 180.472061 -35.836544) (xy 180.543954 -35.785796) (xy 180.620163 -35.741796)
			(xy 180.700058 -35.704909) (xy 180.782977 -35.67544) (xy 180.868232 -35.653633) (xy 180.955116 -35.639669)
			(xy 181.04291 -35.633663) (xy 181.130887 -35.635667) (xy 181.218317 -35.645662) (xy 181.304476 -35.663566)
			(xy 181.38865 -35.68923) (xy 181.470141 -35.722443) (xy 181.548275 -35.762929) (xy 181.622403 -35.810351)
			(xy 181.691911 -35.864318) (xy 181.756225 -35.924383) (xy 181.814809 -35.990047) (xy 181.86718 -36.060766)
			(xy 181.912903 -36.135954) (xy 181.9516 -36.214989) (xy 181.982949 -36.297215) (xy 182.006691 -36.381951)
			(xy 182.022629 -36.468495) (xy 182.030631 -36.55613) (xy 182.031132 -36.60013) (xy 206.098655 -36.60013)
			(xy 206.102659 -36.512245) (xy 206.114639 -36.425088) (xy 206.134494 -36.339381) (xy 206.162061 -36.255836)
			(xy 206.197111 -36.175143) (xy 206.239353 -36.097971) (xy 206.288438 -36.024961) (xy 206.343959 -35.956717)
			(xy 206.405456 -35.893804) (xy 206.472418 -35.836744) (xy 206.544292 -35.78601) (xy 206.620482 -35.742022)
			(xy 206.700356 -35.705144) (xy 206.783253 -35.675683) (xy 206.868485 -35.653881) (xy 206.955347 -35.639921)
			(xy 207.043118 -35.633917) (xy 207.131072 -35.63592) (xy 207.218479 -35.645912) (xy 207.304615 -35.663812)
			(xy 207.388767 -35.68947) (xy 207.470237 -35.722674) (xy 207.54835 -35.763148) (xy 207.622458 -35.810559)
			(xy 207.691949 -35.864512) (xy 207.756245 -35.92456) (xy 207.814814 -35.990207) (xy 207.867171 -36.060907)
			(xy 207.912883 -36.136076) (xy 207.951569 -36.21509) (xy 207.98291 -36.297295) (xy 208.006645 -36.382009)
			(xy 208.022579 -36.46853) (xy 208.030579 -36.556142) (xy 208.03108 -36.60013) (xy 244.198655 -36.60013)
			(xy 244.202659 -36.512245) (xy 244.214639 -36.425088) (xy 244.234494 -36.339381) (xy 244.262061 -36.255836)
			(xy 244.297111 -36.175143) (xy 244.339353 -36.097971) (xy 244.388438 -36.024961) (xy 244.443959 -35.956717)
			(xy 244.505456 -35.893804) (xy 244.572418 -35.836744) (xy 244.644292 -35.78601) (xy 244.720482 -35.742022)
			(xy 244.800356 -35.705144) (xy 244.883253 -35.675683) (xy 244.968485 -35.653881) (xy 245.055347 -35.639921)
			(xy 245.143118 -35.633917) (xy 245.231072 -35.63592) (xy 245.318479 -35.645912) (xy 245.404615 -35.663812)
			(xy 245.488767 -35.68947) (xy 245.570237 -35.722674) (xy 245.64835 -35.763148) (xy 245.722458 -35.810559)
			(xy 245.791949 -35.864512) (xy 245.856245 -35.92456) (xy 245.914814 -35.990207) (xy 245.967171 -36.060907)
			(xy 246.012883 -36.136076) (xy 246.051569 -36.21509) (xy 246.08291 -36.297295) (xy 246.106645 -36.382009)
			(xy 246.122579 -36.46853) (xy 246.130579 -36.556142) (xy 246.13108 -36.60013) (xy 270.198603 -36.60013)
			(xy 270.202607 -36.512245) (xy 270.214587 -36.425088) (xy 270.234442 -36.339381) (xy 270.262009 -36.255836)
			(xy 270.297059 -36.175143) (xy 270.339301 -36.097971) (xy 270.388386 -36.024961) (xy 270.443907 -35.956717)
			(xy 270.505404 -35.893804) (xy 270.572366 -35.836744) (xy 270.64424 -35.78601) (xy 270.72043 -35.742022)
			(xy 270.800304 -35.705144) (xy 270.883201 -35.675683) (xy 270.968433 -35.653881) (xy 271.055295 -35.639921)
			(xy 271.143066 -35.633917) (xy 271.23102 -35.63592) (xy 271.318427 -35.645912) (xy 271.404563 -35.663812)
			(xy 271.488715 -35.68947) (xy 271.570185 -35.722674) (xy 271.648298 -35.763148) (xy 271.722406 -35.810559)
			(xy 271.791897 -35.864512) (xy 271.856193 -35.92456) (xy 271.914762 -35.990207) (xy 271.967119 -36.060907)
			(xy 272.012831 -36.136076) (xy 272.051517 -36.21509) (xy 272.082858 -36.297295) (xy 272.106593 -36.382009)
			(xy 272.122527 -36.46853) (xy 272.130527 -36.556142) (xy 272.131028 -36.60013) (xy 296.198551 -36.60013)
			(xy 296.202555 -36.512245) (xy 296.214535 -36.425088) (xy 296.23439 -36.339381) (xy 296.261957 -36.255836)
			(xy 296.297007 -36.175143) (xy 296.339249 -36.097971) (xy 296.388334 -36.024961) (xy 296.443855 -35.956717)
			(xy 296.505352 -35.893804) (xy 296.572314 -35.836744) (xy 296.644188 -35.78601) (xy 296.720378 -35.742022)
			(xy 296.800252 -35.705144) (xy 296.883149 -35.675683) (xy 296.968381 -35.653881) (xy 297.055243 -35.639921)
			(xy 297.143014 -35.633917) (xy 297.230968 -35.63592) (xy 297.318375 -35.645912) (xy 297.404511 -35.663812)
			(xy 297.488663 -35.68947) (xy 297.570133 -35.722674) (xy 297.648246 -35.763148) (xy 297.722354 -35.810559)
			(xy 297.791845 -35.864512) (xy 297.856141 -35.92456) (xy 297.91471 -35.990207) (xy 297.967067 -36.060907)
			(xy 298.012779 -36.136076) (xy 298.051465 -36.21509) (xy 298.082806 -36.297295) (xy 298.106541 -36.382009)
			(xy 298.122475 -36.46853) (xy 298.130475 -36.556142) (xy 298.130976 -36.60013) (xy 322.197991 -36.60013)
			(xy 322.201996 -36.512222) (xy 322.213979 -36.425042) (xy 322.233839 -36.339313) (xy 322.261414 -36.255745)
			(xy 322.296473 -36.175031) (xy 322.338726 -36.097839) (xy 322.387824 -36.02481) (xy 322.44336 -35.956548)
			(xy 322.504872 -35.893618) (xy 322.571853 -35.836544) (xy 322.643746 -35.785796) (xy 322.719955 -35.741796)
			(xy 322.79985 -35.704909) (xy 322.882769 -35.67544) (xy 322.968024 -35.653633) (xy 323.054908 -35.639669)
			(xy 323.142702 -35.633663) (xy 323.230679 -35.635667) (xy 323.318109 -35.645662) (xy 323.404268 -35.663566)
			(xy 323.488442 -35.68923) (xy 323.569933 -35.722443) (xy 323.648067 -35.762929) (xy 323.722195 -35.810351)
			(xy 323.791703 -35.864318) (xy 323.856017 -35.924383) (xy 323.914601 -35.990047) (xy 323.966972 -36.060766)
			(xy 324.012695 -36.135954) (xy 324.051392 -36.214989) (xy 324.082741 -36.297215) (xy 324.106483 -36.381951)
			(xy 324.122421 -36.468495) (xy 324.130423 -36.55613) (xy 324.130924 -36.60013) (xy 360.298245 -36.60013)
			(xy 360.30225 -36.512222) (xy 360.314233 -36.425042) (xy 360.334093 -36.339313) (xy 360.361668 -36.255745)
			(xy 360.396727 -36.175031) (xy 360.43898 -36.097839) (xy 360.488078 -36.02481) (xy 360.543614 -35.956548)
			(xy 360.605126 -35.893618) (xy 360.672107 -35.836544) (xy 360.744 -35.785796) (xy 360.820209 -35.741796)
			(xy 360.900104 -35.704909) (xy 360.983023 -35.67544) (xy 361.068278 -35.653633) (xy 361.155162 -35.639669)
			(xy 361.242956 -35.633663) (xy 361.330933 -35.635667) (xy 361.418363 -35.645662) (xy 361.504522 -35.663566)
			(xy 361.588696 -35.68923) (xy 361.670187 -35.722443) (xy 361.748321 -35.762929) (xy 361.822449 -35.810351)
			(xy 361.891957 -35.864318) (xy 361.956271 -35.924383) (xy 362.014855 -35.990047) (xy 362.067226 -36.060766)
			(xy 362.112949 -36.135954) (xy 362.151646 -36.214989) (xy 362.182995 -36.297215) (xy 362.206737 -36.381951)
			(xy 362.222675 -36.468495) (xy 362.230677 -36.55613) (xy 362.231178 -36.60013) (xy 386.298193 -36.60013)
			(xy 386.302198 -36.512222) (xy 386.314181 -36.425042) (xy 386.334041 -36.339313) (xy 386.361616 -36.255745)
			(xy 386.396675 -36.175031) (xy 386.438928 -36.097839) (xy 386.488026 -36.02481) (xy 386.543562 -35.956548)
			(xy 386.605074 -35.893618) (xy 386.672055 -35.836544) (xy 386.743948 -35.785796) (xy 386.820157 -35.741796)
			(xy 386.900052 -35.704909) (xy 386.982971 -35.67544) (xy 387.068226 -35.653633) (xy 387.15511 -35.639669)
			(xy 387.242904 -35.633663) (xy 387.330881 -35.635667) (xy 387.418311 -35.645662) (xy 387.50447 -35.663566)
			(xy 387.588644 -35.68923) (xy 387.670135 -35.722443) (xy 387.748269 -35.762929) (xy 387.822397 -35.810351)
			(xy 387.891905 -35.864318) (xy 387.956219 -35.924383) (xy 388.014803 -35.990047) (xy 388.067174 -36.060766)
			(xy 388.112897 -36.135954) (xy 388.151594 -36.214989) (xy 388.182943 -36.297215) (xy 388.206685 -36.381951)
			(xy 388.222623 -36.468495) (xy 388.230625 -36.55613) (xy 388.231126 -36.60013) (xy 412.298649 -36.60013)
			(xy 412.302653 -36.512245) (xy 412.314633 -36.425088) (xy 412.334488 -36.339381) (xy 412.362055 -36.255836)
			(xy 412.397105 -36.175143) (xy 412.439347 -36.097971) (xy 412.488432 -36.024961) (xy 412.543953 -35.956717)
			(xy 412.60545 -35.893804) (xy 412.672412 -35.836744) (xy 412.744286 -35.78601) (xy 412.820476 -35.742022)
			(xy 412.90035 -35.705144) (xy 412.983247 -35.675683) (xy 413.068479 -35.653881) (xy 413.155341 -35.639921)
			(xy 413.243112 -35.633917) (xy 413.331066 -35.63592) (xy 413.418473 -35.645912) (xy 413.504609 -35.663812)
			(xy 413.588761 -35.68947) (xy 413.670231 -35.722674) (xy 413.748344 -35.763148) (xy 413.822452 -35.810559)
			(xy 413.891943 -35.864512) (xy 413.956239 -35.92456) (xy 414.014808 -35.990207) (xy 414.067165 -36.060907)
			(xy 414.112877 -36.136076) (xy 414.151563 -36.21509) (xy 414.182904 -36.297295) (xy 414.206639 -36.382009)
			(xy 414.222573 -36.46853) (xy 414.230573 -36.556142) (xy 414.231074 -36.60013) (xy 438.298597 -36.60013)
			(xy 438.302601 -36.512245) (xy 438.314581 -36.425088) (xy 438.334436 -36.339381) (xy 438.362003 -36.255836)
			(xy 438.397053 -36.175143) (xy 438.439295 -36.097971) (xy 438.48838 -36.024961) (xy 438.543901 -35.956717)
			(xy 438.605398 -35.893804) (xy 438.67236 -35.836744) (xy 438.744234 -35.78601) (xy 438.820424 -35.742022)
			(xy 438.900298 -35.705144) (xy 438.983195 -35.675683) (xy 439.068427 -35.653881) (xy 439.155289 -35.639921)
			(xy 439.24306 -35.633917) (xy 439.331014 -35.63592) (xy 439.418421 -35.645912) (xy 439.504557 -35.663812)
			(xy 439.588709 -35.68947) (xy 439.670179 -35.722674) (xy 439.748292 -35.763148) (xy 439.8224 -35.810559)
			(xy 439.891891 -35.864512) (xy 439.956187 -35.92456) (xy 440.014756 -35.990207) (xy 440.067113 -36.060907)
			(xy 440.112825 -36.136076) (xy 440.151511 -36.21509) (xy 440.182852 -36.297295) (xy 440.206587 -36.382009)
			(xy 440.222521 -36.46853) (xy 440.230521 -36.556142) (xy 440.231022 -36.60013) (xy 440.230521 -36.644118)
			(xy 440.222521 -36.73173) (xy 440.206587 -36.818251) (xy 440.182852 -36.902965) (xy 440.151511 -36.98517)
			(xy 440.112825 -37.064184) (xy 440.067113 -37.139353) (xy 440.014756 -37.210053) (xy 439.956187 -37.2757)
			(xy 439.891891 -37.335748) (xy 439.8224 -37.389701) (xy 439.748292 -37.437112) (xy 439.670179 -37.477586)
			(xy 439.588709 -37.51079) (xy 439.504557 -37.536448) (xy 439.418421 -37.554348) (xy 439.331014 -37.56434)
			(xy 439.24306 -37.566343) (xy 439.155289 -37.560339) (xy 439.068427 -37.546379) (xy 438.983195 -37.524577)
			(xy 438.900298 -37.495116) (xy 438.820424 -37.458238) (xy 438.744234 -37.41425) (xy 438.67236 -37.363516)
			(xy 438.605398 -37.306456) (xy 438.543901 -37.243543) (xy 438.48838 -37.175299) (xy 438.439295 -37.102289)
			(xy 438.397053 -37.025117) (xy 438.362003 -36.944424) (xy 438.334436 -36.860879) (xy 438.314581 -36.775172)
			(xy 438.302601 -36.688015) (xy 438.298597 -36.60013) (xy 414.231074 -36.60013) (xy 414.230573 -36.644118)
			(xy 414.222573 -36.73173) (xy 414.206639 -36.818251) (xy 414.182904 -36.902965) (xy 414.151563 -36.98517)
			(xy 414.112877 -37.064184) (xy 414.067165 -37.139353) (xy 414.014808 -37.210053) (xy 413.956239 -37.2757)
			(xy 413.891943 -37.335748) (xy 413.822452 -37.389701) (xy 413.748344 -37.437112) (xy 413.670231 -37.477586)
			(xy 413.588761 -37.51079) (xy 413.504609 -37.536448) (xy 413.418473 -37.554348) (xy 413.331066 -37.56434)
			(xy 413.243112 -37.566343) (xy 413.155341 -37.560339) (xy 413.068479 -37.546379) (xy 412.983247 -37.524577)
			(xy 412.90035 -37.495116) (xy 412.820476 -37.458238) (xy 412.744286 -37.41425) (xy 412.672412 -37.363516)
			(xy 412.60545 -37.306456) (xy 412.543953 -37.243543) (xy 412.488432 -37.175299) (xy 412.439347 -37.102289)
			(xy 412.397105 -37.025117) (xy 412.362055 -36.944424) (xy 412.334488 -36.860879) (xy 412.314633 -36.775172)
			(xy 412.302653 -36.688015) (xy 412.298649 -36.60013) (xy 388.231126 -36.60013) (xy 388.230625 -36.64413)
			(xy 388.222623 -36.731765) (xy 388.206685 -36.818309) (xy 388.182943 -36.903045) (xy 388.151594 -36.985271)
			(xy 388.112897 -37.064306) (xy 388.067174 -37.139494) (xy 388.014803 -37.210213) (xy 387.956219 -37.275877)
			(xy 387.891905 -37.335942) (xy 387.822397 -37.389909) (xy 387.748269 -37.437331) (xy 387.670135 -37.477817)
			(xy 387.588644 -37.51103) (xy 387.50447 -37.536694) (xy 387.418311 -37.554598) (xy 387.330881 -37.564593)
			(xy 387.242904 -37.566597) (xy 387.15511 -37.560591) (xy 387.068226 -37.546627) (xy 386.982971 -37.52482)
			(xy 386.900052 -37.495351) (xy 386.820157 -37.458464) (xy 386.743948 -37.414464) (xy 386.672055 -37.363716)
			(xy 386.605074 -37.306642) (xy 386.543562 -37.243712) (xy 386.488026 -37.17545) (xy 386.438928 -37.102421)
			(xy 386.396675 -37.025229) (xy 386.361616 -36.944515) (xy 386.334041 -36.860947) (xy 386.314181 -36.775218)
			(xy 386.302198 -36.688038) (xy 386.298193 -36.60013) (xy 362.231178 -36.60013) (xy 362.230677 -36.64413)
			(xy 362.222675 -36.731765) (xy 362.206737 -36.818309) (xy 362.182995 -36.903045) (xy 362.151646 -36.985271)
			(xy 362.112949 -37.064306) (xy 362.067226 -37.139494) (xy 362.014855 -37.210213) (xy 361.956271 -37.275877)
			(xy 361.891957 -37.335942) (xy 361.822449 -37.389909) (xy 361.748321 -37.437331) (xy 361.670187 -37.477817)
			(xy 361.588696 -37.51103) (xy 361.504522 -37.536694) (xy 361.418363 -37.554598) (xy 361.330933 -37.564593)
			(xy 361.242956 -37.566597) (xy 361.155162 -37.560591) (xy 361.068278 -37.546627) (xy 360.983023 -37.52482)
			(xy 360.900104 -37.495351) (xy 360.820209 -37.458464) (xy 360.744 -37.414464) (xy 360.672107 -37.363716)
			(xy 360.605126 -37.306642) (xy 360.543614 -37.243712) (xy 360.488078 -37.17545) (xy 360.43898 -37.102421)
			(xy 360.396727 -37.025229) (xy 360.361668 -36.944515) (xy 360.334093 -36.860947) (xy 360.314233 -36.775218)
			(xy 360.30225 -36.688038) (xy 360.298245 -36.60013) (xy 324.130924 -36.60013) (xy 324.130423 -36.64413)
			(xy 324.122421 -36.731765) (xy 324.106483 -36.818309) (xy 324.082741 -36.903045) (xy 324.051392 -36.985271)
			(xy 324.012695 -37.064306) (xy 323.966972 -37.139494) (xy 323.914601 -37.210213) (xy 323.856017 -37.275877)
			(xy 323.791703 -37.335942) (xy 323.722195 -37.389909) (xy 323.648067 -37.437331) (xy 323.569933 -37.477817)
			(xy 323.488442 -37.51103) (xy 323.404268 -37.536694) (xy 323.318109 -37.554598) (xy 323.230679 -37.564593)
			(xy 323.142702 -37.566597) (xy 323.054908 -37.560591) (xy 322.968024 -37.546627) (xy 322.882769 -37.52482)
			(xy 322.79985 -37.495351) (xy 322.719955 -37.458464) (xy 322.643746 -37.414464) (xy 322.571853 -37.363716)
			(xy 322.504872 -37.306642) (xy 322.44336 -37.243712) (xy 322.387824 -37.17545) (xy 322.338726 -37.102421)
			(xy 322.296473 -37.025229) (xy 322.261414 -36.944515) (xy 322.233839 -36.860947) (xy 322.213979 -36.775218)
			(xy 322.201996 -36.688038) (xy 322.197991 -36.60013) (xy 298.130976 -36.60013) (xy 298.130475 -36.644118)
			(xy 298.122475 -36.73173) (xy 298.106541 -36.818251) (xy 298.082806 -36.902965) (xy 298.051465 -36.98517)
			(xy 298.012779 -37.064184) (xy 297.967067 -37.139353) (xy 297.91471 -37.210053) (xy 297.856141 -37.2757)
			(xy 297.791845 -37.335748) (xy 297.722354 -37.389701) (xy 297.648246 -37.437112) (xy 297.570133 -37.477586)
			(xy 297.488663 -37.51079) (xy 297.404511 -37.536448) (xy 297.318375 -37.554348) (xy 297.230968 -37.56434)
			(xy 297.143014 -37.566343) (xy 297.055243 -37.560339) (xy 296.968381 -37.546379) (xy 296.883149 -37.524577)
			(xy 296.800252 -37.495116) (xy 296.720378 -37.458238) (xy 296.644188 -37.41425) (xy 296.572314 -37.363516)
			(xy 296.505352 -37.306456) (xy 296.443855 -37.243543) (xy 296.388334 -37.175299) (xy 296.339249 -37.102289)
			(xy 296.297007 -37.025117) (xy 296.261957 -36.944424) (xy 296.23439 -36.860879) (xy 296.214535 -36.775172)
			(xy 296.202555 -36.688015) (xy 296.198551 -36.60013) (xy 272.131028 -36.60013) (xy 272.130527 -36.644118)
			(xy 272.122527 -36.73173) (xy 272.106593 -36.818251) (xy 272.082858 -36.902965) (xy 272.051517 -36.98517)
			(xy 272.012831 -37.064184) (xy 271.967119 -37.139353) (xy 271.914762 -37.210053) (xy 271.856193 -37.2757)
			(xy 271.791897 -37.335748) (xy 271.722406 -37.389701) (xy 271.648298 -37.437112) (xy 271.570185 -37.477586)
			(xy 271.488715 -37.51079) (xy 271.404563 -37.536448) (xy 271.318427 -37.554348) (xy 271.23102 -37.56434)
			(xy 271.143066 -37.566343) (xy 271.055295 -37.560339) (xy 270.968433 -37.546379) (xy 270.883201 -37.524577)
			(xy 270.800304 -37.495116) (xy 270.72043 -37.458238) (xy 270.64424 -37.41425) (xy 270.572366 -37.363516)
			(xy 270.505404 -37.306456) (xy 270.443907 -37.243543) (xy 270.388386 -37.175299) (xy 270.339301 -37.102289)
			(xy 270.297059 -37.025117) (xy 270.262009 -36.944424) (xy 270.234442 -36.860879) (xy 270.214587 -36.775172)
			(xy 270.202607 -36.688015) (xy 270.198603 -36.60013) (xy 246.13108 -36.60013) (xy 246.130579 -36.644118)
			(xy 246.122579 -36.73173) (xy 246.106645 -36.818251) (xy 246.08291 -36.902965) (xy 246.051569 -36.98517)
			(xy 246.012883 -37.064184) (xy 245.967171 -37.139353) (xy 245.914814 -37.210053) (xy 245.856245 -37.2757)
			(xy 245.791949 -37.335748) (xy 245.722458 -37.389701) (xy 245.64835 -37.437112) (xy 245.570237 -37.477586)
			(xy 245.488767 -37.51079) (xy 245.404615 -37.536448) (xy 245.318479 -37.554348) (xy 245.231072 -37.56434)
			(xy 245.143118 -37.566343) (xy 245.055347 -37.560339) (xy 244.968485 -37.546379) (xy 244.883253 -37.524577)
			(xy 244.800356 -37.495116) (xy 244.720482 -37.458238) (xy 244.644292 -37.41425) (xy 244.572418 -37.363516)
			(xy 244.505456 -37.306456) (xy 244.443959 -37.243543) (xy 244.388438 -37.175299) (xy 244.339353 -37.102289)
			(xy 244.297111 -37.025117) (xy 244.262061 -36.944424) (xy 244.234494 -36.860879) (xy 244.214639 -36.775172)
			(xy 244.202659 -36.688015) (xy 244.198655 -36.60013) (xy 208.03108 -36.60013) (xy 208.030579 -36.644118)
			(xy 208.022579 -36.73173) (xy 208.006645 -36.818251) (xy 207.98291 -36.902965) (xy 207.951569 -36.98517)
			(xy 207.912883 -37.064184) (xy 207.867171 -37.139353) (xy 207.814814 -37.210053) (xy 207.756245 -37.2757)
			(xy 207.691949 -37.335748) (xy 207.622458 -37.389701) (xy 207.54835 -37.437112) (xy 207.470237 -37.477586)
			(xy 207.388767 -37.51079) (xy 207.304615 -37.536448) (xy 207.218479 -37.554348) (xy 207.131072 -37.56434)
			(xy 207.043118 -37.566343) (xy 206.955347 -37.560339) (xy 206.868485 -37.546379) (xy 206.783253 -37.524577)
			(xy 206.700356 -37.495116) (xy 206.620482 -37.458238) (xy 206.544292 -37.41425) (xy 206.472418 -37.363516)
			(xy 206.405456 -37.306456) (xy 206.343959 -37.243543) (xy 206.288438 -37.175299) (xy 206.239353 -37.102289)
			(xy 206.197111 -37.025117) (xy 206.162061 -36.944424) (xy 206.134494 -36.860879) (xy 206.114639 -36.775172)
			(xy 206.102659 -36.688015) (xy 206.098655 -36.60013) (xy 182.031132 -36.60013) (xy 182.030631 -36.64413)
			(xy 182.022629 -36.731765) (xy 182.006691 -36.818309) (xy 181.982949 -36.903045) (xy 181.9516 -36.985271)
			(xy 181.912903 -37.064306) (xy 181.86718 -37.139494) (xy 181.814809 -37.210213) (xy 181.756225 -37.275877)
			(xy 181.691911 -37.335942) (xy 181.622403 -37.389909) (xy 181.548275 -37.437331) (xy 181.470141 -37.477817)
			(xy 181.38865 -37.51103) (xy 181.304476 -37.536694) (xy 181.218317 -37.554598) (xy 181.130887 -37.564593)
			(xy 181.04291 -37.566597) (xy 180.955116 -37.560591) (xy 180.868232 -37.546627) (xy 180.782977 -37.52482)
			(xy 180.700058 -37.495351) (xy 180.620163 -37.458464) (xy 180.543954 -37.414464) (xy 180.472061 -37.363716)
			(xy 180.40508 -37.306642) (xy 180.343568 -37.243712) (xy 180.288032 -37.17545) (xy 180.238934 -37.102421)
			(xy 180.196681 -37.025229) (xy 180.161622 -36.944515) (xy 180.134047 -36.860947) (xy 180.114187 -36.775218)
			(xy 180.102204 -36.688038) (xy 180.098199 -36.60013) (xy 156.031184 -36.60013) (xy 156.030683 -36.64413)
			(xy 156.022681 -36.731765) (xy 156.006743 -36.818309) (xy 155.983001 -36.903045) (xy 155.951652 -36.985271)
			(xy 155.912955 -37.064306) (xy 155.867232 -37.139494) (xy 155.814861 -37.210213) (xy 155.756277 -37.275877)
			(xy 155.691963 -37.335942) (xy 155.622455 -37.389909) (xy 155.548327 -37.437331) (xy 155.470193 -37.477817)
			(xy 155.388702 -37.51103) (xy 155.304528 -37.536694) (xy 155.218369 -37.554598) (xy 155.130939 -37.564593)
			(xy 155.042962 -37.566597) (xy 154.955168 -37.560591) (xy 154.868284 -37.546627) (xy 154.783029 -37.52482)
			(xy 154.70011 -37.495351) (xy 154.620215 -37.458464) (xy 154.544006 -37.414464) (xy 154.472113 -37.363716)
			(xy 154.405132 -37.306642) (xy 154.34362 -37.243712) (xy 154.288084 -37.17545) (xy 154.238986 -37.102421)
			(xy 154.196733 -37.025229) (xy 154.161674 -36.944515) (xy 154.134099 -36.860947) (xy 154.114239 -36.775218)
			(xy 154.102256 -36.688038) (xy 154.098251 -36.60013) (xy 130.031236 -36.60013) (xy 130.030735 -36.64413)
			(xy 130.022733 -36.731765) (xy 130.006795 -36.818309) (xy 129.983053 -36.903045) (xy 129.951704 -36.985271)
			(xy 129.913007 -37.064306) (xy 129.867284 -37.139494) (xy 129.814913 -37.210213) (xy 129.756329 -37.275877)
			(xy 129.692015 -37.335942) (xy 129.622507 -37.389909) (xy 129.548379 -37.437331) (xy 129.470245 -37.477817)
			(xy 129.388754 -37.51103) (xy 129.30458 -37.536694) (xy 129.218421 -37.554598) (xy 129.130991 -37.564593)
			(xy 129.043014 -37.566597) (xy 128.95522 -37.560591) (xy 128.868336 -37.546627) (xy 128.783081 -37.52482)
			(xy 128.700162 -37.495351) (xy 128.620267 -37.458464) (xy 128.544058 -37.414464) (xy 128.472165 -37.363716)
			(xy 128.405184 -37.306642) (xy 128.343672 -37.243712) (xy 128.288136 -37.17545) (xy 128.239038 -37.102421)
			(xy 128.196785 -37.025229) (xy 128.161726 -36.944515) (xy 128.134151 -36.860947) (xy 128.114291 -36.775218)
			(xy 128.102308 -36.688038) (xy 128.098303 -36.60013) (xy 91.930982 -36.60013) (xy 91.930481 -36.64413)
			(xy 91.922479 -36.731765) (xy 91.906541 -36.818309) (xy 91.882799 -36.903045) (xy 91.85145 -36.985271)
			(xy 91.812753 -37.064306) (xy 91.76703 -37.139494) (xy 91.714659 -37.210213) (xy 91.656075 -37.275877)
			(xy 91.591761 -37.335942) (xy 91.522253 -37.389909) (xy 91.448125 -37.437331) (xy 91.369991 -37.477817)
			(xy 91.2885 -37.51103) (xy 91.204326 -37.536694) (xy 91.118167 -37.554598) (xy 91.030737 -37.564593)
			(xy 90.94276 -37.566597) (xy 90.854966 -37.560591) (xy 90.768082 -37.546627) (xy 90.682827 -37.52482)
			(xy 90.599908 -37.495351) (xy 90.520013 -37.458464) (xy 90.443804 -37.414464) (xy 90.371911 -37.363716)
			(xy 90.30493 -37.306642) (xy 90.243418 -37.243712) (xy 90.187882 -37.17545) (xy 90.138784 -37.102421)
			(xy 90.096531 -37.025229) (xy 90.061472 -36.944515) (xy 90.033897 -36.860947) (xy 90.014037 -36.775218)
			(xy 90.002054 -36.688038) (xy 89.998049 -36.60013) (xy 65.931034 -36.60013) (xy 65.930533 -36.64413)
			(xy 65.922531 -36.731765) (xy 65.906593 -36.818309) (xy 65.882851 -36.903045) (xy 65.851502 -36.985271)
			(xy 65.812805 -37.064306) (xy 65.767082 -37.139494) (xy 65.714711 -37.210213) (xy 65.656127 -37.275877)
			(xy 65.591813 -37.335942) (xy 65.522305 -37.389909) (xy 65.448177 -37.437331) (xy 65.370043 -37.477817)
			(xy 65.288552 -37.51103) (xy 65.204378 -37.536694) (xy 65.118219 -37.554598) (xy 65.030789 -37.564593)
			(xy 64.942812 -37.566597) (xy 64.855018 -37.560591) (xy 64.768134 -37.546627) (xy 64.682879 -37.52482)
			(xy 64.59996 -37.495351) (xy 64.520065 -37.458464) (xy 64.443856 -37.414464) (xy 64.371963 -37.363716)
			(xy 64.304982 -37.306642) (xy 64.24347 -37.243712) (xy 64.187934 -37.17545) (xy 64.138836 -37.102421)
			(xy 64.096583 -37.025229) (xy 64.061524 -36.944515) (xy 64.033949 -36.860947) (xy 64.014089 -36.775218)
			(xy 64.002106 -36.688038) (xy 63.998101 -36.60013) (xy 39.931086 -36.60013) (xy 39.930585 -36.64413)
			(xy 39.922583 -36.731765) (xy 39.906645 -36.818309) (xy 39.882903 -36.903045) (xy 39.851554 -36.985271)
			(xy 39.812857 -37.064306) (xy 39.767134 -37.139494) (xy 39.714763 -37.210213) (xy 39.656179 -37.275877)
			(xy 39.591865 -37.335942) (xy 39.522357 -37.389909) (xy 39.448229 -37.437331) (xy 39.370095 -37.477817)
			(xy 39.288604 -37.51103) (xy 39.20443 -37.536694) (xy 39.118271 -37.554598) (xy 39.030841 -37.564593)
			(xy 38.942864 -37.566597) (xy 38.85507 -37.560591) (xy 38.768186 -37.546627) (xy 38.682931 -37.52482)
			(xy 38.600012 -37.495351) (xy 38.520117 -37.458464) (xy 38.443908 -37.414464) (xy 38.372015 -37.363716)
			(xy 38.305034 -37.306642) (xy 38.243522 -37.243712) (xy 38.187986 -37.17545) (xy 38.138888 -37.102421)
			(xy 38.096635 -37.025229) (xy 38.061576 -36.944515) (xy 38.034001 -36.860947) (xy 38.014141 -36.775218)
			(xy 38.002158 -36.688038) (xy 37.998153 -36.60013) (xy 13.931138 -36.60013) (xy 13.930637 -36.64413)
			(xy 13.922635 -36.731765) (xy 13.906697 -36.818309) (xy 13.882955 -36.903045) (xy 13.851606 -36.985271)
			(xy 13.812909 -37.064306) (xy 13.767186 -37.139494) (xy 13.714815 -37.210213) (xy 13.656231 -37.275877)
			(xy 13.591917 -37.335942) (xy 13.522409 -37.389909) (xy 13.448281 -37.437331) (xy 13.370147 -37.477817)
			(xy 13.288656 -37.51103) (xy 13.204482 -37.536694) (xy 13.118323 -37.554598) (xy 13.030893 -37.564593)
			(xy 12.942916 -37.566597) (xy 12.855122 -37.560591) (xy 12.768238 -37.546627) (xy 12.682983 -37.52482)
			(xy 12.600064 -37.495351) (xy 12.520169 -37.458464) (xy 12.44396 -37.414464) (xy 12.372067 -37.363716)
			(xy 12.305086 -37.306642) (xy 12.243574 -37.243712) (xy 12.188038 -37.17545) (xy 12.13894 -37.102421)
			(xy 12.096687 -37.025229) (xy 12.061628 -36.944515) (xy 12.034053 -36.860947) (xy 12.014193 -36.775218)
			(xy 12.00221 -36.688038) (xy 11.998205 -36.60013) (xy 0.509016 -36.60013) (xy 0.509016 -58.698471)
			(xy 229.808523 -58.698471) (xy 229.808523 -58.601777) (xy 229.816508 -58.505414) (xy 229.832424 -58.410039)
			(xy 229.85616 -58.316305) (xy 229.887557 -58.22485) (xy 229.926398 -58.136301) (xy 229.972419 -58.051261)
			(xy 230.025305 -57.970313) (xy 230.084696 -57.894008) (xy 230.150184 -57.822868) (xy 230.221324 -57.75738)
			(xy 230.297629 -57.697989) (xy 230.378577 -57.645103) (xy 230.463617 -57.599082) (xy 230.552166 -57.560241)
			(xy 230.643621 -57.528844) (xy 230.737355 -57.505108) (xy 230.83273 -57.489192) (xy 230.929093 -57.481207)
			(xy 231.025787 -57.481207) (xy 231.12215 -57.489192) (xy 231.217525 -57.505108) (xy 231.311259 -57.528844)
			(xy 231.402714 -57.560241) (xy 231.491263 -57.599082) (xy 231.576303 -57.645103) (xy 231.657251 -57.697989)
			(xy 231.733556 -57.75738) (xy 231.804696 -57.822868) (xy 231.870184 -57.894008) (xy 231.929575 -57.970313)
			(xy 231.982461 -58.051261) (xy 232.028482 -58.136301) (xy 232.067323 -58.22485) (xy 232.09872 -58.316305)
			(xy 232.122456 -58.410039) (xy 232.138372 -58.505414) (xy 232.146357 -58.601777) (xy 232.146856 -58.650124)
			(xy 232.146357 -58.698471) (xy 232.138372 -58.794834) (xy 232.122456 -58.890209) (xy 232.09872 -58.983943)
			(xy 232.067323 -59.075398) (xy 232.028482 -59.163947) (xy 231.982461 -59.248987) (xy 231.929575 -59.329935)
			(xy 231.870184 -59.40624) (xy 231.804696 -59.47738) (xy 231.733556 -59.542868) (xy 231.657251 -59.602259)
			(xy 231.576303 -59.655145) (xy 231.491263 -59.701166) (xy 231.402714 -59.740007) (xy 231.311259 -59.771404)
			(xy 231.217525 -59.79514) (xy 231.12215 -59.811056) (xy 231.025787 -59.819041) (xy 230.929093 -59.819041)
			(xy 230.83273 -59.811056) (xy 230.737355 -59.79514) (xy 230.643621 -59.771404) (xy 230.552166 -59.740007)
			(xy 230.463617 -59.701166) (xy 230.378577 -59.655145) (xy 230.297629 -59.602259) (xy 230.221324 -59.542868)
			(xy 230.150184 -59.47738) (xy 230.084696 -59.40624) (xy 230.025305 -59.329935) (xy 229.972419 -59.248987)
			(xy 229.926398 -59.163947) (xy 229.887557 -59.075398) (xy 229.85616 -58.983943) (xy 229.832424 -58.890209)
			(xy 229.816508 -58.794834) (xy 229.808523 -58.698471) (xy 0.509016 -58.698471) (xy 0.509016 -60.13196)
			(xy 226.436428 -60.13196) (xy 226.436428 -59.26836) (xy 226.436918 -59.238392) (xy 226.444741 -59.17897)
			(xy 226.460254 -59.121077) (xy 226.48319 -59.065704) (xy 226.513157 -59.013798) (xy 226.549644 -58.966248)
			(xy 226.592024 -58.923868) (xy 226.639574 -58.887381) (xy 226.69148 -58.857414) (xy 226.746853 -58.834478)
			(xy 226.804746 -58.818965) (xy 226.864168 -58.811142) (xy 226.924104 -58.811142) (xy 226.983526 -58.818965)
			(xy 227.041419 -58.834478) (xy 227.096792 -58.857414) (xy 227.148698 -58.887381) (xy 227.196248 -58.923868)
			(xy 227.238628 -58.966248) (xy 227.275115 -59.013798) (xy 227.305082 -59.065704) (xy 227.328018 -59.121077)
			(xy 227.343531 -59.17897) (xy 227.351354 -59.238392) (xy 227.351844 -59.26836) (xy 227.351844 -60.13196)
			(xy 227.351354 -60.161928) (xy 227.343531 -60.22135) (xy 227.328018 -60.279243) (xy 227.305082 -60.334616)
			(xy 227.275115 -60.386522) (xy 227.238628 -60.434072) (xy 227.196248 -60.476452) (xy 227.148698 -60.512939)
			(xy 227.096792 -60.542906) (xy 227.041419 -60.565842) (xy 226.983526 -60.581355) (xy 226.924104 -60.589178)
			(xy 226.864168 -60.589178) (xy 226.804746 -60.581355) (xy 226.746853 -60.565842) (xy 226.69148 -60.542906)
			(xy 226.639574 -60.512939) (xy 226.592024 -60.476452) (xy 226.549644 -60.434072) (xy 226.513157 -60.386522)
			(xy 226.48319 -60.334616) (xy 226.460254 -60.279243) (xy 226.444741 -60.22135) (xy 226.436918 -60.161928)
			(xy 226.436428 -60.13196) (xy 0.509016 -60.13196) (xy 0.509016 -69.798271) (xy 229.808523 -69.798271)
			(xy 229.808523 -69.701577) (xy 229.816508 -69.605214) (xy 229.832424 -69.509839) (xy 229.85616 -69.416105)
			(xy 229.887557 -69.32465) (xy 229.926398 -69.236101) (xy 229.972419 -69.151061) (xy 230.025305 -69.070113)
			(xy 230.084696 -68.993808) (xy 230.150184 -68.922668) (xy 230.221324 -68.85718) (xy 230.297629 -68.797789)
			(xy 230.378577 -68.744903) (xy 230.463617 -68.698882) (xy 230.552166 -68.660041) (xy 230.643621 -68.628644)
			(xy 230.737355 -68.604908) (xy 230.83273 -68.588992) (xy 230.929093 -68.581007) (xy 231.025787 -68.581007)
			(xy 231.12215 -68.588992) (xy 231.217525 -68.604908) (xy 231.311259 -68.628644) (xy 231.402714 -68.660041)
			(xy 231.491263 -68.698882) (xy 231.576303 -68.744903) (xy 231.657251 -68.797789) (xy 231.733556 -68.85718)
			(xy 231.804696 -68.922668) (xy 231.870184 -68.993808) (xy 231.929575 -69.070113) (xy 231.982461 -69.151061)
			(xy 232.028482 -69.236101) (xy 232.067323 -69.32465) (xy 232.09872 -69.416105) (xy 232.122456 -69.509839)
			(xy 232.138372 -69.605214) (xy 232.146357 -69.701577) (xy 232.146856 -69.749924) (xy 232.146357 -69.798271)
			(xy 232.138372 -69.894634) (xy 232.122456 -69.990009) (xy 232.09872 -70.083743) (xy 232.067323 -70.175198)
			(xy 232.028482 -70.263747) (xy 231.982461 -70.348787) (xy 231.929575 -70.429735) (xy 231.870184 -70.50604)
			(xy 231.804696 -70.57718) (xy 231.733556 -70.642668) (xy 231.657251 -70.702059) (xy 231.576303 -70.754945)
			(xy 231.491263 -70.800966) (xy 231.402714 -70.839807) (xy 231.311259 -70.871204) (xy 231.217525 -70.89494)
			(xy 231.12215 -70.910856) (xy 231.025787 -70.918841) (xy 230.929093 -70.918841) (xy 230.83273 -70.910856)
			(xy 230.737355 -70.89494) (xy 230.643621 -70.871204) (xy 230.552166 -70.839807) (xy 230.463617 -70.800966)
			(xy 230.378577 -70.754945) (xy 230.297629 -70.702059) (xy 230.221324 -70.642668) (xy 230.150184 -70.57718)
			(xy 230.084696 -70.50604) (xy 230.025305 -70.429735) (xy 229.972419 -70.348787) (xy 229.926398 -70.263747)
			(xy 229.887557 -70.175198) (xy 229.85616 -70.083743) (xy 229.832424 -69.990009) (xy 229.816508 -69.894634)
			(xy 229.808523 -69.798271) (xy 0.509016 -69.798271) (xy 0.509016 -75.288385) (xy 262.150829 -75.288385)
			(xy 262.150829 -75.228415) (xy 262.158657 -75.168959) (xy 262.174178 -75.111033) (xy 262.197128 -75.055628)
			(xy 262.227114 -75.003693) (xy 262.263621 -74.956116) (xy 262.306027 -74.913712) (xy 262.353605 -74.877206)
			(xy 262.405541 -74.847222) (xy 262.460946 -74.824274) (xy 262.518872 -74.808754) (xy 262.578329 -74.800928)
			(xy 262.608314 -74.80046) (xy 263.471914 -74.80046) (xy 263.501899 -74.800907) (xy 263.561356 -74.808736)
			(xy 263.619283 -74.824259) (xy 263.674687 -74.84721) (xy 263.726623 -74.877196) (xy 263.7742 -74.913705)
			(xy 263.816604 -74.956111) (xy 263.853111 -75.003689) (xy 263.883096 -75.055625) (xy 263.906045 -75.111031)
			(xy 263.921566 -75.168958) (xy 263.929394 -75.228415) (xy 263.929394 -75.288385) (xy 263.921566 -75.347842)
			(xy 263.906045 -75.405769) (xy 263.883096 -75.461175) (xy 263.853111 -75.513111) (xy 263.816604 -75.560689)
			(xy 263.7742 -75.603095) (xy 263.726623 -75.639604) (xy 263.674687 -75.66959) (xy 263.619283 -75.692541)
			(xy 263.561356 -75.708064) (xy 263.501899 -75.715893) (xy 263.471914 -75.716384) (xy 262.608314 -75.716384)
			(xy 262.578329 -75.715872) (xy 262.518872 -75.708046) (xy 262.460946 -75.692526) (xy 262.405541 -75.669578)
			(xy 262.353605 -75.639594) (xy 262.306027 -75.603088) (xy 262.263621 -75.560684) (xy 262.227114 -75.513107)
			(xy 262.197128 -75.461172) (xy 262.174178 -75.405767) (xy 262.158657 -75.347841) (xy 262.150829 -75.288385)
			(xy 0.509016 -75.288385) (xy 0.509016 -76.826085) (xy 229.640845 -76.826085) (xy 229.640845 -76.766115)
			(xy 229.648673 -76.706658) (xy 229.664196 -76.648731) (xy 229.687147 -76.593327) (xy 229.717134 -76.541392)
			(xy 229.753643 -76.493816) (xy 229.796051 -76.451413) (xy 229.84363 -76.414908) (xy 229.895568 -76.384926)
			(xy 229.950975 -76.361981) (xy 230.008903 -76.346464) (xy 230.068361 -76.338642) (xy 230.098346 -76.338176)
			(xy 230.961946 -76.338176) (xy 230.991931 -76.338593) (xy 231.051387 -76.346426) (xy 231.109312 -76.361952)
			(xy 231.164715 -76.384906) (xy 231.216648 -76.414894) (xy 231.264223 -76.451404) (xy 231.306626 -76.493811)
			(xy 231.343131 -76.54139) (xy 231.373114 -76.593326) (xy 231.396063 -76.648732) (xy 231.411583 -76.706658)
			(xy 231.41941 -76.766115) (xy 231.41941 -76.826085) (xy 231.411583 -76.885542) (xy 231.396063 -76.943468)
			(xy 231.373114 -76.998874) (xy 231.343131 -77.05081) (xy 231.306626 -77.098389) (xy 231.264223 -77.140796)
			(xy 231.216648 -77.177306) (xy 231.164715 -77.207294) (xy 231.109312 -77.230248) (xy 231.051387 -77.245774)
			(xy 230.991931 -77.253607) (xy 230.961946 -77.2541) (xy 230.098346 -77.2541) (xy 230.068361 -77.253558)
			(xy 230.008903 -77.245736) (xy 229.950975 -77.230219) (xy 229.895568 -77.207274) (xy 229.84363 -77.177292)
			(xy 229.796051 -77.140787) (xy 229.753643 -77.098384) (xy 229.717134 -77.050808) (xy 229.687147 -76.998873)
			(xy 229.664196 -76.943469) (xy 229.648673 -76.885542) (xy 229.640845 -76.826085) (xy 0.509016 -76.826085)
			(xy 0.509016 -77.365367) (xy 105.150162 -77.365367) (xy 105.150162 -77.305433) (xy 105.157985 -77.246011)
			(xy 105.173496 -77.188119) (xy 105.19643 -77.132746) (xy 105.226396 -77.08084) (xy 105.26288 -77.03329)
			(xy 105.305258 -76.990908) (xy 105.352805 -76.954419) (xy 105.404708 -76.924449) (xy 105.460079 -76.901509)
			(xy 105.51797 -76.885993) (xy 105.577391 -76.878165) (xy 105.607358 -76.877672) (xy 106.470958 -76.877672)
			(xy 106.500928 -76.878178) (xy 106.560354 -76.885997) (xy 106.618252 -76.901506) (xy 106.67363 -76.92444)
			(xy 106.72554 -76.954406) (xy 106.773095 -76.990892) (xy 106.81548 -77.033273) (xy 106.851971 -77.080825)
			(xy 106.881942 -77.132732) (xy 106.904881 -77.188108) (xy 106.920395 -77.246004) (xy 106.928219 -77.305431)
			(xy 106.928219 -77.365367) (xy 109.150162 -77.365367) (xy 109.150162 -77.305433) (xy 109.157984 -77.246012)
			(xy 109.173495 -77.18812) (xy 109.196429 -77.132748) (xy 109.226394 -77.080843) (xy 109.262878 -77.033292)
			(xy 109.305255 -76.990911) (xy 109.352801 -76.954422) (xy 109.404703 -76.924452) (xy 109.460073 -76.901511)
			(xy 109.517963 -76.885994) (xy 109.577383 -76.878165) (xy 109.60735 -76.877672) (xy 110.47095 -76.877672)
			(xy 110.50092 -76.878178) (xy 110.560347 -76.885996) (xy 110.618246 -76.901504) (xy 110.673625 -76.924437)
			(xy 110.725536 -76.954403) (xy 110.773092 -76.990889) (xy 110.815478 -77.03327) (xy 110.851969 -77.080822)
			(xy 110.881941 -77.13273) (xy 110.90488 -77.188107) (xy 110.920395 -77.246003) (xy 110.928219 -77.30543)
			(xy 110.928219 -77.36537) (xy 110.920395 -77.424797) (xy 110.90488 -77.482693) (xy 110.881941 -77.53807)
			(xy 110.851969 -77.589978) (xy 110.815478 -77.63753) (xy 110.773092 -77.679911) (xy 110.725536 -77.716397)
			(xy 110.673625 -77.746363) (xy 110.618246 -77.769296) (xy 110.560347 -77.784804) (xy 110.50092 -77.792622)
			(xy 110.47095 -77.793088) (xy 109.60735 -77.793088) (xy 109.577383 -77.792635) (xy 109.517963 -77.784806)
			(xy 109.460073 -77.769289) (xy 109.404703 -77.746348) (xy 109.352801 -77.716378) (xy 109.305255 -77.679889)
			(xy 109.262878 -77.637508) (xy 109.226394 -77.589957) (xy 109.196429 -77.538052) (xy 109.173495 -77.48268)
			(xy 109.157984 -77.424788) (xy 109.150162 -77.365367) (xy 106.928219 -77.365367) (xy 106.928219 -77.365369)
			(xy 106.920395 -77.424796) (xy 106.904881 -77.482692) (xy 106.881942 -77.538068) (xy 106.851971 -77.589975)
			(xy 106.81548 -77.637527) (xy 106.773095 -77.679908) (xy 106.72554 -77.716394) (xy 106.67363 -77.74636)
			(xy 106.618252 -77.769294) (xy 106.560354 -77.784803) (xy 106.500928 -77.792622) (xy 106.470958 -77.793088)
			(xy 105.607358 -77.793088) (xy 105.577391 -77.792635) (xy 105.51797 -77.784807) (xy 105.460079 -77.769291)
			(xy 105.404708 -77.746351) (xy 105.352805 -77.716381) (xy 105.305258 -77.679892) (xy 105.26288 -77.63751)
			(xy 105.226396 -77.58996) (xy 105.19643 -77.538054) (xy 105.173496 -77.482681) (xy 105.157985 -77.424789)
			(xy 105.150162 -77.365367) (xy 0.509016 -77.365367) (xy 0.509016 -78.127367) (xy 107.150162 -78.127367)
			(xy 107.150162 -78.067433) (xy 107.157984 -78.008012) (xy 107.173496 -77.950119) (xy 107.19643 -77.894747)
			(xy 107.226395 -77.842842) (xy 107.262879 -77.795291) (xy 107.305256 -77.752909) (xy 107.352803 -77.716421)
			(xy 107.404706 -77.68645) (xy 107.460076 -77.66351) (xy 107.517966 -77.647993) (xy 107.577387 -77.640165)
			(xy 107.607354 -77.639672) (xy 108.470954 -77.639672) (xy 108.500924 -77.640178) (xy 108.560351 -77.647996)
			(xy 108.618249 -77.663505) (xy 108.673627 -77.686438) (xy 108.725538 -77.716405) (xy 108.773094 -77.752891)
			(xy 108.815479 -77.795272) (xy 108.85197 -77.842823) (xy 108.881941 -77.894731) (xy 108.90488 -77.950107)
			(xy 108.920395 -78.008004) (xy 108.928219 -78.06743) (xy 108.928219 -78.12737) (xy 108.920395 -78.186796)
			(xy 108.90488 -78.244693) (xy 108.881941 -78.300069) (xy 108.85197 -78.351977) (xy 108.815479 -78.399528)
			(xy 108.773093 -78.441909) (xy 108.725538 -78.478395) (xy 108.673627 -78.508362) (xy 108.618249 -78.531295)
			(xy 108.560351 -78.546804) (xy 108.500924 -78.554622) (xy 108.470954 -78.555088) (xy 107.607354 -78.555088)
			(xy 107.577387 -78.554635) (xy 107.517966 -78.546807) (xy 107.460076 -78.53129) (xy 107.404706 -78.50835)
			(xy 107.352803 -78.478379) (xy 107.305256 -78.441891) (xy 107.262879 -78.399509) (xy 107.226395 -78.351958)
			(xy 107.19643 -78.300053) (xy 107.173496 -78.244681) (xy 107.157984 -78.186788) (xy 107.150162 -78.127367)
			(xy 0.509016 -78.127367) (xy 0.509016 -79.238094) (xy 227.9777 -79.238094) (xy 227.9777 -78.374494)
			(xy 227.97819 -78.344526) (xy 227.986013 -78.285104) (xy 228.001526 -78.227211) (xy 228.024462 -78.171838)
			(xy 228.054429 -78.119932) (xy 228.090916 -78.072382) (xy 228.133296 -78.030002) (xy 228.180846 -77.993515)
			(xy 228.232752 -77.963548) (xy 228.288125 -77.940612) (xy 228.346018 -77.925099) (xy 228.40544 -77.917276)
			(xy 228.465376 -77.917276) (xy 228.524798 -77.925099) (xy 228.582691 -77.940612) (xy 228.638064 -77.963548)
			(xy 228.68997 -77.993515) (xy 228.73752 -78.030002) (xy 228.7799 -78.072382) (xy 228.816387 -78.119932)
			(xy 228.83413 -78.150664) (xy 336.40703 -78.150664) (xy 336.40703 -78.090736) (xy 336.414852 -78.031319)
			(xy 336.430363 -77.973433) (xy 336.453297 -77.918066) (xy 336.483261 -77.866166) (xy 336.519743 -77.818621)
			(xy 336.562119 -77.776245) (xy 336.609664 -77.739762) (xy 336.661564 -77.709797) (xy 336.716931 -77.686864)
			(xy 336.774817 -77.671353) (xy 336.834234 -77.66353) (xy 336.864198 -77.66304) (xy 337.727798 -77.66304)
			(xy 337.75777 -77.663413) (xy 337.817202 -77.671237) (xy 337.875104 -77.686751) (xy 337.930486 -77.709691)
			(xy 337.982399 -77.739663) (xy 338.029957 -77.776155) (xy 338.072344 -77.818542) (xy 338.108836 -77.866099)
			(xy 338.138808 -77.918013) (xy 338.161748 -77.973394) (xy 338.177263 -78.031296) (xy 338.185087 -78.090728)
			(xy 338.185087 -78.150672) (xy 338.177263 -78.210104) (xy 338.161748 -78.268006) (xy 338.138808 -78.323387)
			(xy 338.108836 -78.375301) (xy 338.072344 -78.422858) (xy 338.029957 -78.465245) (xy 337.982399 -78.501737)
			(xy 337.930486 -78.531709) (xy 337.875104 -78.554649) (xy 337.817202 -78.570163) (xy 337.75777 -78.577987)
			(xy 337.727798 -78.578456) (xy 336.864198 -78.578456) (xy 336.834234 -78.57787) (xy 336.774817 -78.570047)
			(xy 336.716931 -78.554536) (xy 336.661564 -78.531603) (xy 336.609664 -78.501638) (xy 336.562119 -78.465155)
			(xy 336.519743 -78.422779) (xy 336.483261 -78.375234) (xy 336.453297 -78.323334) (xy 336.430363 -78.267967)
			(xy 336.414852 -78.210081) (xy 336.40703 -78.150664) (xy 228.83413 -78.150664) (xy 228.846354 -78.171838)
			(xy 228.86929 -78.227211) (xy 228.884803 -78.285104) (xy 228.892626 -78.344526) (xy 228.893116 -78.374494)
			(xy 228.893116 -79.238094) (xy 228.892626 -79.268062) (xy 228.884803 -79.327484) (xy 228.86929 -79.385377)
			(xy 228.846354 -79.44075) (xy 228.816387 -79.492656) (xy 228.7799 -79.540206) (xy 228.73752 -79.582586)
			(xy 228.68997 -79.619073) (xy 228.638064 -79.64904) (xy 228.582691 -79.671976) (xy 228.524798 -79.687489)
			(xy 228.465376 -79.695312) (xy 228.40544 -79.695312) (xy 228.346018 -79.687489) (xy 228.288125 -79.671976)
			(xy 228.232752 -79.64904) (xy 228.180846 -79.619073) (xy 228.133296 -79.582586) (xy 228.090916 -79.540206)
			(xy 228.054429 -79.492656) (xy 228.024462 -79.44075) (xy 228.001526 -79.385377) (xy 227.986013 -79.327484)
			(xy 227.97819 -79.268062) (xy 227.9777 -79.238094) (xy 0.509016 -79.238094) (xy 0.509016 -80.183482)
			(xy 237.540292 -80.183482) (xy 237.540292 -79.319882) (xy 237.540782 -79.289914) (xy 237.548605 -79.230492)
			(xy 237.564118 -79.172599) (xy 237.587054 -79.117226) (xy 237.617021 -79.06532) (xy 237.653508 -79.01777)
			(xy 237.695888 -78.97539) (xy 237.743438 -78.938903) (xy 237.795344 -78.908936) (xy 237.850717 -78.886)
			(xy 237.90861 -78.870487) (xy 237.968032 -78.862664) (xy 238.027968 -78.862664) (xy 238.08739 -78.870487)
			(xy 238.145283 -78.886) (xy 238.200656 -78.908936) (xy 238.207117 -78.912666) (xy 334.407009 -78.912666)
			(xy 334.407009 -78.852734) (xy 334.414832 -78.793315) (xy 334.430343 -78.735425) (xy 334.453278 -78.680055)
			(xy 334.483244 -78.628153) (xy 334.519729 -78.580606) (xy 334.562107 -78.538227) (xy 334.609654 -78.501743)
			(xy 334.661557 -78.471777) (xy 334.716927 -78.448843) (xy 334.774817 -78.433331) (xy 334.834236 -78.425509)
			(xy 334.864202 -78.42504) (xy 335.727802 -78.42504) (xy 335.757773 -78.425434) (xy 335.817201 -78.433258)
			(xy 335.8751 -78.448773) (xy 335.930479 -78.471711) (xy 335.982389 -78.501682) (xy 336.029944 -78.538172)
			(xy 336.072329 -78.580557) (xy 336.108819 -78.628112) (xy 336.13879 -78.680023) (xy 336.161728 -78.735402)
			(xy 336.177242 -78.793301) (xy 336.185066 -78.852729) (xy 336.185066 -78.912664) (xy 338.40703 -78.912664)
			(xy 338.40703 -78.852736) (xy 338.414852 -78.79332) (xy 338.430363 -78.735433) (xy 338.453296 -78.680067)
			(xy 338.48326 -78.628167) (xy 338.519742 -78.580622) (xy 338.562118 -78.538246) (xy 338.609662 -78.501763)
			(xy 338.661561 -78.471799) (xy 338.716928 -78.448865) (xy 338.774814 -78.433353) (xy 338.83423 -78.42553)
			(xy 338.864194 -78.42504) (xy 339.727794 -78.42504) (xy 339.757766 -78.425412) (xy 339.817199 -78.433236)
			(xy 339.875101 -78.44875) (xy 339.930483 -78.47169) (xy 339.982397 -78.501662) (xy 340.029955 -78.538153)
			(xy 340.072343 -78.580541) (xy 340.108835 -78.628098) (xy 340.138808 -78.680011) (xy 340.161748 -78.735393)
			(xy 340.177263 -78.793296) (xy 340.185087 -78.852728) (xy 340.185087 -78.912672) (xy 340.177263 -78.972104)
			(xy 340.161748 -79.030007) (xy 340.138808 -79.085389) (xy 340.108835 -79.137302) (xy 340.072343 -79.184859)
			(xy 340.029955 -79.227247) (xy 339.982397 -79.263738) (xy 339.930483 -79.29371) (xy 339.875101 -79.31665)
			(xy 339.817199 -79.332164) (xy 339.757766 -79.339988) (xy 339.727794 -79.340456) (xy 338.864194 -79.340456)
			(xy 338.83423 -79.33987) (xy 338.774814 -79.332047) (xy 338.716928 -79.316535) (xy 338.661561 -79.293601)
			(xy 338.609662 -79.263637) (xy 338.562118 -79.227154) (xy 338.519742 -79.184778) (xy 338.48326 -79.137233)
			(xy 338.453296 -79.085333) (xy 338.430363 -79.029967) (xy 338.414852 -78.97208) (xy 338.40703 -78.912664)
			(xy 336.185066 -78.912664) (xy 336.185066 -78.912671) (xy 336.177242 -78.972099) (xy 336.161728 -79.029998)
			(xy 336.13879 -79.085377) (xy 336.108819 -79.137288) (xy 336.072329 -79.184843) (xy 336.029944 -79.227228)
			(xy 335.982389 -79.263718) (xy 335.930479 -79.293689) (xy 335.8751 -79.316627) (xy 335.817201 -79.332142)
			(xy 335.757773 -79.339966) (xy 335.727802 -79.340456) (xy 334.864202 -79.340456) (xy 334.834236 -79.339891)
			(xy 334.774817 -79.332069) (xy 334.716927 -79.316557) (xy 334.661557 -79.293623) (xy 334.609654 -79.263657)
			(xy 334.562107 -79.227173) (xy 334.519729 -79.184794) (xy 334.483244 -79.137247) (xy 334.453278 -79.085345)
			(xy 334.430343 -79.029975) (xy 334.414832 -78.972085) (xy 334.407009 -78.912666) (xy 238.207117 -78.912666)
			(xy 238.252562 -78.938903) (xy 238.300112 -78.97539) (xy 238.342492 -79.01777) (xy 238.378979 -79.06532)
			(xy 238.408946 -79.117226) (xy 238.431882 -79.172599) (xy 238.447395 -79.230492) (xy 238.455218 -79.289914)
			(xy 238.455708 -79.319882) (xy 238.455708 -80.183482) (xy 238.455218 -80.21345) (xy 238.447395 -80.272872)
			(xy 238.431882 -80.330765) (xy 238.408946 -80.386138) (xy 238.378979 -80.438044) (xy 238.342492 -80.485594)
			(xy 238.300112 -80.527974) (xy 238.252562 -80.564461) (xy 238.200656 -80.594428) (xy 238.145283 -80.617364)
			(xy 238.08739 -80.632877) (xy 238.027968 -80.6407) (xy 237.968032 -80.6407) (xy 237.90861 -80.632877)
			(xy 237.850717 -80.617364) (xy 237.795344 -80.594428) (xy 237.743438 -80.564461) (xy 237.695888 -80.527974)
			(xy 237.653508 -80.485594) (xy 237.617021 -80.438044) (xy 237.587054 -80.386138) (xy 237.564118 -80.330765)
			(xy 237.548605 -80.272872) (xy 237.540782 -80.21345) (xy 237.540292 -80.183482) (xy 0.509016 -80.183482)
			(xy 0.509016 -82.131916) (xy 0.5095 -82.185129) (xy 0.517108 -82.291282) (xy 0.532268 -82.396623)
			(xy 0.554903 -82.500614) (xy 0.584898 -82.602726) (xy 0.622099 -82.702438) (xy 0.666318 -82.799243)
			(xy 0.717328 -82.892647) (xy 0.774871 -82.982175) (xy 0.838652 -83.067371) (xy 0.908348 -83.147801)
			(xy 0.945642 -83.185762) (xy 2.78524 -85.025538) (xy 44.856389 -85.025538) (xy 44.856389 -84.896398)
			(xy 44.864339 -84.767503) (xy 44.880209 -84.639343) (xy 44.903938 -84.512402) (xy 44.935437 -84.387163)
			(xy 44.974586 -84.2641) (xy 45.021237 -84.143681) (xy 45.075212 -84.026362) (xy 45.136307 -83.912588)
			(xy 45.20429 -83.802791) (xy 45.278904 -83.697388) (xy 45.359865 -83.596778) (xy 45.446865 -83.501343)
			(xy 45.539576 -83.411444) (xy 45.637646 -83.327423) (xy 45.740701 -83.249599) (xy 45.848352 -83.178267)
			(xy 45.960191 -83.113697) (xy 46.075792 -83.056135) (xy 46.194717 -83.005798) (xy 46.316516 -82.962878)
			(xy 46.440726 -82.927537) (xy 46.566875 -82.89991) (xy 46.694487 -82.880101) (xy 46.823076 -82.868185)
			(xy 46.952154 -82.864209) (xy 47.081232 -82.868185) (xy 47.209821 -82.880101) (xy 47.337433 -82.89991)
			(xy 47.463582 -82.927537) (xy 47.587792 -82.962878) (xy 47.709591 -83.005798) (xy 47.828516 -83.056135)
			(xy 47.944117 -83.113697) (xy 48.055956 -83.178267) (xy 48.163607 -83.249599) (xy 48.266662 -83.327423)
			(xy 48.303507 -83.35899) (xy 116.623592 -83.35899) (xy 116.623592 -82.49539) (xy 116.624082 -82.465422)
			(xy 116.631905 -82.406) (xy 116.647418 -82.348107) (xy 116.670354 -82.292734) (xy 116.700321 -82.240828)
			(xy 116.736808 -82.193278) (xy 116.779188 -82.150898) (xy 116.826738 -82.114411) (xy 116.878644 -82.084444)
			(xy 116.934017 -82.061508) (xy 116.99191 -82.045995) (xy 117.051332 -82.038172) (xy 117.111268 -82.038172)
			(xy 117.17069 -82.045995) (xy 117.228583 -82.061508) (xy 117.283956 -82.084444) (xy 117.335862 -82.114411)
			(xy 117.383412 -82.150898) (xy 117.425792 -82.193278) (xy 117.462279 -82.240828) (xy 117.492246 -82.292734)
			(xy 117.515182 -82.348107) (xy 117.530695 -82.406) (xy 117.538518 -82.465422) (xy 117.539008 -82.49539)
			(xy 117.539008 -83.35899) (xy 117.538875 -83.367118) (xy 232.68432 -83.367118) (xy 232.68432 -82.503518)
			(xy 232.68481 -82.47355) (xy 232.692633 -82.414128) (xy 232.708146 -82.356235) (xy 232.731082 -82.300862)
			(xy 232.761049 -82.248956) (xy 232.797536 -82.201406) (xy 232.839916 -82.159026) (xy 232.887466 -82.122539)
			(xy 232.939372 -82.092572) (xy 232.994745 -82.069636) (xy 233.052638 -82.054123) (xy 233.11206 -82.0463)
			(xy 233.171996 -82.0463) (xy 233.231418 -82.054123) (xy 233.289311 -82.069636) (xy 233.344684 -82.092572)
			(xy 233.39659 -82.122539) (xy 233.44414 -82.159026) (xy 233.48652 -82.201406) (xy 233.523007 -82.248956)
			(xy 233.552974 -82.300862) (xy 233.568014 -82.337171) (xy 238.132537 -82.337171) (xy 238.132537 -82.277229)
			(xy 238.140362 -82.217799) (xy 238.155876 -82.159898) (xy 238.178816 -82.104519) (xy 238.208788 -82.052607)
			(xy 238.24528 -82.005052) (xy 238.287667 -81.962667) (xy 238.335224 -81.926177) (xy 238.387137 -81.896207)
			(xy 238.442517 -81.87327) (xy 238.500418 -81.857758) (xy 238.559849 -81.849936) (xy 238.58982 -81.849468)
			(xy 239.45342 -81.849468) (xy 239.483385 -81.850007) (xy 239.542803 -81.857832) (xy 239.600691 -81.873345)
			(xy 239.656058 -81.896282) (xy 239.707959 -81.926248) (xy 239.755504 -81.962733) (xy 239.769238 -81.976468)
			(xy 273.798284 -81.976468) (xy 273.798284 -81.112868) (xy 273.798774 -81.0829) (xy 273.806597 -81.023478)
			(xy 273.82211 -80.965585) (xy 273.845046 -80.910212) (xy 273.875013 -80.858306) (xy 273.9115 -80.810756)
			(xy 273.95388 -80.768376) (xy 274.00143 -80.731889) (xy 274.053336 -80.701922) (xy 274.108709 -80.678986)
			(xy 274.166602 -80.663473) (xy 274.226024 -80.65565) (xy 274.28596 -80.65565) (xy 274.345382 -80.663473)
			(xy 274.403275 -80.678986) (xy 274.458648 -80.701922) (xy 274.510554 -80.731889) (xy 274.558104 -80.768376)
			(xy 274.600484 -80.810756) (xy 274.636971 -80.858306) (xy 274.666938 -80.910212) (xy 274.689874 -80.965585)
			(xy 274.705387 -81.023478) (xy 274.71321 -81.0829) (xy 274.7137 -81.112868) (xy 274.7137 -81.976468)
			(xy 274.71321 -82.006436) (xy 274.705387 -82.065858) (xy 274.689874 -82.123751) (xy 274.666938 -82.179124)
			(xy 274.636971 -82.23103) (xy 274.600484 -82.27858) (xy 274.558104 -82.32096) (xy 274.510554 -82.357447)
			(xy 274.458648 -82.387414) (xy 274.403275 -82.41035) (xy 274.345382 -82.425863) (xy 274.28596 -82.433686)
			(xy 274.226024 -82.433686) (xy 274.166602 -82.425863) (xy 274.108709 -82.41035) (xy 274.053336 -82.387414)
			(xy 274.00143 -82.357447) (xy 273.95388 -82.32096) (xy 273.9115 -82.27858) (xy 273.875013 -82.23103)
			(xy 273.845046 -82.179124) (xy 273.82211 -82.123751) (xy 273.806597 -82.065858) (xy 273.798774 -82.006436)
			(xy 273.798284 -81.976468) (xy 239.769238 -81.976468) (xy 239.79788 -82.005111) (xy 239.834363 -82.052658)
			(xy 239.864327 -82.10456) (xy 239.887261 -82.159928) (xy 239.902772 -82.217817) (xy 239.910594 -82.277235)
			(xy 239.910594 -82.337165) (xy 239.902772 -82.396583) (xy 239.887261 -82.454472) (xy 239.864327 -82.50984)
			(xy 239.834363 -82.561742) (xy 239.79788 -82.609289) (xy 239.755504 -82.651667) (xy 239.707959 -82.688152)
			(xy 239.656058 -82.718118) (xy 239.600691 -82.741055) (xy 239.542803 -82.756568) (xy 239.483385 -82.764393)
			(xy 239.45342 -82.764884) (xy 238.58982 -82.764884) (xy 238.559849 -82.764464) (xy 238.500418 -82.756642)
			(xy 238.442517 -82.74113) (xy 238.387137 -82.718193) (xy 238.335224 -82.688223) (xy 238.287667 -82.651733)
			(xy 238.24528 -82.609348) (xy 238.208788 -82.561793) (xy 238.178816 -82.509881) (xy 238.155876 -82.454502)
			(xy 238.140362 -82.396601) (xy 238.132537 -82.337171) (xy 233.568014 -82.337171) (xy 233.57591 -82.356235)
			(xy 233.591423 -82.414128) (xy 233.599246 -82.47355) (xy 233.599736 -82.503518) (xy 233.599736 -83.367118)
			(xy 233.599246 -83.397086) (xy 233.591423 -83.456508) (xy 233.57591 -83.514401) (xy 233.552974 -83.569774)
			(xy 233.523007 -83.62168) (xy 233.48652 -83.66923) (xy 233.44414 -83.71161) (xy 233.39659 -83.748097)
			(xy 233.344684 -83.778064) (xy 233.289311 -83.801) (xy 233.231418 -83.816513) (xy 233.171996 -83.824336)
			(xy 233.11206 -83.824336) (xy 233.052638 -83.816513) (xy 232.994745 -83.801) (xy 232.939372 -83.778064)
			(xy 232.887466 -83.748097) (xy 232.839916 -83.71161) (xy 232.797536 -83.66923) (xy 232.761049 -83.62168)
			(xy 232.731082 -83.569774) (xy 232.708146 -83.514401) (xy 232.692633 -83.456508) (xy 232.68481 -83.397086)
			(xy 232.68432 -83.367118) (xy 117.538875 -83.367118) (xy 117.538518 -83.388958) (xy 117.530695 -83.44838)
			(xy 117.515182 -83.506273) (xy 117.492246 -83.561646) (xy 117.462279 -83.613552) (xy 117.425792 -83.661102)
			(xy 117.383412 -83.703482) (xy 117.335862 -83.739969) (xy 117.283956 -83.769936) (xy 117.228583 -83.792872)
			(xy 117.17069 -83.808385) (xy 117.111268 -83.816208) (xy 117.051332 -83.816208) (xy 116.99191 -83.808385)
			(xy 116.934017 -83.792872) (xy 116.878644 -83.769936) (xy 116.826738 -83.739969) (xy 116.779188 -83.703482)
			(xy 116.736808 -83.661102) (xy 116.700321 -83.613552) (xy 116.670354 -83.561646) (xy 116.647418 -83.506273)
			(xy 116.631905 -83.44838) (xy 116.624082 -83.388958) (xy 116.623592 -83.35899) (xy 48.303507 -83.35899)
			(xy 48.364732 -83.411444) (xy 48.457443 -83.501343) (xy 48.544443 -83.596778) (xy 48.625404 -83.697388)
			(xy 48.700018 -83.802791) (xy 48.768001 -83.912588) (xy 48.829096 -84.026362) (xy 48.883071 -84.143681)
			(xy 48.929722 -84.2641) (xy 48.968871 -84.387163) (xy 49.00037 -84.512402) (xy 49.024099 -84.639343)
			(xy 49.039969 -84.767503) (xy 49.047919 -84.896398) (xy 49.048416 -84.960968) (xy 49.047919 -85.025538)
			(xy 49.039969 -85.154433) (xy 49.024099 -85.282593) (xy 49.009819 -85.358986) (xy 117.385592 -85.358986)
			(xy 117.385592 -84.495386) (xy 117.386082 -84.465418) (xy 117.393905 -84.405996) (xy 117.409418 -84.348103)
			(xy 117.432354 -84.29273) (xy 117.462321 -84.240824) (xy 117.498808 -84.193274) (xy 117.541188 -84.150894)
			(xy 117.588738 -84.114407) (xy 117.640644 -84.08444) (xy 117.696017 -84.061504) (xy 117.75391 -84.045991)
			(xy 117.813332 -84.038168) (xy 117.873268 -84.038168) (xy 117.93269 -84.045991) (xy 117.990583 -84.061504)
			(xy 118.045956 -84.08444) (xy 118.097862 -84.114407) (xy 118.145412 -84.150894) (xy 118.187792 -84.193274)
			(xy 118.224279 -84.240824) (xy 118.254246 -84.29273) (xy 118.277182 -84.348103) (xy 118.292695 -84.405996)
			(xy 118.300518 -84.465418) (xy 118.301008 -84.495386) (xy 118.301008 -85.358986) (xy 118.300518 -85.388954)
			(xy 118.292695 -85.448376) (xy 118.289959 -85.458587) (xy 232.264389 -85.458587) (xy 232.264389 -85.398613)
			(xy 232.272218 -85.339151) (xy 232.28774 -85.28122) (xy 232.310692 -85.225811) (xy 232.34068 -85.173871)
			(xy 232.377191 -85.126291) (xy 232.4196 -85.083883) (xy 232.467181 -85.047373) (xy 232.519122 -85.017387)
			(xy 232.574531 -84.994437) (xy 232.632463 -84.978915) (xy 232.691925 -84.971088) (xy 232.721912 -84.97062)
			(xy 233.585512 -84.97062) (xy 233.615495 -84.971147) (xy 233.674947 -84.978975) (xy 233.732868 -84.994497)
			(xy 233.788268 -85.017445) (xy 233.840199 -85.047429) (xy 233.887772 -85.083934) (xy 233.930174 -85.126337)
			(xy 233.963295 -85.169502) (xy 238.555276 -85.169502) (xy 238.555276 -84.305902) (xy 238.555766 -84.275918)
			(xy 238.563594 -84.216462) (xy 238.579115 -84.158537) (xy 238.602064 -84.103133) (xy 238.632048 -84.051199)
			(xy 238.668554 -84.003623) (xy 238.710959 -83.961218) (xy 238.758535 -83.924712) (xy 238.810469 -83.894728)
			(xy 238.865873 -83.871779) (xy 238.923798 -83.856258) (xy 238.983254 -83.84843) (xy 239.043222 -83.84843)
			(xy 239.102678 -83.856258) (xy 239.160603 -83.871779) (xy 239.216007 -83.894728) (xy 239.267941 -83.924712)
			(xy 239.315517 -83.961218) (xy 239.357922 -84.003623) (xy 239.394428 -84.051199) (xy 239.424412 -84.103133)
			(xy 239.447361 -84.158537) (xy 239.462882 -84.216462) (xy 239.46603 -84.24037) (xy 273.951192 -84.24037)
			(xy 273.951192 -83.37677) (xy 273.951682 -83.346786) (xy 273.95951 -83.28733) (xy 273.975031 -83.229405)
			(xy 273.99798 -83.174001) (xy 274.027964 -83.122067) (xy 274.06447 -83.074491) (xy 274.106875 -83.032086)
			(xy 274.154451 -82.99558) (xy 274.206385 -82.965596) (xy 274.261789 -82.942647) (xy 274.319714 -82.927126)
			(xy 274.37917 -82.919298) (xy 274.439138 -82.919298) (xy 274.498594 -82.927126) (xy 274.556519 -82.942647)
			(xy 274.611923 -82.965596) (xy 274.663857 -82.99558) (xy 274.711433 -83.032086) (xy 274.753838 -83.074491)
			(xy 274.790344 -83.122067) (xy 274.820328 -83.174001) (xy 274.843277 -83.229405) (xy 274.858798 -83.28733)
			(xy 274.866626 -83.346786) (xy 274.867116 -83.37677) (xy 274.867116 -84.144612) (xy 345.879928 -84.144612)
			(xy 345.879928 -83.281012) (xy 345.880418 -83.251028) (xy 345.888246 -83.191572) (xy 345.903767 -83.133647)
			(xy 345.926716 -83.078243) (xy 345.9567 -83.026309) (xy 345.993206 -82.978733) (xy 346.035611 -82.936328)
			(xy 346.083187 -82.899822) (xy 346.135121 -82.869838) (xy 346.190525 -82.846889) (xy 346.24845 -82.831368)
			(xy 346.307906 -82.82354) (xy 346.367874 -82.82354) (xy 346.42733 -82.831368) (xy 346.485255 -82.846889)
			(xy 346.540659 -82.869838) (xy 346.592593 -82.899822) (xy 346.640169 -82.936328) (xy 346.682574 -82.978733)
			(xy 346.71908 -83.026309) (xy 346.749064 -83.078243) (xy 346.772013 -83.133647) (xy 346.787534 -83.191572)
			(xy 346.795362 -83.251028) (xy 346.795852 -83.281012) (xy 346.795852 -84.144612) (xy 346.795362 -84.174596)
			(xy 346.787534 -84.234052) (xy 346.772013 -84.291977) (xy 346.749064 -84.347381) (xy 346.71908 -84.399315)
			(xy 346.682574 -84.446891) (xy 346.640169 -84.489296) (xy 346.592593 -84.525802) (xy 346.540659 -84.555786)
			(xy 346.485255 -84.578735) (xy 346.42733 -84.594256) (xy 346.367874 -84.602084) (xy 346.307906 -84.602084)
			(xy 346.24845 -84.594256) (xy 346.190525 -84.578735) (xy 346.135121 -84.555786) (xy 346.083187 -84.525802)
			(xy 346.035611 -84.489296) (xy 345.993206 -84.446891) (xy 345.9567 -84.399315) (xy 345.926716 -84.347381)
			(xy 345.903767 -84.291977) (xy 345.888246 -84.234052) (xy 345.880418 -84.174596) (xy 345.879928 -84.144612)
			(xy 274.867116 -84.144612) (xy 274.867116 -84.24037) (xy 274.866626 -84.270354) (xy 274.858798 -84.32981)
			(xy 274.843277 -84.387735) (xy 274.820328 -84.443139) (xy 274.790344 -84.495073) (xy 274.753838 -84.542649)
			(xy 274.711433 -84.585054) (xy 274.663857 -84.62156) (xy 274.611923 -84.651544) (xy 274.556519 -84.674493)
			(xy 274.498594 -84.690014) (xy 274.439138 -84.697842) (xy 274.37917 -84.697842) (xy 274.319714 -84.690014)
			(xy 274.261789 -84.674493) (xy 274.206385 -84.651544) (xy 274.154451 -84.62156) (xy 274.106875 -84.585054)
			(xy 274.06447 -84.542649) (xy 274.027964 -84.495073) (xy 273.99798 -84.443139) (xy 273.975031 -84.387735)
			(xy 273.95951 -84.32981) (xy 273.951682 -84.270354) (xy 273.951192 -84.24037) (xy 239.46603 -84.24037)
			(xy 239.47071 -84.275918) (xy 239.4712 -84.305902) (xy 239.4712 -85.169502) (xy 239.47071 -85.199486)
			(xy 239.462882 -85.258942) (xy 239.447361 -85.316867) (xy 239.424412 -85.372271) (xy 239.394428 -85.424205)
			(xy 239.357922 -85.471781) (xy 239.315517 -85.514186) (xy 239.267941 -85.550692) (xy 239.216007 -85.580676)
			(xy 239.160603 -85.603625) (xy 239.102678 -85.619146) (xy 239.043222 -85.626974) (xy 238.983254 -85.626974)
			(xy 238.923798 -85.619146) (xy 238.865873 -85.603625) (xy 238.810469 -85.580676) (xy 238.758535 -85.550692)
			(xy 238.710959 -85.514186) (xy 238.668554 -85.471781) (xy 238.632048 -85.424205) (xy 238.602064 -85.372271)
			(xy 238.579115 -85.316867) (xy 238.563594 -85.258942) (xy 238.555766 -85.199486) (xy 238.555276 -85.169502)
			(xy 233.963295 -85.169502) (xy 233.966678 -85.173911) (xy 233.99666 -85.225842) (xy 234.019607 -85.281243)
			(xy 234.035127 -85.339165) (xy 234.042954 -85.398617) (xy 234.042954 -85.458583) (xy 234.035127 -85.518035)
			(xy 234.019607 -85.575957) (xy 233.99666 -85.631358) (xy 233.966678 -85.683289) (xy 233.930174 -85.730863)
			(xy 233.887772 -85.773266) (xy 233.840199 -85.809771) (xy 233.788268 -85.839755) (xy 233.732868 -85.862703)
			(xy 233.674947 -85.878225) (xy 233.615495 -85.886053) (xy 233.585512 -85.886544) (xy 232.721912 -85.886544)
			(xy 232.691925 -85.886112) (xy 232.632463 -85.878285) (xy 232.574531 -85.862763) (xy 232.519122 -85.839813)
			(xy 232.467181 -85.809827) (xy 232.4196 -85.773317) (xy 232.377191 -85.730909) (xy 232.34068 -85.683329)
			(xy 232.310692 -85.631389) (xy 232.28774 -85.57598) (xy 232.272218 -85.518049) (xy 232.264389 -85.458587)
			(xy 118.289959 -85.458587) (xy 118.277182 -85.506269) (xy 118.254246 -85.561642) (xy 118.224279 -85.613548)
			(xy 118.187792 -85.661098) (xy 118.145412 -85.703478) (xy 118.097862 -85.739965) (xy 118.045956 -85.769932)
			(xy 117.990583 -85.792868) (xy 117.93269 -85.808381) (xy 117.873268 -85.816204) (xy 117.813332 -85.816204)
			(xy 117.75391 -85.808381) (xy 117.696017 -85.792868) (xy 117.640644 -85.769932) (xy 117.588738 -85.739965)
			(xy 117.541188 -85.703478) (xy 117.498808 -85.661098) (xy 117.462321 -85.613548) (xy 117.432354 -85.561642)
			(xy 117.409418 -85.506269) (xy 117.393905 -85.448376) (xy 117.386082 -85.388954) (xy 117.385592 -85.358986)
			(xy 49.009819 -85.358986) (xy 49.00037 -85.409534) (xy 48.968871 -85.534773) (xy 48.929722 -85.657836)
			(xy 48.883071 -85.778255) (xy 48.829096 -85.895574) (xy 48.768001 -86.009348) (xy 48.700018 -86.119145)
			(xy 48.625404 -86.224548) (xy 48.544443 -86.325158) (xy 48.457443 -86.420593) (xy 48.364732 -86.510492)
			(xy 48.266662 -86.594513) (xy 48.163607 -86.672337) (xy 48.055956 -86.743669) (xy 47.944117 -86.808239)
			(xy 47.937853 -86.811358) (xy 99.84232 -86.811358) (xy 99.84232 -85.947758) (xy 99.84281 -85.917774)
			(xy 99.850638 -85.858318) (xy 99.866159 -85.800393) (xy 99.889108 -85.744989) (xy 99.919092 -85.693055)
			(xy 99.955598 -85.645479) (xy 99.998003 -85.603074) (xy 100.045579 -85.566568) (xy 100.097513 -85.536584)
			(xy 100.152917 -85.513635) (xy 100.210842 -85.498114) (xy 100.270298 -85.490286) (xy 100.330266 -85.490286)
			(xy 100.389722 -85.498114) (xy 100.447647 -85.513635) (xy 100.503051 -85.536584) (xy 100.554985 -85.566568)
			(xy 100.602561 -85.603074) (xy 100.644966 -85.645479) (xy 100.681472 -85.693055) (xy 100.711456 -85.744989)
			(xy 100.734405 -85.800393) (xy 100.749926 -85.858318) (xy 100.757754 -85.917774) (xy 100.758244 -85.947758)
			(xy 100.758244 -86.811358) (xy 100.757754 -86.841342) (xy 100.749926 -86.900798) (xy 100.734405 -86.958723)
			(xy 100.711456 -87.014127) (xy 100.681472 -87.066061) (xy 100.644966 -87.113637) (xy 100.602561 -87.156042)
			(xy 100.554985 -87.192548) (xy 100.503051 -87.222532) (xy 100.447647 -87.245481) (xy 100.389722 -87.261002)
			(xy 100.330266 -87.26883) (xy 100.270298 -87.26883) (xy 100.210842 -87.261002) (xy 100.152917 -87.245481)
			(xy 100.097513 -87.222532) (xy 100.045579 -87.192548) (xy 99.998003 -87.156042) (xy 99.955598 -87.113637)
			(xy 99.919092 -87.066061) (xy 99.889108 -87.014127) (xy 99.866159 -86.958723) (xy 99.850638 -86.900798)
			(xy 99.84281 -86.841342) (xy 99.84232 -86.811358) (xy 47.937853 -86.811358) (xy 47.828516 -86.865801)
			(xy 47.709591 -86.916138) (xy 47.587792 -86.959058) (xy 47.463582 -86.994399) (xy 47.337433 -87.022026)
			(xy 47.209821 -87.041835) (xy 47.081232 -87.053751) (xy 46.952154 -87.057728) (xy 46.823076 -87.053751)
			(xy 46.694487 -87.041835) (xy 46.566875 -87.022026) (xy 46.440726 -86.994399) (xy 46.316516 -86.959058)
			(xy 46.194717 -86.916138) (xy 46.075792 -86.865801) (xy 45.960191 -86.808239) (xy 45.848352 -86.743669)
			(xy 45.740701 -86.672337) (xy 45.637646 -86.594513) (xy 45.539576 -86.510492) (xy 45.446865 -86.420593)
			(xy 45.359865 -86.325158) (xy 45.278904 -86.224548) (xy 45.20429 -86.119145) (xy 45.136307 -86.009348)
			(xy 45.075212 -85.895574) (xy 45.021237 -85.778255) (xy 44.974586 -85.657836) (xy 44.935437 -85.534773)
			(xy 44.903938 -85.409534) (xy 44.880209 -85.282593) (xy 44.864339 -85.154433) (xy 44.856389 -85.025538)
			(xy 2.78524 -85.025538) (xy 3.574034 -85.814408) (xy 3.623456 -85.864516) (xy 3.717262 -85.969457)
			(xy 3.805036 -86.079494) (xy 3.886503 -86.194278) (xy 3.961406 -86.31345) (xy 4.029509 -86.436634)
			(xy 4.090598 -86.563442) (xy 4.144481 -86.693477) (xy 4.190988 -86.826327) (xy 4.229973 -86.961577)
			(xy 4.261314 -87.0988) (xy 4.284912 -87.237564) (xy 4.29861 -87.358982) (xy 116.623592 -87.358982)
			(xy 116.623592 -86.495382) (xy 116.624082 -86.465414) (xy 116.631905 -86.405992) (xy 116.647418 -86.348099)
			(xy 116.670354 -86.292726) (xy 116.700321 -86.24082) (xy 116.736808 -86.19327) (xy 116.779188 -86.15089)
			(xy 116.826738 -86.114403) (xy 116.878644 -86.084436) (xy 116.934017 -86.0615) (xy 116.99191 -86.045987)
			(xy 117.051332 -86.038164) (xy 117.111268 -86.038164) (xy 117.17069 -86.045987) (xy 117.228583 -86.0615)
			(xy 117.283956 -86.084436) (xy 117.335862 -86.114403) (xy 117.383412 -86.15089) (xy 117.425792 -86.19327)
			(xy 117.462279 -86.24082) (xy 117.492246 -86.292726) (xy 117.515182 -86.348099) (xy 117.530695 -86.405992)
			(xy 117.538518 -86.465414) (xy 117.539008 -86.495382) (xy 117.539008 -87.358982) (xy 117.538518 -87.38895)
			(xy 117.531262 -87.444066) (xy 232.194882 -87.444066) (xy 232.194882 -87.384134) (xy 232.202704 -87.324714)
			(xy 232.218215 -87.266824) (xy 232.241149 -87.211454) (xy 232.271114 -87.15955) (xy 232.307596 -87.112002)
			(xy 232.349973 -87.069621) (xy 232.397519 -87.033135) (xy 232.44942 -87.003166) (xy 232.504788 -86.980227)
			(xy 232.562677 -86.964712) (xy 232.622096 -86.956884) (xy 232.652062 -86.956392) (xy 233.515662 -86.956392)
			(xy 233.545633 -86.956859) (xy 233.605062 -86.964678) (xy 233.662961 -86.980188) (xy 233.718341 -87.003123)
			(xy 233.770254 -87.033091) (xy 233.81781 -87.069578) (xy 233.860197 -87.111961) (xy 233.896688 -87.159515)
			(xy 233.92666 -87.211425) (xy 233.9496 -87.266803) (xy 233.965115 -87.324701) (xy 233.972939 -87.384129)
			(xy 233.972939 -87.416385) (xy 234.381521 -87.416385) (xy 234.381521 -87.356415) (xy 234.389349 -87.296959)
			(xy 234.40487 -87.239032) (xy 234.42782 -87.183628) (xy 234.457804 -87.131692) (xy 234.494312 -87.084115)
			(xy 234.536717 -87.04171) (xy 234.584294 -87.005203) (xy 234.636229 -86.975219) (xy 234.691634 -86.952269)
			(xy 234.749561 -86.936748) (xy 234.809017 -86.928921) (xy 234.839002 -86.928452) (xy 235.702602 -86.928452)
			(xy 235.732587 -86.928914) (xy 235.792044 -86.936742) (xy 235.849971 -86.952264) (xy 235.905376 -86.975214)
			(xy 235.957312 -87.005199) (xy 236.004889 -87.041707) (xy 236.047295 -87.084112) (xy 236.083802 -87.13169)
			(xy 236.113787 -87.183626) (xy 236.136737 -87.239031) (xy 236.152258 -87.296958) (xy 236.155843 -87.324184)
			(xy 330.477876 -87.324184) (xy 330.477876 -86.460584) (xy 330.478366 -86.430616) (xy 330.486189 -86.371194)
			(xy 330.501702 -86.313301) (xy 330.524638 -86.257928) (xy 330.554605 -86.206022) (xy 330.591092 -86.158472)
			(xy 330.633472 -86.116092) (xy 330.681022 -86.079605) (xy 330.732928 -86.049638) (xy 330.788301 -86.026702)
			(xy 330.846194 -86.011189) (xy 330.905616 -86.003366) (xy 330.965552 -86.003366) (xy 331.024974 -86.011189)
			(xy 331.082867 -86.026702) (xy 331.13824 -86.049638) (xy 331.190146 -86.079605) (xy 331.237696 -86.116092)
			(xy 331.266212 -86.144608) (xy 346.641928 -86.144608) (xy 346.641928 -85.281008) (xy 346.642418 -85.251024)
			(xy 346.650246 -85.191568) (xy 346.665767 -85.133643) (xy 346.688716 -85.078239) (xy 346.7187 -85.026305)
			(xy 346.755206 -84.978729) (xy 346.797611 -84.936324) (xy 346.845187 -84.899818) (xy 346.897121 -84.869834)
			(xy 346.952525 -84.846885) (xy 347.01045 -84.831364) (xy 347.069906 -84.823536) (xy 347.129874 -84.823536)
			(xy 347.18933 -84.831364) (xy 347.247255 -84.846885) (xy 347.302659 -84.869834) (xy 347.354593 -84.899818)
			(xy 347.402169 -84.936324) (xy 347.444574 -84.978729) (xy 347.48108 -85.026305) (xy 347.511064 -85.078239)
			(xy 347.534013 -85.133643) (xy 347.549534 -85.191568) (xy 347.557362 -85.251024) (xy 347.557852 -85.281008)
			(xy 347.557852 -86.144608) (xy 347.557362 -86.174592) (xy 347.549534 -86.234048) (xy 347.534013 -86.291973)
			(xy 347.511064 -86.347377) (xy 347.48108 -86.399311) (xy 347.444574 -86.446887) (xy 347.402169 -86.489292)
			(xy 347.354593 -86.525798) (xy 347.302659 -86.555782) (xy 347.247255 -86.578731) (xy 347.18933 -86.594252)
			(xy 347.129874 -86.60208) (xy 347.069906 -86.60208) (xy 347.01045 -86.594252) (xy 346.952525 -86.578731)
			(xy 346.897121 -86.555782) (xy 346.845187 -86.525798) (xy 346.797611 -86.489292) (xy 346.755206 -86.446887)
			(xy 346.7187 -86.399311) (xy 346.688716 -86.347377) (xy 346.665767 -86.291973) (xy 346.650246 -86.234048)
			(xy 346.642418 -86.174592) (xy 346.641928 -86.144608) (xy 331.266212 -86.144608) (xy 331.280076 -86.158472)
			(xy 331.316563 -86.206022) (xy 331.34653 -86.257928) (xy 331.369466 -86.313301) (xy 331.384979 -86.371194)
			(xy 331.392802 -86.430616) (xy 331.393292 -86.460584) (xy 331.393292 -87.324184) (xy 331.392802 -87.354152)
			(xy 331.384979 -87.413574) (xy 331.369466 -87.471467) (xy 331.34653 -87.52684) (xy 331.316563 -87.578746)
			(xy 331.280076 -87.626296) (xy 331.237696 -87.668676) (xy 331.190146 -87.705163) (xy 331.13824 -87.73513)
			(xy 331.082867 -87.758066) (xy 331.024974 -87.773579) (xy 330.965552 -87.781402) (xy 330.905616 -87.781402)
			(xy 330.846194 -87.773579) (xy 330.788301 -87.758066) (xy 330.732928 -87.73513) (xy 330.681022 -87.705163)
			(xy 330.633472 -87.668676) (xy 330.591092 -87.626296) (xy 330.554605 -87.578746) (xy 330.524638 -87.52684)
			(xy 330.501702 -87.471467) (xy 330.486189 -87.413574) (xy 330.478366 -87.354152) (xy 330.477876 -87.324184)
			(xy 236.155843 -87.324184) (xy 236.160086 -87.356415) (xy 236.160086 -87.416385) (xy 236.152258 -87.475842)
			(xy 236.136737 -87.533769) (xy 236.113787 -87.589174) (xy 236.083802 -87.64111) (xy 236.047295 -87.688688)
			(xy 236.004889 -87.731093) (xy 235.957312 -87.767601) (xy 235.905376 -87.797586) (xy 235.849971 -87.820536)
			(xy 235.792044 -87.836058) (xy 235.732587 -87.843886) (xy 235.702602 -87.844376) (xy 234.839002 -87.844376)
			(xy 234.809017 -87.843879) (xy 234.749561 -87.836052) (xy 234.691634 -87.820531) (xy 234.636229 -87.797581)
			(xy 234.584294 -87.767597) (xy 234.536717 -87.73109) (xy 234.494312 -87.688685) (xy 234.457804 -87.641108)
			(xy 234.42782 -87.589172) (xy 234.40487 -87.533768) (xy 234.389349 -87.475841) (xy 234.381521 -87.416385)
			(xy 233.972939 -87.416385) (xy 233.972939 -87.444071) (xy 233.965115 -87.503499) (xy 233.9496 -87.561397)
			(xy 233.92666 -87.616775) (xy 233.896688 -87.668685) (xy 233.860197 -87.716239) (xy 233.81781 -87.758622)
			(xy 233.770254 -87.795109) (xy 233.718341 -87.825077) (xy 233.662961 -87.848012) (xy 233.605062 -87.863522)
			(xy 233.545633 -87.871341) (xy 233.515662 -87.871808) (xy 232.652062 -87.871808) (xy 232.622096 -87.871316)
			(xy 232.562677 -87.863488) (xy 232.504788 -87.847973) (xy 232.44942 -87.825034) (xy 232.397519 -87.795065)
			(xy 232.349973 -87.758579) (xy 232.307596 -87.716198) (xy 232.271114 -87.66865) (xy 232.241149 -87.616746)
			(xy 232.218215 -87.561376) (xy 232.202704 -87.503486) (xy 232.194882 -87.444066) (xy 117.531262 -87.444066)
			(xy 117.530695 -87.448372) (xy 117.515182 -87.506265) (xy 117.492246 -87.561638) (xy 117.462279 -87.613544)
			(xy 117.425792 -87.661094) (xy 117.383412 -87.703474) (xy 117.335862 -87.739961) (xy 117.283956 -87.769928)
			(xy 117.228583 -87.792864) (xy 117.17069 -87.808377) (xy 117.111268 -87.8162) (xy 117.051332 -87.8162)
			(xy 116.99191 -87.808377) (xy 116.934017 -87.792864) (xy 116.878644 -87.769928) (xy 116.826738 -87.739961)
			(xy 116.779188 -87.703474) (xy 116.736808 -87.661094) (xy 116.700321 -87.613544) (xy 116.670354 -87.561638)
			(xy 116.647418 -87.506265) (xy 116.631905 -87.448372) (xy 116.624082 -87.38895) (xy 116.623592 -87.358982)
			(xy 4.29861 -87.358982) (xy 4.300692 -87.377432) (xy 4.308605 -87.517966) (xy 4.30911 -87.588344)
			(xy 4.30911 -88.006187) (xy 238.124409 -88.006187) (xy 238.124409 -87.946213) (xy 238.132238 -87.886751)
			(xy 238.147762 -87.82882) (xy 238.170714 -87.773411) (xy 238.200704 -87.721472) (xy 238.237216 -87.673892)
			(xy 238.279627 -87.631486) (xy 238.32721 -87.594978) (xy 238.379152 -87.564994) (xy 238.434563 -87.542047)
			(xy 238.492496 -87.526529) (xy 238.551959 -87.518706) (xy 238.581946 -87.51824) (xy 239.445546 -87.51824)
			(xy 239.475528 -87.518729) (xy 239.53498 -87.526561) (xy 239.5929 -87.542086) (xy 239.648299 -87.565038)
			(xy 239.700228 -87.595024) (xy 239.747799 -87.631531) (xy 239.790199 -87.673935) (xy 239.826701 -87.72151)
			(xy 239.856682 -87.773442) (xy 239.879628 -87.828843) (xy 239.895148 -87.886765) (xy 239.902974 -87.946217)
			(xy 239.902974 -88.006183) (xy 239.895148 -88.065635) (xy 239.879628 -88.123557) (xy 239.870911 -88.144604)
			(xy 345.879928 -88.144604) (xy 345.879928 -87.281004) (xy 345.880418 -87.25102) (xy 345.888246 -87.191564)
			(xy 345.903767 -87.133639) (xy 345.926716 -87.078235) (xy 345.9567 -87.026301) (xy 345.993206 -86.978725)
			(xy 346.035611 -86.93632) (xy 346.083187 -86.899814) (xy 346.135121 -86.86983) (xy 346.190525 -86.846881)
			(xy 346.24845 -86.83136) (xy 346.307906 -86.823532) (xy 346.367874 -86.823532) (xy 346.42733 -86.83136)
			(xy 346.485255 -86.846881) (xy 346.540659 -86.86983) (xy 346.592593 -86.899814) (xy 346.640169 -86.93632)
			(xy 346.682574 -86.978725) (xy 346.71908 -87.026301) (xy 346.749064 -87.078235) (xy 346.772013 -87.133639)
			(xy 346.787534 -87.191564) (xy 346.795362 -87.25102) (xy 346.795852 -87.281004) (xy 346.795852 -88.144604)
			(xy 346.795362 -88.174588) (xy 346.787534 -88.234044) (xy 346.772013 -88.291969) (xy 346.749064 -88.347373)
			(xy 346.71908 -88.399307) (xy 346.682574 -88.446883) (xy 346.640169 -88.489288) (xy 346.592593 -88.525794)
			(xy 346.540659 -88.555778) (xy 346.485255 -88.578727) (xy 346.42733 -88.594248) (xy 346.367874 -88.602076)
			(xy 346.307906 -88.602076) (xy 346.24845 -88.594248) (xy 346.190525 -88.578727) (xy 346.135121 -88.555778)
			(xy 346.083187 -88.525794) (xy 346.035611 -88.489288) (xy 345.993206 -88.446883) (xy 345.9567 -88.399307)
			(xy 345.926716 -88.347373) (xy 345.903767 -88.291969) (xy 345.888246 -88.234044) (xy 345.880418 -88.174588)
			(xy 345.879928 -88.144604) (xy 239.870911 -88.144604) (xy 239.856682 -88.178958) (xy 239.826701 -88.23089)
			(xy 239.790199 -88.278465) (xy 239.747799 -88.320869) (xy 239.700228 -88.357376) (xy 239.648299 -88.387362)
			(xy 239.5929 -88.410314) (xy 239.53498 -88.425839) (xy 239.475528 -88.433671) (xy 239.445546 -88.434164)
			(xy 238.581946 -88.434164) (xy 238.551959 -88.433694) (xy 238.492496 -88.425871) (xy 238.434563 -88.410353)
			(xy 238.379152 -88.387406) (xy 238.32721 -88.357422) (xy 238.279627 -88.320914) (xy 238.237216 -88.278508)
			(xy 238.200704 -88.230928) (xy 238.170714 -88.178989) (xy 238.147762 -88.12358) (xy 238.132238 -88.065649)
			(xy 238.124409 -88.006187) (xy 4.30911 -88.006187) (xy 4.30911 -89.358978) (xy 117.385592 -89.358978)
			(xy 117.385592 -88.495378) (xy 117.386082 -88.46541) (xy 117.393905 -88.405988) (xy 117.409418 -88.348095)
			(xy 117.432354 -88.292722) (xy 117.462321 -88.240816) (xy 117.498808 -88.193266) (xy 117.541188 -88.150886)
			(xy 117.588738 -88.114399) (xy 117.640644 -88.084432) (xy 117.696017 -88.061496) (xy 117.75391 -88.045983)
			(xy 117.813332 -88.03816) (xy 117.873268 -88.03816) (xy 117.93269 -88.045983) (xy 117.990583 -88.061496)
			(xy 118.045956 -88.084432) (xy 118.097862 -88.114399) (xy 118.145412 -88.150886) (xy 118.187792 -88.193266)
			(xy 118.224279 -88.240816) (xy 118.254246 -88.292722) (xy 118.277182 -88.348095) (xy 118.292695 -88.405988)
			(xy 118.300518 -88.46541) (xy 118.301008 -88.495378) (xy 118.301008 -89.358978) (xy 118.300518 -89.388946)
			(xy 118.292695 -89.448368) (xy 118.277182 -89.506261) (xy 118.254246 -89.561634) (xy 118.224279 -89.61354)
			(xy 118.187792 -89.66109) (xy 118.145412 -89.70347) (xy 118.097862 -89.739957) (xy 118.045956 -89.769924)
			(xy 117.990583 -89.79286) (xy 117.93269 -89.808373) (xy 117.873268 -89.816196) (xy 117.813332 -89.816196)
			(xy 117.75391 -89.808373) (xy 117.696017 -89.79286) (xy 117.640644 -89.769924) (xy 117.588738 -89.739957)
			(xy 117.541188 -89.70347) (xy 117.498808 -89.66109) (xy 117.462321 -89.61354) (xy 117.432354 -89.561634)
			(xy 117.409418 -89.506261) (xy 117.393905 -89.448368) (xy 117.386082 -89.388946) (xy 117.385592 -89.358978)
			(xy 4.30911 -89.358978) (xy 4.30911 -90.1446) (xy 346.641928 -90.1446) (xy 346.641928 -89.281) (xy 346.642418 -89.251016)
			(xy 346.650246 -89.19156) (xy 346.665767 -89.133635) (xy 346.688716 -89.078231) (xy 346.7187 -89.026297)
			(xy 346.755206 -88.978721) (xy 346.797611 -88.936316) (xy 346.845187 -88.89981) (xy 346.897121 -88.869826)
			(xy 346.952525 -88.846877) (xy 347.01045 -88.831356) (xy 347.069906 -88.823528) (xy 347.129874 -88.823528)
			(xy 347.18933 -88.831356) (xy 347.247255 -88.846877) (xy 347.302659 -88.869826) (xy 347.354593 -88.89981)
			(xy 347.402169 -88.936316) (xy 347.444574 -88.978721) (xy 347.48108 -89.026297) (xy 347.511064 -89.078231)
			(xy 347.534013 -89.133635) (xy 347.549534 -89.19156) (xy 347.557362 -89.251016) (xy 347.557852 -89.281)
			(xy 347.557852 -90.1446) (xy 347.557362 -90.174584) (xy 347.549534 -90.23404) (xy 347.534013 -90.291965)
			(xy 347.511064 -90.347369) (xy 347.48108 -90.399303) (xy 347.444574 -90.446879) (xy 347.402169 -90.489284)
			(xy 347.354593 -90.52579) (xy 347.302659 -90.555774) (xy 347.247255 -90.578723) (xy 347.18933 -90.594244)
			(xy 347.129874 -90.602072) (xy 347.069906 -90.602072) (xy 347.01045 -90.594244) (xy 346.952525 -90.578723)
			(xy 346.897121 -90.555774) (xy 346.845187 -90.52579) (xy 346.797611 -90.489284) (xy 346.755206 -90.446879)
			(xy 346.7187 -90.399303) (xy 346.688716 -90.347369) (xy 346.665767 -90.291965) (xy 346.650246 -90.23404)
			(xy 346.642418 -90.174584) (xy 346.641928 -90.1446) (xy 4.30911 -90.1446) (xy 4.30911 -94.088485)
			(xy 109.149614 -94.088485) (xy 109.149614 -94.028515) (xy 109.157442 -93.969058) (xy 109.172963 -93.911131)
			(xy 109.195912 -93.855726) (xy 109.225897 -93.80379) (xy 109.262405 -93.756213) (xy 109.30481 -93.713807)
			(xy 109.352387 -93.6773) (xy 109.404322 -93.647314) (xy 109.459727 -93.624364) (xy 109.517654 -93.608843)
			(xy 109.577111 -93.601014) (xy 109.607096 -93.600524) (xy 110.470696 -93.600524) (xy 110.500681 -93.601021)
			(xy 110.560138 -93.608848) (xy 110.618064 -93.624369) (xy 110.673469 -93.647318) (xy 110.725405 -93.677303)
			(xy 110.772982 -93.71381) (xy 110.815388 -93.756215) (xy 110.851895 -93.803792) (xy 110.88188 -93.855727)
			(xy 110.90483 -93.911132) (xy 110.920351 -93.969058) (xy 110.928179 -94.028515) (xy 110.928179 -94.088485)
			(xy 110.920351 -94.147942) (xy 110.90483 -94.205868) (xy 110.88188 -94.261273) (xy 110.851895 -94.313208)
			(xy 110.815388 -94.360785) (xy 110.772982 -94.40319) (xy 110.725405 -94.439697) (xy 110.673469 -94.469682)
			(xy 110.618064 -94.492631) (xy 110.560138 -94.508152) (xy 110.500681 -94.515979) (xy 110.470696 -94.516448)
			(xy 109.607096 -94.516448) (xy 109.577111 -94.515986) (xy 109.517654 -94.508157) (xy 109.459727 -94.492636)
			(xy 109.404322 -94.469686) (xy 109.352387 -94.4397) (xy 109.30481 -94.403193) (xy 109.262405 -94.360787)
			(xy 109.225897 -94.31321) (xy 109.195912 -94.261274) (xy 109.172963 -94.205869) (xy 109.157442 -94.147942)
			(xy 109.149614 -94.088485) (xy 4.30911 -94.088485) (xy 4.30911 -95.214948) (xy 47.274239 -95.214948)
			(xy 47.278194 -95.123111) (xy 47.290029 -95.031954) (xy 47.309656 -94.942151) (xy 47.33693 -94.854369)
			(xy 47.37165 -94.769255) (xy 47.413558 -94.687442) (xy 47.462344 -94.609534) (xy 47.517647 -94.536109)
			(xy 47.579057 -94.467709) (xy 47.646119 -94.404842) (xy 47.718338 -94.347972) (xy 47.795178 -94.297521)
			(xy 47.876071 -94.253862) (xy 47.960417 -94.217319) (xy 48.047593 -94.188162) (xy 48.136952 -94.166608)
			(xy 48.227833 -94.152814) (xy 48.319564 -94.146884) (xy 48.411465 -94.148862) (xy 48.502856 -94.158733)
			(xy 48.59306 -94.176423) (xy 48.681409 -94.201803) (xy 48.767249 -94.234683) (xy 48.849945 -94.274821)
			(xy 48.928885 -94.32192) (xy 49.003483 -94.37563) (xy 49.073189 -94.435554) (xy 49.137484 -94.501248)
			(xy 49.195895 -94.572226) (xy 49.247987 -94.647963) (xy 49.293376 -94.727898) (xy 49.331726 -94.811438)
			(xy 49.362751 -94.897966) (xy 49.386224 -94.986841) (xy 49.40197 -95.077405) (xy 49.409872 -95.168987)
			(xy 49.410366 -95.214948) (xy 71.639189 -95.214948) (xy 71.643144 -95.123111) (xy 71.654979 -95.031954)
			(xy 71.674606 -94.942151) (xy 71.70188 -94.854369) (xy 71.7366 -94.769255) (xy 71.778508 -94.687442)
			(xy 71.827294 -94.609534) (xy 71.882597 -94.536109) (xy 71.944007 -94.467709) (xy 72.011069 -94.404842)
			(xy 72.083288 -94.347972) (xy 72.160128 -94.297521) (xy 72.241021 -94.253862) (xy 72.325367 -94.217319)
			(xy 72.412543 -94.188162) (xy 72.501902 -94.166608) (xy 72.592783 -94.152814) (xy 72.684514 -94.146884)
			(xy 72.776415 -94.148862) (xy 72.867806 -94.158733) (xy 72.95801 -94.176423) (xy 73.046359 -94.201803)
			(xy 73.132199 -94.234683) (xy 73.214895 -94.274821) (xy 73.293835 -94.32192) (xy 73.368433 -94.37563)
			(xy 73.438139 -94.435554) (xy 73.502434 -94.501248) (xy 73.560845 -94.572226) (xy 73.612937 -94.647963)
			(xy 73.658326 -94.727898) (xy 73.696676 -94.811438) (xy 73.727701 -94.897966) (xy 73.751174 -94.986841)
			(xy 73.76692 -95.077405) (xy 73.774822 -95.168987) (xy 73.775316 -95.214948) (xy 73.774822 -95.260909)
			(xy 73.774772 -95.261486) (xy 163.375394 -95.261486) (xy 163.375394 -95.168314) (xy 163.383515 -95.075496)
			(xy 163.399694 -94.983738) (xy 163.423808 -94.893741) (xy 163.455675 -94.806187) (xy 163.495052 -94.721744)
			(xy 163.541638 -94.641054) (xy 163.595079 -94.564731) (xy 163.654969 -94.493357) (xy 163.720852 -94.427473)
			(xy 163.792226 -94.367583) (xy 163.868549 -94.314141) (xy 163.949238 -94.267554) (xy 164.033681 -94.228178)
			(xy 164.121235 -94.19631) (xy 164.211233 -94.172195) (xy 164.30299 -94.156015) (xy 164.395808 -94.147894)
			(xy 164.442394 -94.147386) (xy 164.442648 -94.147386) (xy 164.489237 -94.1478) (xy 164.582061 -94.155925)
			(xy 164.673824 -94.172109) (xy 164.763826 -94.196229) (xy 164.851385 -94.228101) (xy 164.935832 -94.267483)
			(xy 165.016526 -94.314074) (xy 165.092852 -94.367522) (xy 165.164229 -94.427418) (xy 165.230115 -94.493306)
			(xy 165.290008 -94.564687) (xy 165.343451 -94.641015) (xy 165.390039 -94.721711) (xy 165.429417 -94.80616)
			(xy 165.461286 -94.893719) (xy 165.485401 -94.983723) (xy 165.501581 -95.075487) (xy 165.509702 -95.168311)
			(xy 165.509702 -95.214948) (xy 187.739796 -95.214948) (xy 187.743748 -95.123155) (xy 187.755578 -95.032041)
			(xy 187.775195 -94.942281) (xy 187.802457 -94.85454) (xy 187.83716 -94.769468) (xy 187.879048 -94.687693)
			(xy 187.927811 -94.609822) (xy 187.983087 -94.536432) (xy 188.044468 -94.468065) (xy 188.111499 -94.405227)
			(xy 188.183683 -94.348385) (xy 188.260487 -94.297958) (xy 188.341341 -94.25432) (xy 188.425647 -94.217794)
			(xy 188.512781 -94.188651) (xy 188.602098 -94.167106) (xy 188.692936 -94.15332) (xy 188.784623 -94.147393)
			(xy 188.87648 -94.14937) (xy 188.967828 -94.159236) (xy 189.057988 -94.176918) (xy 189.146296 -94.202285)
			(xy 189.232095 -94.23515) (xy 189.314752 -94.275269) (xy 189.393654 -94.322345) (xy 189.468217 -94.376029)
			(xy 189.537889 -94.435925) (xy 189.602154 -94.501588) (xy 189.660537 -94.572532) (xy 189.712604 -94.648233)
			(xy 189.757972 -94.72813) (xy 189.796303 -94.81163) (xy 189.827314 -94.898117) (xy 189.850775 -94.98695)
			(xy 189.866514 -95.07747) (xy 189.874412 -95.169009) (xy 189.874906 -95.214948) (xy 279.474181 -95.214948)
			(xy 279.478136 -95.123111) (xy 279.489971 -95.031954) (xy 279.509598 -94.942151) (xy 279.536872 -94.854369)
			(xy 279.571592 -94.769255) (xy 279.6135 -94.687442) (xy 279.662286 -94.609534) (xy 279.717589 -94.536109)
			(xy 279.778999 -94.467709) (xy 279.846061 -94.404842) (xy 279.91828 -94.347972) (xy 279.99512 -94.297521)
			(xy 280.076013 -94.253862) (xy 280.160359 -94.217319) (xy 280.247535 -94.188162) (xy 280.336894 -94.166608)
			(xy 280.427775 -94.152814) (xy 280.519506 -94.146884) (xy 280.611407 -94.148862) (xy 280.702798 -94.158733)
			(xy 280.793002 -94.176423) (xy 280.881351 -94.201803) (xy 280.967191 -94.234683) (xy 281.049887 -94.274821)
			(xy 281.128827 -94.32192) (xy 281.203425 -94.37563) (xy 281.273131 -94.435554) (xy 281.337426 -94.501248)
			(xy 281.395837 -94.572226) (xy 281.447929 -94.647963) (xy 281.493318 -94.727898) (xy 281.531668 -94.811438)
			(xy 281.562693 -94.897966) (xy 281.586166 -94.986841) (xy 281.601912 -95.077405) (xy 281.609814 -95.168987)
			(xy 281.610308 -95.214948) (xy 303.839131 -95.214948) (xy 303.843086 -95.123111) (xy 303.854921 -95.031954)
			(xy 303.874548 -94.942151) (xy 303.901822 -94.854369) (xy 303.936542 -94.769255) (xy 303.97845 -94.687442)
			(xy 304.027236 -94.609534) (xy 304.082539 -94.536109) (xy 304.143949 -94.467709) (xy 304.211011 -94.404842)
			(xy 304.28323 -94.347972) (xy 304.36007 -94.297521) (xy 304.440963 -94.253862) (xy 304.525309 -94.217319)
			(xy 304.612485 -94.188162) (xy 304.701844 -94.166608) (xy 304.792725 -94.152814) (xy 304.884456 -94.146884)
			(xy 304.976357 -94.148862) (xy 305.067748 -94.158733) (xy 305.157952 -94.176423) (xy 305.246301 -94.201803)
			(xy 305.332141 -94.234683) (xy 305.414837 -94.274821) (xy 305.493777 -94.32192) (xy 305.568375 -94.37563)
			(xy 305.638081 -94.435554) (xy 305.702376 -94.501248) (xy 305.760787 -94.572226) (xy 305.812879 -94.647963)
			(xy 305.858268 -94.727898) (xy 305.896618 -94.811438) (xy 305.91901 -94.87389) (xy 338.405861 -94.87389)
			(xy 338.405861 -94.81391) (xy 338.413691 -94.754443) (xy 338.429215 -94.696507) (xy 338.45217 -94.641093)
			(xy 338.482161 -94.58915) (xy 338.518676 -94.541565) (xy 338.561089 -94.499155) (xy 338.608676 -94.462643)
			(xy 338.660622 -94.432655) (xy 338.716037 -94.409705) (xy 338.773975 -94.394184) (xy 338.833442 -94.386359)
			(xy 338.863432 -94.385892) (xy 339.727032 -94.385892) (xy 339.757012 -94.386476) (xy 339.816458 -94.394306)
			(xy 339.874374 -94.409828) (xy 339.929769 -94.432777) (xy 339.981694 -94.462759) (xy 340.029262 -94.499262)
			(xy 340.071659 -94.541662) (xy 340.108159 -94.589232) (xy 340.138137 -94.64116) (xy 340.161082 -94.696556)
			(xy 340.1766 -94.754473) (xy 340.184426 -94.81392) (xy 340.184426 -94.87388) (xy 340.1766 -94.933327)
			(xy 340.161082 -94.991244) (xy 340.138137 -95.04664) (xy 340.108159 -95.098568) (xy 340.071659 -95.146138)
			(xy 340.029262 -95.188538) (xy 339.994846 -95.214948) (xy 395.574279 -95.214948) (xy 395.578234 -95.123111)
			(xy 395.590069 -95.031954) (xy 395.609696 -94.942151) (xy 395.63697 -94.854369) (xy 395.67169 -94.769255)
			(xy 395.713598 -94.687442) (xy 395.762384 -94.609534) (xy 395.817687 -94.536109) (xy 395.879097 -94.467709)
			(xy 395.946159 -94.404842) (xy 396.018378 -94.347972) (xy 396.095218 -94.297521) (xy 396.176111 -94.253862)
			(xy 396.260457 -94.217319) (xy 396.347633 -94.188162) (xy 396.436992 -94.166608) (xy 396.527873 -94.152814)
			(xy 396.619604 -94.146884) (xy 396.711505 -94.148862) (xy 396.802896 -94.158733) (xy 396.8931 -94.176423)
			(xy 396.981449 -94.201803) (xy 397.067289 -94.234683) (xy 397.149985 -94.274821) (xy 397.228925 -94.32192)
			(xy 397.303523 -94.37563) (xy 397.373229 -94.435554) (xy 397.437524 -94.501248) (xy 397.495935 -94.572226)
			(xy 397.548027 -94.647963) (xy 397.593416 -94.727898) (xy 397.631766 -94.811438) (xy 397.662791 -94.897966)
			(xy 397.686264 -94.986841) (xy 397.70201 -95.077405) (xy 397.709912 -95.168987) (xy 397.710406 -95.214948)
			(xy 419.939229 -95.214948) (xy 419.943184 -95.123111) (xy 419.955019 -95.031954) (xy 419.974646 -94.942151)
			(xy 420.00192 -94.854369) (xy 420.03664 -94.769255) (xy 420.078548 -94.687442) (xy 420.127334 -94.609534)
			(xy 420.182637 -94.536109) (xy 420.244047 -94.467709) (xy 420.311109 -94.404842) (xy 420.383328 -94.347972)
			(xy 420.460168 -94.297521) (xy 420.541061 -94.253862) (xy 420.625407 -94.217319) (xy 420.712583 -94.188162)
			(xy 420.801942 -94.166608) (xy 420.892823 -94.152814) (xy 420.984554 -94.146884) (xy 421.076455 -94.148862)
			(xy 421.167846 -94.158733) (xy 421.25805 -94.176423) (xy 421.346399 -94.201803) (xy 421.432239 -94.234683)
			(xy 421.514935 -94.274821) (xy 421.593875 -94.32192) (xy 421.668473 -94.37563) (xy 421.738179 -94.435554)
			(xy 421.802474 -94.501248) (xy 421.860885 -94.572226) (xy 421.912977 -94.647963) (xy 421.958366 -94.727898)
			(xy 421.996716 -94.811438) (xy 422.027741 -94.897966) (xy 422.051214 -94.986841) (xy 422.06696 -95.077405)
			(xy 422.074862 -95.168987) (xy 422.075356 -95.214948) (xy 422.074862 -95.260909) (xy 422.06696 -95.352491)
			(xy 422.051214 -95.443055) (xy 422.027741 -95.53193) (xy 421.996716 -95.618458) (xy 421.958366 -95.701998)
			(xy 421.912977 -95.781933) (xy 421.860885 -95.85767) (xy 421.802474 -95.928648) (xy 421.738179 -95.994342)
			(xy 421.668473 -96.054266) (xy 421.593875 -96.107976) (xy 421.514935 -96.155075) (xy 421.432239 -96.195213)
			(xy 421.346399 -96.228093) (xy 421.25805 -96.253473) (xy 421.167846 -96.271163) (xy 421.076455 -96.281034)
			(xy 420.984554 -96.283012) (xy 420.892823 -96.277082) (xy 420.801942 -96.263288) (xy 420.712583 -96.241734)
			(xy 420.625407 -96.212577) (xy 420.541061 -96.176034) (xy 420.460168 -96.132375) (xy 420.383328 -96.081924)
			(xy 420.311109 -96.025054) (xy 420.244047 -95.962187) (xy 420.182637 -95.893787) (xy 420.127334 -95.820362)
			(xy 420.078548 -95.742454) (xy 420.03664 -95.660641) (xy 420.00192 -95.575527) (xy 419.974646 -95.487745)
			(xy 419.955019 -95.397942) (xy 419.943184 -95.306785) (xy 419.939229 -95.214948) (xy 397.710406 -95.214948)
			(xy 397.709912 -95.260909) (xy 397.70201 -95.352491) (xy 397.686264 -95.443055) (xy 397.662791 -95.53193)
			(xy 397.631766 -95.618458) (xy 397.593416 -95.701998) (xy 397.548027 -95.781933) (xy 397.495935 -95.85767)
			(xy 397.437524 -95.928648) (xy 397.373229 -95.994342) (xy 397.303523 -96.054266) (xy 397.228925 -96.107976)
			(xy 397.149985 -96.155075) (xy 397.067289 -96.195213) (xy 396.981449 -96.228093) (xy 396.8931 -96.253473)
			(xy 396.802896 -96.271163) (xy 396.711505 -96.281034) (xy 396.619604 -96.283012) (xy 396.527873 -96.277082)
			(xy 396.436992 -96.263288) (xy 396.347633 -96.241734) (xy 396.260457 -96.212577) (xy 396.176111 -96.176034)
			(xy 396.095218 -96.132375) (xy 396.018378 -96.081924) (xy 395.946159 -96.025054) (xy 395.879097 -95.962187)
			(xy 395.817687 -95.893787) (xy 395.762384 -95.820362) (xy 395.713598 -95.742454) (xy 395.67169 -95.660641)
			(xy 395.63697 -95.575527) (xy 395.609696 -95.487745) (xy 395.590069 -95.397942) (xy 395.578234 -95.306785)
			(xy 395.574279 -95.214948) (xy 339.994846 -95.214948) (xy 339.981694 -95.225041) (xy 339.929769 -95.255023)
			(xy 339.874374 -95.277972) (xy 339.816458 -95.293494) (xy 339.757012 -95.301324) (xy 339.727032 -95.301816)
			(xy 338.863432 -95.301816) (xy 338.833442 -95.301441) (xy 338.773975 -95.293616) (xy 338.716037 -95.278095)
			(xy 338.660622 -95.255145) (xy 338.608676 -95.225157) (xy 338.561089 -95.188645) (xy 338.518676 -95.146235)
			(xy 338.482161 -95.09865) (xy 338.45217 -95.046707) (xy 338.429215 -94.991293) (xy 338.413691 -94.933357)
			(xy 338.405861 -94.87389) (xy 305.91901 -94.87389) (xy 305.927643 -94.897966) (xy 305.951116 -94.986841)
			(xy 305.966862 -95.077405) (xy 305.974764 -95.168987) (xy 305.975258 -95.214948) (xy 305.974764 -95.260909)
			(xy 305.966862 -95.352491) (xy 305.951116 -95.443055) (xy 305.927643 -95.53193) (xy 305.896618 -95.618458)
			(xy 305.858268 -95.701998) (xy 305.812879 -95.781933) (xy 305.760787 -95.85767) (xy 305.702376 -95.928648)
			(xy 305.638081 -95.994342) (xy 305.568375 -96.054266) (xy 305.493777 -96.107976) (xy 305.414837 -96.155075)
			(xy 305.332141 -96.195213) (xy 305.246301 -96.228093) (xy 305.157952 -96.253473) (xy 305.067748 -96.271163)
			(xy 304.976357 -96.281034) (xy 304.884456 -96.283012) (xy 304.792725 -96.277082) (xy 304.701844 -96.263288)
			(xy 304.612485 -96.241734) (xy 304.525309 -96.212577) (xy 304.440963 -96.176034) (xy 304.36007 -96.132375)
			(xy 304.28323 -96.081924) (xy 304.211011 -96.025054) (xy 304.143949 -95.962187) (xy 304.082539 -95.893787)
			(xy 304.027236 -95.820362) (xy 303.97845 -95.742454) (xy 303.936542 -95.660641) (xy 303.901822 -95.575527)
			(xy 303.874548 -95.487745) (xy 303.854921 -95.397942) (xy 303.843086 -95.306785) (xy 303.839131 -95.214948)
			(xy 281.610308 -95.214948) (xy 281.609814 -95.260909) (xy 281.601912 -95.352491) (xy 281.586166 -95.443055)
			(xy 281.562693 -95.53193) (xy 281.531668 -95.618458) (xy 281.493318 -95.701998) (xy 281.447929 -95.781933)
			(xy 281.395837 -95.85767) (xy 281.337426 -95.928648) (xy 281.273131 -95.994342) (xy 281.203425 -96.054266)
			(xy 281.128827 -96.107976) (xy 281.049887 -96.155075) (xy 280.967191 -96.195213) (xy 280.881351 -96.228093)
			(xy 280.793002 -96.253473) (xy 280.702798 -96.271163) (xy 280.611407 -96.281034) (xy 280.519506 -96.283012)
			(xy 280.427775 -96.277082) (xy 280.336894 -96.263288) (xy 280.247535 -96.241734) (xy 280.160359 -96.212577)
			(xy 280.076013 -96.176034) (xy 279.99512 -96.132375) (xy 279.91828 -96.081924) (xy 279.846061 -96.025054)
			(xy 279.778999 -95.962187) (xy 279.717589 -95.893787) (xy 279.662286 -95.820362) (xy 279.6135 -95.742454)
			(xy 279.571592 -95.660641) (xy 279.536872 -95.575527) (xy 279.509598 -95.487745) (xy 279.489971 -95.397942)
			(xy 279.478136 -95.306785) (xy 279.474181 -95.214948) (xy 189.874906 -95.214948) (xy 189.874412 -95.260887)
			(xy 189.866514 -95.352426) (xy 189.850775 -95.442946) (xy 189.827314 -95.531779) (xy 189.796303 -95.618266)
			(xy 189.757972 -95.701766) (xy 189.712604 -95.781663) (xy 189.660537 -95.857364) (xy 189.602154 -95.928308)
			(xy 189.537889 -95.993971) (xy 189.468217 -96.053867) (xy 189.393654 -96.107551) (xy 189.314752 -96.154627)
			(xy 189.232095 -96.194746) (xy 189.146296 -96.227611) (xy 189.057988 -96.252978) (xy 188.967828 -96.27066)
			(xy 188.87648 -96.280526) (xy 188.784623 -96.282503) (xy 188.692936 -96.276576) (xy 188.602098 -96.26279)
			(xy 188.512781 -96.241245) (xy 188.425647 -96.212102) (xy 188.341341 -96.175576) (xy 188.260487 -96.131938)
			(xy 188.183683 -96.081511) (xy 188.111499 -96.024669) (xy 188.044468 -95.961831) (xy 187.983087 -95.893464)
			(xy 187.927811 -95.820074) (xy 187.879048 -95.742203) (xy 187.83716 -95.660428) (xy 187.802457 -95.575356)
			(xy 187.775195 -95.487615) (xy 187.755578 -95.397855) (xy 187.743748 -95.306741) (xy 187.739796 -95.214948)
			(xy 165.509702 -95.214948) (xy 165.509702 -95.261489) (xy 165.501581 -95.354313) (xy 165.485401 -95.446077)
			(xy 165.461286 -95.536081) (xy 165.429417 -95.62364) (xy 165.390039 -95.708089) (xy 165.343451 -95.788785)
			(xy 165.290008 -95.865113) (xy 165.230115 -95.936494) (xy 165.164229 -96.002382) (xy 165.092852 -96.062278)
			(xy 165.016526 -96.115726) (xy 164.935832 -96.162317) (xy 164.851385 -96.201699) (xy 164.763826 -96.233571)
			(xy 164.673824 -96.257691) (xy 164.582061 -96.273875) (xy 164.489237 -96.282) (xy 164.442648 -96.28251)
			(xy 164.442394 -96.28251) (xy 164.395808 -96.281906) (xy 164.30299 -96.273785) (xy 164.211233 -96.257605)
			(xy 164.121235 -96.23349) (xy 164.033681 -96.201622) (xy 163.949238 -96.162246) (xy 163.868549 -96.115659)
			(xy 163.792226 -96.062217) (xy 163.720852 -96.002327) (xy 163.654969 -95.936443) (xy 163.595079 -95.865069)
			(xy 163.541638 -95.788746) (xy 163.495052 -95.708056) (xy 163.455675 -95.623613) (xy 163.423808 -95.536059)
			(xy 163.399694 -95.446062) (xy 163.383515 -95.354304) (xy 163.375394 -95.261486) (xy 73.774772 -95.261486)
			(xy 73.76692 -95.352491) (xy 73.751174 -95.443055) (xy 73.727701 -95.53193) (xy 73.696676 -95.618458)
			(xy 73.658326 -95.701998) (xy 73.612937 -95.781933) (xy 73.560845 -95.85767) (xy 73.502434 -95.928648)
			(xy 73.438139 -95.994342) (xy 73.368433 -96.054266) (xy 73.293835 -96.107976) (xy 73.214895 -96.155075)
			(xy 73.132199 -96.195213) (xy 73.046359 -96.228093) (xy 72.95801 -96.253473) (xy 72.867806 -96.271163)
			(xy 72.776415 -96.281034) (xy 72.684514 -96.283012) (xy 72.592783 -96.277082) (xy 72.501902 -96.263288)
			(xy 72.412543 -96.241734) (xy 72.325367 -96.212577) (xy 72.241021 -96.176034) (xy 72.160128 -96.132375)
			(xy 72.083288 -96.081924) (xy 72.011069 -96.025054) (xy 71.944007 -95.962187) (xy 71.882597 -95.893787)
			(xy 71.827294 -95.820362) (xy 71.778508 -95.742454) (xy 71.7366 -95.660641) (xy 71.70188 -95.575527)
			(xy 71.674606 -95.487745) (xy 71.654979 -95.397942) (xy 71.643144 -95.306785) (xy 71.639189 -95.214948)
			(xy 49.410366 -95.214948) (xy 49.409872 -95.260909) (xy 49.40197 -95.352491) (xy 49.386224 -95.443055)
			(xy 49.362751 -95.53193) (xy 49.331726 -95.618458) (xy 49.293376 -95.701998) (xy 49.247987 -95.781933)
			(xy 49.195895 -95.85767) (xy 49.137484 -95.928648) (xy 49.073189 -95.994342) (xy 49.003483 -96.054266)
			(xy 48.928885 -96.107976) (xy 48.849945 -96.155075) (xy 48.767249 -96.195213) (xy 48.681409 -96.228093)
			(xy 48.59306 -96.253473) (xy 48.502856 -96.271163) (xy 48.411465 -96.281034) (xy 48.319564 -96.283012)
			(xy 48.227833 -96.277082) (xy 48.136952 -96.263288) (xy 48.047593 -96.241734) (xy 47.960417 -96.212577)
			(xy 47.876071 -96.176034) (xy 47.795178 -96.132375) (xy 47.718338 -96.081924) (xy 47.646119 -96.025054)
			(xy 47.579057 -95.962187) (xy 47.517647 -95.893787) (xy 47.462344 -95.820362) (xy 47.413558 -95.742454)
			(xy 47.37165 -95.660641) (xy 47.33693 -95.575527) (xy 47.309656 -95.487745) (xy 47.290029 -95.397942)
			(xy 47.278194 -95.306785) (xy 47.274239 -95.214948) (xy 4.30911 -95.214948) (xy 4.30911 -98.766863)
			(xy 206.090008 -98.766863) (xy 206.090008 -98.633301) (xy 206.098072 -98.499983) (xy 206.114172 -98.367395)
			(xy 206.138247 -98.236021) (xy 206.17021 -98.10634) (xy 206.209945 -97.978826) (xy 206.257307 -97.853943)
			(xy 206.312122 -97.732148) (xy 206.374192 -97.613885) (xy 206.443288 -97.499586) (xy 206.51916 -97.389666)
			(xy 206.60153 -97.284529) (xy 206.690098 -97.184556) (xy 206.78454 -97.090114) (xy 206.884513 -97.001546)
			(xy 206.98965 -96.919176) (xy 207.09957 -96.843304) (xy 207.213869 -96.774208) (xy 207.332132 -96.712138)
			(xy 207.453927 -96.657323) (xy 207.57881 -96.609961) (xy 207.706324 -96.570226) (xy 207.836005 -96.538263)
			(xy 207.967379 -96.514188) (xy 208.099967 -96.498088) (xy 208.233285 -96.490024) (xy 208.366847 -96.490024)
			(xy 208.500165 -96.498088) (xy 208.632753 -96.514188) (xy 208.764127 -96.538263) (xy 208.893808 -96.570226)
			(xy 209.021322 -96.609961) (xy 209.146205 -96.657323) (xy 209.268 -96.712138) (xy 209.386263 -96.774208)
			(xy 209.500562 -96.843304) (xy 209.610482 -96.919176) (xy 209.715619 -97.001546) (xy 209.815592 -97.090114)
			(xy 209.910034 -97.184556) (xy 209.998602 -97.284529) (xy 210.080972 -97.389666) (xy 210.156844 -97.499586)
			(xy 210.22594 -97.613885) (xy 210.28801 -97.732148) (xy 210.342825 -97.853943) (xy 210.390187 -97.978826)
			(xy 210.429922 -98.10634) (xy 210.461885 -98.236021) (xy 210.48596 -98.367395) (xy 210.50206 -98.499983)
			(xy 210.510124 -98.633301) (xy 210.510628 -98.700082) (xy 210.510124 -98.766863) (xy 257.089906 -98.766863)
			(xy 257.089906 -98.633301) (xy 257.09797 -98.499983) (xy 257.11407 -98.367395) (xy 257.138145 -98.236021)
			(xy 257.170108 -98.10634) (xy 257.209843 -97.978826) (xy 257.257205 -97.853943) (xy 257.31202 -97.732148)
			(xy 257.37409 -97.613885) (xy 257.443186 -97.499586) (xy 257.519058 -97.389666) (xy 257.601428 -97.284529)
			(xy 257.689996 -97.184556) (xy 257.784438 -97.090114) (xy 257.884411 -97.001546) (xy 257.989548 -96.919176)
			(xy 258.099468 -96.843304) (xy 258.213767 -96.774208) (xy 258.33203 -96.712138) (xy 258.453825 -96.657323)
			(xy 258.578708 -96.609961) (xy 258.706222 -96.570226) (xy 258.835903 -96.538263) (xy 258.967277 -96.514188)
			(xy 259.099865 -96.498088) (xy 259.233183 -96.490024) (xy 259.366745 -96.490024) (xy 259.500063 -96.498088)
			(xy 259.632651 -96.514188) (xy 259.764025 -96.538263) (xy 259.893706 -96.570226) (xy 260.02122 -96.609961)
			(xy 260.146103 -96.657323) (xy 260.267898 -96.712138) (xy 260.386161 -96.774208) (xy 260.50046 -96.843304)
			(xy 260.61038 -96.919176) (xy 260.715517 -97.001546) (xy 260.81549 -97.090114) (xy 260.909932 -97.184556)
			(xy 260.9985 -97.284529) (xy 261.08087 -97.389666) (xy 261.156742 -97.499586) (xy 261.225838 -97.613885)
			(xy 261.287908 -97.732148) (xy 261.342723 -97.853943) (xy 261.390085 -97.978826) (xy 261.42982 -98.10634)
			(xy 261.461783 -98.236021) (xy 261.485858 -98.367395) (xy 261.501958 -98.499983) (xy 261.510022 -98.633301)
			(xy 261.510526 -98.700082) (xy 261.510022 -98.766863) (xy 261.501958 -98.900181) (xy 261.485858 -99.032769)
			(xy 261.461783 -99.164143) (xy 261.42982 -99.293824) (xy 261.390085 -99.421338) (xy 261.342723 -99.546221)
			(xy 261.287908 -99.668016) (xy 261.225838 -99.786279) (xy 261.156742 -99.900578) (xy 261.08087 -100.010498)
			(xy 260.9985 -100.115635) (xy 260.943379 -100.177854) (xy 269.509748 -100.177854) (xy 269.509748 -99.314254)
			(xy 269.510238 -99.28427) (xy 269.518066 -99.224814) (xy 269.533587 -99.166889) (xy 269.556536 -99.111485)
			(xy 269.58652 -99.059551) (xy 269.623026 -99.011975) (xy 269.665431 -98.96957) (xy 269.713007 -98.933064)
			(xy 269.764941 -98.90308) (xy 269.820345 -98.880131) (xy 269.87827 -98.86461) (xy 269.937726 -98.856782)
			(xy 269.997694 -98.856782) (xy 270.05715 -98.86461) (xy 270.115075 -98.880131) (xy 270.170479 -98.90308)
			(xy 270.222413 -98.933064) (xy 270.269989 -98.96957) (xy 270.312394 -99.011975) (xy 270.3489 -99.059551)
			(xy 270.378884 -99.111485) (xy 270.401833 -99.166889) (xy 270.417354 -99.224814) (xy 270.425182 -99.28427)
			(xy 270.425672 -99.314254) (xy 270.425672 -100.17633) (xy 285.8389 -100.17633) (xy 285.8389 -99.31273)
			(xy 285.83939 -99.282746) (xy 285.847218 -99.22329) (xy 285.862739 -99.165365) (xy 285.885688 -99.109961)
			(xy 285.915672 -99.058027) (xy 285.952178 -99.010451) (xy 285.994583 -98.968046) (xy 286.042159 -98.93154)
			(xy 286.094093 -98.901556) (xy 286.149497 -98.878607) (xy 286.207422 -98.863086) (xy 286.266878 -98.855258)
			(xy 286.326846 -98.855258) (xy 286.386302 -98.863086) (xy 286.444227 -98.878607) (xy 286.499631 -98.901556)
			(xy 286.551565 -98.93154) (xy 286.599141 -98.968046) (xy 286.641546 -99.010451) (xy 286.678052 -99.058027)
			(xy 286.708036 -99.109961) (xy 286.730985 -99.165365) (xy 286.746506 -99.22329) (xy 286.754334 -99.282746)
			(xy 286.754824 -99.31273) (xy 286.754824 -100.17633) (xy 286.754799 -100.177854) (xy 385.6101 -100.177854)
			(xy 385.6101 -99.314254) (xy 385.61059 -99.284286) (xy 385.618413 -99.224864) (xy 385.633926 -99.166971)
			(xy 385.656862 -99.111598) (xy 385.686829 -99.059692) (xy 385.723316 -99.012142) (xy 385.765696 -98.969762)
			(xy 385.813246 -98.933275) (xy 385.865152 -98.903308) (xy 385.920525 -98.880372) (xy 385.978418 -98.864859)
			(xy 386.03784 -98.857036) (xy 386.097776 -98.857036) (xy 386.157198 -98.864859) (xy 386.215091 -98.880372)
			(xy 386.270464 -98.903308) (xy 386.32237 -98.933275) (xy 386.36992 -98.969762) (xy 386.4123 -99.012142)
			(xy 386.448787 -99.059692) (xy 386.478754 -99.111598) (xy 386.50169 -99.166971) (xy 386.517203 -99.224864)
			(xy 386.525026 -99.284286) (xy 386.525516 -99.314254) (xy 386.525516 -100.17633) (xy 401.939252 -100.17633)
			(xy 401.939252 -99.31273) (xy 401.939742 -99.282762) (xy 401.947565 -99.22334) (xy 401.963078 -99.165447)
			(xy 401.986014 -99.110074) (xy 402.015981 -99.058168) (xy 402.052468 -99.010618) (xy 402.094848 -98.968238)
			(xy 402.142398 -98.931751) (xy 402.194304 -98.901784) (xy 402.249677 -98.878848) (xy 402.30757 -98.863335)
			(xy 402.366992 -98.855512) (xy 402.426928 -98.855512) (xy 402.48635 -98.863335) (xy 402.544243 -98.878848)
			(xy 402.599616 -98.901784) (xy 402.651522 -98.931751) (xy 402.699072 -98.968238) (xy 402.741452 -99.010618)
			(xy 402.777939 -99.058168) (xy 402.807906 -99.110074) (xy 402.830842 -99.165447) (xy 402.846355 -99.22334)
			(xy 402.854178 -99.282762) (xy 402.854668 -99.31273) (xy 402.854668 -100.17633) (xy 402.854178 -100.206298)
			(xy 402.846355 -100.26572) (xy 402.830842 -100.323613) (xy 402.807906 -100.378986) (xy 402.777939 -100.430892)
			(xy 402.741452 -100.478442) (xy 402.699072 -100.520822) (xy 402.651522 -100.557309) (xy 402.599616 -100.587276)
			(xy 402.544243 -100.610212) (xy 402.48635 -100.625725) (xy 402.426928 -100.633548) (xy 402.366992 -100.633548)
			(xy 402.30757 -100.625725) (xy 402.249677 -100.610212) (xy 402.194304 -100.587276) (xy 402.142398 -100.557309)
			(xy 402.094848 -100.520822) (xy 402.052468 -100.478442) (xy 402.015981 -100.430892) (xy 401.986014 -100.378986)
			(xy 401.963078 -100.323613) (xy 401.947565 -100.26572) (xy 401.939742 -100.206298) (xy 401.939252 -100.17633)
			(xy 386.525516 -100.17633) (xy 386.525516 -100.177854) (xy 386.525026 -100.207822) (xy 386.517203 -100.267244)
			(xy 386.50169 -100.325137) (xy 386.478754 -100.38051) (xy 386.448787 -100.432416) (xy 386.4123 -100.479966)
			(xy 386.36992 -100.522346) (xy 386.32237 -100.558833) (xy 386.270464 -100.5888) (xy 386.215091 -100.611736)
			(xy 386.157198 -100.627249) (xy 386.097776 -100.635072) (xy 386.03784 -100.635072) (xy 385.978418 -100.627249)
			(xy 385.920525 -100.611736) (xy 385.865152 -100.5888) (xy 385.813246 -100.558833) (xy 385.765696 -100.522346)
			(xy 385.723316 -100.479966) (xy 385.686829 -100.432416) (xy 385.656862 -100.38051) (xy 385.633926 -100.325137)
			(xy 385.618413 -100.267244) (xy 385.61059 -100.207822) (xy 385.6101 -100.177854) (xy 286.754799 -100.177854)
			(xy 286.754334 -100.206314) (xy 286.746506 -100.26577) (xy 286.730985 -100.323695) (xy 286.708036 -100.379099)
			(xy 286.678052 -100.431033) (xy 286.641546 -100.478609) (xy 286.599141 -100.521014) (xy 286.551565 -100.55752)
			(xy 286.499631 -100.587504) (xy 286.444227 -100.610453) (xy 286.386302 -100.625974) (xy 286.326846 -100.633802)
			(xy 286.266878 -100.633802) (xy 286.207422 -100.625974) (xy 286.149497 -100.610453) (xy 286.094093 -100.587504)
			(xy 286.042159 -100.55752) (xy 285.994583 -100.521014) (xy 285.952178 -100.478609) (xy 285.915672 -100.431033)
			(xy 285.885688 -100.379099) (xy 285.862739 -100.323695) (xy 285.847218 -100.26577) (xy 285.83939 -100.206314)
			(xy 285.8389 -100.17633) (xy 270.425672 -100.17633) (xy 270.425672 -100.177854) (xy 270.425182 -100.207838)
			(xy 270.417354 -100.267294) (xy 270.401833 -100.325219) (xy 270.378884 -100.380623) (xy 270.3489 -100.432557)
			(xy 270.312394 -100.480133) (xy 270.269989 -100.522538) (xy 270.222413 -100.559044) (xy 270.170479 -100.589028)
			(xy 270.115075 -100.611977) (xy 270.05715 -100.627498) (xy 269.997694 -100.635326) (xy 269.937726 -100.635326)
			(xy 269.87827 -100.627498) (xy 269.820345 -100.611977) (xy 269.764941 -100.589028) (xy 269.713007 -100.559044)
			(xy 269.665431 -100.522538) (xy 269.623026 -100.480133) (xy 269.58652 -100.432557) (xy 269.556536 -100.380623)
			(xy 269.533587 -100.325219) (xy 269.518066 -100.267294) (xy 269.510238 -100.207838) (xy 269.509748 -100.177854)
			(xy 260.943379 -100.177854) (xy 260.909932 -100.215608) (xy 260.81549 -100.31005) (xy 260.715517 -100.398618)
			(xy 260.61038 -100.480988) (xy 260.50046 -100.55686) (xy 260.386161 -100.625956) (xy 260.267898 -100.688026)
			(xy 260.146103 -100.742841) (xy 260.02122 -100.790203) (xy 259.893706 -100.829938) (xy 259.764025 -100.861901)
			(xy 259.632651 -100.885976) (xy 259.500063 -100.902076) (xy 259.366745 -100.91014) (xy 259.233183 -100.91014)
			(xy 259.099865 -100.902076) (xy 258.967277 -100.885976) (xy 258.835903 -100.861901) (xy 258.706222 -100.829938)
			(xy 258.578708 -100.790203) (xy 258.453825 -100.742841) (xy 258.33203 -100.688026) (xy 258.213767 -100.625956)
			(xy 258.099468 -100.55686) (xy 257.989548 -100.480988) (xy 257.884411 -100.398618) (xy 257.784438 -100.31005)
			(xy 257.689996 -100.215608) (xy 257.601428 -100.115635) (xy 257.519058 -100.010498) (xy 257.443186 -99.900578)
			(xy 257.37409 -99.786279) (xy 257.31202 -99.668016) (xy 257.257205 -99.546221) (xy 257.209843 -99.421338)
			(xy 257.170108 -99.293824) (xy 257.138145 -99.164143) (xy 257.11407 -99.032769) (xy 257.09797 -98.900181)
			(xy 257.089906 -98.766863) (xy 210.510124 -98.766863) (xy 210.50206 -98.900181) (xy 210.48596 -99.032769)
			(xy 210.461885 -99.164143) (xy 210.429922 -99.293824) (xy 210.390187 -99.421338) (xy 210.342825 -99.546221)
			(xy 210.28801 -99.668016) (xy 210.22594 -99.786279) (xy 210.156844 -99.900578) (xy 210.080972 -100.010498)
			(xy 209.998602 -100.115635) (xy 209.910034 -100.215608) (xy 209.815592 -100.31005) (xy 209.715619 -100.398618)
			(xy 209.610482 -100.480988) (xy 209.500562 -100.55686) (xy 209.386263 -100.625956) (xy 209.268 -100.688026)
			(xy 209.146205 -100.742841) (xy 209.021322 -100.790203) (xy 208.893808 -100.829938) (xy 208.764127 -100.861901)
			(xy 208.632753 -100.885976) (xy 208.500165 -100.902076) (xy 208.366847 -100.91014) (xy 208.233285 -100.91014)
			(xy 208.099967 -100.902076) (xy 207.967379 -100.885976) (xy 207.836005 -100.861901) (xy 207.706324 -100.829938)
			(xy 207.57881 -100.790203) (xy 207.453927 -100.742841) (xy 207.332132 -100.688026) (xy 207.213869 -100.625956)
			(xy 207.09957 -100.55686) (xy 206.98965 -100.480988) (xy 206.884513 -100.398618) (xy 206.78454 -100.31005)
			(xy 206.690098 -100.215608) (xy 206.60153 -100.115635) (xy 206.51916 -100.010498) (xy 206.443288 -99.900578)
			(xy 206.374192 -99.786279) (xy 206.312122 -99.668016) (xy 206.257307 -99.546221) (xy 206.209945 -99.421338)
			(xy 206.17021 -99.293824) (xy 206.138247 -99.164143) (xy 206.114172 -99.032769) (xy 206.098072 -98.900181)
			(xy 206.090008 -98.766863) (xy 4.30911 -98.766863) (xy 4.30911 -100.177854) (xy 37.31006 -100.177854)
			(xy 37.31006 -99.314254) (xy 37.31055 -99.284286) (xy 37.318373 -99.224864) (xy 37.333886 -99.166971)
			(xy 37.356822 -99.111598) (xy 37.386789 -99.059692) (xy 37.423276 -99.012142) (xy 37.465656 -98.969762)
			(xy 37.513206 -98.933275) (xy 37.565112 -98.903308) (xy 37.620485 -98.880372) (xy 37.678378 -98.864859)
			(xy 37.7378 -98.857036) (xy 37.797736 -98.857036) (xy 37.857158 -98.864859) (xy 37.915051 -98.880372)
			(xy 37.970424 -98.903308) (xy 38.02233 -98.933275) (xy 38.06988 -98.969762) (xy 38.11226 -99.012142)
			(xy 38.148747 -99.059692) (xy 38.178714 -99.111598) (xy 38.20165 -99.166971) (xy 38.217163 -99.224864)
			(xy 38.224986 -99.284286) (xy 38.225476 -99.314254) (xy 38.225476 -100.17633) (xy 53.639212 -100.17633)
			(xy 53.639212 -99.31273) (xy 53.639702 -99.282762) (xy 53.647525 -99.22334) (xy 53.663038 -99.165447)
			(xy 53.685974 -99.110074) (xy 53.715941 -99.058168) (xy 53.752428 -99.010618) (xy 53.794808 -98.968238)
			(xy 53.842358 -98.931751) (xy 53.894264 -98.901784) (xy 53.949637 -98.878848) (xy 54.00753 -98.863335)
			(xy 54.066952 -98.855512) (xy 54.126888 -98.855512) (xy 54.18631 -98.863335) (xy 54.244203 -98.878848)
			(xy 54.299576 -98.901784) (xy 54.351482 -98.931751) (xy 54.399032 -98.968238) (xy 54.441412 -99.010618)
			(xy 54.477899 -99.058168) (xy 54.507866 -99.110074) (xy 54.530802 -99.165447) (xy 54.546315 -99.22334)
			(xy 54.554138 -99.282762) (xy 54.554628 -99.31273) (xy 54.554628 -100.17633) (xy 54.554603 -100.177854)
			(xy 153.409904 -100.177854) (xy 153.409904 -99.314254) (xy 153.410394 -99.28427) (xy 153.418222 -99.224814)
			(xy 153.433743 -99.166889) (xy 153.456692 -99.111485) (xy 153.486676 -99.059551) (xy 153.523182 -99.011975)
			(xy 153.565587 -98.96957) (xy 153.613163 -98.933064) (xy 153.665097 -98.90308) (xy 153.720501 -98.880131)
			(xy 153.778426 -98.86461) (xy 153.837882 -98.856782) (xy 153.89785 -98.856782) (xy 153.957306 -98.86461)
			(xy 154.015231 -98.880131) (xy 154.070635 -98.90308) (xy 154.122569 -98.933064) (xy 154.170145 -98.96957)
			(xy 154.21255 -99.011975) (xy 154.249056 -99.059551) (xy 154.27904 -99.111485) (xy 154.301989 -99.166889)
			(xy 154.31751 -99.224814) (xy 154.325338 -99.28427) (xy 154.325828 -99.314254) (xy 154.325828 -100.17633)
			(xy 169.739056 -100.17633) (xy 169.739056 -99.31273) (xy 169.739546 -99.282746) (xy 169.747374 -99.22329)
			(xy 169.762895 -99.165365) (xy 169.785844 -99.109961) (xy 169.815828 -99.058027) (xy 169.852334 -99.010451)
			(xy 169.894739 -98.968046) (xy 169.942315 -98.93154) (xy 169.994249 -98.901556) (xy 170.049653 -98.878607)
			(xy 170.107578 -98.863086) (xy 170.167034 -98.855258) (xy 170.227002 -98.855258) (xy 170.286458 -98.863086)
			(xy 170.344383 -98.878607) (xy 170.399787 -98.901556) (xy 170.451721 -98.93154) (xy 170.499297 -98.968046)
			(xy 170.541702 -99.010451) (xy 170.578208 -99.058027) (xy 170.608192 -99.109961) (xy 170.631141 -99.165365)
			(xy 170.646662 -99.22329) (xy 170.65449 -99.282746) (xy 170.65498 -99.31273) (xy 170.65498 -100.17633)
			(xy 170.65449 -100.206314) (xy 170.646662 -100.26577) (xy 170.631141 -100.323695) (xy 170.608192 -100.379099)
			(xy 170.578208 -100.431033) (xy 170.541702 -100.478609) (xy 170.499297 -100.521014) (xy 170.451721 -100.55752)
			(xy 170.399787 -100.587504) (xy 170.344383 -100.610453) (xy 170.286458 -100.625974) (xy 170.227002 -100.633802)
			(xy 170.167034 -100.633802) (xy 170.107578 -100.625974) (xy 170.049653 -100.610453) (xy 169.994249 -100.587504)
			(xy 169.942315 -100.55752) (xy 169.894739 -100.521014) (xy 169.852334 -100.478609) (xy 169.815828 -100.431033)
			(xy 169.785844 -100.379099) (xy 169.762895 -100.323695) (xy 169.747374 -100.26577) (xy 169.739546 -100.206314)
			(xy 169.739056 -100.17633) (xy 154.325828 -100.17633) (xy 154.325828 -100.177854) (xy 154.325338 -100.207838)
			(xy 154.31751 -100.267294) (xy 154.301989 -100.325219) (xy 154.27904 -100.380623) (xy 154.249056 -100.432557)
			(xy 154.21255 -100.480133) (xy 154.170145 -100.522538) (xy 154.122569 -100.559044) (xy 154.070635 -100.589028)
			(xy 154.015231 -100.611977) (xy 153.957306 -100.627498) (xy 153.89785 -100.635326) (xy 153.837882 -100.635326)
			(xy 153.778426 -100.627498) (xy 153.720501 -100.611977) (xy 153.665097 -100.589028) (xy 153.613163 -100.559044)
			(xy 153.565587 -100.522538) (xy 153.523182 -100.480133) (xy 153.486676 -100.432557) (xy 153.456692 -100.380623)
			(xy 153.433743 -100.325219) (xy 153.418222 -100.267294) (xy 153.410394 -100.207838) (xy 153.409904 -100.177854)
			(xy 54.554603 -100.177854) (xy 54.554138 -100.206298) (xy 54.546315 -100.26572) (xy 54.530802 -100.323613)
			(xy 54.507866 -100.378986) (xy 54.477899 -100.430892) (xy 54.441412 -100.478442) (xy 54.399032 -100.520822)
			(xy 54.351482 -100.557309) (xy 54.299576 -100.587276) (xy 54.244203 -100.610212) (xy 54.18631 -100.625725)
			(xy 54.126888 -100.633548) (xy 54.066952 -100.633548) (xy 54.00753 -100.625725) (xy 53.949637 -100.610212)
			(xy 53.894264 -100.587276) (xy 53.842358 -100.557309) (xy 53.794808 -100.520822) (xy 53.752428 -100.478442)
			(xy 53.715941 -100.430892) (xy 53.685974 -100.378986) (xy 53.663038 -100.323613) (xy 53.647525 -100.26572)
			(xy 53.639702 -100.206298) (xy 53.639212 -100.17633) (xy 38.225476 -100.17633) (xy 38.225476 -100.177854)
			(xy 38.224986 -100.207822) (xy 38.217163 -100.267244) (xy 38.20165 -100.325137) (xy 38.178714 -100.38051)
			(xy 38.148747 -100.432416) (xy 38.11226 -100.479966) (xy 38.06988 -100.522346) (xy 38.02233 -100.558833)
			(xy 37.970424 -100.5888) (xy 37.915051 -100.611736) (xy 37.857158 -100.627249) (xy 37.797736 -100.635072)
			(xy 37.7378 -100.635072) (xy 37.678378 -100.627249) (xy 37.620485 -100.611736) (xy 37.565112 -100.5888)
			(xy 37.513206 -100.558833) (xy 37.465656 -100.522346) (xy 37.423276 -100.479966) (xy 37.386789 -100.432416)
			(xy 37.356822 -100.38051) (xy 37.333886 -100.325137) (xy 37.318373 -100.267244) (xy 37.31055 -100.207822)
			(xy 37.31006 -100.177854) (xy 4.30911 -100.177854) (xy 4.30911 -101.984302) (xy 35.277552 -101.984302)
			(xy 35.277552 -101.120702) (xy 35.278042 -101.090734) (xy 35.285865 -101.031312) (xy 35.301378 -100.973419)
			(xy 35.324314 -100.918046) (xy 35.354281 -100.86614) (xy 35.390768 -100.81859) (xy 35.433148 -100.77621)
			(xy 35.480698 -100.739723) (xy 35.532604 -100.709756) (xy 35.587977 -100.68682) (xy 35.64587 -100.671307)
			(xy 35.705292 -100.663484) (xy 35.765228 -100.663484) (xy 35.82465 -100.671307) (xy 35.882543 -100.68682)
			(xy 35.937916 -100.709756) (xy 35.989822 -100.739723) (xy 36.037372 -100.77621) (xy 36.079752 -100.81859)
			(xy 36.116239 -100.86614) (xy 36.146206 -100.918046) (xy 36.169142 -100.973419) (xy 36.184655 -101.031312)
			(xy 36.192478 -101.090734) (xy 36.192968 -101.120702) (xy 36.192968 -101.976428) (xy 51.785012 -101.976428)
			(xy 51.785012 -101.112828) (xy 51.785502 -101.08286) (xy 51.793325 -101.023438) (xy 51.808838 -100.965545)
			(xy 51.831774 -100.910172) (xy 51.861741 -100.858266) (xy 51.898228 -100.810716) (xy 51.940608 -100.768336)
			(xy 51.988158 -100.731849) (xy 52.040064 -100.701882) (xy 52.095437 -100.678946) (xy 52.15333 -100.663433)
			(xy 52.212752 -100.65561) (xy 52.272688 -100.65561) (xy 52.33211 -100.663433) (xy 52.390003 -100.678946)
			(xy 52.445376 -100.701882) (xy 52.497282 -100.731849) (xy 52.544832 -100.768336) (xy 52.587212 -100.810716)
			(xy 52.623699 -100.858266) (xy 52.653666 -100.910172) (xy 52.676602 -100.965545) (xy 52.692115 -101.023438)
			(xy 52.699938 -101.08286) (xy 52.700428 -101.112828) (xy 52.700428 -101.976428) (xy 52.700299 -101.984302)
			(xy 151.377396 -101.984302) (xy 151.377396 -101.120702) (xy 151.377886 -101.090718) (xy 151.385714 -101.031262)
			(xy 151.401235 -100.973337) (xy 151.424184 -100.917933) (xy 151.454168 -100.865999) (xy 151.490674 -100.818423)
			(xy 151.533079 -100.776018) (xy 151.580655 -100.739512) (xy 151.632589 -100.709528) (xy 151.687993 -100.686579)
			(xy 151.745918 -100.671058) (xy 151.805374 -100.66323) (xy 151.865342 -100.66323) (xy 151.924798 -100.671058)
			(xy 151.982723 -100.686579) (xy 152.038127 -100.709528) (xy 152.090061 -100.739512) (xy 152.137637 -100.776018)
			(xy 152.180042 -100.818423) (xy 152.216548 -100.865999) (xy 152.246532 -100.917933) (xy 152.269481 -100.973337)
			(xy 152.285002 -101.031262) (xy 152.29283 -101.090718) (xy 152.29332 -101.120702) (xy 152.29332 -101.976428)
			(xy 167.884856 -101.976428) (xy 167.884856 -101.112828) (xy 167.885346 -101.082844) (xy 167.893174 -101.023388)
			(xy 167.908695 -100.965463) (xy 167.931644 -100.910059) (xy 167.961628 -100.858125) (xy 167.998134 -100.810549)
			(xy 168.040539 -100.768144) (xy 168.088115 -100.731638) (xy 168.140049 -100.701654) (xy 168.195453 -100.678705)
			(xy 168.253378 -100.663184) (xy 168.312834 -100.655356) (xy 168.372802 -100.655356) (xy 168.432258 -100.663184)
			(xy 168.490183 -100.678705) (xy 168.545587 -100.701654) (xy 168.597521 -100.731638) (xy 168.645097 -100.768144)
			(xy 168.687502 -100.810549) (xy 168.724008 -100.858125) (xy 168.753992 -100.910059) (xy 168.776941 -100.965463)
			(xy 168.792462 -101.023388) (xy 168.80029 -101.082844) (xy 168.80078 -101.112828) (xy 168.80078 -101.976428)
			(xy 168.800651 -101.984302) (xy 267.47724 -101.984302) (xy 267.47724 -101.120702) (xy 267.47773 -101.090718)
			(xy 267.485558 -101.031262) (xy 267.501079 -100.973337) (xy 267.524028 -100.917933) (xy 267.554012 -100.865999)
			(xy 267.590518 -100.818423) (xy 267.632923 -100.776018) (xy 267.680499 -100.739512) (xy 267.732433 -100.709528)
			(xy 267.787837 -100.686579) (xy 267.845762 -100.671058) (xy 267.905218 -100.66323) (xy 267.965186 -100.66323)
			(xy 268.024642 -100.671058) (xy 268.082567 -100.686579) (xy 268.137971 -100.709528) (xy 268.189905 -100.739512)
			(xy 268.237481 -100.776018) (xy 268.279886 -100.818423) (xy 268.316392 -100.865999) (xy 268.346376 -100.917933)
			(xy 268.369325 -100.973337) (xy 268.384846 -101.031262) (xy 268.392674 -101.090718) (xy 268.393164 -101.120702)
			(xy 268.393164 -101.976428) (xy 283.9847 -101.976428) (xy 283.9847 -101.112828) (xy 283.98519 -101.082844)
			(xy 283.993018 -101.023388) (xy 284.008539 -100.965463) (xy 284.031488 -100.910059) (xy 284.061472 -100.858125)
			(xy 284.097978 -100.810549) (xy 284.140383 -100.768144) (xy 284.187959 -100.731638) (xy 284.239893 -100.701654)
			(xy 284.295297 -100.678705) (xy 284.353222 -100.663184) (xy 284.412678 -100.655356) (xy 284.472646 -100.655356)
			(xy 284.532102 -100.663184) (xy 284.590027 -100.678705) (xy 284.645431 -100.701654) (xy 284.697365 -100.731638)
			(xy 284.744941 -100.768144) (xy 284.787346 -100.810549) (xy 284.823852 -100.858125) (xy 284.853836 -100.910059)
			(xy 284.876785 -100.965463) (xy 284.892306 -101.023388) (xy 284.900134 -101.082844) (xy 284.900624 -101.112828)
			(xy 284.900624 -101.976428) (xy 284.900495 -101.984302) (xy 383.577592 -101.984302) (xy 383.577592 -101.120702)
			(xy 383.578082 -101.090734) (xy 383.585905 -101.031312) (xy 383.601418 -100.973419) (xy 383.624354 -100.918046)
			(xy 383.654321 -100.86614) (xy 383.690808 -100.81859) (xy 383.733188 -100.77621) (xy 383.780738 -100.739723)
			(xy 383.832644 -100.709756) (xy 383.888017 -100.68682) (xy 383.94591 -100.671307) (xy 384.005332 -100.663484)
			(xy 384.065268 -100.663484) (xy 384.12469 -100.671307) (xy 384.182583 -100.68682) (xy 384.237956 -100.709756)
			(xy 384.289862 -100.739723) (xy 384.337412 -100.77621) (xy 384.379792 -100.81859) (xy 384.416279 -100.86614)
			(xy 384.446246 -100.918046) (xy 384.469182 -100.973419) (xy 384.484695 -101.031312) (xy 384.492518 -101.090734)
			(xy 384.493008 -101.120702) (xy 384.493008 -101.976428) (xy 400.085052 -101.976428) (xy 400.085052 -101.112828)
			(xy 400.085542 -101.08286) (xy 400.093365 -101.023438) (xy 400.108878 -100.965545) (xy 400.131814 -100.910172)
			(xy 400.161781 -100.858266) (xy 400.198268 -100.810716) (xy 400.240648 -100.768336) (xy 400.288198 -100.731849)
			(xy 400.340104 -100.701882) (xy 400.395477 -100.678946) (xy 400.45337 -100.663433) (xy 400.512792 -100.65561)
			(xy 400.572728 -100.65561) (xy 400.63215 -100.663433) (xy 400.690043 -100.678946) (xy 400.745416 -100.701882)
			(xy 400.797322 -100.731849) (xy 400.844872 -100.768336) (xy 400.887252 -100.810716) (xy 400.923739 -100.858266)
			(xy 400.953706 -100.910172) (xy 400.976642 -100.965545) (xy 400.992155 -101.023438) (xy 400.999978 -101.08286)
			(xy 401.000468 -101.112828) (xy 401.000468 -101.976428) (xy 400.999978 -102.006396) (xy 400.992155 -102.065818)
			(xy 400.976642 -102.123711) (xy 400.953706 -102.179084) (xy 400.923739 -102.23099) (xy 400.887252 -102.27854)
			(xy 400.844872 -102.32092) (xy 400.797322 -102.357407) (xy 400.745416 -102.387374) (xy 400.690043 -102.41031)
			(xy 400.63215 -102.425823) (xy 400.572728 -102.433646) (xy 400.512792 -102.433646) (xy 400.45337 -102.425823)
			(xy 400.395477 -102.41031) (xy 400.340104 -102.387374) (xy 400.288198 -102.357407) (xy 400.240648 -102.32092)
			(xy 400.198268 -102.27854) (xy 400.161781 -102.23099) (xy 400.131814 -102.179084) (xy 400.108878 -102.123711)
			(xy 400.093365 -102.065818) (xy 400.085542 -102.006396) (xy 400.085052 -101.976428) (xy 384.493008 -101.976428)
			(xy 384.493008 -101.984302) (xy 384.492518 -102.01427) (xy 384.484695 -102.073692) (xy 384.469182 -102.131585)
			(xy 384.446246 -102.186958) (xy 384.416279 -102.238864) (xy 384.379792 -102.286414) (xy 384.337412 -102.328794)
			(xy 384.289862 -102.365281) (xy 384.237956 -102.395248) (xy 384.182583 -102.418184) (xy 384.12469 -102.433697)
			(xy 384.065268 -102.44152) (xy 384.005332 -102.44152) (xy 383.94591 -102.433697) (xy 383.888017 -102.418184)
			(xy 383.832644 -102.395248) (xy 383.780738 -102.365281) (xy 383.733188 -102.328794) (xy 383.690808 -102.286414)
			(xy 383.654321 -102.238864) (xy 383.624354 -102.186958) (xy 383.601418 -102.131585) (xy 383.585905 -102.073692)
			(xy 383.578082 -102.01427) (xy 383.577592 -101.984302) (xy 284.900495 -101.984302) (xy 284.900134 -102.006412)
			(xy 284.892306 -102.065868) (xy 284.876785 -102.123793) (xy 284.853836 -102.179197) (xy 284.823852 -102.231131)
			(xy 284.787346 -102.278707) (xy 284.744941 -102.321112) (xy 284.697365 -102.357618) (xy 284.645431 -102.387602)
			(xy 284.590027 -102.410551) (xy 284.532102 -102.426072) (xy 284.472646 -102.4339) (xy 284.412678 -102.4339)
			(xy 284.353222 -102.426072) (xy 284.295297 -102.410551) (xy 284.239893 -102.387602) (xy 284.187959 -102.357618)
			(xy 284.140383 -102.321112) (xy 284.097978 -102.278707) (xy 284.061472 -102.231131) (xy 284.031488 -102.179197)
			(xy 284.008539 -102.123793) (xy 283.993018 -102.065868) (xy 283.98519 -102.006412) (xy 283.9847 -101.976428)
			(xy 268.393164 -101.976428) (xy 268.393164 -101.984302) (xy 268.392674 -102.014286) (xy 268.384846 -102.073742)
			(xy 268.369325 -102.131667) (xy 268.346376 -102.187071) (xy 268.316392 -102.239005) (xy 268.279886 -102.286581)
			(xy 268.237481 -102.328986) (xy 268.189905 -102.365492) (xy 268.137971 -102.395476) (xy 268.082567 -102.418425)
			(xy 268.024642 -102.433946) (xy 267.965186 -102.441774) (xy 267.905218 -102.441774) (xy 267.845762 -102.433946)
			(xy 267.787837 -102.418425) (xy 267.732433 -102.395476) (xy 267.680499 -102.365492) (xy 267.632923 -102.328986)
			(xy 267.590518 -102.286581) (xy 267.554012 -102.239005) (xy 267.524028 -102.187071) (xy 267.501079 -102.131667)
			(xy 267.485558 -102.073742) (xy 267.47773 -102.014286) (xy 267.47724 -101.984302) (xy 168.800651 -101.984302)
			(xy 168.80029 -102.006412) (xy 168.792462 -102.065868) (xy 168.776941 -102.123793) (xy 168.753992 -102.179197)
			(xy 168.724008 -102.231131) (xy 168.687502 -102.278707) (xy 168.645097 -102.321112) (xy 168.597521 -102.357618)
			(xy 168.545587 -102.387602) (xy 168.490183 -102.410551) (xy 168.432258 -102.426072) (xy 168.372802 -102.4339)
			(xy 168.312834 -102.4339) (xy 168.253378 -102.426072) (xy 168.195453 -102.410551) (xy 168.140049 -102.387602)
			(xy 168.088115 -102.357618) (xy 168.040539 -102.321112) (xy 167.998134 -102.278707) (xy 167.961628 -102.231131)
			(xy 167.931644 -102.179197) (xy 167.908695 -102.123793) (xy 167.893174 -102.065868) (xy 167.885346 -102.006412)
			(xy 167.884856 -101.976428) (xy 152.29332 -101.976428) (xy 152.29332 -101.984302) (xy 152.29283 -102.014286)
			(xy 152.285002 -102.073742) (xy 152.269481 -102.131667) (xy 152.246532 -102.187071) (xy 152.216548 -102.239005)
			(xy 152.180042 -102.286581) (xy 152.137637 -102.328986) (xy 152.090061 -102.365492) (xy 152.038127 -102.395476)
			(xy 151.982723 -102.418425) (xy 151.924798 -102.433946) (xy 151.865342 -102.441774) (xy 151.805374 -102.441774)
			(xy 151.745918 -102.433946) (xy 151.687993 -102.418425) (xy 151.632589 -102.395476) (xy 151.580655 -102.365492)
			(xy 151.533079 -102.328986) (xy 151.490674 -102.286581) (xy 151.454168 -102.239005) (xy 151.424184 -102.187071)
			(xy 151.401235 -102.131667) (xy 151.385714 -102.073742) (xy 151.377886 -102.014286) (xy 151.377396 -101.984302)
			(xy 52.700299 -101.984302) (xy 52.699938 -102.006396) (xy 52.692115 -102.065818) (xy 52.676602 -102.123711)
			(xy 52.653666 -102.179084) (xy 52.623699 -102.23099) (xy 52.587212 -102.27854) (xy 52.544832 -102.32092)
			(xy 52.497282 -102.357407) (xy 52.445376 -102.387374) (xy 52.390003 -102.41031) (xy 52.33211 -102.425823)
			(xy 52.272688 -102.433646) (xy 52.212752 -102.433646) (xy 52.15333 -102.425823) (xy 52.095437 -102.41031)
			(xy 52.040064 -102.387374) (xy 51.988158 -102.357407) (xy 51.940608 -102.32092) (xy 51.898228 -102.27854)
			(xy 51.861741 -102.23099) (xy 51.831774 -102.179084) (xy 51.808838 -102.123711) (xy 51.793325 -102.065818)
			(xy 51.785502 -102.006396) (xy 51.785012 -101.976428) (xy 36.192968 -101.976428) (xy 36.192968 -101.984302)
			(xy 36.192478 -102.01427) (xy 36.184655 -102.073692) (xy 36.169142 -102.131585) (xy 36.146206 -102.186958)
			(xy 36.116239 -102.238864) (xy 36.079752 -102.286414) (xy 36.037372 -102.328794) (xy 35.989822 -102.365281)
			(xy 35.937916 -102.395248) (xy 35.882543 -102.418184) (xy 35.82465 -102.433697) (xy 35.765228 -102.44152)
			(xy 35.705292 -102.44152) (xy 35.64587 -102.433697) (xy 35.587977 -102.418184) (xy 35.532604 -102.395248)
			(xy 35.480698 -102.365281) (xy 35.433148 -102.328794) (xy 35.390768 -102.286414) (xy 35.354281 -102.238864)
			(xy 35.324314 -102.186958) (xy 35.301378 -102.131585) (xy 35.285865 -102.073692) (xy 35.278042 -102.01427)
			(xy 35.277552 -101.984302) (xy 4.30911 -101.984302) (xy 4.30911 -103.777796) (xy 37.31006 -103.777796)
			(xy 37.31006 -102.914196) (xy 37.31055 -102.884228) (xy 37.318373 -102.824806) (xy 37.333886 -102.766913)
			(xy 37.356822 -102.71154) (xy 37.386789 -102.659634) (xy 37.423276 -102.612084) (xy 37.465656 -102.569704)
			(xy 37.513206 -102.533217) (xy 37.565112 -102.50325) (xy 37.620485 -102.480314) (xy 37.678378 -102.464801)
			(xy 37.7378 -102.456978) (xy 37.797736 -102.456978) (xy 37.857158 -102.464801) (xy 37.915051 -102.480314)
			(xy 37.970424 -102.50325) (xy 38.02233 -102.533217) (xy 38.06988 -102.569704) (xy 38.11226 -102.612084)
			(xy 38.148747 -102.659634) (xy 38.178714 -102.71154) (xy 38.20165 -102.766913) (xy 38.217163 -102.824806)
			(xy 38.224986 -102.884228) (xy 38.225476 -102.914196) (xy 38.225476 -103.776272) (xy 53.639212 -103.776272)
			(xy 53.639212 -102.912672) (xy 53.639702 -102.882704) (xy 53.647525 -102.823282) (xy 53.663038 -102.765389)
			(xy 53.685974 -102.710016) (xy 53.715941 -102.65811) (xy 53.752428 -102.61056) (xy 53.794808 -102.56818)
			(xy 53.842358 -102.531693) (xy 53.894264 -102.501726) (xy 53.949637 -102.47879) (xy 54.00753 -102.463277)
			(xy 54.066952 -102.455454) (xy 54.126888 -102.455454) (xy 54.18631 -102.463277) (xy 54.244203 -102.47879)
			(xy 54.299576 -102.501726) (xy 54.351482 -102.531693) (xy 54.399032 -102.56818) (xy 54.441412 -102.61056)
			(xy 54.477899 -102.65811) (xy 54.507866 -102.710016) (xy 54.530802 -102.765389) (xy 54.546315 -102.823282)
			(xy 54.554138 -102.882704) (xy 54.554628 -102.912672) (xy 54.554628 -103.776272) (xy 54.554603 -103.777796)
			(xy 153.409904 -103.777796) (xy 153.409904 -102.914196) (xy 153.410394 -102.884212) (xy 153.418222 -102.824756)
			(xy 153.433743 -102.766831) (xy 153.456692 -102.711427) (xy 153.486676 -102.659493) (xy 153.523182 -102.611917)
			(xy 153.565587 -102.569512) (xy 153.613163 -102.533006) (xy 153.665097 -102.503022) (xy 153.720501 -102.480073)
			(xy 153.778426 -102.464552) (xy 153.837882 -102.456724) (xy 153.89785 -102.456724) (xy 153.957306 -102.464552)
			(xy 154.015231 -102.480073) (xy 154.070635 -102.503022) (xy 154.122569 -102.533006) (xy 154.170145 -102.569512)
			(xy 154.21255 -102.611917) (xy 154.249056 -102.659493) (xy 154.27904 -102.711427) (xy 154.301989 -102.766831)
			(xy 154.31751 -102.824756) (xy 154.325338 -102.884212) (xy 154.325828 -102.914196) (xy 154.325828 -103.776272)
			(xy 169.739056 -103.776272) (xy 169.739056 -102.912672) (xy 169.739546 -102.882688) (xy 169.747374 -102.823232)
			(xy 169.762895 -102.765307) (xy 169.785844 -102.709903) (xy 169.815828 -102.657969) (xy 169.852334 -102.610393)
			(xy 169.894739 -102.567988) (xy 169.942315 -102.531482) (xy 169.994249 -102.501498) (xy 170.049653 -102.478549)
			(xy 170.107578 -102.463028) (xy 170.167034 -102.4552) (xy 170.227002 -102.4552) (xy 170.286458 -102.463028)
			(xy 170.344383 -102.478549) (xy 170.399787 -102.501498) (xy 170.451721 -102.531482) (xy 170.499297 -102.567988)
			(xy 170.541702 -102.610393) (xy 170.578208 -102.657969) (xy 170.608192 -102.709903) (xy 170.631141 -102.765307)
			(xy 170.646662 -102.823232) (xy 170.65449 -102.882688) (xy 170.65498 -102.912672) (xy 170.65498 -103.776272)
			(xy 170.654955 -103.777796) (xy 269.509748 -103.777796) (xy 269.509748 -102.914196) (xy 269.510238 -102.884212)
			(xy 269.518066 -102.824756) (xy 269.533587 -102.766831) (xy 269.556536 -102.711427) (xy 269.58652 -102.659493)
			(xy 269.623026 -102.611917) (xy 269.665431 -102.569512) (xy 269.713007 -102.533006) (xy 269.764941 -102.503022)
			(xy 269.820345 -102.480073) (xy 269.87827 -102.464552) (xy 269.937726 -102.456724) (xy 269.997694 -102.456724)
			(xy 270.05715 -102.464552) (xy 270.115075 -102.480073) (xy 270.170479 -102.503022) (xy 270.222413 -102.533006)
			(xy 270.269989 -102.569512) (xy 270.312394 -102.611917) (xy 270.3489 -102.659493) (xy 270.378884 -102.711427)
			(xy 270.401833 -102.766831) (xy 270.417354 -102.824756) (xy 270.425182 -102.884212) (xy 270.425672 -102.914196)
			(xy 270.425672 -103.776272) (xy 285.8389 -103.776272) (xy 285.8389 -102.912672) (xy 285.83939 -102.882688)
			(xy 285.847218 -102.823232) (xy 285.862739 -102.765307) (xy 285.885688 -102.709903) (xy 285.915672 -102.657969)
			(xy 285.952178 -102.610393) (xy 285.994583 -102.567988) (xy 286.042159 -102.531482) (xy 286.094093 -102.501498)
			(xy 286.149497 -102.478549) (xy 286.207422 -102.463028) (xy 286.266878 -102.4552) (xy 286.326846 -102.4552)
			(xy 286.386302 -102.463028) (xy 286.444227 -102.478549) (xy 286.499631 -102.501498) (xy 286.551565 -102.531482)
			(xy 286.599141 -102.567988) (xy 286.641546 -102.610393) (xy 286.678052 -102.657969) (xy 286.708036 -102.709903)
			(xy 286.730985 -102.765307) (xy 286.746506 -102.823232) (xy 286.754334 -102.882688) (xy 286.754824 -102.912672)
			(xy 286.754824 -103.776272) (xy 286.754799 -103.777796) (xy 385.6101 -103.777796) (xy 385.6101 -102.914196)
			(xy 385.61059 -102.884228) (xy 385.618413 -102.824806) (xy 385.633926 -102.766913) (xy 385.656862 -102.71154)
			(xy 385.686829 -102.659634) (xy 385.723316 -102.612084) (xy 385.765696 -102.569704) (xy 385.813246 -102.533217)
			(xy 385.865152 -102.50325) (xy 385.920525 -102.480314) (xy 385.978418 -102.464801) (xy 386.03784 -102.456978)
			(xy 386.097776 -102.456978) (xy 386.157198 -102.464801) (xy 386.215091 -102.480314) (xy 386.270464 -102.50325)
			(xy 386.32237 -102.533217) (xy 386.36992 -102.569704) (xy 386.4123 -102.612084) (xy 386.448787 -102.659634)
			(xy 386.478754 -102.71154) (xy 386.50169 -102.766913) (xy 386.517203 -102.824806) (xy 386.525026 -102.884228)
			(xy 386.525516 -102.914196) (xy 386.525516 -103.776272) (xy 401.939252 -103.776272) (xy 401.939252 -102.912672)
			(xy 401.939742 -102.882704) (xy 401.947565 -102.823282) (xy 401.963078 -102.765389) (xy 401.986014 -102.710016)
			(xy 402.015981 -102.65811) (xy 402.052468 -102.61056) (xy 402.094848 -102.56818) (xy 402.142398 -102.531693)
			(xy 402.194304 -102.501726) (xy 402.249677 -102.47879) (xy 402.30757 -102.463277) (xy 402.366992 -102.455454)
			(xy 402.426928 -102.455454) (xy 402.48635 -102.463277) (xy 402.544243 -102.47879) (xy 402.599616 -102.501726)
			(xy 402.651522 -102.531693) (xy 402.699072 -102.56818) (xy 402.741452 -102.61056) (xy 402.777939 -102.65811)
			(xy 402.807906 -102.710016) (xy 402.830842 -102.765389) (xy 402.846355 -102.823282) (xy 402.854178 -102.882704)
			(xy 402.854668 -102.912672) (xy 402.854668 -103.776272) (xy 402.854178 -103.80624) (xy 402.846355 -103.865662)
			(xy 402.830842 -103.923555) (xy 402.807906 -103.978928) (xy 402.777939 -104.030834) (xy 402.741452 -104.078384)
			(xy 402.699072 -104.120764) (xy 402.651522 -104.157251) (xy 402.599616 -104.187218) (xy 402.544243 -104.210154)
			(xy 402.48635 -104.225667) (xy 402.426928 -104.23349) (xy 402.366992 -104.23349) (xy 402.30757 -104.225667)
			(xy 402.249677 -104.210154) (xy 402.194304 -104.187218) (xy 402.142398 -104.157251) (xy 402.094848 -104.120764)
			(xy 402.052468 -104.078384) (xy 402.015981 -104.030834) (xy 401.986014 -103.978928) (xy 401.963078 -103.923555)
			(xy 401.947565 -103.865662) (xy 401.939742 -103.80624) (xy 401.939252 -103.776272) (xy 386.525516 -103.776272)
			(xy 386.525516 -103.777796) (xy 386.525026 -103.807764) (xy 386.517203 -103.867186) (xy 386.50169 -103.925079)
			(xy 386.478754 -103.980452) (xy 386.448787 -104.032358) (xy 386.4123 -104.079908) (xy 386.36992 -104.122288)
			(xy 386.32237 -104.158775) (xy 386.270464 -104.188742) (xy 386.215091 -104.211678) (xy 386.157198 -104.227191)
			(xy 386.097776 -104.235014) (xy 386.03784 -104.235014) (xy 385.978418 -104.227191) (xy 385.920525 -104.211678)
			(xy 385.865152 -104.188742) (xy 385.813246 -104.158775) (xy 385.765696 -104.122288) (xy 385.723316 -104.079908)
			(xy 385.686829 -104.032358) (xy 385.656862 -103.980452) (xy 385.633926 -103.925079) (xy 385.618413 -103.867186)
			(xy 385.61059 -103.807764) (xy 385.6101 -103.777796) (xy 286.754799 -103.777796) (xy 286.754334 -103.806256)
			(xy 286.746506 -103.865712) (xy 286.730985 -103.923637) (xy 286.708036 -103.979041) (xy 286.678052 -104.030975)
			(xy 286.641546 -104.078551) (xy 286.599141 -104.120956) (xy 286.551565 -104.157462) (xy 286.499631 -104.187446)
			(xy 286.444227 -104.210395) (xy 286.386302 -104.225916) (xy 286.326846 -104.233744) (xy 286.266878 -104.233744)
			(xy 286.207422 -104.225916) (xy 286.149497 -104.210395) (xy 286.094093 -104.187446) (xy 286.042159 -104.157462)
			(xy 285.994583 -104.120956) (xy 285.952178 -104.078551) (xy 285.915672 -104.030975) (xy 285.885688 -103.979041)
			(xy 285.862739 -103.923637) (xy 285.847218 -103.865712) (xy 285.83939 -103.806256) (xy 285.8389 -103.776272)
			(xy 270.425672 -103.776272) (xy 270.425672 -103.777796) (xy 270.425182 -103.80778) (xy 270.417354 -103.867236)
			(xy 270.401833 -103.925161) (xy 270.378884 -103.980565) (xy 270.3489 -104.032499) (xy 270.312394 -104.080075)
			(xy 270.269989 -104.12248) (xy 270.222413 -104.158986) (xy 270.170479 -104.18897) (xy 270.115075 -104.211919)
			(xy 270.05715 -104.22744) (xy 269.997694 -104.235268) (xy 269.937726 -104.235268) (xy 269.87827 -104.22744)
			(xy 269.820345 -104.211919) (xy 269.764941 -104.18897) (xy 269.713007 -104.158986) (xy 269.665431 -104.12248)
			(xy 269.623026 -104.080075) (xy 269.58652 -104.032499) (xy 269.556536 -103.980565) (xy 269.533587 -103.925161)
			(xy 269.518066 -103.867236) (xy 269.510238 -103.80778) (xy 269.509748 -103.777796) (xy 170.654955 -103.777796)
			(xy 170.65449 -103.806256) (xy 170.646662 -103.865712) (xy 170.631141 -103.923637) (xy 170.608192 -103.979041)
			(xy 170.578208 -104.030975) (xy 170.541702 -104.078551) (xy 170.499297 -104.120956) (xy 170.451721 -104.157462)
			(xy 170.399787 -104.187446) (xy 170.344383 -104.210395) (xy 170.286458 -104.225916) (xy 170.227002 -104.233744)
			(xy 170.167034 -104.233744) (xy 170.107578 -104.225916) (xy 170.049653 -104.210395) (xy 169.994249 -104.187446)
			(xy 169.942315 -104.157462) (xy 169.894739 -104.120956) (xy 169.852334 -104.078551) (xy 169.815828 -104.030975)
			(xy 169.785844 -103.979041) (xy 169.762895 -103.923637) (xy 169.747374 -103.865712) (xy 169.739546 -103.806256)
			(xy 169.739056 -103.776272) (xy 154.325828 -103.776272) (xy 154.325828 -103.777796) (xy 154.325338 -103.80778)
			(xy 154.31751 -103.867236) (xy 154.301989 -103.925161) (xy 154.27904 -103.980565) (xy 154.249056 -104.032499)
			(xy 154.21255 -104.080075) (xy 154.170145 -104.12248) (xy 154.122569 -104.158986) (xy 154.070635 -104.18897)
			(xy 154.015231 -104.211919) (xy 153.957306 -104.22744) (xy 153.89785 -104.235268) (xy 153.837882 -104.235268)
			(xy 153.778426 -104.22744) (xy 153.720501 -104.211919) (xy 153.665097 -104.18897) (xy 153.613163 -104.158986)
			(xy 153.565587 -104.12248) (xy 153.523182 -104.080075) (xy 153.486676 -104.032499) (xy 153.456692 -103.980565)
			(xy 153.433743 -103.925161) (xy 153.418222 -103.867236) (xy 153.410394 -103.80778) (xy 153.409904 -103.777796)
			(xy 54.554603 -103.777796) (xy 54.554138 -103.80624) (xy 54.546315 -103.865662) (xy 54.530802 -103.923555)
			(xy 54.507866 -103.978928) (xy 54.477899 -104.030834) (xy 54.441412 -104.078384) (xy 54.399032 -104.120764)
			(xy 54.351482 -104.157251) (xy 54.299576 -104.187218) (xy 54.244203 -104.210154) (xy 54.18631 -104.225667)
			(xy 54.126888 -104.23349) (xy 54.066952 -104.23349) (xy 54.00753 -104.225667) (xy 53.949637 -104.210154)
			(xy 53.894264 -104.187218) (xy 53.842358 -104.157251) (xy 53.794808 -104.120764) (xy 53.752428 -104.078384)
			(xy 53.715941 -104.030834) (xy 53.685974 -103.978928) (xy 53.663038 -103.923555) (xy 53.647525 -103.865662)
			(xy 53.639702 -103.80624) (xy 53.639212 -103.776272) (xy 38.225476 -103.776272) (xy 38.225476 -103.777796)
			(xy 38.224986 -103.807764) (xy 38.217163 -103.867186) (xy 38.20165 -103.925079) (xy 38.178714 -103.980452)
			(xy 38.148747 -104.032358) (xy 38.11226 -104.079908) (xy 38.06988 -104.122288) (xy 38.02233 -104.158775)
			(xy 37.970424 -104.188742) (xy 37.915051 -104.211678) (xy 37.857158 -104.227191) (xy 37.797736 -104.235014)
			(xy 37.7378 -104.235014) (xy 37.678378 -104.227191) (xy 37.620485 -104.211678) (xy 37.565112 -104.188742)
			(xy 37.513206 -104.158775) (xy 37.465656 -104.122288) (xy 37.423276 -104.079908) (xy 37.386789 -104.032358)
			(xy 37.356822 -103.980452) (xy 37.333886 -103.925079) (xy 37.318373 -103.867186) (xy 37.31055 -103.807764)
			(xy 37.31006 -103.777796) (xy 4.30911 -103.777796) (xy 4.30911 -105.584498) (xy 34.667952 -105.584498)
			(xy 34.667952 -104.720898) (xy 34.668442 -104.69093) (xy 34.676265 -104.631508) (xy 34.691778 -104.573615)
			(xy 34.714714 -104.518242) (xy 34.744681 -104.466336) (xy 34.781168 -104.418786) (xy 34.823548 -104.376406)
			(xy 34.871098 -104.339919) (xy 34.923004 -104.309952) (xy 34.978377 -104.287016) (xy 35.03627 -104.271503)
			(xy 35.095692 -104.26368) (xy 35.155628 -104.26368) (xy 35.21505 -104.271503) (xy 35.272943 -104.287016)
			(xy 35.328316 -104.309952) (xy 35.380222 -104.339919) (xy 35.427772 -104.376406) (xy 35.470152 -104.418786)
			(xy 35.506639 -104.466336) (xy 35.536606 -104.518242) (xy 35.559542 -104.573615) (xy 35.575055 -104.631508)
			(xy 35.582878 -104.69093) (xy 35.583368 -104.720898) (xy 35.583368 -105.57637) (xy 51.785012 -105.57637)
			(xy 51.785012 -104.71277) (xy 51.785502 -104.682802) (xy 51.793325 -104.62338) (xy 51.808838 -104.565487)
			(xy 51.831774 -104.510114) (xy 51.861741 -104.458208) (xy 51.898228 -104.410658) (xy 51.940608 -104.368278)
			(xy 51.988158 -104.331791) (xy 52.040064 -104.301824) (xy 52.095437 -104.278888) (xy 52.15333 -104.263375)
			(xy 52.212752 -104.255552) (xy 52.272688 -104.255552) (xy 52.33211 -104.263375) (xy 52.390003 -104.278888)
			(xy 52.445376 -104.301824) (xy 52.497282 -104.331791) (xy 52.544832 -104.368278) (xy 52.587212 -104.410658)
			(xy 52.623699 -104.458208) (xy 52.653666 -104.510114) (xy 52.676602 -104.565487) (xy 52.692115 -104.62338)
			(xy 52.699938 -104.682802) (xy 52.700428 -104.71277) (xy 52.700428 -105.57637) (xy 52.700295 -105.584498)
			(xy 150.767796 -105.584498) (xy 150.767796 -104.720898) (xy 150.768286 -104.690914) (xy 150.776114 -104.631458)
			(xy 150.791635 -104.573533) (xy 150.814584 -104.518129) (xy 150.844568 -104.466195) (xy 150.881074 -104.418619)
			(xy 150.923479 -104.376214) (xy 150.971055 -104.339708) (xy 151.022989 -104.309724) (xy 151.078393 -104.286775)
			(xy 151.136318 -104.271254) (xy 151.195774 -104.263426) (xy 151.255742 -104.263426) (xy 151.315198 -104.271254)
			(xy 151.373123 -104.286775) (xy 151.428527 -104.309724) (xy 151.480461 -104.339708) (xy 151.528037 -104.376214)
			(xy 151.570442 -104.418619) (xy 151.606948 -104.466195) (xy 151.636932 -104.518129) (xy 151.659881 -104.573533)
			(xy 151.675402 -104.631458) (xy 151.68323 -104.690914) (xy 151.68372 -104.720898) (xy 151.68372 -105.57637)
			(xy 167.884856 -105.57637) (xy 167.884856 -104.71277) (xy 167.885346 -104.682786) (xy 167.893174 -104.62333)
			(xy 167.908695 -104.565405) (xy 167.931644 -104.510001) (xy 167.961628 -104.458067) (xy 167.998134 -104.410491)
			(xy 168.040539 -104.368086) (xy 168.088115 -104.33158) (xy 168.140049 -104.301596) (xy 168.195453 -104.278647)
			(xy 168.253378 -104.263126) (xy 168.312834 -104.255298) (xy 168.372802 -104.255298) (xy 168.432258 -104.263126)
			(xy 168.490183 -104.278647) (xy 168.545587 -104.301596) (xy 168.597521 -104.33158) (xy 168.645097 -104.368086)
			(xy 168.687502 -104.410491) (xy 168.724008 -104.458067) (xy 168.753992 -104.510001) (xy 168.776941 -104.565405)
			(xy 168.792462 -104.62333) (xy 168.80029 -104.682786) (xy 168.80078 -104.71277) (xy 168.80078 -105.57637)
			(xy 168.800647 -105.584498) (xy 266.86764 -105.584498) (xy 266.86764 -104.720898) (xy 266.86813 -104.690914)
			(xy 266.875958 -104.631458) (xy 266.891479 -104.573533) (xy 266.914428 -104.518129) (xy 266.944412 -104.466195)
			(xy 266.980918 -104.418619) (xy 267.023323 -104.376214) (xy 267.070899 -104.339708) (xy 267.122833 -104.309724)
			(xy 267.178237 -104.286775) (xy 267.236162 -104.271254) (xy 267.295618 -104.263426) (xy 267.355586 -104.263426)
			(xy 267.415042 -104.271254) (xy 267.472967 -104.286775) (xy 267.528371 -104.309724) (xy 267.580305 -104.339708)
			(xy 267.627881 -104.376214) (xy 267.670286 -104.418619) (xy 267.706792 -104.466195) (xy 267.736776 -104.518129)
			(xy 267.759725 -104.573533) (xy 267.775246 -104.631458) (xy 267.783074 -104.690914) (xy 267.783564 -104.720898)
			(xy 267.783564 -105.57637) (xy 283.9847 -105.57637) (xy 283.9847 -104.71277) (xy 283.98519 -104.682786)
			(xy 283.993018 -104.62333) (xy 284.008539 -104.565405) (xy 284.031488 -104.510001) (xy 284.061472 -104.458067)
			(xy 284.097978 -104.410491) (xy 284.140383 -104.368086) (xy 284.187959 -104.33158) (xy 284.239893 -104.301596)
			(xy 284.295297 -104.278647) (xy 284.353222 -104.263126) (xy 284.412678 -104.255298) (xy 284.472646 -104.255298)
			(xy 284.532102 -104.263126) (xy 284.590027 -104.278647) (xy 284.645431 -104.301596) (xy 284.697365 -104.33158)
			(xy 284.744941 -104.368086) (xy 284.787346 -104.410491) (xy 284.823852 -104.458067) (xy 284.853836 -104.510001)
			(xy 284.876785 -104.565405) (xy 284.892306 -104.62333) (xy 284.900134 -104.682786) (xy 284.900624 -104.71277)
			(xy 284.900624 -105.57637) (xy 284.900491 -105.584498) (xy 382.967992 -105.584498) (xy 382.967992 -104.720898)
			(xy 382.968482 -104.69093) (xy 382.976305 -104.631508) (xy 382.991818 -104.573615) (xy 383.014754 -104.518242)
			(xy 383.044721 -104.466336) (xy 383.081208 -104.418786) (xy 383.123588 -104.376406) (xy 383.171138 -104.339919)
			(xy 383.223044 -104.309952) (xy 383.278417 -104.287016) (xy 383.33631 -104.271503) (xy 383.395732 -104.26368)
			(xy 383.455668 -104.26368) (xy 383.51509 -104.271503) (xy 383.572983 -104.287016) (xy 383.628356 -104.309952)
			(xy 383.680262 -104.339919) (xy 383.727812 -104.376406) (xy 383.770192 -104.418786) (xy 383.806679 -104.466336)
			(xy 383.836646 -104.518242) (xy 383.859582 -104.573615) (xy 383.875095 -104.631508) (xy 383.882918 -104.69093)
			(xy 383.883408 -104.720898) (xy 383.883408 -105.57637) (xy 400.085052 -105.57637) (xy 400.085052 -104.71277)
			(xy 400.085542 -104.682802) (xy 400.093365 -104.62338) (xy 400.108878 -104.565487) (xy 400.131814 -104.510114)
			(xy 400.161781 -104.458208) (xy 400.198268 -104.410658) (xy 400.240648 -104.368278) (xy 400.288198 -104.331791)
			(xy 400.340104 -104.301824) (xy 400.395477 -104.278888) (xy 400.45337 -104.263375) (xy 400.512792 -104.255552)
			(xy 400.572728 -104.255552) (xy 400.63215 -104.263375) (xy 400.690043 -104.278888) (xy 400.745416 -104.301824)
			(xy 400.797322 -104.331791) (xy 400.844872 -104.368278) (xy 400.887252 -104.410658) (xy 400.923739 -104.458208)
			(xy 400.953706 -104.510114) (xy 400.976642 -104.565487) (xy 400.992155 -104.62338) (xy 400.999978 -104.682802)
			(xy 401.000468 -104.71277) (xy 401.000468 -105.57637) (xy 400.999978 -105.606338) (xy 400.992155 -105.66576)
			(xy 400.976642 -105.723653) (xy 400.953706 -105.779026) (xy 400.923739 -105.830932) (xy 400.887252 -105.878482)
			(xy 400.844872 -105.920862) (xy 400.797322 -105.957349) (xy 400.745416 -105.987316) (xy 400.690043 -106.010252)
			(xy 400.63215 -106.025765) (xy 400.572728 -106.033588) (xy 400.512792 -106.033588) (xy 400.45337 -106.025765)
			(xy 400.395477 -106.010252) (xy 400.340104 -105.987316) (xy 400.288198 -105.957349) (xy 400.240648 -105.920862)
			(xy 400.198268 -105.878482) (xy 400.161781 -105.830932) (xy 400.131814 -105.779026) (xy 400.108878 -105.723653)
			(xy 400.093365 -105.66576) (xy 400.085542 -105.606338) (xy 400.085052 -105.57637) (xy 383.883408 -105.57637)
			(xy 383.883408 -105.584498) (xy 383.882918 -105.614466) (xy 383.875095 -105.673888) (xy 383.859582 -105.731781)
			(xy 383.836646 -105.787154) (xy 383.806679 -105.83906) (xy 383.770192 -105.88661) (xy 383.727812 -105.92899)
			(xy 383.680262 -105.965477) (xy 383.628356 -105.995444) (xy 383.572983 -106.01838) (xy 383.51509 -106.033893)
			(xy 383.455668 -106.041716) (xy 383.395732 -106.041716) (xy 383.33631 -106.033893) (xy 383.278417 -106.01838)
			(xy 383.223044 -105.995444) (xy 383.171138 -105.965477) (xy 383.123588 -105.92899) (xy 383.081208 -105.88661)
			(xy 383.044721 -105.83906) (xy 383.014754 -105.787154) (xy 382.991818 -105.731781) (xy 382.976305 -105.673888)
			(xy 382.968482 -105.614466) (xy 382.967992 -105.584498) (xy 284.900491 -105.584498) (xy 284.900134 -105.606354)
			(xy 284.892306 -105.66581) (xy 284.876785 -105.723735) (xy 284.853836 -105.779139) (xy 284.823852 -105.831073)
			(xy 284.787346 -105.878649) (xy 284.744941 -105.921054) (xy 284.697365 -105.95756) (xy 284.645431 -105.987544)
			(xy 284.590027 -106.010493) (xy 284.532102 -106.026014) (xy 284.472646 -106.033842) (xy 284.412678 -106.033842)
			(xy 284.353222 -106.026014) (xy 284.295297 -106.010493) (xy 284.239893 -105.987544) (xy 284.187959 -105.95756)
			(xy 284.140383 -105.921054) (xy 284.097978 -105.878649) (xy 284.061472 -105.831073) (xy 284.031488 -105.779139)
			(xy 284.008539 -105.723735) (xy 283.993018 -105.66581) (xy 283.98519 -105.606354) (xy 283.9847 -105.57637)
			(xy 267.783564 -105.57637) (xy 267.783564 -105.584498) (xy 267.783074 -105.614482) (xy 267.775246 -105.673938)
			(xy 267.759725 -105.731863) (xy 267.736776 -105.787267) (xy 267.706792 -105.839201) (xy 267.670286 -105.886777)
			(xy 267.627881 -105.929182) (xy 267.580305 -105.965688) (xy 267.528371 -105.995672) (xy 267.472967 -106.018621)
			(xy 267.415042 -106.034142) (xy 267.355586 -106.04197) (xy 267.295618 -106.04197) (xy 267.236162 -106.034142)
			(xy 267.178237 -106.018621) (xy 267.122833 -105.995672) (xy 267.070899 -105.965688) (xy 267.023323 -105.929182)
			(xy 266.980918 -105.886777) (xy 266.944412 -105.839201) (xy 266.914428 -105.787267) (xy 266.891479 -105.731863)
			(xy 266.875958 -105.673938) (xy 266.86813 -105.614482) (xy 266.86764 -105.584498) (xy 168.800647 -105.584498)
			(xy 168.80029 -105.606354) (xy 168.792462 -105.66581) (xy 168.776941 -105.723735) (xy 168.753992 -105.779139)
			(xy 168.724008 -105.831073) (xy 168.687502 -105.878649) (xy 168.645097 -105.921054) (xy 168.597521 -105.95756)
			(xy 168.545587 -105.987544) (xy 168.490183 -106.010493) (xy 168.432258 -106.026014) (xy 168.372802 -106.033842)
			(xy 168.312834 -106.033842) (xy 168.253378 -106.026014) (xy 168.195453 -106.010493) (xy 168.140049 -105.987544)
			(xy 168.088115 -105.95756) (xy 168.040539 -105.921054) (xy 167.998134 -105.878649) (xy 167.961628 -105.831073)
			(xy 167.931644 -105.779139) (xy 167.908695 -105.723735) (xy 167.893174 -105.66581) (xy 167.885346 -105.606354)
			(xy 167.884856 -105.57637) (xy 151.68372 -105.57637) (xy 151.68372 -105.584498) (xy 151.68323 -105.614482)
			(xy 151.675402 -105.673938) (xy 151.659881 -105.731863) (xy 151.636932 -105.787267) (xy 151.606948 -105.839201)
			(xy 151.570442 -105.886777) (xy 151.528037 -105.929182) (xy 151.480461 -105.965688) (xy 151.428527 -105.995672)
			(xy 151.373123 -106.018621) (xy 151.315198 -106.034142) (xy 151.255742 -106.04197) (xy 151.195774 -106.04197)
			(xy 151.136318 -106.034142) (xy 151.078393 -106.018621) (xy 151.022989 -105.995672) (xy 150.971055 -105.965688)
			(xy 150.923479 -105.929182) (xy 150.881074 -105.886777) (xy 150.844568 -105.839201) (xy 150.814584 -105.787267)
			(xy 150.791635 -105.731863) (xy 150.776114 -105.673938) (xy 150.768286 -105.614482) (xy 150.767796 -105.584498)
			(xy 52.700295 -105.584498) (xy 52.699938 -105.606338) (xy 52.692115 -105.66576) (xy 52.676602 -105.723653)
			(xy 52.653666 -105.779026) (xy 52.623699 -105.830932) (xy 52.587212 -105.878482) (xy 52.544832 -105.920862)
			(xy 52.497282 -105.957349) (xy 52.445376 -105.987316) (xy 52.390003 -106.010252) (xy 52.33211 -106.025765)
			(xy 52.272688 -106.033588) (xy 52.212752 -106.033588) (xy 52.15333 -106.025765) (xy 52.095437 -106.010252)
			(xy 52.040064 -105.987316) (xy 51.988158 -105.957349) (xy 51.940608 -105.920862) (xy 51.898228 -105.878482)
			(xy 51.861741 -105.830932) (xy 51.831774 -105.779026) (xy 51.808838 -105.723653) (xy 51.793325 -105.66576)
			(xy 51.785502 -105.606338) (xy 51.785012 -105.57637) (xy 35.583368 -105.57637) (xy 35.583368 -105.584498)
			(xy 35.582878 -105.614466) (xy 35.575055 -105.673888) (xy 35.559542 -105.731781) (xy 35.536606 -105.787154)
			(xy 35.506639 -105.83906) (xy 35.470152 -105.88661) (xy 35.427772 -105.92899) (xy 35.380222 -105.965477)
			(xy 35.328316 -105.995444) (xy 35.272943 -106.01838) (xy 35.21505 -106.033893) (xy 35.155628 -106.041716)
			(xy 35.095692 -106.041716) (xy 35.03627 -106.033893) (xy 34.978377 -106.01838) (xy 34.923004 -105.995444)
			(xy 34.871098 -105.965477) (xy 34.823548 -105.92899) (xy 34.781168 -105.88661) (xy 34.744681 -105.83906)
			(xy 34.714714 -105.787154) (xy 34.691778 -105.731781) (xy 34.676265 -105.673888) (xy 34.668442 -105.614466)
			(xy 34.667952 -105.584498) (xy 4.30911 -105.584498) (xy 4.30911 -107.377738) (xy 37.31006 -107.377738)
			(xy 37.31006 -106.514138) (xy 37.31055 -106.48417) (xy 37.318373 -106.424748) (xy 37.333886 -106.366855)
			(xy 37.356822 -106.311482) (xy 37.386789 -106.259576) (xy 37.423276 -106.212026) (xy 37.465656 -106.169646)
			(xy 37.513206 -106.133159) (xy 37.565112 -106.103192) (xy 37.620485 -106.080256) (xy 37.678378 -106.064743)
			(xy 37.7378 -106.05692) (xy 37.797736 -106.05692) (xy 37.857158 -106.064743) (xy 37.915051 -106.080256)
			(xy 37.970424 -106.103192) (xy 38.02233 -106.133159) (xy 38.06988 -106.169646) (xy 38.11226 -106.212026)
			(xy 38.148747 -106.259576) (xy 38.178714 -106.311482) (xy 38.20165 -106.366855) (xy 38.217163 -106.424748)
			(xy 38.224986 -106.48417) (xy 38.225476 -106.514138) (xy 38.225476 -107.376214) (xy 53.639212 -107.376214)
			(xy 53.639212 -106.512614) (xy 53.639702 -106.482646) (xy 53.647525 -106.423224) (xy 53.663038 -106.365331)
			(xy 53.685974 -106.309958) (xy 53.715941 -106.258052) (xy 53.752428 -106.210502) (xy 53.794808 -106.168122)
			(xy 53.842358 -106.131635) (xy 53.894264 -106.101668) (xy 53.949637 -106.078732) (xy 54.00753 -106.063219)
			(xy 54.066952 -106.055396) (xy 54.126888 -106.055396) (xy 54.18631 -106.063219) (xy 54.244203 -106.078732)
			(xy 54.299576 -106.101668) (xy 54.351482 -106.131635) (xy 54.399032 -106.168122) (xy 54.441412 -106.210502)
			(xy 54.477899 -106.258052) (xy 54.507866 -106.309958) (xy 54.530802 -106.365331) (xy 54.546315 -106.423224)
			(xy 54.554138 -106.482646) (xy 54.554628 -106.512614) (xy 54.554628 -107.376214) (xy 54.554603 -107.377738)
			(xy 153.409904 -107.377738) (xy 153.409904 -106.514138) (xy 153.410394 -106.484154) (xy 153.418222 -106.424698)
			(xy 153.433743 -106.366773) (xy 153.456692 -106.311369) (xy 153.486676 -106.259435) (xy 153.523182 -106.211859)
			(xy 153.565587 -106.169454) (xy 153.613163 -106.132948) (xy 153.665097 -106.102964) (xy 153.720501 -106.080015)
			(xy 153.778426 -106.064494) (xy 153.837882 -106.056666) (xy 153.89785 -106.056666) (xy 153.957306 -106.064494)
			(xy 154.015231 -106.080015) (xy 154.070635 -106.102964) (xy 154.122569 -106.132948) (xy 154.170145 -106.169454)
			(xy 154.21255 -106.211859) (xy 154.249056 -106.259435) (xy 154.27904 -106.311369) (xy 154.301989 -106.366773)
			(xy 154.31751 -106.424698) (xy 154.325338 -106.484154) (xy 154.325828 -106.514138) (xy 154.325828 -107.376214)
			(xy 169.739056 -107.376214) (xy 169.739056 -106.512614) (xy 169.739546 -106.48263) (xy 169.747374 -106.423174)
			(xy 169.762895 -106.365249) (xy 169.785844 -106.309845) (xy 169.815828 -106.257911) (xy 169.852334 -106.210335)
			(xy 169.894739 -106.16793) (xy 169.942315 -106.131424) (xy 169.994249 -106.10144) (xy 170.049653 -106.078491)
			(xy 170.107578 -106.06297) (xy 170.167034 -106.055142) (xy 170.227002 -106.055142) (xy 170.286458 -106.06297)
			(xy 170.344383 -106.078491) (xy 170.399787 -106.10144) (xy 170.451721 -106.131424) (xy 170.499297 -106.16793)
			(xy 170.541702 -106.210335) (xy 170.578208 -106.257911) (xy 170.608192 -106.309845) (xy 170.631141 -106.365249)
			(xy 170.646662 -106.423174) (xy 170.65449 -106.48263) (xy 170.65498 -106.512614) (xy 170.65498 -107.376214)
			(xy 170.654955 -107.377738) (xy 269.509748 -107.377738) (xy 269.509748 -106.514138) (xy 269.510238 -106.484154)
			(xy 269.518066 -106.424698) (xy 269.533587 -106.366773) (xy 269.556536 -106.311369) (xy 269.58652 -106.259435)
			(xy 269.623026 -106.211859) (xy 269.665431 -106.169454) (xy 269.713007 -106.132948) (xy 269.764941 -106.102964)
			(xy 269.820345 -106.080015) (xy 269.87827 -106.064494) (xy 269.937726 -106.056666) (xy 269.997694 -106.056666)
			(xy 270.05715 -106.064494) (xy 270.115075 -106.080015) (xy 270.170479 -106.102964) (xy 270.222413 -106.132948)
			(xy 270.269989 -106.169454) (xy 270.312394 -106.211859) (xy 270.3489 -106.259435) (xy 270.378884 -106.311369)
			(xy 270.401833 -106.366773) (xy 270.417354 -106.424698) (xy 270.425182 -106.484154) (xy 270.425672 -106.514138)
			(xy 270.425672 -107.376214) (xy 285.8389 -107.376214) (xy 285.8389 -106.512614) (xy 285.83939 -106.48263)
			(xy 285.847218 -106.423174) (xy 285.862739 -106.365249) (xy 285.885688 -106.309845) (xy 285.915672 -106.257911)
			(xy 285.952178 -106.210335) (xy 285.994583 -106.16793) (xy 286.042159 -106.131424) (xy 286.094093 -106.10144)
			(xy 286.149497 -106.078491) (xy 286.207422 -106.06297) (xy 286.266878 -106.055142) (xy 286.326846 -106.055142)
			(xy 286.386302 -106.06297) (xy 286.444227 -106.078491) (xy 286.499631 -106.10144) (xy 286.551565 -106.131424)
			(xy 286.599141 -106.16793) (xy 286.641546 -106.210335) (xy 286.678052 -106.257911) (xy 286.708036 -106.309845)
			(xy 286.730985 -106.365249) (xy 286.746506 -106.423174) (xy 286.754334 -106.48263) (xy 286.754824 -106.512614)
			(xy 286.754824 -107.376214) (xy 286.754799 -107.377738) (xy 385.6101 -107.377738) (xy 385.6101 -106.514138)
			(xy 385.61059 -106.48417) (xy 385.618413 -106.424748) (xy 385.633926 -106.366855) (xy 385.656862 -106.311482)
			(xy 385.686829 -106.259576) (xy 385.723316 -106.212026) (xy 385.765696 -106.169646) (xy 385.813246 -106.133159)
			(xy 385.865152 -106.103192) (xy 385.920525 -106.080256) (xy 385.978418 -106.064743) (xy 386.03784 -106.05692)
			(xy 386.097776 -106.05692) (xy 386.157198 -106.064743) (xy 386.215091 -106.080256) (xy 386.270464 -106.103192)
			(xy 386.32237 -106.133159) (xy 386.36992 -106.169646) (xy 386.4123 -106.212026) (xy 386.448787 -106.259576)
			(xy 386.478754 -106.311482) (xy 386.50169 -106.366855) (xy 386.517203 -106.424748) (xy 386.525026 -106.48417)
			(xy 386.525516 -106.514138) (xy 386.525516 -107.376214) (xy 401.939252 -107.376214) (xy 401.939252 -106.512614)
			(xy 401.939742 -106.482646) (xy 401.947565 -106.423224) (xy 401.963078 -106.365331) (xy 401.986014 -106.309958)
			(xy 402.015981 -106.258052) (xy 402.052468 -106.210502) (xy 402.094848 -106.168122) (xy 402.142398 -106.131635)
			(xy 402.194304 -106.101668) (xy 402.249677 -106.078732) (xy 402.30757 -106.063219) (xy 402.366992 -106.055396)
			(xy 402.426928 -106.055396) (xy 402.48635 -106.063219) (xy 402.544243 -106.078732) (xy 402.599616 -106.101668)
			(xy 402.651522 -106.131635) (xy 402.699072 -106.168122) (xy 402.741452 -106.210502) (xy 402.777939 -106.258052)
			(xy 402.807906 -106.309958) (xy 402.830842 -106.365331) (xy 402.846355 -106.423224) (xy 402.854178 -106.482646)
			(xy 402.854668 -106.512614) (xy 402.854668 -107.376214) (xy 402.854178 -107.406182) (xy 402.846355 -107.465604)
			(xy 402.830842 -107.523497) (xy 402.807906 -107.57887) (xy 402.777939 -107.630776) (xy 402.741452 -107.678326)
			(xy 402.699072 -107.720706) (xy 402.651522 -107.757193) (xy 402.599616 -107.78716) (xy 402.544243 -107.810096)
			(xy 402.48635 -107.825609) (xy 402.426928 -107.833432) (xy 402.366992 -107.833432) (xy 402.30757 -107.825609)
			(xy 402.249677 -107.810096) (xy 402.194304 -107.78716) (xy 402.142398 -107.757193) (xy 402.094848 -107.720706)
			(xy 402.052468 -107.678326) (xy 402.015981 -107.630776) (xy 401.986014 -107.57887) (xy 401.963078 -107.523497)
			(xy 401.947565 -107.465604) (xy 401.939742 -107.406182) (xy 401.939252 -107.376214) (xy 386.525516 -107.376214)
			(xy 386.525516 -107.377738) (xy 386.525026 -107.407706) (xy 386.517203 -107.467128) (xy 386.50169 -107.525021)
			(xy 386.478754 -107.580394) (xy 386.448787 -107.6323) (xy 386.4123 -107.67985) (xy 386.36992 -107.72223)
			(xy 386.32237 -107.758717) (xy 386.270464 -107.788684) (xy 386.215091 -107.81162) (xy 386.157198 -107.827133)
			(xy 386.097776 -107.834956) (xy 386.03784 -107.834956) (xy 385.978418 -107.827133) (xy 385.920525 -107.81162)
			(xy 385.865152 -107.788684) (xy 385.813246 -107.758717) (xy 385.765696 -107.72223) (xy 385.723316 -107.67985)
			(xy 385.686829 -107.6323) (xy 385.656862 -107.580394) (xy 385.633926 -107.525021) (xy 385.618413 -107.467128)
			(xy 385.61059 -107.407706) (xy 385.6101 -107.377738) (xy 286.754799 -107.377738) (xy 286.754334 -107.406198)
			(xy 286.746506 -107.465654) (xy 286.730985 -107.523579) (xy 286.708036 -107.578983) (xy 286.678052 -107.630917)
			(xy 286.641546 -107.678493) (xy 286.599141 -107.720898) (xy 286.551565 -107.757404) (xy 286.499631 -107.787388)
			(xy 286.444227 -107.810337) (xy 286.386302 -107.825858) (xy 286.326846 -107.833686) (xy 286.266878 -107.833686)
			(xy 286.207422 -107.825858) (xy 286.149497 -107.810337) (xy 286.094093 -107.787388) (xy 286.042159 -107.757404)
			(xy 285.994583 -107.720898) (xy 285.952178 -107.678493) (xy 285.915672 -107.630917) (xy 285.885688 -107.578983)
			(xy 285.862739 -107.523579) (xy 285.847218 -107.465654) (xy 285.83939 -107.406198) (xy 285.8389 -107.376214)
			(xy 270.425672 -107.376214) (xy 270.425672 -107.377738) (xy 270.425182 -107.407722) (xy 270.417354 -107.467178)
			(xy 270.401833 -107.525103) (xy 270.378884 -107.580507) (xy 270.3489 -107.632441) (xy 270.312394 -107.680017)
			(xy 270.269989 -107.722422) (xy 270.222413 -107.758928) (xy 270.170479 -107.788912) (xy 270.115075 -107.811861)
			(xy 270.05715 -107.827382) (xy 269.997694 -107.83521) (xy 269.937726 -107.83521) (xy 269.87827 -107.827382)
			(xy 269.820345 -107.811861) (xy 269.764941 -107.788912) (xy 269.713007 -107.758928) (xy 269.665431 -107.722422)
			(xy 269.623026 -107.680017) (xy 269.58652 -107.632441) (xy 269.556536 -107.580507) (xy 269.533587 -107.525103)
			(xy 269.518066 -107.467178) (xy 269.510238 -107.407722) (xy 269.509748 -107.377738) (xy 170.654955 -107.377738)
			(xy 170.65449 -107.406198) (xy 170.646662 -107.465654) (xy 170.631141 -107.523579) (xy 170.608192 -107.578983)
			(xy 170.578208 -107.630917) (xy 170.541702 -107.678493) (xy 170.499297 -107.720898) (xy 170.451721 -107.757404)
			(xy 170.399787 -107.787388) (xy 170.344383 -107.810337) (xy 170.286458 -107.825858) (xy 170.227002 -107.833686)
			(xy 170.167034 -107.833686) (xy 170.107578 -107.825858) (xy 170.049653 -107.810337) (xy 169.994249 -107.787388)
			(xy 169.942315 -107.757404) (xy 169.894739 -107.720898) (xy 169.852334 -107.678493) (xy 169.815828 -107.630917)
			(xy 169.785844 -107.578983) (xy 169.762895 -107.523579) (xy 169.747374 -107.465654) (xy 169.739546 -107.406198)
			(xy 169.739056 -107.376214) (xy 154.325828 -107.376214) (xy 154.325828 -107.377738) (xy 154.325338 -107.407722)
			(xy 154.31751 -107.467178) (xy 154.301989 -107.525103) (xy 154.27904 -107.580507) (xy 154.249056 -107.632441)
			(xy 154.21255 -107.680017) (xy 154.170145 -107.722422) (xy 154.122569 -107.758928) (xy 154.070635 -107.788912)
			(xy 154.015231 -107.811861) (xy 153.957306 -107.827382) (xy 153.89785 -107.83521) (xy 153.837882 -107.83521)
			(xy 153.778426 -107.827382) (xy 153.720501 -107.811861) (xy 153.665097 -107.788912) (xy 153.613163 -107.758928)
			(xy 153.565587 -107.722422) (xy 153.523182 -107.680017) (xy 153.486676 -107.632441) (xy 153.456692 -107.580507)
			(xy 153.433743 -107.525103) (xy 153.418222 -107.467178) (xy 153.410394 -107.407722) (xy 153.409904 -107.377738)
			(xy 54.554603 -107.377738) (xy 54.554138 -107.406182) (xy 54.546315 -107.465604) (xy 54.530802 -107.523497)
			(xy 54.507866 -107.57887) (xy 54.477899 -107.630776) (xy 54.441412 -107.678326) (xy 54.399032 -107.720706)
			(xy 54.351482 -107.757193) (xy 54.299576 -107.78716) (xy 54.244203 -107.810096) (xy 54.18631 -107.825609)
			(xy 54.126888 -107.833432) (xy 54.066952 -107.833432) (xy 54.00753 -107.825609) (xy 53.949637 -107.810096)
			(xy 53.894264 -107.78716) (xy 53.842358 -107.757193) (xy 53.794808 -107.720706) (xy 53.752428 -107.678326)
			(xy 53.715941 -107.630776) (xy 53.685974 -107.57887) (xy 53.663038 -107.523497) (xy 53.647525 -107.465604)
			(xy 53.639702 -107.406182) (xy 53.639212 -107.376214) (xy 38.225476 -107.376214) (xy 38.225476 -107.377738)
			(xy 38.224986 -107.407706) (xy 38.217163 -107.467128) (xy 38.20165 -107.525021) (xy 38.178714 -107.580394)
			(xy 38.148747 -107.6323) (xy 38.11226 -107.67985) (xy 38.06988 -107.72223) (xy 38.02233 -107.758717)
			(xy 37.970424 -107.788684) (xy 37.915051 -107.81162) (xy 37.857158 -107.827133) (xy 37.797736 -107.834956)
			(xy 37.7378 -107.834956) (xy 37.678378 -107.827133) (xy 37.620485 -107.81162) (xy 37.565112 -107.788684)
			(xy 37.513206 -107.758717) (xy 37.465656 -107.72223) (xy 37.423276 -107.67985) (xy 37.386789 -107.6323)
			(xy 37.356822 -107.580394) (xy 37.333886 -107.525021) (xy 37.318373 -107.467128) (xy 37.31055 -107.407706)
			(xy 37.31006 -107.377738) (xy 4.30911 -107.377738) (xy 4.30911 -109.18444) (xy 34.667952 -109.18444)
			(xy 34.667952 -108.32084) (xy 34.668442 -108.290872) (xy 34.676265 -108.23145) (xy 34.691778 -108.173557)
			(xy 34.714714 -108.118184) (xy 34.744681 -108.066278) (xy 34.781168 -108.018728) (xy 34.823548 -107.976348)
			(xy 34.871098 -107.939861) (xy 34.923004 -107.909894) (xy 34.978377 -107.886958) (xy 35.03627 -107.871445)
			(xy 35.095692 -107.863622) (xy 35.155628 -107.863622) (xy 35.21505 -107.871445) (xy 35.272943 -107.886958)
			(xy 35.328316 -107.909894) (xy 35.380222 -107.939861) (xy 35.427772 -107.976348) (xy 35.470152 -108.018728)
			(xy 35.506639 -108.066278) (xy 35.536606 -108.118184) (xy 35.559542 -108.173557) (xy 35.575055 -108.23145)
			(xy 35.582878 -108.290872) (xy 35.583368 -108.32084) (xy 35.583368 -109.176312) (xy 51.785012 -109.176312)
			(xy 51.785012 -108.312712) (xy 51.785502 -108.282744) (xy 51.793325 -108.223322) (xy 51.808838 -108.165429)
			(xy 51.831774 -108.110056) (xy 51.861741 -108.05815) (xy 51.898228 -108.0106) (xy 51.940608 -107.96822)
			(xy 51.988158 -107.931733) (xy 52.040064 -107.901766) (xy 52.095437 -107.87883) (xy 52.15333 -107.863317)
			(xy 52.212752 -107.855494) (xy 52.272688 -107.855494) (xy 52.33211 -107.863317) (xy 52.390003 -107.87883)
			(xy 52.445376 -107.901766) (xy 52.497282 -107.931733) (xy 52.544832 -107.96822) (xy 52.587212 -108.0106)
			(xy 52.623699 -108.05815) (xy 52.653666 -108.110056) (xy 52.676602 -108.165429) (xy 52.692115 -108.223322)
			(xy 52.699938 -108.282744) (xy 52.700428 -108.312712) (xy 52.700428 -109.176312) (xy 52.700295 -109.18444)
			(xy 150.767796 -109.18444) (xy 150.767796 -108.32084) (xy 150.768286 -108.290856) (xy 150.776114 -108.2314)
			(xy 150.791635 -108.173475) (xy 150.814584 -108.118071) (xy 150.844568 -108.066137) (xy 150.881074 -108.018561)
			(xy 150.923479 -107.976156) (xy 150.971055 -107.93965) (xy 151.022989 -107.909666) (xy 151.078393 -107.886717)
			(xy 151.136318 -107.871196) (xy 151.195774 -107.863368) (xy 151.255742 -107.863368) (xy 151.315198 -107.871196)
			(xy 151.373123 -107.886717) (xy 151.428527 -107.909666) (xy 151.480461 -107.93965) (xy 151.528037 -107.976156)
			(xy 151.570442 -108.018561) (xy 151.606948 -108.066137) (xy 151.636932 -108.118071) (xy 151.659881 -108.173475)
			(xy 151.675402 -108.2314) (xy 151.68323 -108.290856) (xy 151.68372 -108.32084) (xy 151.68372 -109.176312)
			(xy 167.884856 -109.176312) (xy 167.884856 -108.312712) (xy 167.885346 -108.282728) (xy 167.893174 -108.223272)
			(xy 167.908695 -108.165347) (xy 167.931644 -108.109943) (xy 167.961628 -108.058009) (xy 167.998134 -108.010433)
			(xy 168.040539 -107.968028) (xy 168.088115 -107.931522) (xy 168.140049 -107.901538) (xy 168.195453 -107.878589)
			(xy 168.253378 -107.863068) (xy 168.312834 -107.85524) (xy 168.372802 -107.85524) (xy 168.432258 -107.863068)
			(xy 168.490183 -107.878589) (xy 168.545587 -107.901538) (xy 168.597521 -107.931522) (xy 168.645097 -107.968028)
			(xy 168.687502 -108.010433) (xy 168.724008 -108.058009) (xy 168.753992 -108.109943) (xy 168.776941 -108.165347)
			(xy 168.792462 -108.223272) (xy 168.80029 -108.282728) (xy 168.80078 -108.312712) (xy 168.80078 -109.176312)
			(xy 168.800647 -109.18444) (xy 266.86764 -109.18444) (xy 266.86764 -108.32084) (xy 266.86813 -108.290856)
			(xy 266.875958 -108.2314) (xy 266.891479 -108.173475) (xy 266.914428 -108.118071) (xy 266.944412 -108.066137)
			(xy 266.980918 -108.018561) (xy 267.023323 -107.976156) (xy 267.070899 -107.93965) (xy 267.122833 -107.909666)
			(xy 267.178237 -107.886717) (xy 267.236162 -107.871196) (xy 267.295618 -107.863368) (xy 267.355586 -107.863368)
			(xy 267.415042 -107.871196) (xy 267.472967 -107.886717) (xy 267.528371 -107.909666) (xy 267.580305 -107.93965)
			(xy 267.627881 -107.976156) (xy 267.670286 -108.018561) (xy 267.706792 -108.066137) (xy 267.736776 -108.118071)
			(xy 267.759725 -108.173475) (xy 267.775246 -108.2314) (xy 267.783074 -108.290856) (xy 267.783564 -108.32084)
			(xy 267.783564 -109.176312) (xy 283.9847 -109.176312) (xy 283.9847 -108.312712) (xy 283.98519 -108.282728)
			(xy 283.993018 -108.223272) (xy 284.008539 -108.165347) (xy 284.031488 -108.109943) (xy 284.061472 -108.058009)
			(xy 284.097978 -108.010433) (xy 284.140383 -107.968028) (xy 284.187959 -107.931522) (xy 284.239893 -107.901538)
			(xy 284.295297 -107.878589) (xy 284.353222 -107.863068) (xy 284.412678 -107.85524) (xy 284.472646 -107.85524)
			(xy 284.532102 -107.863068) (xy 284.590027 -107.878589) (xy 284.645431 -107.901538) (xy 284.697365 -107.931522)
			(xy 284.744941 -107.968028) (xy 284.787346 -108.010433) (xy 284.823852 -108.058009) (xy 284.853836 -108.109943)
			(xy 284.876785 -108.165347) (xy 284.892306 -108.223272) (xy 284.900134 -108.282728) (xy 284.900624 -108.312712)
			(xy 284.900624 -109.176312) (xy 284.900491 -109.18444) (xy 382.967992 -109.18444) (xy 382.967992 -108.32084)
			(xy 382.968482 -108.290872) (xy 382.976305 -108.23145) (xy 382.991818 -108.173557) (xy 383.014754 -108.118184)
			(xy 383.044721 -108.066278) (xy 383.081208 -108.018728) (xy 383.123588 -107.976348) (xy 383.171138 -107.939861)
			(xy 383.223044 -107.909894) (xy 383.278417 -107.886958) (xy 383.33631 -107.871445) (xy 383.395732 -107.863622)
			(xy 383.455668 -107.863622) (xy 383.51509 -107.871445) (xy 383.572983 -107.886958) (xy 383.628356 -107.909894)
			(xy 383.680262 -107.939861) (xy 383.727812 -107.976348) (xy 383.770192 -108.018728) (xy 383.806679 -108.066278)
			(xy 383.836646 -108.118184) (xy 383.859582 -108.173557) (xy 383.875095 -108.23145) (xy 383.882918 -108.290872)
			(xy 383.883408 -108.32084) (xy 383.883408 -109.176312) (xy 400.085052 -109.176312) (xy 400.085052 -108.312712)
			(xy 400.085542 -108.282744) (xy 400.093365 -108.223322) (xy 400.108878 -108.165429) (xy 400.131814 -108.110056)
			(xy 400.161781 -108.05815) (xy 400.198268 -108.0106) (xy 400.240648 -107.96822) (xy 400.288198 -107.931733)
			(xy 400.340104 -107.901766) (xy 400.395477 -107.87883) (xy 400.45337 -107.863317) (xy 400.512792 -107.855494)
			(xy 400.572728 -107.855494) (xy 400.63215 -107.863317) (xy 400.690043 -107.87883) (xy 400.745416 -107.901766)
			(xy 400.797322 -107.931733) (xy 400.844872 -107.96822) (xy 400.887252 -108.0106) (xy 400.923739 -108.05815)
			(xy 400.953706 -108.110056) (xy 400.976642 -108.165429) (xy 400.992155 -108.223322) (xy 400.999978 -108.282744)
			(xy 401.000468 -108.312712) (xy 401.000468 -109.176312) (xy 400.999978 -109.20628) (xy 400.992155 -109.265702)
			(xy 400.976642 -109.323595) (xy 400.953706 -109.378968) (xy 400.923739 -109.430874) (xy 400.887252 -109.478424)
			(xy 400.844872 -109.520804) (xy 400.797322 -109.557291) (xy 400.745416 -109.587258) (xy 400.690043 -109.610194)
			(xy 400.63215 -109.625707) (xy 400.572728 -109.63353) (xy 400.512792 -109.63353) (xy 400.45337 -109.625707)
			(xy 400.395477 -109.610194) (xy 400.340104 -109.587258) (xy 400.288198 -109.557291) (xy 400.240648 -109.520804)
			(xy 400.198268 -109.478424) (xy 400.161781 -109.430874) (xy 400.131814 -109.378968) (xy 400.108878 -109.323595)
			(xy 400.093365 -109.265702) (xy 400.085542 -109.20628) (xy 400.085052 -109.176312) (xy 383.883408 -109.176312)
			(xy 383.883408 -109.18444) (xy 383.882918 -109.214408) (xy 383.875095 -109.27383) (xy 383.859582 -109.331723)
			(xy 383.836646 -109.387096) (xy 383.806679 -109.439002) (xy 383.770192 -109.486552) (xy 383.727812 -109.528932)
			(xy 383.680262 -109.565419) (xy 383.628356 -109.595386) (xy 383.572983 -109.618322) (xy 383.51509 -109.633835)
			(xy 383.455668 -109.641658) (xy 383.395732 -109.641658) (xy 383.33631 -109.633835) (xy 383.278417 -109.618322)
			(xy 383.223044 -109.595386) (xy 383.171138 -109.565419) (xy 383.123588 -109.528932) (xy 383.081208 -109.486552)
			(xy 383.044721 -109.439002) (xy 383.014754 -109.387096) (xy 382.991818 -109.331723) (xy 382.976305 -109.27383)
			(xy 382.968482 -109.214408) (xy 382.967992 -109.18444) (xy 284.900491 -109.18444) (xy 284.900134 -109.206296)
			(xy 284.892306 -109.265752) (xy 284.876785 -109.323677) (xy 284.853836 -109.379081) (xy 284.823852 -109.431015)
			(xy 284.787346 -109.478591) (xy 284.744941 -109.520996) (xy 284.697365 -109.557502) (xy 284.645431 -109.587486)
			(xy 284.590027 -109.610435) (xy 284.532102 -109.625956) (xy 284.472646 -109.633784) (xy 284.412678 -109.633784)
			(xy 284.353222 -109.625956) (xy 284.295297 -109.610435) (xy 284.239893 -109.587486) (xy 284.187959 -109.557502)
			(xy 284.140383 -109.520996) (xy 284.097978 -109.478591) (xy 284.061472 -109.431015) (xy 284.031488 -109.379081)
			(xy 284.008539 -109.323677) (xy 283.993018 -109.265752) (xy 283.98519 -109.206296) (xy 283.9847 -109.176312)
			(xy 267.783564 -109.176312) (xy 267.783564 -109.18444) (xy 267.783074 -109.214424) (xy 267.775246 -109.27388)
			(xy 267.759725 -109.331805) (xy 267.736776 -109.387209) (xy 267.706792 -109.439143) (xy 267.670286 -109.486719)
			(xy 267.627881 -109.529124) (xy 267.580305 -109.56563) (xy 267.528371 -109.595614) (xy 267.472967 -109.618563)
			(xy 267.415042 -109.634084) (xy 267.355586 -109.641912) (xy 267.295618 -109.641912) (xy 267.236162 -109.634084)
			(xy 267.178237 -109.618563) (xy 267.122833 -109.595614) (xy 267.070899 -109.56563) (xy 267.023323 -109.529124)
			(xy 266.980918 -109.486719) (xy 266.944412 -109.439143) (xy 266.914428 -109.387209) (xy 266.891479 -109.331805)
			(xy 266.875958 -109.27388) (xy 266.86813 -109.214424) (xy 266.86764 -109.18444) (xy 168.800647 -109.18444)
			(xy 168.80029 -109.206296) (xy 168.792462 -109.265752) (xy 168.776941 -109.323677) (xy 168.753992 -109.379081)
			(xy 168.724008 -109.431015) (xy 168.687502 -109.478591) (xy 168.645097 -109.520996) (xy 168.597521 -109.557502)
			(xy 168.545587 -109.587486) (xy 168.490183 -109.610435) (xy 168.432258 -109.625956) (xy 168.372802 -109.633784)
			(xy 168.312834 -109.633784) (xy 168.253378 -109.625956) (xy 168.195453 -109.610435) (xy 168.140049 -109.587486)
			(xy 168.088115 -109.557502) (xy 168.040539 -109.520996) (xy 167.998134 -109.478591) (xy 167.961628 -109.431015)
			(xy 167.931644 -109.379081) (xy 167.908695 -109.323677) (xy 167.893174 -109.265752) (xy 167.885346 -109.206296)
			(xy 167.884856 -109.176312) (xy 151.68372 -109.176312) (xy 151.68372 -109.18444) (xy 151.68323 -109.214424)
			(xy 151.675402 -109.27388) (xy 151.659881 -109.331805) (xy 151.636932 -109.387209) (xy 151.606948 -109.439143)
			(xy 151.570442 -109.486719) (xy 151.528037 -109.529124) (xy 151.480461 -109.56563) (xy 151.428527 -109.595614)
			(xy 151.373123 -109.618563) (xy 151.315198 -109.634084) (xy 151.255742 -109.641912) (xy 151.195774 -109.641912)
			(xy 151.136318 -109.634084) (xy 151.078393 -109.618563) (xy 151.022989 -109.595614) (xy 150.971055 -109.56563)
			(xy 150.923479 -109.529124) (xy 150.881074 -109.486719) (xy 150.844568 -109.439143) (xy 150.814584 -109.387209)
			(xy 150.791635 -109.331805) (xy 150.776114 -109.27388) (xy 150.768286 -109.214424) (xy 150.767796 -109.18444)
			(xy 52.700295 -109.18444) (xy 52.699938 -109.20628) (xy 52.692115 -109.265702) (xy 52.676602 -109.323595)
			(xy 52.653666 -109.378968) (xy 52.623699 -109.430874) (xy 52.587212 -109.478424) (xy 52.544832 -109.520804)
			(xy 52.497282 -109.557291) (xy 52.445376 -109.587258) (xy 52.390003 -109.610194) (xy 52.33211 -109.625707)
			(xy 52.272688 -109.63353) (xy 52.212752 -109.63353) (xy 52.15333 -109.625707) (xy 52.095437 -109.610194)
			(xy 52.040064 -109.587258) (xy 51.988158 -109.557291) (xy 51.940608 -109.520804) (xy 51.898228 -109.478424)
			(xy 51.861741 -109.430874) (xy 51.831774 -109.378968) (xy 51.808838 -109.323595) (xy 51.793325 -109.265702)
			(xy 51.785502 -109.20628) (xy 51.785012 -109.176312) (xy 35.583368 -109.176312) (xy 35.583368 -109.18444)
			(xy 35.582878 -109.214408) (xy 35.575055 -109.27383) (xy 35.559542 -109.331723) (xy 35.536606 -109.387096)
			(xy 35.506639 -109.439002) (xy 35.470152 -109.486552) (xy 35.427772 -109.528932) (xy 35.380222 -109.565419)
			(xy 35.328316 -109.595386) (xy 35.272943 -109.618322) (xy 35.21505 -109.633835) (xy 35.155628 -109.641658)
			(xy 35.095692 -109.641658) (xy 35.03627 -109.633835) (xy 34.978377 -109.618322) (xy 34.923004 -109.595386)
			(xy 34.871098 -109.565419) (xy 34.823548 -109.528932) (xy 34.781168 -109.486552) (xy 34.744681 -109.439002)
			(xy 34.714714 -109.387096) (xy 34.691778 -109.331723) (xy 34.676265 -109.27383) (xy 34.668442 -109.214408)
			(xy 34.667952 -109.18444) (xy 4.30911 -109.18444) (xy 4.30911 -110.977934) (xy 37.31006 -110.977934)
			(xy 37.31006 -110.114334) (xy 37.31055 -110.084366) (xy 37.318373 -110.024944) (xy 37.333886 -109.967051)
			(xy 37.356822 -109.911678) (xy 37.386789 -109.859772) (xy 37.423276 -109.812222) (xy 37.465656 -109.769842)
			(xy 37.513206 -109.733355) (xy 37.565112 -109.703388) (xy 37.620485 -109.680452) (xy 37.678378 -109.664939)
			(xy 37.7378 -109.657116) (xy 37.797736 -109.657116) (xy 37.857158 -109.664939) (xy 37.915051 -109.680452)
			(xy 37.970424 -109.703388) (xy 38.02233 -109.733355) (xy 38.06988 -109.769842) (xy 38.11226 -109.812222)
			(xy 38.148747 -109.859772) (xy 38.178714 -109.911678) (xy 38.20165 -109.967051) (xy 38.217163 -110.024944)
			(xy 38.224986 -110.084366) (xy 38.225476 -110.114334) (xy 38.225476 -110.97641) (xy 53.639212 -110.97641)
			(xy 53.639212 -110.11281) (xy 53.639702 -110.082842) (xy 53.647525 -110.02342) (xy 53.663038 -109.965527)
			(xy 53.685974 -109.910154) (xy 53.715941 -109.858248) (xy 53.752428 -109.810698) (xy 53.794808 -109.768318)
			(xy 53.842358 -109.731831) (xy 53.894264 -109.701864) (xy 53.949637 -109.678928) (xy 54.00753 -109.663415)
			(xy 54.066952 -109.655592) (xy 54.126888 -109.655592) (xy 54.18631 -109.663415) (xy 54.244203 -109.678928)
			(xy 54.299576 -109.701864) (xy 54.351482 -109.731831) (xy 54.399032 -109.768318) (xy 54.441412 -109.810698)
			(xy 54.477899 -109.858248) (xy 54.507866 -109.910154) (xy 54.530802 -109.965527) (xy 54.546315 -110.02342)
			(xy 54.554138 -110.082842) (xy 54.554628 -110.11281) (xy 54.554628 -110.97641) (xy 54.554603 -110.977934)
			(xy 153.409904 -110.977934) (xy 153.409904 -110.114334) (xy 153.410394 -110.08435) (xy 153.418222 -110.024894)
			(xy 153.433743 -109.966969) (xy 153.456692 -109.911565) (xy 153.486676 -109.859631) (xy 153.523182 -109.812055)
			(xy 153.565587 -109.76965) (xy 153.613163 -109.733144) (xy 153.665097 -109.70316) (xy 153.720501 -109.680211)
			(xy 153.778426 -109.66469) (xy 153.837882 -109.656862) (xy 153.89785 -109.656862) (xy 153.957306 -109.66469)
			(xy 154.015231 -109.680211) (xy 154.070635 -109.70316) (xy 154.122569 -109.733144) (xy 154.170145 -109.76965)
			(xy 154.21255 -109.812055) (xy 154.249056 -109.859631) (xy 154.27904 -109.911565) (xy 154.301989 -109.966969)
			(xy 154.31751 -110.024894) (xy 154.325338 -110.08435) (xy 154.325828 -110.114334) (xy 154.325828 -110.97641)
			(xy 169.739056 -110.97641) (xy 169.739056 -110.11281) (xy 169.739546 -110.082826) (xy 169.747374 -110.02337)
			(xy 169.762895 -109.965445) (xy 169.785844 -109.910041) (xy 169.815828 -109.858107) (xy 169.852334 -109.810531)
			(xy 169.894739 -109.768126) (xy 169.942315 -109.73162) (xy 169.994249 -109.701636) (xy 170.049653 -109.678687)
			(xy 170.107578 -109.663166) (xy 170.167034 -109.655338) (xy 170.227002 -109.655338) (xy 170.286458 -109.663166)
			(xy 170.344383 -109.678687) (xy 170.399787 -109.701636) (xy 170.451721 -109.73162) (xy 170.499297 -109.768126)
			(xy 170.541702 -109.810531) (xy 170.578208 -109.858107) (xy 170.608192 -109.910041) (xy 170.631141 -109.965445)
			(xy 170.646662 -110.02337) (xy 170.65449 -110.082826) (xy 170.65498 -110.11281) (xy 170.65498 -110.97641)
			(xy 170.654955 -110.977934) (xy 269.509748 -110.977934) (xy 269.509748 -110.114334) (xy 269.510238 -110.08435)
			(xy 269.518066 -110.024894) (xy 269.533587 -109.966969) (xy 269.556536 -109.911565) (xy 269.58652 -109.859631)
			(xy 269.623026 -109.812055) (xy 269.665431 -109.76965) (xy 269.713007 -109.733144) (xy 269.764941 -109.70316)
			(xy 269.820345 -109.680211) (xy 269.87827 -109.66469) (xy 269.937726 -109.656862) (xy 269.997694 -109.656862)
			(xy 270.05715 -109.66469) (xy 270.115075 -109.680211) (xy 270.170479 -109.70316) (xy 270.222413 -109.733144)
			(xy 270.269989 -109.76965) (xy 270.312394 -109.812055) (xy 270.3489 -109.859631) (xy 270.378884 -109.911565)
			(xy 270.401833 -109.966969) (xy 270.417354 -110.024894) (xy 270.425182 -110.08435) (xy 270.425672 -110.114334)
			(xy 270.425672 -110.97641) (xy 285.8389 -110.97641) (xy 285.8389 -110.11281) (xy 285.83939 -110.082826)
			(xy 285.847218 -110.02337) (xy 285.862739 -109.965445) (xy 285.885688 -109.910041) (xy 285.915672 -109.858107)
			(xy 285.952178 -109.810531) (xy 285.994583 -109.768126) (xy 286.042159 -109.73162) (xy 286.094093 -109.701636)
			(xy 286.149497 -109.678687) (xy 286.207422 -109.663166) (xy 286.266878 -109.655338) (xy 286.326846 -109.655338)
			(xy 286.386302 -109.663166) (xy 286.444227 -109.678687) (xy 286.499631 -109.701636) (xy 286.551565 -109.73162)
			(xy 286.599141 -109.768126) (xy 286.641546 -109.810531) (xy 286.678052 -109.858107) (xy 286.708036 -109.910041)
			(xy 286.730985 -109.965445) (xy 286.746506 -110.02337) (xy 286.754334 -110.082826) (xy 286.754824 -110.11281)
			(xy 286.754824 -110.97641) (xy 286.754799 -110.977934) (xy 385.6101 -110.977934) (xy 385.6101 -110.114334)
			(xy 385.61059 -110.084366) (xy 385.618413 -110.024944) (xy 385.633926 -109.967051) (xy 385.656862 -109.911678)
			(xy 385.686829 -109.859772) (xy 385.723316 -109.812222) (xy 385.765696 -109.769842) (xy 385.813246 -109.733355)
			(xy 385.865152 -109.703388) (xy 385.920525 -109.680452) (xy 385.978418 -109.664939) (xy 386.03784 -109.657116)
			(xy 386.097776 -109.657116) (xy 386.157198 -109.664939) (xy 386.215091 -109.680452) (xy 386.270464 -109.703388)
			(xy 386.32237 -109.733355) (xy 386.36992 -109.769842) (xy 386.4123 -109.812222) (xy 386.448787 -109.859772)
			(xy 386.478754 -109.911678) (xy 386.50169 -109.967051) (xy 386.517203 -110.024944) (xy 386.525026 -110.084366)
			(xy 386.525516 -110.114334) (xy 386.525516 -110.97641) (xy 401.939252 -110.97641) (xy 401.939252 -110.11281)
			(xy 401.939742 -110.082842) (xy 401.947565 -110.02342) (xy 401.963078 -109.965527) (xy 401.986014 -109.910154)
			(xy 402.015981 -109.858248) (xy 402.052468 -109.810698) (xy 402.094848 -109.768318) (xy 402.142398 -109.731831)
			(xy 402.194304 -109.701864) (xy 402.249677 -109.678928) (xy 402.30757 -109.663415) (xy 402.366992 -109.655592)
			(xy 402.426928 -109.655592) (xy 402.48635 -109.663415) (xy 402.544243 -109.678928) (xy 402.599616 -109.701864)
			(xy 402.651522 -109.731831) (xy 402.699072 -109.768318) (xy 402.741452 -109.810698) (xy 402.777939 -109.858248)
			(xy 402.807906 -109.910154) (xy 402.830842 -109.965527) (xy 402.846355 -110.02342) (xy 402.854178 -110.082842)
			(xy 402.854668 -110.11281) (xy 402.854668 -110.97641) (xy 402.854178 -111.006378) (xy 402.846355 -111.0658)
			(xy 402.830842 -111.123693) (xy 402.807906 -111.179066) (xy 402.777939 -111.230972) (xy 402.741452 -111.278522)
			(xy 402.699072 -111.320902) (xy 402.651522 -111.357389) (xy 402.599616 -111.387356) (xy 402.544243 -111.410292)
			(xy 402.48635 -111.425805) (xy 402.426928 -111.433628) (xy 402.366992 -111.433628) (xy 402.30757 -111.425805)
			(xy 402.249677 -111.410292) (xy 402.194304 -111.387356) (xy 402.142398 -111.357389) (xy 402.094848 -111.320902)
			(xy 402.052468 -111.278522) (xy 402.015981 -111.230972) (xy 401.986014 -111.179066) (xy 401.963078 -111.123693)
			(xy 401.947565 -111.0658) (xy 401.939742 -111.006378) (xy 401.939252 -110.97641) (xy 386.525516 -110.97641)
			(xy 386.525516 -110.977934) (xy 386.525026 -111.007902) (xy 386.517203 -111.067324) (xy 386.50169 -111.125217)
			(xy 386.478754 -111.18059) (xy 386.448787 -111.232496) (xy 386.4123 -111.280046) (xy 386.36992 -111.322426)
			(xy 386.32237 -111.358913) (xy 386.270464 -111.38888) (xy 386.215091 -111.411816) (xy 386.157198 -111.427329)
			(xy 386.097776 -111.435152) (xy 386.03784 -111.435152) (xy 385.978418 -111.427329) (xy 385.920525 -111.411816)
			(xy 385.865152 -111.38888) (xy 385.813246 -111.358913) (xy 385.765696 -111.322426) (xy 385.723316 -111.280046)
			(xy 385.686829 -111.232496) (xy 385.656862 -111.18059) (xy 385.633926 -111.125217) (xy 385.618413 -111.067324)
			(xy 385.61059 -111.007902) (xy 385.6101 -110.977934) (xy 286.754799 -110.977934) (xy 286.754334 -111.006394)
			(xy 286.746506 -111.06585) (xy 286.730985 -111.123775) (xy 286.708036 -111.179179) (xy 286.678052 -111.231113)
			(xy 286.641546 -111.278689) (xy 286.599141 -111.321094) (xy 286.551565 -111.3576) (xy 286.499631 -111.387584)
			(xy 286.444227 -111.410533) (xy 286.386302 -111.426054) (xy 286.326846 -111.433882) (xy 286.266878 -111.433882)
			(xy 286.207422 -111.426054) (xy 286.149497 -111.410533) (xy 286.094093 -111.387584) (xy 286.042159 -111.3576)
			(xy 285.994583 -111.321094) (xy 285.952178 -111.278689) (xy 285.915672 -111.231113) (xy 285.885688 -111.179179)
			(xy 285.862739 -111.123775) (xy 285.847218 -111.06585) (xy 285.83939 -111.006394) (xy 285.8389 -110.97641)
			(xy 270.425672 -110.97641) (xy 270.425672 -110.977934) (xy 270.425182 -111.007918) (xy 270.417354 -111.067374)
			(xy 270.401833 -111.125299) (xy 270.378884 -111.180703) (xy 270.3489 -111.232637) (xy 270.312394 -111.280213)
			(xy 270.269989 -111.322618) (xy 270.222413 -111.359124) (xy 270.170479 -111.389108) (xy 270.115075 -111.412057)
			(xy 270.05715 -111.427578) (xy 269.997694 -111.435406) (xy 269.937726 -111.435406) (xy 269.87827 -111.427578)
			(xy 269.820345 -111.412057) (xy 269.764941 -111.389108) (xy 269.713007 -111.359124) (xy 269.665431 -111.322618)
			(xy 269.623026 -111.280213) (xy 269.58652 -111.232637) (xy 269.556536 -111.180703) (xy 269.533587 -111.125299)
			(xy 269.518066 -111.067374) (xy 269.510238 -111.007918) (xy 269.509748 -110.977934) (xy 170.654955 -110.977934)
			(xy 170.65449 -111.006394) (xy 170.646662 -111.06585) (xy 170.631141 -111.123775) (xy 170.608192 -111.179179)
			(xy 170.578208 -111.231113) (xy 170.541702 -111.278689) (xy 170.499297 -111.321094) (xy 170.451721 -111.3576)
			(xy 170.399787 -111.387584) (xy 170.344383 -111.410533) (xy 170.286458 -111.426054) (xy 170.227002 -111.433882)
			(xy 170.167034 -111.433882) (xy 170.107578 -111.426054) (xy 170.049653 -111.410533) (xy 169.994249 -111.387584)
			(xy 169.942315 -111.3576) (xy 169.894739 -111.321094) (xy 169.852334 -111.278689) (xy 169.815828 -111.231113)
			(xy 169.785844 -111.179179) (xy 169.762895 -111.123775) (xy 169.747374 -111.06585) (xy 169.739546 -111.006394)
			(xy 169.739056 -110.97641) (xy 154.325828 -110.97641) (xy 154.325828 -110.977934) (xy 154.325338 -111.007918)
			(xy 154.31751 -111.067374) (xy 154.301989 -111.125299) (xy 154.27904 -111.180703) (xy 154.249056 -111.232637)
			(xy 154.21255 -111.280213) (xy 154.170145 -111.322618) (xy 154.122569 -111.359124) (xy 154.070635 -111.389108)
			(xy 154.015231 -111.412057) (xy 153.957306 -111.427578) (xy 153.89785 -111.435406) (xy 153.837882 -111.435406)
			(xy 153.778426 -111.427578) (xy 153.720501 -111.412057) (xy 153.665097 -111.389108) (xy 153.613163 -111.359124)
			(xy 153.565587 -111.322618) (xy 153.523182 -111.280213) (xy 153.486676 -111.232637) (xy 153.456692 -111.180703)
			(xy 153.433743 -111.125299) (xy 153.418222 -111.067374) (xy 153.410394 -111.007918) (xy 153.409904 -110.977934)
			(xy 54.554603 -110.977934) (xy 54.554138 -111.006378) (xy 54.546315 -111.0658) (xy 54.530802 -111.123693)
			(xy 54.507866 -111.179066) (xy 54.477899 -111.230972) (xy 54.441412 -111.278522) (xy 54.399032 -111.320902)
			(xy 54.351482 -111.357389) (xy 54.299576 -111.387356) (xy 54.244203 -111.410292) (xy 54.18631 -111.425805)
			(xy 54.126888 -111.433628) (xy 54.066952 -111.433628) (xy 54.00753 -111.425805) (xy 53.949637 -111.410292)
			(xy 53.894264 -111.387356) (xy 53.842358 -111.357389) (xy 53.794808 -111.320902) (xy 53.752428 -111.278522)
			(xy 53.715941 -111.230972) (xy 53.685974 -111.179066) (xy 53.663038 -111.123693) (xy 53.647525 -111.0658)
			(xy 53.639702 -111.006378) (xy 53.639212 -110.97641) (xy 38.225476 -110.97641) (xy 38.225476 -110.977934)
			(xy 38.224986 -111.007902) (xy 38.217163 -111.067324) (xy 38.20165 -111.125217) (xy 38.178714 -111.18059)
			(xy 38.148747 -111.232496) (xy 38.11226 -111.280046) (xy 38.06988 -111.322426) (xy 38.02233 -111.358913)
			(xy 37.970424 -111.38888) (xy 37.915051 -111.411816) (xy 37.857158 -111.427329) (xy 37.797736 -111.435152)
			(xy 37.7378 -111.435152) (xy 37.678378 -111.427329) (xy 37.620485 -111.411816) (xy 37.565112 -111.38888)
			(xy 37.513206 -111.358913) (xy 37.465656 -111.322426) (xy 37.423276 -111.280046) (xy 37.386789 -111.232496)
			(xy 37.356822 -111.18059) (xy 37.333886 -111.125217) (xy 37.318373 -111.067324) (xy 37.31055 -111.007902)
			(xy 37.31006 -110.977934) (xy 4.30911 -110.977934) (xy 4.30911 -112.784382) (xy 34.667952 -112.784382)
			(xy 34.667952 -111.920782) (xy 34.668442 -111.890814) (xy 34.676265 -111.831392) (xy 34.691778 -111.773499)
			(xy 34.714714 -111.718126) (xy 34.744681 -111.66622) (xy 34.781168 -111.61867) (xy 34.823548 -111.57629)
			(xy 34.871098 -111.539803) (xy 34.923004 -111.509836) (xy 34.978377 -111.4869) (xy 35.03627 -111.471387)
			(xy 35.095692 -111.463564) (xy 35.155628 -111.463564) (xy 35.21505 -111.471387) (xy 35.272943 -111.4869)
			(xy 35.328316 -111.509836) (xy 35.380222 -111.539803) (xy 35.427772 -111.57629) (xy 35.470152 -111.61867)
			(xy 35.506639 -111.66622) (xy 35.536606 -111.718126) (xy 35.559542 -111.773499) (xy 35.575055 -111.831392)
			(xy 35.582878 -111.890814) (xy 35.583368 -111.920782) (xy 35.583368 -112.776508) (xy 51.785012 -112.776508)
			(xy 51.785012 -111.912908) (xy 51.785502 -111.88294) (xy 51.793325 -111.823518) (xy 51.808838 -111.765625)
			(xy 51.831774 -111.710252) (xy 51.861741 -111.658346) (xy 51.898228 -111.610796) (xy 51.940608 -111.568416)
			(xy 51.988158 -111.531929) (xy 52.040064 -111.501962) (xy 52.095437 -111.479026) (xy 52.15333 -111.463513)
			(xy 52.212752 -111.45569) (xy 52.272688 -111.45569) (xy 52.33211 -111.463513) (xy 52.390003 -111.479026)
			(xy 52.445376 -111.501962) (xy 52.497282 -111.531929) (xy 52.544832 -111.568416) (xy 52.587212 -111.610796)
			(xy 52.623699 -111.658346) (xy 52.653666 -111.710252) (xy 52.676602 -111.765625) (xy 52.692115 -111.823518)
			(xy 52.699938 -111.88294) (xy 52.700428 -111.912908) (xy 52.700428 -112.776508) (xy 52.700299 -112.784382)
			(xy 150.767796 -112.784382) (xy 150.767796 -111.920782) (xy 150.768286 -111.890798) (xy 150.776114 -111.831342)
			(xy 150.791635 -111.773417) (xy 150.814584 -111.718013) (xy 150.844568 -111.666079) (xy 150.881074 -111.618503)
			(xy 150.923479 -111.576098) (xy 150.971055 -111.539592) (xy 151.022989 -111.509608) (xy 151.078393 -111.486659)
			(xy 151.136318 -111.471138) (xy 151.195774 -111.46331) (xy 151.255742 -111.46331) (xy 151.315198 -111.471138)
			(xy 151.373123 -111.486659) (xy 151.428527 -111.509608) (xy 151.480461 -111.539592) (xy 151.528037 -111.576098)
			(xy 151.570442 -111.618503) (xy 151.606948 -111.666079) (xy 151.636932 -111.718013) (xy 151.659881 -111.773417)
			(xy 151.675402 -111.831342) (xy 151.68323 -111.890798) (xy 151.68372 -111.920782) (xy 151.68372 -112.776508)
			(xy 167.884856 -112.776508) (xy 167.884856 -111.912908) (xy 167.885346 -111.882924) (xy 167.893174 -111.823468)
			(xy 167.908695 -111.765543) (xy 167.931644 -111.710139) (xy 167.961628 -111.658205) (xy 167.998134 -111.610629)
			(xy 168.040539 -111.568224) (xy 168.088115 -111.531718) (xy 168.140049 -111.501734) (xy 168.195453 -111.478785)
			(xy 168.253378 -111.463264) (xy 168.312834 -111.455436) (xy 168.372802 -111.455436) (xy 168.432258 -111.463264)
			(xy 168.490183 -111.478785) (xy 168.545587 -111.501734) (xy 168.597521 -111.531718) (xy 168.645097 -111.568224)
			(xy 168.687502 -111.610629) (xy 168.724008 -111.658205) (xy 168.753992 -111.710139) (xy 168.776941 -111.765543)
			(xy 168.792462 -111.823468) (xy 168.80029 -111.882924) (xy 168.80078 -111.912908) (xy 168.80078 -112.776508)
			(xy 168.800651 -112.784382) (xy 266.86764 -112.784382) (xy 266.86764 -111.920782) (xy 266.86813 -111.890798)
			(xy 266.875958 -111.831342) (xy 266.891479 -111.773417) (xy 266.914428 -111.718013) (xy 266.944412 -111.666079)
			(xy 266.980918 -111.618503) (xy 267.023323 -111.576098) (xy 267.070899 -111.539592) (xy 267.122833 -111.509608)
			(xy 267.178237 -111.486659) (xy 267.236162 -111.471138) (xy 267.295618 -111.46331) (xy 267.355586 -111.46331)
			(xy 267.415042 -111.471138) (xy 267.472967 -111.486659) (xy 267.528371 -111.509608) (xy 267.580305 -111.539592)
			(xy 267.627881 -111.576098) (xy 267.670286 -111.618503) (xy 267.706792 -111.666079) (xy 267.736776 -111.718013)
			(xy 267.759725 -111.773417) (xy 267.775246 -111.831342) (xy 267.783074 -111.890798) (xy 267.783564 -111.920782)
			(xy 267.783564 -112.776508) (xy 283.9847 -112.776508) (xy 283.9847 -111.912908) (xy 283.98519 -111.882924)
			(xy 283.993018 -111.823468) (xy 284.008539 -111.765543) (xy 284.031488 -111.710139) (xy 284.061472 -111.658205)
			(xy 284.097978 -111.610629) (xy 284.140383 -111.568224) (xy 284.187959 -111.531718) (xy 284.239893 -111.501734)
			(xy 284.295297 -111.478785) (xy 284.353222 -111.463264) (xy 284.412678 -111.455436) (xy 284.472646 -111.455436)
			(xy 284.532102 -111.463264) (xy 284.590027 -111.478785) (xy 284.645431 -111.501734) (xy 284.697365 -111.531718)
			(xy 284.744941 -111.568224) (xy 284.787346 -111.610629) (xy 284.823852 -111.658205) (xy 284.853836 -111.710139)
			(xy 284.876785 -111.765543) (xy 284.892306 -111.823468) (xy 284.900134 -111.882924) (xy 284.900624 -111.912908)
			(xy 284.900624 -112.776508) (xy 284.900495 -112.784382) (xy 382.967992 -112.784382) (xy 382.967992 -111.920782)
			(xy 382.968482 -111.890814) (xy 382.976305 -111.831392) (xy 382.991818 -111.773499) (xy 383.014754 -111.718126)
			(xy 383.044721 -111.66622) (xy 383.081208 -111.61867) (xy 383.123588 -111.57629) (xy 383.171138 -111.539803)
			(xy 383.223044 -111.509836) (xy 383.278417 -111.4869) (xy 383.33631 -111.471387) (xy 383.395732 -111.463564)
			(xy 383.455668 -111.463564) (xy 383.51509 -111.471387) (xy 383.572983 -111.4869) (xy 383.628356 -111.509836)
			(xy 383.680262 -111.539803) (xy 383.727812 -111.57629) (xy 383.770192 -111.61867) (xy 383.806679 -111.66622)
			(xy 383.836646 -111.718126) (xy 383.859582 -111.773499) (xy 383.875095 -111.831392) (xy 383.882918 -111.890814)
			(xy 383.883408 -111.920782) (xy 383.883408 -112.776508) (xy 400.085052 -112.776508) (xy 400.085052 -111.912908)
			(xy 400.085542 -111.88294) (xy 400.093365 -111.823518) (xy 400.108878 -111.765625) (xy 400.131814 -111.710252)
			(xy 400.161781 -111.658346) (xy 400.198268 -111.610796) (xy 400.240648 -111.568416) (xy 400.288198 -111.531929)
			(xy 400.340104 -111.501962) (xy 400.395477 -111.479026) (xy 400.45337 -111.463513) (xy 400.512792 -111.45569)
			(xy 400.572728 -111.45569) (xy 400.63215 -111.463513) (xy 400.690043 -111.479026) (xy 400.745416 -111.501962)
			(xy 400.797322 -111.531929) (xy 400.844872 -111.568416) (xy 400.887252 -111.610796) (xy 400.923739 -111.658346)
			(xy 400.953706 -111.710252) (xy 400.976642 -111.765625) (xy 400.992155 -111.823518) (xy 400.999978 -111.88294)
			(xy 401.000468 -111.912908) (xy 401.000468 -112.776508) (xy 400.999978 -112.806476) (xy 400.992155 -112.865898)
			(xy 400.976642 -112.923791) (xy 400.953706 -112.979164) (xy 400.923739 -113.03107) (xy 400.887252 -113.07862)
			(xy 400.844872 -113.121) (xy 400.797322 -113.157487) (xy 400.745416 -113.187454) (xy 400.690043 -113.21039)
			(xy 400.63215 -113.225903) (xy 400.572728 -113.233726) (xy 400.512792 -113.233726) (xy 400.45337 -113.225903)
			(xy 400.395477 -113.21039) (xy 400.340104 -113.187454) (xy 400.288198 -113.157487) (xy 400.240648 -113.121)
			(xy 400.198268 -113.07862) (xy 400.161781 -113.03107) (xy 400.131814 -112.979164) (xy 400.108878 -112.923791)
			(xy 400.093365 -112.865898) (xy 400.085542 -112.806476) (xy 400.085052 -112.776508) (xy 383.883408 -112.776508)
			(xy 383.883408 -112.784382) (xy 383.882918 -112.81435) (xy 383.875095 -112.873772) (xy 383.859582 -112.931665)
			(xy 383.836646 -112.987038) (xy 383.806679 -113.038944) (xy 383.770192 -113.086494) (xy 383.727812 -113.128874)
			(xy 383.680262 -113.165361) (xy 383.628356 -113.195328) (xy 383.572983 -113.218264) (xy 383.51509 -113.233777)
			(xy 383.455668 -113.2416) (xy 383.395732 -113.2416) (xy 383.33631 -113.233777) (xy 383.278417 -113.218264)
			(xy 383.223044 -113.195328) (xy 383.171138 -113.165361) (xy 383.123588 -113.128874) (xy 383.081208 -113.086494)
			(xy 383.044721 -113.038944) (xy 383.014754 -112.987038) (xy 382.991818 -112.931665) (xy 382.976305 -112.873772)
			(xy 382.968482 -112.81435) (xy 382.967992 -112.784382) (xy 284.900495 -112.784382) (xy 284.900134 -112.806492)
			(xy 284.892306 -112.865948) (xy 284.876785 -112.923873) (xy 284.853836 -112.979277) (xy 284.823852 -113.031211)
			(xy 284.787346 -113.078787) (xy 284.744941 -113.121192) (xy 284.697365 -113.157698) (xy 284.645431 -113.187682)
			(xy 284.590027 -113.210631) (xy 284.532102 -113.226152) (xy 284.472646 -113.23398) (xy 284.412678 -113.23398)
			(xy 284.353222 -113.226152) (xy 284.295297 -113.210631) (xy 284.239893 -113.187682) (xy 284.187959 -113.157698)
			(xy 284.140383 -113.121192) (xy 284.097978 -113.078787) (xy 284.061472 -113.031211) (xy 284.031488 -112.979277)
			(xy 284.008539 -112.923873) (xy 283.993018 -112.865948) (xy 283.98519 -112.806492) (xy 283.9847 -112.776508)
			(xy 267.783564 -112.776508) (xy 267.783564 -112.784382) (xy 267.783074 -112.814366) (xy 267.775246 -112.873822)
			(xy 267.759725 -112.931747) (xy 267.736776 -112.987151) (xy 267.706792 -113.039085) (xy 267.670286 -113.086661)
			(xy 267.627881 -113.129066) (xy 267.580305 -113.165572) (xy 267.528371 -113.195556) (xy 267.472967 -113.218505)
			(xy 267.415042 -113.234026) (xy 267.355586 -113.241854) (xy 267.295618 -113.241854) (xy 267.236162 -113.234026)
			(xy 267.178237 -113.218505) (xy 267.122833 -113.195556) (xy 267.070899 -113.165572) (xy 267.023323 -113.129066)
			(xy 266.980918 -113.086661) (xy 266.944412 -113.039085) (xy 266.914428 -112.987151) (xy 266.891479 -112.931747)
			(xy 266.875958 -112.873822) (xy 266.86813 -112.814366) (xy 266.86764 -112.784382) (xy 168.800651 -112.784382)
			(xy 168.80029 -112.806492) (xy 168.792462 -112.865948) (xy 168.776941 -112.923873) (xy 168.753992 -112.979277)
			(xy 168.724008 -113.031211) (xy 168.687502 -113.078787) (xy 168.645097 -113.121192) (xy 168.597521 -113.157698)
			(xy 168.545587 -113.187682) (xy 168.490183 -113.210631) (xy 168.432258 -113.226152) (xy 168.372802 -113.23398)
			(xy 168.312834 -113.23398) (xy 168.253378 -113.226152) (xy 168.195453 -113.210631) (xy 168.140049 -113.187682)
			(xy 168.088115 -113.157698) (xy 168.040539 -113.121192) (xy 167.998134 -113.078787) (xy 167.961628 -113.031211)
			(xy 167.931644 -112.979277) (xy 167.908695 -112.923873) (xy 167.893174 -112.865948) (xy 167.885346 -112.806492)
			(xy 167.884856 -112.776508) (xy 151.68372 -112.776508) (xy 151.68372 -112.784382) (xy 151.68323 -112.814366)
			(xy 151.675402 -112.873822) (xy 151.659881 -112.931747) (xy 151.636932 -112.987151) (xy 151.606948 -113.039085)
			(xy 151.570442 -113.086661) (xy 151.528037 -113.129066) (xy 151.480461 -113.165572) (xy 151.428527 -113.195556)
			(xy 151.373123 -113.218505) (xy 151.315198 -113.234026) (xy 151.255742 -113.241854) (xy 151.195774 -113.241854)
			(xy 151.136318 -113.234026) (xy 151.078393 -113.218505) (xy 151.022989 -113.195556) (xy 150.971055 -113.165572)
			(xy 150.923479 -113.129066) (xy 150.881074 -113.086661) (xy 150.844568 -113.039085) (xy 150.814584 -112.987151)
			(xy 150.791635 -112.931747) (xy 150.776114 -112.873822) (xy 150.768286 -112.814366) (xy 150.767796 -112.784382)
			(xy 52.700299 -112.784382) (xy 52.699938 -112.806476) (xy 52.692115 -112.865898) (xy 52.676602 -112.923791)
			(xy 52.653666 -112.979164) (xy 52.623699 -113.03107) (xy 52.587212 -113.07862) (xy 52.544832 -113.121)
			(xy 52.497282 -113.157487) (xy 52.445376 -113.187454) (xy 52.390003 -113.21039) (xy 52.33211 -113.225903)
			(xy 52.272688 -113.233726) (xy 52.212752 -113.233726) (xy 52.15333 -113.225903) (xy 52.095437 -113.21039)
			(xy 52.040064 -113.187454) (xy 51.988158 -113.157487) (xy 51.940608 -113.121) (xy 51.898228 -113.07862)
			(xy 51.861741 -113.03107) (xy 51.831774 -112.979164) (xy 51.808838 -112.923791) (xy 51.793325 -112.865898)
			(xy 51.785502 -112.806476) (xy 51.785012 -112.776508) (xy 35.583368 -112.776508) (xy 35.583368 -112.784382)
			(xy 35.582878 -112.81435) (xy 35.575055 -112.873772) (xy 35.559542 -112.931665) (xy 35.536606 -112.987038)
			(xy 35.506639 -113.038944) (xy 35.470152 -113.086494) (xy 35.427772 -113.128874) (xy 35.380222 -113.165361)
			(xy 35.328316 -113.195328) (xy 35.272943 -113.218264) (xy 35.21505 -113.233777) (xy 35.155628 -113.2416)
			(xy 35.095692 -113.2416) (xy 35.03627 -113.233777) (xy 34.978377 -113.218264) (xy 34.923004 -113.195328)
			(xy 34.871098 -113.165361) (xy 34.823548 -113.128874) (xy 34.781168 -113.086494) (xy 34.744681 -113.038944)
			(xy 34.714714 -112.987038) (xy 34.691778 -112.931665) (xy 34.676265 -112.873772) (xy 34.668442 -112.81435)
			(xy 34.667952 -112.784382) (xy 4.30911 -112.784382) (xy 4.30911 -117.758718) (xy 74.474832 -117.758718)
			(xy 74.474832 -116.895118) (xy 74.475322 -116.865134) (xy 74.48315 -116.805678) (xy 74.498671 -116.747753)
			(xy 74.52162 -116.692349) (xy 74.551604 -116.640415) (xy 74.58811 -116.592839) (xy 74.630515 -116.550434)
			(xy 74.678091 -116.513928) (xy 74.730025 -116.483944) (xy 74.785429 -116.460995) (xy 74.843354 -116.445474)
			(xy 74.90281 -116.437646) (xy 74.962778 -116.437646) (xy 75.022234 -116.445474) (xy 75.080159 -116.460995)
			(xy 75.135563 -116.483944) (xy 75.187497 -116.513928) (xy 75.235073 -116.550434) (xy 75.277478 -116.592839)
			(xy 75.313984 -116.640415) (xy 75.343968 -116.692349) (xy 75.366917 -116.747753) (xy 75.382438 -116.805678)
			(xy 75.390266 -116.865134) (xy 75.390756 -116.895118) (xy 75.390756 -117.758718) (xy 190.574676 -117.758718)
			(xy 190.574676 -116.895118) (xy 190.575166 -116.865134) (xy 190.582994 -116.805678) (xy 190.598515 -116.747753)
			(xy 190.621464 -116.692349) (xy 190.651448 -116.640415) (xy 190.687954 -116.592839) (xy 190.730359 -116.550434)
			(xy 190.777935 -116.513928) (xy 190.829869 -116.483944) (xy 190.885273 -116.460995) (xy 190.943198 -116.445474)
			(xy 191.002654 -116.437646) (xy 191.062622 -116.437646) (xy 191.122078 -116.445474) (xy 191.180003 -116.460995)
			(xy 191.235407 -116.483944) (xy 191.287341 -116.513928) (xy 191.334917 -116.550434) (xy 191.377322 -116.592839)
			(xy 191.413828 -116.640415) (xy 191.443812 -116.692349) (xy 191.466761 -116.747753) (xy 191.482282 -116.805678)
			(xy 191.49011 -116.865134) (xy 191.4906 -116.895118) (xy 191.4906 -117.758718) (xy 306.675028 -117.758718)
			(xy 306.675028 -116.895118) (xy 306.675518 -116.86515) (xy 306.683341 -116.805728) (xy 306.698854 -116.747835)
			(xy 306.72179 -116.692462) (xy 306.751757 -116.640556) (xy 306.788244 -116.593006) (xy 306.830624 -116.550626)
			(xy 306.878174 -116.514139) (xy 306.93008 -116.484172) (xy 306.985453 -116.461236) (xy 307.043346 -116.445723)
			(xy 307.102768 -116.4379) (xy 307.162704 -116.4379) (xy 307.222126 -116.445723) (xy 307.280019 -116.461236)
			(xy 307.335392 -116.484172) (xy 307.387298 -116.514139) (xy 307.434848 -116.550626) (xy 307.477228 -116.593006)
			(xy 307.513715 -116.640556) (xy 307.543682 -116.692462) (xy 307.566618 -116.747835) (xy 307.582131 -116.805728)
			(xy 307.589954 -116.86515) (xy 307.590444 -116.895118) (xy 307.590444 -117.758718) (xy 307.590436 -117.759226)
			(xy 422.774872 -117.759226) (xy 422.774872 -116.895626) (xy 422.775362 -116.865642) (xy 422.78319 -116.806186)
			(xy 422.798711 -116.748261) (xy 422.82166 -116.692857) (xy 422.851644 -116.640923) (xy 422.88815 -116.593347)
			(xy 422.930555 -116.550942) (xy 422.978131 -116.514436) (xy 423.030065 -116.484452) (xy 423.085469 -116.461503)
			(xy 423.143394 -116.445982) (xy 423.20285 -116.438154) (xy 423.262818 -116.438154) (xy 423.322274 -116.445982)
			(xy 423.380199 -116.461503) (xy 423.435603 -116.484452) (xy 423.487537 -116.514436) (xy 423.535113 -116.550942)
			(xy 423.577518 -116.593347) (xy 423.614024 -116.640923) (xy 423.644008 -116.692857) (xy 423.666957 -116.748261)
			(xy 423.682478 -116.806186) (xy 423.690306 -116.865642) (xy 423.690796 -116.895626) (xy 423.690796 -117.759226)
			(xy 423.690306 -117.78921) (xy 423.682478 -117.848666) (xy 423.666957 -117.906591) (xy 423.644008 -117.961995)
			(xy 423.614024 -118.013929) (xy 423.577518 -118.061505) (xy 423.535113 -118.10391) (xy 423.487537 -118.140416)
			(xy 423.435603 -118.1704) (xy 423.380199 -118.193349) (xy 423.322274 -118.20887) (xy 423.262818 -118.216698)
			(xy 423.20285 -118.216698) (xy 423.143394 -118.20887) (xy 423.085469 -118.193349) (xy 423.030065 -118.1704)
			(xy 422.978131 -118.140416) (xy 422.930555 -118.10391) (xy 422.88815 -118.061505) (xy 422.851644 -118.013929)
			(xy 422.82166 -117.961995) (xy 422.798711 -117.906591) (xy 422.78319 -117.848666) (xy 422.775362 -117.78921)
			(xy 422.774872 -117.759226) (xy 307.590436 -117.759226) (xy 307.589954 -117.788686) (xy 307.582131 -117.848108)
			(xy 307.566618 -117.906001) (xy 307.543682 -117.961374) (xy 307.513715 -118.01328) (xy 307.477228 -118.06083)
			(xy 307.434848 -118.10321) (xy 307.387298 -118.139697) (xy 307.335392 -118.169664) (xy 307.280019 -118.1926)
			(xy 307.222126 -118.208113) (xy 307.162704 -118.215936) (xy 307.102768 -118.215936) (xy 307.043346 -118.208113)
			(xy 306.985453 -118.1926) (xy 306.93008 -118.169664) (xy 306.878174 -118.139697) (xy 306.830624 -118.10321)
			(xy 306.788244 -118.06083) (xy 306.751757 -118.01328) (xy 306.72179 -117.961374) (xy 306.698854 -117.906001)
			(xy 306.683341 -117.848108) (xy 306.675518 -117.788686) (xy 306.675028 -117.758718) (xy 191.4906 -117.758718)
			(xy 191.49011 -117.788702) (xy 191.482282 -117.848158) (xy 191.466761 -117.906083) (xy 191.443812 -117.961487)
			(xy 191.413828 -118.013421) (xy 191.377322 -118.060997) (xy 191.334917 -118.103402) (xy 191.287341 -118.139908)
			(xy 191.235407 -118.169892) (xy 191.180003 -118.192841) (xy 191.122078 -118.208362) (xy 191.062622 -118.21619)
			(xy 191.002654 -118.21619) (xy 190.943198 -118.208362) (xy 190.885273 -118.192841) (xy 190.829869 -118.169892)
			(xy 190.777935 -118.139908) (xy 190.730359 -118.103402) (xy 190.687954 -118.060997) (xy 190.651448 -118.013421)
			(xy 190.621464 -117.961487) (xy 190.598515 -117.906083) (xy 190.582994 -117.848158) (xy 190.575166 -117.788702)
			(xy 190.574676 -117.758718) (xy 75.390756 -117.758718) (xy 75.390266 -117.788702) (xy 75.382438 -117.848158)
			(xy 75.366917 -117.906083) (xy 75.343968 -117.961487) (xy 75.313984 -118.013421) (xy 75.277478 -118.060997)
			(xy 75.235073 -118.103402) (xy 75.187497 -118.139908) (xy 75.135563 -118.169892) (xy 75.080159 -118.192841)
			(xy 75.022234 -118.208362) (xy 74.962778 -118.21619) (xy 74.90281 -118.21619) (xy 74.843354 -118.208362)
			(xy 74.785429 -118.192841) (xy 74.730025 -118.169892) (xy 74.678091 -118.139908) (xy 74.630515 -118.103402)
			(xy 74.58811 -118.060997) (xy 74.551604 -118.013421) (xy 74.52162 -117.961487) (xy 74.498671 -117.906083)
			(xy 74.48315 -117.848158) (xy 74.475322 -117.788702) (xy 74.474832 -117.758718) (xy 4.30911 -117.758718)
			(xy 4.30911 -120.087898) (xy 34.667952 -120.087898) (xy 34.667952 -119.224298) (xy 34.668442 -119.19433)
			(xy 34.676265 -119.134908) (xy 34.691778 -119.077015) (xy 34.714714 -119.021642) (xy 34.744681 -118.969736)
			(xy 34.781168 -118.922186) (xy 34.823548 -118.879806) (xy 34.871098 -118.843319) (xy 34.923004 -118.813352)
			(xy 34.978377 -118.790416) (xy 35.03627 -118.774903) (xy 35.095692 -118.76708) (xy 35.155628 -118.76708)
			(xy 35.21505 -118.774903) (xy 35.272943 -118.790416) (xy 35.328316 -118.813352) (xy 35.380222 -118.843319)
			(xy 35.427772 -118.879806) (xy 35.470152 -118.922186) (xy 35.506639 -118.969736) (xy 35.536606 -119.021642)
			(xy 35.559542 -119.077015) (xy 35.575055 -119.134908) (xy 35.582878 -119.19433) (xy 35.583368 -119.224298)
			(xy 35.583368 -120.086374) (xy 53.639212 -120.086374) (xy 53.639212 -119.222774) (xy 53.639702 -119.192806)
			(xy 53.647525 -119.133384) (xy 53.663038 -119.075491) (xy 53.685974 -119.020118) (xy 53.715941 -118.968212)
			(xy 53.752428 -118.920662) (xy 53.794808 -118.878282) (xy 53.842358 -118.841795) (xy 53.894264 -118.811828)
			(xy 53.949637 -118.788892) (xy 54.00753 -118.773379) (xy 54.066952 -118.765556) (xy 54.126888 -118.765556)
			(xy 54.18631 -118.773379) (xy 54.244203 -118.788892) (xy 54.299576 -118.811828) (xy 54.351482 -118.841795)
			(xy 54.399032 -118.878282) (xy 54.441412 -118.920662) (xy 54.477899 -118.968212) (xy 54.507866 -119.020118)
			(xy 54.530802 -119.075491) (xy 54.546315 -119.133384) (xy 54.554138 -119.192806) (xy 54.554628 -119.222774)
			(xy 54.554628 -119.567198) (xy 66.599308 -119.567198) (xy 66.599308 -118.703598) (xy 66.599798 -118.673614)
			(xy 66.607626 -118.614158) (xy 66.623147 -118.556233) (xy 66.646096 -118.500829) (xy 66.67608 -118.448895)
			(xy 66.712586 -118.401319) (xy 66.754991 -118.358914) (xy 66.802567 -118.322408) (xy 66.854501 -118.292424)
			(xy 66.909905 -118.269475) (xy 66.96783 -118.253954) (xy 67.027286 -118.246126) (xy 67.087254 -118.246126)
			(xy 67.14671 -118.253954) (xy 67.204635 -118.269475) (xy 67.260039 -118.292424) (xy 67.311973 -118.322408)
			(xy 67.359549 -118.358914) (xy 67.401954 -118.401319) (xy 67.43846 -118.448895) (xy 67.468444 -118.500829)
			(xy 67.491393 -118.556233) (xy 67.506914 -118.614158) (xy 67.514742 -118.673614) (xy 67.515232 -118.703598)
			(xy 67.515232 -119.55907) (xy 81.07426 -119.55907) (xy 81.07426 -118.69547) (xy 81.07475 -118.665486)
			(xy 81.082578 -118.60603) (xy 81.098099 -118.548105) (xy 81.121048 -118.492701) (xy 81.151032 -118.440767)
			(xy 81.187538 -118.393191) (xy 81.229943 -118.350786) (xy 81.277519 -118.31428) (xy 81.329453 -118.284296)
			(xy 81.384857 -118.261347) (xy 81.442782 -118.245826) (xy 81.502238 -118.237998) (xy 81.562206 -118.237998)
			(xy 81.621662 -118.245826) (xy 81.679587 -118.261347) (xy 81.734991 -118.284296) (xy 81.786925 -118.31428)
			(xy 81.834501 -118.350786) (xy 81.876906 -118.393191) (xy 81.913412 -118.440767) (xy 81.943396 -118.492701)
			(xy 81.966345 -118.548105) (xy 81.981866 -118.60603) (xy 81.989694 -118.665486) (xy 81.990184 -118.69547)
			(xy 81.990184 -119.55907) (xy 81.989694 -119.589054) (xy 81.981866 -119.64851) (xy 81.966345 -119.706435)
			(xy 81.943396 -119.761839) (xy 81.913412 -119.813773) (xy 81.876906 -119.861349) (xy 81.834501 -119.903754)
			(xy 81.786925 -119.94026) (xy 81.734991 -119.970244) (xy 81.679587 -119.993193) (xy 81.621662 -120.008714)
			(xy 81.562206 -120.016542) (xy 81.502238 -120.016542) (xy 81.442782 -120.008714) (xy 81.384857 -119.993193)
			(xy 81.329453 -119.970244) (xy 81.277519 -119.94026) (xy 81.229943 -119.903754) (xy 81.187538 -119.861349)
			(xy 81.151032 -119.813773) (xy 81.121048 -119.761839) (xy 81.098099 -119.706435) (xy 81.082578 -119.64851)
			(xy 81.07475 -119.589054) (xy 81.07426 -119.55907) (xy 67.515232 -119.55907) (xy 67.515232 -119.567198)
			(xy 67.514742 -119.597182) (xy 67.506914 -119.656638) (xy 67.491393 -119.714563) (xy 67.468444 -119.769967)
			(xy 67.43846 -119.821901) (xy 67.401954 -119.869477) (xy 67.359549 -119.911882) (xy 67.311973 -119.948388)
			(xy 67.260039 -119.978372) (xy 67.204635 -120.001321) (xy 67.14671 -120.016842) (xy 67.087254 -120.02467)
			(xy 67.027286 -120.02467) (xy 66.96783 -120.016842) (xy 66.909905 -120.001321) (xy 66.854501 -119.978372)
			(xy 66.802567 -119.948388) (xy 66.754991 -119.911882) (xy 66.712586 -119.869477) (xy 66.67608 -119.821901)
			(xy 66.646096 -119.769967) (xy 66.623147 -119.714563) (xy 66.607626 -119.656638) (xy 66.599798 -119.597182)
			(xy 66.599308 -119.567198) (xy 54.554628 -119.567198) (xy 54.554628 -120.086374) (xy 54.554138 -120.116342)
			(xy 54.546315 -120.175764) (xy 54.530802 -120.233657) (xy 54.507866 -120.28903) (xy 54.477899 -120.340936)
			(xy 54.441412 -120.388486) (xy 54.399032 -120.430866) (xy 54.351482 -120.467353) (xy 54.299576 -120.49732)
			(xy 54.244203 -120.520256) (xy 54.18631 -120.535769) (xy 54.126888 -120.543592) (xy 54.066952 -120.543592)
			(xy 54.00753 -120.535769) (xy 53.949637 -120.520256) (xy 53.894264 -120.49732) (xy 53.842358 -120.467353)
			(xy 53.794808 -120.430866) (xy 53.752428 -120.388486) (xy 53.715941 -120.340936) (xy 53.685974 -120.28903)
			(xy 53.663038 -120.233657) (xy 53.647525 -120.175764) (xy 53.639702 -120.116342) (xy 53.639212 -120.086374)
			(xy 35.583368 -120.086374) (xy 35.583368 -120.087898) (xy 35.582878 -120.117866) (xy 35.575055 -120.177288)
			(xy 35.559542 -120.235181) (xy 35.536606 -120.290554) (xy 35.506639 -120.34246) (xy 35.470152 -120.39001)
			(xy 35.427772 -120.43239) (xy 35.380222 -120.468877) (xy 35.328316 -120.498844) (xy 35.272943 -120.52178)
			(xy 35.21505 -120.537293) (xy 35.155628 -120.545116) (xy 35.095692 -120.545116) (xy 35.03627 -120.537293)
			(xy 34.978377 -120.52178) (xy 34.923004 -120.498844) (xy 34.871098 -120.468877) (xy 34.823548 -120.43239)
			(xy 34.781168 -120.39001) (xy 34.744681 -120.34246) (xy 34.714714 -120.290554) (xy 34.691778 -120.235181)
			(xy 34.676265 -120.177288) (xy 34.668442 -120.117866) (xy 34.667952 -120.087898) (xy 4.30911 -120.087898)
			(xy 4.30911 -121.894346) (xy 37.31006 -121.894346) (xy 37.31006 -121.030746) (xy 37.31055 -121.000778)
			(xy 37.318373 -120.941356) (xy 37.333886 -120.883463) (xy 37.356822 -120.82809) (xy 37.386789 -120.776184)
			(xy 37.423276 -120.728634) (xy 37.465656 -120.686254) (xy 37.513206 -120.649767) (xy 37.565112 -120.6198)
			(xy 37.620485 -120.596864) (xy 37.678378 -120.581351) (xy 37.7378 -120.573528) (xy 37.797736 -120.573528)
			(xy 37.857158 -120.581351) (xy 37.915051 -120.596864) (xy 37.970424 -120.6198) (xy 38.02233 -120.649767)
			(xy 38.06988 -120.686254) (xy 38.11226 -120.728634) (xy 38.148747 -120.776184) (xy 38.178714 -120.82809)
			(xy 38.20165 -120.883463) (xy 38.217163 -120.941356) (xy 38.224986 -121.000778) (xy 38.225476 -121.030746)
			(xy 38.225476 -121.886472) (xy 51.785012 -121.886472) (xy 51.785012 -121.022872) (xy 51.785502 -120.992904)
			(xy 51.793325 -120.933482) (xy 51.808838 -120.875589) (xy 51.831774 -120.820216) (xy 51.861741 -120.76831)
			(xy 51.898228 -120.72076) (xy 51.940608 -120.67838) (xy 51.988158 -120.641893) (xy 52.040064 -120.611926)
			(xy 52.095437 -120.58899) (xy 52.15333 -120.573477) (xy 52.212752 -120.565654) (xy 52.272688 -120.565654)
			(xy 52.33211 -120.573477) (xy 52.390003 -120.58899) (xy 52.445376 -120.611926) (xy 52.497282 -120.641893)
			(xy 52.544832 -120.67838) (xy 52.587212 -120.72076) (xy 52.623699 -120.76831) (xy 52.653666 -120.820216)
			(xy 52.676602 -120.875589) (xy 52.692115 -120.933482) (xy 52.699938 -120.992904) (xy 52.700428 -121.022872)
			(xy 52.700428 -121.367296) (xy 64.745108 -121.367296) (xy 64.745108 -120.503696) (xy 64.745598 -120.473712)
			(xy 64.753426 -120.414256) (xy 64.768947 -120.356331) (xy 64.791896 -120.300927) (xy 64.82188 -120.248993)
			(xy 64.858386 -120.201417) (xy 64.900791 -120.159012) (xy 64.948367 -120.122506) (xy 65.000301 -120.092522)
			(xy 65.055705 -120.069573) (xy 65.11363 -120.054052) (xy 65.173086 -120.046224) (xy 65.233054 -120.046224)
			(xy 65.29251 -120.054052) (xy 65.350435 -120.069573) (xy 65.405839 -120.092522) (xy 65.457773 -120.122506)
			(xy 65.505349 -120.159012) (xy 65.547754 -120.201417) (xy 65.58426 -120.248993) (xy 65.614244 -120.300927)
			(xy 65.637193 -120.356331) (xy 65.652714 -120.414256) (xy 65.660542 -120.473712) (xy 65.661032 -120.503696)
			(xy 65.661032 -121.365772) (xy 83.716368 -121.365772) (xy 83.716368 -120.502172) (xy 83.716858 -120.472188)
			(xy 83.724686 -120.412732) (xy 83.740207 -120.354807) (xy 83.763156 -120.299403) (xy 83.79314 -120.247469)
			(xy 83.829646 -120.199893) (xy 83.872051 -120.157488) (xy 83.919627 -120.120982) (xy 83.971561 -120.090998)
			(xy 84.026965 -120.068049) (xy 84.08489 -120.052528) (xy 84.144346 -120.0447) (xy 84.204314 -120.0447)
			(xy 84.26377 -120.052528) (xy 84.321695 -120.068049) (xy 84.369615 -120.087898) (xy 150.767796 -120.087898)
			(xy 150.767796 -119.224298) (xy 150.768286 -119.194314) (xy 150.776114 -119.134858) (xy 150.791635 -119.076933)
			(xy 150.814584 -119.021529) (xy 150.844568 -118.969595) (xy 150.881074 -118.922019) (xy 150.923479 -118.879614)
			(xy 150.971055 -118.843108) (xy 151.022989 -118.813124) (xy 151.078393 -118.790175) (xy 151.136318 -118.774654)
			(xy 151.195774 -118.766826) (xy 151.255742 -118.766826) (xy 151.315198 -118.774654) (xy 151.373123 -118.790175)
			(xy 151.428527 -118.813124) (xy 151.480461 -118.843108) (xy 151.528037 -118.879614) (xy 151.570442 -118.922019)
			(xy 151.606948 -118.969595) (xy 151.636932 -119.021529) (xy 151.659881 -119.076933) (xy 151.675402 -119.134858)
			(xy 151.68323 -119.194314) (xy 151.68372 -119.224298) (xy 151.68372 -120.086374) (xy 169.739056 -120.086374)
			(xy 169.739056 -119.222774) (xy 169.739546 -119.19279) (xy 169.747374 -119.133334) (xy 169.762895 -119.075409)
			(xy 169.785844 -119.020005) (xy 169.815828 -118.968071) (xy 169.852334 -118.920495) (xy 169.894739 -118.87809)
			(xy 169.942315 -118.841584) (xy 169.994249 -118.8116) (xy 170.049653 -118.788651) (xy 170.107578 -118.77313)
			(xy 170.167034 -118.765302) (xy 170.227002 -118.765302) (xy 170.286458 -118.77313) (xy 170.344383 -118.788651)
			(xy 170.399787 -118.8116) (xy 170.451721 -118.841584) (xy 170.499297 -118.87809) (xy 170.541702 -118.920495)
			(xy 170.578208 -118.968071) (xy 170.608192 -119.020005) (xy 170.631141 -119.075409) (xy 170.646662 -119.133334)
			(xy 170.65449 -119.19279) (xy 170.65498 -119.222774) (xy 170.65498 -119.567198) (xy 182.69966 -119.567198)
			(xy 182.69966 -118.703598) (xy 182.70015 -118.67363) (xy 182.707973 -118.614208) (xy 182.723486 -118.556315)
			(xy 182.746422 -118.500942) (xy 182.776389 -118.449036) (xy 182.812876 -118.401486) (xy 182.855256 -118.359106)
			(xy 182.902806 -118.322619) (xy 182.954712 -118.292652) (xy 183.010085 -118.269716) (xy 183.067978 -118.254203)
			(xy 183.1274 -118.24638) (xy 183.187336 -118.24638) (xy 183.246758 -118.254203) (xy 183.304651 -118.269716)
			(xy 183.360024 -118.292652) (xy 183.41193 -118.322619) (xy 183.45948 -118.359106) (xy 183.50186 -118.401486)
			(xy 183.538347 -118.449036) (xy 183.568314 -118.500942) (xy 183.59125 -118.556315) (xy 183.606763 -118.614208)
			(xy 183.614586 -118.67363) (xy 183.615076 -118.703598) (xy 183.615076 -119.559324) (xy 197.174612 -119.559324)
			(xy 197.174612 -118.695724) (xy 197.175102 -118.665756) (xy 197.182925 -118.606334) (xy 197.198438 -118.548441)
			(xy 197.221374 -118.493068) (xy 197.251341 -118.441162) (xy 197.287828 -118.393612) (xy 197.330208 -118.351232)
			(xy 197.377758 -118.314745) (xy 197.429664 -118.284778) (xy 197.485037 -118.261842) (xy 197.54293 -118.246329)
			(xy 197.602352 -118.238506) (xy 197.662288 -118.238506) (xy 197.72171 -118.246329) (xy 197.779603 -118.261842)
			(xy 197.834976 -118.284778) (xy 197.886882 -118.314745) (xy 197.934432 -118.351232) (xy 197.976812 -118.393612)
			(xy 198.013299 -118.441162) (xy 198.043266 -118.493068) (xy 198.066202 -118.548441) (xy 198.081715 -118.606334)
			(xy 198.089538 -118.665756) (xy 198.090028 -118.695724) (xy 198.090028 -119.559324) (xy 198.089538 -119.589292)
			(xy 198.081715 -119.648714) (xy 198.066202 -119.706607) (xy 198.043266 -119.76198) (xy 198.013299 -119.813886)
			(xy 197.976812 -119.861436) (xy 197.934432 -119.903816) (xy 197.886882 -119.940303) (xy 197.834976 -119.97027)
			(xy 197.779603 -119.993206) (xy 197.72171 -120.008719) (xy 197.662288 -120.016542) (xy 197.602352 -120.016542)
			(xy 197.54293 -120.008719) (xy 197.485037 -119.993206) (xy 197.429664 -119.97027) (xy 197.377758 -119.940303)
			(xy 197.330208 -119.903816) (xy 197.287828 -119.861436) (xy 197.251341 -119.813886) (xy 197.221374 -119.76198)
			(xy 197.198438 -119.706607) (xy 197.182925 -119.648714) (xy 197.175102 -119.589292) (xy 197.174612 -119.559324)
			(xy 183.615076 -119.559324) (xy 183.615076 -119.567198) (xy 183.614586 -119.597166) (xy 183.606763 -119.656588)
			(xy 183.59125 -119.714481) (xy 183.568314 -119.769854) (xy 183.538347 -119.82176) (xy 183.50186 -119.86931)
			(xy 183.45948 -119.91169) (xy 183.41193 -119.948177) (xy 183.360024 -119.978144) (xy 183.304651 -120.00108)
			(xy 183.246758 -120.016593) (xy 183.187336 -120.024416) (xy 183.1274 -120.024416) (xy 183.067978 -120.016593)
			(xy 183.010085 -120.00108) (xy 182.954712 -119.978144) (xy 182.902806 -119.948177) (xy 182.855256 -119.91169)
			(xy 182.812876 -119.86931) (xy 182.776389 -119.82176) (xy 182.746422 -119.769854) (xy 182.723486 -119.714481)
			(xy 182.707973 -119.656588) (xy 182.70015 -119.597166) (xy 182.69966 -119.567198) (xy 170.65498 -119.567198)
			(xy 170.65498 -120.086374) (xy 170.65449 -120.116358) (xy 170.646662 -120.175814) (xy 170.631141 -120.233739)
			(xy 170.608192 -120.289143) (xy 170.578208 -120.341077) (xy 170.541702 -120.388653) (xy 170.499297 -120.431058)
			(xy 170.451721 -120.467564) (xy 170.399787 -120.497548) (xy 170.344383 -120.520497) (xy 170.286458 -120.536018)
			(xy 170.227002 -120.543846) (xy 170.167034 -120.543846) (xy 170.107578 -120.536018) (xy 170.049653 -120.520497)
			(xy 169.994249 -120.497548) (xy 169.942315 -120.467564) (xy 169.894739 -120.431058) (xy 169.852334 -120.388653)
			(xy 169.815828 -120.341077) (xy 169.785844 -120.289143) (xy 169.762895 -120.233739) (xy 169.747374 -120.175814)
			(xy 169.739546 -120.116358) (xy 169.739056 -120.086374) (xy 151.68372 -120.086374) (xy 151.68372 -120.087898)
			(xy 151.68323 -120.117882) (xy 151.675402 -120.177338) (xy 151.659881 -120.235263) (xy 151.636932 -120.290667)
			(xy 151.606948 -120.342601) (xy 151.570442 -120.390177) (xy 151.528037 -120.432582) (xy 151.480461 -120.469088)
			(xy 151.428527 -120.499072) (xy 151.373123 -120.522021) (xy 151.315198 -120.537542) (xy 151.255742 -120.54537)
			(xy 151.195774 -120.54537) (xy 151.136318 -120.537542) (xy 151.078393 -120.522021) (xy 151.022989 -120.499072)
			(xy 150.971055 -120.469088) (xy 150.923479 -120.432582) (xy 150.881074 -120.390177) (xy 150.844568 -120.342601)
			(xy 150.814584 -120.290667) (xy 150.791635 -120.235263) (xy 150.776114 -120.177338) (xy 150.768286 -120.117882)
			(xy 150.767796 -120.087898) (xy 84.369615 -120.087898) (xy 84.377099 -120.090998) (xy 84.429033 -120.120982)
			(xy 84.476609 -120.157488) (xy 84.519014 -120.199893) (xy 84.55552 -120.247469) (xy 84.585504 -120.299403)
			(xy 84.608453 -120.354807) (xy 84.623974 -120.412732) (xy 84.631802 -120.472188) (xy 84.632292 -120.502172)
			(xy 84.632292 -121.365772) (xy 84.631802 -121.395756) (xy 84.623974 -121.455212) (xy 84.608453 -121.513137)
			(xy 84.585504 -121.568541) (xy 84.55552 -121.620475) (xy 84.519014 -121.668051) (xy 84.476609 -121.710456)
			(xy 84.429033 -121.746962) (xy 84.377099 -121.776946) (xy 84.321695 -121.799895) (xy 84.26377 -121.815416)
			(xy 84.204314 -121.823244) (xy 84.144346 -121.823244) (xy 84.08489 -121.815416) (xy 84.026965 -121.799895)
			(xy 83.971561 -121.776946) (xy 83.919627 -121.746962) (xy 83.872051 -121.710456) (xy 83.829646 -121.668051)
			(xy 83.79314 -121.620475) (xy 83.763156 -121.568541) (xy 83.740207 -121.513137) (xy 83.724686 -121.455212)
			(xy 83.716858 -121.395756) (xy 83.716368 -121.365772) (xy 65.661032 -121.365772) (xy 65.661032 -121.367296)
			(xy 65.660542 -121.39728) (xy 65.652714 -121.456736) (xy 65.637193 -121.514661) (xy 65.614244 -121.570065)
			(xy 65.58426 -121.621999) (xy 65.547754 -121.669575) (xy 65.505349 -121.71198) (xy 65.457773 -121.748486)
			(xy 65.405839 -121.77847) (xy 65.350435 -121.801419) (xy 65.29251 -121.81694) (xy 65.233054 -121.824768)
			(xy 65.173086 -121.824768) (xy 65.11363 -121.81694) (xy 65.055705 -121.801419) (xy 65.000301 -121.77847)
			(xy 64.948367 -121.748486) (xy 64.900791 -121.71198) (xy 64.858386 -121.669575) (xy 64.82188 -121.621999)
			(xy 64.791896 -121.570065) (xy 64.768947 -121.514661) (xy 64.753426 -121.456736) (xy 64.745598 -121.39728)
			(xy 64.745108 -121.367296) (xy 52.700428 -121.367296) (xy 52.700428 -121.886472) (xy 52.699938 -121.91644)
			(xy 52.692115 -121.975862) (xy 52.676602 -122.033755) (xy 52.653666 -122.089128) (xy 52.623699 -122.141034)
			(xy 52.587212 -122.188584) (xy 52.544832 -122.230964) (xy 52.497282 -122.267451) (xy 52.445376 -122.297418)
			(xy 52.390003 -122.320354) (xy 52.33211 -122.335867) (xy 52.272688 -122.34369) (xy 52.212752 -122.34369)
			(xy 52.15333 -122.335867) (xy 52.095437 -122.320354) (xy 52.040064 -122.297418) (xy 51.988158 -122.267451)
			(xy 51.940608 -122.230964) (xy 51.898228 -122.188584) (xy 51.861741 -122.141034) (xy 51.831774 -122.089128)
			(xy 51.808838 -122.033755) (xy 51.793325 -121.975862) (xy 51.785502 -121.91644) (xy 51.785012 -121.886472)
			(xy 38.225476 -121.886472) (xy 38.225476 -121.894346) (xy 38.224986 -121.924314) (xy 38.217163 -121.983736)
			(xy 38.20165 -122.041629) (xy 38.178714 -122.097002) (xy 38.148747 -122.148908) (xy 38.11226 -122.196458)
			(xy 38.06988 -122.238838) (xy 38.02233 -122.275325) (xy 37.970424 -122.305292) (xy 37.915051 -122.328228)
			(xy 37.857158 -122.343741) (xy 37.797736 -122.351564) (xy 37.7378 -122.351564) (xy 37.678378 -122.343741)
			(xy 37.620485 -122.328228) (xy 37.565112 -122.305292) (xy 37.513206 -122.275325) (xy 37.465656 -122.238838)
			(xy 37.423276 -122.196458) (xy 37.386789 -122.148908) (xy 37.356822 -122.097002) (xy 37.333886 -122.041629)
			(xy 37.318373 -121.983736) (xy 37.31055 -121.924314) (xy 37.31006 -121.894346) (xy 4.30911 -121.894346)
			(xy 4.30911 -123.68784) (xy 34.667952 -123.68784) (xy 34.667952 -122.82424) (xy 34.668442 -122.794272)
			(xy 34.676265 -122.73485) (xy 34.691778 -122.676957) (xy 34.714714 -122.621584) (xy 34.744681 -122.569678)
			(xy 34.781168 -122.522128) (xy 34.823548 -122.479748) (xy 34.871098 -122.443261) (xy 34.923004 -122.413294)
			(xy 34.978377 -122.390358) (xy 35.03627 -122.374845) (xy 35.095692 -122.367022) (xy 35.155628 -122.367022)
			(xy 35.21505 -122.374845) (xy 35.272943 -122.390358) (xy 35.328316 -122.413294) (xy 35.380222 -122.443261)
			(xy 35.427772 -122.479748) (xy 35.470152 -122.522128) (xy 35.506639 -122.569678) (xy 35.536606 -122.621584)
			(xy 35.559542 -122.676957) (xy 35.575055 -122.73485) (xy 35.582878 -122.794272) (xy 35.583368 -122.82424)
			(xy 35.583368 -123.686316) (xy 53.639212 -123.686316) (xy 53.639212 -122.822716) (xy 53.639702 -122.792748)
			(xy 53.647525 -122.733326) (xy 53.663038 -122.675433) (xy 53.685974 -122.62006) (xy 53.715941 -122.568154)
			(xy 53.752428 -122.520604) (xy 53.794808 -122.478224) (xy 53.842358 -122.441737) (xy 53.894264 -122.41177)
			(xy 53.949637 -122.388834) (xy 54.00753 -122.373321) (xy 54.066952 -122.365498) (xy 54.126888 -122.365498)
			(xy 54.18631 -122.373321) (xy 54.244203 -122.388834) (xy 54.299576 -122.41177) (xy 54.351482 -122.441737)
			(xy 54.399032 -122.478224) (xy 54.441412 -122.520604) (xy 54.477899 -122.568154) (xy 54.507866 -122.62006)
			(xy 54.530802 -122.675433) (xy 54.546315 -122.733326) (xy 54.554138 -122.792748) (xy 54.554628 -122.822716)
			(xy 54.554628 -123.16714) (xy 66.599308 -123.16714) (xy 66.599308 -122.30354) (xy 66.599798 -122.273556)
			(xy 66.607626 -122.2141) (xy 66.623147 -122.156175) (xy 66.646096 -122.100771) (xy 66.67608 -122.048837)
			(xy 66.712586 -122.001261) (xy 66.754991 -121.958856) (xy 66.802567 -121.92235) (xy 66.854501 -121.892366)
			(xy 66.909905 -121.869417) (xy 66.96783 -121.853896) (xy 67.027286 -121.846068) (xy 67.087254 -121.846068)
			(xy 67.14671 -121.853896) (xy 67.204635 -121.869417) (xy 67.260039 -121.892366) (xy 67.311973 -121.92235)
			(xy 67.359549 -121.958856) (xy 67.401954 -122.001261) (xy 67.43846 -122.048837) (xy 67.468444 -122.100771)
			(xy 67.491393 -122.156175) (xy 67.506914 -122.2141) (xy 67.514742 -122.273556) (xy 67.515232 -122.30354)
			(xy 67.515232 -123.159266) (xy 81.07426 -123.159266) (xy 81.07426 -122.295666) (xy 81.07475 -122.265682)
			(xy 81.082578 -122.206226) (xy 81.098099 -122.148301) (xy 81.121048 -122.092897) (xy 81.151032 -122.040963)
			(xy 81.187538 -121.993387) (xy 81.229943 -121.950982) (xy 81.277519 -121.914476) (xy 81.329453 -121.884492)
			(xy 81.384857 -121.861543) (xy 81.442782 -121.846022) (xy 81.502238 -121.838194) (xy 81.562206 -121.838194)
			(xy 81.621662 -121.846022) (xy 81.679587 -121.861543) (xy 81.734991 -121.884492) (xy 81.752059 -121.894346)
			(xy 153.409904 -121.894346) (xy 153.409904 -121.030746) (xy 153.410394 -121.000762) (xy 153.418222 -120.941306)
			(xy 153.433743 -120.883381) (xy 153.456692 -120.827977) (xy 153.486676 -120.776043) (xy 153.523182 -120.728467)
			(xy 153.565587 -120.686062) (xy 153.613163 -120.649556) (xy 153.665097 -120.619572) (xy 153.720501 -120.596623)
			(xy 153.778426 -120.581102) (xy 153.837882 -120.573274) (xy 153.89785 -120.573274) (xy 153.957306 -120.581102)
			(xy 154.015231 -120.596623) (xy 154.070635 -120.619572) (xy 154.122569 -120.649556) (xy 154.170145 -120.686062)
			(xy 154.21255 -120.728467) (xy 154.249056 -120.776043) (xy 154.27904 -120.827977) (xy 154.301989 -120.883381)
			(xy 154.31751 -120.941306) (xy 154.325338 -121.000762) (xy 154.325828 -121.030746) (xy 154.325828 -121.886472)
			(xy 167.884856 -121.886472) (xy 167.884856 -121.022872) (xy 167.885346 -120.992888) (xy 167.893174 -120.933432)
			(xy 167.908695 -120.875507) (xy 167.931644 -120.820103) (xy 167.961628 -120.768169) (xy 167.998134 -120.720593)
			(xy 168.040539 -120.678188) (xy 168.088115 -120.641682) (xy 168.140049 -120.611698) (xy 168.195453 -120.588749)
			(xy 168.253378 -120.573228) (xy 168.312834 -120.5654) (xy 168.372802 -120.5654) (xy 168.432258 -120.573228)
			(xy 168.490183 -120.588749) (xy 168.545587 -120.611698) (xy 168.597521 -120.641682) (xy 168.645097 -120.678188)
			(xy 168.687502 -120.720593) (xy 168.724008 -120.768169) (xy 168.753992 -120.820103) (xy 168.776941 -120.875507)
			(xy 168.792462 -120.933432) (xy 168.80029 -120.992888) (xy 168.80078 -121.022872) (xy 168.80078 -121.367296)
			(xy 180.84546 -121.367296) (xy 180.84546 -120.503696) (xy 180.84595 -120.473728) (xy 180.853773 -120.414306)
			(xy 180.869286 -120.356413) (xy 180.892222 -120.30104) (xy 180.922189 -120.249134) (xy 180.958676 -120.201584)
			(xy 181.001056 -120.159204) (xy 181.048606 -120.122717) (xy 181.100512 -120.09275) (xy 181.155885 -120.069814)
			(xy 181.213778 -120.054301) (xy 181.2732 -120.046478) (xy 181.333136 -120.046478) (xy 181.392558 -120.054301)
			(xy 181.450451 -120.069814) (xy 181.505824 -120.09275) (xy 181.55773 -120.122717) (xy 181.60528 -120.159204)
			(xy 181.64766 -120.201584) (xy 181.684147 -120.249134) (xy 181.714114 -120.30104) (xy 181.73705 -120.356413)
			(xy 181.752563 -120.414306) (xy 181.760386 -120.473728) (xy 181.760876 -120.503696) (xy 181.760876 -121.365772)
			(xy 199.81672 -121.365772) (xy 199.81672 -120.502172) (xy 199.81721 -120.472204) (xy 199.825033 -120.412782)
			(xy 199.840546 -120.354889) (xy 199.863482 -120.299516) (xy 199.893449 -120.24761) (xy 199.929936 -120.20006)
			(xy 199.972316 -120.15768) (xy 200.019866 -120.121193) (xy 200.071772 -120.091226) (xy 200.127145 -120.06829)
			(xy 200.185038 -120.052777) (xy 200.24446 -120.044954) (xy 200.304396 -120.044954) (xy 200.363818 -120.052777)
			(xy 200.421711 -120.06829) (xy 200.469049 -120.087898) (xy 266.86764 -120.087898) (xy 266.86764 -119.224298)
			(xy 266.86813 -119.194314) (xy 266.875958 -119.134858) (xy 266.891479 -119.076933) (xy 266.914428 -119.021529)
			(xy 266.944412 -118.969595) (xy 266.980918 -118.922019) (xy 267.023323 -118.879614) (xy 267.070899 -118.843108)
			(xy 267.122833 -118.813124) (xy 267.178237 -118.790175) (xy 267.236162 -118.774654) (xy 267.295618 -118.766826)
			(xy 267.355586 -118.766826) (xy 267.415042 -118.774654) (xy 267.472967 -118.790175) (xy 267.528371 -118.813124)
			(xy 267.580305 -118.843108) (xy 267.627881 -118.879614) (xy 267.670286 -118.922019) (xy 267.706792 -118.969595)
			(xy 267.736776 -119.021529) (xy 267.759725 -119.076933) (xy 267.775246 -119.134858) (xy 267.783074 -119.194314)
			(xy 267.783564 -119.224298) (xy 267.783564 -120.086374) (xy 285.8389 -120.086374) (xy 285.8389 -119.222774)
			(xy 285.83939 -119.19279) (xy 285.847218 -119.133334) (xy 285.862739 -119.075409) (xy 285.885688 -119.020005)
			(xy 285.915672 -118.968071) (xy 285.952178 -118.920495) (xy 285.994583 -118.87809) (xy 286.042159 -118.841584)
			(xy 286.094093 -118.8116) (xy 286.149497 -118.788651) (xy 286.207422 -118.77313) (xy 286.266878 -118.765302)
			(xy 286.326846 -118.765302) (xy 286.386302 -118.77313) (xy 286.444227 -118.788651) (xy 286.499631 -118.8116)
			(xy 286.551565 -118.841584) (xy 286.599141 -118.87809) (xy 286.641546 -118.920495) (xy 286.678052 -118.968071)
			(xy 286.708036 -119.020005) (xy 286.730985 -119.075409) (xy 286.746506 -119.133334) (xy 286.754334 -119.19279)
			(xy 286.754824 -119.222774) (xy 286.754824 -119.567198) (xy 298.799504 -119.567198) (xy 298.799504 -118.703598)
			(xy 298.799994 -118.67363) (xy 298.807817 -118.614208) (xy 298.82333 -118.556315) (xy 298.846266 -118.500942)
			(xy 298.876233 -118.449036) (xy 298.91272 -118.401486) (xy 298.9551 -118.359106) (xy 299.00265 -118.322619)
			(xy 299.054556 -118.292652) (xy 299.109929 -118.269716) (xy 299.167822 -118.254203) (xy 299.227244 -118.24638)
			(xy 299.28718 -118.24638) (xy 299.346602 -118.254203) (xy 299.404495 -118.269716) (xy 299.459868 -118.292652)
			(xy 299.511774 -118.322619) (xy 299.559324 -118.359106) (xy 299.601704 -118.401486) (xy 299.638191 -118.449036)
			(xy 299.668158 -118.500942) (xy 299.691094 -118.556315) (xy 299.706607 -118.614208) (xy 299.71443 -118.67363)
			(xy 299.71492 -118.703598) (xy 299.71492 -119.559324) (xy 313.274456 -119.559324) (xy 313.274456 -118.695724)
			(xy 313.274946 -118.665756) (xy 313.282769 -118.606334) (xy 313.298282 -118.548441) (xy 313.321218 -118.493068)
			(xy 313.351185 -118.441162) (xy 313.387672 -118.393612) (xy 313.430052 -118.351232) (xy 313.477602 -118.314745)
			(xy 313.529508 -118.284778) (xy 313.584881 -118.261842) (xy 313.642774 -118.246329) (xy 313.702196 -118.238506)
			(xy 313.762132 -118.238506) (xy 313.821554 -118.246329) (xy 313.879447 -118.261842) (xy 313.93482 -118.284778)
			(xy 313.986726 -118.314745) (xy 314.034276 -118.351232) (xy 314.076656 -118.393612) (xy 314.113143 -118.441162)
			(xy 314.14311 -118.493068) (xy 314.166046 -118.548441) (xy 314.181559 -118.606334) (xy 314.189382 -118.665756)
			(xy 314.189872 -118.695724) (xy 314.189872 -119.559324) (xy 314.189382 -119.589292) (xy 314.181559 -119.648714)
			(xy 314.166046 -119.706607) (xy 314.14311 -119.76198) (xy 314.113143 -119.813886) (xy 314.076656 -119.861436)
			(xy 314.034276 -119.903816) (xy 313.986726 -119.940303) (xy 313.93482 -119.97027) (xy 313.879447 -119.993206)
			(xy 313.821554 -120.008719) (xy 313.762132 -120.016542) (xy 313.702196 -120.016542) (xy 313.642774 -120.008719)
			(xy 313.584881 -119.993206) (xy 313.529508 -119.97027) (xy 313.477602 -119.940303) (xy 313.430052 -119.903816)
			(xy 313.387672 -119.861436) (xy 313.351185 -119.813886) (xy 313.321218 -119.76198) (xy 313.298282 -119.706607)
			(xy 313.282769 -119.648714) (xy 313.274946 -119.589292) (xy 313.274456 -119.559324) (xy 299.71492 -119.559324)
			(xy 299.71492 -119.567198) (xy 299.71443 -119.597166) (xy 299.706607 -119.656588) (xy 299.691094 -119.714481)
			(xy 299.668158 -119.769854) (xy 299.638191 -119.82176) (xy 299.601704 -119.86931) (xy 299.559324 -119.91169)
			(xy 299.511774 -119.948177) (xy 299.459868 -119.978144) (xy 299.404495 -120.00108) (xy 299.346602 -120.016593)
			(xy 299.28718 -120.024416) (xy 299.227244 -120.024416) (xy 299.167822 -120.016593) (xy 299.109929 -120.00108)
			(xy 299.054556 -119.978144) (xy 299.00265 -119.948177) (xy 298.9551 -119.91169) (xy 298.91272 -119.86931)
			(xy 298.876233 -119.82176) (xy 298.846266 -119.769854) (xy 298.82333 -119.714481) (xy 298.807817 -119.656588)
			(xy 298.799994 -119.597166) (xy 298.799504 -119.567198) (xy 286.754824 -119.567198) (xy 286.754824 -120.086374)
			(xy 286.754334 -120.116358) (xy 286.746506 -120.175814) (xy 286.730985 -120.233739) (xy 286.708036 -120.289143)
			(xy 286.678052 -120.341077) (xy 286.641546 -120.388653) (xy 286.599141 -120.431058) (xy 286.551565 -120.467564)
			(xy 286.499631 -120.497548) (xy 286.444227 -120.520497) (xy 286.386302 -120.536018) (xy 286.326846 -120.543846)
			(xy 286.266878 -120.543846) (xy 286.207422 -120.536018) (xy 286.149497 -120.520497) (xy 286.094093 -120.497548)
			(xy 286.042159 -120.467564) (xy 285.994583 -120.431058) (xy 285.952178 -120.388653) (xy 285.915672 -120.341077)
			(xy 285.885688 -120.289143) (xy 285.862739 -120.233739) (xy 285.847218 -120.175814) (xy 285.83939 -120.116358)
			(xy 285.8389 -120.086374) (xy 267.783564 -120.086374) (xy 267.783564 -120.087898) (xy 267.783074 -120.117882)
			(xy 267.775246 -120.177338) (xy 267.759725 -120.235263) (xy 267.736776 -120.290667) (xy 267.706792 -120.342601)
			(xy 267.670286 -120.390177) (xy 267.627881 -120.432582) (xy 267.580305 -120.469088) (xy 267.528371 -120.499072)
			(xy 267.472967 -120.522021) (xy 267.415042 -120.537542) (xy 267.355586 -120.54537) (xy 267.295618 -120.54537)
			(xy 267.236162 -120.537542) (xy 267.178237 -120.522021) (xy 267.122833 -120.499072) (xy 267.070899 -120.469088)
			(xy 267.023323 -120.432582) (xy 266.980918 -120.390177) (xy 266.944412 -120.342601) (xy 266.914428 -120.290667)
			(xy 266.891479 -120.235263) (xy 266.875958 -120.177338) (xy 266.86813 -120.117882) (xy 266.86764 -120.087898)
			(xy 200.469049 -120.087898) (xy 200.477084 -120.091226) (xy 200.52899 -120.121193) (xy 200.57654 -120.15768)
			(xy 200.61892 -120.20006) (xy 200.655407 -120.24761) (xy 200.685374 -120.299516) (xy 200.70831 -120.354889)
			(xy 200.723823 -120.412782) (xy 200.731646 -120.472204) (xy 200.732136 -120.502172) (xy 200.732136 -121.365772)
			(xy 200.731646 -121.39574) (xy 200.723823 -121.455162) (xy 200.70831 -121.513055) (xy 200.685374 -121.568428)
			(xy 200.655407 -121.620334) (xy 200.61892 -121.667884) (xy 200.57654 -121.710264) (xy 200.52899 -121.746751)
			(xy 200.477084 -121.776718) (xy 200.421711 -121.799654) (xy 200.363818 -121.815167) (xy 200.304396 -121.82299)
			(xy 200.24446 -121.82299) (xy 200.185038 -121.815167) (xy 200.127145 -121.799654) (xy 200.071772 -121.776718)
			(xy 200.019866 -121.746751) (xy 199.972316 -121.710264) (xy 199.929936 -121.667884) (xy 199.893449 -121.620334)
			(xy 199.863482 -121.568428) (xy 199.840546 -121.513055) (xy 199.825033 -121.455162) (xy 199.81721 -121.39574)
			(xy 199.81672 -121.365772) (xy 181.760876 -121.365772) (xy 181.760876 -121.367296) (xy 181.760386 -121.397264)
			(xy 181.752563 -121.456686) (xy 181.73705 -121.514579) (xy 181.714114 -121.569952) (xy 181.684147 -121.621858)
			(xy 181.64766 -121.669408) (xy 181.60528 -121.711788) (xy 181.55773 -121.748275) (xy 181.505824 -121.778242)
			(xy 181.450451 -121.801178) (xy 181.392558 -121.816691) (xy 181.333136 -121.824514) (xy 181.2732 -121.824514)
			(xy 181.213778 -121.816691) (xy 181.155885 -121.801178) (xy 181.100512 -121.778242) (xy 181.048606 -121.748275)
			(xy 181.001056 -121.711788) (xy 180.958676 -121.669408) (xy 180.922189 -121.621858) (xy 180.892222 -121.569952)
			(xy 180.869286 -121.514579) (xy 180.853773 -121.456686) (xy 180.84595 -121.397264) (xy 180.84546 -121.367296)
			(xy 168.80078 -121.367296) (xy 168.80078 -121.886472) (xy 168.80029 -121.916456) (xy 168.792462 -121.975912)
			(xy 168.776941 -122.033837) (xy 168.753992 -122.089241) (xy 168.724008 -122.141175) (xy 168.687502 -122.188751)
			(xy 168.645097 -122.231156) (xy 168.597521 -122.267662) (xy 168.545587 -122.297646) (xy 168.490183 -122.320595)
			(xy 168.432258 -122.336116) (xy 168.372802 -122.343944) (xy 168.312834 -122.343944) (xy 168.253378 -122.336116)
			(xy 168.195453 -122.320595) (xy 168.140049 -122.297646) (xy 168.088115 -122.267662) (xy 168.040539 -122.231156)
			(xy 167.998134 -122.188751) (xy 167.961628 -122.141175) (xy 167.931644 -122.089241) (xy 167.908695 -122.033837)
			(xy 167.893174 -121.975912) (xy 167.885346 -121.916456) (xy 167.884856 -121.886472) (xy 154.325828 -121.886472)
			(xy 154.325828 -121.894346) (xy 154.325338 -121.92433) (xy 154.31751 -121.983786) (xy 154.301989 -122.041711)
			(xy 154.27904 -122.097115) (xy 154.249056 -122.149049) (xy 154.21255 -122.196625) (xy 154.170145 -122.23903)
			(xy 154.122569 -122.275536) (xy 154.070635 -122.30552) (xy 154.015231 -122.328469) (xy 153.957306 -122.34399)
			(xy 153.89785 -122.351818) (xy 153.837882 -122.351818) (xy 153.778426 -122.34399) (xy 153.720501 -122.328469)
			(xy 153.665097 -122.30552) (xy 153.613163 -122.275536) (xy 153.565587 -122.23903) (xy 153.523182 -122.196625)
			(xy 153.486676 -122.149049) (xy 153.456692 -122.097115) (xy 153.433743 -122.041711) (xy 153.418222 -121.983786)
			(xy 153.410394 -121.92433) (xy 153.409904 -121.894346) (xy 81.752059 -121.894346) (xy 81.786925 -121.914476)
			(xy 81.834501 -121.950982) (xy 81.876906 -121.993387) (xy 81.913412 -122.040963) (xy 81.943396 -122.092897)
			(xy 81.966345 -122.148301) (xy 81.981866 -122.206226) (xy 81.989694 -122.265682) (xy 81.990184 -122.295666)
			(xy 81.990184 -123.159266) (xy 81.989694 -123.18925) (xy 81.981866 -123.248706) (xy 81.966345 -123.306631)
			(xy 81.943396 -123.362035) (xy 81.913412 -123.413969) (xy 81.876906 -123.461545) (xy 81.834501 -123.50395)
			(xy 81.786925 -123.540456) (xy 81.734991 -123.57044) (xy 81.679587 -123.593389) (xy 81.621662 -123.60891)
			(xy 81.562206 -123.616738) (xy 81.502238 -123.616738) (xy 81.442782 -123.60891) (xy 81.384857 -123.593389)
			(xy 81.329453 -123.57044) (xy 81.277519 -123.540456) (xy 81.229943 -123.50395) (xy 81.187538 -123.461545)
			(xy 81.151032 -123.413969) (xy 81.121048 -123.362035) (xy 81.098099 -123.306631) (xy 81.082578 -123.248706)
			(xy 81.07475 -123.18925) (xy 81.07426 -123.159266) (xy 67.515232 -123.159266) (xy 67.515232 -123.16714)
			(xy 67.514742 -123.197124) (xy 67.506914 -123.25658) (xy 67.491393 -123.314505) (xy 67.468444 -123.369909)
			(xy 67.43846 -123.421843) (xy 67.401954 -123.469419) (xy 67.359549 -123.511824) (xy 67.311973 -123.54833)
			(xy 67.260039 -123.578314) (xy 67.204635 -123.601263) (xy 67.14671 -123.616784) (xy 67.087254 -123.624612)
			(xy 67.027286 -123.624612) (xy 66.96783 -123.616784) (xy 66.909905 -123.601263) (xy 66.854501 -123.578314)
			(xy 66.802567 -123.54833) (xy 66.754991 -123.511824) (xy 66.712586 -123.469419) (xy 66.67608 -123.421843)
			(xy 66.646096 -123.369909) (xy 66.623147 -123.314505) (xy 66.607626 -123.25658) (xy 66.599798 -123.197124)
			(xy 66.599308 -123.16714) (xy 54.554628 -123.16714) (xy 54.554628 -123.686316) (xy 54.554138 -123.716284)
			(xy 54.546315 -123.775706) (xy 54.530802 -123.833599) (xy 54.507866 -123.888972) (xy 54.477899 -123.940878)
			(xy 54.441412 -123.988428) (xy 54.399032 -124.030808) (xy 54.351482 -124.067295) (xy 54.299576 -124.097262)
			(xy 54.244203 -124.120198) (xy 54.18631 -124.135711) (xy 54.126888 -124.143534) (xy 54.066952 -124.143534)
			(xy 54.00753 -124.135711) (xy 53.949637 -124.120198) (xy 53.894264 -124.097262) (xy 53.842358 -124.067295)
			(xy 53.794808 -124.030808) (xy 53.752428 -123.988428) (xy 53.715941 -123.940878) (xy 53.685974 -123.888972)
			(xy 53.663038 -123.833599) (xy 53.647525 -123.775706) (xy 53.639702 -123.716284) (xy 53.639212 -123.686316)
			(xy 35.583368 -123.686316) (xy 35.583368 -123.68784) (xy 35.582878 -123.717808) (xy 35.575055 -123.77723)
			(xy 35.559542 -123.835123) (xy 35.536606 -123.890496) (xy 35.506639 -123.942402) (xy 35.470152 -123.989952)
			(xy 35.427772 -124.032332) (xy 35.380222 -124.068819) (xy 35.328316 -124.098786) (xy 35.272943 -124.121722)
			(xy 35.21505 -124.137235) (xy 35.155628 -124.145058) (xy 35.095692 -124.145058) (xy 35.03627 -124.137235)
			(xy 34.978377 -124.121722) (xy 34.923004 -124.098786) (xy 34.871098 -124.068819) (xy 34.823548 -124.032332)
			(xy 34.781168 -123.989952) (xy 34.744681 -123.942402) (xy 34.714714 -123.890496) (xy 34.691778 -123.835123)
			(xy 34.676265 -123.77723) (xy 34.668442 -123.717808) (xy 34.667952 -123.68784) (xy 4.30911 -123.68784)
			(xy 4.30911 -125.494542) (xy 37.31006 -125.494542) (xy 37.31006 -124.630942) (xy 37.31055 -124.600974)
			(xy 37.318373 -124.541552) (xy 37.333886 -124.483659) (xy 37.356822 -124.428286) (xy 37.386789 -124.37638)
			(xy 37.423276 -124.32883) (xy 37.465656 -124.28645) (xy 37.513206 -124.249963) (xy 37.565112 -124.219996)
			(xy 37.620485 -124.19706) (xy 37.678378 -124.181547) (xy 37.7378 -124.173724) (xy 37.797736 -124.173724)
			(xy 37.857158 -124.181547) (xy 37.915051 -124.19706) (xy 37.970424 -124.219996) (xy 38.02233 -124.249963)
			(xy 38.06988 -124.28645) (xy 38.11226 -124.32883) (xy 38.148747 -124.37638) (xy 38.178714 -124.428286)
			(xy 38.20165 -124.483659) (xy 38.217163 -124.541552) (xy 38.224986 -124.600974) (xy 38.225476 -124.630942)
			(xy 38.225476 -125.486414) (xy 51.785012 -125.486414) (xy 51.785012 -124.622814) (xy 51.785502 -124.592846)
			(xy 51.793325 -124.533424) (xy 51.808838 -124.475531) (xy 51.831774 -124.420158) (xy 51.861741 -124.368252)
			(xy 51.898228 -124.320702) (xy 51.940608 -124.278322) (xy 51.988158 -124.241835) (xy 52.040064 -124.211868)
			(xy 52.095437 -124.188932) (xy 52.15333 -124.173419) (xy 52.212752 -124.165596) (xy 52.272688 -124.165596)
			(xy 52.33211 -124.173419) (xy 52.390003 -124.188932) (xy 52.445376 -124.211868) (xy 52.497282 -124.241835)
			(xy 52.544832 -124.278322) (xy 52.587212 -124.320702) (xy 52.623699 -124.368252) (xy 52.653666 -124.420158)
			(xy 52.676602 -124.475531) (xy 52.692115 -124.533424) (xy 52.699938 -124.592846) (xy 52.700428 -124.622814)
			(xy 52.700428 -124.967238) (xy 64.745108 -124.967238) (xy 64.745108 -124.103638) (xy 64.745598 -124.073654)
			(xy 64.753426 -124.014198) (xy 64.768947 -123.956273) (xy 64.791896 -123.900869) (xy 64.82188 -123.848935)
			(xy 64.858386 -123.801359) (xy 64.900791 -123.758954) (xy 64.948367 -123.722448) (xy 65.000301 -123.692464)
			(xy 65.055705 -123.669515) (xy 65.11363 -123.653994) (xy 65.173086 -123.646166) (xy 65.233054 -123.646166)
			(xy 65.29251 -123.653994) (xy 65.350435 -123.669515) (xy 65.405839 -123.692464) (xy 65.457773 -123.722448)
			(xy 65.505349 -123.758954) (xy 65.547754 -123.801359) (xy 65.58426 -123.848935) (xy 65.614244 -123.900869)
			(xy 65.637193 -123.956273) (xy 65.652714 -124.014198) (xy 65.660542 -124.073654) (xy 65.661032 -124.103638)
			(xy 65.661032 -124.965714) (xy 83.716368 -124.965714) (xy 83.716368 -124.102114) (xy 83.716858 -124.07213)
			(xy 83.724686 -124.012674) (xy 83.740207 -123.954749) (xy 83.763156 -123.899345) (xy 83.79314 -123.847411)
			(xy 83.829646 -123.799835) (xy 83.872051 -123.75743) (xy 83.919627 -123.720924) (xy 83.971561 -123.69094)
			(xy 84.026965 -123.667991) (xy 84.08489 -123.65247) (xy 84.144346 -123.644642) (xy 84.204314 -123.644642)
			(xy 84.26377 -123.65247) (xy 84.321695 -123.667991) (xy 84.369615 -123.68784) (xy 150.767796 -123.68784)
			(xy 150.767796 -122.82424) (xy 150.768286 -122.794256) (xy 150.776114 -122.7348) (xy 150.791635 -122.676875)
			(xy 150.814584 -122.621471) (xy 150.844568 -122.569537) (xy 150.881074 -122.521961) (xy 150.923479 -122.479556)
			(xy 150.971055 -122.44305) (xy 151.022989 -122.413066) (xy 151.078393 -122.390117) (xy 151.136318 -122.374596)
			(xy 151.195774 -122.366768) (xy 151.255742 -122.366768) (xy 151.315198 -122.374596) (xy 151.373123 -122.390117)
			(xy 151.428527 -122.413066) (xy 151.480461 -122.44305) (xy 151.528037 -122.479556) (xy 151.570442 -122.521961)
			(xy 151.606948 -122.569537) (xy 151.636932 -122.621471) (xy 151.659881 -122.676875) (xy 151.675402 -122.7348)
			(xy 151.68323 -122.794256) (xy 151.68372 -122.82424) (xy 151.68372 -123.686316) (xy 169.739056 -123.686316)
			(xy 169.739056 -122.822716) (xy 169.739546 -122.792732) (xy 169.747374 -122.733276) (xy 169.762895 -122.675351)
			(xy 169.785844 -122.619947) (xy 169.815828 -122.568013) (xy 169.852334 -122.520437) (xy 169.894739 -122.478032)
			(xy 169.942315 -122.441526) (xy 169.994249 -122.411542) (xy 170.049653 -122.388593) (xy 170.107578 -122.373072)
			(xy 170.167034 -122.365244) (xy 170.227002 -122.365244) (xy 170.286458 -122.373072) (xy 170.344383 -122.388593)
			(xy 170.399787 -122.411542) (xy 170.451721 -122.441526) (xy 170.499297 -122.478032) (xy 170.541702 -122.520437)
			(xy 170.578208 -122.568013) (xy 170.608192 -122.619947) (xy 170.631141 -122.675351) (xy 170.646662 -122.733276)
			(xy 170.65449 -122.792732) (xy 170.65498 -122.822716) (xy 170.65498 -123.16714) (xy 182.69966 -123.16714)
			(xy 182.69966 -122.30354) (xy 182.70015 -122.273572) (xy 182.707973 -122.21415) (xy 182.723486 -122.156257)
			(xy 182.746422 -122.100884) (xy 182.776389 -122.048978) (xy 182.812876 -122.001428) (xy 182.855256 -121.959048)
			(xy 182.902806 -121.922561) (xy 182.954712 -121.892594) (xy 183.010085 -121.869658) (xy 183.067978 -121.854145)
			(xy 183.1274 -121.846322) (xy 183.187336 -121.846322) (xy 183.246758 -121.854145) (xy 183.304651 -121.869658)
			(xy 183.360024 -121.892594) (xy 183.41193 -121.922561) (xy 183.45948 -121.959048) (xy 183.50186 -122.001428)
			(xy 183.538347 -122.048978) (xy 183.568314 -122.100884) (xy 183.59125 -122.156257) (xy 183.606763 -122.21415)
			(xy 183.614586 -122.273572) (xy 183.615076 -122.30354) (xy 183.615076 -123.159266) (xy 197.174612 -123.159266)
			(xy 197.174612 -122.295666) (xy 197.175102 -122.265698) (xy 197.182925 -122.206276) (xy 197.198438 -122.148383)
			(xy 197.221374 -122.09301) (xy 197.251341 -122.041104) (xy 197.287828 -121.993554) (xy 197.330208 -121.951174)
			(xy 197.377758 -121.914687) (xy 197.429664 -121.88472) (xy 197.485037 -121.861784) (xy 197.54293 -121.846271)
			(xy 197.602352 -121.838448) (xy 197.662288 -121.838448) (xy 197.72171 -121.846271) (xy 197.779603 -121.861784)
			(xy 197.834976 -121.88472) (xy 197.851649 -121.894346) (xy 269.509748 -121.894346) (xy 269.509748 -121.030746)
			(xy 269.510238 -121.000762) (xy 269.518066 -120.941306) (xy 269.533587 -120.883381) (xy 269.556536 -120.827977)
			(xy 269.58652 -120.776043) (xy 269.623026 -120.728467) (xy 269.665431 -120.686062) (xy 269.713007 -120.649556)
			(xy 269.764941 -120.619572) (xy 269.820345 -120.596623) (xy 269.87827 -120.581102) (xy 269.937726 -120.573274)
			(xy 269.997694 -120.573274) (xy 270.05715 -120.581102) (xy 270.115075 -120.596623) (xy 270.170479 -120.619572)
			(xy 270.222413 -120.649556) (xy 270.269989 -120.686062) (xy 270.312394 -120.728467) (xy 270.3489 -120.776043)
			(xy 270.378884 -120.827977) (xy 270.401833 -120.883381) (xy 270.417354 -120.941306) (xy 270.425182 -121.000762)
			(xy 270.425672 -121.030746) (xy 270.425672 -121.886472) (xy 283.9847 -121.886472) (xy 283.9847 -121.022872)
			(xy 283.98519 -120.992888) (xy 283.993018 -120.933432) (xy 284.008539 -120.875507) (xy 284.031488 -120.820103)
			(xy 284.061472 -120.768169) (xy 284.097978 -120.720593) (xy 284.140383 -120.678188) (xy 284.187959 -120.641682)
			(xy 284.239893 -120.611698) (xy 284.295297 -120.588749) (xy 284.353222 -120.573228) (xy 284.412678 -120.5654)
			(xy 284.472646 -120.5654) (xy 284.532102 -120.573228) (xy 284.590027 -120.588749) (xy 284.645431 -120.611698)
			(xy 284.697365 -120.641682) (xy 284.744941 -120.678188) (xy 284.787346 -120.720593) (xy 284.823852 -120.768169)
			(xy 284.853836 -120.820103) (xy 284.876785 -120.875507) (xy 284.892306 -120.933432) (xy 284.900134 -120.992888)
			(xy 284.900624 -121.022872) (xy 284.900624 -121.367296) (xy 296.945304 -121.367296) (xy 296.945304 -120.503696)
			(xy 296.945794 -120.473728) (xy 296.953617 -120.414306) (xy 296.96913 -120.356413) (xy 296.992066 -120.30104)
			(xy 297.022033 -120.249134) (xy 297.05852 -120.201584) (xy 297.1009 -120.159204) (xy 297.14845 -120.122717)
			(xy 297.200356 -120.09275) (xy 297.255729 -120.069814) (xy 297.313622 -120.054301) (xy 297.373044 -120.046478)
			(xy 297.43298 -120.046478) (xy 297.492402 -120.054301) (xy 297.550295 -120.069814) (xy 297.605668 -120.09275)
			(xy 297.657574 -120.122717) (xy 297.705124 -120.159204) (xy 297.747504 -120.201584) (xy 297.783991 -120.249134)
			(xy 297.813958 -120.30104) (xy 297.836894 -120.356413) (xy 297.852407 -120.414306) (xy 297.86023 -120.473728)
			(xy 297.86072 -120.503696) (xy 297.86072 -121.365772) (xy 315.916564 -121.365772) (xy 315.916564 -120.502172)
			(xy 315.917054 -120.472204) (xy 315.924877 -120.412782) (xy 315.94039 -120.354889) (xy 315.963326 -120.299516)
			(xy 315.993293 -120.24761) (xy 316.02978 -120.20006) (xy 316.07216 -120.15768) (xy 316.11971 -120.121193)
			(xy 316.171616 -120.091226) (xy 316.226989 -120.06829) (xy 316.284882 -120.052777) (xy 316.344304 -120.044954)
			(xy 316.40424 -120.044954) (xy 316.463662 -120.052777) (xy 316.521555 -120.06829) (xy 316.568893 -120.087898)
			(xy 382.967992 -120.087898) (xy 382.967992 -119.224298) (xy 382.968482 -119.19433) (xy 382.976305 -119.134908)
			(xy 382.991818 -119.077015) (xy 383.014754 -119.021642) (xy 383.044721 -118.969736) (xy 383.081208 -118.922186)
			(xy 383.123588 -118.879806) (xy 383.171138 -118.843319) (xy 383.223044 -118.813352) (xy 383.278417 -118.790416)
			(xy 383.33631 -118.774903) (xy 383.395732 -118.76708) (xy 383.455668 -118.76708) (xy 383.51509 -118.774903)
			(xy 383.572983 -118.790416) (xy 383.628356 -118.813352) (xy 383.680262 -118.843319) (xy 383.727812 -118.879806)
			(xy 383.770192 -118.922186) (xy 383.806679 -118.969736) (xy 383.836646 -119.021642) (xy 383.859582 -119.077015)
			(xy 383.875095 -119.134908) (xy 383.882918 -119.19433) (xy 383.883408 -119.224298) (xy 383.883408 -120.086374)
			(xy 401.939252 -120.086374) (xy 401.939252 -119.222774) (xy 401.939742 -119.192806) (xy 401.947565 -119.133384)
			(xy 401.963078 -119.075491) (xy 401.986014 -119.020118) (xy 402.015981 -118.968212) (xy 402.052468 -118.920662)
			(xy 402.094848 -118.878282) (xy 402.142398 -118.841795) (xy 402.194304 -118.811828) (xy 402.249677 -118.788892)
			(xy 402.30757 -118.773379) (xy 402.366992 -118.765556) (xy 402.426928 -118.765556) (xy 402.48635 -118.773379)
			(xy 402.544243 -118.788892) (xy 402.599616 -118.811828) (xy 402.651522 -118.841795) (xy 402.699072 -118.878282)
			(xy 402.741452 -118.920662) (xy 402.777939 -118.968212) (xy 402.807906 -119.020118) (xy 402.830842 -119.075491)
			(xy 402.846355 -119.133384) (xy 402.854178 -119.192806) (xy 402.854668 -119.222774) (xy 402.854668 -119.567198)
			(xy 414.899348 -119.567198) (xy 414.899348 -118.703598) (xy 414.899838 -118.673614) (xy 414.907666 -118.614158)
			(xy 414.923187 -118.556233) (xy 414.946136 -118.500829) (xy 414.97612 -118.448895) (xy 415.012626 -118.401319)
			(xy 415.055031 -118.358914) (xy 415.102607 -118.322408) (xy 415.154541 -118.292424) (xy 415.209945 -118.269475)
			(xy 415.26787 -118.253954) (xy 415.327326 -118.246126) (xy 415.387294 -118.246126) (xy 415.44675 -118.253954)
			(xy 415.504675 -118.269475) (xy 415.560079 -118.292424) (xy 415.612013 -118.322408) (xy 415.659589 -118.358914)
			(xy 415.701994 -118.401319) (xy 415.7385 -118.448895) (xy 415.768484 -118.500829) (xy 415.791433 -118.556233)
			(xy 415.806954 -118.614158) (xy 415.814782 -118.673614) (xy 415.815272 -118.703598) (xy 415.815272 -119.559324)
			(xy 429.3743 -119.559324) (xy 429.3743 -118.695724) (xy 429.37479 -118.66574) (xy 429.382618 -118.606284)
			(xy 429.398139 -118.548359) (xy 429.421088 -118.492955) (xy 429.451072 -118.441021) (xy 429.487578 -118.393445)
			(xy 429.529983 -118.35104) (xy 429.577559 -118.314534) (xy 429.629493 -118.28455) (xy 429.684897 -118.261601)
			(xy 429.742822 -118.24608) (xy 429.802278 -118.238252) (xy 429.862246 -118.238252) (xy 429.921702 -118.24608)
			(xy 429.979627 -118.261601) (xy 430.035031 -118.28455) (xy 430.086965 -118.314534) (xy 430.134541 -118.35104)
			(xy 430.176946 -118.393445) (xy 430.213452 -118.441021) (xy 430.243436 -118.492955) (xy 430.266385 -118.548359)
			(xy 430.281906 -118.606284) (xy 430.289734 -118.66574) (xy 430.290224 -118.695724) (xy 430.290224 -119.559324)
			(xy 430.289734 -119.589308) (xy 430.281906 -119.648764) (xy 430.266385 -119.706689) (xy 430.243436 -119.762093)
			(xy 430.213452 -119.814027) (xy 430.176946 -119.861603) (xy 430.134541 -119.904008) (xy 430.086965 -119.940514)
			(xy 430.035031 -119.970498) (xy 429.979627 -119.993447) (xy 429.921702 -120.008968) (xy 429.862246 -120.016796)
			(xy 429.802278 -120.016796) (xy 429.742822 -120.008968) (xy 429.684897 -119.993447) (xy 429.629493 -119.970498)
			(xy 429.577559 -119.940514) (xy 429.529983 -119.904008) (xy 429.487578 -119.861603) (xy 429.451072 -119.814027)
			(xy 429.421088 -119.762093) (xy 429.398139 -119.706689) (xy 429.382618 -119.648764) (xy 429.37479 -119.589308)
			(xy 429.3743 -119.559324) (xy 415.815272 -119.559324) (xy 415.815272 -119.567198) (xy 415.814782 -119.597182)
			(xy 415.806954 -119.656638) (xy 415.791433 -119.714563) (xy 415.768484 -119.769967) (xy 415.7385 -119.821901)
			(xy 415.701994 -119.869477) (xy 415.659589 -119.911882) (xy 415.612013 -119.948388) (xy 415.560079 -119.978372)
			(xy 415.504675 -120.001321) (xy 415.44675 -120.016842) (xy 415.387294 -120.02467) (xy 415.327326 -120.02467)
			(xy 415.26787 -120.016842) (xy 415.209945 -120.001321) (xy 415.154541 -119.978372) (xy 415.102607 -119.948388)
			(xy 415.055031 -119.911882) (xy 415.012626 -119.869477) (xy 414.97612 -119.821901) (xy 414.946136 -119.769967)
			(xy 414.923187 -119.714563) (xy 414.907666 -119.656638) (xy 414.899838 -119.597182) (xy 414.899348 -119.567198)
			(xy 402.854668 -119.567198) (xy 402.854668 -120.086374) (xy 402.854178 -120.116342) (xy 402.846355 -120.175764)
			(xy 402.830842 -120.233657) (xy 402.807906 -120.28903) (xy 402.777939 -120.340936) (xy 402.741452 -120.388486)
			(xy 402.699072 -120.430866) (xy 402.651522 -120.467353) (xy 402.599616 -120.49732) (xy 402.544243 -120.520256)
			(xy 402.48635 -120.535769) (xy 402.426928 -120.543592) (xy 402.366992 -120.543592) (xy 402.30757 -120.535769)
			(xy 402.249677 -120.520256) (xy 402.194304 -120.49732) (xy 402.142398 -120.467353) (xy 402.094848 -120.430866)
			(xy 402.052468 -120.388486) (xy 402.015981 -120.340936) (xy 401.986014 -120.28903) (xy 401.963078 -120.233657)
			(xy 401.947565 -120.175764) (xy 401.939742 -120.116342) (xy 401.939252 -120.086374) (xy 383.883408 -120.086374)
			(xy 383.883408 -120.087898) (xy 383.882918 -120.117866) (xy 383.875095 -120.177288) (xy 383.859582 -120.235181)
			(xy 383.836646 -120.290554) (xy 383.806679 -120.34246) (xy 383.770192 -120.39001) (xy 383.727812 -120.43239)
			(xy 383.680262 -120.468877) (xy 383.628356 -120.498844) (xy 383.572983 -120.52178) (xy 383.51509 -120.537293)
			(xy 383.455668 -120.545116) (xy 383.395732 -120.545116) (xy 383.33631 -120.537293) (xy 383.278417 -120.52178)
			(xy 383.223044 -120.498844) (xy 383.171138 -120.468877) (xy 383.123588 -120.43239) (xy 383.081208 -120.39001)
			(xy 383.044721 -120.34246) (xy 383.014754 -120.290554) (xy 382.991818 -120.235181) (xy 382.976305 -120.177288)
			(xy 382.968482 -120.117866) (xy 382.967992 -120.087898) (xy 316.568893 -120.087898) (xy 316.576928 -120.091226)
			(xy 316.628834 -120.121193) (xy 316.676384 -120.15768) (xy 316.718764 -120.20006) (xy 316.755251 -120.24761)
			(xy 316.785218 -120.299516) (xy 316.808154 -120.354889) (xy 316.823667 -120.412782) (xy 316.83149 -120.472204)
			(xy 316.83198 -120.502172) (xy 316.83198 -121.365772) (xy 316.83149 -121.39574) (xy 316.823667 -121.455162)
			(xy 316.808154 -121.513055) (xy 316.785218 -121.568428) (xy 316.755251 -121.620334) (xy 316.718764 -121.667884)
			(xy 316.676384 -121.710264) (xy 316.628834 -121.746751) (xy 316.576928 -121.776718) (xy 316.521555 -121.799654)
			(xy 316.463662 -121.815167) (xy 316.40424 -121.82299) (xy 316.344304 -121.82299) (xy 316.284882 -121.815167)
			(xy 316.226989 -121.799654) (xy 316.171616 -121.776718) (xy 316.11971 -121.746751) (xy 316.07216 -121.710264)
			(xy 316.02978 -121.667884) (xy 315.993293 -121.620334) (xy 315.963326 -121.568428) (xy 315.94039 -121.513055)
			(xy 315.924877 -121.455162) (xy 315.917054 -121.39574) (xy 315.916564 -121.365772) (xy 297.86072 -121.365772)
			(xy 297.86072 -121.367296) (xy 297.86023 -121.397264) (xy 297.852407 -121.456686) (xy 297.836894 -121.514579)
			(xy 297.813958 -121.569952) (xy 297.783991 -121.621858) (xy 297.747504 -121.669408) (xy 297.705124 -121.711788)
			(xy 297.657574 -121.748275) (xy 297.605668 -121.778242) (xy 297.550295 -121.801178) (xy 297.492402 -121.816691)
			(xy 297.43298 -121.824514) (xy 297.373044 -121.824514) (xy 297.313622 -121.816691) (xy 297.255729 -121.801178)
			(xy 297.200356 -121.778242) (xy 297.14845 -121.748275) (xy 297.1009 -121.711788) (xy 297.05852 -121.669408)
			(xy 297.022033 -121.621858) (xy 296.992066 -121.569952) (xy 296.96913 -121.514579) (xy 296.953617 -121.456686)
			(xy 296.945794 -121.397264) (xy 296.945304 -121.367296) (xy 284.900624 -121.367296) (xy 284.900624 -121.886472)
			(xy 284.900134 -121.916456) (xy 284.892306 -121.975912) (xy 284.876785 -122.033837) (xy 284.853836 -122.089241)
			(xy 284.823852 -122.141175) (xy 284.787346 -122.188751) (xy 284.744941 -122.231156) (xy 284.697365 -122.267662)
			(xy 284.645431 -122.297646) (xy 284.590027 -122.320595) (xy 284.532102 -122.336116) (xy 284.472646 -122.343944)
			(xy 284.412678 -122.343944) (xy 284.353222 -122.336116) (xy 284.295297 -122.320595) (xy 284.239893 -122.297646)
			(xy 284.187959 -122.267662) (xy 284.140383 -122.231156) (xy 284.097978 -122.188751) (xy 284.061472 -122.141175)
			(xy 284.031488 -122.089241) (xy 284.008539 -122.033837) (xy 283.993018 -121.975912) (xy 283.98519 -121.916456)
			(xy 283.9847 -121.886472) (xy 270.425672 -121.886472) (xy 270.425672 -121.894346) (xy 270.425182 -121.92433)
			(xy 270.417354 -121.983786) (xy 270.401833 -122.041711) (xy 270.378884 -122.097115) (xy 270.3489 -122.149049)
			(xy 270.312394 -122.196625) (xy 270.269989 -122.23903) (xy 270.222413 -122.275536) (xy 270.170479 -122.30552)
			(xy 270.115075 -122.328469) (xy 270.05715 -122.34399) (xy 269.997694 -122.351818) (xy 269.937726 -122.351818)
			(xy 269.87827 -122.34399) (xy 269.820345 -122.328469) (xy 269.764941 -122.30552) (xy 269.713007 -122.275536)
			(xy 269.665431 -122.23903) (xy 269.623026 -122.196625) (xy 269.58652 -122.149049) (xy 269.556536 -122.097115)
			(xy 269.533587 -122.041711) (xy 269.518066 -121.983786) (xy 269.510238 -121.92433) (xy 269.509748 -121.894346)
			(xy 197.851649 -121.894346) (xy 197.886882 -121.914687) (xy 197.934432 -121.951174) (xy 197.976812 -121.993554)
			(xy 198.013299 -122.041104) (xy 198.043266 -122.09301) (xy 198.066202 -122.148383) (xy 198.081715 -122.206276)
			(xy 198.089538 -122.265698) (xy 198.090028 -122.295666) (xy 198.090028 -123.159266) (xy 198.089538 -123.189234)
			(xy 198.081715 -123.248656) (xy 198.066202 -123.306549) (xy 198.043266 -123.361922) (xy 198.013299 -123.413828)
			(xy 197.976812 -123.461378) (xy 197.934432 -123.503758) (xy 197.886882 -123.540245) (xy 197.834976 -123.570212)
			(xy 197.779603 -123.593148) (xy 197.72171 -123.608661) (xy 197.662288 -123.616484) (xy 197.602352 -123.616484)
			(xy 197.54293 -123.608661) (xy 197.485037 -123.593148) (xy 197.429664 -123.570212) (xy 197.377758 -123.540245)
			(xy 197.330208 -123.503758) (xy 197.287828 -123.461378) (xy 197.251341 -123.413828) (xy 197.221374 -123.361922)
			(xy 197.198438 -123.306549) (xy 197.182925 -123.248656) (xy 197.175102 -123.189234) (xy 197.174612 -123.159266)
			(xy 183.615076 -123.159266) (xy 183.615076 -123.16714) (xy 183.614586 -123.197108) (xy 183.606763 -123.25653)
			(xy 183.59125 -123.314423) (xy 183.568314 -123.369796) (xy 183.538347 -123.421702) (xy 183.50186 -123.469252)
			(xy 183.45948 -123.511632) (xy 183.41193 -123.548119) (xy 183.360024 -123.578086) (xy 183.304651 -123.601022)
			(xy 183.246758 -123.616535) (xy 183.187336 -123.624358) (xy 183.1274 -123.624358) (xy 183.067978 -123.616535)
			(xy 183.010085 -123.601022) (xy 182.954712 -123.578086) (xy 182.902806 -123.548119) (xy 182.855256 -123.511632)
			(xy 182.812876 -123.469252) (xy 182.776389 -123.421702) (xy 182.746422 -123.369796) (xy 182.723486 -123.314423)
			(xy 182.707973 -123.25653) (xy 182.70015 -123.197108) (xy 182.69966 -123.16714) (xy 170.65498 -123.16714)
			(xy 170.65498 -123.686316) (xy 170.65449 -123.7163) (xy 170.646662 -123.775756) (xy 170.631141 -123.833681)
			(xy 170.608192 -123.889085) (xy 170.578208 -123.941019) (xy 170.541702 -123.988595) (xy 170.499297 -124.031)
			(xy 170.451721 -124.067506) (xy 170.399787 -124.09749) (xy 170.344383 -124.120439) (xy 170.286458 -124.13596)
			(xy 170.227002 -124.143788) (xy 170.167034 -124.143788) (xy 170.107578 -124.13596) (xy 170.049653 -124.120439)
			(xy 169.994249 -124.09749) (xy 169.942315 -124.067506) (xy 169.894739 -124.031) (xy 169.852334 -123.988595)
			(xy 169.815828 -123.941019) (xy 169.785844 -123.889085) (xy 169.762895 -123.833681) (xy 169.747374 -123.775756)
			(xy 169.739546 -123.7163) (xy 169.739056 -123.686316) (xy 151.68372 -123.686316) (xy 151.68372 -123.68784)
			(xy 151.68323 -123.717824) (xy 151.675402 -123.77728) (xy 151.659881 -123.835205) (xy 151.636932 -123.890609)
			(xy 151.606948 -123.942543) (xy 151.570442 -123.990119) (xy 151.528037 -124.032524) (xy 151.480461 -124.06903)
			(xy 151.428527 -124.099014) (xy 151.373123 -124.121963) (xy 151.315198 -124.137484) (xy 151.255742 -124.145312)
			(xy 151.195774 -124.145312) (xy 151.136318 -124.137484) (xy 151.078393 -124.121963) (xy 151.022989 -124.099014)
			(xy 150.971055 -124.06903) (xy 150.923479 -124.032524) (xy 150.881074 -123.990119) (xy 150.844568 -123.942543)
			(xy 150.814584 -123.890609) (xy 150.791635 -123.835205) (xy 150.776114 -123.77728) (xy 150.768286 -123.717824)
			(xy 150.767796 -123.68784) (xy 84.369615 -123.68784) (xy 84.377099 -123.69094) (xy 84.429033 -123.720924)
			(xy 84.476609 -123.75743) (xy 84.519014 -123.799835) (xy 84.55552 -123.847411) (xy 84.585504 -123.899345)
			(xy 84.608453 -123.954749) (xy 84.623974 -124.012674) (xy 84.631802 -124.07213) (xy 84.632292 -124.102114)
			(xy 84.632292 -124.965714) (xy 84.631802 -124.995698) (xy 84.623974 -125.055154) (xy 84.608453 -125.113079)
			(xy 84.585504 -125.168483) (xy 84.55552 -125.220417) (xy 84.519014 -125.267993) (xy 84.476609 -125.310398)
			(xy 84.429033 -125.346904) (xy 84.377099 -125.376888) (xy 84.321695 -125.399837) (xy 84.26377 -125.415358)
			(xy 84.204314 -125.423186) (xy 84.144346 -125.423186) (xy 84.08489 -125.415358) (xy 84.026965 -125.399837)
			(xy 83.971561 -125.376888) (xy 83.919627 -125.346904) (xy 83.872051 -125.310398) (xy 83.829646 -125.267993)
			(xy 83.79314 -125.220417) (xy 83.763156 -125.168483) (xy 83.740207 -125.113079) (xy 83.724686 -125.055154)
			(xy 83.716858 -124.995698) (xy 83.716368 -124.965714) (xy 65.661032 -124.965714) (xy 65.661032 -124.967238)
			(xy 65.660542 -124.997222) (xy 65.652714 -125.056678) (xy 65.637193 -125.114603) (xy 65.614244 -125.170007)
			(xy 65.58426 -125.221941) (xy 65.547754 -125.269517) (xy 65.505349 -125.311922) (xy 65.457773 -125.348428)
			(xy 65.405839 -125.378412) (xy 65.350435 -125.401361) (xy 65.29251 -125.416882) (xy 65.233054 -125.42471)
			(xy 65.173086 -125.42471) (xy 65.11363 -125.416882) (xy 65.055705 -125.401361) (xy 65.000301 -125.378412)
			(xy 64.948367 -125.348428) (xy 64.900791 -125.311922) (xy 64.858386 -125.269517) (xy 64.82188 -125.221941)
			(xy 64.791896 -125.170007) (xy 64.768947 -125.114603) (xy 64.753426 -125.056678) (xy 64.745598 -124.997222)
			(xy 64.745108 -124.967238) (xy 52.700428 -124.967238) (xy 52.700428 -125.486414) (xy 52.700295 -125.494542)
			(xy 153.409904 -125.494542) (xy 153.409904 -124.630942) (xy 153.410394 -124.600958) (xy 153.418222 -124.541502)
			(xy 153.433743 -124.483577) (xy 153.456692 -124.428173) (xy 153.486676 -124.376239) (xy 153.523182 -124.328663)
			(xy 153.565587 -124.286258) (xy 153.613163 -124.249752) (xy 153.665097 -124.219768) (xy 153.720501 -124.196819)
			(xy 153.778426 -124.181298) (xy 153.837882 -124.17347) (xy 153.89785 -124.17347) (xy 153.957306 -124.181298)
			(xy 154.015231 -124.196819) (xy 154.070635 -124.219768) (xy 154.122569 -124.249752) (xy 154.170145 -124.286258)
			(xy 154.21255 -124.328663) (xy 154.249056 -124.376239) (xy 154.27904 -124.428173) (xy 154.301989 -124.483577)
			(xy 154.31751 -124.541502) (xy 154.325338 -124.600958) (xy 154.325828 -124.630942) (xy 154.325828 -125.486414)
			(xy 167.884856 -125.486414) (xy 167.884856 -124.622814) (xy 167.885346 -124.59283) (xy 167.893174 -124.533374)
			(xy 167.908695 -124.475449) (xy 167.931644 -124.420045) (xy 167.961628 -124.368111) (xy 167.998134 -124.320535)
			(xy 168.040539 -124.27813) (xy 168.088115 -124.241624) (xy 168.140049 -124.21164) (xy 168.195453 -124.188691)
			(xy 168.253378 -124.17317) (xy 168.312834 -124.165342) (xy 168.372802 -124.165342) (xy 168.432258 -124.17317)
			(xy 168.490183 -124.188691) (xy 168.545587 -124.21164) (xy 168.597521 -124.241624) (xy 168.645097 -124.27813)
			(xy 168.687502 -124.320535) (xy 168.724008 -124.368111) (xy 168.753992 -124.420045) (xy 168.776941 -124.475449)
			(xy 168.792462 -124.533374) (xy 168.80029 -124.59283) (xy 168.80078 -124.622814) (xy 168.80078 -124.967238)
			(xy 180.84546 -124.967238) (xy 180.84546 -124.103638) (xy 180.84595 -124.07367) (xy 180.853773 -124.014248)
			(xy 180.869286 -123.956355) (xy 180.892222 -123.900982) (xy 180.922189 -123.849076) (xy 180.958676 -123.801526)
			(xy 181.001056 -123.759146) (xy 181.048606 -123.722659) (xy 181.100512 -123.692692) (xy 181.155885 -123.669756)
			(xy 181.213778 -123.654243) (xy 181.2732 -123.64642) (xy 181.333136 -123.64642) (xy 181.392558 -123.654243)
			(xy 181.450451 -123.669756) (xy 181.505824 -123.692692) (xy 181.55773 -123.722659) (xy 181.60528 -123.759146)
			(xy 181.64766 -123.801526) (xy 181.684147 -123.849076) (xy 181.714114 -123.900982) (xy 181.73705 -123.956355)
			(xy 181.752563 -124.014248) (xy 181.760386 -124.07367) (xy 181.760876 -124.103638) (xy 181.760876 -124.965714)
			(xy 199.81672 -124.965714) (xy 199.81672 -124.102114) (xy 199.81721 -124.072146) (xy 199.825033 -124.012724)
			(xy 199.840546 -123.954831) (xy 199.863482 -123.899458) (xy 199.893449 -123.847552) (xy 199.929936 -123.800002)
			(xy 199.972316 -123.757622) (xy 200.019866 -123.721135) (xy 200.071772 -123.691168) (xy 200.127145 -123.668232)
			(xy 200.185038 -123.652719) (xy 200.24446 -123.644896) (xy 200.304396 -123.644896) (xy 200.363818 -123.652719)
			(xy 200.421711 -123.668232) (xy 200.469049 -123.68784) (xy 266.86764 -123.68784) (xy 266.86764 -122.82424)
			(xy 266.86813 -122.794256) (xy 266.875958 -122.7348) (xy 266.891479 -122.676875) (xy 266.914428 -122.621471)
			(xy 266.944412 -122.569537) (xy 266.980918 -122.521961) (xy 267.023323 -122.479556) (xy 267.070899 -122.44305)
			(xy 267.122833 -122.413066) (xy 267.178237 -122.390117) (xy 267.236162 -122.374596) (xy 267.295618 -122.366768)
			(xy 267.355586 -122.366768) (xy 267.415042 -122.374596) (xy 267.472967 -122.390117) (xy 267.528371 -122.413066)
			(xy 267.580305 -122.44305) (xy 267.627881 -122.479556) (xy 267.670286 -122.521961) (xy 267.706792 -122.569537)
			(xy 267.736776 -122.621471) (xy 267.759725 -122.676875) (xy 267.775246 -122.7348) (xy 267.783074 -122.794256)
			(xy 267.783564 -122.82424) (xy 267.783564 -123.686316) (xy 285.8389 -123.686316) (xy 285.8389 -122.822716)
			(xy 285.83939 -122.792732) (xy 285.847218 -122.733276) (xy 285.862739 -122.675351) (xy 285.885688 -122.619947)
			(xy 285.915672 -122.568013) (xy 285.952178 -122.520437) (xy 285.994583 -122.478032) (xy 286.042159 -122.441526)
			(xy 286.094093 -122.411542) (xy 286.149497 -122.388593) (xy 286.207422 -122.373072) (xy 286.266878 -122.365244)
			(xy 286.326846 -122.365244) (xy 286.386302 -122.373072) (xy 286.444227 -122.388593) (xy 286.499631 -122.411542)
			(xy 286.551565 -122.441526) (xy 286.599141 -122.478032) (xy 286.641546 -122.520437) (xy 286.678052 -122.568013)
			(xy 286.708036 -122.619947) (xy 286.730985 -122.675351) (xy 286.746506 -122.733276) (xy 286.754334 -122.792732)
			(xy 286.754824 -122.822716) (xy 286.754824 -123.16714) (xy 298.799504 -123.16714) (xy 298.799504 -122.30354)
			(xy 298.799994 -122.273572) (xy 298.807817 -122.21415) (xy 298.82333 -122.156257) (xy 298.846266 -122.100884)
			(xy 298.876233 -122.048978) (xy 298.91272 -122.001428) (xy 298.9551 -121.959048) (xy 299.00265 -121.922561)
			(xy 299.054556 -121.892594) (xy 299.109929 -121.869658) (xy 299.167822 -121.854145) (xy 299.227244 -121.846322)
			(xy 299.28718 -121.846322) (xy 299.346602 -121.854145) (xy 299.404495 -121.869658) (xy 299.459868 -121.892594)
			(xy 299.511774 -121.922561) (xy 299.559324 -121.959048) (xy 299.601704 -122.001428) (xy 299.638191 -122.048978)
			(xy 299.668158 -122.100884) (xy 299.691094 -122.156257) (xy 299.706607 -122.21415) (xy 299.71443 -122.273572)
			(xy 299.71492 -122.30354) (xy 299.71492 -123.159266) (xy 313.274456 -123.159266) (xy 313.274456 -122.295666)
			(xy 313.274946 -122.265698) (xy 313.282769 -122.206276) (xy 313.298282 -122.148383) (xy 313.321218 -122.09301)
			(xy 313.351185 -122.041104) (xy 313.387672 -121.993554) (xy 313.430052 -121.951174) (xy 313.477602 -121.914687)
			(xy 313.529508 -121.88472) (xy 313.584881 -121.861784) (xy 313.642774 -121.846271) (xy 313.702196 -121.838448)
			(xy 313.762132 -121.838448) (xy 313.821554 -121.846271) (xy 313.879447 -121.861784) (xy 313.93482 -121.88472)
			(xy 313.951493 -121.894346) (xy 385.6101 -121.894346) (xy 385.6101 -121.030746) (xy 385.61059 -121.000778)
			(xy 385.618413 -120.941356) (xy 385.633926 -120.883463) (xy 385.656862 -120.82809) (xy 385.686829 -120.776184)
			(xy 385.723316 -120.728634) (xy 385.765696 -120.686254) (xy 385.813246 -120.649767) (xy 385.865152 -120.6198)
			(xy 385.920525 -120.596864) (xy 385.978418 -120.581351) (xy 386.03784 -120.573528) (xy 386.097776 -120.573528)
			(xy 386.157198 -120.581351) (xy 386.215091 -120.596864) (xy 386.270464 -120.6198) (xy 386.32237 -120.649767)
			(xy 386.36992 -120.686254) (xy 386.4123 -120.728634) (xy 386.448787 -120.776184) (xy 386.478754 -120.82809)
			(xy 386.50169 -120.883463) (xy 386.517203 -120.941356) (xy 386.525026 -121.000778) (xy 386.525516 -121.030746)
			(xy 386.525516 -121.886472) (xy 400.085052 -121.886472) (xy 400.085052 -121.022872) (xy 400.085542 -120.992904)
			(xy 400.093365 -120.933482) (xy 400.108878 -120.875589) (xy 400.131814 -120.820216) (xy 400.161781 -120.76831)
			(xy 400.198268 -120.72076) (xy 400.240648 -120.67838) (xy 400.288198 -120.641893) (xy 400.340104 -120.611926)
			(xy 400.395477 -120.58899) (xy 400.45337 -120.573477) (xy 400.512792 -120.565654) (xy 400.572728 -120.565654)
			(xy 400.63215 -120.573477) (xy 400.690043 -120.58899) (xy 400.745416 -120.611926) (xy 400.797322 -120.641893)
			(xy 400.844872 -120.67838) (xy 400.887252 -120.72076) (xy 400.923739 -120.76831) (xy 400.953706 -120.820216)
			(xy 400.976642 -120.875589) (xy 400.992155 -120.933482) (xy 400.999978 -120.992904) (xy 401.000468 -121.022872)
			(xy 401.000468 -121.367296) (xy 413.045148 -121.367296) (xy 413.045148 -120.503696) (xy 413.045638 -120.473712)
			(xy 413.053466 -120.414256) (xy 413.068987 -120.356331) (xy 413.091936 -120.300927) (xy 413.12192 -120.248993)
			(xy 413.158426 -120.201417) (xy 413.200831 -120.159012) (xy 413.248407 -120.122506) (xy 413.300341 -120.092522)
			(xy 413.355745 -120.069573) (xy 413.41367 -120.054052) (xy 413.473126 -120.046224) (xy 413.533094 -120.046224)
			(xy 413.59255 -120.054052) (xy 413.650475 -120.069573) (xy 413.705879 -120.092522) (xy 413.757813 -120.122506)
			(xy 413.805389 -120.159012) (xy 413.847794 -120.201417) (xy 413.8843 -120.248993) (xy 413.914284 -120.300927)
			(xy 413.937233 -120.356331) (xy 413.952754 -120.414256) (xy 413.960582 -120.473712) (xy 413.961072 -120.503696)
			(xy 413.961072 -121.365772) (xy 432.016408 -121.365772) (xy 432.016408 -120.502172) (xy 432.016898 -120.472188)
			(xy 432.024726 -120.412732) (xy 432.040247 -120.354807) (xy 432.063196 -120.299403) (xy 432.09318 -120.247469)
			(xy 432.129686 -120.199893) (xy 432.172091 -120.157488) (xy 432.219667 -120.120982) (xy 432.271601 -120.090998)
			(xy 432.327005 -120.068049) (xy 432.38493 -120.052528) (xy 432.444386 -120.0447) (xy 432.504354 -120.0447)
			(xy 432.56381 -120.052528) (xy 432.621735 -120.068049) (xy 432.677139 -120.090998) (xy 432.729073 -120.120982)
			(xy 432.776649 -120.157488) (xy 432.819054 -120.199893) (xy 432.85556 -120.247469) (xy 432.885544 -120.299403)
			(xy 432.908493 -120.354807) (xy 432.924014 -120.412732) (xy 432.931842 -120.472188) (xy 432.932332 -120.502172)
			(xy 432.932332 -121.365772) (xy 432.931842 -121.395756) (xy 432.924014 -121.455212) (xy 432.908493 -121.513137)
			(xy 432.885544 -121.568541) (xy 432.85556 -121.620475) (xy 432.819054 -121.668051) (xy 432.776649 -121.710456)
			(xy 432.729073 -121.746962) (xy 432.677139 -121.776946) (xy 432.621735 -121.799895) (xy 432.56381 -121.815416)
			(xy 432.504354 -121.823244) (xy 432.444386 -121.823244) (xy 432.38493 -121.815416) (xy 432.327005 -121.799895)
			(xy 432.271601 -121.776946) (xy 432.219667 -121.746962) (xy 432.172091 -121.710456) (xy 432.129686 -121.668051)
			(xy 432.09318 -121.620475) (xy 432.063196 -121.568541) (xy 432.040247 -121.513137) (xy 432.024726 -121.455212)
			(xy 432.016898 -121.395756) (xy 432.016408 -121.365772) (xy 413.961072 -121.365772) (xy 413.961072 -121.367296)
			(xy 413.960582 -121.39728) (xy 413.952754 -121.456736) (xy 413.937233 -121.514661) (xy 413.914284 -121.570065)
			(xy 413.8843 -121.621999) (xy 413.847794 -121.669575) (xy 413.805389 -121.71198) (xy 413.757813 -121.748486)
			(xy 413.705879 -121.77847) (xy 413.650475 -121.801419) (xy 413.59255 -121.81694) (xy 413.533094 -121.824768)
			(xy 413.473126 -121.824768) (xy 413.41367 -121.81694) (xy 413.355745 -121.801419) (xy 413.300341 -121.77847)
			(xy 413.248407 -121.748486) (xy 413.200831 -121.71198) (xy 413.158426 -121.669575) (xy 413.12192 -121.621999)
			(xy 413.091936 -121.570065) (xy 413.068987 -121.514661) (xy 413.053466 -121.456736) (xy 413.045638 -121.39728)
			(xy 413.045148 -121.367296) (xy 401.000468 -121.367296) (xy 401.000468 -121.886472) (xy 400.999978 -121.91644)
			(xy 400.992155 -121.975862) (xy 400.976642 -122.033755) (xy 400.953706 -122.089128) (xy 400.923739 -122.141034)
			(xy 400.887252 -122.188584) (xy 400.844872 -122.230964) (xy 400.797322 -122.267451) (xy 400.745416 -122.297418)
			(xy 400.690043 -122.320354) (xy 400.63215 -122.335867) (xy 400.572728 -122.34369) (xy 400.512792 -122.34369)
			(xy 400.45337 -122.335867) (xy 400.395477 -122.320354) (xy 400.340104 -122.297418) (xy 400.288198 -122.267451)
			(xy 400.240648 -122.230964) (xy 400.198268 -122.188584) (xy 400.161781 -122.141034) (xy 400.131814 -122.089128)
			(xy 400.108878 -122.033755) (xy 400.093365 -121.975862) (xy 400.085542 -121.91644) (xy 400.085052 -121.886472)
			(xy 386.525516 -121.886472) (xy 386.525516 -121.894346) (xy 386.525026 -121.924314) (xy 386.517203 -121.983736)
			(xy 386.50169 -122.041629) (xy 386.478754 -122.097002) (xy 386.448787 -122.148908) (xy 386.4123 -122.196458)
			(xy 386.36992 -122.238838) (xy 386.32237 -122.275325) (xy 386.270464 -122.305292) (xy 386.215091 -122.328228)
			(xy 386.157198 -122.343741) (xy 386.097776 -122.351564) (xy 386.03784 -122.351564) (xy 385.978418 -122.343741)
			(xy 385.920525 -122.328228) (xy 385.865152 -122.305292) (xy 385.813246 -122.275325) (xy 385.765696 -122.238838)
			(xy 385.723316 -122.196458) (xy 385.686829 -122.148908) (xy 385.656862 -122.097002) (xy 385.633926 -122.041629)
			(xy 385.618413 -121.983736) (xy 385.61059 -121.924314) (xy 385.6101 -121.894346) (xy 313.951493 -121.894346)
			(xy 313.986726 -121.914687) (xy 314.034276 -121.951174) (xy 314.076656 -121.993554) (xy 314.113143 -122.041104)
			(xy 314.14311 -122.09301) (xy 314.166046 -122.148383) (xy 314.181559 -122.206276) (xy 314.189382 -122.265698)
			(xy 314.189872 -122.295666) (xy 314.189872 -123.159266) (xy 314.189382 -123.189234) (xy 314.181559 -123.248656)
			(xy 314.166046 -123.306549) (xy 314.14311 -123.361922) (xy 314.113143 -123.413828) (xy 314.076656 -123.461378)
			(xy 314.034276 -123.503758) (xy 313.986726 -123.540245) (xy 313.93482 -123.570212) (xy 313.879447 -123.593148)
			(xy 313.821554 -123.608661) (xy 313.762132 -123.616484) (xy 313.702196 -123.616484) (xy 313.642774 -123.608661)
			(xy 313.584881 -123.593148) (xy 313.529508 -123.570212) (xy 313.477602 -123.540245) (xy 313.430052 -123.503758)
			(xy 313.387672 -123.461378) (xy 313.351185 -123.413828) (xy 313.321218 -123.361922) (xy 313.298282 -123.306549)
			(xy 313.282769 -123.248656) (xy 313.274946 -123.189234) (xy 313.274456 -123.159266) (xy 299.71492 -123.159266)
			(xy 299.71492 -123.16714) (xy 299.71443 -123.197108) (xy 299.706607 -123.25653) (xy 299.691094 -123.314423)
			(xy 299.668158 -123.369796) (xy 299.638191 -123.421702) (xy 299.601704 -123.469252) (xy 299.559324 -123.511632)
			(xy 299.511774 -123.548119) (xy 299.459868 -123.578086) (xy 299.404495 -123.601022) (xy 299.346602 -123.616535)
			(xy 299.28718 -123.624358) (xy 299.227244 -123.624358) (xy 299.167822 -123.616535) (xy 299.109929 -123.601022)
			(xy 299.054556 -123.578086) (xy 299.00265 -123.548119) (xy 298.9551 -123.511632) (xy 298.91272 -123.469252)
			(xy 298.876233 -123.421702) (xy 298.846266 -123.369796) (xy 298.82333 -123.314423) (xy 298.807817 -123.25653)
			(xy 298.799994 -123.197108) (xy 298.799504 -123.16714) (xy 286.754824 -123.16714) (xy 286.754824 -123.686316)
			(xy 286.754334 -123.7163) (xy 286.746506 -123.775756) (xy 286.730985 -123.833681) (xy 286.708036 -123.889085)
			(xy 286.678052 -123.941019) (xy 286.641546 -123.988595) (xy 286.599141 -124.031) (xy 286.551565 -124.067506)
			(xy 286.499631 -124.09749) (xy 286.444227 -124.120439) (xy 286.386302 -124.13596) (xy 286.326846 -124.143788)
			(xy 286.266878 -124.143788) (xy 286.207422 -124.13596) (xy 286.149497 -124.120439) (xy 286.094093 -124.09749)
			(xy 286.042159 -124.067506) (xy 285.994583 -124.031) (xy 285.952178 -123.988595) (xy 285.915672 -123.941019)
			(xy 285.885688 -123.889085) (xy 285.862739 -123.833681) (xy 285.847218 -123.775756) (xy 285.83939 -123.7163)
			(xy 285.8389 -123.686316) (xy 267.783564 -123.686316) (xy 267.783564 -123.68784) (xy 267.783074 -123.717824)
			(xy 267.775246 -123.77728) (xy 267.759725 -123.835205) (xy 267.736776 -123.890609) (xy 267.706792 -123.942543)
			(xy 267.670286 -123.990119) (xy 267.627881 -124.032524) (xy 267.580305 -124.06903) (xy 267.528371 -124.099014)
			(xy 267.472967 -124.121963) (xy 267.415042 -124.137484) (xy 267.355586 -124.145312) (xy 267.295618 -124.145312)
			(xy 267.236162 -124.137484) (xy 267.178237 -124.121963) (xy 267.122833 -124.099014) (xy 267.070899 -124.06903)
			(xy 267.023323 -124.032524) (xy 266.980918 -123.990119) (xy 266.944412 -123.942543) (xy 266.914428 -123.890609)
			(xy 266.891479 -123.835205) (xy 266.875958 -123.77728) (xy 266.86813 -123.717824) (xy 266.86764 -123.68784)
			(xy 200.469049 -123.68784) (xy 200.477084 -123.691168) (xy 200.52899 -123.721135) (xy 200.57654 -123.757622)
			(xy 200.61892 -123.800002) (xy 200.655407 -123.847552) (xy 200.685374 -123.899458) (xy 200.70831 -123.954831)
			(xy 200.723823 -124.012724) (xy 200.731646 -124.072146) (xy 200.732136 -124.102114) (xy 200.732136 -124.965714)
			(xy 200.731646 -124.995682) (xy 200.723823 -125.055104) (xy 200.70831 -125.112997) (xy 200.685374 -125.16837)
			(xy 200.655407 -125.220276) (xy 200.61892 -125.267826) (xy 200.57654 -125.310206) (xy 200.52899 -125.346693)
			(xy 200.477084 -125.37666) (xy 200.421711 -125.399596) (xy 200.363818 -125.415109) (xy 200.304396 -125.422932)
			(xy 200.24446 -125.422932) (xy 200.185038 -125.415109) (xy 200.127145 -125.399596) (xy 200.071772 -125.37666)
			(xy 200.019866 -125.346693) (xy 199.972316 -125.310206) (xy 199.929936 -125.267826) (xy 199.893449 -125.220276)
			(xy 199.863482 -125.16837) (xy 199.840546 -125.112997) (xy 199.825033 -125.055104) (xy 199.81721 -124.995682)
			(xy 199.81672 -124.965714) (xy 181.760876 -124.965714) (xy 181.760876 -124.967238) (xy 181.760386 -124.997206)
			(xy 181.752563 -125.056628) (xy 181.73705 -125.114521) (xy 181.714114 -125.169894) (xy 181.684147 -125.2218)
			(xy 181.64766 -125.26935) (xy 181.60528 -125.31173) (xy 181.55773 -125.348217) (xy 181.505824 -125.378184)
			(xy 181.450451 -125.40112) (xy 181.392558 -125.416633) (xy 181.333136 -125.424456) (xy 181.2732 -125.424456)
			(xy 181.213778 -125.416633) (xy 181.155885 -125.40112) (xy 181.100512 -125.378184) (xy 181.048606 -125.348217)
			(xy 181.001056 -125.31173) (xy 180.958676 -125.26935) (xy 180.922189 -125.2218) (xy 180.892222 -125.169894)
			(xy 180.869286 -125.114521) (xy 180.853773 -125.056628) (xy 180.84595 -124.997206) (xy 180.84546 -124.967238)
			(xy 168.80078 -124.967238) (xy 168.80078 -125.486414) (xy 168.800647 -125.494542) (xy 269.509748 -125.494542)
			(xy 269.509748 -124.630942) (xy 269.510238 -124.600958) (xy 269.518066 -124.541502) (xy 269.533587 -124.483577)
			(xy 269.556536 -124.428173) (xy 269.58652 -124.376239) (xy 269.623026 -124.328663) (xy 269.665431 -124.286258)
			(xy 269.713007 -124.249752) (xy 269.764941 -124.219768) (xy 269.820345 -124.196819) (xy 269.87827 -124.181298)
			(xy 269.937726 -124.17347) (xy 269.997694 -124.17347) (xy 270.05715 -124.181298) (xy 270.115075 -124.196819)
			(xy 270.170479 -124.219768) (xy 270.222413 -124.249752) (xy 270.269989 -124.286258) (xy 270.312394 -124.328663)
			(xy 270.3489 -124.376239) (xy 270.378884 -124.428173) (xy 270.401833 -124.483577) (xy 270.417354 -124.541502)
			(xy 270.425182 -124.600958) (xy 270.425672 -124.630942) (xy 270.425672 -125.486414) (xy 283.9847 -125.486414)
			(xy 283.9847 -124.622814) (xy 283.98519 -124.59283) (xy 283.993018 -124.533374) (xy 284.008539 -124.475449)
			(xy 284.031488 -124.420045) (xy 284.061472 -124.368111) (xy 284.097978 -124.320535) (xy 284.140383 -124.27813)
			(xy 284.187959 -124.241624) (xy 284.239893 -124.21164) (xy 284.295297 -124.188691) (xy 284.353222 -124.17317)
			(xy 284.412678 -124.165342) (xy 284.472646 -124.165342) (xy 284.532102 -124.17317) (xy 284.590027 -124.188691)
			(xy 284.645431 -124.21164) (xy 284.697365 -124.241624) (xy 284.744941 -124.27813) (xy 284.787346 -124.320535)
			(xy 284.823852 -124.368111) (xy 284.853836 -124.420045) (xy 284.876785 -124.475449) (xy 284.892306 -124.533374)
			(xy 284.900134 -124.59283) (xy 284.900624 -124.622814) (xy 284.900624 -124.967238) (xy 296.945304 -124.967238)
			(xy 296.945304 -124.103638) (xy 296.945794 -124.07367) (xy 296.953617 -124.014248) (xy 296.96913 -123.956355)
			(xy 296.992066 -123.900982) (xy 297.022033 -123.849076) (xy 297.05852 -123.801526) (xy 297.1009 -123.759146)
			(xy 297.14845 -123.722659) (xy 297.200356 -123.692692) (xy 297.255729 -123.669756) (xy 297.313622 -123.654243)
			(xy 297.373044 -123.64642) (xy 297.43298 -123.64642) (xy 297.492402 -123.654243) (xy 297.550295 -123.669756)
			(xy 297.605668 -123.692692) (xy 297.657574 -123.722659) (xy 297.705124 -123.759146) (xy 297.747504 -123.801526)
			(xy 297.783991 -123.849076) (xy 297.813958 -123.900982) (xy 297.836894 -123.956355) (xy 297.852407 -124.014248)
			(xy 297.86023 -124.07367) (xy 297.86072 -124.103638) (xy 297.86072 -124.965714) (xy 315.916564 -124.965714)
			(xy 315.916564 -124.102114) (xy 315.917054 -124.072146) (xy 315.924877 -124.012724) (xy 315.94039 -123.954831)
			(xy 315.963326 -123.899458) (xy 315.993293 -123.847552) (xy 316.02978 -123.800002) (xy 316.07216 -123.757622)
			(xy 316.11971 -123.721135) (xy 316.171616 -123.691168) (xy 316.226989 -123.668232) (xy 316.284882 -123.652719)
			(xy 316.344304 -123.644896) (xy 316.40424 -123.644896) (xy 316.463662 -123.652719) (xy 316.521555 -123.668232)
			(xy 316.568893 -123.68784) (xy 382.967992 -123.68784) (xy 382.967992 -122.82424) (xy 382.968482 -122.794272)
			(xy 382.976305 -122.73485) (xy 382.991818 -122.676957) (xy 383.014754 -122.621584) (xy 383.044721 -122.569678)
			(xy 383.081208 -122.522128) (xy 383.123588 -122.479748) (xy 383.171138 -122.443261) (xy 383.223044 -122.413294)
			(xy 383.278417 -122.390358) (xy 383.33631 -122.374845) (xy 383.395732 -122.367022) (xy 383.455668 -122.367022)
			(xy 383.51509 -122.374845) (xy 383.572983 -122.390358) (xy 383.628356 -122.413294) (xy 383.680262 -122.443261)
			(xy 383.727812 -122.479748) (xy 383.770192 -122.522128) (xy 383.806679 -122.569678) (xy 383.836646 -122.621584)
			(xy 383.859582 -122.676957) (xy 383.875095 -122.73485) (xy 383.882918 -122.794272) (xy 383.883408 -122.82424)
			(xy 383.883408 -123.686316) (xy 401.939252 -123.686316) (xy 401.939252 -122.822716) (xy 401.939742 -122.792748)
			(xy 401.947565 -122.733326) (xy 401.963078 -122.675433) (xy 401.986014 -122.62006) (xy 402.015981 -122.568154)
			(xy 402.052468 -122.520604) (xy 402.094848 -122.478224) (xy 402.142398 -122.441737) (xy 402.194304 -122.41177)
			(xy 402.249677 -122.388834) (xy 402.30757 -122.373321) (xy 402.366992 -122.365498) (xy 402.426928 -122.365498)
			(xy 402.48635 -122.373321) (xy 402.544243 -122.388834) (xy 402.599616 -122.41177) (xy 402.651522 -122.441737)
			(xy 402.699072 -122.478224) (xy 402.741452 -122.520604) (xy 402.777939 -122.568154) (xy 402.807906 -122.62006)
			(xy 402.830842 -122.675433) (xy 402.846355 -122.733326) (xy 402.854178 -122.792748) (xy 402.854668 -122.822716)
			(xy 402.854668 -123.16714) (xy 414.899348 -123.16714) (xy 414.899348 -122.30354) (xy 414.899838 -122.273556)
			(xy 414.907666 -122.2141) (xy 414.923187 -122.156175) (xy 414.946136 -122.100771) (xy 414.97612 -122.048837)
			(xy 415.012626 -122.001261) (xy 415.055031 -121.958856) (xy 415.102607 -121.92235) (xy 415.154541 -121.892366)
			(xy 415.209945 -121.869417) (xy 415.26787 -121.853896) (xy 415.327326 -121.846068) (xy 415.387294 -121.846068)
			(xy 415.44675 -121.853896) (xy 415.504675 -121.869417) (xy 415.560079 -121.892366) (xy 415.612013 -121.92235)
			(xy 415.659589 -121.958856) (xy 415.701994 -122.001261) (xy 415.7385 -122.048837) (xy 415.768484 -122.100771)
			(xy 415.791433 -122.156175) (xy 415.806954 -122.2141) (xy 415.814782 -122.273556) (xy 415.815272 -122.30354)
			(xy 415.815272 -123.159266) (xy 429.3743 -123.159266) (xy 429.3743 -122.295666) (xy 429.37479 -122.265682)
			(xy 429.382618 -122.206226) (xy 429.398139 -122.148301) (xy 429.421088 -122.092897) (xy 429.451072 -122.040963)
			(xy 429.487578 -121.993387) (xy 429.529983 -121.950982) (xy 429.577559 -121.914476) (xy 429.629493 -121.884492)
			(xy 429.684897 -121.861543) (xy 429.742822 -121.846022) (xy 429.802278 -121.838194) (xy 429.862246 -121.838194)
			(xy 429.921702 -121.846022) (xy 429.979627 -121.861543) (xy 430.035031 -121.884492) (xy 430.086965 -121.914476)
			(xy 430.134541 -121.950982) (xy 430.176946 -121.993387) (xy 430.213452 -122.040963) (xy 430.243436 -122.092897)
			(xy 430.266385 -122.148301) (xy 430.281906 -122.206226) (xy 430.289734 -122.265682) (xy 430.290224 -122.295666)
			(xy 430.290224 -123.159266) (xy 430.289734 -123.18925) (xy 430.281906 -123.248706) (xy 430.266385 -123.306631)
			(xy 430.243436 -123.362035) (xy 430.213452 -123.413969) (xy 430.176946 -123.461545) (xy 430.134541 -123.50395)
			(xy 430.086965 -123.540456) (xy 430.035031 -123.57044) (xy 429.979627 -123.593389) (xy 429.921702 -123.60891)
			(xy 429.862246 -123.616738) (xy 429.802278 -123.616738) (xy 429.742822 -123.60891) (xy 429.684897 -123.593389)
			(xy 429.629493 -123.57044) (xy 429.577559 -123.540456) (xy 429.529983 -123.50395) (xy 429.487578 -123.461545)
			(xy 429.451072 -123.413969) (xy 429.421088 -123.362035) (xy 429.398139 -123.306631) (xy 429.382618 -123.248706)
			(xy 429.37479 -123.18925) (xy 429.3743 -123.159266) (xy 415.815272 -123.159266) (xy 415.815272 -123.16714)
			(xy 415.814782 -123.197124) (xy 415.806954 -123.25658) (xy 415.791433 -123.314505) (xy 415.768484 -123.369909)
			(xy 415.7385 -123.421843) (xy 415.701994 -123.469419) (xy 415.659589 -123.511824) (xy 415.612013 -123.54833)
			(xy 415.560079 -123.578314) (xy 415.504675 -123.601263) (xy 415.44675 -123.616784) (xy 415.387294 -123.624612)
			(xy 415.327326 -123.624612) (xy 415.26787 -123.616784) (xy 415.209945 -123.601263) (xy 415.154541 -123.578314)
			(xy 415.102607 -123.54833) (xy 415.055031 -123.511824) (xy 415.012626 -123.469419) (xy 414.97612 -123.421843)
			(xy 414.946136 -123.369909) (xy 414.923187 -123.314505) (xy 414.907666 -123.25658) (xy 414.899838 -123.197124)
			(xy 414.899348 -123.16714) (xy 402.854668 -123.16714) (xy 402.854668 -123.686316) (xy 402.854178 -123.716284)
			(xy 402.846355 -123.775706) (xy 402.830842 -123.833599) (xy 402.807906 -123.888972) (xy 402.777939 -123.940878)
			(xy 402.741452 -123.988428) (xy 402.699072 -124.030808) (xy 402.651522 -124.067295) (xy 402.599616 -124.097262)
			(xy 402.544243 -124.120198) (xy 402.48635 -124.135711) (xy 402.426928 -124.143534) (xy 402.366992 -124.143534)
			(xy 402.30757 -124.135711) (xy 402.249677 -124.120198) (xy 402.194304 -124.097262) (xy 402.142398 -124.067295)
			(xy 402.094848 -124.030808) (xy 402.052468 -123.988428) (xy 402.015981 -123.940878) (xy 401.986014 -123.888972)
			(xy 401.963078 -123.833599) (xy 401.947565 -123.775706) (xy 401.939742 -123.716284) (xy 401.939252 -123.686316)
			(xy 383.883408 -123.686316) (xy 383.883408 -123.68784) (xy 383.882918 -123.717808) (xy 383.875095 -123.77723)
			(xy 383.859582 -123.835123) (xy 383.836646 -123.890496) (xy 383.806679 -123.942402) (xy 383.770192 -123.989952)
			(xy 383.727812 -124.032332) (xy 383.680262 -124.068819) (xy 383.628356 -124.098786) (xy 383.572983 -124.121722)
			(xy 383.51509 -124.137235) (xy 383.455668 -124.145058) (xy 383.395732 -124.145058) (xy 383.33631 -124.137235)
			(xy 383.278417 -124.121722) (xy 383.223044 -124.098786) (xy 383.171138 -124.068819) (xy 383.123588 -124.032332)
			(xy 383.081208 -123.989952) (xy 383.044721 -123.942402) (xy 383.014754 -123.890496) (xy 382.991818 -123.835123)
			(xy 382.976305 -123.77723) (xy 382.968482 -123.717808) (xy 382.967992 -123.68784) (xy 316.568893 -123.68784)
			(xy 316.576928 -123.691168) (xy 316.628834 -123.721135) (xy 316.676384 -123.757622) (xy 316.718764 -123.800002)
			(xy 316.755251 -123.847552) (xy 316.785218 -123.899458) (xy 316.808154 -123.954831) (xy 316.823667 -124.012724)
			(xy 316.83149 -124.072146) (xy 316.83198 -124.102114) (xy 316.83198 -124.965714) (xy 316.83149 -124.995682)
			(xy 316.823667 -125.055104) (xy 316.808154 -125.112997) (xy 316.785218 -125.16837) (xy 316.755251 -125.220276)
			(xy 316.718764 -125.267826) (xy 316.676384 -125.310206) (xy 316.628834 -125.346693) (xy 316.576928 -125.37666)
			(xy 316.521555 -125.399596) (xy 316.463662 -125.415109) (xy 316.40424 -125.422932) (xy 316.344304 -125.422932)
			(xy 316.284882 -125.415109) (xy 316.226989 -125.399596) (xy 316.171616 -125.37666) (xy 316.11971 -125.346693)
			(xy 316.07216 -125.310206) (xy 316.02978 -125.267826) (xy 315.993293 -125.220276) (xy 315.963326 -125.16837)
			(xy 315.94039 -125.112997) (xy 315.924877 -125.055104) (xy 315.917054 -124.995682) (xy 315.916564 -124.965714)
			(xy 297.86072 -124.965714) (xy 297.86072 -124.967238) (xy 297.86023 -124.997206) (xy 297.852407 -125.056628)
			(xy 297.836894 -125.114521) (xy 297.813958 -125.169894) (xy 297.783991 -125.2218) (xy 297.747504 -125.26935)
			(xy 297.705124 -125.31173) (xy 297.657574 -125.348217) (xy 297.605668 -125.378184) (xy 297.550295 -125.40112)
			(xy 297.492402 -125.416633) (xy 297.43298 -125.424456) (xy 297.373044 -125.424456) (xy 297.313622 -125.416633)
			(xy 297.255729 -125.40112) (xy 297.200356 -125.378184) (xy 297.14845 -125.348217) (xy 297.1009 -125.31173)
			(xy 297.05852 -125.26935) (xy 297.022033 -125.2218) (xy 296.992066 -125.169894) (xy 296.96913 -125.114521)
			(xy 296.953617 -125.056628) (xy 296.945794 -124.997206) (xy 296.945304 -124.967238) (xy 284.900624 -124.967238)
			(xy 284.900624 -125.486414) (xy 284.900491 -125.494542) (xy 385.6101 -125.494542) (xy 385.6101 -124.630942)
			(xy 385.61059 -124.600974) (xy 385.618413 -124.541552) (xy 385.633926 -124.483659) (xy 385.656862 -124.428286)
			(xy 385.686829 -124.37638) (xy 385.723316 -124.32883) (xy 385.765696 -124.28645) (xy 385.813246 -124.249963)
			(xy 385.865152 -124.219996) (xy 385.920525 -124.19706) (xy 385.978418 -124.181547) (xy 386.03784 -124.173724)
			(xy 386.097776 -124.173724) (xy 386.157198 -124.181547) (xy 386.215091 -124.19706) (xy 386.270464 -124.219996)
			(xy 386.32237 -124.249963) (xy 386.36992 -124.28645) (xy 386.4123 -124.32883) (xy 386.448787 -124.37638)
			(xy 386.478754 -124.428286) (xy 386.50169 -124.483659) (xy 386.517203 -124.541552) (xy 386.525026 -124.600974)
			(xy 386.525516 -124.630942) (xy 386.525516 -125.486414) (xy 400.085052 -125.486414) (xy 400.085052 -124.622814)
			(xy 400.085542 -124.592846) (xy 400.093365 -124.533424) (xy 400.108878 -124.475531) (xy 400.131814 -124.420158)
			(xy 400.161781 -124.368252) (xy 400.198268 -124.320702) (xy 400.240648 -124.278322) (xy 400.288198 -124.241835)
			(xy 400.340104 -124.211868) (xy 400.395477 -124.188932) (xy 400.45337 -124.173419) (xy 400.512792 -124.165596)
			(xy 400.572728 -124.165596) (xy 400.63215 -124.173419) (xy 400.690043 -124.188932) (xy 400.745416 -124.211868)
			(xy 400.797322 -124.241835) (xy 400.844872 -124.278322) (xy 400.887252 -124.320702) (xy 400.923739 -124.368252)
			(xy 400.953706 -124.420158) (xy 400.976642 -124.475531) (xy 400.992155 -124.533424) (xy 400.999978 -124.592846)
			(xy 401.000468 -124.622814) (xy 401.000468 -124.967238) (xy 413.045148 -124.967238) (xy 413.045148 -124.103638)
			(xy 413.045638 -124.073654) (xy 413.053466 -124.014198) (xy 413.068987 -123.956273) (xy 413.091936 -123.900869)
			(xy 413.12192 -123.848935) (xy 413.158426 -123.801359) (xy 413.200831 -123.758954) (xy 413.248407 -123.722448)
			(xy 413.300341 -123.692464) (xy 413.355745 -123.669515) (xy 413.41367 -123.653994) (xy 413.473126 -123.646166)
			(xy 413.533094 -123.646166) (xy 413.59255 -123.653994) (xy 413.650475 -123.669515) (xy 413.705879 -123.692464)
			(xy 413.757813 -123.722448) (xy 413.805389 -123.758954) (xy 413.847794 -123.801359) (xy 413.8843 -123.848935)
			(xy 413.914284 -123.900869) (xy 413.937233 -123.956273) (xy 413.952754 -124.014198) (xy 413.960582 -124.073654)
			(xy 413.961072 -124.103638) (xy 413.961072 -124.965714) (xy 432.016408 -124.965714) (xy 432.016408 -124.102114)
			(xy 432.016898 -124.07213) (xy 432.024726 -124.012674) (xy 432.040247 -123.954749) (xy 432.063196 -123.899345)
			(xy 432.09318 -123.847411) (xy 432.129686 -123.799835) (xy 432.172091 -123.75743) (xy 432.219667 -123.720924)
			(xy 432.271601 -123.69094) (xy 432.327005 -123.667991) (xy 432.38493 -123.65247) (xy 432.444386 -123.644642)
			(xy 432.504354 -123.644642) (xy 432.56381 -123.65247) (xy 432.621735 -123.667991) (xy 432.677139 -123.69094)
			(xy 432.729073 -123.720924) (xy 432.776649 -123.75743) (xy 432.819054 -123.799835) (xy 432.85556 -123.847411)
			(xy 432.885544 -123.899345) (xy 432.908493 -123.954749) (xy 432.924014 -124.012674) (xy 432.931842 -124.07213)
			(xy 432.932332 -124.102114) (xy 432.932332 -124.965714) (xy 432.931842 -124.995698) (xy 432.924014 -125.055154)
			(xy 432.908493 -125.113079) (xy 432.885544 -125.168483) (xy 432.85556 -125.220417) (xy 432.819054 -125.267993)
			(xy 432.776649 -125.310398) (xy 432.729073 -125.346904) (xy 432.677139 -125.376888) (xy 432.621735 -125.399837)
			(xy 432.56381 -125.415358) (xy 432.504354 -125.423186) (xy 432.444386 -125.423186) (xy 432.38493 -125.415358)
			(xy 432.327005 -125.399837) (xy 432.271601 -125.376888) (xy 432.219667 -125.346904) (xy 432.172091 -125.310398)
			(xy 432.129686 -125.267993) (xy 432.09318 -125.220417) (xy 432.063196 -125.168483) (xy 432.040247 -125.113079)
			(xy 432.024726 -125.055154) (xy 432.016898 -124.995698) (xy 432.016408 -124.965714) (xy 413.961072 -124.965714)
			(xy 413.961072 -124.967238) (xy 413.960582 -124.997222) (xy 413.952754 -125.056678) (xy 413.937233 -125.114603)
			(xy 413.914284 -125.170007) (xy 413.8843 -125.221941) (xy 413.847794 -125.269517) (xy 413.805389 -125.311922)
			(xy 413.757813 -125.348428) (xy 413.705879 -125.378412) (xy 413.650475 -125.401361) (xy 413.59255 -125.416882)
			(xy 413.533094 -125.42471) (xy 413.473126 -125.42471) (xy 413.41367 -125.416882) (xy 413.355745 -125.401361)
			(xy 413.300341 -125.378412) (xy 413.248407 -125.348428) (xy 413.200831 -125.311922) (xy 413.158426 -125.269517)
			(xy 413.12192 -125.221941) (xy 413.091936 -125.170007) (xy 413.068987 -125.114603) (xy 413.053466 -125.056678)
			(xy 413.045638 -124.997222) (xy 413.045148 -124.967238) (xy 401.000468 -124.967238) (xy 401.000468 -125.486414)
			(xy 400.999978 -125.516382) (xy 400.992155 -125.575804) (xy 400.976642 -125.633697) (xy 400.953706 -125.68907)
			(xy 400.923739 -125.740976) (xy 400.887252 -125.788526) (xy 400.844872 -125.830906) (xy 400.797322 -125.867393)
			(xy 400.745416 -125.89736) (xy 400.690043 -125.920296) (xy 400.63215 -125.935809) (xy 400.572728 -125.943632)
			(xy 400.512792 -125.943632) (xy 400.45337 -125.935809) (xy 400.395477 -125.920296) (xy 400.340104 -125.89736)
			(xy 400.288198 -125.867393) (xy 400.240648 -125.830906) (xy 400.198268 -125.788526) (xy 400.161781 -125.740976)
			(xy 400.131814 -125.68907) (xy 400.108878 -125.633697) (xy 400.093365 -125.575804) (xy 400.085542 -125.516382)
			(xy 400.085052 -125.486414) (xy 386.525516 -125.486414) (xy 386.525516 -125.494542) (xy 386.525026 -125.52451)
			(xy 386.517203 -125.583932) (xy 386.50169 -125.641825) (xy 386.478754 -125.697198) (xy 386.448787 -125.749104)
			(xy 386.4123 -125.796654) (xy 386.36992 -125.839034) (xy 386.32237 -125.875521) (xy 386.270464 -125.905488)
			(xy 386.215091 -125.928424) (xy 386.157198 -125.943937) (xy 386.097776 -125.95176) (xy 386.03784 -125.95176)
			(xy 385.978418 -125.943937) (xy 385.920525 -125.928424) (xy 385.865152 -125.905488) (xy 385.813246 -125.875521)
			(xy 385.765696 -125.839034) (xy 385.723316 -125.796654) (xy 385.686829 -125.749104) (xy 385.656862 -125.697198)
			(xy 385.633926 -125.641825) (xy 385.618413 -125.583932) (xy 385.61059 -125.52451) (xy 385.6101 -125.494542)
			(xy 284.900491 -125.494542) (xy 284.900134 -125.516398) (xy 284.892306 -125.575854) (xy 284.876785 -125.633779)
			(xy 284.853836 -125.689183) (xy 284.823852 -125.741117) (xy 284.787346 -125.788693) (xy 284.744941 -125.831098)
			(xy 284.697365 -125.867604) (xy 284.645431 -125.897588) (xy 284.590027 -125.920537) (xy 284.532102 -125.936058)
			(xy 284.472646 -125.943886) (xy 284.412678 -125.943886) (xy 284.353222 -125.936058) (xy 284.295297 -125.920537)
			(xy 284.239893 -125.897588) (xy 284.187959 -125.867604) (xy 284.140383 -125.831098) (xy 284.097978 -125.788693)
			(xy 284.061472 -125.741117) (xy 284.031488 -125.689183) (xy 284.008539 -125.633779) (xy 283.993018 -125.575854)
			(xy 283.98519 -125.516398) (xy 283.9847 -125.486414) (xy 270.425672 -125.486414) (xy 270.425672 -125.494542)
			(xy 270.425182 -125.524526) (xy 270.417354 -125.583982) (xy 270.401833 -125.641907) (xy 270.378884 -125.697311)
			(xy 270.3489 -125.749245) (xy 270.312394 -125.796821) (xy 270.269989 -125.839226) (xy 270.222413 -125.875732)
			(xy 270.170479 -125.905716) (xy 270.115075 -125.928665) (xy 270.05715 -125.944186) (xy 269.997694 -125.952014)
			(xy 269.937726 -125.952014) (xy 269.87827 -125.944186) (xy 269.820345 -125.928665) (xy 269.764941 -125.905716)
			(xy 269.713007 -125.875732) (xy 269.665431 -125.839226) (xy 269.623026 -125.796821) (xy 269.58652 -125.749245)
			(xy 269.556536 -125.697311) (xy 269.533587 -125.641907) (xy 269.518066 -125.583982) (xy 269.510238 -125.524526)
			(xy 269.509748 -125.494542) (xy 168.800647 -125.494542) (xy 168.80029 -125.516398) (xy 168.792462 -125.575854)
			(xy 168.776941 -125.633779) (xy 168.753992 -125.689183) (xy 168.724008 -125.741117) (xy 168.687502 -125.788693)
			(xy 168.645097 -125.831098) (xy 168.597521 -125.867604) (xy 168.545587 -125.897588) (xy 168.490183 -125.920537)
			(xy 168.432258 -125.936058) (xy 168.372802 -125.943886) (xy 168.312834 -125.943886) (xy 168.253378 -125.936058)
			(xy 168.195453 -125.920537) (xy 168.140049 -125.897588) (xy 168.088115 -125.867604) (xy 168.040539 -125.831098)
			(xy 167.998134 -125.788693) (xy 167.961628 -125.741117) (xy 167.931644 -125.689183) (xy 167.908695 -125.633779)
			(xy 167.893174 -125.575854) (xy 167.885346 -125.516398) (xy 167.884856 -125.486414) (xy 154.325828 -125.486414)
			(xy 154.325828 -125.494542) (xy 154.325338 -125.524526) (xy 154.31751 -125.583982) (xy 154.301989 -125.641907)
			(xy 154.27904 -125.697311) (xy 154.249056 -125.749245) (xy 154.21255 -125.796821) (xy 154.170145 -125.839226)
			(xy 154.122569 -125.875732) (xy 154.070635 -125.905716) (xy 154.015231 -125.928665) (xy 153.957306 -125.944186)
			(xy 153.89785 -125.952014) (xy 153.837882 -125.952014) (xy 153.778426 -125.944186) (xy 153.720501 -125.928665)
			(xy 153.665097 -125.905716) (xy 153.613163 -125.875732) (xy 153.565587 -125.839226) (xy 153.523182 -125.796821)
			(xy 153.486676 -125.749245) (xy 153.456692 -125.697311) (xy 153.433743 -125.641907) (xy 153.418222 -125.583982)
			(xy 153.410394 -125.524526) (xy 153.409904 -125.494542) (xy 52.700295 -125.494542) (xy 52.699938 -125.516382)
			(xy 52.692115 -125.575804) (xy 52.676602 -125.633697) (xy 52.653666 -125.68907) (xy 52.623699 -125.740976)
			(xy 52.587212 -125.788526) (xy 52.544832 -125.830906) (xy 52.497282 -125.867393) (xy 52.445376 -125.89736)
			(xy 52.390003 -125.920296) (xy 52.33211 -125.935809) (xy 52.272688 -125.943632) (xy 52.212752 -125.943632)
			(xy 52.15333 -125.935809) (xy 52.095437 -125.920296) (xy 52.040064 -125.89736) (xy 51.988158 -125.867393)
			(xy 51.940608 -125.830906) (xy 51.898228 -125.788526) (xy 51.861741 -125.740976) (xy 51.831774 -125.68907)
			(xy 51.808838 -125.633697) (xy 51.793325 -125.575804) (xy 51.785502 -125.516382) (xy 51.785012 -125.486414)
			(xy 38.225476 -125.486414) (xy 38.225476 -125.494542) (xy 38.224986 -125.52451) (xy 38.217163 -125.583932)
			(xy 38.20165 -125.641825) (xy 38.178714 -125.697198) (xy 38.148747 -125.749104) (xy 38.11226 -125.796654)
			(xy 38.06988 -125.839034) (xy 38.02233 -125.875521) (xy 37.970424 -125.905488) (xy 37.915051 -125.928424)
			(xy 37.857158 -125.943937) (xy 37.797736 -125.95176) (xy 37.7378 -125.95176) (xy 37.678378 -125.943937)
			(xy 37.620485 -125.928424) (xy 37.565112 -125.905488) (xy 37.513206 -125.875521) (xy 37.465656 -125.839034)
			(xy 37.423276 -125.796654) (xy 37.386789 -125.749104) (xy 37.356822 -125.697198) (xy 37.333886 -125.641825)
			(xy 37.318373 -125.583932) (xy 37.31055 -125.52451) (xy 37.31006 -125.494542) (xy 4.30911 -125.494542)
			(xy 4.30911 -131.297934) (xy 34.667952 -131.297934) (xy 34.667952 -130.434334) (xy 34.668442 -130.404366)
			(xy 34.676265 -130.344944) (xy 34.691778 -130.287051) (xy 34.714714 -130.231678) (xy 34.744681 -130.179772)
			(xy 34.781168 -130.132222) (xy 34.823548 -130.089842) (xy 34.871098 -130.053355) (xy 34.923004 -130.023388)
			(xy 34.978377 -130.000452) (xy 35.03627 -129.984939) (xy 35.095692 -129.977116) (xy 35.155628 -129.977116)
			(xy 35.21505 -129.984939) (xy 35.272943 -130.000452) (xy 35.328316 -130.023388) (xy 35.380222 -130.053355)
			(xy 35.427772 -130.089842) (xy 35.470152 -130.132222) (xy 35.506639 -130.179772) (xy 35.536606 -130.231678)
			(xy 35.559542 -130.287051) (xy 35.575055 -130.344944) (xy 35.582878 -130.404366) (xy 35.583368 -130.434334)
			(xy 35.583368 -131.29641) (xy 53.639212 -131.29641) (xy 53.639212 -130.43281) (xy 53.639702 -130.402842)
			(xy 53.647525 -130.34342) (xy 53.663038 -130.285527) (xy 53.685974 -130.230154) (xy 53.715941 -130.178248)
			(xy 53.752428 -130.130698) (xy 53.794808 -130.088318) (xy 53.842358 -130.051831) (xy 53.894264 -130.021864)
			(xy 53.949637 -129.998928) (xy 54.00753 -129.983415) (xy 54.066952 -129.975592) (xy 54.126888 -129.975592)
			(xy 54.18631 -129.983415) (xy 54.244203 -129.998928) (xy 54.299576 -130.021864) (xy 54.351482 -130.051831)
			(xy 54.399032 -130.088318) (xy 54.441412 -130.130698) (xy 54.477899 -130.178248) (xy 54.507866 -130.230154)
			(xy 54.530802 -130.285527) (xy 54.546315 -130.34342) (xy 54.554138 -130.402842) (xy 54.554628 -130.43281)
			(xy 54.554628 -130.777234) (xy 66.599308 -130.777234) (xy 66.599308 -129.913634) (xy 66.599798 -129.88365)
			(xy 66.607626 -129.824194) (xy 66.623147 -129.766269) (xy 66.646096 -129.710865) (xy 66.67608 -129.658931)
			(xy 66.712586 -129.611355) (xy 66.754991 -129.56895) (xy 66.802567 -129.532444) (xy 66.854501 -129.50246)
			(xy 66.909905 -129.479511) (xy 66.96783 -129.46399) (xy 67.027286 -129.456162) (xy 67.087254 -129.456162)
			(xy 67.14671 -129.46399) (xy 67.204635 -129.479511) (xy 67.260039 -129.50246) (xy 67.311973 -129.532444)
			(xy 67.359549 -129.56895) (xy 67.401954 -129.611355) (xy 67.43846 -129.658931) (xy 67.468444 -129.710865)
			(xy 67.491393 -129.766269) (xy 67.506914 -129.824194) (xy 67.514742 -129.88365) (xy 67.515232 -129.913634)
			(xy 67.515232 -130.769106) (xy 81.07426 -130.769106) (xy 81.07426 -129.905506) (xy 81.07475 -129.875522)
			(xy 81.082578 -129.816066) (xy 81.098099 -129.758141) (xy 81.121048 -129.702737) (xy 81.151032 -129.650803)
			(xy 81.187538 -129.603227) (xy 81.229943 -129.560822) (xy 81.277519 -129.524316) (xy 81.329453 -129.494332)
			(xy 81.384857 -129.471383) (xy 81.442782 -129.455862) (xy 81.502238 -129.448034) (xy 81.562206 -129.448034)
			(xy 81.621662 -129.455862) (xy 81.679587 -129.471383) (xy 81.734991 -129.494332) (xy 81.786925 -129.524316)
			(xy 81.834501 -129.560822) (xy 81.876906 -129.603227) (xy 81.913412 -129.650803) (xy 81.943396 -129.702737)
			(xy 81.966345 -129.758141) (xy 81.981866 -129.816066) (xy 81.989694 -129.875522) (xy 81.990184 -129.905506)
			(xy 81.990184 -130.769106) (xy 81.989694 -130.79909) (xy 81.981866 -130.858546) (xy 81.966345 -130.916471)
			(xy 81.943396 -130.971875) (xy 81.913412 -131.023809) (xy 81.876906 -131.071385) (xy 81.834501 -131.11379)
			(xy 81.786925 -131.150296) (xy 81.734991 -131.18028) (xy 81.679587 -131.203229) (xy 81.621662 -131.21875)
			(xy 81.562206 -131.226578) (xy 81.502238 -131.226578) (xy 81.442782 -131.21875) (xy 81.384857 -131.203229)
			(xy 81.329453 -131.18028) (xy 81.277519 -131.150296) (xy 81.229943 -131.11379) (xy 81.187538 -131.071385)
			(xy 81.151032 -131.023809) (xy 81.121048 -130.971875) (xy 81.098099 -130.916471) (xy 81.082578 -130.858546)
			(xy 81.07475 -130.79909) (xy 81.07426 -130.769106) (xy 67.515232 -130.769106) (xy 67.515232 -130.777234)
			(xy 67.514742 -130.807218) (xy 67.506914 -130.866674) (xy 67.491393 -130.924599) (xy 67.468444 -130.980003)
			(xy 67.43846 -131.031937) (xy 67.401954 -131.079513) (xy 67.359549 -131.121918) (xy 67.311973 -131.158424)
			(xy 67.260039 -131.188408) (xy 67.204635 -131.211357) (xy 67.14671 -131.226878) (xy 67.087254 -131.234706)
			(xy 67.027286 -131.234706) (xy 66.96783 -131.226878) (xy 66.909905 -131.211357) (xy 66.854501 -131.188408)
			(xy 66.802567 -131.158424) (xy 66.754991 -131.121918) (xy 66.712586 -131.079513) (xy 66.67608 -131.031937)
			(xy 66.646096 -130.980003) (xy 66.623147 -130.924599) (xy 66.607626 -130.866674) (xy 66.599798 -130.807218)
			(xy 66.599308 -130.777234) (xy 54.554628 -130.777234) (xy 54.554628 -131.29641) (xy 54.554138 -131.326378)
			(xy 54.546315 -131.3858) (xy 54.530802 -131.443693) (xy 54.507866 -131.499066) (xy 54.477899 -131.550972)
			(xy 54.441412 -131.598522) (xy 54.399032 -131.640902) (xy 54.351482 -131.677389) (xy 54.299576 -131.707356)
			(xy 54.244203 -131.730292) (xy 54.18631 -131.745805) (xy 54.126888 -131.753628) (xy 54.066952 -131.753628)
			(xy 54.00753 -131.745805) (xy 53.949637 -131.730292) (xy 53.894264 -131.707356) (xy 53.842358 -131.677389)
			(xy 53.794808 -131.640902) (xy 53.752428 -131.598522) (xy 53.715941 -131.550972) (xy 53.685974 -131.499066)
			(xy 53.663038 -131.443693) (xy 53.647525 -131.3858) (xy 53.639702 -131.326378) (xy 53.639212 -131.29641)
			(xy 35.583368 -131.29641) (xy 35.583368 -131.297934) (xy 35.582878 -131.327902) (xy 35.575055 -131.387324)
			(xy 35.559542 -131.445217) (xy 35.536606 -131.50059) (xy 35.506639 -131.552496) (xy 35.470152 -131.600046)
			(xy 35.427772 -131.642426) (xy 35.380222 -131.678913) (xy 35.328316 -131.70888) (xy 35.272943 -131.731816)
			(xy 35.21505 -131.747329) (xy 35.155628 -131.755152) (xy 35.095692 -131.755152) (xy 35.03627 -131.747329)
			(xy 34.978377 -131.731816) (xy 34.923004 -131.70888) (xy 34.871098 -131.678913) (xy 34.823548 -131.642426)
			(xy 34.781168 -131.600046) (xy 34.744681 -131.552496) (xy 34.714714 -131.50059) (xy 34.691778 -131.445217)
			(xy 34.676265 -131.387324) (xy 34.668442 -131.327902) (xy 34.667952 -131.297934) (xy 4.30911 -131.297934)
			(xy 4.30911 -133.104382) (xy 37.31006 -133.104382) (xy 37.31006 -132.240782) (xy 37.31055 -132.210814)
			(xy 37.318373 -132.151392) (xy 37.333886 -132.093499) (xy 37.356822 -132.038126) (xy 37.386789 -131.98622)
			(xy 37.423276 -131.93867) (xy 37.465656 -131.89629) (xy 37.513206 -131.859803) (xy 37.565112 -131.829836)
			(xy 37.620485 -131.8069) (xy 37.678378 -131.791387) (xy 37.7378 -131.783564) (xy 37.797736 -131.783564)
			(xy 37.857158 -131.791387) (xy 37.915051 -131.8069) (xy 37.970424 -131.829836) (xy 38.02233 -131.859803)
			(xy 38.06988 -131.89629) (xy 38.11226 -131.93867) (xy 38.148747 -131.98622) (xy 38.178714 -132.038126)
			(xy 38.20165 -132.093499) (xy 38.217163 -132.151392) (xy 38.224986 -132.210814) (xy 38.225476 -132.240782)
			(xy 38.225476 -133.096508) (xy 51.785012 -133.096508) (xy 51.785012 -132.232908) (xy 51.785502 -132.20294)
			(xy 51.793325 -132.143518) (xy 51.808838 -132.085625) (xy 51.831774 -132.030252) (xy 51.861741 -131.978346)
			(xy 51.898228 -131.930796) (xy 51.940608 -131.888416) (xy 51.988158 -131.851929) (xy 52.040064 -131.821962)
			(xy 52.095437 -131.799026) (xy 52.15333 -131.783513) (xy 52.212752 -131.77569) (xy 52.272688 -131.77569)
			(xy 52.33211 -131.783513) (xy 52.390003 -131.799026) (xy 52.445376 -131.821962) (xy 52.497282 -131.851929)
			(xy 52.544832 -131.888416) (xy 52.587212 -131.930796) (xy 52.623699 -131.978346) (xy 52.653666 -132.030252)
			(xy 52.676602 -132.085625) (xy 52.692115 -132.143518) (xy 52.699938 -132.20294) (xy 52.700428 -132.232908)
			(xy 52.700428 -132.577332) (xy 64.745108 -132.577332) (xy 64.745108 -131.713732) (xy 64.745598 -131.683748)
			(xy 64.753426 -131.624292) (xy 64.768947 -131.566367) (xy 64.791896 -131.510963) (xy 64.82188 -131.459029)
			(xy 64.858386 -131.411453) (xy 64.900791 -131.369048) (xy 64.948367 -131.332542) (xy 65.000301 -131.302558)
			(xy 65.055705 -131.279609) (xy 65.11363 -131.264088) (xy 65.173086 -131.25626) (xy 65.233054 -131.25626)
			(xy 65.29251 -131.264088) (xy 65.350435 -131.279609) (xy 65.405839 -131.302558) (xy 65.457773 -131.332542)
			(xy 65.505349 -131.369048) (xy 65.547754 -131.411453) (xy 65.58426 -131.459029) (xy 65.614244 -131.510963)
			(xy 65.637193 -131.566367) (xy 65.652714 -131.624292) (xy 65.660542 -131.683748) (xy 65.661032 -131.713732)
			(xy 65.661032 -132.575808) (xy 83.716368 -132.575808) (xy 83.716368 -131.712208) (xy 83.716858 -131.682224)
			(xy 83.724686 -131.622768) (xy 83.740207 -131.564843) (xy 83.763156 -131.509439) (xy 83.79314 -131.457505)
			(xy 83.829646 -131.409929) (xy 83.872051 -131.367524) (xy 83.919627 -131.331018) (xy 83.971561 -131.301034)
			(xy 84.026965 -131.278085) (xy 84.08489 -131.262564) (xy 84.144346 -131.254736) (xy 84.204314 -131.254736)
			(xy 84.26377 -131.262564) (xy 84.321695 -131.278085) (xy 84.369615 -131.297934) (xy 150.767796 -131.297934)
			(xy 150.767796 -130.434334) (xy 150.768286 -130.40435) (xy 150.776114 -130.344894) (xy 150.791635 -130.286969)
			(xy 150.814584 -130.231565) (xy 150.844568 -130.179631) (xy 150.881074 -130.132055) (xy 150.923479 -130.08965)
			(xy 150.971055 -130.053144) (xy 151.022989 -130.02316) (xy 151.078393 -130.000211) (xy 151.136318 -129.98469)
			(xy 151.195774 -129.976862) (xy 151.255742 -129.976862) (xy 151.315198 -129.98469) (xy 151.373123 -130.000211)
			(xy 151.428527 -130.02316) (xy 151.480461 -130.053144) (xy 151.528037 -130.08965) (xy 151.570442 -130.132055)
			(xy 151.606948 -130.179631) (xy 151.636932 -130.231565) (xy 151.659881 -130.286969) (xy 151.675402 -130.344894)
			(xy 151.68323 -130.40435) (xy 151.68372 -130.434334) (xy 151.68372 -131.29641) (xy 169.739056 -131.29641)
			(xy 169.739056 -130.43281) (xy 169.739546 -130.402826) (xy 169.747374 -130.34337) (xy 169.762895 -130.285445)
			(xy 169.785844 -130.230041) (xy 169.815828 -130.178107) (xy 169.852334 -130.130531) (xy 169.894739 -130.088126)
			(xy 169.942315 -130.05162) (xy 169.994249 -130.021636) (xy 170.049653 -129.998687) (xy 170.107578 -129.983166)
			(xy 170.167034 -129.975338) (xy 170.227002 -129.975338) (xy 170.286458 -129.983166) (xy 170.344383 -129.998687)
			(xy 170.399787 -130.021636) (xy 170.451721 -130.05162) (xy 170.499297 -130.088126) (xy 170.541702 -130.130531)
			(xy 170.578208 -130.178107) (xy 170.608192 -130.230041) (xy 170.631141 -130.285445) (xy 170.646662 -130.34337)
			(xy 170.65449 -130.402826) (xy 170.65498 -130.43281) (xy 170.65498 -130.777234) (xy 182.69966 -130.777234)
			(xy 182.69966 -129.913634) (xy 182.70015 -129.883666) (xy 182.707973 -129.824244) (xy 182.723486 -129.766351)
			(xy 182.746422 -129.710978) (xy 182.776389 -129.659072) (xy 182.812876 -129.611522) (xy 182.855256 -129.569142)
			(xy 182.902806 -129.532655) (xy 182.954712 -129.502688) (xy 183.010085 -129.479752) (xy 183.067978 -129.464239)
			(xy 183.1274 -129.456416) (xy 183.187336 -129.456416) (xy 183.246758 -129.464239) (xy 183.304651 -129.479752)
			(xy 183.360024 -129.502688) (xy 183.41193 -129.532655) (xy 183.45948 -129.569142) (xy 183.50186 -129.611522)
			(xy 183.538347 -129.659072) (xy 183.568314 -129.710978) (xy 183.59125 -129.766351) (xy 183.606763 -129.824244)
			(xy 183.614586 -129.883666) (xy 183.615076 -129.913634) (xy 183.615076 -130.769106) (xy 197.174612 -130.769106)
			(xy 197.174612 -129.905506) (xy 197.175102 -129.875538) (xy 197.182925 -129.816116) (xy 197.198438 -129.758223)
			(xy 197.221374 -129.70285) (xy 197.251341 -129.650944) (xy 197.287828 -129.603394) (xy 197.330208 -129.561014)
			(xy 197.377758 -129.524527) (xy 197.429664 -129.49456) (xy 197.485037 -129.471624) (xy 197.54293 -129.456111)
			(xy 197.602352 -129.448288) (xy 197.662288 -129.448288) (xy 197.72171 -129.456111) (xy 197.779603 -129.471624)
			(xy 197.834976 -129.49456) (xy 197.886882 -129.524527) (xy 197.934432 -129.561014) (xy 197.976812 -129.603394)
			(xy 198.013299 -129.650944) (xy 198.043266 -129.70285) (xy 198.066202 -129.758223) (xy 198.081715 -129.816116)
			(xy 198.089538 -129.875538) (xy 198.090028 -129.905506) (xy 198.090028 -130.769106) (xy 198.089538 -130.799074)
			(xy 198.081715 -130.858496) (xy 198.066202 -130.916389) (xy 198.043266 -130.971762) (xy 198.013299 -131.023668)
			(xy 197.976812 -131.071218) (xy 197.934432 -131.113598) (xy 197.886882 -131.150085) (xy 197.834976 -131.180052)
			(xy 197.779603 -131.202988) (xy 197.72171 -131.218501) (xy 197.662288 -131.226324) (xy 197.602352 -131.226324)
			(xy 197.54293 -131.218501) (xy 197.485037 -131.202988) (xy 197.429664 -131.180052) (xy 197.377758 -131.150085)
			(xy 197.330208 -131.113598) (xy 197.287828 -131.071218) (xy 197.251341 -131.023668) (xy 197.221374 -130.971762)
			(xy 197.198438 -130.916389) (xy 197.182925 -130.858496) (xy 197.175102 -130.799074) (xy 197.174612 -130.769106)
			(xy 183.615076 -130.769106) (xy 183.615076 -130.777234) (xy 183.614586 -130.807202) (xy 183.606763 -130.866624)
			(xy 183.59125 -130.924517) (xy 183.568314 -130.97989) (xy 183.538347 -131.031796) (xy 183.50186 -131.079346)
			(xy 183.45948 -131.121726) (xy 183.41193 -131.158213) (xy 183.360024 -131.18818) (xy 183.304651 -131.211116)
			(xy 183.246758 -131.226629) (xy 183.187336 -131.234452) (xy 183.1274 -131.234452) (xy 183.067978 -131.226629)
			(xy 183.010085 -131.211116) (xy 182.954712 -131.18818) (xy 182.902806 -131.158213) (xy 182.855256 -131.121726)
			(xy 182.812876 -131.079346) (xy 182.776389 -131.031796) (xy 182.746422 -130.97989) (xy 182.723486 -130.924517)
			(xy 182.707973 -130.866624) (xy 182.70015 -130.807202) (xy 182.69966 -130.777234) (xy 170.65498 -130.777234)
			(xy 170.65498 -131.29641) (xy 170.65449 -131.326394) (xy 170.646662 -131.38585) (xy 170.631141 -131.443775)
			(xy 170.608192 -131.499179) (xy 170.578208 -131.551113) (xy 170.541702 -131.598689) (xy 170.499297 -131.641094)
			(xy 170.451721 -131.6776) (xy 170.399787 -131.707584) (xy 170.344383 -131.730533) (xy 170.286458 -131.746054)
			(xy 170.227002 -131.753882) (xy 170.167034 -131.753882) (xy 170.107578 -131.746054) (xy 170.049653 -131.730533)
			(xy 169.994249 -131.707584) (xy 169.942315 -131.6776) (xy 169.894739 -131.641094) (xy 169.852334 -131.598689)
			(xy 169.815828 -131.551113) (xy 169.785844 -131.499179) (xy 169.762895 -131.443775) (xy 169.747374 -131.38585)
			(xy 169.739546 -131.326394) (xy 169.739056 -131.29641) (xy 151.68372 -131.29641) (xy 151.68372 -131.297934)
			(xy 151.68323 -131.327918) (xy 151.675402 -131.387374) (xy 151.659881 -131.445299) (xy 151.636932 -131.500703)
			(xy 151.606948 -131.552637) (xy 151.570442 -131.600213) (xy 151.528037 -131.642618) (xy 151.480461 -131.679124)
			(xy 151.428527 -131.709108) (xy 151.373123 -131.732057) (xy 151.315198 -131.747578) (xy 151.255742 -131.755406)
			(xy 151.195774 -131.755406) (xy 151.136318 -131.747578) (xy 151.078393 -131.732057) (xy 151.022989 -131.709108)
			(xy 150.971055 -131.679124) (xy 150.923479 -131.642618) (xy 150.881074 -131.600213) (xy 150.844568 -131.552637)
			(xy 150.814584 -131.500703) (xy 150.791635 -131.445299) (xy 150.776114 -131.387374) (xy 150.768286 -131.327918)
			(xy 150.767796 -131.297934) (xy 84.369615 -131.297934) (xy 84.377099 -131.301034) (xy 84.429033 -131.331018)
			(xy 84.476609 -131.367524) (xy 84.519014 -131.409929) (xy 84.55552 -131.457505) (xy 84.585504 -131.509439)
			(xy 84.608453 -131.564843) (xy 84.623974 -131.622768) (xy 84.631802 -131.682224) (xy 84.632292 -131.712208)
			(xy 84.632292 -132.575808) (xy 84.631802 -132.605792) (xy 84.623974 -132.665248) (xy 84.608453 -132.723173)
			(xy 84.585504 -132.778577) (xy 84.55552 -132.830511) (xy 84.519014 -132.878087) (xy 84.476609 -132.920492)
			(xy 84.429033 -132.956998) (xy 84.377099 -132.986982) (xy 84.321695 -133.009931) (xy 84.26377 -133.025452)
			(xy 84.204314 -133.03328) (xy 84.144346 -133.03328) (xy 84.08489 -133.025452) (xy 84.026965 -133.009931)
			(xy 83.971561 -132.986982) (xy 83.919627 -132.956998) (xy 83.872051 -132.920492) (xy 83.829646 -132.878087)
			(xy 83.79314 -132.830511) (xy 83.763156 -132.778577) (xy 83.740207 -132.723173) (xy 83.724686 -132.665248)
			(xy 83.716858 -132.605792) (xy 83.716368 -132.575808) (xy 65.661032 -132.575808) (xy 65.661032 -132.577332)
			(xy 65.660542 -132.607316) (xy 65.652714 -132.666772) (xy 65.637193 -132.724697) (xy 65.614244 -132.780101)
			(xy 65.58426 -132.832035) (xy 65.547754 -132.879611) (xy 65.505349 -132.922016) (xy 65.457773 -132.958522)
			(xy 65.405839 -132.988506) (xy 65.350435 -133.011455) (xy 65.29251 -133.026976) (xy 65.233054 -133.034804)
			(xy 65.173086 -133.034804) (xy 65.11363 -133.026976) (xy 65.055705 -133.011455) (xy 65.000301 -132.988506)
			(xy 64.948367 -132.958522) (xy 64.900791 -132.922016) (xy 64.858386 -132.879611) (xy 64.82188 -132.832035)
			(xy 64.791896 -132.780101) (xy 64.768947 -132.724697) (xy 64.753426 -132.666772) (xy 64.745598 -132.607316)
			(xy 64.745108 -132.577332) (xy 52.700428 -132.577332) (xy 52.700428 -133.096508) (xy 52.699938 -133.126476)
			(xy 52.692115 -133.185898) (xy 52.676602 -133.243791) (xy 52.653666 -133.299164) (xy 52.623699 -133.35107)
			(xy 52.587212 -133.39862) (xy 52.544832 -133.441) (xy 52.497282 -133.477487) (xy 52.445376 -133.507454)
			(xy 52.390003 -133.53039) (xy 52.33211 -133.545903) (xy 52.272688 -133.553726) (xy 52.212752 -133.553726)
			(xy 52.15333 -133.545903) (xy 52.095437 -133.53039) (xy 52.040064 -133.507454) (xy 51.988158 -133.477487)
			(xy 51.940608 -133.441) (xy 51.898228 -133.39862) (xy 51.861741 -133.35107) (xy 51.831774 -133.299164)
			(xy 51.808838 -133.243791) (xy 51.793325 -133.185898) (xy 51.785502 -133.126476) (xy 51.785012 -133.096508)
			(xy 38.225476 -133.096508) (xy 38.225476 -133.104382) (xy 38.224986 -133.13435) (xy 38.217163 -133.193772)
			(xy 38.20165 -133.251665) (xy 38.178714 -133.307038) (xy 38.148747 -133.358944) (xy 38.11226 -133.406494)
			(xy 38.06988 -133.448874) (xy 38.02233 -133.485361) (xy 37.970424 -133.515328) (xy 37.915051 -133.538264)
			(xy 37.857158 -133.553777) (xy 37.797736 -133.5616) (xy 37.7378 -133.5616) (xy 37.678378 -133.553777)
			(xy 37.620485 -133.538264) (xy 37.565112 -133.515328) (xy 37.513206 -133.485361) (xy 37.465656 -133.448874)
			(xy 37.423276 -133.406494) (xy 37.386789 -133.358944) (xy 37.356822 -133.307038) (xy 37.333886 -133.251665)
			(xy 37.318373 -133.193772) (xy 37.31055 -133.13435) (xy 37.31006 -133.104382) (xy 4.30911 -133.104382)
			(xy 4.30911 -134.897876) (xy 34.667952 -134.897876) (xy 34.667952 -134.034276) (xy 34.668442 -134.004308)
			(xy 34.676265 -133.944886) (xy 34.691778 -133.886993) (xy 34.714714 -133.83162) (xy 34.744681 -133.779714)
			(xy 34.781168 -133.732164) (xy 34.823548 -133.689784) (xy 34.871098 -133.653297) (xy 34.923004 -133.62333)
			(xy 34.978377 -133.600394) (xy 35.03627 -133.584881) (xy 35.095692 -133.577058) (xy 35.155628 -133.577058)
			(xy 35.21505 -133.584881) (xy 35.272943 -133.600394) (xy 35.328316 -133.62333) (xy 35.380222 -133.653297)
			(xy 35.427772 -133.689784) (xy 35.470152 -133.732164) (xy 35.506639 -133.779714) (xy 35.536606 -133.83162)
			(xy 35.559542 -133.886993) (xy 35.575055 -133.944886) (xy 35.582878 -134.004308) (xy 35.583368 -134.034276)
			(xy 35.583368 -134.896352) (xy 53.639212 -134.896352) (xy 53.639212 -134.032752) (xy 53.639702 -134.002784)
			(xy 53.647525 -133.943362) (xy 53.663038 -133.885469) (xy 53.685974 -133.830096) (xy 53.715941 -133.77819)
			(xy 53.752428 -133.73064) (xy 53.794808 -133.68826) (xy 53.842358 -133.651773) (xy 53.894264 -133.621806)
			(xy 53.949637 -133.59887) (xy 54.00753 -133.583357) (xy 54.066952 -133.575534) (xy 54.126888 -133.575534)
			(xy 54.18631 -133.583357) (xy 54.244203 -133.59887) (xy 54.299576 -133.621806) (xy 54.351482 -133.651773)
			(xy 54.399032 -133.68826) (xy 54.441412 -133.73064) (xy 54.477899 -133.77819) (xy 54.507866 -133.830096)
			(xy 54.530802 -133.885469) (xy 54.546315 -133.943362) (xy 54.554138 -134.002784) (xy 54.554628 -134.032752)
			(xy 54.554628 -134.377176) (xy 66.599308 -134.377176) (xy 66.599308 -133.513576) (xy 66.599798 -133.483592)
			(xy 66.607626 -133.424136) (xy 66.623147 -133.366211) (xy 66.646096 -133.310807) (xy 66.67608 -133.258873)
			(xy 66.712586 -133.211297) (xy 66.754991 -133.168892) (xy 66.802567 -133.132386) (xy 66.854501 -133.102402)
			(xy 66.909905 -133.079453) (xy 66.96783 -133.063932) (xy 67.027286 -133.056104) (xy 67.087254 -133.056104)
			(xy 67.14671 -133.063932) (xy 67.204635 -133.079453) (xy 67.260039 -133.102402) (xy 67.311973 -133.132386)
			(xy 67.359549 -133.168892) (xy 67.401954 -133.211297) (xy 67.43846 -133.258873) (xy 67.468444 -133.310807)
			(xy 67.491393 -133.366211) (xy 67.506914 -133.424136) (xy 67.514742 -133.483592) (xy 67.515232 -133.513576)
			(xy 67.515232 -134.369302) (xy 81.07426 -134.369302) (xy 81.07426 -133.505702) (xy 81.07475 -133.475718)
			(xy 81.082578 -133.416262) (xy 81.098099 -133.358337) (xy 81.121048 -133.302933) (xy 81.151032 -133.250999)
			(xy 81.187538 -133.203423) (xy 81.229943 -133.161018) (xy 81.277519 -133.124512) (xy 81.329453 -133.094528)
			(xy 81.384857 -133.071579) (xy 81.442782 -133.056058) (xy 81.502238 -133.04823) (xy 81.562206 -133.04823)
			(xy 81.621662 -133.056058) (xy 81.679587 -133.071579) (xy 81.734991 -133.094528) (xy 81.752059 -133.104382)
			(xy 153.409904 -133.104382) (xy 153.409904 -132.240782) (xy 153.410394 -132.210798) (xy 153.418222 -132.151342)
			(xy 153.433743 -132.093417) (xy 153.456692 -132.038013) (xy 153.486676 -131.986079) (xy 153.523182 -131.938503)
			(xy 153.565587 -131.896098) (xy 153.613163 -131.859592) (xy 153.665097 -131.829608) (xy 153.720501 -131.806659)
			(xy 153.778426 -131.791138) (xy 153.837882 -131.78331) (xy 153.89785 -131.78331) (xy 153.957306 -131.791138)
			(xy 154.015231 -131.806659) (xy 154.070635 -131.829608) (xy 154.122569 -131.859592) (xy 154.170145 -131.896098)
			(xy 154.21255 -131.938503) (xy 154.249056 -131.986079) (xy 154.27904 -132.038013) (xy 154.301989 -132.093417)
			(xy 154.31751 -132.151342) (xy 154.325338 -132.210798) (xy 154.325828 -132.240782) (xy 154.325828 -133.096508)
			(xy 167.884856 -133.096508) (xy 167.884856 -132.232908) (xy 167.885346 -132.202924) (xy 167.893174 -132.143468)
			(xy 167.908695 -132.085543) (xy 167.931644 -132.030139) (xy 167.961628 -131.978205) (xy 167.998134 -131.930629)
			(xy 168.040539 -131.888224) (xy 168.088115 -131.851718) (xy 168.140049 -131.821734) (xy 168.195453 -131.798785)
			(xy 168.253378 -131.783264) (xy 168.312834 -131.775436) (xy 168.372802 -131.775436) (xy 168.432258 -131.783264)
			(xy 168.490183 -131.798785) (xy 168.545587 -131.821734) (xy 168.597521 -131.851718) (xy 168.645097 -131.888224)
			(xy 168.687502 -131.930629) (xy 168.724008 -131.978205) (xy 168.753992 -132.030139) (xy 168.776941 -132.085543)
			(xy 168.792462 -132.143468) (xy 168.80029 -132.202924) (xy 168.80078 -132.232908) (xy 168.80078 -132.577332)
			(xy 180.84546 -132.577332) (xy 180.84546 -131.713732) (xy 180.84595 -131.683764) (xy 180.853773 -131.624342)
			(xy 180.869286 -131.566449) (xy 180.892222 -131.511076) (xy 180.922189 -131.45917) (xy 180.958676 -131.41162)
			(xy 181.001056 -131.36924) (xy 181.048606 -131.332753) (xy 181.100512 -131.302786) (xy 181.155885 -131.27985)
			(xy 181.213778 -131.264337) (xy 181.2732 -131.256514) (xy 181.333136 -131.256514) (xy 181.392558 -131.264337)
			(xy 181.450451 -131.27985) (xy 181.505824 -131.302786) (xy 181.55773 -131.332753) (xy 181.60528 -131.36924)
			(xy 181.64766 -131.41162) (xy 181.684147 -131.45917) (xy 181.714114 -131.511076) (xy 181.73705 -131.566449)
			(xy 181.752563 -131.624342) (xy 181.760386 -131.683764) (xy 181.760876 -131.713732) (xy 181.760876 -132.575808)
			(xy 199.81672 -132.575808) (xy 199.81672 -131.712208) (xy 199.81721 -131.68224) (xy 199.825033 -131.622818)
			(xy 199.840546 -131.564925) (xy 199.863482 -131.509552) (xy 199.893449 -131.457646) (xy 199.929936 -131.410096)
			(xy 199.972316 -131.367716) (xy 200.019866 -131.331229) (xy 200.071772 -131.301262) (xy 200.127145 -131.278326)
			(xy 200.185038 -131.262813) (xy 200.24446 -131.25499) (xy 200.304396 -131.25499) (xy 200.363818 -131.262813)
			(xy 200.421711 -131.278326) (xy 200.469049 -131.297934) (xy 266.86764 -131.297934) (xy 266.86764 -130.434334)
			(xy 266.86813 -130.40435) (xy 266.875958 -130.344894) (xy 266.891479 -130.286969) (xy 266.914428 -130.231565)
			(xy 266.944412 -130.179631) (xy 266.980918 -130.132055) (xy 267.023323 -130.08965) (xy 267.070899 -130.053144)
			(xy 267.122833 -130.02316) (xy 267.178237 -130.000211) (xy 267.236162 -129.98469) (xy 267.295618 -129.976862)
			(xy 267.355586 -129.976862) (xy 267.415042 -129.98469) (xy 267.472967 -130.000211) (xy 267.528371 -130.02316)
			(xy 267.580305 -130.053144) (xy 267.627881 -130.08965) (xy 267.670286 -130.132055) (xy 267.706792 -130.179631)
			(xy 267.736776 -130.231565) (xy 267.759725 -130.286969) (xy 267.775246 -130.344894) (xy 267.783074 -130.40435)
			(xy 267.783564 -130.434334) (xy 267.783564 -131.29641) (xy 285.8389 -131.29641) (xy 285.8389 -130.43281)
			(xy 285.83939 -130.402826) (xy 285.847218 -130.34337) (xy 285.862739 -130.285445) (xy 285.885688 -130.230041)
			(xy 285.915672 -130.178107) (xy 285.952178 -130.130531) (xy 285.994583 -130.088126) (xy 286.042159 -130.05162)
			(xy 286.094093 -130.021636) (xy 286.149497 -129.998687) (xy 286.207422 -129.983166) (xy 286.266878 -129.975338)
			(xy 286.326846 -129.975338) (xy 286.386302 -129.983166) (xy 286.444227 -129.998687) (xy 286.499631 -130.021636)
			(xy 286.551565 -130.05162) (xy 286.599141 -130.088126) (xy 286.641546 -130.130531) (xy 286.678052 -130.178107)
			(xy 286.708036 -130.230041) (xy 286.730985 -130.285445) (xy 286.746506 -130.34337) (xy 286.754334 -130.402826)
			(xy 286.754824 -130.43281) (xy 286.754824 -130.777234) (xy 298.799504 -130.777234) (xy 298.799504 -129.913634)
			(xy 298.799994 -129.883666) (xy 298.807817 -129.824244) (xy 298.82333 -129.766351) (xy 298.846266 -129.710978)
			(xy 298.876233 -129.659072) (xy 298.91272 -129.611522) (xy 298.9551 -129.569142) (xy 299.00265 -129.532655)
			(xy 299.054556 -129.502688) (xy 299.109929 -129.479752) (xy 299.167822 -129.464239) (xy 299.227244 -129.456416)
			(xy 299.28718 -129.456416) (xy 299.346602 -129.464239) (xy 299.404495 -129.479752) (xy 299.459868 -129.502688)
			(xy 299.511774 -129.532655) (xy 299.559324 -129.569142) (xy 299.601704 -129.611522) (xy 299.638191 -129.659072)
			(xy 299.668158 -129.710978) (xy 299.691094 -129.766351) (xy 299.706607 -129.824244) (xy 299.71443 -129.883666)
			(xy 299.71492 -129.913634) (xy 299.71492 -130.769106) (xy 313.274456 -130.769106) (xy 313.274456 -129.905506)
			(xy 313.274946 -129.875538) (xy 313.282769 -129.816116) (xy 313.298282 -129.758223) (xy 313.321218 -129.70285)
			(xy 313.351185 -129.650944) (xy 313.387672 -129.603394) (xy 313.430052 -129.561014) (xy 313.477602 -129.524527)
			(xy 313.529508 -129.49456) (xy 313.584881 -129.471624) (xy 313.642774 -129.456111) (xy 313.702196 -129.448288)
			(xy 313.762132 -129.448288) (xy 313.821554 -129.456111) (xy 313.879447 -129.471624) (xy 313.93482 -129.49456)
			(xy 313.986726 -129.524527) (xy 314.034276 -129.561014) (xy 314.076656 -129.603394) (xy 314.113143 -129.650944)
			(xy 314.14311 -129.70285) (xy 314.166046 -129.758223) (xy 314.181559 -129.816116) (xy 314.189382 -129.875538)
			(xy 314.189872 -129.905506) (xy 314.189872 -130.769106) (xy 314.189382 -130.799074) (xy 314.181559 -130.858496)
			(xy 314.166046 -130.916389) (xy 314.14311 -130.971762) (xy 314.113143 -131.023668) (xy 314.076656 -131.071218)
			(xy 314.034276 -131.113598) (xy 313.986726 -131.150085) (xy 313.93482 -131.180052) (xy 313.879447 -131.202988)
			(xy 313.821554 -131.218501) (xy 313.762132 -131.226324) (xy 313.702196 -131.226324) (xy 313.642774 -131.218501)
			(xy 313.584881 -131.202988) (xy 313.529508 -131.180052) (xy 313.477602 -131.150085) (xy 313.430052 -131.113598)
			(xy 313.387672 -131.071218) (xy 313.351185 -131.023668) (xy 313.321218 -130.971762) (xy 313.298282 -130.916389)
			(xy 313.282769 -130.858496) (xy 313.274946 -130.799074) (xy 313.274456 -130.769106) (xy 299.71492 -130.769106)
			(xy 299.71492 -130.777234) (xy 299.71443 -130.807202) (xy 299.706607 -130.866624) (xy 299.691094 -130.924517)
			(xy 299.668158 -130.97989) (xy 299.638191 -131.031796) (xy 299.601704 -131.079346) (xy 299.559324 -131.121726)
			(xy 299.511774 -131.158213) (xy 299.459868 -131.18818) (xy 299.404495 -131.211116) (xy 299.346602 -131.226629)
			(xy 299.28718 -131.234452) (xy 299.227244 -131.234452) (xy 299.167822 -131.226629) (xy 299.109929 -131.211116)
			(xy 299.054556 -131.18818) (xy 299.00265 -131.158213) (xy 298.9551 -131.121726) (xy 298.91272 -131.079346)
			(xy 298.876233 -131.031796) (xy 298.846266 -130.97989) (xy 298.82333 -130.924517) (xy 298.807817 -130.866624)
			(xy 298.799994 -130.807202) (xy 298.799504 -130.777234) (xy 286.754824 -130.777234) (xy 286.754824 -131.29641)
			(xy 286.754334 -131.326394) (xy 286.746506 -131.38585) (xy 286.730985 -131.443775) (xy 286.708036 -131.499179)
			(xy 286.678052 -131.551113) (xy 286.641546 -131.598689) (xy 286.599141 -131.641094) (xy 286.551565 -131.6776)
			(xy 286.499631 -131.707584) (xy 286.444227 -131.730533) (xy 286.386302 -131.746054) (xy 286.326846 -131.753882)
			(xy 286.266878 -131.753882) (xy 286.207422 -131.746054) (xy 286.149497 -131.730533) (xy 286.094093 -131.707584)
			(xy 286.042159 -131.6776) (xy 285.994583 -131.641094) (xy 285.952178 -131.598689) (xy 285.915672 -131.551113)
			(xy 285.885688 -131.499179) (xy 285.862739 -131.443775) (xy 285.847218 -131.38585) (xy 285.83939 -131.326394)
			(xy 285.8389 -131.29641) (xy 267.783564 -131.29641) (xy 267.783564 -131.297934) (xy 267.783074 -131.327918)
			(xy 267.775246 -131.387374) (xy 267.759725 -131.445299) (xy 267.736776 -131.500703) (xy 267.706792 -131.552637)
			(xy 267.670286 -131.600213) (xy 267.627881 -131.642618) (xy 267.580305 -131.679124) (xy 267.528371 -131.709108)
			(xy 267.472967 -131.732057) (xy 267.415042 -131.747578) (xy 267.355586 -131.755406) (xy 267.295618 -131.755406)
			(xy 267.236162 -131.747578) (xy 267.178237 -131.732057) (xy 267.122833 -131.709108) (xy 267.070899 -131.679124)
			(xy 267.023323 -131.642618) (xy 266.980918 -131.600213) (xy 266.944412 -131.552637) (xy 266.914428 -131.500703)
			(xy 266.891479 -131.445299) (xy 266.875958 -131.387374) (xy 266.86813 -131.327918) (xy 266.86764 -131.297934)
			(xy 200.469049 -131.297934) (xy 200.477084 -131.301262) (xy 200.52899 -131.331229) (xy 200.57654 -131.367716)
			(xy 200.61892 -131.410096) (xy 200.655407 -131.457646) (xy 200.685374 -131.509552) (xy 200.70831 -131.564925)
			(xy 200.723823 -131.622818) (xy 200.731646 -131.68224) (xy 200.732136 -131.712208) (xy 200.732136 -132.575808)
			(xy 200.731646 -132.605776) (xy 200.723823 -132.665198) (xy 200.70831 -132.723091) (xy 200.685374 -132.778464)
			(xy 200.655407 -132.83037) (xy 200.61892 -132.87792) (xy 200.57654 -132.9203) (xy 200.52899 -132.956787)
			(xy 200.477084 -132.986754) (xy 200.421711 -133.00969) (xy 200.363818 -133.025203) (xy 200.304396 -133.033026)
			(xy 200.24446 -133.033026) (xy 200.185038 -133.025203) (xy 200.127145 -133.00969) (xy 200.071772 -132.986754)
			(xy 200.019866 -132.956787) (xy 199.972316 -132.9203) (xy 199.929936 -132.87792) (xy 199.893449 -132.83037)
			(xy 199.863482 -132.778464) (xy 199.840546 -132.723091) (xy 199.825033 -132.665198) (xy 199.81721 -132.605776)
			(xy 199.81672 -132.575808) (xy 181.760876 -132.575808) (xy 181.760876 -132.577332) (xy 181.760386 -132.6073)
			(xy 181.752563 -132.666722) (xy 181.73705 -132.724615) (xy 181.714114 -132.779988) (xy 181.684147 -132.831894)
			(xy 181.64766 -132.879444) (xy 181.60528 -132.921824) (xy 181.55773 -132.958311) (xy 181.505824 -132.988278)
			(xy 181.450451 -133.011214) (xy 181.392558 -133.026727) (xy 181.333136 -133.03455) (xy 181.2732 -133.03455)
			(xy 181.213778 -133.026727) (xy 181.155885 -133.011214) (xy 181.100512 -132.988278) (xy 181.048606 -132.958311)
			(xy 181.001056 -132.921824) (xy 180.958676 -132.879444) (xy 180.922189 -132.831894) (xy 180.892222 -132.779988)
			(xy 180.869286 -132.724615) (xy 180.853773 -132.666722) (xy 180.84595 -132.6073) (xy 180.84546 -132.577332)
			(xy 168.80078 -132.577332) (xy 168.80078 -133.096508) (xy 168.80029 -133.126492) (xy 168.792462 -133.185948)
			(xy 168.776941 -133.243873) (xy 168.753992 -133.299277) (xy 168.724008 -133.351211) (xy 168.687502 -133.398787)
			(xy 168.645097 -133.441192) (xy 168.597521 -133.477698) (xy 168.545587 -133.507682) (xy 168.490183 -133.530631)
			(xy 168.432258 -133.546152) (xy 168.372802 -133.55398) (xy 168.312834 -133.55398) (xy 168.253378 -133.546152)
			(xy 168.195453 -133.530631) (xy 168.140049 -133.507682) (xy 168.088115 -133.477698) (xy 168.040539 -133.441192)
			(xy 167.998134 -133.398787) (xy 167.961628 -133.351211) (xy 167.931644 -133.299277) (xy 167.908695 -133.243873)
			(xy 167.893174 -133.185948) (xy 167.885346 -133.126492) (xy 167.884856 -133.096508) (xy 154.325828 -133.096508)
			(xy 154.325828 -133.104382) (xy 154.325338 -133.134366) (xy 154.31751 -133.193822) (xy 154.301989 -133.251747)
			(xy 154.27904 -133.307151) (xy 154.249056 -133.359085) (xy 154.21255 -133.406661) (xy 154.170145 -133.449066)
			(xy 154.122569 -133.485572) (xy 154.070635 -133.515556) (xy 154.015231 -133.538505) (xy 153.957306 -133.554026)
			(xy 153.89785 -133.561854) (xy 153.837882 -133.561854) (xy 153.778426 -133.554026) (xy 153.720501 -133.538505)
			(xy 153.665097 -133.515556) (xy 153.613163 -133.485572) (xy 153.565587 -133.449066) (xy 153.523182 -133.406661)
			(xy 153.486676 -133.359085) (xy 153.456692 -133.307151) (xy 153.433743 -133.251747) (xy 153.418222 -133.193822)
			(xy 153.410394 -133.134366) (xy 153.409904 -133.104382) (xy 81.752059 -133.104382) (xy 81.786925 -133.124512)
			(xy 81.834501 -133.161018) (xy 81.876906 -133.203423) (xy 81.913412 -133.250999) (xy 81.943396 -133.302933)
			(xy 81.966345 -133.358337) (xy 81.981866 -133.416262) (xy 81.989694 -133.475718) (xy 81.990184 -133.505702)
			(xy 81.990184 -134.369302) (xy 81.989694 -134.399286) (xy 81.981866 -134.458742) (xy 81.966345 -134.516667)
			(xy 81.943396 -134.572071) (xy 81.913412 -134.624005) (xy 81.876906 -134.671581) (xy 81.834501 -134.713986)
			(xy 81.786925 -134.750492) (xy 81.734991 -134.780476) (xy 81.679587 -134.803425) (xy 81.621662 -134.818946)
			(xy 81.562206 -134.826774) (xy 81.502238 -134.826774) (xy 81.442782 -134.818946) (xy 81.384857 -134.803425)
			(xy 81.329453 -134.780476) (xy 81.277519 -134.750492) (xy 81.229943 -134.713986) (xy 81.187538 -134.671581)
			(xy 81.151032 -134.624005) (xy 81.121048 -134.572071) (xy 81.098099 -134.516667) (xy 81.082578 -134.458742)
			(xy 81.07475 -134.399286) (xy 81.07426 -134.369302) (xy 67.515232 -134.369302) (xy 67.515232 -134.377176)
			(xy 67.514742 -134.40716) (xy 67.506914 -134.466616) (xy 67.491393 -134.524541) (xy 67.468444 -134.579945)
			(xy 67.43846 -134.631879) (xy 67.401954 -134.679455) (xy 67.359549 -134.72186) (xy 67.311973 -134.758366)
			(xy 67.260039 -134.78835) (xy 67.204635 -134.811299) (xy 67.14671 -134.82682) (xy 67.087254 -134.834648)
			(xy 67.027286 -134.834648) (xy 66.96783 -134.82682) (xy 66.909905 -134.811299) (xy 66.854501 -134.78835)
			(xy 66.802567 -134.758366) (xy 66.754991 -134.72186) (xy 66.712586 -134.679455) (xy 66.67608 -134.631879)
			(xy 66.646096 -134.579945) (xy 66.623147 -134.524541) (xy 66.607626 -134.466616) (xy 66.599798 -134.40716)
			(xy 66.599308 -134.377176) (xy 54.554628 -134.377176) (xy 54.554628 -134.896352) (xy 54.554138 -134.92632)
			(xy 54.546315 -134.985742) (xy 54.530802 -135.043635) (xy 54.507866 -135.099008) (xy 54.477899 -135.150914)
			(xy 54.441412 -135.198464) (xy 54.399032 -135.240844) (xy 54.351482 -135.277331) (xy 54.299576 -135.307298)
			(xy 54.244203 -135.330234) (xy 54.18631 -135.345747) (xy 54.126888 -135.35357) (xy 54.066952 -135.35357)
			(xy 54.00753 -135.345747) (xy 53.949637 -135.330234) (xy 53.894264 -135.307298) (xy 53.842358 -135.277331)
			(xy 53.794808 -135.240844) (xy 53.752428 -135.198464) (xy 53.715941 -135.150914) (xy 53.685974 -135.099008)
			(xy 53.663038 -135.043635) (xy 53.647525 -134.985742) (xy 53.639702 -134.92632) (xy 53.639212 -134.896352)
			(xy 35.583368 -134.896352) (xy 35.583368 -134.897876) (xy 35.582878 -134.927844) (xy 35.575055 -134.987266)
			(xy 35.559542 -135.045159) (xy 35.536606 -135.100532) (xy 35.506639 -135.152438) (xy 35.470152 -135.199988)
			(xy 35.427772 -135.242368) (xy 35.380222 -135.278855) (xy 35.328316 -135.308822) (xy 35.272943 -135.331758)
			(xy 35.21505 -135.347271) (xy 35.155628 -135.355094) (xy 35.095692 -135.355094) (xy 35.03627 -135.347271)
			(xy 34.978377 -135.331758) (xy 34.923004 -135.308822) (xy 34.871098 -135.278855) (xy 34.823548 -135.242368)
			(xy 34.781168 -135.199988) (xy 34.744681 -135.152438) (xy 34.714714 -135.100532) (xy 34.691778 -135.045159)
			(xy 34.676265 -134.987266) (xy 34.668442 -134.927844) (xy 34.667952 -134.897876) (xy 4.30911 -134.897876)
			(xy 4.30911 -136.704324) (xy 37.31006 -136.704324) (xy 37.31006 -135.840724) (xy 37.31055 -135.810756)
			(xy 37.318373 -135.751334) (xy 37.333886 -135.693441) (xy 37.356822 -135.638068) (xy 37.386789 -135.586162)
			(xy 37.423276 -135.538612) (xy 37.465656 -135.496232) (xy 37.513206 -135.459745) (xy 37.565112 -135.429778)
			(xy 37.620485 -135.406842) (xy 37.678378 -135.391329) (xy 37.7378 -135.383506) (xy 37.797736 -135.383506)
			(xy 37.857158 -135.391329) (xy 37.915051 -135.406842) (xy 37.970424 -135.429778) (xy 38.02233 -135.459745)
			(xy 38.06988 -135.496232) (xy 38.11226 -135.538612) (xy 38.148747 -135.586162) (xy 38.178714 -135.638068)
			(xy 38.20165 -135.693441) (xy 38.217163 -135.751334) (xy 38.224986 -135.810756) (xy 38.225476 -135.840724)
			(xy 38.225476 -136.69645) (xy 51.785012 -136.69645) (xy 51.785012 -135.83285) (xy 51.785502 -135.802882)
			(xy 51.793325 -135.74346) (xy 51.808838 -135.685567) (xy 51.831774 -135.630194) (xy 51.861741 -135.578288)
			(xy 51.898228 -135.530738) (xy 51.940608 -135.488358) (xy 51.988158 -135.451871) (xy 52.040064 -135.421904)
			(xy 52.095437 -135.398968) (xy 52.15333 -135.383455) (xy 52.212752 -135.375632) (xy 52.272688 -135.375632)
			(xy 52.33211 -135.383455) (xy 52.390003 -135.398968) (xy 52.445376 -135.421904) (xy 52.497282 -135.451871)
			(xy 52.544832 -135.488358) (xy 52.587212 -135.530738) (xy 52.623699 -135.578288) (xy 52.653666 -135.630194)
			(xy 52.676602 -135.685567) (xy 52.692115 -135.74346) (xy 52.699938 -135.802882) (xy 52.700428 -135.83285)
			(xy 52.700428 -136.177274) (xy 64.745108 -136.177274) (xy 64.745108 -135.313674) (xy 64.745598 -135.28369)
			(xy 64.753426 -135.224234) (xy 64.768947 -135.166309) (xy 64.791896 -135.110905) (xy 64.82188 -135.058971)
			(xy 64.858386 -135.011395) (xy 64.900791 -134.96899) (xy 64.948367 -134.932484) (xy 65.000301 -134.9025)
			(xy 65.055705 -134.879551) (xy 65.11363 -134.86403) (xy 65.173086 -134.856202) (xy 65.233054 -134.856202)
			(xy 65.29251 -134.86403) (xy 65.350435 -134.879551) (xy 65.405839 -134.9025) (xy 65.457773 -134.932484)
			(xy 65.505349 -134.96899) (xy 65.547754 -135.011395) (xy 65.58426 -135.058971) (xy 65.614244 -135.110905)
			(xy 65.637193 -135.166309) (xy 65.652714 -135.224234) (xy 65.660542 -135.28369) (xy 65.661032 -135.313674)
			(xy 65.661032 -136.17575) (xy 83.716368 -136.17575) (xy 83.716368 -135.31215) (xy 83.716858 -135.282166)
			(xy 83.724686 -135.22271) (xy 83.740207 -135.164785) (xy 83.763156 -135.109381) (xy 83.79314 -135.057447)
			(xy 83.829646 -135.009871) (xy 83.872051 -134.967466) (xy 83.919627 -134.93096) (xy 83.971561 -134.900976)
			(xy 84.026965 -134.878027) (xy 84.08489 -134.862506) (xy 84.144346 -134.854678) (xy 84.204314 -134.854678)
			(xy 84.26377 -134.862506) (xy 84.321695 -134.878027) (xy 84.369615 -134.897876) (xy 150.767796 -134.897876)
			(xy 150.767796 -134.034276) (xy 150.768286 -134.004292) (xy 150.776114 -133.944836) (xy 150.791635 -133.886911)
			(xy 150.814584 -133.831507) (xy 150.844568 -133.779573) (xy 150.881074 -133.731997) (xy 150.923479 -133.689592)
			(xy 150.971055 -133.653086) (xy 151.022989 -133.623102) (xy 151.078393 -133.600153) (xy 151.136318 -133.584632)
			(xy 151.195774 -133.576804) (xy 151.255742 -133.576804) (xy 151.315198 -133.584632) (xy 151.373123 -133.600153)
			(xy 151.428527 -133.623102) (xy 151.480461 -133.653086) (xy 151.528037 -133.689592) (xy 151.570442 -133.731997)
			(xy 151.606948 -133.779573) (xy 151.636932 -133.831507) (xy 151.659881 -133.886911) (xy 151.675402 -133.944836)
			(xy 151.68323 -134.004292) (xy 151.68372 -134.034276) (xy 151.68372 -134.896352) (xy 169.739056 -134.896352)
			(xy 169.739056 -134.032752) (xy 169.739546 -134.002768) (xy 169.747374 -133.943312) (xy 169.762895 -133.885387)
			(xy 169.785844 -133.829983) (xy 169.815828 -133.778049) (xy 169.852334 -133.730473) (xy 169.894739 -133.688068)
			(xy 169.942315 -133.651562) (xy 169.994249 -133.621578) (xy 170.049653 -133.598629) (xy 170.107578 -133.583108)
			(xy 170.167034 -133.57528) (xy 170.227002 -133.57528) (xy 170.286458 -133.583108) (xy 170.344383 -133.598629)
			(xy 170.399787 -133.621578) (xy 170.451721 -133.651562) (xy 170.499297 -133.688068) (xy 170.541702 -133.730473)
			(xy 170.578208 -133.778049) (xy 170.608192 -133.829983) (xy 170.631141 -133.885387) (xy 170.646662 -133.943312)
			(xy 170.65449 -134.002768) (xy 170.65498 -134.032752) (xy 170.65498 -134.377176) (xy 182.69966 -134.377176)
			(xy 182.69966 -133.513576) (xy 182.70015 -133.483608) (xy 182.707973 -133.424186) (xy 182.723486 -133.366293)
			(xy 182.746422 -133.31092) (xy 182.776389 -133.259014) (xy 182.812876 -133.211464) (xy 182.855256 -133.169084)
			(xy 182.902806 -133.132597) (xy 182.954712 -133.10263) (xy 183.010085 -133.079694) (xy 183.067978 -133.064181)
			(xy 183.1274 -133.056358) (xy 183.187336 -133.056358) (xy 183.246758 -133.064181) (xy 183.304651 -133.079694)
			(xy 183.360024 -133.10263) (xy 183.41193 -133.132597) (xy 183.45948 -133.169084) (xy 183.50186 -133.211464)
			(xy 183.538347 -133.259014) (xy 183.568314 -133.31092) (xy 183.59125 -133.366293) (xy 183.606763 -133.424186)
			(xy 183.614586 -133.483608) (xy 183.615076 -133.513576) (xy 183.615076 -134.369302) (xy 197.174612 -134.369302)
			(xy 197.174612 -133.505702) (xy 197.175102 -133.475734) (xy 197.182925 -133.416312) (xy 197.198438 -133.358419)
			(xy 197.221374 -133.303046) (xy 197.251341 -133.25114) (xy 197.287828 -133.20359) (xy 197.330208 -133.16121)
			(xy 197.377758 -133.124723) (xy 197.429664 -133.094756) (xy 197.485037 -133.07182) (xy 197.54293 -133.056307)
			(xy 197.602352 -133.048484) (xy 197.662288 -133.048484) (xy 197.72171 -133.056307) (xy 197.779603 -133.07182)
			(xy 197.834976 -133.094756) (xy 197.851649 -133.104382) (xy 269.509748 -133.104382) (xy 269.509748 -132.240782)
			(xy 269.510238 -132.210798) (xy 269.518066 -132.151342) (xy 269.533587 -132.093417) (xy 269.556536 -132.038013)
			(xy 269.58652 -131.986079) (xy 269.623026 -131.938503) (xy 269.665431 -131.896098) (xy 269.713007 -131.859592)
			(xy 269.764941 -131.829608) (xy 269.820345 -131.806659) (xy 269.87827 -131.791138) (xy 269.937726 -131.78331)
			(xy 269.997694 -131.78331) (xy 270.05715 -131.791138) (xy 270.115075 -131.806659) (xy 270.170479 -131.829608)
			(xy 270.222413 -131.859592) (xy 270.269989 -131.896098) (xy 270.312394 -131.938503) (xy 270.3489 -131.986079)
			(xy 270.378884 -132.038013) (xy 270.401833 -132.093417) (xy 270.417354 -132.151342) (xy 270.425182 -132.210798)
			(xy 270.425672 -132.240782) (xy 270.425672 -133.096508) (xy 283.9847 -133.096508) (xy 283.9847 -132.232908)
			(xy 283.98519 -132.202924) (xy 283.993018 -132.143468) (xy 284.008539 -132.085543) (xy 284.031488 -132.030139)
			(xy 284.061472 -131.978205) (xy 284.097978 -131.930629) (xy 284.140383 -131.888224) (xy 284.187959 -131.851718)
			(xy 284.239893 -131.821734) (xy 284.295297 -131.798785) (xy 284.353222 -131.783264) (xy 284.412678 -131.775436)
			(xy 284.472646 -131.775436) (xy 284.532102 -131.783264) (xy 284.590027 -131.798785) (xy 284.645431 -131.821734)
			(xy 284.697365 -131.851718) (xy 284.744941 -131.888224) (xy 284.787346 -131.930629) (xy 284.823852 -131.978205)
			(xy 284.853836 -132.030139) (xy 284.876785 -132.085543) (xy 284.892306 -132.143468) (xy 284.900134 -132.202924)
			(xy 284.900624 -132.232908) (xy 284.900624 -132.577332) (xy 296.945304 -132.577332) (xy 296.945304 -131.713732)
			(xy 296.945794 -131.683764) (xy 296.953617 -131.624342) (xy 296.96913 -131.566449) (xy 296.992066 -131.511076)
			(xy 297.022033 -131.45917) (xy 297.05852 -131.41162) (xy 297.1009 -131.36924) (xy 297.14845 -131.332753)
			(xy 297.200356 -131.302786) (xy 297.255729 -131.27985) (xy 297.313622 -131.264337) (xy 297.373044 -131.256514)
			(xy 297.43298 -131.256514) (xy 297.492402 -131.264337) (xy 297.550295 -131.27985) (xy 297.605668 -131.302786)
			(xy 297.657574 -131.332753) (xy 297.705124 -131.36924) (xy 297.747504 -131.41162) (xy 297.783991 -131.45917)
			(xy 297.813958 -131.511076) (xy 297.836894 -131.566449) (xy 297.852407 -131.624342) (xy 297.86023 -131.683764)
			(xy 297.86072 -131.713732) (xy 297.86072 -132.575808) (xy 315.916564 -132.575808) (xy 315.916564 -131.712208)
			(xy 315.917054 -131.68224) (xy 315.924877 -131.622818) (xy 315.94039 -131.564925) (xy 315.963326 -131.509552)
			(xy 315.993293 -131.457646) (xy 316.02978 -131.410096) (xy 316.07216 -131.367716) (xy 316.11971 -131.331229)
			(xy 316.171616 -131.301262) (xy 316.226989 -131.278326) (xy 316.284882 -131.262813) (xy 316.344304 -131.25499)
			(xy 316.40424 -131.25499) (xy 316.463662 -131.262813) (xy 316.521555 -131.278326) (xy 316.568893 -131.297934)
			(xy 382.967992 -131.297934) (xy 382.967992 -130.434334) (xy 382.968482 -130.404366) (xy 382.976305 -130.344944)
			(xy 382.991818 -130.287051) (xy 383.014754 -130.231678) (xy 383.044721 -130.179772) (xy 383.081208 -130.132222)
			(xy 383.123588 -130.089842) (xy 383.171138 -130.053355) (xy 383.223044 -130.023388) (xy 383.278417 -130.000452)
			(xy 383.33631 -129.984939) (xy 383.395732 -129.977116) (xy 383.455668 -129.977116) (xy 383.51509 -129.984939)
			(xy 383.572983 -130.000452) (xy 383.628356 -130.023388) (xy 383.680262 -130.053355) (xy 383.727812 -130.089842)
			(xy 383.770192 -130.132222) (xy 383.806679 -130.179772) (xy 383.836646 -130.231678) (xy 383.859582 -130.287051)
			(xy 383.875095 -130.344944) (xy 383.882918 -130.404366) (xy 383.883408 -130.434334) (xy 383.883408 -131.29641)
			(xy 401.939252 -131.29641) (xy 401.939252 -130.43281) (xy 401.939742 -130.402842) (xy 401.947565 -130.34342)
			(xy 401.963078 -130.285527) (xy 401.986014 -130.230154) (xy 402.015981 -130.178248) (xy 402.052468 -130.130698)
			(xy 402.094848 -130.088318) (xy 402.142398 -130.051831) (xy 402.194304 -130.021864) (xy 402.249677 -129.998928)
			(xy 402.30757 -129.983415) (xy 402.366992 -129.975592) (xy 402.426928 -129.975592) (xy 402.48635 -129.983415)
			(xy 402.544243 -129.998928) (xy 402.599616 -130.021864) (xy 402.651522 -130.051831) (xy 402.699072 -130.088318)
			(xy 402.741452 -130.130698) (xy 402.777939 -130.178248) (xy 402.807906 -130.230154) (xy 402.830842 -130.285527)
			(xy 402.846355 -130.34342) (xy 402.854178 -130.402842) (xy 402.854668 -130.43281) (xy 402.854668 -130.777234)
			(xy 414.899348 -130.777234) (xy 414.899348 -129.913634) (xy 414.899838 -129.88365) (xy 414.907666 -129.824194)
			(xy 414.923187 -129.766269) (xy 414.946136 -129.710865) (xy 414.97612 -129.658931) (xy 415.012626 -129.611355)
			(xy 415.055031 -129.56895) (xy 415.102607 -129.532444) (xy 415.154541 -129.50246) (xy 415.209945 -129.479511)
			(xy 415.26787 -129.46399) (xy 415.327326 -129.456162) (xy 415.387294 -129.456162) (xy 415.44675 -129.46399)
			(xy 415.504675 -129.479511) (xy 415.560079 -129.50246) (xy 415.612013 -129.532444) (xy 415.659589 -129.56895)
			(xy 415.701994 -129.611355) (xy 415.7385 -129.658931) (xy 415.768484 -129.710865) (xy 415.791433 -129.766269)
			(xy 415.806954 -129.824194) (xy 415.814782 -129.88365) (xy 415.815272 -129.913634) (xy 415.815272 -130.769106)
			(xy 429.3743 -130.769106) (xy 429.3743 -129.905506) (xy 429.37479 -129.875522) (xy 429.382618 -129.816066)
			(xy 429.398139 -129.758141) (xy 429.421088 -129.702737) (xy 429.451072 -129.650803) (xy 429.487578 -129.603227)
			(xy 429.529983 -129.560822) (xy 429.577559 -129.524316) (xy 429.629493 -129.494332) (xy 429.684897 -129.471383)
			(xy 429.742822 -129.455862) (xy 429.802278 -129.448034) (xy 429.862246 -129.448034) (xy 429.921702 -129.455862)
			(xy 429.979627 -129.471383) (xy 430.035031 -129.494332) (xy 430.086965 -129.524316) (xy 430.134541 -129.560822)
			(xy 430.176946 -129.603227) (xy 430.213452 -129.650803) (xy 430.243436 -129.702737) (xy 430.266385 -129.758141)
			(xy 430.281906 -129.816066) (xy 430.289734 -129.875522) (xy 430.290224 -129.905506) (xy 430.290224 -130.769106)
			(xy 430.289734 -130.79909) (xy 430.281906 -130.858546) (xy 430.266385 -130.916471) (xy 430.243436 -130.971875)
			(xy 430.213452 -131.023809) (xy 430.176946 -131.071385) (xy 430.134541 -131.11379) (xy 430.086965 -131.150296)
			(xy 430.035031 -131.18028) (xy 429.979627 -131.203229) (xy 429.921702 -131.21875) (xy 429.862246 -131.226578)
			(xy 429.802278 -131.226578) (xy 429.742822 -131.21875) (xy 429.684897 -131.203229) (xy 429.629493 -131.18028)
			(xy 429.577559 -131.150296) (xy 429.529983 -131.11379) (xy 429.487578 -131.071385) (xy 429.451072 -131.023809)
			(xy 429.421088 -130.971875) (xy 429.398139 -130.916471) (xy 429.382618 -130.858546) (xy 429.37479 -130.79909)
			(xy 429.3743 -130.769106) (xy 415.815272 -130.769106) (xy 415.815272 -130.777234) (xy 415.814782 -130.807218)
			(xy 415.806954 -130.866674) (xy 415.791433 -130.924599) (xy 415.768484 -130.980003) (xy 415.7385 -131.031937)
			(xy 415.701994 -131.079513) (xy 415.659589 -131.121918) (xy 415.612013 -131.158424) (xy 415.560079 -131.188408)
			(xy 415.504675 -131.211357) (xy 415.44675 -131.226878) (xy 415.387294 -131.234706) (xy 415.327326 -131.234706)
			(xy 415.26787 -131.226878) (xy 415.209945 -131.211357) (xy 415.154541 -131.188408) (xy 415.102607 -131.158424)
			(xy 415.055031 -131.121918) (xy 415.012626 -131.079513) (xy 414.97612 -131.031937) (xy 414.946136 -130.980003)
			(xy 414.923187 -130.924599) (xy 414.907666 -130.866674) (xy 414.899838 -130.807218) (xy 414.899348 -130.777234)
			(xy 402.854668 -130.777234) (xy 402.854668 -131.29641) (xy 402.854178 -131.326378) (xy 402.846355 -131.3858)
			(xy 402.830842 -131.443693) (xy 402.807906 -131.499066) (xy 402.777939 -131.550972) (xy 402.741452 -131.598522)
			(xy 402.699072 -131.640902) (xy 402.651522 -131.677389) (xy 402.599616 -131.707356) (xy 402.544243 -131.730292)
			(xy 402.48635 -131.745805) (xy 402.426928 -131.753628) (xy 402.366992 -131.753628) (xy 402.30757 -131.745805)
			(xy 402.249677 -131.730292) (xy 402.194304 -131.707356) (xy 402.142398 -131.677389) (xy 402.094848 -131.640902)
			(xy 402.052468 -131.598522) (xy 402.015981 -131.550972) (xy 401.986014 -131.499066) (xy 401.963078 -131.443693)
			(xy 401.947565 -131.3858) (xy 401.939742 -131.326378) (xy 401.939252 -131.29641) (xy 383.883408 -131.29641)
			(xy 383.883408 -131.297934) (xy 383.882918 -131.327902) (xy 383.875095 -131.387324) (xy 383.859582 -131.445217)
			(xy 383.836646 -131.50059) (xy 383.806679 -131.552496) (xy 383.770192 -131.600046) (xy 383.727812 -131.642426)
			(xy 383.680262 -131.678913) (xy 383.628356 -131.70888) (xy 383.572983 -131.731816) (xy 383.51509 -131.747329)
			(xy 383.455668 -131.755152) (xy 383.395732 -131.755152) (xy 383.33631 -131.747329) (xy 383.278417 -131.731816)
			(xy 383.223044 -131.70888) (xy 383.171138 -131.678913) (xy 383.123588 -131.642426) (xy 383.081208 -131.600046)
			(xy 383.044721 -131.552496) (xy 383.014754 -131.50059) (xy 382.991818 -131.445217) (xy 382.976305 -131.387324)
			(xy 382.968482 -131.327902) (xy 382.967992 -131.297934) (xy 316.568893 -131.297934) (xy 316.576928 -131.301262)
			(xy 316.628834 -131.331229) (xy 316.676384 -131.367716) (xy 316.718764 -131.410096) (xy 316.755251 -131.457646)
			(xy 316.785218 -131.509552) (xy 316.808154 -131.564925) (xy 316.823667 -131.622818) (xy 316.83149 -131.68224)
			(xy 316.83198 -131.712208) (xy 316.83198 -132.575808) (xy 316.83149 -132.605776) (xy 316.823667 -132.665198)
			(xy 316.808154 -132.723091) (xy 316.785218 -132.778464) (xy 316.755251 -132.83037) (xy 316.718764 -132.87792)
			(xy 316.676384 -132.9203) (xy 316.628834 -132.956787) (xy 316.576928 -132.986754) (xy 316.521555 -133.00969)
			(xy 316.463662 -133.025203) (xy 316.40424 -133.033026) (xy 316.344304 -133.033026) (xy 316.284882 -133.025203)
			(xy 316.226989 -133.00969) (xy 316.171616 -132.986754) (xy 316.11971 -132.956787) (xy 316.07216 -132.9203)
			(xy 316.02978 -132.87792) (xy 315.993293 -132.83037) (xy 315.963326 -132.778464) (xy 315.94039 -132.723091)
			(xy 315.924877 -132.665198) (xy 315.917054 -132.605776) (xy 315.916564 -132.575808) (xy 297.86072 -132.575808)
			(xy 297.86072 -132.577332) (xy 297.86023 -132.6073) (xy 297.852407 -132.666722) (xy 297.836894 -132.724615)
			(xy 297.813958 -132.779988) (xy 297.783991 -132.831894) (xy 297.747504 -132.879444) (xy 297.705124 -132.921824)
			(xy 297.657574 -132.958311) (xy 297.605668 -132.988278) (xy 297.550295 -133.011214) (xy 297.492402 -133.026727)
			(xy 297.43298 -133.03455) (xy 297.373044 -133.03455) (xy 297.313622 -133.026727) (xy 297.255729 -133.011214)
			(xy 297.200356 -132.988278) (xy 297.14845 -132.958311) (xy 297.1009 -132.921824) (xy 297.05852 -132.879444)
			(xy 297.022033 -132.831894) (xy 296.992066 -132.779988) (xy 296.96913 -132.724615) (xy 296.953617 -132.666722)
			(xy 296.945794 -132.6073) (xy 296.945304 -132.577332) (xy 284.900624 -132.577332) (xy 284.900624 -133.096508)
			(xy 284.900134 -133.126492) (xy 284.892306 -133.185948) (xy 284.876785 -133.243873) (xy 284.853836 -133.299277)
			(xy 284.823852 -133.351211) (xy 284.787346 -133.398787) (xy 284.744941 -133.441192) (xy 284.697365 -133.477698)
			(xy 284.645431 -133.507682) (xy 284.590027 -133.530631) (xy 284.532102 -133.546152) (xy 284.472646 -133.55398)
			(xy 284.412678 -133.55398) (xy 284.353222 -133.546152) (xy 284.295297 -133.530631) (xy 284.239893 -133.507682)
			(xy 284.187959 -133.477698) (xy 284.140383 -133.441192) (xy 284.097978 -133.398787) (xy 284.061472 -133.351211)
			(xy 284.031488 -133.299277) (xy 284.008539 -133.243873) (xy 283.993018 -133.185948) (xy 283.98519 -133.126492)
			(xy 283.9847 -133.096508) (xy 270.425672 -133.096508) (xy 270.425672 -133.104382) (xy 270.425182 -133.134366)
			(xy 270.417354 -133.193822) (xy 270.401833 -133.251747) (xy 270.378884 -133.307151) (xy 270.3489 -133.359085)
			(xy 270.312394 -133.406661) (xy 270.269989 -133.449066) (xy 270.222413 -133.485572) (xy 270.170479 -133.515556)
			(xy 270.115075 -133.538505) (xy 270.05715 -133.554026) (xy 269.997694 -133.561854) (xy 269.937726 -133.561854)
			(xy 269.87827 -133.554026) (xy 269.820345 -133.538505) (xy 269.764941 -133.515556) (xy 269.713007 -133.485572)
			(xy 269.665431 -133.449066) (xy 269.623026 -133.406661) (xy 269.58652 -133.359085) (xy 269.556536 -133.307151)
			(xy 269.533587 -133.251747) (xy 269.518066 -133.193822) (xy 269.510238 -133.134366) (xy 269.509748 -133.104382)
			(xy 197.851649 -133.104382) (xy 197.886882 -133.124723) (xy 197.934432 -133.16121) (xy 197.976812 -133.20359)
			(xy 198.013299 -133.25114) (xy 198.043266 -133.303046) (xy 198.066202 -133.358419) (xy 198.081715 -133.416312)
			(xy 198.089538 -133.475734) (xy 198.090028 -133.505702) (xy 198.090028 -134.369302) (xy 198.089538 -134.39927)
			(xy 198.081715 -134.458692) (xy 198.066202 -134.516585) (xy 198.043266 -134.571958) (xy 198.013299 -134.623864)
			(xy 197.976812 -134.671414) (xy 197.934432 -134.713794) (xy 197.886882 -134.750281) (xy 197.834976 -134.780248)
			(xy 197.779603 -134.803184) (xy 197.72171 -134.818697) (xy 197.662288 -134.82652) (xy 197.602352 -134.82652)
			(xy 197.54293 -134.818697) (xy 197.485037 -134.803184) (xy 197.429664 -134.780248) (xy 197.377758 -134.750281)
			(xy 197.330208 -134.713794) (xy 197.287828 -134.671414) (xy 197.251341 -134.623864) (xy 197.221374 -134.571958)
			(xy 197.198438 -134.516585) (xy 197.182925 -134.458692) (xy 197.175102 -134.39927) (xy 197.174612 -134.369302)
			(xy 183.615076 -134.369302) (xy 183.615076 -134.377176) (xy 183.614586 -134.407144) (xy 183.606763 -134.466566)
			(xy 183.59125 -134.524459) (xy 183.568314 -134.579832) (xy 183.538347 -134.631738) (xy 183.50186 -134.679288)
			(xy 183.45948 -134.721668) (xy 183.41193 -134.758155) (xy 183.360024 -134.788122) (xy 183.304651 -134.811058)
			(xy 183.246758 -134.826571) (xy 183.187336 -134.834394) (xy 183.1274 -134.834394) (xy 183.067978 -134.826571)
			(xy 183.010085 -134.811058) (xy 182.954712 -134.788122) (xy 182.902806 -134.758155) (xy 182.855256 -134.721668)
			(xy 182.812876 -134.679288) (xy 182.776389 -134.631738) (xy 182.746422 -134.579832) (xy 182.723486 -134.524459)
			(xy 182.707973 -134.466566) (xy 182.70015 -134.407144) (xy 182.69966 -134.377176) (xy 170.65498 -134.377176)
			(xy 170.65498 -134.896352) (xy 170.65449 -134.926336) (xy 170.646662 -134.985792) (xy 170.631141 -135.043717)
			(xy 170.608192 -135.099121) (xy 170.578208 -135.151055) (xy 170.541702 -135.198631) (xy 170.499297 -135.241036)
			(xy 170.451721 -135.277542) (xy 170.399787 -135.307526) (xy 170.344383 -135.330475) (xy 170.286458 -135.345996)
			(xy 170.227002 -135.353824) (xy 170.167034 -135.353824) (xy 170.107578 -135.345996) (xy 170.049653 -135.330475)
			(xy 169.994249 -135.307526) (xy 169.942315 -135.277542) (xy 169.894739 -135.241036) (xy 169.852334 -135.198631)
			(xy 169.815828 -135.151055) (xy 169.785844 -135.099121) (xy 169.762895 -135.043717) (xy 169.747374 -134.985792)
			(xy 169.739546 -134.926336) (xy 169.739056 -134.896352) (xy 151.68372 -134.896352) (xy 151.68372 -134.897876)
			(xy 151.68323 -134.92786) (xy 151.675402 -134.987316) (xy 151.659881 -135.045241) (xy 151.636932 -135.100645)
			(xy 151.606948 -135.152579) (xy 151.570442 -135.200155) (xy 151.528037 -135.24256) (xy 151.480461 -135.279066)
			(xy 151.428527 -135.30905) (xy 151.373123 -135.331999) (xy 151.315198 -135.34752) (xy 151.255742 -135.355348)
			(xy 151.195774 -135.355348) (xy 151.136318 -135.34752) (xy 151.078393 -135.331999) (xy 151.022989 -135.30905)
			(xy 150.971055 -135.279066) (xy 150.923479 -135.24256) (xy 150.881074 -135.200155) (xy 150.844568 -135.152579)
			(xy 150.814584 -135.100645) (xy 150.791635 -135.045241) (xy 150.776114 -134.987316) (xy 150.768286 -134.92786)
			(xy 150.767796 -134.897876) (xy 84.369615 -134.897876) (xy 84.377099 -134.900976) (xy 84.429033 -134.93096)
			(xy 84.476609 -134.967466) (xy 84.519014 -135.009871) (xy 84.55552 -135.057447) (xy 84.585504 -135.109381)
			(xy 84.608453 -135.164785) (xy 84.623974 -135.22271) (xy 84.631802 -135.282166) (xy 84.632292 -135.31215)
			(xy 84.632292 -136.17575) (xy 84.631802 -136.205734) (xy 84.623974 -136.26519) (xy 84.608453 -136.323115)
			(xy 84.585504 -136.378519) (xy 84.55552 -136.430453) (xy 84.519014 -136.478029) (xy 84.476609 -136.520434)
			(xy 84.429033 -136.55694) (xy 84.377099 -136.586924) (xy 84.321695 -136.609873) (xy 84.26377 -136.625394)
			(xy 84.204314 -136.633222) (xy 84.144346 -136.633222) (xy 84.08489 -136.625394) (xy 84.026965 -136.609873)
			(xy 83.971561 -136.586924) (xy 83.919627 -136.55694) (xy 83.872051 -136.520434) (xy 83.829646 -136.478029)
			(xy 83.79314 -136.430453) (xy 83.763156 -136.378519) (xy 83.740207 -136.323115) (xy 83.724686 -136.26519)
			(xy 83.716858 -136.205734) (xy 83.716368 -136.17575) (xy 65.661032 -136.17575) (xy 65.661032 -136.177274)
			(xy 65.660542 -136.207258) (xy 65.652714 -136.266714) (xy 65.637193 -136.324639) (xy 65.614244 -136.380043)
			(xy 65.58426 -136.431977) (xy 65.547754 -136.479553) (xy 65.505349 -136.521958) (xy 65.457773 -136.558464)
			(xy 65.405839 -136.588448) (xy 65.350435 -136.611397) (xy 65.29251 -136.626918) (xy 65.233054 -136.634746)
			(xy 65.173086 -136.634746) (xy 65.11363 -136.626918) (xy 65.055705 -136.611397) (xy 65.000301 -136.588448)
			(xy 64.948367 -136.558464) (xy 64.900791 -136.521958) (xy 64.858386 -136.479553) (xy 64.82188 -136.431977)
			(xy 64.791896 -136.380043) (xy 64.768947 -136.324639) (xy 64.753426 -136.266714) (xy 64.745598 -136.207258)
			(xy 64.745108 -136.177274) (xy 52.700428 -136.177274) (xy 52.700428 -136.69645) (xy 52.700299 -136.704324)
			(xy 153.409904 -136.704324) (xy 153.409904 -135.840724) (xy 153.410394 -135.81074) (xy 153.418222 -135.751284)
			(xy 153.433743 -135.693359) (xy 153.456692 -135.637955) (xy 153.486676 -135.586021) (xy 153.523182 -135.538445)
			(xy 153.565587 -135.49604) (xy 153.613163 -135.459534) (xy 153.665097 -135.42955) (xy 153.720501 -135.406601)
			(xy 153.778426 -135.39108) (xy 153.837882 -135.383252) (xy 153.89785 -135.383252) (xy 153.957306 -135.39108)
			(xy 154.015231 -135.406601) (xy 154.070635 -135.42955) (xy 154.122569 -135.459534) (xy 154.170145 -135.49604)
			(xy 154.21255 -135.538445) (xy 154.249056 -135.586021) (xy 154.27904 -135.637955) (xy 154.301989 -135.693359)
			(xy 154.31751 -135.751284) (xy 154.325338 -135.81074) (xy 154.325828 -135.840724) (xy 154.325828 -136.69645)
			(xy 167.884856 -136.69645) (xy 167.884856 -135.83285) (xy 167.885346 -135.802866) (xy 167.893174 -135.74341)
			(xy 167.908695 -135.685485) (xy 167.931644 -135.630081) (xy 167.961628 -135.578147) (xy 167.998134 -135.530571)
			(xy 168.040539 -135.488166) (xy 168.088115 -135.45166) (xy 168.140049 -135.421676) (xy 168.195453 -135.398727)
			(xy 168.253378 -135.383206) (xy 168.312834 -135.375378) (xy 168.372802 -135.375378) (xy 168.432258 -135.383206)
			(xy 168.490183 -135.398727) (xy 168.545587 -135.421676) (xy 168.597521 -135.45166) (xy 168.645097 -135.488166)
			(xy 168.687502 -135.530571) (xy 168.724008 -135.578147) (xy 168.753992 -135.630081) (xy 168.776941 -135.685485)
			(xy 168.792462 -135.74341) (xy 168.80029 -135.802866) (xy 168.80078 -135.83285) (xy 168.80078 -136.177274)
			(xy 180.84546 -136.177274) (xy 180.84546 -135.313674) (xy 180.84595 -135.283706) (xy 180.853773 -135.224284)
			(xy 180.869286 -135.166391) (xy 180.892222 -135.111018) (xy 180.922189 -135.059112) (xy 180.958676 -135.011562)
			(xy 181.001056 -134.969182) (xy 181.048606 -134.932695) (xy 181.100512 -134.902728) (xy 181.155885 -134.879792)
			(xy 181.213778 -134.864279) (xy 181.2732 -134.856456) (xy 181.333136 -134.856456) (xy 181.392558 -134.864279)
			(xy 181.450451 -134.879792) (xy 181.505824 -134.902728) (xy 181.55773 -134.932695) (xy 181.60528 -134.969182)
			(xy 181.64766 -135.011562) (xy 181.684147 -135.059112) (xy 181.714114 -135.111018) (xy 181.73705 -135.166391)
			(xy 181.752563 -135.224284) (xy 181.760386 -135.283706) (xy 181.760876 -135.313674) (xy 181.760876 -136.17575)
			(xy 199.81672 -136.17575) (xy 199.81672 -135.31215) (xy 199.81721 -135.282182) (xy 199.825033 -135.22276)
			(xy 199.840546 -135.164867) (xy 199.863482 -135.109494) (xy 199.893449 -135.057588) (xy 199.929936 -135.010038)
			(xy 199.972316 -134.967658) (xy 200.019866 -134.931171) (xy 200.071772 -134.901204) (xy 200.127145 -134.878268)
			(xy 200.185038 -134.862755) (xy 200.24446 -134.854932) (xy 200.304396 -134.854932) (xy 200.363818 -134.862755)
			(xy 200.421711 -134.878268) (xy 200.469049 -134.897876) (xy 266.86764 -134.897876) (xy 266.86764 -134.034276)
			(xy 266.86813 -134.004292) (xy 266.875958 -133.944836) (xy 266.891479 -133.886911) (xy 266.914428 -133.831507)
			(xy 266.944412 -133.779573) (xy 266.980918 -133.731997) (xy 267.023323 -133.689592) (xy 267.070899 -133.653086)
			(xy 267.122833 -133.623102) (xy 267.178237 -133.600153) (xy 267.236162 -133.584632) (xy 267.295618 -133.576804)
			(xy 267.355586 -133.576804) (xy 267.415042 -133.584632) (xy 267.472967 -133.600153) (xy 267.528371 -133.623102)
			(xy 267.580305 -133.653086) (xy 267.627881 -133.689592) (xy 267.670286 -133.731997) (xy 267.706792 -133.779573)
			(xy 267.736776 -133.831507) (xy 267.759725 -133.886911) (xy 267.775246 -133.944836) (xy 267.783074 -134.004292)
			(xy 267.783564 -134.034276) (xy 267.783564 -134.896352) (xy 285.8389 -134.896352) (xy 285.8389 -134.032752)
			(xy 285.83939 -134.002768) (xy 285.847218 -133.943312) (xy 285.862739 -133.885387) (xy 285.885688 -133.829983)
			(xy 285.915672 -133.778049) (xy 285.952178 -133.730473) (xy 285.994583 -133.688068) (xy 286.042159 -133.651562)
			(xy 286.094093 -133.621578) (xy 286.149497 -133.598629) (xy 286.207422 -133.583108) (xy 286.266878 -133.57528)
			(xy 286.326846 -133.57528) (xy 286.386302 -133.583108) (xy 286.444227 -133.598629) (xy 286.499631 -133.621578)
			(xy 286.551565 -133.651562) (xy 286.599141 -133.688068) (xy 286.641546 -133.730473) (xy 286.678052 -133.778049)
			(xy 286.708036 -133.829983) (xy 286.730985 -133.885387) (xy 286.746506 -133.943312) (xy 286.754334 -134.002768)
			(xy 286.754824 -134.032752) (xy 286.754824 -134.377176) (xy 298.799504 -134.377176) (xy 298.799504 -133.513576)
			(xy 298.799994 -133.483608) (xy 298.807817 -133.424186) (xy 298.82333 -133.366293) (xy 298.846266 -133.31092)
			(xy 298.876233 -133.259014) (xy 298.91272 -133.211464) (xy 298.9551 -133.169084) (xy 299.00265 -133.132597)
			(xy 299.054556 -133.10263) (xy 299.109929 -133.079694) (xy 299.167822 -133.064181) (xy 299.227244 -133.056358)
			(xy 299.28718 -133.056358) (xy 299.346602 -133.064181) (xy 299.404495 -133.079694) (xy 299.459868 -133.10263)
			(xy 299.511774 -133.132597) (xy 299.559324 -133.169084) (xy 299.601704 -133.211464) (xy 299.638191 -133.259014)
			(xy 299.668158 -133.31092) (xy 299.691094 -133.366293) (xy 299.706607 -133.424186) (xy 299.71443 -133.483608)
			(xy 299.71492 -133.513576) (xy 299.71492 -134.369302) (xy 313.274456 -134.369302) (xy 313.274456 -133.505702)
			(xy 313.274946 -133.475734) (xy 313.282769 -133.416312) (xy 313.298282 -133.358419) (xy 313.321218 -133.303046)
			(xy 313.351185 -133.25114) (xy 313.387672 -133.20359) (xy 313.430052 -133.16121) (xy 313.477602 -133.124723)
			(xy 313.529508 -133.094756) (xy 313.584881 -133.07182) (xy 313.642774 -133.056307) (xy 313.702196 -133.048484)
			(xy 313.762132 -133.048484) (xy 313.821554 -133.056307) (xy 313.879447 -133.07182) (xy 313.93482 -133.094756)
			(xy 313.951493 -133.104382) (xy 385.6101 -133.104382) (xy 385.6101 -132.240782) (xy 385.61059 -132.210814)
			(xy 385.618413 -132.151392) (xy 385.633926 -132.093499) (xy 385.656862 -132.038126) (xy 385.686829 -131.98622)
			(xy 385.723316 -131.93867) (xy 385.765696 -131.89629) (xy 385.813246 -131.859803) (xy 385.865152 -131.829836)
			(xy 385.920525 -131.8069) (xy 385.978418 -131.791387) (xy 386.03784 -131.783564) (xy 386.097776 -131.783564)
			(xy 386.157198 -131.791387) (xy 386.215091 -131.8069) (xy 386.270464 -131.829836) (xy 386.32237 -131.859803)
			(xy 386.36992 -131.89629) (xy 386.4123 -131.93867) (xy 386.448787 -131.98622) (xy 386.478754 -132.038126)
			(xy 386.50169 -132.093499) (xy 386.517203 -132.151392) (xy 386.525026 -132.210814) (xy 386.525516 -132.240782)
			(xy 386.525516 -133.096508) (xy 400.085052 -133.096508) (xy 400.085052 -132.232908) (xy 400.085542 -132.20294)
			(xy 400.093365 -132.143518) (xy 400.108878 -132.085625) (xy 400.131814 -132.030252) (xy 400.161781 -131.978346)
			(xy 400.198268 -131.930796) (xy 400.240648 -131.888416) (xy 400.288198 -131.851929) (xy 400.340104 -131.821962)
			(xy 400.395477 -131.799026) (xy 400.45337 -131.783513) (xy 400.512792 -131.77569) (xy 400.572728 -131.77569)
			(xy 400.63215 -131.783513) (xy 400.690043 -131.799026) (xy 400.745416 -131.821962) (xy 400.797322 -131.851929)
			(xy 400.844872 -131.888416) (xy 400.887252 -131.930796) (xy 400.923739 -131.978346) (xy 400.953706 -132.030252)
			(xy 400.976642 -132.085625) (xy 400.992155 -132.143518) (xy 400.999978 -132.20294) (xy 401.000468 -132.232908)
			(xy 401.000468 -132.577332) (xy 413.045148 -132.577332) (xy 413.045148 -131.713732) (xy 413.045638 -131.683748)
			(xy 413.053466 -131.624292) (xy 413.068987 -131.566367) (xy 413.091936 -131.510963) (xy 413.12192 -131.459029)
			(xy 413.158426 -131.411453) (xy 413.200831 -131.369048) (xy 413.248407 -131.332542) (xy 413.300341 -131.302558)
			(xy 413.355745 -131.279609) (xy 413.41367 -131.264088) (xy 413.473126 -131.25626) (xy 413.533094 -131.25626)
			(xy 413.59255 -131.264088) (xy 413.650475 -131.279609) (xy 413.705879 -131.302558) (xy 413.757813 -131.332542)
			(xy 413.805389 -131.369048) (xy 413.847794 -131.411453) (xy 413.8843 -131.459029) (xy 413.914284 -131.510963)
			(xy 413.937233 -131.566367) (xy 413.952754 -131.624292) (xy 413.960582 -131.683748) (xy 413.961072 -131.713732)
			(xy 413.961072 -132.575808) (xy 432.016408 -132.575808) (xy 432.016408 -131.712208) (xy 432.016898 -131.682224)
			(xy 432.024726 -131.622768) (xy 432.040247 -131.564843) (xy 432.063196 -131.509439) (xy 432.09318 -131.457505)
			(xy 432.129686 -131.409929) (xy 432.172091 -131.367524) (xy 432.219667 -131.331018) (xy 432.271601 -131.301034)
			(xy 432.327005 -131.278085) (xy 432.38493 -131.262564) (xy 432.444386 -131.254736) (xy 432.504354 -131.254736)
			(xy 432.56381 -131.262564) (xy 432.621735 -131.278085) (xy 432.677139 -131.301034) (xy 432.729073 -131.331018)
			(xy 432.776649 -131.367524) (xy 432.819054 -131.409929) (xy 432.85556 -131.457505) (xy 432.885544 -131.509439)
			(xy 432.908493 -131.564843) (xy 432.924014 -131.622768) (xy 432.931842 -131.682224) (xy 432.932332 -131.712208)
			(xy 432.932332 -132.575808) (xy 432.931842 -132.605792) (xy 432.924014 -132.665248) (xy 432.908493 -132.723173)
			(xy 432.885544 -132.778577) (xy 432.85556 -132.830511) (xy 432.819054 -132.878087) (xy 432.776649 -132.920492)
			(xy 432.729073 -132.956998) (xy 432.677139 -132.986982) (xy 432.621735 -133.009931) (xy 432.56381 -133.025452)
			(xy 432.504354 -133.03328) (xy 432.444386 -133.03328) (xy 432.38493 -133.025452) (xy 432.327005 -133.009931)
			(xy 432.271601 -132.986982) (xy 432.219667 -132.956998) (xy 432.172091 -132.920492) (xy 432.129686 -132.878087)
			(xy 432.09318 -132.830511) (xy 432.063196 -132.778577) (xy 432.040247 -132.723173) (xy 432.024726 -132.665248)
			(xy 432.016898 -132.605792) (xy 432.016408 -132.575808) (xy 413.961072 -132.575808) (xy 413.961072 -132.577332)
			(xy 413.960582 -132.607316) (xy 413.952754 -132.666772) (xy 413.937233 -132.724697) (xy 413.914284 -132.780101)
			(xy 413.8843 -132.832035) (xy 413.847794 -132.879611) (xy 413.805389 -132.922016) (xy 413.757813 -132.958522)
			(xy 413.705879 -132.988506) (xy 413.650475 -133.011455) (xy 413.59255 -133.026976) (xy 413.533094 -133.034804)
			(xy 413.473126 -133.034804) (xy 413.41367 -133.026976) (xy 413.355745 -133.011455) (xy 413.300341 -132.988506)
			(xy 413.248407 -132.958522) (xy 413.200831 -132.922016) (xy 413.158426 -132.879611) (xy 413.12192 -132.832035)
			(xy 413.091936 -132.780101) (xy 413.068987 -132.724697) (xy 413.053466 -132.666772) (xy 413.045638 -132.607316)
			(xy 413.045148 -132.577332) (xy 401.000468 -132.577332) (xy 401.000468 -133.096508) (xy 400.999978 -133.126476)
			(xy 400.992155 -133.185898) (xy 400.976642 -133.243791) (xy 400.953706 -133.299164) (xy 400.923739 -133.35107)
			(xy 400.887252 -133.39862) (xy 400.844872 -133.441) (xy 400.797322 -133.477487) (xy 400.745416 -133.507454)
			(xy 400.690043 -133.53039) (xy 400.63215 -133.545903) (xy 400.572728 -133.553726) (xy 400.512792 -133.553726)
			(xy 400.45337 -133.545903) (xy 400.395477 -133.53039) (xy 400.340104 -133.507454) (xy 400.288198 -133.477487)
			(xy 400.240648 -133.441) (xy 400.198268 -133.39862) (xy 400.161781 -133.35107) (xy 400.131814 -133.299164)
			(xy 400.108878 -133.243791) (xy 400.093365 -133.185898) (xy 400.085542 -133.126476) (xy 400.085052 -133.096508)
			(xy 386.525516 -133.096508) (xy 386.525516 -133.104382) (xy 386.525026 -133.13435) (xy 386.517203 -133.193772)
			(xy 386.50169 -133.251665) (xy 386.478754 -133.307038) (xy 386.448787 -133.358944) (xy 386.4123 -133.406494)
			(xy 386.36992 -133.448874) (xy 386.32237 -133.485361) (xy 386.270464 -133.515328) (xy 386.215091 -133.538264)
			(xy 386.157198 -133.553777) (xy 386.097776 -133.5616) (xy 386.03784 -133.5616) (xy 385.978418 -133.553777)
			(xy 385.920525 -133.538264) (xy 385.865152 -133.515328) (xy 385.813246 -133.485361) (xy 385.765696 -133.448874)
			(xy 385.723316 -133.406494) (xy 385.686829 -133.358944) (xy 385.656862 -133.307038) (xy 385.633926 -133.251665)
			(xy 385.618413 -133.193772) (xy 385.61059 -133.13435) (xy 385.6101 -133.104382) (xy 313.951493 -133.104382)
			(xy 313.986726 -133.124723) (xy 314.034276 -133.16121) (xy 314.076656 -133.20359) (xy 314.113143 -133.25114)
			(xy 314.14311 -133.303046) (xy 314.166046 -133.358419) (xy 314.181559 -133.416312) (xy 314.189382 -133.475734)
			(xy 314.189872 -133.505702) (xy 314.189872 -134.369302) (xy 314.189382 -134.39927) (xy 314.181559 -134.458692)
			(xy 314.166046 -134.516585) (xy 314.14311 -134.571958) (xy 314.113143 -134.623864) (xy 314.076656 -134.671414)
			(xy 314.034276 -134.713794) (xy 313.986726 -134.750281) (xy 313.93482 -134.780248) (xy 313.879447 -134.803184)
			(xy 313.821554 -134.818697) (xy 313.762132 -134.82652) (xy 313.702196 -134.82652) (xy 313.642774 -134.818697)
			(xy 313.584881 -134.803184) (xy 313.529508 -134.780248) (xy 313.477602 -134.750281) (xy 313.430052 -134.713794)
			(xy 313.387672 -134.671414) (xy 313.351185 -134.623864) (xy 313.321218 -134.571958) (xy 313.298282 -134.516585)
			(xy 313.282769 -134.458692) (xy 313.274946 -134.39927) (xy 313.274456 -134.369302) (xy 299.71492 -134.369302)
			(xy 299.71492 -134.377176) (xy 299.71443 -134.407144) (xy 299.706607 -134.466566) (xy 299.691094 -134.524459)
			(xy 299.668158 -134.579832) (xy 299.638191 -134.631738) (xy 299.601704 -134.679288) (xy 299.559324 -134.721668)
			(xy 299.511774 -134.758155) (xy 299.459868 -134.788122) (xy 299.404495 -134.811058) (xy 299.346602 -134.826571)
			(xy 299.28718 -134.834394) (xy 299.227244 -134.834394) (xy 299.167822 -134.826571) (xy 299.109929 -134.811058)
			(xy 299.054556 -134.788122) (xy 299.00265 -134.758155) (xy 298.9551 -134.721668) (xy 298.91272 -134.679288)
			(xy 298.876233 -134.631738) (xy 298.846266 -134.579832) (xy 298.82333 -134.524459) (xy 298.807817 -134.466566)
			(xy 298.799994 -134.407144) (xy 298.799504 -134.377176) (xy 286.754824 -134.377176) (xy 286.754824 -134.896352)
			(xy 286.754334 -134.926336) (xy 286.746506 -134.985792) (xy 286.730985 -135.043717) (xy 286.708036 -135.099121)
			(xy 286.678052 -135.151055) (xy 286.641546 -135.198631) (xy 286.599141 -135.241036) (xy 286.551565 -135.277542)
			(xy 286.499631 -135.307526) (xy 286.444227 -135.330475) (xy 286.386302 -135.345996) (xy 286.326846 -135.353824)
			(xy 286.266878 -135.353824) (xy 286.207422 -135.345996) (xy 286.149497 -135.330475) (xy 286.094093 -135.307526)
			(xy 286.042159 -135.277542) (xy 285.994583 -135.241036) (xy 285.952178 -135.198631) (xy 285.915672 -135.151055)
			(xy 285.885688 -135.099121) (xy 285.862739 -135.043717) (xy 285.847218 -134.985792) (xy 285.83939 -134.926336)
			(xy 285.8389 -134.896352) (xy 267.783564 -134.896352) (xy 267.783564 -134.897876) (xy 267.783074 -134.92786)
			(xy 267.775246 -134.987316) (xy 267.759725 -135.045241) (xy 267.736776 -135.100645) (xy 267.706792 -135.152579)
			(xy 267.670286 -135.200155) (xy 267.627881 -135.24256) (xy 267.580305 -135.279066) (xy 267.528371 -135.30905)
			(xy 267.472967 -135.331999) (xy 267.415042 -135.34752) (xy 267.355586 -135.355348) (xy 267.295618 -135.355348)
			(xy 267.236162 -135.34752) (xy 267.178237 -135.331999) (xy 267.122833 -135.30905) (xy 267.070899 -135.279066)
			(xy 267.023323 -135.24256) (xy 266.980918 -135.200155) (xy 266.944412 -135.152579) (xy 266.914428 -135.100645)
			(xy 266.891479 -135.045241) (xy 266.875958 -134.987316) (xy 266.86813 -134.92786) (xy 266.86764 -134.897876)
			(xy 200.469049 -134.897876) (xy 200.477084 -134.901204) (xy 200.52899 -134.931171) (xy 200.57654 -134.967658)
			(xy 200.61892 -135.010038) (xy 200.655407 -135.057588) (xy 200.685374 -135.109494) (xy 200.70831 -135.164867)
			(xy 200.723823 -135.22276) (xy 200.731646 -135.282182) (xy 200.732136 -135.31215) (xy 200.732136 -136.17575)
			(xy 200.731646 -136.205718) (xy 200.723823 -136.26514) (xy 200.70831 -136.323033) (xy 200.685374 -136.378406)
			(xy 200.655407 -136.430312) (xy 200.61892 -136.477862) (xy 200.57654 -136.520242) (xy 200.52899 -136.556729)
			(xy 200.477084 -136.586696) (xy 200.421711 -136.609632) (xy 200.363818 -136.625145) (xy 200.304396 -136.632968)
			(xy 200.24446 -136.632968) (xy 200.185038 -136.625145) (xy 200.127145 -136.609632) (xy 200.071772 -136.586696)
			(xy 200.019866 -136.556729) (xy 199.972316 -136.520242) (xy 199.929936 -136.477862) (xy 199.893449 -136.430312)
			(xy 199.863482 -136.378406) (xy 199.840546 -136.323033) (xy 199.825033 -136.26514) (xy 199.81721 -136.205718)
			(xy 199.81672 -136.17575) (xy 181.760876 -136.17575) (xy 181.760876 -136.177274) (xy 181.760386 -136.207242)
			(xy 181.752563 -136.266664) (xy 181.73705 -136.324557) (xy 181.714114 -136.37993) (xy 181.684147 -136.431836)
			(xy 181.64766 -136.479386) (xy 181.60528 -136.521766) (xy 181.55773 -136.558253) (xy 181.505824 -136.58822)
			(xy 181.450451 -136.611156) (xy 181.392558 -136.626669) (xy 181.333136 -136.634492) (xy 181.2732 -136.634492)
			(xy 181.213778 -136.626669) (xy 181.155885 -136.611156) (xy 181.100512 -136.58822) (xy 181.048606 -136.558253)
			(xy 181.001056 -136.521766) (xy 180.958676 -136.479386) (xy 180.922189 -136.431836) (xy 180.892222 -136.37993)
			(xy 180.869286 -136.324557) (xy 180.853773 -136.266664) (xy 180.84595 -136.207242) (xy 180.84546 -136.177274)
			(xy 168.80078 -136.177274) (xy 168.80078 -136.69645) (xy 168.800651 -136.704324) (xy 269.509748 -136.704324)
			(xy 269.509748 -135.840724) (xy 269.510238 -135.81074) (xy 269.518066 -135.751284) (xy 269.533587 -135.693359)
			(xy 269.556536 -135.637955) (xy 269.58652 -135.586021) (xy 269.623026 -135.538445) (xy 269.665431 -135.49604)
			(xy 269.713007 -135.459534) (xy 269.764941 -135.42955) (xy 269.820345 -135.406601) (xy 269.87827 -135.39108)
			(xy 269.937726 -135.383252) (xy 269.997694 -135.383252) (xy 270.05715 -135.39108) (xy 270.115075 -135.406601)
			(xy 270.170479 -135.42955) (xy 270.222413 -135.459534) (xy 270.269989 -135.49604) (xy 270.312394 -135.538445)
			(xy 270.3489 -135.586021) (xy 270.378884 -135.637955) (xy 270.401833 -135.693359) (xy 270.417354 -135.751284)
			(xy 270.425182 -135.81074) (xy 270.425672 -135.840724) (xy 270.425672 -136.69645) (xy 283.9847 -136.69645)
			(xy 283.9847 -135.83285) (xy 283.98519 -135.802866) (xy 283.993018 -135.74341) (xy 284.008539 -135.685485)
			(xy 284.031488 -135.630081) (xy 284.061472 -135.578147) (xy 284.097978 -135.530571) (xy 284.140383 -135.488166)
			(xy 284.187959 -135.45166) (xy 284.239893 -135.421676) (xy 284.295297 -135.398727) (xy 284.353222 -135.383206)
			(xy 284.412678 -135.375378) (xy 284.472646 -135.375378) (xy 284.532102 -135.383206) (xy 284.590027 -135.398727)
			(xy 284.645431 -135.421676) (xy 284.697365 -135.45166) (xy 284.744941 -135.488166) (xy 284.787346 -135.530571)
			(xy 284.823852 -135.578147) (xy 284.853836 -135.630081) (xy 284.876785 -135.685485) (xy 284.892306 -135.74341)
			(xy 284.900134 -135.802866) (xy 284.900624 -135.83285) (xy 284.900624 -136.177274) (xy 296.945304 -136.177274)
			(xy 296.945304 -135.313674) (xy 296.945794 -135.283706) (xy 296.953617 -135.224284) (xy 296.96913 -135.166391)
			(xy 296.992066 -135.111018) (xy 297.022033 -135.059112) (xy 297.05852 -135.011562) (xy 297.1009 -134.969182)
			(xy 297.14845 -134.932695) (xy 297.200356 -134.902728) (xy 297.255729 -134.879792) (xy 297.313622 -134.864279)
			(xy 297.373044 -134.856456) (xy 297.43298 -134.856456) (xy 297.492402 -134.864279) (xy 297.550295 -134.879792)
			(xy 297.605668 -134.902728) (xy 297.657574 -134.932695) (xy 297.705124 -134.969182) (xy 297.747504 -135.011562)
			(xy 297.783991 -135.059112) (xy 297.813958 -135.111018) (xy 297.836894 -135.166391) (xy 297.852407 -135.224284)
			(xy 297.86023 -135.283706) (xy 297.86072 -135.313674) (xy 297.86072 -136.17575) (xy 315.916564 -136.17575)
			(xy 315.916564 -135.31215) (xy 315.917054 -135.282182) (xy 315.924877 -135.22276) (xy 315.94039 -135.164867)
			(xy 315.963326 -135.109494) (xy 315.993293 -135.057588) (xy 316.02978 -135.010038) (xy 316.07216 -134.967658)
			(xy 316.11971 -134.931171) (xy 316.171616 -134.901204) (xy 316.226989 -134.878268) (xy 316.284882 -134.862755)
			(xy 316.344304 -134.854932) (xy 316.40424 -134.854932) (xy 316.463662 -134.862755) (xy 316.521555 -134.878268)
			(xy 316.568893 -134.897876) (xy 382.967992 -134.897876) (xy 382.967992 -134.034276) (xy 382.968482 -134.004308)
			(xy 382.976305 -133.944886) (xy 382.991818 -133.886993) (xy 383.014754 -133.83162) (xy 383.044721 -133.779714)
			(xy 383.081208 -133.732164) (xy 383.123588 -133.689784) (xy 383.171138 -133.653297) (xy 383.223044 -133.62333)
			(xy 383.278417 -133.600394) (xy 383.33631 -133.584881) (xy 383.395732 -133.577058) (xy 383.455668 -133.577058)
			(xy 383.51509 -133.584881) (xy 383.572983 -133.600394) (xy 383.628356 -133.62333) (xy 383.680262 -133.653297)
			(xy 383.727812 -133.689784) (xy 383.770192 -133.732164) (xy 383.806679 -133.779714) (xy 383.836646 -133.83162)
			(xy 383.859582 -133.886993) (xy 383.875095 -133.944886) (xy 383.882918 -134.004308) (xy 383.883408 -134.034276)
			(xy 383.883408 -134.896352) (xy 401.939252 -134.896352) (xy 401.939252 -134.032752) (xy 401.939742 -134.002784)
			(xy 401.947565 -133.943362) (xy 401.963078 -133.885469) (xy 401.986014 -133.830096) (xy 402.015981 -133.77819)
			(xy 402.052468 -133.73064) (xy 402.094848 -133.68826) (xy 402.142398 -133.651773) (xy 402.194304 -133.621806)
			(xy 402.249677 -133.59887) (xy 402.30757 -133.583357) (xy 402.366992 -133.575534) (xy 402.426928 -133.575534)
			(xy 402.48635 -133.583357) (xy 402.544243 -133.59887) (xy 402.599616 -133.621806) (xy 402.651522 -133.651773)
			(xy 402.699072 -133.68826) (xy 402.741452 -133.73064) (xy 402.777939 -133.77819) (xy 402.807906 -133.830096)
			(xy 402.830842 -133.885469) (xy 402.846355 -133.943362) (xy 402.854178 -134.002784) (xy 402.854668 -134.032752)
			(xy 402.854668 -134.377176) (xy 414.899348 -134.377176) (xy 414.899348 -133.513576) (xy 414.899838 -133.483592)
			(xy 414.907666 -133.424136) (xy 414.923187 -133.366211) (xy 414.946136 -133.310807) (xy 414.97612 -133.258873)
			(xy 415.012626 -133.211297) (xy 415.055031 -133.168892) (xy 415.102607 -133.132386) (xy 415.154541 -133.102402)
			(xy 415.209945 -133.079453) (xy 415.26787 -133.063932) (xy 415.327326 -133.056104) (xy 415.387294 -133.056104)
			(xy 415.44675 -133.063932) (xy 415.504675 -133.079453) (xy 415.560079 -133.102402) (xy 415.612013 -133.132386)
			(xy 415.659589 -133.168892) (xy 415.701994 -133.211297) (xy 415.7385 -133.258873) (xy 415.768484 -133.310807)
			(xy 415.791433 -133.366211) (xy 415.806954 -133.424136) (xy 415.814782 -133.483592) (xy 415.815272 -133.513576)
			(xy 415.815272 -134.369302) (xy 429.3743 -134.369302) (xy 429.3743 -133.505702) (xy 429.37479 -133.475718)
			(xy 429.382618 -133.416262) (xy 429.398139 -133.358337) (xy 429.421088 -133.302933) (xy 429.451072 -133.250999)
			(xy 429.487578 -133.203423) (xy 429.529983 -133.161018) (xy 429.577559 -133.124512) (xy 429.629493 -133.094528)
			(xy 429.684897 -133.071579) (xy 429.742822 -133.056058) (xy 429.802278 -133.04823) (xy 429.862246 -133.04823)
			(xy 429.921702 -133.056058) (xy 429.979627 -133.071579) (xy 430.035031 -133.094528) (xy 430.086965 -133.124512)
			(xy 430.134541 -133.161018) (xy 430.176946 -133.203423) (xy 430.213452 -133.250999) (xy 430.243436 -133.302933)
			(xy 430.266385 -133.358337) (xy 430.281906 -133.416262) (xy 430.289734 -133.475718) (xy 430.290224 -133.505702)
			(xy 430.290224 -134.369302) (xy 430.289734 -134.399286) (xy 430.281906 -134.458742) (xy 430.266385 -134.516667)
			(xy 430.243436 -134.572071) (xy 430.213452 -134.624005) (xy 430.176946 -134.671581) (xy 430.134541 -134.713986)
			(xy 430.086965 -134.750492) (xy 430.035031 -134.780476) (xy 429.979627 -134.803425) (xy 429.921702 -134.818946)
			(xy 429.862246 -134.826774) (xy 429.802278 -134.826774) (xy 429.742822 -134.818946) (xy 429.684897 -134.803425)
			(xy 429.629493 -134.780476) (xy 429.577559 -134.750492) (xy 429.529983 -134.713986) (xy 429.487578 -134.671581)
			(xy 429.451072 -134.624005) (xy 429.421088 -134.572071) (xy 429.398139 -134.516667) (xy 429.382618 -134.458742)
			(xy 429.37479 -134.399286) (xy 429.3743 -134.369302) (xy 415.815272 -134.369302) (xy 415.815272 -134.377176)
			(xy 415.814782 -134.40716) (xy 415.806954 -134.466616) (xy 415.791433 -134.524541) (xy 415.768484 -134.579945)
			(xy 415.7385 -134.631879) (xy 415.701994 -134.679455) (xy 415.659589 -134.72186) (xy 415.612013 -134.758366)
			(xy 415.560079 -134.78835) (xy 415.504675 -134.811299) (xy 415.44675 -134.82682) (xy 415.387294 -134.834648)
			(xy 415.327326 -134.834648) (xy 415.26787 -134.82682) (xy 415.209945 -134.811299) (xy 415.154541 -134.78835)
			(xy 415.102607 -134.758366) (xy 415.055031 -134.72186) (xy 415.012626 -134.679455) (xy 414.97612 -134.631879)
			(xy 414.946136 -134.579945) (xy 414.923187 -134.524541) (xy 414.907666 -134.466616) (xy 414.899838 -134.40716)
			(xy 414.899348 -134.377176) (xy 402.854668 -134.377176) (xy 402.854668 -134.896352) (xy 402.854178 -134.92632)
			(xy 402.846355 -134.985742) (xy 402.830842 -135.043635) (xy 402.807906 -135.099008) (xy 402.777939 -135.150914)
			(xy 402.741452 -135.198464) (xy 402.699072 -135.240844) (xy 402.651522 -135.277331) (xy 402.599616 -135.307298)
			(xy 402.544243 -135.330234) (xy 402.48635 -135.345747) (xy 402.426928 -135.35357) (xy 402.366992 -135.35357)
			(xy 402.30757 -135.345747) (xy 402.249677 -135.330234) (xy 402.194304 -135.307298) (xy 402.142398 -135.277331)
			(xy 402.094848 -135.240844) (xy 402.052468 -135.198464) (xy 402.015981 -135.150914) (xy 401.986014 -135.099008)
			(xy 401.963078 -135.043635) (xy 401.947565 -134.985742) (xy 401.939742 -134.92632) (xy 401.939252 -134.896352)
			(xy 383.883408 -134.896352) (xy 383.883408 -134.897876) (xy 383.882918 -134.927844) (xy 383.875095 -134.987266)
			(xy 383.859582 -135.045159) (xy 383.836646 -135.100532) (xy 383.806679 -135.152438) (xy 383.770192 -135.199988)
			(xy 383.727812 -135.242368) (xy 383.680262 -135.278855) (xy 383.628356 -135.308822) (xy 383.572983 -135.331758)
			(xy 383.51509 -135.347271) (xy 383.455668 -135.355094) (xy 383.395732 -135.355094) (xy 383.33631 -135.347271)
			(xy 383.278417 -135.331758) (xy 383.223044 -135.308822) (xy 383.171138 -135.278855) (xy 383.123588 -135.242368)
			(xy 383.081208 -135.199988) (xy 383.044721 -135.152438) (xy 383.014754 -135.100532) (xy 382.991818 -135.045159)
			(xy 382.976305 -134.987266) (xy 382.968482 -134.927844) (xy 382.967992 -134.897876) (xy 316.568893 -134.897876)
			(xy 316.576928 -134.901204) (xy 316.628834 -134.931171) (xy 316.676384 -134.967658) (xy 316.718764 -135.010038)
			(xy 316.755251 -135.057588) (xy 316.785218 -135.109494) (xy 316.808154 -135.164867) (xy 316.823667 -135.22276)
			(xy 316.83149 -135.282182) (xy 316.83198 -135.31215) (xy 316.83198 -136.17575) (xy 316.83149 -136.205718)
			(xy 316.823667 -136.26514) (xy 316.808154 -136.323033) (xy 316.785218 -136.378406) (xy 316.755251 -136.430312)
			(xy 316.718764 -136.477862) (xy 316.676384 -136.520242) (xy 316.628834 -136.556729) (xy 316.576928 -136.586696)
			(xy 316.521555 -136.609632) (xy 316.463662 -136.625145) (xy 316.40424 -136.632968) (xy 316.344304 -136.632968)
			(xy 316.284882 -136.625145) (xy 316.226989 -136.609632) (xy 316.171616 -136.586696) (xy 316.11971 -136.556729)
			(xy 316.07216 -136.520242) (xy 316.02978 -136.477862) (xy 315.993293 -136.430312) (xy 315.963326 -136.378406)
			(xy 315.94039 -136.323033) (xy 315.924877 -136.26514) (xy 315.917054 -136.205718) (xy 315.916564 -136.17575)
			(xy 297.86072 -136.17575) (xy 297.86072 -136.177274) (xy 297.86023 -136.207242) (xy 297.852407 -136.266664)
			(xy 297.836894 -136.324557) (xy 297.813958 -136.37993) (xy 297.783991 -136.431836) (xy 297.747504 -136.479386)
			(xy 297.705124 -136.521766) (xy 297.657574 -136.558253) (xy 297.605668 -136.58822) (xy 297.550295 -136.611156)
			(xy 297.492402 -136.626669) (xy 297.43298 -136.634492) (xy 297.373044 -136.634492) (xy 297.313622 -136.626669)
			(xy 297.255729 -136.611156) (xy 297.200356 -136.58822) (xy 297.14845 -136.558253) (xy 297.1009 -136.521766)
			(xy 297.05852 -136.479386) (xy 297.022033 -136.431836) (xy 296.992066 -136.37993) (xy 296.96913 -136.324557)
			(xy 296.953617 -136.266664) (xy 296.945794 -136.207242) (xy 296.945304 -136.177274) (xy 284.900624 -136.177274)
			(xy 284.900624 -136.69645) (xy 284.900495 -136.704324) (xy 385.6101 -136.704324) (xy 385.6101 -135.840724)
			(xy 385.61059 -135.810756) (xy 385.618413 -135.751334) (xy 385.633926 -135.693441) (xy 385.656862 -135.638068)
			(xy 385.686829 -135.586162) (xy 385.723316 -135.538612) (xy 385.765696 -135.496232) (xy 385.813246 -135.459745)
			(xy 385.865152 -135.429778) (xy 385.920525 -135.406842) (xy 385.978418 -135.391329) (xy 386.03784 -135.383506)
			(xy 386.097776 -135.383506) (xy 386.157198 -135.391329) (xy 386.215091 -135.406842) (xy 386.270464 -135.429778)
			(xy 386.32237 -135.459745) (xy 386.36992 -135.496232) (xy 386.4123 -135.538612) (xy 386.448787 -135.586162)
			(xy 386.478754 -135.638068) (xy 386.50169 -135.693441) (xy 386.517203 -135.751334) (xy 386.525026 -135.810756)
			(xy 386.525516 -135.840724) (xy 386.525516 -136.69645) (xy 400.085052 -136.69645) (xy 400.085052 -135.83285)
			(xy 400.085542 -135.802882) (xy 400.093365 -135.74346) (xy 400.108878 -135.685567) (xy 400.131814 -135.630194)
			(xy 400.161781 -135.578288) (xy 400.198268 -135.530738) (xy 400.240648 -135.488358) (xy 400.288198 -135.451871)
			(xy 400.340104 -135.421904) (xy 400.395477 -135.398968) (xy 400.45337 -135.383455) (xy 400.512792 -135.375632)
			(xy 400.572728 -135.375632) (xy 400.63215 -135.383455) (xy 400.690043 -135.398968) (xy 400.745416 -135.421904)
			(xy 400.797322 -135.451871) (xy 400.844872 -135.488358) (xy 400.887252 -135.530738) (xy 400.923739 -135.578288)
			(xy 400.953706 -135.630194) (xy 400.976642 -135.685567) (xy 400.992155 -135.74346) (xy 400.999978 -135.802882)
			(xy 401.000468 -135.83285) (xy 401.000468 -136.177274) (xy 413.045148 -136.177274) (xy 413.045148 -135.313674)
			(xy 413.045638 -135.28369) (xy 413.053466 -135.224234) (xy 413.068987 -135.166309) (xy 413.091936 -135.110905)
			(xy 413.12192 -135.058971) (xy 413.158426 -135.011395) (xy 413.200831 -134.96899) (xy 413.248407 -134.932484)
			(xy 413.300341 -134.9025) (xy 413.355745 -134.879551) (xy 413.41367 -134.86403) (xy 413.473126 -134.856202)
			(xy 413.533094 -134.856202) (xy 413.59255 -134.86403) (xy 413.650475 -134.879551) (xy 413.705879 -134.9025)
			(xy 413.757813 -134.932484) (xy 413.805389 -134.96899) (xy 413.847794 -135.011395) (xy 413.8843 -135.058971)
			(xy 413.914284 -135.110905) (xy 413.937233 -135.166309) (xy 413.952754 -135.224234) (xy 413.960582 -135.28369)
			(xy 413.961072 -135.313674) (xy 413.961072 -136.17575) (xy 432.016408 -136.17575) (xy 432.016408 -135.31215)
			(xy 432.016898 -135.282166) (xy 432.024726 -135.22271) (xy 432.040247 -135.164785) (xy 432.063196 -135.109381)
			(xy 432.09318 -135.057447) (xy 432.129686 -135.009871) (xy 432.172091 -134.967466) (xy 432.219667 -134.93096)
			(xy 432.271601 -134.900976) (xy 432.327005 -134.878027) (xy 432.38493 -134.862506) (xy 432.444386 -134.854678)
			(xy 432.504354 -134.854678) (xy 432.56381 -134.862506) (xy 432.621735 -134.878027) (xy 432.677139 -134.900976)
			(xy 432.729073 -134.93096) (xy 432.776649 -134.967466) (xy 432.819054 -135.009871) (xy 432.85556 -135.057447)
			(xy 432.885544 -135.109381) (xy 432.908493 -135.164785) (xy 432.924014 -135.22271) (xy 432.931842 -135.282166)
			(xy 432.932332 -135.31215) (xy 432.932332 -136.17575) (xy 432.931842 -136.205734) (xy 432.924014 -136.26519)
			(xy 432.908493 -136.323115) (xy 432.885544 -136.378519) (xy 432.85556 -136.430453) (xy 432.819054 -136.478029)
			(xy 432.776649 -136.520434) (xy 432.729073 -136.55694) (xy 432.677139 -136.586924) (xy 432.621735 -136.609873)
			(xy 432.56381 -136.625394) (xy 432.504354 -136.633222) (xy 432.444386 -136.633222) (xy 432.38493 -136.625394)
			(xy 432.327005 -136.609873) (xy 432.271601 -136.586924) (xy 432.219667 -136.55694) (xy 432.172091 -136.520434)
			(xy 432.129686 -136.478029) (xy 432.09318 -136.430453) (xy 432.063196 -136.378519) (xy 432.040247 -136.323115)
			(xy 432.024726 -136.26519) (xy 432.016898 -136.205734) (xy 432.016408 -136.17575) (xy 413.961072 -136.17575)
			(xy 413.961072 -136.177274) (xy 413.960582 -136.207258) (xy 413.952754 -136.266714) (xy 413.937233 -136.324639)
			(xy 413.914284 -136.380043) (xy 413.8843 -136.431977) (xy 413.847794 -136.479553) (xy 413.805389 -136.521958)
			(xy 413.757813 -136.558464) (xy 413.705879 -136.588448) (xy 413.650475 -136.611397) (xy 413.59255 -136.626918)
			(xy 413.533094 -136.634746) (xy 413.473126 -136.634746) (xy 413.41367 -136.626918) (xy 413.355745 -136.611397)
			(xy 413.300341 -136.588448) (xy 413.248407 -136.558464) (xy 413.200831 -136.521958) (xy 413.158426 -136.479553)
			(xy 413.12192 -136.431977) (xy 413.091936 -136.380043) (xy 413.068987 -136.324639) (xy 413.053466 -136.266714)
			(xy 413.045638 -136.207258) (xy 413.045148 -136.177274) (xy 401.000468 -136.177274) (xy 401.000468 -136.69645)
			(xy 400.999978 -136.726418) (xy 400.992155 -136.78584) (xy 400.976642 -136.843733) (xy 400.953706 -136.899106)
			(xy 400.923739 -136.951012) (xy 400.887252 -136.998562) (xy 400.844872 -137.040942) (xy 400.797322 -137.077429)
			(xy 400.745416 -137.107396) (xy 400.690043 -137.130332) (xy 400.63215 -137.145845) (xy 400.572728 -137.153668)
			(xy 400.512792 -137.153668) (xy 400.45337 -137.145845) (xy 400.395477 -137.130332) (xy 400.340104 -137.107396)
			(xy 400.288198 -137.077429) (xy 400.240648 -137.040942) (xy 400.198268 -136.998562) (xy 400.161781 -136.951012)
			(xy 400.131814 -136.899106) (xy 400.108878 -136.843733) (xy 400.093365 -136.78584) (xy 400.085542 -136.726418)
			(xy 400.085052 -136.69645) (xy 386.525516 -136.69645) (xy 386.525516 -136.704324) (xy 386.525026 -136.734292)
			(xy 386.517203 -136.793714) (xy 386.50169 -136.851607) (xy 386.478754 -136.90698) (xy 386.448787 -136.958886)
			(xy 386.4123 -137.006436) (xy 386.36992 -137.048816) (xy 386.32237 -137.085303) (xy 386.270464 -137.11527)
			(xy 386.215091 -137.138206) (xy 386.157198 -137.153719) (xy 386.097776 -137.161542) (xy 386.03784 -137.161542)
			(xy 385.978418 -137.153719) (xy 385.920525 -137.138206) (xy 385.865152 -137.11527) (xy 385.813246 -137.085303)
			(xy 385.765696 -137.048816) (xy 385.723316 -137.006436) (xy 385.686829 -136.958886) (xy 385.656862 -136.90698)
			(xy 385.633926 -136.851607) (xy 385.618413 -136.793714) (xy 385.61059 -136.734292) (xy 385.6101 -136.704324)
			(xy 284.900495 -136.704324) (xy 284.900134 -136.726434) (xy 284.892306 -136.78589) (xy 284.876785 -136.843815)
			(xy 284.853836 -136.899219) (xy 284.823852 -136.951153) (xy 284.787346 -136.998729) (xy 284.744941 -137.041134)
			(xy 284.697365 -137.07764) (xy 284.645431 -137.107624) (xy 284.590027 -137.130573) (xy 284.532102 -137.146094)
			(xy 284.472646 -137.153922) (xy 284.412678 -137.153922) (xy 284.353222 -137.146094) (xy 284.295297 -137.130573)
			(xy 284.239893 -137.107624) (xy 284.187959 -137.07764) (xy 284.140383 -137.041134) (xy 284.097978 -136.998729)
			(xy 284.061472 -136.951153) (xy 284.031488 -136.899219) (xy 284.008539 -136.843815) (xy 283.993018 -136.78589)
			(xy 283.98519 -136.726434) (xy 283.9847 -136.69645) (xy 270.425672 -136.69645) (xy 270.425672 -136.704324)
			(xy 270.425182 -136.734308) (xy 270.417354 -136.793764) (xy 270.401833 -136.851689) (xy 270.378884 -136.907093)
			(xy 270.3489 -136.959027) (xy 270.312394 -137.006603) (xy 270.269989 -137.049008) (xy 270.222413 -137.085514)
			(xy 270.170479 -137.115498) (xy 270.115075 -137.138447) (xy 270.05715 -137.153968) (xy 269.997694 -137.161796)
			(xy 269.937726 -137.161796) (xy 269.87827 -137.153968) (xy 269.820345 -137.138447) (xy 269.764941 -137.115498)
			(xy 269.713007 -137.085514) (xy 269.665431 -137.049008) (xy 269.623026 -137.006603) (xy 269.58652 -136.959027)
			(xy 269.556536 -136.907093) (xy 269.533587 -136.851689) (xy 269.518066 -136.793764) (xy 269.510238 -136.734308)
			(xy 269.509748 -136.704324) (xy 168.800651 -136.704324) (xy 168.80029 -136.726434) (xy 168.792462 -136.78589)
			(xy 168.776941 -136.843815) (xy 168.753992 -136.899219) (xy 168.724008 -136.951153) (xy 168.687502 -136.998729)
			(xy 168.645097 -137.041134) (xy 168.597521 -137.07764) (xy 168.545587 -137.107624) (xy 168.490183 -137.130573)
			(xy 168.432258 -137.146094) (xy 168.372802 -137.153922) (xy 168.312834 -137.153922) (xy 168.253378 -137.146094)
			(xy 168.195453 -137.130573) (xy 168.140049 -137.107624) (xy 168.088115 -137.07764) (xy 168.040539 -137.041134)
			(xy 167.998134 -136.998729) (xy 167.961628 -136.951153) (xy 167.931644 -136.899219) (xy 167.908695 -136.843815)
			(xy 167.893174 -136.78589) (xy 167.885346 -136.726434) (xy 167.884856 -136.69645) (xy 154.325828 -136.69645)
			(xy 154.325828 -136.704324) (xy 154.325338 -136.734308) (xy 154.31751 -136.793764) (xy 154.301989 -136.851689)
			(xy 154.27904 -136.907093) (xy 154.249056 -136.959027) (xy 154.21255 -137.006603) (xy 154.170145 -137.049008)
			(xy 154.122569 -137.085514) (xy 154.070635 -137.115498) (xy 154.015231 -137.138447) (xy 153.957306 -137.153968)
			(xy 153.89785 -137.161796) (xy 153.837882 -137.161796) (xy 153.778426 -137.153968) (xy 153.720501 -137.138447)
			(xy 153.665097 -137.115498) (xy 153.613163 -137.085514) (xy 153.565587 -137.049008) (xy 153.523182 -137.006603)
			(xy 153.486676 -136.959027) (xy 153.456692 -136.907093) (xy 153.433743 -136.851689) (xy 153.418222 -136.793764)
			(xy 153.410394 -136.734308) (xy 153.409904 -136.704324) (xy 52.700299 -136.704324) (xy 52.699938 -136.726418)
			(xy 52.692115 -136.78584) (xy 52.676602 -136.843733) (xy 52.653666 -136.899106) (xy 52.623699 -136.951012)
			(xy 52.587212 -136.998562) (xy 52.544832 -137.040942) (xy 52.497282 -137.077429) (xy 52.445376 -137.107396)
			(xy 52.390003 -137.130332) (xy 52.33211 -137.145845) (xy 52.272688 -137.153668) (xy 52.212752 -137.153668)
			(xy 52.15333 -137.145845) (xy 52.095437 -137.130332) (xy 52.040064 -137.107396) (xy 51.988158 -137.077429)
			(xy 51.940608 -137.040942) (xy 51.898228 -136.998562) (xy 51.861741 -136.951012) (xy 51.831774 -136.899106)
			(xy 51.808838 -136.843733) (xy 51.793325 -136.78584) (xy 51.785502 -136.726418) (xy 51.785012 -136.69645)
			(xy 38.225476 -136.69645) (xy 38.225476 -136.704324) (xy 38.224986 -136.734292) (xy 38.217163 -136.793714)
			(xy 38.20165 -136.851607) (xy 38.178714 -136.90698) (xy 38.148747 -136.958886) (xy 38.11226 -137.006436)
			(xy 38.06988 -137.048816) (xy 38.02233 -137.085303) (xy 37.970424 -137.11527) (xy 37.915051 -137.138206)
			(xy 37.857158 -137.153719) (xy 37.797736 -137.161542) (xy 37.7378 -137.161542) (xy 37.678378 -137.153719)
			(xy 37.620485 -137.138206) (xy 37.565112 -137.11527) (xy 37.513206 -137.085303) (xy 37.465656 -137.048816)
			(xy 37.423276 -137.006436) (xy 37.386789 -136.958886) (xy 37.356822 -136.90698) (xy 37.333886 -136.851607)
			(xy 37.318373 -136.793714) (xy 37.31055 -136.734292) (xy 37.31006 -136.704324) (xy 4.30911 -136.704324)
			(xy 4.30911 -138.496548) (xy 43.97248 -138.496548) (xy 43.97248 -137.632948) (xy 43.97297 -137.602964)
			(xy 43.980798 -137.543508) (xy 43.996319 -137.485583) (xy 44.019268 -137.430179) (xy 44.049252 -137.378245)
			(xy 44.085758 -137.330669) (xy 44.128163 -137.288264) (xy 44.175739 -137.251758) (xy 44.227673 -137.221774)
			(xy 44.283077 -137.198825) (xy 44.341002 -137.183304) (xy 44.400458 -137.175476) (xy 44.460426 -137.175476)
			(xy 44.519882 -137.183304) (xy 44.577807 -137.198825) (xy 44.633211 -137.221774) (xy 44.685145 -137.251758)
			(xy 44.732721 -137.288264) (xy 44.775126 -137.330669) (xy 44.811632 -137.378245) (xy 44.841616 -137.430179)
			(xy 44.864565 -137.485583) (xy 44.880086 -137.543508) (xy 44.887914 -137.602964) (xy 44.888404 -137.632948)
			(xy 44.888404 -138.496548) (xy 160.072324 -138.496548) (xy 160.072324 -137.632948) (xy 160.072814 -137.602964)
			(xy 160.080642 -137.543508) (xy 160.096163 -137.485583) (xy 160.119112 -137.430179) (xy 160.149096 -137.378245)
			(xy 160.185602 -137.330669) (xy 160.228007 -137.288264) (xy 160.275583 -137.251758) (xy 160.327517 -137.221774)
			(xy 160.382921 -137.198825) (xy 160.440846 -137.183304) (xy 160.500302 -137.175476) (xy 160.56027 -137.175476)
			(xy 160.619726 -137.183304) (xy 160.677651 -137.198825) (xy 160.733055 -137.221774) (xy 160.784989 -137.251758)
			(xy 160.832565 -137.288264) (xy 160.87497 -137.330669) (xy 160.911476 -137.378245) (xy 160.94146 -137.430179)
			(xy 160.964409 -137.485583) (xy 160.97993 -137.543508) (xy 160.987758 -137.602964) (xy 160.988248 -137.632948)
			(xy 160.988248 -138.496548) (xy 276.172676 -138.496548) (xy 276.172676 -137.632948) (xy 276.173166 -137.60298)
			(xy 276.180989 -137.543558) (xy 276.196502 -137.485665) (xy 276.219438 -137.430292) (xy 276.249405 -137.378386)
			(xy 276.285892 -137.330836) (xy 276.328272 -137.288456) (xy 276.375822 -137.251969) (xy 276.427728 -137.222002)
			(xy 276.483101 -137.199066) (xy 276.540994 -137.183553) (xy 276.600416 -137.17573) (xy 276.660352 -137.17573)
			(xy 276.719774 -137.183553) (xy 276.777667 -137.199066) (xy 276.83304 -137.222002) (xy 276.884946 -137.251969)
			(xy 276.932496 -137.288456) (xy 276.974876 -137.330836) (xy 277.011363 -137.378386) (xy 277.04133 -137.430292)
			(xy 277.064266 -137.485665) (xy 277.079779 -137.543558) (xy 277.087602 -137.60298) (xy 277.088092 -137.632948)
			(xy 277.088092 -138.496548) (xy 277.088084 -138.497056) (xy 392.27252 -138.497056) (xy 392.27252 -137.633456)
			(xy 392.27301 -137.603472) (xy 392.280838 -137.544016) (xy 392.296359 -137.486091) (xy 392.319308 -137.430687)
			(xy 392.349292 -137.378753) (xy 392.385798 -137.331177) (xy 392.428203 -137.288772) (xy 392.475779 -137.252266)
			(xy 392.527713 -137.222282) (xy 392.583117 -137.199333) (xy 392.641042 -137.183812) (xy 392.700498 -137.175984)
			(xy 392.760466 -137.175984) (xy 392.819922 -137.183812) (xy 392.877847 -137.199333) (xy 392.933251 -137.222282)
			(xy 392.985185 -137.252266) (xy 393.032761 -137.288772) (xy 393.075166 -137.331177) (xy 393.111672 -137.378753)
			(xy 393.141656 -137.430687) (xy 393.164605 -137.486091) (xy 393.180126 -137.544016) (xy 393.187954 -137.603472)
			(xy 393.188444 -137.633456) (xy 393.188444 -138.497056) (xy 393.187954 -138.52704) (xy 393.180126 -138.586496)
			(xy 393.164605 -138.644421) (xy 393.141656 -138.699825) (xy 393.111672 -138.751759) (xy 393.075166 -138.799335)
			(xy 393.032761 -138.84174) (xy 392.985185 -138.878246) (xy 392.933251 -138.90823) (xy 392.877847 -138.931179)
			(xy 392.819922 -138.9467) (xy 392.760466 -138.954528) (xy 392.700498 -138.954528) (xy 392.641042 -138.9467)
			(xy 392.583117 -138.931179) (xy 392.527713 -138.90823) (xy 392.475779 -138.878246) (xy 392.428203 -138.84174)
			(xy 392.385798 -138.799335) (xy 392.349292 -138.751759) (xy 392.319308 -138.699825) (xy 392.296359 -138.644421)
			(xy 392.280838 -138.586496) (xy 392.27301 -138.52704) (xy 392.27252 -138.497056) (xy 277.088084 -138.497056)
			(xy 277.087602 -138.526516) (xy 277.079779 -138.585938) (xy 277.064266 -138.643831) (xy 277.04133 -138.699204)
			(xy 277.011363 -138.75111) (xy 276.974876 -138.79866) (xy 276.932496 -138.84104) (xy 276.884946 -138.877527)
			(xy 276.83304 -138.907494) (xy 276.777667 -138.93043) (xy 276.719774 -138.945943) (xy 276.660352 -138.953766)
			(xy 276.600416 -138.953766) (xy 276.540994 -138.945943) (xy 276.483101 -138.93043) (xy 276.427728 -138.907494)
			(xy 276.375822 -138.877527) (xy 276.328272 -138.84104) (xy 276.285892 -138.79866) (xy 276.249405 -138.75111)
			(xy 276.219438 -138.699204) (xy 276.196502 -138.643831) (xy 276.180989 -138.585938) (xy 276.173166 -138.526516)
			(xy 276.172676 -138.496548) (xy 160.988248 -138.496548) (xy 160.987758 -138.526532) (xy 160.97993 -138.585988)
			(xy 160.964409 -138.643913) (xy 160.94146 -138.699317) (xy 160.911476 -138.751251) (xy 160.87497 -138.798827)
			(xy 160.832565 -138.841232) (xy 160.784989 -138.877738) (xy 160.733055 -138.907722) (xy 160.677651 -138.930671)
			(xy 160.619726 -138.946192) (xy 160.56027 -138.95402) (xy 160.500302 -138.95402) (xy 160.440846 -138.946192)
			(xy 160.382921 -138.930671) (xy 160.327517 -138.907722) (xy 160.275583 -138.877738) (xy 160.228007 -138.841232)
			(xy 160.185602 -138.798827) (xy 160.149096 -138.751251) (xy 160.119112 -138.699317) (xy 160.096163 -138.643913)
			(xy 160.080642 -138.585988) (xy 160.072814 -138.526532) (xy 160.072324 -138.496548) (xy 44.888404 -138.496548)
			(xy 44.887914 -138.526532) (xy 44.880086 -138.585988) (xy 44.864565 -138.643913) (xy 44.841616 -138.699317)
			(xy 44.811632 -138.751251) (xy 44.775126 -138.798827) (xy 44.732721 -138.841232) (xy 44.685145 -138.877738)
			(xy 44.633211 -138.907722) (xy 44.577807 -138.930671) (xy 44.519882 -138.946192) (xy 44.460426 -138.95402)
			(xy 44.400458 -138.95402) (xy 44.341002 -138.946192) (xy 44.283077 -138.930671) (xy 44.227673 -138.907722)
			(xy 44.175739 -138.877738) (xy 44.128163 -138.841232) (xy 44.085758 -138.798827) (xy 44.049252 -138.751251)
			(xy 44.019268 -138.699317) (xy 43.996319 -138.643913) (xy 43.980798 -138.585988) (xy 43.97297 -138.526532)
			(xy 43.97248 -138.496548) (xy 4.30911 -138.496548) (xy 4.30911 -143.48714) (xy 66.599308 -143.48714)
			(xy 66.599308 -142.62354) (xy 66.599798 -142.593556) (xy 66.607626 -142.5341) (xy 66.623147 -142.476175)
			(xy 66.646096 -142.420771) (xy 66.67608 -142.368837) (xy 66.712586 -142.321261) (xy 66.754991 -142.278856)
			(xy 66.802567 -142.24235) (xy 66.854501 -142.212366) (xy 66.909905 -142.189417) (xy 66.96783 -142.173896)
			(xy 67.027286 -142.166068) (xy 67.087254 -142.166068) (xy 67.14671 -142.173896) (xy 67.204635 -142.189417)
			(xy 67.260039 -142.212366) (xy 67.311973 -142.24235) (xy 67.359549 -142.278856) (xy 67.401954 -142.321261)
			(xy 67.43846 -142.368837) (xy 67.468444 -142.420771) (xy 67.491393 -142.476175) (xy 67.506914 -142.5341)
			(xy 67.514742 -142.593556) (xy 67.515232 -142.62354) (xy 67.515232 -143.479266) (xy 81.07426 -143.479266)
			(xy 81.07426 -142.615666) (xy 81.07475 -142.585682) (xy 81.082578 -142.526226) (xy 81.098099 -142.468301)
			(xy 81.121048 -142.412897) (xy 81.151032 -142.360963) (xy 81.187538 -142.313387) (xy 81.229943 -142.270982)
			(xy 81.277519 -142.234476) (xy 81.329453 -142.204492) (xy 81.384857 -142.181543) (xy 81.442782 -142.166022)
			(xy 81.502238 -142.158194) (xy 81.562206 -142.158194) (xy 81.621662 -142.166022) (xy 81.679587 -142.181543)
			(xy 81.734991 -142.204492) (xy 81.786925 -142.234476) (xy 81.834501 -142.270982) (xy 81.876906 -142.313387)
			(xy 81.913412 -142.360963) (xy 81.943396 -142.412897) (xy 81.966345 -142.468301) (xy 81.981866 -142.526226)
			(xy 81.989694 -142.585682) (xy 81.990184 -142.615666) (xy 81.990184 -143.479266) (xy 81.990055 -143.48714)
			(xy 182.69966 -143.48714) (xy 182.69966 -142.62354) (xy 182.70015 -142.593572) (xy 182.707973 -142.53415)
			(xy 182.723486 -142.476257) (xy 182.746422 -142.420884) (xy 182.776389 -142.368978) (xy 182.812876 -142.321428)
			(xy 182.855256 -142.279048) (xy 182.902806 -142.242561) (xy 182.954712 -142.212594) (xy 183.010085 -142.189658)
			(xy 183.067978 -142.174145) (xy 183.1274 -142.166322) (xy 183.187336 -142.166322) (xy 183.246758 -142.174145)
			(xy 183.304651 -142.189658) (xy 183.360024 -142.212594) (xy 183.41193 -142.242561) (xy 183.45948 -142.279048)
			(xy 183.50186 -142.321428) (xy 183.538347 -142.368978) (xy 183.568314 -142.420884) (xy 183.59125 -142.476257)
			(xy 183.606763 -142.53415) (xy 183.614586 -142.593572) (xy 183.615076 -142.62354) (xy 183.615076 -143.479266)
			(xy 197.174612 -143.479266) (xy 197.174612 -142.615666) (xy 197.175102 -142.585698) (xy 197.182925 -142.526276)
			(xy 197.198438 -142.468383) (xy 197.221374 -142.41301) (xy 197.251341 -142.361104) (xy 197.287828 -142.313554)
			(xy 197.330208 -142.271174) (xy 197.377758 -142.234687) (xy 197.429664 -142.20472) (xy 197.485037 -142.181784)
			(xy 197.54293 -142.166271) (xy 197.602352 -142.158448) (xy 197.662288 -142.158448) (xy 197.72171 -142.166271)
			(xy 197.779603 -142.181784) (xy 197.834976 -142.20472) (xy 197.886882 -142.234687) (xy 197.934432 -142.271174)
			(xy 197.976812 -142.313554) (xy 198.013299 -142.361104) (xy 198.043266 -142.41301) (xy 198.066202 -142.468383)
			(xy 198.081715 -142.526276) (xy 198.089538 -142.585698) (xy 198.090028 -142.615666) (xy 198.090028 -143.479266)
			(xy 198.089899 -143.48714) (xy 298.799504 -143.48714) (xy 298.799504 -142.62354) (xy 298.799994 -142.593572)
			(xy 298.807817 -142.53415) (xy 298.82333 -142.476257) (xy 298.846266 -142.420884) (xy 298.876233 -142.368978)
			(xy 298.91272 -142.321428) (xy 298.9551 -142.279048) (xy 299.00265 -142.242561) (xy 299.054556 -142.212594)
			(xy 299.109929 -142.189658) (xy 299.167822 -142.174145) (xy 299.227244 -142.166322) (xy 299.28718 -142.166322)
			(xy 299.346602 -142.174145) (xy 299.404495 -142.189658) (xy 299.459868 -142.212594) (xy 299.511774 -142.242561)
			(xy 299.559324 -142.279048) (xy 299.601704 -142.321428) (xy 299.638191 -142.368978) (xy 299.668158 -142.420884)
			(xy 299.691094 -142.476257) (xy 299.706607 -142.53415) (xy 299.71443 -142.593572) (xy 299.71492 -142.62354)
			(xy 299.71492 -143.479266) (xy 313.274456 -143.479266) (xy 313.274456 -142.615666) (xy 313.274946 -142.585698)
			(xy 313.282769 -142.526276) (xy 313.298282 -142.468383) (xy 313.321218 -142.41301) (xy 313.351185 -142.361104)
			(xy 313.387672 -142.313554) (xy 313.430052 -142.271174) (xy 313.477602 -142.234687) (xy 313.529508 -142.20472)
			(xy 313.584881 -142.181784) (xy 313.642774 -142.166271) (xy 313.702196 -142.158448) (xy 313.762132 -142.158448)
			(xy 313.821554 -142.166271) (xy 313.879447 -142.181784) (xy 313.93482 -142.20472) (xy 313.986726 -142.234687)
			(xy 314.034276 -142.271174) (xy 314.076656 -142.313554) (xy 314.113143 -142.361104) (xy 314.14311 -142.41301)
			(xy 314.166046 -142.468383) (xy 314.181559 -142.526276) (xy 314.189382 -142.585698) (xy 314.189872 -142.615666)
			(xy 314.189872 -143.479266) (xy 314.189743 -143.48714) (xy 414.899348 -143.48714) (xy 414.899348 -142.62354)
			(xy 414.899838 -142.593556) (xy 414.907666 -142.5341) (xy 414.923187 -142.476175) (xy 414.946136 -142.420771)
			(xy 414.97612 -142.368837) (xy 415.012626 -142.321261) (xy 415.055031 -142.278856) (xy 415.102607 -142.24235)
			(xy 415.154541 -142.212366) (xy 415.209945 -142.189417) (xy 415.26787 -142.173896) (xy 415.327326 -142.166068)
			(xy 415.387294 -142.166068) (xy 415.44675 -142.173896) (xy 415.504675 -142.189417) (xy 415.560079 -142.212366)
			(xy 415.612013 -142.24235) (xy 415.659589 -142.278856) (xy 415.701994 -142.321261) (xy 415.7385 -142.368837)
			(xy 415.768484 -142.420771) (xy 415.791433 -142.476175) (xy 415.806954 -142.5341) (xy 415.814782 -142.593556)
			(xy 415.815272 -142.62354) (xy 415.815272 -143.479266) (xy 429.3743 -143.479266) (xy 429.3743 -142.615666)
			(xy 429.37479 -142.585682) (xy 429.382618 -142.526226) (xy 429.398139 -142.468301) (xy 429.421088 -142.412897)
			(xy 429.451072 -142.360963) (xy 429.487578 -142.313387) (xy 429.529983 -142.270982) (xy 429.577559 -142.234476)
			(xy 429.629493 -142.204492) (xy 429.684897 -142.181543) (xy 429.742822 -142.166022) (xy 429.802278 -142.158194)
			(xy 429.862246 -142.158194) (xy 429.921702 -142.166022) (xy 429.979627 -142.181543) (xy 430.035031 -142.204492)
			(xy 430.086965 -142.234476) (xy 430.134541 -142.270982) (xy 430.176946 -142.313387) (xy 430.213452 -142.360963)
			(xy 430.243436 -142.412897) (xy 430.266385 -142.468301) (xy 430.281906 -142.526226) (xy 430.289734 -142.585682)
			(xy 430.290224 -142.615666) (xy 430.290224 -143.479266) (xy 430.289734 -143.50925) (xy 430.281906 -143.568706)
			(xy 430.266385 -143.626631) (xy 430.243436 -143.682035) (xy 430.213452 -143.733969) (xy 430.176946 -143.781545)
			(xy 430.134541 -143.82395) (xy 430.086965 -143.860456) (xy 430.035031 -143.89044) (xy 429.979627 -143.913389)
			(xy 429.921702 -143.92891) (xy 429.862246 -143.936738) (xy 429.802278 -143.936738) (xy 429.742822 -143.92891)
			(xy 429.684897 -143.913389) (xy 429.629493 -143.89044) (xy 429.577559 -143.860456) (xy 429.529983 -143.82395)
			(xy 429.487578 -143.781545) (xy 429.451072 -143.733969) (xy 429.421088 -143.682035) (xy 429.398139 -143.626631)
			(xy 429.382618 -143.568706) (xy 429.37479 -143.50925) (xy 429.3743 -143.479266) (xy 415.815272 -143.479266)
			(xy 415.815272 -143.48714) (xy 415.814782 -143.517124) (xy 415.806954 -143.57658) (xy 415.791433 -143.634505)
			(xy 415.768484 -143.689909) (xy 415.7385 -143.741843) (xy 415.701994 -143.789419) (xy 415.659589 -143.831824)
			(xy 415.612013 -143.86833) (xy 415.560079 -143.898314) (xy 415.504675 -143.921263) (xy 415.44675 -143.936784)
			(xy 415.387294 -143.944612) (xy 415.327326 -143.944612) (xy 415.26787 -143.936784) (xy 415.209945 -143.921263)
			(xy 415.154541 -143.898314) (xy 415.102607 -143.86833) (xy 415.055031 -143.831824) (xy 415.012626 -143.789419)
			(xy 414.97612 -143.741843) (xy 414.946136 -143.689909) (xy 414.923187 -143.634505) (xy 414.907666 -143.57658)
			(xy 414.899838 -143.517124) (xy 414.899348 -143.48714) (xy 314.189743 -143.48714) (xy 314.189382 -143.509234)
			(xy 314.181559 -143.568656) (xy 314.166046 -143.626549) (xy 314.14311 -143.681922) (xy 314.113143 -143.733828)
			(xy 314.076656 -143.781378) (xy 314.034276 -143.823758) (xy 313.986726 -143.860245) (xy 313.93482 -143.890212)
			(xy 313.879447 -143.913148) (xy 313.821554 -143.928661) (xy 313.762132 -143.936484) (xy 313.702196 -143.936484)
			(xy 313.642774 -143.928661) (xy 313.584881 -143.913148) (xy 313.529508 -143.890212) (xy 313.477602 -143.860245)
			(xy 313.430052 -143.823758) (xy 313.387672 -143.781378) (xy 313.351185 -143.733828) (xy 313.321218 -143.681922)
			(xy 313.298282 -143.626549) (xy 313.282769 -143.568656) (xy 313.274946 -143.509234) (xy 313.274456 -143.479266)
			(xy 299.71492 -143.479266) (xy 299.71492 -143.48714) (xy 299.71443 -143.517108) (xy 299.706607 -143.57653)
			(xy 299.691094 -143.634423) (xy 299.668158 -143.689796) (xy 299.638191 -143.741702) (xy 299.601704 -143.789252)
			(xy 299.559324 -143.831632) (xy 299.511774 -143.868119) (xy 299.459868 -143.898086) (xy 299.404495 -143.921022)
			(xy 299.346602 -143.936535) (xy 299.28718 -143.944358) (xy 299.227244 -143.944358) (xy 299.167822 -143.936535)
			(xy 299.109929 -143.921022) (xy 299.054556 -143.898086) (xy 299.00265 -143.868119) (xy 298.9551 -143.831632)
			(xy 298.91272 -143.789252) (xy 298.876233 -143.741702) (xy 298.846266 -143.689796) (xy 298.82333 -143.634423)
			(xy 298.807817 -143.57653) (xy 298.799994 -143.517108) (xy 298.799504 -143.48714) (xy 198.089899 -143.48714)
			(xy 198.089538 -143.509234) (xy 198.081715 -143.568656) (xy 198.066202 -143.626549) (xy 198.043266 -143.681922)
			(xy 198.013299 -143.733828) (xy 197.976812 -143.781378) (xy 197.934432 -143.823758) (xy 197.886882 -143.860245)
			(xy 197.834976 -143.890212) (xy 197.779603 -143.913148) (xy 197.72171 -143.928661) (xy 197.662288 -143.936484)
			(xy 197.602352 -143.936484) (xy 197.54293 -143.928661) (xy 197.485037 -143.913148) (xy 197.429664 -143.890212)
			(xy 197.377758 -143.860245) (xy 197.330208 -143.823758) (xy 197.287828 -143.781378) (xy 197.251341 -143.733828)
			(xy 197.221374 -143.681922) (xy 197.198438 -143.626549) (xy 197.182925 -143.568656) (xy 197.175102 -143.509234)
			(xy 197.174612 -143.479266) (xy 183.615076 -143.479266) (xy 183.615076 -143.48714) (xy 183.614586 -143.517108)
			(xy 183.606763 -143.57653) (xy 183.59125 -143.634423) (xy 183.568314 -143.689796) (xy 183.538347 -143.741702)
			(xy 183.50186 -143.789252) (xy 183.45948 -143.831632) (xy 183.41193 -143.868119) (xy 183.360024 -143.898086)
			(xy 183.304651 -143.921022) (xy 183.246758 -143.936535) (xy 183.187336 -143.944358) (xy 183.1274 -143.944358)
			(xy 183.067978 -143.936535) (xy 183.010085 -143.921022) (xy 182.954712 -143.898086) (xy 182.902806 -143.868119)
			(xy 182.855256 -143.831632) (xy 182.812876 -143.789252) (xy 182.776389 -143.741702) (xy 182.746422 -143.689796)
			(xy 182.723486 -143.634423) (xy 182.707973 -143.57653) (xy 182.70015 -143.517108) (xy 182.69966 -143.48714)
			(xy 81.990055 -143.48714) (xy 81.989694 -143.50925) (xy 81.981866 -143.568706) (xy 81.966345 -143.626631)
			(xy 81.943396 -143.682035) (xy 81.913412 -143.733969) (xy 81.876906 -143.781545) (xy 81.834501 -143.82395)
			(xy 81.786925 -143.860456) (xy 81.734991 -143.89044) (xy 81.679587 -143.913389) (xy 81.621662 -143.92891)
			(xy 81.562206 -143.936738) (xy 81.502238 -143.936738) (xy 81.442782 -143.92891) (xy 81.384857 -143.913389)
			(xy 81.329453 -143.89044) (xy 81.277519 -143.860456) (xy 81.229943 -143.82395) (xy 81.187538 -143.781545)
			(xy 81.151032 -143.733969) (xy 81.121048 -143.682035) (xy 81.098099 -143.626631) (xy 81.082578 -143.568706)
			(xy 81.07475 -143.50925) (xy 81.07426 -143.479266) (xy 67.515232 -143.479266) (xy 67.515232 -143.48714)
			(xy 67.514742 -143.517124) (xy 67.506914 -143.57658) (xy 67.491393 -143.634505) (xy 67.468444 -143.689909)
			(xy 67.43846 -143.741843) (xy 67.401954 -143.789419) (xy 67.359549 -143.831824) (xy 67.311973 -143.86833)
			(xy 67.260039 -143.898314) (xy 67.204635 -143.921263) (xy 67.14671 -143.936784) (xy 67.087254 -143.944612)
			(xy 67.027286 -143.944612) (xy 66.96783 -143.936784) (xy 66.909905 -143.921263) (xy 66.854501 -143.898314)
			(xy 66.802567 -143.86833) (xy 66.754991 -143.831824) (xy 66.712586 -143.789419) (xy 66.67608 -143.741843)
			(xy 66.646096 -143.689909) (xy 66.623147 -143.634505) (xy 66.607626 -143.57658) (xy 66.599798 -143.517124)
			(xy 66.599308 -143.48714) (xy 4.30911 -143.48714) (xy 4.30911 -145.287238) (xy 64.745108 -145.287238)
			(xy 64.745108 -144.423638) (xy 64.745598 -144.393654) (xy 64.753426 -144.334198) (xy 64.768947 -144.276273)
			(xy 64.791896 -144.220869) (xy 64.82188 -144.168935) (xy 64.858386 -144.121359) (xy 64.900791 -144.078954)
			(xy 64.948367 -144.042448) (xy 65.000301 -144.012464) (xy 65.055705 -143.989515) (xy 65.11363 -143.973994)
			(xy 65.173086 -143.966166) (xy 65.233054 -143.966166) (xy 65.29251 -143.973994) (xy 65.350435 -143.989515)
			(xy 65.405839 -144.012464) (xy 65.457773 -144.042448) (xy 65.505349 -144.078954) (xy 65.547754 -144.121359)
			(xy 65.58426 -144.168935) (xy 65.614244 -144.220869) (xy 65.637193 -144.276273) (xy 65.652714 -144.334198)
			(xy 65.660542 -144.393654) (xy 65.661032 -144.423638) (xy 65.661032 -145.285714) (xy 83.716368 -145.285714)
			(xy 83.716368 -144.422114) (xy 83.716858 -144.39213) (xy 83.724686 -144.332674) (xy 83.740207 -144.274749)
			(xy 83.763156 -144.219345) (xy 83.79314 -144.167411) (xy 83.829646 -144.119835) (xy 83.872051 -144.07743)
			(xy 83.919627 -144.040924) (xy 83.971561 -144.01094) (xy 84.026965 -143.987991) (xy 84.08489 -143.97247)
			(xy 84.144346 -143.964642) (xy 84.204314 -143.964642) (xy 84.26377 -143.97247) (xy 84.321695 -143.987991)
			(xy 84.377099 -144.01094) (xy 84.429033 -144.040924) (xy 84.476609 -144.07743) (xy 84.519014 -144.119835)
			(xy 84.55552 -144.167411) (xy 84.585504 -144.219345) (xy 84.608453 -144.274749) (xy 84.623974 -144.332674)
			(xy 84.631802 -144.39213) (xy 84.632292 -144.422114) (xy 84.632292 -145.285714) (xy 84.632267 -145.287238)
			(xy 180.84546 -145.287238) (xy 180.84546 -144.423638) (xy 180.84595 -144.39367) (xy 180.853773 -144.334248)
			(xy 180.869286 -144.276355) (xy 180.892222 -144.220982) (xy 180.922189 -144.169076) (xy 180.958676 -144.121526)
			(xy 181.001056 -144.079146) (xy 181.048606 -144.042659) (xy 181.100512 -144.012692) (xy 181.155885 -143.989756)
			(xy 181.213778 -143.974243) (xy 181.2732 -143.96642) (xy 181.333136 -143.96642) (xy 181.392558 -143.974243)
			(xy 181.450451 -143.989756) (xy 181.505824 -144.012692) (xy 181.55773 -144.042659) (xy 181.60528 -144.079146)
			(xy 181.64766 -144.121526) (xy 181.684147 -144.169076) (xy 181.714114 -144.220982) (xy 181.73705 -144.276355)
			(xy 181.752563 -144.334248) (xy 181.760386 -144.39367) (xy 181.760876 -144.423638) (xy 181.760876 -145.285714)
			(xy 199.81672 -145.285714) (xy 199.81672 -144.422114) (xy 199.81721 -144.392146) (xy 199.825033 -144.332724)
			(xy 199.840546 -144.274831) (xy 199.863482 -144.219458) (xy 199.893449 -144.167552) (xy 199.929936 -144.120002)
			(xy 199.972316 -144.077622) (xy 200.019866 -144.041135) (xy 200.071772 -144.011168) (xy 200.127145 -143.988232)
			(xy 200.185038 -143.972719) (xy 200.24446 -143.964896) (xy 200.304396 -143.964896) (xy 200.363818 -143.972719)
			(xy 200.421711 -143.988232) (xy 200.477084 -144.011168) (xy 200.52899 -144.041135) (xy 200.57654 -144.077622)
			(xy 200.61892 -144.120002) (xy 200.655407 -144.167552) (xy 200.685374 -144.219458) (xy 200.70831 -144.274831)
			(xy 200.723823 -144.332724) (xy 200.731646 -144.392146) (xy 200.732136 -144.422114) (xy 200.732136 -145.285714)
			(xy 200.732111 -145.287238) (xy 296.945304 -145.287238) (xy 296.945304 -144.423638) (xy 296.945794 -144.39367)
			(xy 296.953617 -144.334248) (xy 296.96913 -144.276355) (xy 296.992066 -144.220982) (xy 297.022033 -144.169076)
			(xy 297.05852 -144.121526) (xy 297.1009 -144.079146) (xy 297.14845 -144.042659) (xy 297.200356 -144.012692)
			(xy 297.255729 -143.989756) (xy 297.313622 -143.974243) (xy 297.373044 -143.96642) (xy 297.43298 -143.96642)
			(xy 297.492402 -143.974243) (xy 297.550295 -143.989756) (xy 297.605668 -144.012692) (xy 297.657574 -144.042659)
			(xy 297.705124 -144.079146) (xy 297.747504 -144.121526) (xy 297.783991 -144.169076) (xy 297.813958 -144.220982)
			(xy 297.836894 -144.276355) (xy 297.852407 -144.334248) (xy 297.86023 -144.39367) (xy 297.86072 -144.423638)
			(xy 297.86072 -145.285714) (xy 315.916564 -145.285714) (xy 315.916564 -144.422114) (xy 315.917054 -144.392146)
			(xy 315.924877 -144.332724) (xy 315.94039 -144.274831) (xy 315.963326 -144.219458) (xy 315.993293 -144.167552)
			(xy 316.02978 -144.120002) (xy 316.07216 -144.077622) (xy 316.11971 -144.041135) (xy 316.171616 -144.011168)
			(xy 316.226989 -143.988232) (xy 316.284882 -143.972719) (xy 316.344304 -143.964896) (xy 316.40424 -143.964896)
			(xy 316.463662 -143.972719) (xy 316.521555 -143.988232) (xy 316.576928 -144.011168) (xy 316.628834 -144.041135)
			(xy 316.676384 -144.077622) (xy 316.718764 -144.120002) (xy 316.755251 -144.167552) (xy 316.785218 -144.219458)
			(xy 316.808154 -144.274831) (xy 316.823667 -144.332724) (xy 316.83149 -144.392146) (xy 316.83198 -144.422114)
			(xy 316.83198 -145.285714) (xy 316.831955 -145.287238) (xy 413.045148 -145.287238) (xy 413.045148 -144.423638)
			(xy 413.045638 -144.393654) (xy 413.053466 -144.334198) (xy 413.068987 -144.276273) (xy 413.091936 -144.220869)
			(xy 413.12192 -144.168935) (xy 413.158426 -144.121359) (xy 413.200831 -144.078954) (xy 413.248407 -144.042448)
			(xy 413.300341 -144.012464) (xy 413.355745 -143.989515) (xy 413.41367 -143.973994) (xy 413.473126 -143.966166)
			(xy 413.533094 -143.966166) (xy 413.59255 -143.973994) (xy 413.650475 -143.989515) (xy 413.705879 -144.012464)
			(xy 413.757813 -144.042448) (xy 413.805389 -144.078954) (xy 413.847794 -144.121359) (xy 413.8843 -144.168935)
			(xy 413.914284 -144.220869) (xy 413.937233 -144.276273) (xy 413.952754 -144.334198) (xy 413.960582 -144.393654)
			(xy 413.961072 -144.423638) (xy 413.961072 -145.285714) (xy 432.016408 -145.285714) (xy 432.016408 -144.422114)
			(xy 432.016898 -144.39213) (xy 432.024726 -144.332674) (xy 432.040247 -144.274749) (xy 432.063196 -144.219345)
			(xy 432.09318 -144.167411) (xy 432.129686 -144.119835) (xy 432.172091 -144.07743) (xy 432.219667 -144.040924)
			(xy 432.271601 -144.01094) (xy 432.327005 -143.987991) (xy 432.38493 -143.97247) (xy 432.444386 -143.964642)
			(xy 432.504354 -143.964642) (xy 432.56381 -143.97247) (xy 432.621735 -143.987991) (xy 432.677139 -144.01094)
			(xy 432.729073 -144.040924) (xy 432.776649 -144.07743) (xy 432.819054 -144.119835) (xy 432.85556 -144.167411)
			(xy 432.885544 -144.219345) (xy 432.908493 -144.274749) (xy 432.924014 -144.332674) (xy 432.931842 -144.39213)
			(xy 432.932332 -144.422114) (xy 432.932332 -145.285714) (xy 432.931842 -145.315698) (xy 432.924014 -145.375154)
			(xy 432.908493 -145.433079) (xy 432.885544 -145.488483) (xy 432.85556 -145.540417) (xy 432.819054 -145.587993)
			(xy 432.776649 -145.630398) (xy 432.729073 -145.666904) (xy 432.677139 -145.696888) (xy 432.621735 -145.719837)
			(xy 432.56381 -145.735358) (xy 432.504354 -145.743186) (xy 432.444386 -145.743186) (xy 432.38493 -145.735358)
			(xy 432.327005 -145.719837) (xy 432.271601 -145.696888) (xy 432.219667 -145.666904) (xy 432.172091 -145.630398)
			(xy 432.129686 -145.587993) (xy 432.09318 -145.540417) (xy 432.063196 -145.488483) (xy 432.040247 -145.433079)
			(xy 432.024726 -145.375154) (xy 432.016898 -145.315698) (xy 432.016408 -145.285714) (xy 413.961072 -145.285714)
			(xy 413.961072 -145.287238) (xy 413.960582 -145.317222) (xy 413.952754 -145.376678) (xy 413.937233 -145.434603)
			(xy 413.914284 -145.490007) (xy 413.8843 -145.541941) (xy 413.847794 -145.589517) (xy 413.805389 -145.631922)
			(xy 413.757813 -145.668428) (xy 413.705879 -145.698412) (xy 413.650475 -145.721361) (xy 413.59255 -145.736882)
			(xy 413.533094 -145.74471) (xy 413.473126 -145.74471) (xy 413.41367 -145.736882) (xy 413.355745 -145.721361)
			(xy 413.300341 -145.698412) (xy 413.248407 -145.668428) (xy 413.200831 -145.631922) (xy 413.158426 -145.589517)
			(xy 413.12192 -145.541941) (xy 413.091936 -145.490007) (xy 413.068987 -145.434603) (xy 413.053466 -145.376678)
			(xy 413.045638 -145.317222) (xy 413.045148 -145.287238) (xy 316.831955 -145.287238) (xy 316.83149 -145.315682)
			(xy 316.823667 -145.375104) (xy 316.808154 -145.432997) (xy 316.785218 -145.48837) (xy 316.755251 -145.540276)
			(xy 316.718764 -145.587826) (xy 316.676384 -145.630206) (xy 316.628834 -145.666693) (xy 316.576928 -145.69666)
			(xy 316.521555 -145.719596) (xy 316.463662 -145.735109) (xy 316.40424 -145.742932) (xy 316.344304 -145.742932)
			(xy 316.284882 -145.735109) (xy 316.226989 -145.719596) (xy 316.171616 -145.69666) (xy 316.11971 -145.666693)
			(xy 316.07216 -145.630206) (xy 316.02978 -145.587826) (xy 315.993293 -145.540276) (xy 315.963326 -145.48837)
			(xy 315.94039 -145.432997) (xy 315.924877 -145.375104) (xy 315.917054 -145.315682) (xy 315.916564 -145.285714)
			(xy 297.86072 -145.285714) (xy 297.86072 -145.287238) (xy 297.86023 -145.317206) (xy 297.852407 -145.376628)
			(xy 297.836894 -145.434521) (xy 297.813958 -145.489894) (xy 297.783991 -145.5418) (xy 297.747504 -145.58935)
			(xy 297.705124 -145.63173) (xy 297.657574 -145.668217) (xy 297.605668 -145.698184) (xy 297.550295 -145.72112)
			(xy 297.492402 -145.736633) (xy 297.43298 -145.744456) (xy 297.373044 -145.744456) (xy 297.313622 -145.736633)
			(xy 297.255729 -145.72112) (xy 297.200356 -145.698184) (xy 297.14845 -145.668217) (xy 297.1009 -145.63173)
			(xy 297.05852 -145.58935) (xy 297.022033 -145.5418) (xy 296.992066 -145.489894) (xy 296.96913 -145.434521)
			(xy 296.953617 -145.376628) (xy 296.945794 -145.317206) (xy 296.945304 -145.287238) (xy 200.732111 -145.287238)
			(xy 200.731646 -145.315682) (xy 200.723823 -145.375104) (xy 200.70831 -145.432997) (xy 200.685374 -145.48837)
			(xy 200.655407 -145.540276) (xy 200.61892 -145.587826) (xy 200.57654 -145.630206) (xy 200.52899 -145.666693)
			(xy 200.477084 -145.69666) (xy 200.421711 -145.719596) (xy 200.363818 -145.735109) (xy 200.304396 -145.742932)
			(xy 200.24446 -145.742932) (xy 200.185038 -145.735109) (xy 200.127145 -145.719596) (xy 200.071772 -145.69666)
			(xy 200.019866 -145.666693) (xy 199.972316 -145.630206) (xy 199.929936 -145.587826) (xy 199.893449 -145.540276)
			(xy 199.863482 -145.48837) (xy 199.840546 -145.432997) (xy 199.825033 -145.375104) (xy 199.81721 -145.315682)
			(xy 199.81672 -145.285714) (xy 181.760876 -145.285714) (xy 181.760876 -145.287238) (xy 181.760386 -145.317206)
			(xy 181.752563 -145.376628) (xy 181.73705 -145.434521) (xy 181.714114 -145.489894) (xy 181.684147 -145.5418)
			(xy 181.64766 -145.58935) (xy 181.60528 -145.63173) (xy 181.55773 -145.668217) (xy 181.505824 -145.698184)
			(xy 181.450451 -145.72112) (xy 181.392558 -145.736633) (xy 181.333136 -145.744456) (xy 181.2732 -145.744456)
			(xy 181.213778 -145.736633) (xy 181.155885 -145.72112) (xy 181.100512 -145.698184) (xy 181.048606 -145.668217)
			(xy 181.001056 -145.63173) (xy 180.958676 -145.58935) (xy 180.922189 -145.5418) (xy 180.892222 -145.489894)
			(xy 180.869286 -145.434521) (xy 180.853773 -145.376628) (xy 180.84595 -145.317206) (xy 180.84546 -145.287238)
			(xy 84.632267 -145.287238) (xy 84.631802 -145.315698) (xy 84.623974 -145.375154) (xy 84.608453 -145.433079)
			(xy 84.585504 -145.488483) (xy 84.55552 -145.540417) (xy 84.519014 -145.587993) (xy 84.476609 -145.630398)
			(xy 84.429033 -145.666904) (xy 84.377099 -145.696888) (xy 84.321695 -145.719837) (xy 84.26377 -145.735358)
			(xy 84.204314 -145.743186) (xy 84.144346 -145.743186) (xy 84.08489 -145.735358) (xy 84.026965 -145.719837)
			(xy 83.971561 -145.696888) (xy 83.919627 -145.666904) (xy 83.872051 -145.630398) (xy 83.829646 -145.587993)
			(xy 83.79314 -145.540417) (xy 83.763156 -145.488483) (xy 83.740207 -145.433079) (xy 83.724686 -145.375154)
			(xy 83.716858 -145.315698) (xy 83.716368 -145.285714) (xy 65.661032 -145.285714) (xy 65.661032 -145.287238)
			(xy 65.660542 -145.317222) (xy 65.652714 -145.376678) (xy 65.637193 -145.434603) (xy 65.614244 -145.490007)
			(xy 65.58426 -145.541941) (xy 65.547754 -145.589517) (xy 65.505349 -145.631922) (xy 65.457773 -145.668428)
			(xy 65.405839 -145.698412) (xy 65.350435 -145.721361) (xy 65.29251 -145.736882) (xy 65.233054 -145.74471)
			(xy 65.173086 -145.74471) (xy 65.11363 -145.736882) (xy 65.055705 -145.721361) (xy 65.000301 -145.698412)
			(xy 64.948367 -145.668428) (xy 64.900791 -145.631922) (xy 64.858386 -145.589517) (xy 64.82188 -145.541941)
			(xy 64.791896 -145.490007) (xy 64.768947 -145.434603) (xy 64.753426 -145.376678) (xy 64.745598 -145.317222)
			(xy 64.745108 -145.287238) (xy 4.30911 -145.287238) (xy 4.30911 -147.087336) (xy 66.599308 -147.087336)
			(xy 66.599308 -146.223736) (xy 66.599798 -146.193752) (xy 66.607626 -146.134296) (xy 66.623147 -146.076371)
			(xy 66.646096 -146.020967) (xy 66.67608 -145.969033) (xy 66.712586 -145.921457) (xy 66.754991 -145.879052)
			(xy 66.802567 -145.842546) (xy 66.854501 -145.812562) (xy 66.909905 -145.789613) (xy 66.96783 -145.774092)
			(xy 67.027286 -145.766264) (xy 67.087254 -145.766264) (xy 67.14671 -145.774092) (xy 67.204635 -145.789613)
			(xy 67.260039 -145.812562) (xy 67.311973 -145.842546) (xy 67.359549 -145.879052) (xy 67.401954 -145.921457)
			(xy 67.43846 -145.969033) (xy 67.468444 -146.020967) (xy 67.491393 -146.076371) (xy 67.506914 -146.134296)
			(xy 67.514742 -146.193752) (xy 67.515232 -146.223736) (xy 67.515232 -147.079208) (xy 81.07426 -147.079208)
			(xy 81.07426 -146.215608) (xy 81.07475 -146.185624) (xy 81.082578 -146.126168) (xy 81.098099 -146.068243)
			(xy 81.121048 -146.012839) (xy 81.151032 -145.960905) (xy 81.187538 -145.913329) (xy 81.229943 -145.870924)
			(xy 81.277519 -145.834418) (xy 81.329453 -145.804434) (xy 81.384857 -145.781485) (xy 81.442782 -145.765964)
			(xy 81.502238 -145.758136) (xy 81.562206 -145.758136) (xy 81.621662 -145.765964) (xy 81.679587 -145.781485)
			(xy 81.734991 -145.804434) (xy 81.786925 -145.834418) (xy 81.834501 -145.870924) (xy 81.876906 -145.913329)
			(xy 81.913412 -145.960905) (xy 81.943396 -146.012839) (xy 81.966345 -146.068243) (xy 81.981866 -146.126168)
			(xy 81.989694 -146.185624) (xy 81.990184 -146.215608) (xy 81.990184 -147.079208) (xy 81.990051 -147.087336)
			(xy 182.69966 -147.087336) (xy 182.69966 -146.223736) (xy 182.70015 -146.193768) (xy 182.707973 -146.134346)
			(xy 182.723486 -146.076453) (xy 182.746422 -146.02108) (xy 182.776389 -145.969174) (xy 182.812876 -145.921624)
			(xy 182.855256 -145.879244) (xy 182.902806 -145.842757) (xy 182.954712 -145.81279) (xy 183.010085 -145.789854)
			(xy 183.067978 -145.774341) (xy 183.1274 -145.766518) (xy 183.187336 -145.766518) (xy 183.246758 -145.774341)
			(xy 183.304651 -145.789854) (xy 183.360024 -145.81279) (xy 183.41193 -145.842757) (xy 183.45948 -145.879244)
			(xy 183.50186 -145.921624) (xy 183.538347 -145.969174) (xy 183.568314 -146.02108) (xy 183.59125 -146.076453)
			(xy 183.606763 -146.134346) (xy 183.614586 -146.193768) (xy 183.615076 -146.223736) (xy 183.615076 -147.079208)
			(xy 197.174612 -147.079208) (xy 197.174612 -146.215608) (xy 197.175102 -146.18564) (xy 197.182925 -146.126218)
			(xy 197.198438 -146.068325) (xy 197.221374 -146.012952) (xy 197.251341 -145.961046) (xy 197.287828 -145.913496)
			(xy 197.330208 -145.871116) (xy 197.377758 -145.834629) (xy 197.429664 -145.804662) (xy 197.485037 -145.781726)
			(xy 197.54293 -145.766213) (xy 197.602352 -145.75839) (xy 197.662288 -145.75839) (xy 197.72171 -145.766213)
			(xy 197.779603 -145.781726) (xy 197.834976 -145.804662) (xy 197.886882 -145.834629) (xy 197.934432 -145.871116)
			(xy 197.976812 -145.913496) (xy 198.013299 -145.961046) (xy 198.043266 -146.012952) (xy 198.066202 -146.068325)
			(xy 198.081715 -146.126218) (xy 198.089538 -146.18564) (xy 198.090028 -146.215608) (xy 198.090028 -147.079208)
			(xy 198.089895 -147.087336) (xy 298.799504 -147.087336) (xy 298.799504 -146.223736) (xy 298.799994 -146.193768)
			(xy 298.807817 -146.134346) (xy 298.82333 -146.076453) (xy 298.846266 -146.02108) (xy 298.876233 -145.969174)
			(xy 298.91272 -145.921624) (xy 298.9551 -145.879244) (xy 299.00265 -145.842757) (xy 299.054556 -145.81279)
			(xy 299.109929 -145.789854) (xy 299.167822 -145.774341) (xy 299.227244 -145.766518) (xy 299.28718 -145.766518)
			(xy 299.346602 -145.774341) (xy 299.404495 -145.789854) (xy 299.459868 -145.81279) (xy 299.511774 -145.842757)
			(xy 299.559324 -145.879244) (xy 299.601704 -145.921624) (xy 299.638191 -145.969174) (xy 299.668158 -146.02108)
			(xy 299.691094 -146.076453) (xy 299.706607 -146.134346) (xy 299.71443 -146.193768) (xy 299.71492 -146.223736)
			(xy 299.71492 -147.079208) (xy 313.274456 -147.079208) (xy 313.274456 -146.215608) (xy 313.274946 -146.18564)
			(xy 313.282769 -146.126218) (xy 313.298282 -146.068325) (xy 313.321218 -146.012952) (xy 313.351185 -145.961046)
			(xy 313.387672 -145.913496) (xy 313.430052 -145.871116) (xy 313.477602 -145.834629) (xy 313.529508 -145.804662)
			(xy 313.584881 -145.781726) (xy 313.642774 -145.766213) (xy 313.702196 -145.75839) (xy 313.762132 -145.75839)
			(xy 313.821554 -145.766213) (xy 313.879447 -145.781726) (xy 313.93482 -145.804662) (xy 313.986726 -145.834629)
			(xy 314.034276 -145.871116) (xy 314.076656 -145.913496) (xy 314.113143 -145.961046) (xy 314.14311 -146.012952)
			(xy 314.166046 -146.068325) (xy 314.181559 -146.126218) (xy 314.189382 -146.18564) (xy 314.189872 -146.215608)
			(xy 314.189872 -147.079208) (xy 314.189739 -147.087336) (xy 414.899348 -147.087336) (xy 414.899348 -146.223736)
			(xy 414.899838 -146.193752) (xy 414.907666 -146.134296) (xy 414.923187 -146.076371) (xy 414.946136 -146.020967)
			(xy 414.97612 -145.969033) (xy 415.012626 -145.921457) (xy 415.055031 -145.879052) (xy 415.102607 -145.842546)
			(xy 415.154541 -145.812562) (xy 415.209945 -145.789613) (xy 415.26787 -145.774092) (xy 415.327326 -145.766264)
			(xy 415.387294 -145.766264) (xy 415.44675 -145.774092) (xy 415.504675 -145.789613) (xy 415.560079 -145.812562)
			(xy 415.612013 -145.842546) (xy 415.659589 -145.879052) (xy 415.701994 -145.921457) (xy 415.7385 -145.969033)
			(xy 415.768484 -146.020967) (xy 415.791433 -146.076371) (xy 415.806954 -146.134296) (xy 415.814782 -146.193752)
			(xy 415.815272 -146.223736) (xy 415.815272 -147.079208) (xy 429.3743 -147.079208) (xy 429.3743 -146.215608)
			(xy 429.37479 -146.185624) (xy 429.382618 -146.126168) (xy 429.398139 -146.068243) (xy 429.421088 -146.012839)
			(xy 429.451072 -145.960905) (xy 429.487578 -145.913329) (xy 429.529983 -145.870924) (xy 429.577559 -145.834418)
			(xy 429.629493 -145.804434) (xy 429.684897 -145.781485) (xy 429.742822 -145.765964) (xy 429.802278 -145.758136)
			(xy 429.862246 -145.758136) (xy 429.921702 -145.765964) (xy 429.979627 -145.781485) (xy 430.035031 -145.804434)
			(xy 430.086965 -145.834418) (xy 430.134541 -145.870924) (xy 430.176946 -145.913329) (xy 430.213452 -145.960905)
			(xy 430.243436 -146.012839) (xy 430.266385 -146.068243) (xy 430.281906 -146.126168) (xy 430.289734 -146.185624)
			(xy 430.290224 -146.215608) (xy 430.290224 -147.079208) (xy 430.289734 -147.109192) (xy 430.281906 -147.168648)
			(xy 430.266385 -147.226573) (xy 430.243436 -147.281977) (xy 430.213452 -147.333911) (xy 430.176946 -147.381487)
			(xy 430.134541 -147.423892) (xy 430.086965 -147.460398) (xy 430.035031 -147.490382) (xy 429.979627 -147.513331)
			(xy 429.921702 -147.528852) (xy 429.862246 -147.53668) (xy 429.802278 -147.53668) (xy 429.742822 -147.528852)
			(xy 429.684897 -147.513331) (xy 429.629493 -147.490382) (xy 429.577559 -147.460398) (xy 429.529983 -147.423892)
			(xy 429.487578 -147.381487) (xy 429.451072 -147.333911) (xy 429.421088 -147.281977) (xy 429.398139 -147.226573)
			(xy 429.382618 -147.168648) (xy 429.37479 -147.109192) (xy 429.3743 -147.079208) (xy 415.815272 -147.079208)
			(xy 415.815272 -147.087336) (xy 415.814782 -147.11732) (xy 415.806954 -147.176776) (xy 415.791433 -147.234701)
			(xy 415.768484 -147.290105) (xy 415.7385 -147.342039) (xy 415.701994 -147.389615) (xy 415.659589 -147.43202)
			(xy 415.612013 -147.468526) (xy 415.560079 -147.49851) (xy 415.504675 -147.521459) (xy 415.44675 -147.53698)
			(xy 415.387294 -147.544808) (xy 415.327326 -147.544808) (xy 415.26787 -147.53698) (xy 415.209945 -147.521459)
			(xy 415.154541 -147.49851) (xy 415.102607 -147.468526) (xy 415.055031 -147.43202) (xy 415.012626 -147.389615)
			(xy 414.97612 -147.342039) (xy 414.946136 -147.290105) (xy 414.923187 -147.234701) (xy 414.907666 -147.176776)
			(xy 414.899838 -147.11732) (xy 414.899348 -147.087336) (xy 314.189739 -147.087336) (xy 314.189382 -147.109176)
			(xy 314.181559 -147.168598) (xy 314.166046 -147.226491) (xy 314.14311 -147.281864) (xy 314.113143 -147.33377)
			(xy 314.076656 -147.38132) (xy 314.034276 -147.4237) (xy 313.986726 -147.460187) (xy 313.93482 -147.490154)
			(xy 313.879447 -147.51309) (xy 313.821554 -147.528603) (xy 313.762132 -147.536426) (xy 313.702196 -147.536426)
			(xy 313.642774 -147.528603) (xy 313.584881 -147.51309) (xy 313.529508 -147.490154) (xy 313.477602 -147.460187)
			(xy 313.430052 -147.4237) (xy 313.387672 -147.38132) (xy 313.351185 -147.33377) (xy 313.321218 -147.281864)
			(xy 313.298282 -147.226491) (xy 313.282769 -147.168598) (xy 313.274946 -147.109176) (xy 313.274456 -147.079208)
			(xy 299.71492 -147.079208) (xy 299.71492 -147.087336) (xy 299.71443 -147.117304) (xy 299.706607 -147.176726)
			(xy 299.691094 -147.234619) (xy 299.668158 -147.289992) (xy 299.638191 -147.341898) (xy 299.601704 -147.389448)
			(xy 299.559324 -147.431828) (xy 299.511774 -147.468315) (xy 299.459868 -147.498282) (xy 299.404495 -147.521218)
			(xy 299.346602 -147.536731) (xy 299.28718 -147.544554) (xy 299.227244 -147.544554) (xy 299.167822 -147.536731)
			(xy 299.109929 -147.521218) (xy 299.054556 -147.498282) (xy 299.00265 -147.468315) (xy 298.9551 -147.431828)
			(xy 298.91272 -147.389448) (xy 298.876233 -147.341898) (xy 298.846266 -147.289992) (xy 298.82333 -147.234619)
			(xy 298.807817 -147.176726) (xy 298.799994 -147.117304) (xy 298.799504 -147.087336) (xy 198.089895 -147.087336)
			(xy 198.089538 -147.109176) (xy 198.081715 -147.168598) (xy 198.066202 -147.226491) (xy 198.043266 -147.281864)
			(xy 198.013299 -147.33377) (xy 197.976812 -147.38132) (xy 197.934432 -147.4237) (xy 197.886882 -147.460187)
			(xy 197.834976 -147.490154) (xy 197.779603 -147.51309) (xy 197.72171 -147.528603) (xy 197.662288 -147.536426)
			(xy 197.602352 -147.536426) (xy 197.54293 -147.528603) (xy 197.485037 -147.51309) (xy 197.429664 -147.490154)
			(xy 197.377758 -147.460187) (xy 197.330208 -147.4237) (xy 197.287828 -147.38132) (xy 197.251341 -147.33377)
			(xy 197.221374 -147.281864) (xy 197.198438 -147.226491) (xy 197.182925 -147.168598) (xy 197.175102 -147.109176)
			(xy 197.174612 -147.079208) (xy 183.615076 -147.079208) (xy 183.615076 -147.087336) (xy 183.614586 -147.117304)
			(xy 183.606763 -147.176726) (xy 183.59125 -147.234619) (xy 183.568314 -147.289992) (xy 183.538347 -147.341898)
			(xy 183.50186 -147.389448) (xy 183.45948 -147.431828) (xy 183.41193 -147.468315) (xy 183.360024 -147.498282)
			(xy 183.304651 -147.521218) (xy 183.246758 -147.536731) (xy 183.187336 -147.544554) (xy 183.1274 -147.544554)
			(xy 183.067978 -147.536731) (xy 183.010085 -147.521218) (xy 182.954712 -147.498282) (xy 182.902806 -147.468315)
			(xy 182.855256 -147.431828) (xy 182.812876 -147.389448) (xy 182.776389 -147.341898) (xy 182.746422 -147.289992)
			(xy 182.723486 -147.234619) (xy 182.707973 -147.176726) (xy 182.70015 -147.117304) (xy 182.69966 -147.087336)
			(xy 81.990051 -147.087336) (xy 81.989694 -147.109192) (xy 81.981866 -147.168648) (xy 81.966345 -147.226573)
			(xy 81.943396 -147.281977) (xy 81.913412 -147.333911) (xy 81.876906 -147.381487) (xy 81.834501 -147.423892)
			(xy 81.786925 -147.460398) (xy 81.734991 -147.490382) (xy 81.679587 -147.513331) (xy 81.621662 -147.528852)
			(xy 81.562206 -147.53668) (xy 81.502238 -147.53668) (xy 81.442782 -147.528852) (xy 81.384857 -147.513331)
			(xy 81.329453 -147.490382) (xy 81.277519 -147.460398) (xy 81.229943 -147.423892) (xy 81.187538 -147.381487)
			(xy 81.151032 -147.333911) (xy 81.121048 -147.281977) (xy 81.098099 -147.226573) (xy 81.082578 -147.168648)
			(xy 81.07475 -147.109192) (xy 81.07426 -147.079208) (xy 67.515232 -147.079208) (xy 67.515232 -147.087336)
			(xy 67.514742 -147.11732) (xy 67.506914 -147.176776) (xy 67.491393 -147.234701) (xy 67.468444 -147.290105)
			(xy 67.43846 -147.342039) (xy 67.401954 -147.389615) (xy 67.359549 -147.43202) (xy 67.311973 -147.468526)
			(xy 67.260039 -147.49851) (xy 67.204635 -147.521459) (xy 67.14671 -147.53698) (xy 67.087254 -147.544808)
			(xy 67.027286 -147.544808) (xy 66.96783 -147.53698) (xy 66.909905 -147.521459) (xy 66.854501 -147.49851)
			(xy 66.802567 -147.468526) (xy 66.754991 -147.43202) (xy 66.712586 -147.389615) (xy 66.67608 -147.342039)
			(xy 66.646096 -147.290105) (xy 66.623147 -147.234701) (xy 66.607626 -147.176776) (xy 66.599798 -147.11732)
			(xy 66.599308 -147.087336) (xy 4.30911 -147.087336) (xy 4.30911 -148.887434) (xy 64.745108 -148.887434)
			(xy 64.745108 -148.023834) (xy 64.745598 -147.99385) (xy 64.753426 -147.934394) (xy 64.768947 -147.876469)
			(xy 64.791896 -147.821065) (xy 64.82188 -147.769131) (xy 64.858386 -147.721555) (xy 64.900791 -147.67915)
			(xy 64.948367 -147.642644) (xy 65.000301 -147.61266) (xy 65.055705 -147.589711) (xy 65.11363 -147.57419)
			(xy 65.173086 -147.566362) (xy 65.233054 -147.566362) (xy 65.29251 -147.57419) (xy 65.350435 -147.589711)
			(xy 65.405839 -147.61266) (xy 65.457773 -147.642644) (xy 65.505349 -147.67915) (xy 65.547754 -147.721555)
			(xy 65.58426 -147.769131) (xy 65.614244 -147.821065) (xy 65.637193 -147.876469) (xy 65.652714 -147.934394)
			(xy 65.660542 -147.99385) (xy 65.661032 -148.023834) (xy 65.661032 -148.88591) (xy 83.716368 -148.88591)
			(xy 83.716368 -148.02231) (xy 83.716858 -147.992326) (xy 83.724686 -147.93287) (xy 83.740207 -147.874945)
			(xy 83.763156 -147.819541) (xy 83.79314 -147.767607) (xy 83.829646 -147.720031) (xy 83.872051 -147.677626)
			(xy 83.919627 -147.64112) (xy 83.971561 -147.611136) (xy 84.026965 -147.588187) (xy 84.08489 -147.572666)
			(xy 84.144346 -147.564838) (xy 84.204314 -147.564838) (xy 84.26377 -147.572666) (xy 84.321695 -147.588187)
			(xy 84.377099 -147.611136) (xy 84.429033 -147.64112) (xy 84.476609 -147.677626) (xy 84.519014 -147.720031)
			(xy 84.55552 -147.767607) (xy 84.585504 -147.819541) (xy 84.608453 -147.874945) (xy 84.623974 -147.93287)
			(xy 84.631802 -147.992326) (xy 84.632292 -148.02231) (xy 84.632292 -148.88591) (xy 84.632267 -148.887434)
			(xy 180.84546 -148.887434) (xy 180.84546 -148.023834) (xy 180.84595 -147.993866) (xy 180.853773 -147.934444)
			(xy 180.869286 -147.876551) (xy 180.892222 -147.821178) (xy 180.922189 -147.769272) (xy 180.958676 -147.721722)
			(xy 181.001056 -147.679342) (xy 181.048606 -147.642855) (xy 181.100512 -147.612888) (xy 181.155885 -147.589952)
			(xy 181.213778 -147.574439) (xy 181.2732 -147.566616) (xy 181.333136 -147.566616) (xy 181.392558 -147.574439)
			(xy 181.450451 -147.589952) (xy 181.505824 -147.612888) (xy 181.55773 -147.642855) (xy 181.60528 -147.679342)
			(xy 181.64766 -147.721722) (xy 181.684147 -147.769272) (xy 181.714114 -147.821178) (xy 181.73705 -147.876551)
			(xy 181.752563 -147.934444) (xy 181.760386 -147.993866) (xy 181.760876 -148.023834) (xy 181.760876 -148.88591)
			(xy 199.81672 -148.88591) (xy 199.81672 -148.02231) (xy 199.81721 -147.992342) (xy 199.825033 -147.93292)
			(xy 199.840546 -147.875027) (xy 199.863482 -147.819654) (xy 199.893449 -147.767748) (xy 199.929936 -147.720198)
			(xy 199.972316 -147.677818) (xy 200.019866 -147.641331) (xy 200.071772 -147.611364) (xy 200.127145 -147.588428)
			(xy 200.185038 -147.572915) (xy 200.24446 -147.565092) (xy 200.304396 -147.565092) (xy 200.363818 -147.572915)
			(xy 200.421711 -147.588428) (xy 200.477084 -147.611364) (xy 200.52899 -147.641331) (xy 200.57654 -147.677818)
			(xy 200.61892 -147.720198) (xy 200.655407 -147.767748) (xy 200.685374 -147.819654) (xy 200.70831 -147.875027)
			(xy 200.723823 -147.93292) (xy 200.731646 -147.992342) (xy 200.732136 -148.02231) (xy 200.732136 -148.88591)
			(xy 200.731646 -148.915878) (xy 200.723823 -148.9753) (xy 200.70831 -149.033193) (xy 200.685374 -149.088566)
			(xy 200.655407 -149.140472) (xy 200.61892 -149.188022) (xy 200.57654 -149.230402) (xy 200.52899 -149.266889)
			(xy 200.477084 -149.296856) (xy 200.421711 -149.319792) (xy 200.363818 -149.335305) (xy 200.304396 -149.343128)
			(xy 200.24446 -149.343128) (xy 200.185038 -149.335305) (xy 200.127145 -149.319792) (xy 200.071772 -149.296856)
			(xy 200.019866 -149.266889) (xy 199.972316 -149.230402) (xy 199.929936 -149.188022) (xy 199.893449 -149.140472)
			(xy 199.863482 -149.088566) (xy 199.840546 -149.033193) (xy 199.825033 -148.9753) (xy 199.81721 -148.915878)
			(xy 199.81672 -148.88591) (xy 181.760876 -148.88591) (xy 181.760876 -148.887434) (xy 181.760386 -148.917402)
			(xy 181.752563 -148.976824) (xy 181.73705 -149.034717) (xy 181.714114 -149.09009) (xy 181.684147 -149.141996)
			(xy 181.64766 -149.189546) (xy 181.60528 -149.231926) (xy 181.55773 -149.268413) (xy 181.505824 -149.29838)
			(xy 181.450451 -149.321316) (xy 181.392558 -149.336829) (xy 181.333136 -149.344652) (xy 181.2732 -149.344652)
			(xy 181.213778 -149.336829) (xy 181.155885 -149.321316) (xy 181.100512 -149.29838) (xy 181.048606 -149.268413)
			(xy 181.001056 -149.231926) (xy 180.958676 -149.189546) (xy 180.922189 -149.141996) (xy 180.892222 -149.09009)
			(xy 180.869286 -149.034717) (xy 180.853773 -148.976824) (xy 180.84595 -148.917402) (xy 180.84546 -148.887434)
			(xy 84.632267 -148.887434) (xy 84.631802 -148.915894) (xy 84.623974 -148.97535) (xy 84.608453 -149.033275)
			(xy 84.585504 -149.088679) (xy 84.55552 -149.140613) (xy 84.519014 -149.188189) (xy 84.476609 -149.230594)
			(xy 84.429033 -149.2671) (xy 84.377099 -149.297084) (xy 84.321695 -149.320033) (xy 84.26377 -149.335554)
			(xy 84.204314 -149.343382) (xy 84.144346 -149.343382) (xy 84.08489 -149.335554) (xy 84.026965 -149.320033)
			(xy 83.971561 -149.297084) (xy 83.919627 -149.2671) (xy 83.872051 -149.230594) (xy 83.829646 -149.188189)
			(xy 83.79314 -149.140613) (xy 83.763156 -149.088679) (xy 83.740207 -149.033275) (xy 83.724686 -148.97535)
			(xy 83.716858 -148.915894) (xy 83.716368 -148.88591) (xy 65.661032 -148.88591) (xy 65.661032 -148.887434)
			(xy 65.660542 -148.917418) (xy 65.652714 -148.976874) (xy 65.637193 -149.034799) (xy 65.614244 -149.090203)
			(xy 65.58426 -149.142137) (xy 65.547754 -149.189713) (xy 65.505349 -149.232118) (xy 65.457773 -149.268624)
			(xy 65.405839 -149.298608) (xy 65.350435 -149.321557) (xy 65.29251 -149.337078) (xy 65.233054 -149.344906)
			(xy 65.173086 -149.344906) (xy 65.11363 -149.337078) (xy 65.055705 -149.321557) (xy 65.000301 -149.298608)
			(xy 64.948367 -149.268624) (xy 64.900791 -149.232118) (xy 64.858386 -149.189713) (xy 64.82188 -149.142137)
			(xy 64.791896 -149.090203) (xy 64.768947 -149.034799) (xy 64.753426 -148.976874) (xy 64.745598 -148.917418)
			(xy 64.745108 -148.887434) (xy 4.30911 -148.887434) (xy 4.30911 -150.687278) (xy 66.599308 -150.687278)
			(xy 66.599308 -149.823678) (xy 66.599798 -149.793694) (xy 66.607626 -149.734238) (xy 66.623147 -149.676313)
			(xy 66.646096 -149.620909) (xy 66.67608 -149.568975) (xy 66.712586 -149.521399) (xy 66.754991 -149.478994)
			(xy 66.802567 -149.442488) (xy 66.854501 -149.412504) (xy 66.909905 -149.389555) (xy 66.96783 -149.374034)
			(xy 67.027286 -149.366206) (xy 67.087254 -149.366206) (xy 67.14671 -149.374034) (xy 67.204635 -149.389555)
			(xy 67.260039 -149.412504) (xy 67.311973 -149.442488) (xy 67.359549 -149.478994) (xy 67.401954 -149.521399)
			(xy 67.43846 -149.568975) (xy 67.468444 -149.620909) (xy 67.491393 -149.676313) (xy 67.506914 -149.734238)
			(xy 67.514742 -149.793694) (xy 67.515232 -149.823678) (xy 67.515232 -150.67915) (xy 81.07426 -150.67915)
			(xy 81.07426 -149.81555) (xy 81.07475 -149.785566) (xy 81.082578 -149.72611) (xy 81.098099 -149.668185)
			(xy 81.121048 -149.612781) (xy 81.151032 -149.560847) (xy 81.187538 -149.513271) (xy 81.229943 -149.470866)
			(xy 81.277519 -149.43436) (xy 81.329453 -149.404376) (xy 81.384857 -149.381427) (xy 81.442782 -149.365906)
			(xy 81.502238 -149.358078) (xy 81.562206 -149.358078) (xy 81.621662 -149.365906) (xy 81.679587 -149.381427)
			(xy 81.734991 -149.404376) (xy 81.786925 -149.43436) (xy 81.834501 -149.470866) (xy 81.876906 -149.513271)
			(xy 81.913412 -149.560847) (xy 81.943396 -149.612781) (xy 81.966345 -149.668185) (xy 81.981866 -149.72611)
			(xy 81.989694 -149.785566) (xy 81.990184 -149.81555) (xy 81.990184 -150.67915) (xy 81.990051 -150.687278)
			(xy 182.69966 -150.687278) (xy 182.69966 -149.823678) (xy 182.70015 -149.79371) (xy 182.707973 -149.734288)
			(xy 182.723486 -149.676395) (xy 182.746422 -149.621022) (xy 182.776389 -149.569116) (xy 182.812876 -149.521566)
			(xy 182.855256 -149.479186) (xy 182.902806 -149.442699) (xy 182.954712 -149.412732) (xy 183.010085 -149.389796)
			(xy 183.067978 -149.374283) (xy 183.1274 -149.36646) (xy 183.187336 -149.36646) (xy 183.246758 -149.374283)
			(xy 183.304651 -149.389796) (xy 183.360024 -149.412732) (xy 183.41193 -149.442699) (xy 183.45948 -149.479186)
			(xy 183.50186 -149.521566) (xy 183.538347 -149.569116) (xy 183.568314 -149.621022) (xy 183.59125 -149.676395)
			(xy 183.606763 -149.734288) (xy 183.614586 -149.79371) (xy 183.615076 -149.823678) (xy 183.615076 -150.67915)
			(xy 197.174612 -150.67915) (xy 197.174612 -149.81555) (xy 197.175102 -149.785582) (xy 197.182925 -149.72616)
			(xy 197.198438 -149.668267) (xy 197.221374 -149.612894) (xy 197.251341 -149.560988) (xy 197.287828 -149.513438)
			(xy 197.330208 -149.471058) (xy 197.377758 -149.434571) (xy 197.429664 -149.404604) (xy 197.485037 -149.381668)
			(xy 197.54293 -149.366155) (xy 197.602352 -149.358332) (xy 197.662288 -149.358332) (xy 197.72171 -149.366155)
			(xy 197.779603 -149.381668) (xy 197.834976 -149.404604) (xy 197.886882 -149.434571) (xy 197.934432 -149.471058)
			(xy 197.976812 -149.513438) (xy 198.013299 -149.560988) (xy 198.043266 -149.612894) (xy 198.066202 -149.668267)
			(xy 198.072386 -149.691344) (xy 236.708188 -149.691344) (xy 236.708188 -148.827744) (xy 236.708678 -148.79776)
			(xy 236.716506 -148.738304) (xy 236.732027 -148.680379) (xy 236.754976 -148.624975) (xy 236.78496 -148.573041)
			(xy 236.821466 -148.525465) (xy 236.863871 -148.48306) (xy 236.911447 -148.446554) (xy 236.963381 -148.41657)
			(xy 237.018785 -148.393621) (xy 237.07671 -148.3781) (xy 237.136166 -148.370272) (xy 237.196134 -148.370272)
			(xy 237.25559 -148.3781) (xy 237.313515 -148.393621) (xy 237.368919 -148.41657) (xy 237.420853 -148.446554)
			(xy 237.468429 -148.48306) (xy 237.510834 -148.525465) (xy 237.54734 -148.573041) (xy 237.577324 -148.624975)
			(xy 237.600273 -148.680379) (xy 237.615794 -148.738304) (xy 237.623622 -148.79776) (xy 237.624112 -148.827744)
			(xy 237.624112 -148.887434) (xy 296.945304 -148.887434) (xy 296.945304 -148.023834) (xy 296.945794 -147.993866)
			(xy 296.953617 -147.934444) (xy 296.96913 -147.876551) (xy 296.992066 -147.821178) (xy 297.022033 -147.769272)
			(xy 297.05852 -147.721722) (xy 297.1009 -147.679342) (xy 297.14845 -147.642855) (xy 297.200356 -147.612888)
			(xy 297.255729 -147.589952) (xy 297.313622 -147.574439) (xy 297.373044 -147.566616) (xy 297.43298 -147.566616)
			(xy 297.492402 -147.574439) (xy 297.550295 -147.589952) (xy 297.605668 -147.612888) (xy 297.657574 -147.642855)
			(xy 297.705124 -147.679342) (xy 297.747504 -147.721722) (xy 297.783991 -147.769272) (xy 297.813958 -147.821178)
			(xy 297.836894 -147.876551) (xy 297.852407 -147.934444) (xy 297.86023 -147.993866) (xy 297.86072 -148.023834)
			(xy 297.86072 -148.88591) (xy 315.916564 -148.88591) (xy 315.916564 -148.02231) (xy 315.917054 -147.992342)
			(xy 315.924877 -147.93292) (xy 315.94039 -147.875027) (xy 315.963326 -147.819654) (xy 315.993293 -147.767748)
			(xy 316.02978 -147.720198) (xy 316.07216 -147.677818) (xy 316.11971 -147.641331) (xy 316.171616 -147.611364)
			(xy 316.226989 -147.588428) (xy 316.284882 -147.572915) (xy 316.344304 -147.565092) (xy 316.40424 -147.565092)
			(xy 316.463662 -147.572915) (xy 316.521555 -147.588428) (xy 316.576928 -147.611364) (xy 316.628834 -147.641331)
			(xy 316.676384 -147.677818) (xy 316.718764 -147.720198) (xy 316.755251 -147.767748) (xy 316.785218 -147.819654)
			(xy 316.808154 -147.875027) (xy 316.823667 -147.93292) (xy 316.83149 -147.992342) (xy 316.83198 -148.02231)
			(xy 316.83198 -148.88591) (xy 316.831955 -148.887434) (xy 413.045148 -148.887434) (xy 413.045148 -148.023834)
			(xy 413.045638 -147.99385) (xy 413.053466 -147.934394) (xy 413.068987 -147.876469) (xy 413.091936 -147.821065)
			(xy 413.12192 -147.769131) (xy 413.158426 -147.721555) (xy 413.200831 -147.67915) (xy 413.248407 -147.642644)
			(xy 413.300341 -147.61266) (xy 413.355745 -147.589711) (xy 413.41367 -147.57419) (xy 413.473126 -147.566362)
			(xy 413.533094 -147.566362) (xy 413.59255 -147.57419) (xy 413.650475 -147.589711) (xy 413.705879 -147.61266)
			(xy 413.757813 -147.642644) (xy 413.805389 -147.67915) (xy 413.847794 -147.721555) (xy 413.8843 -147.769131)
			(xy 413.914284 -147.821065) (xy 413.937233 -147.876469) (xy 413.952754 -147.934394) (xy 413.960582 -147.99385)
			(xy 413.961072 -148.023834) (xy 413.961072 -148.88591) (xy 432.016408 -148.88591) (xy 432.016408 -148.02231)
			(xy 432.016898 -147.992326) (xy 432.024726 -147.93287) (xy 432.040247 -147.874945) (xy 432.063196 -147.819541)
			(xy 432.09318 -147.767607) (xy 432.129686 -147.720031) (xy 432.172091 -147.677626) (xy 432.219667 -147.64112)
			(xy 432.271601 -147.611136) (xy 432.327005 -147.588187) (xy 432.38493 -147.572666) (xy 432.444386 -147.564838)
			(xy 432.504354 -147.564838) (xy 432.56381 -147.572666) (xy 432.621735 -147.588187) (xy 432.677139 -147.611136)
			(xy 432.729073 -147.64112) (xy 432.776649 -147.677626) (xy 432.819054 -147.720031) (xy 432.85556 -147.767607)
			(xy 432.885544 -147.819541) (xy 432.908493 -147.874945) (xy 432.924014 -147.93287) (xy 432.931842 -147.992326)
			(xy 432.932332 -148.02231) (xy 432.932332 -148.88591) (xy 432.931842 -148.915894) (xy 432.924014 -148.97535)
			(xy 432.908493 -149.033275) (xy 432.885544 -149.088679) (xy 432.85556 -149.140613) (xy 432.819054 -149.188189)
			(xy 432.776649 -149.230594) (xy 432.729073 -149.2671) (xy 432.677139 -149.297084) (xy 432.621735 -149.320033)
			(xy 432.56381 -149.335554) (xy 432.504354 -149.343382) (xy 432.444386 -149.343382) (xy 432.38493 -149.335554)
			(xy 432.327005 -149.320033) (xy 432.271601 -149.297084) (xy 432.219667 -149.2671) (xy 432.172091 -149.230594)
			(xy 432.129686 -149.188189) (xy 432.09318 -149.140613) (xy 432.063196 -149.088679) (xy 432.040247 -149.033275)
			(xy 432.024726 -148.97535) (xy 432.016898 -148.915894) (xy 432.016408 -148.88591) (xy 413.961072 -148.88591)
			(xy 413.961072 -148.887434) (xy 413.960582 -148.917418) (xy 413.952754 -148.976874) (xy 413.937233 -149.034799)
			(xy 413.914284 -149.090203) (xy 413.8843 -149.142137) (xy 413.847794 -149.189713) (xy 413.805389 -149.232118)
			(xy 413.757813 -149.268624) (xy 413.705879 -149.298608) (xy 413.650475 -149.321557) (xy 413.59255 -149.337078)
			(xy 413.533094 -149.344906) (xy 413.473126 -149.344906) (xy 413.41367 -149.337078) (xy 413.355745 -149.321557)
			(xy 413.300341 -149.298608) (xy 413.248407 -149.268624) (xy 413.200831 -149.232118) (xy 413.158426 -149.189713)
			(xy 413.12192 -149.142137) (xy 413.091936 -149.090203) (xy 413.068987 -149.034799) (xy 413.053466 -148.976874)
			(xy 413.045638 -148.917418) (xy 413.045148 -148.887434) (xy 316.831955 -148.887434) (xy 316.83149 -148.915878)
			(xy 316.823667 -148.9753) (xy 316.808154 -149.033193) (xy 316.785218 -149.088566) (xy 316.755251 -149.140472)
			(xy 316.718764 -149.188022) (xy 316.676384 -149.230402) (xy 316.628834 -149.266889) (xy 316.576928 -149.296856)
			(xy 316.521555 -149.319792) (xy 316.463662 -149.335305) (xy 316.40424 -149.343128) (xy 316.344304 -149.343128)
			(xy 316.284882 -149.335305) (xy 316.226989 -149.319792) (xy 316.171616 -149.296856) (xy 316.11971 -149.266889)
			(xy 316.07216 -149.230402) (xy 316.02978 -149.188022) (xy 315.993293 -149.140472) (xy 315.963326 -149.088566)
			(xy 315.94039 -149.033193) (xy 315.924877 -148.9753) (xy 315.917054 -148.915878) (xy 315.916564 -148.88591)
			(xy 297.86072 -148.88591) (xy 297.86072 -148.887434) (xy 297.86023 -148.917402) (xy 297.852407 -148.976824)
			(xy 297.836894 -149.034717) (xy 297.813958 -149.09009) (xy 297.783991 -149.141996) (xy 297.747504 -149.189546)
			(xy 297.705124 -149.231926) (xy 297.657574 -149.268413) (xy 297.605668 -149.29838) (xy 297.550295 -149.321316)
			(xy 297.492402 -149.336829) (xy 297.43298 -149.344652) (xy 297.373044 -149.344652) (xy 297.313622 -149.336829)
			(xy 297.255729 -149.321316) (xy 297.200356 -149.29838) (xy 297.14845 -149.268413) (xy 297.1009 -149.231926)
			(xy 297.05852 -149.189546) (xy 297.022033 -149.141996) (xy 296.992066 -149.09009) (xy 296.96913 -149.034717)
			(xy 296.953617 -148.976824) (xy 296.945794 -148.917402) (xy 296.945304 -148.887434) (xy 237.624112 -148.887434)
			(xy 237.624112 -149.691344) (xy 237.623622 -149.721328) (xy 237.615794 -149.780784) (xy 237.600273 -149.838709)
			(xy 237.577324 -149.894113) (xy 237.54734 -149.946047) (xy 237.510834 -149.993623) (xy 237.468429 -150.036028)
			(xy 237.420853 -150.072534) (xy 237.368919 -150.102518) (xy 237.313515 -150.125467) (xy 237.25559 -150.140988)
			(xy 237.196134 -150.148816) (xy 237.136166 -150.148816) (xy 237.07671 -150.140988) (xy 237.018785 -150.125467)
			(xy 236.963381 -150.102518) (xy 236.911447 -150.072534) (xy 236.863871 -150.036028) (xy 236.821466 -149.993623)
			(xy 236.78496 -149.946047) (xy 236.754976 -149.894113) (xy 236.732027 -149.838709) (xy 236.716506 -149.780784)
			(xy 236.708678 -149.721328) (xy 236.708188 -149.691344) (xy 198.072386 -149.691344) (xy 198.081715 -149.72616)
			(xy 198.089538 -149.785582) (xy 198.090028 -149.81555) (xy 198.090028 -150.67915) (xy 198.089538 -150.709118)
			(xy 198.081715 -150.76854) (xy 198.066202 -150.826433) (xy 198.043266 -150.881806) (xy 198.013299 -150.933712)
			(xy 197.976812 -150.981262) (xy 197.934432 -151.023642) (xy 197.886882 -151.060129) (xy 197.834976 -151.090096)
			(xy 197.779603 -151.113032) (xy 197.72171 -151.128545) (xy 197.662288 -151.136368) (xy 197.602352 -151.136368)
			(xy 197.54293 -151.128545) (xy 197.485037 -151.113032) (xy 197.429664 -151.090096) (xy 197.377758 -151.060129)
			(xy 197.330208 -151.023642) (xy 197.287828 -150.981262) (xy 197.251341 -150.933712) (xy 197.221374 -150.881806)
			(xy 197.198438 -150.826433) (xy 197.182925 -150.76854) (xy 197.175102 -150.709118) (xy 197.174612 -150.67915)
			(xy 183.615076 -150.67915) (xy 183.615076 -150.687278) (xy 183.614586 -150.717246) (xy 183.606763 -150.776668)
			(xy 183.59125 -150.834561) (xy 183.568314 -150.889934) (xy 183.538347 -150.94184) (xy 183.50186 -150.98939)
			(xy 183.45948 -151.03177) (xy 183.41193 -151.068257) (xy 183.360024 -151.098224) (xy 183.304651 -151.12116)
			(xy 183.246758 -151.136673) (xy 183.187336 -151.144496) (xy 183.1274 -151.144496) (xy 183.067978 -151.136673)
			(xy 183.010085 -151.12116) (xy 182.954712 -151.098224) (xy 182.902806 -151.068257) (xy 182.855256 -151.03177)
			(xy 182.812876 -150.98939) (xy 182.776389 -150.94184) (xy 182.746422 -150.889934) (xy 182.723486 -150.834561)
			(xy 182.707973 -150.776668) (xy 182.70015 -150.717246) (xy 182.69966 -150.687278) (xy 81.990051 -150.687278)
			(xy 81.989694 -150.709134) (xy 81.981866 -150.76859) (xy 81.966345 -150.826515) (xy 81.943396 -150.881919)
			(xy 81.913412 -150.933853) (xy 81.876906 -150.981429) (xy 81.834501 -151.023834) (xy 81.786925 -151.06034)
			(xy 81.734991 -151.090324) (xy 81.679587 -151.113273) (xy 81.621662 -151.128794) (xy 81.562206 -151.136622)
			(xy 81.502238 -151.136622) (xy 81.442782 -151.128794) (xy 81.384857 -151.113273) (xy 81.329453 -151.090324)
			(xy 81.277519 -151.06034) (xy 81.229943 -151.023834) (xy 81.187538 -150.981429) (xy 81.151032 -150.933853)
			(xy 81.121048 -150.881919) (xy 81.098099 -150.826515) (xy 81.082578 -150.76859) (xy 81.07475 -150.709134)
			(xy 81.07426 -150.67915) (xy 67.515232 -150.67915) (xy 67.515232 -150.687278) (xy 67.514742 -150.717262)
			(xy 67.506914 -150.776718) (xy 67.491393 -150.834643) (xy 67.468444 -150.890047) (xy 67.43846 -150.941981)
			(xy 67.401954 -150.989557) (xy 67.359549 -151.031962) (xy 67.311973 -151.068468) (xy 67.260039 -151.098452)
			(xy 67.204635 -151.121401) (xy 67.14671 -151.136922) (xy 67.087254 -151.14475) (xy 67.027286 -151.14475)
			(xy 66.96783 -151.136922) (xy 66.909905 -151.121401) (xy 66.854501 -151.098452) (xy 66.802567 -151.068468)
			(xy 66.754991 -151.031962) (xy 66.712586 -150.989557) (xy 66.67608 -150.941981) (xy 66.646096 -150.890047)
			(xy 66.623147 -150.834643) (xy 66.607626 -150.776718) (xy 66.599798 -150.717262) (xy 66.599308 -150.687278)
			(xy 4.30911 -150.687278) (xy 4.30911 -152.487376) (xy 64.745108 -152.487376) (xy 64.745108 -151.623776)
			(xy 64.745598 -151.593792) (xy 64.753426 -151.534336) (xy 64.768947 -151.476411) (xy 64.791896 -151.421007)
			(xy 64.82188 -151.369073) (xy 64.858386 -151.321497) (xy 64.900791 -151.279092) (xy 64.948367 -151.242586)
			(xy 65.000301 -151.212602) (xy 65.055705 -151.189653) (xy 65.11363 -151.174132) (xy 65.173086 -151.166304)
			(xy 65.233054 -151.166304) (xy 65.29251 -151.174132) (xy 65.350435 -151.189653) (xy 65.405839 -151.212602)
			(xy 65.457773 -151.242586) (xy 65.505349 -151.279092) (xy 65.547754 -151.321497) (xy 65.58426 -151.369073)
			(xy 65.614244 -151.421007) (xy 65.637193 -151.476411) (xy 65.652714 -151.534336) (xy 65.660542 -151.593792)
			(xy 65.661032 -151.623776) (xy 65.661032 -152.485852) (xy 83.716368 -152.485852) (xy 83.716368 -151.622252)
			(xy 83.716858 -151.592268) (xy 83.724686 -151.532812) (xy 83.740207 -151.474887) (xy 83.763156 -151.419483)
			(xy 83.79314 -151.367549) (xy 83.829646 -151.319973) (xy 83.872051 -151.277568) (xy 83.919627 -151.241062)
			(xy 83.971561 -151.211078) (xy 84.026965 -151.188129) (xy 84.08489 -151.172608) (xy 84.144346 -151.16478)
			(xy 84.204314 -151.16478) (xy 84.26377 -151.172608) (xy 84.321695 -151.188129) (xy 84.377099 -151.211078)
			(xy 84.429033 -151.241062) (xy 84.476609 -151.277568) (xy 84.519014 -151.319973) (xy 84.55552 -151.367549)
			(xy 84.585504 -151.419483) (xy 84.608453 -151.474887) (xy 84.623974 -151.532812) (xy 84.631802 -151.592268)
			(xy 84.632292 -151.622252) (xy 84.632292 -152.485852) (xy 84.632267 -152.487376) (xy 180.84546 -152.487376)
			(xy 180.84546 -151.623776) (xy 180.84595 -151.593808) (xy 180.853773 -151.534386) (xy 180.869286 -151.476493)
			(xy 180.892222 -151.42112) (xy 180.922189 -151.369214) (xy 180.958676 -151.321664) (xy 181.001056 -151.279284)
			(xy 181.048606 -151.242797) (xy 181.100512 -151.21283) (xy 181.155885 -151.189894) (xy 181.213778 -151.174381)
			(xy 181.2732 -151.166558) (xy 181.333136 -151.166558) (xy 181.392558 -151.174381) (xy 181.450451 -151.189894)
			(xy 181.505824 -151.21283) (xy 181.55773 -151.242797) (xy 181.60528 -151.279284) (xy 181.64766 -151.321664)
			(xy 181.684147 -151.369214) (xy 181.714114 -151.42112) (xy 181.73705 -151.476493) (xy 181.752563 -151.534386)
			(xy 181.760386 -151.593808) (xy 181.760876 -151.623776) (xy 181.760876 -152.485852) (xy 199.81672 -152.485852)
			(xy 199.81672 -151.622252) (xy 199.81721 -151.592284) (xy 199.825033 -151.532862) (xy 199.840546 -151.474969)
			(xy 199.863482 -151.419596) (xy 199.893449 -151.36769) (xy 199.929936 -151.32014) (xy 199.972316 -151.27776)
			(xy 200.019866 -151.241273) (xy 200.071772 -151.211306) (xy 200.127145 -151.18837) (xy 200.185038 -151.172857)
			(xy 200.24446 -151.165034) (xy 200.304396 -151.165034) (xy 200.363818 -151.172857) (xy 200.421711 -151.18837)
			(xy 200.477084 -151.211306) (xy 200.52899 -151.241273) (xy 200.57654 -151.27776) (xy 200.61892 -151.32014)
			(xy 200.655407 -151.36769) (xy 200.685374 -151.419596) (xy 200.70831 -151.474969) (xy 200.723823 -151.532862)
			(xy 200.731646 -151.592284) (xy 200.732136 -151.622252) (xy 200.732136 -151.914098) (xy 236.712252 -151.914098)
			(xy 236.712252 -151.050498) (xy 236.712742 -151.020514) (xy 236.72057 -150.961058) (xy 236.736091 -150.903133)
			(xy 236.75904 -150.847729) (xy 236.789024 -150.795795) (xy 236.82553 -150.748219) (xy 236.867935 -150.705814)
			(xy 236.915511 -150.669308) (xy 236.967445 -150.639324) (xy 237.022849 -150.616375) (xy 237.080774 -150.600854)
			(xy 237.14023 -150.593026) (xy 237.200198 -150.593026) (xy 237.259654 -150.600854) (xy 237.317579 -150.616375)
			(xy 237.372983 -150.639324) (xy 237.424917 -150.669308) (xy 237.448336 -150.687278) (xy 298.799504 -150.687278)
			(xy 298.799504 -149.823678) (xy 298.799994 -149.79371) (xy 298.807817 -149.734288) (xy 298.82333 -149.676395)
			(xy 298.846266 -149.621022) (xy 298.876233 -149.569116) (xy 298.91272 -149.521566) (xy 298.9551 -149.479186)
			(xy 299.00265 -149.442699) (xy 299.054556 -149.412732) (xy 299.109929 -149.389796) (xy 299.167822 -149.374283)
			(xy 299.227244 -149.36646) (xy 299.28718 -149.36646) (xy 299.346602 -149.374283) (xy 299.404495 -149.389796)
			(xy 299.459868 -149.412732) (xy 299.511774 -149.442699) (xy 299.559324 -149.479186) (xy 299.601704 -149.521566)
			(xy 299.638191 -149.569116) (xy 299.668158 -149.621022) (xy 299.691094 -149.676395) (xy 299.706607 -149.734288)
			(xy 299.71443 -149.79371) (xy 299.71492 -149.823678) (xy 299.71492 -150.67915) (xy 313.274456 -150.67915)
			(xy 313.274456 -149.81555) (xy 313.274946 -149.785582) (xy 313.282769 -149.72616) (xy 313.298282 -149.668267)
			(xy 313.321218 -149.612894) (xy 313.351185 -149.560988) (xy 313.387672 -149.513438) (xy 313.430052 -149.471058)
			(xy 313.477602 -149.434571) (xy 313.529508 -149.404604) (xy 313.584881 -149.381668) (xy 313.642774 -149.366155)
			(xy 313.702196 -149.358332) (xy 313.762132 -149.358332) (xy 313.821554 -149.366155) (xy 313.879447 -149.381668)
			(xy 313.93482 -149.404604) (xy 313.986726 -149.434571) (xy 314.034276 -149.471058) (xy 314.076656 -149.513438)
			(xy 314.113143 -149.560988) (xy 314.14311 -149.612894) (xy 314.166046 -149.668267) (xy 314.181559 -149.72616)
			(xy 314.189382 -149.785582) (xy 314.189872 -149.81555) (xy 314.189872 -150.67915) (xy 314.189739 -150.687278)
			(xy 414.899348 -150.687278) (xy 414.899348 -149.823678) (xy 414.899838 -149.793694) (xy 414.907666 -149.734238)
			(xy 414.923187 -149.676313) (xy 414.946136 -149.620909) (xy 414.97612 -149.568975) (xy 415.012626 -149.521399)
			(xy 415.055031 -149.478994) (xy 415.102607 -149.442488) (xy 415.154541 -149.412504) (xy 415.209945 -149.389555)
			(xy 415.26787 -149.374034) (xy 415.327326 -149.366206) (xy 415.387294 -149.366206) (xy 415.44675 -149.374034)
			(xy 415.504675 -149.389555) (xy 415.560079 -149.412504) (xy 415.612013 -149.442488) (xy 415.659589 -149.478994)
			(xy 415.701994 -149.521399) (xy 415.7385 -149.568975) (xy 415.768484 -149.620909) (xy 415.791433 -149.676313)
			(xy 415.806954 -149.734238) (xy 415.814782 -149.793694) (xy 415.815272 -149.823678) (xy 415.815272 -150.67915)
			(xy 429.3743 -150.67915) (xy 429.3743 -149.81555) (xy 429.37479 -149.785566) (xy 429.382618 -149.72611)
			(xy 429.398139 -149.668185) (xy 429.421088 -149.612781) (xy 429.451072 -149.560847) (xy 429.487578 -149.513271)
			(xy 429.529983 -149.470866) (xy 429.577559 -149.43436) (xy 429.629493 -149.404376) (xy 429.684897 -149.381427)
			(xy 429.742822 -149.365906) (xy 429.802278 -149.358078) (xy 429.862246 -149.358078) (xy 429.921702 -149.365906)
			(xy 429.979627 -149.381427) (xy 430.035031 -149.404376) (xy 430.086965 -149.43436) (xy 430.134541 -149.470866)
			(xy 430.176946 -149.513271) (xy 430.213452 -149.560847) (xy 430.243436 -149.612781) (xy 430.266385 -149.668185)
			(xy 430.281906 -149.72611) (xy 430.289734 -149.785566) (xy 430.290224 -149.81555) (xy 430.290224 -150.67915)
			(xy 430.289734 -150.709134) (xy 430.281906 -150.76859) (xy 430.266385 -150.826515) (xy 430.243436 -150.881919)
			(xy 430.213452 -150.933853) (xy 430.176946 -150.981429) (xy 430.134541 -151.023834) (xy 430.086965 -151.06034)
			(xy 430.035031 -151.090324) (xy 429.979627 -151.113273) (xy 429.921702 -151.128794) (xy 429.862246 -151.136622)
			(xy 429.802278 -151.136622) (xy 429.742822 -151.128794) (xy 429.684897 -151.113273) (xy 429.629493 -151.090324)
			(xy 429.577559 -151.06034) (xy 429.529983 -151.023834) (xy 429.487578 -150.981429) (xy 429.451072 -150.933853)
			(xy 429.421088 -150.881919) (xy 429.398139 -150.826515) (xy 429.382618 -150.76859) (xy 429.37479 -150.709134)
			(xy 429.3743 -150.67915) (xy 415.815272 -150.67915) (xy 415.815272 -150.687278) (xy 415.814782 -150.717262)
			(xy 415.806954 -150.776718) (xy 415.791433 -150.834643) (xy 415.768484 -150.890047) (xy 415.7385 -150.941981)
			(xy 415.701994 -150.989557) (xy 415.659589 -151.031962) (xy 415.612013 -151.068468) (xy 415.560079 -151.098452)
			(xy 415.504675 -151.121401) (xy 415.44675 -151.136922) (xy 415.387294 -151.14475) (xy 415.327326 -151.14475)
			(xy 415.26787 -151.136922) (xy 415.209945 -151.121401) (xy 415.154541 -151.098452) (xy 415.102607 -151.068468)
			(xy 415.055031 -151.031962) (xy 415.012626 -150.989557) (xy 414.97612 -150.941981) (xy 414.946136 -150.890047)
			(xy 414.923187 -150.834643) (xy 414.907666 -150.776718) (xy 414.899838 -150.717262) (xy 414.899348 -150.687278)
			(xy 314.189739 -150.687278) (xy 314.189382 -150.709118) (xy 314.181559 -150.76854) (xy 314.166046 -150.826433)
			(xy 314.14311 -150.881806) (xy 314.113143 -150.933712) (xy 314.076656 -150.981262) (xy 314.034276 -151.023642)
			(xy 313.986726 -151.060129) (xy 313.93482 -151.090096) (xy 313.879447 -151.113032) (xy 313.821554 -151.128545)
			(xy 313.762132 -151.136368) (xy 313.702196 -151.136368) (xy 313.642774 -151.128545) (xy 313.584881 -151.113032)
			(xy 313.529508 -151.090096) (xy 313.477602 -151.060129) (xy 313.430052 -151.023642) (xy 313.387672 -150.981262)
			(xy 313.351185 -150.933712) (xy 313.321218 -150.881806) (xy 313.298282 -150.826433) (xy 313.282769 -150.76854)
			(xy 313.274946 -150.709118) (xy 313.274456 -150.67915) (xy 299.71492 -150.67915) (xy 299.71492 -150.687278)
			(xy 299.71443 -150.717246) (xy 299.706607 -150.776668) (xy 299.691094 -150.834561) (xy 299.668158 -150.889934)
			(xy 299.638191 -150.94184) (xy 299.601704 -150.98939) (xy 299.559324 -151.03177) (xy 299.511774 -151.068257)
			(xy 299.459868 -151.098224) (xy 299.404495 -151.12116) (xy 299.346602 -151.136673) (xy 299.28718 -151.144496)
			(xy 299.227244 -151.144496) (xy 299.167822 -151.136673) (xy 299.109929 -151.12116) (xy 299.054556 -151.098224)
			(xy 299.00265 -151.068257) (xy 298.9551 -151.03177) (xy 298.91272 -150.98939) (xy 298.876233 -150.94184)
			(xy 298.846266 -150.889934) (xy 298.82333 -150.834561) (xy 298.807817 -150.776668) (xy 298.799994 -150.717246)
			(xy 298.799504 -150.687278) (xy 237.448336 -150.687278) (xy 237.472493 -150.705814) (xy 237.514898 -150.748219)
			(xy 237.551404 -150.795795) (xy 237.581388 -150.847729) (xy 237.604337 -150.903133) (xy 237.619858 -150.961058)
			(xy 237.627686 -151.020514) (xy 237.628176 -151.050498) (xy 237.628176 -151.914098) (xy 237.627686 -151.944082)
			(xy 237.619858 -152.003538) (xy 237.604337 -152.061463) (xy 237.581388 -152.116867) (xy 237.551404 -152.168801)
			(xy 237.514898 -152.216377) (xy 237.472493 -152.258782) (xy 237.424917 -152.295288) (xy 237.372983 -152.325272)
			(xy 237.317579 -152.348221) (xy 237.259654 -152.363742) (xy 237.200198 -152.37157) (xy 237.14023 -152.37157)
			(xy 237.080774 -152.363742) (xy 237.022849 -152.348221) (xy 236.967445 -152.325272) (xy 236.915511 -152.295288)
			(xy 236.867935 -152.258782) (xy 236.82553 -152.216377) (xy 236.789024 -152.168801) (xy 236.75904 -152.116867)
			(xy 236.736091 -152.061463) (xy 236.72057 -152.003538) (xy 236.712742 -151.944082) (xy 236.712252 -151.914098)
			(xy 200.732136 -151.914098) (xy 200.732136 -152.485852) (xy 200.732111 -152.487376) (xy 296.945304 -152.487376)
			(xy 296.945304 -151.623776) (xy 296.945794 -151.593808) (xy 296.953617 -151.534386) (xy 296.96913 -151.476493)
			(xy 296.992066 -151.42112) (xy 297.022033 -151.369214) (xy 297.05852 -151.321664) (xy 297.1009 -151.279284)
			(xy 297.14845 -151.242797) (xy 297.200356 -151.21283) (xy 297.255729 -151.189894) (xy 297.313622 -151.174381)
			(xy 297.373044 -151.166558) (xy 297.43298 -151.166558) (xy 297.492402 -151.174381) (xy 297.550295 -151.189894)
			(xy 297.605668 -151.21283) (xy 297.657574 -151.242797) (xy 297.705124 -151.279284) (xy 297.747504 -151.321664)
			(xy 297.783991 -151.369214) (xy 297.813958 -151.42112) (xy 297.836894 -151.476493) (xy 297.852407 -151.534386)
			(xy 297.86023 -151.593808) (xy 297.86072 -151.623776) (xy 297.86072 -152.485852) (xy 315.916564 -152.485852)
			(xy 315.916564 -151.622252) (xy 315.917054 -151.592284) (xy 315.924877 -151.532862) (xy 315.94039 -151.474969)
			(xy 315.963326 -151.419596) (xy 315.993293 -151.36769) (xy 316.02978 -151.32014) (xy 316.07216 -151.27776)
			(xy 316.11971 -151.241273) (xy 316.171616 -151.211306) (xy 316.226989 -151.18837) (xy 316.284882 -151.172857)
			(xy 316.344304 -151.165034) (xy 316.40424 -151.165034) (xy 316.463662 -151.172857) (xy 316.521555 -151.18837)
			(xy 316.576928 -151.211306) (xy 316.628834 -151.241273) (xy 316.676384 -151.27776) (xy 316.718764 -151.32014)
			(xy 316.755251 -151.36769) (xy 316.785218 -151.419596) (xy 316.808154 -151.474969) (xy 316.823667 -151.532862)
			(xy 316.83149 -151.592284) (xy 316.83198 -151.622252) (xy 316.83198 -152.485852) (xy 316.831955 -152.487376)
			(xy 413.045148 -152.487376) (xy 413.045148 -151.623776) (xy 413.045638 -151.593792) (xy 413.053466 -151.534336)
			(xy 413.068987 -151.476411) (xy 413.091936 -151.421007) (xy 413.12192 -151.369073) (xy 413.158426 -151.321497)
			(xy 413.200831 -151.279092) (xy 413.248407 -151.242586) (xy 413.300341 -151.212602) (xy 413.355745 -151.189653)
			(xy 413.41367 -151.174132) (xy 413.473126 -151.166304) (xy 413.533094 -151.166304) (xy 413.59255 -151.174132)
			(xy 413.650475 -151.189653) (xy 413.705879 -151.212602) (xy 413.757813 -151.242586) (xy 413.805389 -151.279092)
			(xy 413.847794 -151.321497) (xy 413.8843 -151.369073) (xy 413.914284 -151.421007) (xy 413.937233 -151.476411)
			(xy 413.952754 -151.534336) (xy 413.960582 -151.593792) (xy 413.961072 -151.623776) (xy 413.961072 -152.485852)
			(xy 432.016408 -152.485852) (xy 432.016408 -151.622252) (xy 432.016898 -151.592268) (xy 432.024726 -151.532812)
			(xy 432.040247 -151.474887) (xy 432.063196 -151.419483) (xy 432.09318 -151.367549) (xy 432.129686 -151.319973)
			(xy 432.172091 -151.277568) (xy 432.219667 -151.241062) (xy 432.271601 -151.211078) (xy 432.327005 -151.188129)
			(xy 432.38493 -151.172608) (xy 432.444386 -151.16478) (xy 432.504354 -151.16478) (xy 432.56381 -151.172608)
			(xy 432.621735 -151.188129) (xy 432.677139 -151.211078) (xy 432.729073 -151.241062) (xy 432.776649 -151.277568)
			(xy 432.819054 -151.319973) (xy 432.85556 -151.367549) (xy 432.885544 -151.419483) (xy 432.908493 -151.474887)
			(xy 432.924014 -151.532812) (xy 432.931842 -151.592268) (xy 432.932332 -151.622252) (xy 432.932332 -152.485852)
			(xy 432.931842 -152.515836) (xy 432.924014 -152.575292) (xy 432.908493 -152.633217) (xy 432.885544 -152.688621)
			(xy 432.85556 -152.740555) (xy 432.819054 -152.788131) (xy 432.776649 -152.830536) (xy 432.729073 -152.867042)
			(xy 432.677139 -152.897026) (xy 432.621735 -152.919975) (xy 432.56381 -152.935496) (xy 432.504354 -152.943324)
			(xy 432.444386 -152.943324) (xy 432.38493 -152.935496) (xy 432.327005 -152.919975) (xy 432.271601 -152.897026)
			(xy 432.219667 -152.867042) (xy 432.172091 -152.830536) (xy 432.129686 -152.788131) (xy 432.09318 -152.740555)
			(xy 432.063196 -152.688621) (xy 432.040247 -152.633217) (xy 432.024726 -152.575292) (xy 432.016898 -152.515836)
			(xy 432.016408 -152.485852) (xy 413.961072 -152.485852) (xy 413.961072 -152.487376) (xy 413.960582 -152.51736)
			(xy 413.952754 -152.576816) (xy 413.937233 -152.634741) (xy 413.914284 -152.690145) (xy 413.8843 -152.742079)
			(xy 413.847794 -152.789655) (xy 413.805389 -152.83206) (xy 413.757813 -152.868566) (xy 413.705879 -152.89855)
			(xy 413.650475 -152.921499) (xy 413.59255 -152.93702) (xy 413.533094 -152.944848) (xy 413.473126 -152.944848)
			(xy 413.41367 -152.93702) (xy 413.355745 -152.921499) (xy 413.300341 -152.89855) (xy 413.248407 -152.868566)
			(xy 413.200831 -152.83206) (xy 413.158426 -152.789655) (xy 413.12192 -152.742079) (xy 413.091936 -152.690145)
			(xy 413.068987 -152.634741) (xy 413.053466 -152.576816) (xy 413.045638 -152.51736) (xy 413.045148 -152.487376)
			(xy 316.831955 -152.487376) (xy 316.83149 -152.51582) (xy 316.823667 -152.575242) (xy 316.808154 -152.633135)
			(xy 316.785218 -152.688508) (xy 316.755251 -152.740414) (xy 316.718764 -152.787964) (xy 316.676384 -152.830344)
			(xy 316.628834 -152.866831) (xy 316.576928 -152.896798) (xy 316.521555 -152.919734) (xy 316.463662 -152.935247)
			(xy 316.40424 -152.94307) (xy 316.344304 -152.94307) (xy 316.284882 -152.935247) (xy 316.226989 -152.919734)
			(xy 316.171616 -152.896798) (xy 316.11971 -152.866831) (xy 316.07216 -152.830344) (xy 316.02978 -152.787964)
			(xy 315.993293 -152.740414) (xy 315.963326 -152.688508) (xy 315.94039 -152.633135) (xy 315.924877 -152.575242)
			(xy 315.917054 -152.51582) (xy 315.916564 -152.485852) (xy 297.86072 -152.485852) (xy 297.86072 -152.487376)
			(xy 297.86023 -152.517344) (xy 297.852407 -152.576766) (xy 297.836894 -152.634659) (xy 297.813958 -152.690032)
			(xy 297.783991 -152.741938) (xy 297.747504 -152.789488) (xy 297.705124 -152.831868) (xy 297.657574 -152.868355)
			(xy 297.605668 -152.898322) (xy 297.550295 -152.921258) (xy 297.492402 -152.936771) (xy 297.43298 -152.944594)
			(xy 297.373044 -152.944594) (xy 297.313622 -152.936771) (xy 297.255729 -152.921258) (xy 297.200356 -152.898322)
			(xy 297.14845 -152.868355) (xy 297.1009 -152.831868) (xy 297.05852 -152.789488) (xy 297.022033 -152.741938)
			(xy 296.992066 -152.690032) (xy 296.96913 -152.634659) (xy 296.953617 -152.576766) (xy 296.945794 -152.517344)
			(xy 296.945304 -152.487376) (xy 200.732111 -152.487376) (xy 200.731646 -152.51582) (xy 200.723823 -152.575242)
			(xy 200.70831 -152.633135) (xy 200.685374 -152.688508) (xy 200.655407 -152.740414) (xy 200.61892 -152.787964)
			(xy 200.57654 -152.830344) (xy 200.52899 -152.866831) (xy 200.477084 -152.896798) (xy 200.421711 -152.919734)
			(xy 200.363818 -152.935247) (xy 200.304396 -152.94307) (xy 200.24446 -152.94307) (xy 200.185038 -152.935247)
			(xy 200.127145 -152.919734) (xy 200.071772 -152.896798) (xy 200.019866 -152.866831) (xy 199.972316 -152.830344)
			(xy 199.929936 -152.787964) (xy 199.893449 -152.740414) (xy 199.863482 -152.688508) (xy 199.840546 -152.633135)
			(xy 199.825033 -152.575242) (xy 199.81721 -152.51582) (xy 199.81672 -152.485852) (xy 181.760876 -152.485852)
			(xy 181.760876 -152.487376) (xy 181.760386 -152.517344) (xy 181.752563 -152.576766) (xy 181.73705 -152.634659)
			(xy 181.714114 -152.690032) (xy 181.684147 -152.741938) (xy 181.64766 -152.789488) (xy 181.60528 -152.831868)
			(xy 181.55773 -152.868355) (xy 181.505824 -152.898322) (xy 181.450451 -152.921258) (xy 181.392558 -152.936771)
			(xy 181.333136 -152.944594) (xy 181.2732 -152.944594) (xy 181.213778 -152.936771) (xy 181.155885 -152.921258)
			(xy 181.100512 -152.898322) (xy 181.048606 -152.868355) (xy 181.001056 -152.831868) (xy 180.958676 -152.789488)
			(xy 180.922189 -152.741938) (xy 180.892222 -152.690032) (xy 180.869286 -152.634659) (xy 180.853773 -152.576766)
			(xy 180.84595 -152.517344) (xy 180.84546 -152.487376) (xy 84.632267 -152.487376) (xy 84.631802 -152.515836)
			(xy 84.623974 -152.575292) (xy 84.608453 -152.633217) (xy 84.585504 -152.688621) (xy 84.55552 -152.740555)
			(xy 84.519014 -152.788131) (xy 84.476609 -152.830536) (xy 84.429033 -152.867042) (xy 84.377099 -152.897026)
			(xy 84.321695 -152.919975) (xy 84.26377 -152.935496) (xy 84.204314 -152.943324) (xy 84.144346 -152.943324)
			(xy 84.08489 -152.935496) (xy 84.026965 -152.919975) (xy 83.971561 -152.897026) (xy 83.919627 -152.867042)
			(xy 83.872051 -152.830536) (xy 83.829646 -152.788131) (xy 83.79314 -152.740555) (xy 83.763156 -152.688621)
			(xy 83.740207 -152.633217) (xy 83.724686 -152.575292) (xy 83.716858 -152.515836) (xy 83.716368 -152.485852)
			(xy 65.661032 -152.485852) (xy 65.661032 -152.487376) (xy 65.660542 -152.51736) (xy 65.652714 -152.576816)
			(xy 65.637193 -152.634741) (xy 65.614244 -152.690145) (xy 65.58426 -152.742079) (xy 65.547754 -152.789655)
			(xy 65.505349 -152.83206) (xy 65.457773 -152.868566) (xy 65.405839 -152.89855) (xy 65.350435 -152.921499)
			(xy 65.29251 -152.93702) (xy 65.233054 -152.944848) (xy 65.173086 -152.944848) (xy 65.11363 -152.93702)
			(xy 65.055705 -152.921499) (xy 65.000301 -152.89855) (xy 64.948367 -152.868566) (xy 64.900791 -152.83206)
			(xy 64.858386 -152.789655) (xy 64.82188 -152.742079) (xy 64.791896 -152.690145) (xy 64.768947 -152.634741)
			(xy 64.753426 -152.576816) (xy 64.745598 -152.51736) (xy 64.745108 -152.487376) (xy 4.30911 -152.487376)
			(xy 4.30911 -154.28722) (xy 66.599308 -154.28722) (xy 66.599308 -153.42362) (xy 66.599798 -153.393636)
			(xy 66.607626 -153.33418) (xy 66.623147 -153.276255) (xy 66.646096 -153.220851) (xy 66.67608 -153.168917)
			(xy 66.712586 -153.121341) (xy 66.754991 -153.078936) (xy 66.802567 -153.04243) (xy 66.854501 -153.012446)
			(xy 66.909905 -152.989497) (xy 66.96783 -152.973976) (xy 67.027286 -152.966148) (xy 67.087254 -152.966148)
			(xy 67.14671 -152.973976) (xy 67.204635 -152.989497) (xy 67.260039 -153.012446) (xy 67.311973 -153.04243)
			(xy 67.359549 -153.078936) (xy 67.401954 -153.121341) (xy 67.43846 -153.168917) (xy 67.468444 -153.220851)
			(xy 67.491393 -153.276255) (xy 67.506914 -153.33418) (xy 67.514742 -153.393636) (xy 67.515232 -153.42362)
			(xy 67.515232 -154.279346) (xy 81.07426 -154.279346) (xy 81.07426 -153.415746) (xy 81.07475 -153.385762)
			(xy 81.082578 -153.326306) (xy 81.098099 -153.268381) (xy 81.121048 -153.212977) (xy 81.151032 -153.161043)
			(xy 81.187538 -153.113467) (xy 81.229943 -153.071062) (xy 81.277519 -153.034556) (xy 81.329453 -153.004572)
			(xy 81.384857 -152.981623) (xy 81.442782 -152.966102) (xy 81.502238 -152.958274) (xy 81.562206 -152.958274)
			(xy 81.621662 -152.966102) (xy 81.679587 -152.981623) (xy 81.734991 -153.004572) (xy 81.786925 -153.034556)
			(xy 81.834501 -153.071062) (xy 81.876906 -153.113467) (xy 81.913412 -153.161043) (xy 81.943396 -153.212977)
			(xy 81.966345 -153.268381) (xy 81.981866 -153.326306) (xy 81.989694 -153.385762) (xy 81.990184 -153.415746)
			(xy 81.990184 -154.279346) (xy 81.990055 -154.28722) (xy 182.69966 -154.28722) (xy 182.69966 -153.42362)
			(xy 182.70015 -153.393652) (xy 182.707973 -153.33423) (xy 182.723486 -153.276337) (xy 182.746422 -153.220964)
			(xy 182.776389 -153.169058) (xy 182.812876 -153.121508) (xy 182.855256 -153.079128) (xy 182.902806 -153.042641)
			(xy 182.954712 -153.012674) (xy 183.010085 -152.989738) (xy 183.067978 -152.974225) (xy 183.1274 -152.966402)
			(xy 183.187336 -152.966402) (xy 183.246758 -152.974225) (xy 183.304651 -152.989738) (xy 183.360024 -153.012674)
			(xy 183.41193 -153.042641) (xy 183.45948 -153.079128) (xy 183.50186 -153.121508) (xy 183.538347 -153.169058)
			(xy 183.568314 -153.220964) (xy 183.59125 -153.276337) (xy 183.606763 -153.33423) (xy 183.614586 -153.393652)
			(xy 183.615076 -153.42362) (xy 183.615076 -154.279346) (xy 197.174612 -154.279346) (xy 197.174612 -153.415746)
			(xy 197.175102 -153.385778) (xy 197.182925 -153.326356) (xy 197.198438 -153.268463) (xy 197.221374 -153.21309)
			(xy 197.251341 -153.161184) (xy 197.287828 -153.113634) (xy 197.330208 -153.071254) (xy 197.377758 -153.034767)
			(xy 197.429664 -153.0048) (xy 197.485037 -152.981864) (xy 197.54293 -152.966351) (xy 197.602352 -152.958528)
			(xy 197.662288 -152.958528) (xy 197.72171 -152.966351) (xy 197.779603 -152.981864) (xy 197.834976 -153.0048)
			(xy 197.886882 -153.034767) (xy 197.934432 -153.071254) (xy 197.976812 -153.113634) (xy 198.013299 -153.161184)
			(xy 198.043266 -153.21309) (xy 198.066202 -153.268463) (xy 198.081715 -153.326356) (xy 198.089538 -153.385778)
			(xy 198.090028 -153.415746) (xy 198.090028 -154.279346) (xy 198.089899 -154.28722) (xy 298.799504 -154.28722)
			(xy 298.799504 -153.42362) (xy 298.799994 -153.393652) (xy 298.807817 -153.33423) (xy 298.82333 -153.276337)
			(xy 298.846266 -153.220964) (xy 298.876233 -153.169058) (xy 298.91272 -153.121508) (xy 298.9551 -153.079128)
			(xy 299.00265 -153.042641) (xy 299.054556 -153.012674) (xy 299.109929 -152.989738) (xy 299.167822 -152.974225)
			(xy 299.227244 -152.966402) (xy 299.28718 -152.966402) (xy 299.346602 -152.974225) (xy 299.404495 -152.989738)
			(xy 299.459868 -153.012674) (xy 299.511774 -153.042641) (xy 299.559324 -153.079128) (xy 299.601704 -153.121508)
			(xy 299.638191 -153.169058) (xy 299.668158 -153.220964) (xy 299.691094 -153.276337) (xy 299.706607 -153.33423)
			(xy 299.71443 -153.393652) (xy 299.71492 -153.42362) (xy 299.71492 -154.279346) (xy 313.274456 -154.279346)
			(xy 313.274456 -153.415746) (xy 313.274946 -153.385778) (xy 313.282769 -153.326356) (xy 313.298282 -153.268463)
			(xy 313.321218 -153.21309) (xy 313.351185 -153.161184) (xy 313.387672 -153.113634) (xy 313.430052 -153.071254)
			(xy 313.477602 -153.034767) (xy 313.529508 -153.0048) (xy 313.584881 -152.981864) (xy 313.642774 -152.966351)
			(xy 313.702196 -152.958528) (xy 313.762132 -152.958528) (xy 313.821554 -152.966351) (xy 313.879447 -152.981864)
			(xy 313.93482 -153.0048) (xy 313.986726 -153.034767) (xy 314.034276 -153.071254) (xy 314.076656 -153.113634)
			(xy 314.113143 -153.161184) (xy 314.14311 -153.21309) (xy 314.166046 -153.268463) (xy 314.181559 -153.326356)
			(xy 314.189382 -153.385778) (xy 314.189872 -153.415746) (xy 314.189872 -154.279346) (xy 314.189743 -154.28722)
			(xy 414.899348 -154.28722) (xy 414.899348 -153.42362) (xy 414.899838 -153.393636) (xy 414.907666 -153.33418)
			(xy 414.923187 -153.276255) (xy 414.946136 -153.220851) (xy 414.97612 -153.168917) (xy 415.012626 -153.121341)
			(xy 415.055031 -153.078936) (xy 415.102607 -153.04243) (xy 415.154541 -153.012446) (xy 415.209945 -152.989497)
			(xy 415.26787 -152.973976) (xy 415.327326 -152.966148) (xy 415.387294 -152.966148) (xy 415.44675 -152.973976)
			(xy 415.504675 -152.989497) (xy 415.560079 -153.012446) (xy 415.612013 -153.04243) (xy 415.659589 -153.078936)
			(xy 415.701994 -153.121341) (xy 415.7385 -153.168917) (xy 415.768484 -153.220851) (xy 415.791433 -153.276255)
			(xy 415.806954 -153.33418) (xy 415.814782 -153.393636) (xy 415.815272 -153.42362) (xy 415.815272 -154.279346)
			(xy 429.3743 -154.279346) (xy 429.3743 -153.415746) (xy 429.37479 -153.385762) (xy 429.382618 -153.326306)
			(xy 429.398139 -153.268381) (xy 429.421088 -153.212977) (xy 429.451072 -153.161043) (xy 429.487578 -153.113467)
			(xy 429.529983 -153.071062) (xy 429.577559 -153.034556) (xy 429.629493 -153.004572) (xy 429.684897 -152.981623)
			(xy 429.742822 -152.966102) (xy 429.802278 -152.958274) (xy 429.862246 -152.958274) (xy 429.921702 -152.966102)
			(xy 429.979627 -152.981623) (xy 430.035031 -153.004572) (xy 430.086965 -153.034556) (xy 430.134541 -153.071062)
			(xy 430.176946 -153.113467) (xy 430.213452 -153.161043) (xy 430.243436 -153.212977) (xy 430.266385 -153.268381)
			(xy 430.281906 -153.326306) (xy 430.289734 -153.385762) (xy 430.290224 -153.415746) (xy 430.290224 -154.279346)
			(xy 430.289734 -154.30933) (xy 430.281906 -154.368786) (xy 430.266385 -154.426711) (xy 430.243436 -154.482115)
			(xy 430.213452 -154.534049) (xy 430.176946 -154.581625) (xy 430.134541 -154.62403) (xy 430.086965 -154.660536)
			(xy 430.035031 -154.69052) (xy 429.979627 -154.713469) (xy 429.921702 -154.72899) (xy 429.862246 -154.736818)
			(xy 429.802278 -154.736818) (xy 429.742822 -154.72899) (xy 429.684897 -154.713469) (xy 429.629493 -154.69052)
			(xy 429.577559 -154.660536) (xy 429.529983 -154.62403) (xy 429.487578 -154.581625) (xy 429.451072 -154.534049)
			(xy 429.421088 -154.482115) (xy 429.398139 -154.426711) (xy 429.382618 -154.368786) (xy 429.37479 -154.30933)
			(xy 429.3743 -154.279346) (xy 415.815272 -154.279346) (xy 415.815272 -154.28722) (xy 415.814782 -154.317204)
			(xy 415.806954 -154.37666) (xy 415.791433 -154.434585) (xy 415.768484 -154.489989) (xy 415.7385 -154.541923)
			(xy 415.701994 -154.589499) (xy 415.659589 -154.631904) (xy 415.612013 -154.66841) (xy 415.560079 -154.698394)
			(xy 415.504675 -154.721343) (xy 415.44675 -154.736864) (xy 415.387294 -154.744692) (xy 415.327326 -154.744692)
			(xy 415.26787 -154.736864) (xy 415.209945 -154.721343) (xy 415.154541 -154.698394) (xy 415.102607 -154.66841)
			(xy 415.055031 -154.631904) (xy 415.012626 -154.589499) (xy 414.97612 -154.541923) (xy 414.946136 -154.489989)
			(xy 414.923187 -154.434585) (xy 414.907666 -154.37666) (xy 414.899838 -154.317204) (xy 414.899348 -154.28722)
			(xy 314.189743 -154.28722) (xy 314.189382 -154.309314) (xy 314.181559 -154.368736) (xy 314.166046 -154.426629)
			(xy 314.14311 -154.482002) (xy 314.113143 -154.533908) (xy 314.076656 -154.581458) (xy 314.034276 -154.623838)
			(xy 313.986726 -154.660325) (xy 313.93482 -154.690292) (xy 313.879447 -154.713228) (xy 313.821554 -154.728741)
			(xy 313.762132 -154.736564) (xy 313.702196 -154.736564) (xy 313.642774 -154.728741) (xy 313.584881 -154.713228)
			(xy 313.529508 -154.690292) (xy 313.477602 -154.660325) (xy 313.430052 -154.623838) (xy 313.387672 -154.581458)
			(xy 313.351185 -154.533908) (xy 313.321218 -154.482002) (xy 313.298282 -154.426629) (xy 313.282769 -154.368736)
			(xy 313.274946 -154.309314) (xy 313.274456 -154.279346) (xy 299.71492 -154.279346) (xy 299.71492 -154.28722)
			(xy 299.71443 -154.317188) (xy 299.706607 -154.37661) (xy 299.691094 -154.434503) (xy 299.668158 -154.489876)
			(xy 299.638191 -154.541782) (xy 299.601704 -154.589332) (xy 299.559324 -154.631712) (xy 299.511774 -154.668199)
			(xy 299.459868 -154.698166) (xy 299.404495 -154.721102) (xy 299.346602 -154.736615) (xy 299.28718 -154.744438)
			(xy 299.227244 -154.744438) (xy 299.167822 -154.736615) (xy 299.109929 -154.721102) (xy 299.054556 -154.698166)
			(xy 299.00265 -154.668199) (xy 298.9551 -154.631712) (xy 298.91272 -154.589332) (xy 298.876233 -154.541782)
			(xy 298.846266 -154.489876) (xy 298.82333 -154.434503) (xy 298.807817 -154.37661) (xy 298.799994 -154.317188)
			(xy 298.799504 -154.28722) (xy 198.089899 -154.28722) (xy 198.089538 -154.309314) (xy 198.081715 -154.368736)
			(xy 198.066202 -154.426629) (xy 198.043266 -154.482002) (xy 198.013299 -154.533908) (xy 197.976812 -154.581458)
			(xy 197.934432 -154.623838) (xy 197.886882 -154.660325) (xy 197.834976 -154.690292) (xy 197.779603 -154.713228)
			(xy 197.72171 -154.728741) (xy 197.662288 -154.736564) (xy 197.602352 -154.736564) (xy 197.54293 -154.728741)
			(xy 197.485037 -154.713228) (xy 197.429664 -154.690292) (xy 197.377758 -154.660325) (xy 197.330208 -154.623838)
			(xy 197.287828 -154.581458) (xy 197.251341 -154.533908) (xy 197.221374 -154.482002) (xy 197.198438 -154.426629)
			(xy 197.182925 -154.368736) (xy 197.175102 -154.309314) (xy 197.174612 -154.279346) (xy 183.615076 -154.279346)
			(xy 183.615076 -154.28722) (xy 183.614586 -154.317188) (xy 183.606763 -154.37661) (xy 183.59125 -154.434503)
			(xy 183.568314 -154.489876) (xy 183.538347 -154.541782) (xy 183.50186 -154.589332) (xy 183.45948 -154.631712)
			(xy 183.41193 -154.668199) (xy 183.360024 -154.698166) (xy 183.304651 -154.721102) (xy 183.246758 -154.736615)
			(xy 183.187336 -154.744438) (xy 183.1274 -154.744438) (xy 183.067978 -154.736615) (xy 183.010085 -154.721102)
			(xy 182.954712 -154.698166) (xy 182.902806 -154.668199) (xy 182.855256 -154.631712) (xy 182.812876 -154.589332)
			(xy 182.776389 -154.541782) (xy 182.746422 -154.489876) (xy 182.723486 -154.434503) (xy 182.707973 -154.37661)
			(xy 182.70015 -154.317188) (xy 182.69966 -154.28722) (xy 81.990055 -154.28722) (xy 81.989694 -154.30933)
			(xy 81.981866 -154.368786) (xy 81.966345 -154.426711) (xy 81.943396 -154.482115) (xy 81.913412 -154.534049)
			(xy 81.876906 -154.581625) (xy 81.834501 -154.62403) (xy 81.786925 -154.660536) (xy 81.734991 -154.69052)
			(xy 81.679587 -154.713469) (xy 81.621662 -154.72899) (xy 81.562206 -154.736818) (xy 81.502238 -154.736818)
			(xy 81.442782 -154.72899) (xy 81.384857 -154.713469) (xy 81.329453 -154.69052) (xy 81.277519 -154.660536)
			(xy 81.229943 -154.62403) (xy 81.187538 -154.581625) (xy 81.151032 -154.534049) (xy 81.121048 -154.482115)
			(xy 81.098099 -154.426711) (xy 81.082578 -154.368786) (xy 81.07475 -154.30933) (xy 81.07426 -154.279346)
			(xy 67.515232 -154.279346) (xy 67.515232 -154.28722) (xy 67.514742 -154.317204) (xy 67.506914 -154.37666)
			(xy 67.491393 -154.434585) (xy 67.468444 -154.489989) (xy 67.43846 -154.541923) (xy 67.401954 -154.589499)
			(xy 67.359549 -154.631904) (xy 67.311973 -154.66841) (xy 67.260039 -154.698394) (xy 67.204635 -154.721343)
			(xy 67.14671 -154.736864) (xy 67.087254 -154.744692) (xy 67.027286 -154.744692) (xy 66.96783 -154.736864)
			(xy 66.909905 -154.721343) (xy 66.854501 -154.698394) (xy 66.802567 -154.66841) (xy 66.754991 -154.631904)
			(xy 66.712586 -154.589499) (xy 66.67608 -154.541923) (xy 66.646096 -154.489989) (xy 66.623147 -154.434585)
			(xy 66.607626 -154.37666) (xy 66.599798 -154.317204) (xy 66.599308 -154.28722) (xy 4.30911 -154.28722)
			(xy 4.30911 -156.087318) (xy 64.745108 -156.087318) (xy 64.745108 -155.223718) (xy 64.745598 -155.193734)
			(xy 64.753426 -155.134278) (xy 64.768947 -155.076353) (xy 64.791896 -155.020949) (xy 64.82188 -154.969015)
			(xy 64.858386 -154.921439) (xy 64.900791 -154.879034) (xy 64.948367 -154.842528) (xy 65.000301 -154.812544)
			(xy 65.055705 -154.789595) (xy 65.11363 -154.774074) (xy 65.173086 -154.766246) (xy 65.233054 -154.766246)
			(xy 65.29251 -154.774074) (xy 65.350435 -154.789595) (xy 65.405839 -154.812544) (xy 65.457773 -154.842528)
			(xy 65.505349 -154.879034) (xy 65.547754 -154.921439) (xy 65.58426 -154.969015) (xy 65.614244 -155.020949)
			(xy 65.637193 -155.076353) (xy 65.652714 -155.134278) (xy 65.660542 -155.193734) (xy 65.661032 -155.223718)
			(xy 65.661032 -156.085794) (xy 83.716368 -156.085794) (xy 83.716368 -155.222194) (xy 83.716858 -155.19221)
			(xy 83.724686 -155.132754) (xy 83.740207 -155.074829) (xy 83.763156 -155.019425) (xy 83.79314 -154.967491)
			(xy 83.829646 -154.919915) (xy 83.872051 -154.87751) (xy 83.919627 -154.841004) (xy 83.971561 -154.81102)
			(xy 84.026965 -154.788071) (xy 84.08489 -154.77255) (xy 84.144346 -154.764722) (xy 84.204314 -154.764722)
			(xy 84.26377 -154.77255) (xy 84.321695 -154.788071) (xy 84.377099 -154.81102) (xy 84.429033 -154.841004)
			(xy 84.476609 -154.87751) (xy 84.519014 -154.919915) (xy 84.55552 -154.967491) (xy 84.585504 -155.019425)
			(xy 84.608453 -155.074829) (xy 84.623974 -155.132754) (xy 84.631802 -155.19221) (xy 84.632292 -155.222194)
			(xy 84.632292 -156.085794) (xy 84.632267 -156.087318) (xy 180.84546 -156.087318) (xy 180.84546 -155.223718)
			(xy 180.84595 -155.19375) (xy 180.853773 -155.134328) (xy 180.869286 -155.076435) (xy 180.892222 -155.021062)
			(xy 180.922189 -154.969156) (xy 180.958676 -154.921606) (xy 181.001056 -154.879226) (xy 181.048606 -154.842739)
			(xy 181.100512 -154.812772) (xy 181.155885 -154.789836) (xy 181.213778 -154.774323) (xy 181.2732 -154.7665)
			(xy 181.333136 -154.7665) (xy 181.392558 -154.774323) (xy 181.450451 -154.789836) (xy 181.505824 -154.812772)
			(xy 181.55773 -154.842739) (xy 181.60528 -154.879226) (xy 181.64766 -154.921606) (xy 181.684147 -154.969156)
			(xy 181.714114 -155.021062) (xy 181.73705 -155.076435) (xy 181.752563 -155.134328) (xy 181.760386 -155.19375)
			(xy 181.760876 -155.223718) (xy 181.760876 -156.085794) (xy 199.81672 -156.085794) (xy 199.81672 -155.222194)
			(xy 199.81721 -155.192226) (xy 199.825033 -155.132804) (xy 199.840546 -155.074911) (xy 199.863482 -155.019538)
			(xy 199.893449 -154.967632) (xy 199.929936 -154.920082) (xy 199.972316 -154.877702) (xy 200.019866 -154.841215)
			(xy 200.071772 -154.811248) (xy 200.127145 -154.788312) (xy 200.185038 -154.772799) (xy 200.24446 -154.764976)
			(xy 200.304396 -154.764976) (xy 200.363818 -154.772799) (xy 200.421711 -154.788312) (xy 200.477084 -154.811248)
			(xy 200.52899 -154.841215) (xy 200.57654 -154.877702) (xy 200.61892 -154.920082) (xy 200.655407 -154.967632)
			(xy 200.685374 -155.019538) (xy 200.70831 -155.074911) (xy 200.723823 -155.132804) (xy 200.731646 -155.192226)
			(xy 200.732136 -155.222194) (xy 200.732136 -156.085794) (xy 200.732111 -156.087318) (xy 296.945304 -156.087318)
			(xy 296.945304 -155.223718) (xy 296.945794 -155.19375) (xy 296.953617 -155.134328) (xy 296.96913 -155.076435)
			(xy 296.992066 -155.021062) (xy 297.022033 -154.969156) (xy 297.05852 -154.921606) (xy 297.1009 -154.879226)
			(xy 297.14845 -154.842739) (xy 297.200356 -154.812772) (xy 297.255729 -154.789836) (xy 297.313622 -154.774323)
			(xy 297.373044 -154.7665) (xy 297.43298 -154.7665) (xy 297.492402 -154.774323) (xy 297.550295 -154.789836)
			(xy 297.605668 -154.812772) (xy 297.657574 -154.842739) (xy 297.705124 -154.879226) (xy 297.747504 -154.921606)
			(xy 297.783991 -154.969156) (xy 297.813958 -155.021062) (xy 297.836894 -155.076435) (xy 297.852407 -155.134328)
			(xy 297.86023 -155.19375) (xy 297.86072 -155.223718) (xy 297.86072 -156.085794) (xy 315.916564 -156.085794)
			(xy 315.916564 -155.222194) (xy 315.917054 -155.192226) (xy 315.924877 -155.132804) (xy 315.94039 -155.074911)
			(xy 315.963326 -155.019538) (xy 315.993293 -154.967632) (xy 316.02978 -154.920082) (xy 316.07216 -154.877702)
			(xy 316.11971 -154.841215) (xy 316.171616 -154.811248) (xy 316.226989 -154.788312) (xy 316.284882 -154.772799)
			(xy 316.344304 -154.764976) (xy 316.40424 -154.764976) (xy 316.463662 -154.772799) (xy 316.521555 -154.788312)
			(xy 316.576928 -154.811248) (xy 316.628834 -154.841215) (xy 316.676384 -154.877702) (xy 316.718764 -154.920082)
			(xy 316.755251 -154.967632) (xy 316.785218 -155.019538) (xy 316.808154 -155.074911) (xy 316.823667 -155.132804)
			(xy 316.83149 -155.192226) (xy 316.83198 -155.222194) (xy 316.83198 -156.085794) (xy 316.831955 -156.087318)
			(xy 413.045148 -156.087318) (xy 413.045148 -155.223718) (xy 413.045638 -155.193734) (xy 413.053466 -155.134278)
			(xy 413.068987 -155.076353) (xy 413.091936 -155.020949) (xy 413.12192 -154.969015) (xy 413.158426 -154.921439)
			(xy 413.200831 -154.879034) (xy 413.248407 -154.842528) (xy 413.300341 -154.812544) (xy 413.355745 -154.789595)
			(xy 413.41367 -154.774074) (xy 413.473126 -154.766246) (xy 413.533094 -154.766246) (xy 413.59255 -154.774074)
			(xy 413.650475 -154.789595) (xy 413.705879 -154.812544) (xy 413.757813 -154.842528) (xy 413.805389 -154.879034)
			(xy 413.847794 -154.921439) (xy 413.8843 -154.969015) (xy 413.914284 -155.020949) (xy 413.937233 -155.076353)
			(xy 413.952754 -155.134278) (xy 413.960582 -155.193734) (xy 413.961072 -155.223718) (xy 413.961072 -156.085794)
			(xy 432.016408 -156.085794) (xy 432.016408 -155.222194) (xy 432.016898 -155.19221) (xy 432.024726 -155.132754)
			(xy 432.040247 -155.074829) (xy 432.063196 -155.019425) (xy 432.09318 -154.967491) (xy 432.129686 -154.919915)
			(xy 432.172091 -154.87751) (xy 432.219667 -154.841004) (xy 432.271601 -154.81102) (xy 432.327005 -154.788071)
			(xy 432.38493 -154.77255) (xy 432.444386 -154.764722) (xy 432.504354 -154.764722) (xy 432.56381 -154.77255)
			(xy 432.621735 -154.788071) (xy 432.677139 -154.81102) (xy 432.729073 -154.841004) (xy 432.776649 -154.87751)
			(xy 432.819054 -154.919915) (xy 432.85556 -154.967491) (xy 432.885544 -155.019425) (xy 432.908493 -155.074829)
			(xy 432.924014 -155.132754) (xy 432.931842 -155.19221) (xy 432.932332 -155.222194) (xy 432.932332 -156.085794)
			(xy 432.931842 -156.115778) (xy 432.924014 -156.175234) (xy 432.908493 -156.233159) (xy 432.885544 -156.288563)
			(xy 432.85556 -156.340497) (xy 432.819054 -156.388073) (xy 432.776649 -156.430478) (xy 432.729073 -156.466984)
			(xy 432.677139 -156.496968) (xy 432.621735 -156.519917) (xy 432.56381 -156.535438) (xy 432.504354 -156.543266)
			(xy 432.444386 -156.543266) (xy 432.38493 -156.535438) (xy 432.327005 -156.519917) (xy 432.271601 -156.496968)
			(xy 432.219667 -156.466984) (xy 432.172091 -156.430478) (xy 432.129686 -156.388073) (xy 432.09318 -156.340497)
			(xy 432.063196 -156.288563) (xy 432.040247 -156.233159) (xy 432.024726 -156.175234) (xy 432.016898 -156.115778)
			(xy 432.016408 -156.085794) (xy 413.961072 -156.085794) (xy 413.961072 -156.087318) (xy 413.960582 -156.117302)
			(xy 413.952754 -156.176758) (xy 413.937233 -156.234683) (xy 413.914284 -156.290087) (xy 413.8843 -156.342021)
			(xy 413.847794 -156.389597) (xy 413.805389 -156.432002) (xy 413.757813 -156.468508) (xy 413.705879 -156.498492)
			(xy 413.650475 -156.521441) (xy 413.59255 -156.536962) (xy 413.533094 -156.54479) (xy 413.473126 -156.54479)
			(xy 413.41367 -156.536962) (xy 413.355745 -156.521441) (xy 413.300341 -156.498492) (xy 413.248407 -156.468508)
			(xy 413.200831 -156.432002) (xy 413.158426 -156.389597) (xy 413.12192 -156.342021) (xy 413.091936 -156.290087)
			(xy 413.068987 -156.234683) (xy 413.053466 -156.176758) (xy 413.045638 -156.117302) (xy 413.045148 -156.087318)
			(xy 316.831955 -156.087318) (xy 316.83149 -156.115762) (xy 316.823667 -156.175184) (xy 316.808154 -156.233077)
			(xy 316.785218 -156.28845) (xy 316.755251 -156.340356) (xy 316.718764 -156.387906) (xy 316.676384 -156.430286)
			(xy 316.628834 -156.466773) (xy 316.576928 -156.49674) (xy 316.521555 -156.519676) (xy 316.463662 -156.535189)
			(xy 316.40424 -156.543012) (xy 316.344304 -156.543012) (xy 316.284882 -156.535189) (xy 316.226989 -156.519676)
			(xy 316.171616 -156.49674) (xy 316.11971 -156.466773) (xy 316.07216 -156.430286) (xy 316.02978 -156.387906)
			(xy 315.993293 -156.340356) (xy 315.963326 -156.28845) (xy 315.94039 -156.233077) (xy 315.924877 -156.175184)
			(xy 315.917054 -156.115762) (xy 315.916564 -156.085794) (xy 297.86072 -156.085794) (xy 297.86072 -156.087318)
			(xy 297.86023 -156.117286) (xy 297.852407 -156.176708) (xy 297.836894 -156.234601) (xy 297.813958 -156.289974)
			(xy 297.783991 -156.34188) (xy 297.747504 -156.38943) (xy 297.705124 -156.43181) (xy 297.657574 -156.468297)
			(xy 297.605668 -156.498264) (xy 297.550295 -156.5212) (xy 297.492402 -156.536713) (xy 297.43298 -156.544536)
			(xy 297.373044 -156.544536) (xy 297.313622 -156.536713) (xy 297.255729 -156.5212) (xy 297.200356 -156.498264)
			(xy 297.14845 -156.468297) (xy 297.1009 -156.43181) (xy 297.05852 -156.38943) (xy 297.022033 -156.34188)
			(xy 296.992066 -156.289974) (xy 296.96913 -156.234601) (xy 296.953617 -156.176708) (xy 296.945794 -156.117286)
			(xy 296.945304 -156.087318) (xy 200.732111 -156.087318) (xy 200.731646 -156.115762) (xy 200.723823 -156.175184)
			(xy 200.70831 -156.233077) (xy 200.685374 -156.28845) (xy 200.655407 -156.340356) (xy 200.61892 -156.387906)
			(xy 200.57654 -156.430286) (xy 200.52899 -156.466773) (xy 200.477084 -156.49674) (xy 200.421711 -156.519676)
			(xy 200.363818 -156.535189) (xy 200.304396 -156.543012) (xy 200.24446 -156.543012) (xy 200.185038 -156.535189)
			(xy 200.127145 -156.519676) (xy 200.071772 -156.49674) (xy 200.019866 -156.466773) (xy 199.972316 -156.430286)
			(xy 199.929936 -156.387906) (xy 199.893449 -156.340356) (xy 199.863482 -156.28845) (xy 199.840546 -156.233077)
			(xy 199.825033 -156.175184) (xy 199.81721 -156.115762) (xy 199.81672 -156.085794) (xy 181.760876 -156.085794)
			(xy 181.760876 -156.087318) (xy 181.760386 -156.117286) (xy 181.752563 -156.176708) (xy 181.73705 -156.234601)
			(xy 181.714114 -156.289974) (xy 181.684147 -156.34188) (xy 181.64766 -156.38943) (xy 181.60528 -156.43181)
			(xy 181.55773 -156.468297) (xy 181.505824 -156.498264) (xy 181.450451 -156.5212) (xy 181.392558 -156.536713)
			(xy 181.333136 -156.544536) (xy 181.2732 -156.544536) (xy 181.213778 -156.536713) (xy 181.155885 -156.5212)
			(xy 181.100512 -156.498264) (xy 181.048606 -156.468297) (xy 181.001056 -156.43181) (xy 180.958676 -156.38943)
			(xy 180.922189 -156.34188) (xy 180.892222 -156.289974) (xy 180.869286 -156.234601) (xy 180.853773 -156.176708)
			(xy 180.84595 -156.117286) (xy 180.84546 -156.087318) (xy 84.632267 -156.087318) (xy 84.631802 -156.115778)
			(xy 84.623974 -156.175234) (xy 84.608453 -156.233159) (xy 84.585504 -156.288563) (xy 84.55552 -156.340497)
			(xy 84.519014 -156.388073) (xy 84.476609 -156.430478) (xy 84.429033 -156.466984) (xy 84.377099 -156.496968)
			(xy 84.321695 -156.519917) (xy 84.26377 -156.535438) (xy 84.204314 -156.543266) (xy 84.144346 -156.543266)
			(xy 84.08489 -156.535438) (xy 84.026965 -156.519917) (xy 83.971561 -156.496968) (xy 83.919627 -156.466984)
			(xy 83.872051 -156.430478) (xy 83.829646 -156.388073) (xy 83.79314 -156.340497) (xy 83.763156 -156.288563)
			(xy 83.740207 -156.233159) (xy 83.724686 -156.175234) (xy 83.716858 -156.115778) (xy 83.716368 -156.085794)
			(xy 65.661032 -156.085794) (xy 65.661032 -156.087318) (xy 65.660542 -156.117302) (xy 65.652714 -156.176758)
			(xy 65.637193 -156.234683) (xy 65.614244 -156.290087) (xy 65.58426 -156.342021) (xy 65.547754 -156.389597)
			(xy 65.505349 -156.432002) (xy 65.457773 -156.468508) (xy 65.405839 -156.498492) (xy 65.350435 -156.521441)
			(xy 65.29251 -156.536962) (xy 65.233054 -156.54479) (xy 65.173086 -156.54479) (xy 65.11363 -156.536962)
			(xy 65.055705 -156.521441) (xy 65.000301 -156.498492) (xy 64.948367 -156.468508) (xy 64.900791 -156.432002)
			(xy 64.858386 -156.389597) (xy 64.82188 -156.342021) (xy 64.791896 -156.290087) (xy 64.768947 -156.234683)
			(xy 64.753426 -156.176758) (xy 64.745598 -156.117302) (xy 64.745108 -156.087318) (xy 4.30911 -156.087318)
			(xy 4.30911 -157.900066) (xy 228.314505 -157.900066) (xy 228.314505 -157.840134) (xy 228.322328 -157.780714)
			(xy 228.33784 -157.722823) (xy 228.360775 -157.667453) (xy 228.390741 -157.61555) (xy 228.427226 -157.568002)
			(xy 228.469605 -157.525624) (xy 228.517153 -157.489139) (xy 228.569056 -157.459173) (xy 228.624427 -157.436238)
			(xy 228.682318 -157.420727) (xy 228.741738 -157.412905) (xy 228.771704 -157.412436) (xy 229.635304 -157.412436)
			(xy 229.665274 -157.412838) (xy 229.724702 -157.420663) (xy 229.7826 -157.436177) (xy 229.837978 -157.459116)
			(xy 229.889888 -157.489086) (xy 229.937442 -157.525576) (xy 229.979827 -157.567961) (xy 230.016316 -157.615515)
			(xy 230.046286 -157.667425) (xy 230.069224 -157.722803) (xy 230.084738 -157.780702) (xy 230.092562 -157.84013)
			(xy 230.092562 -157.90007) (xy 230.089876 -157.920473) (xy 230.557725 -157.920473) (xy 230.557725 -157.860527)
			(xy 230.56555 -157.801095) (xy 230.581066 -157.743192) (xy 230.604007 -157.68781) (xy 230.633981 -157.635897)
			(xy 230.670475 -157.58834) (xy 230.712864 -157.545953) (xy 230.760423 -157.509463) (xy 230.812339 -157.479493)
			(xy 230.867722 -157.456555) (xy 230.925626 -157.441044) (xy 230.985059 -157.433223) (xy 231.015032 -157.432756)
			(xy 231.878632 -157.432756) (xy 231.908596 -157.43332) (xy 231.968011 -157.441146) (xy 232.025896 -157.45666)
			(xy 232.081261 -157.479596) (xy 232.133158 -157.509563) (xy 232.180701 -157.546046) (xy 232.223075 -157.588423)
			(xy 232.259555 -157.635968) (xy 232.289518 -157.687868) (xy 232.31245 -157.743235) (xy 232.32796 -157.801121)
			(xy 232.335782 -157.860536) (xy 232.335782 -157.920464) (xy 232.32796 -157.979879) (xy 232.31245 -158.037765)
			(xy 232.289518 -158.093132) (xy 232.259555 -158.145032) (xy 232.223075 -158.192577) (xy 232.180701 -158.234954)
			(xy 232.133158 -158.271437) (xy 232.081261 -158.301404) (xy 232.025896 -158.32434) (xy 231.968011 -158.339854)
			(xy 231.908596 -158.34768) (xy 231.878632 -158.348172) (xy 231.015032 -158.348172) (xy 230.985059 -158.347777)
			(xy 230.925626 -158.339956) (xy 230.867722 -158.324445) (xy 230.812339 -158.301507) (xy 230.760423 -158.271537)
			(xy 230.712864 -158.235047) (xy 230.670475 -158.19266) (xy 230.633981 -158.145103) (xy 230.604007 -158.09319)
			(xy 230.581066 -158.037808) (xy 230.56555 -157.979905) (xy 230.557725 -157.920473) (xy 230.089876 -157.920473)
			(xy 230.084738 -157.959498) (xy 230.069224 -158.017397) (xy 230.046286 -158.072775) (xy 230.016316 -158.124685)
			(xy 229.979827 -158.172239) (xy 229.937442 -158.214624) (xy 229.889888 -158.251114) (xy 229.837978 -158.281084)
			(xy 229.7826 -158.304023) (xy 229.724702 -158.319537) (xy 229.665274 -158.327362) (xy 229.635304 -158.327852)
			(xy 228.771704 -158.327852) (xy 228.741738 -158.327295) (xy 228.682318 -158.319473) (xy 228.624427 -158.303962)
			(xy 228.569056 -158.281027) (xy 228.517153 -158.251061) (xy 228.469605 -158.214576) (xy 228.427226 -158.172198)
			(xy 228.390741 -158.12465) (xy 228.360775 -158.072747) (xy 228.33784 -158.017377) (xy 228.322328 -157.959486)
			(xy 228.314505 -157.900066) (xy 4.30911 -157.900066) (xy 4.30911 -160.1851) (xy 45.524179 -160.1851)
			(xy 45.528134 -160.093263) (xy 45.539969 -160.002106) (xy 45.559596 -159.912303) (xy 45.58687 -159.824521)
			(xy 45.62159 -159.739407) (xy 45.663498 -159.657594) (xy 45.712284 -159.579686) (xy 45.767587 -159.506261)
			(xy 45.828997 -159.437861) (xy 45.896059 -159.374994) (xy 45.968278 -159.318124) (xy 46.045118 -159.267673)
			(xy 46.126011 -159.224014) (xy 46.210357 -159.187471) (xy 46.297533 -159.158314) (xy 46.386892 -159.13676)
			(xy 46.477773 -159.122966) (xy 46.569504 -159.117036) (xy 46.661405 -159.119014) (xy 46.752796 -159.128885)
			(xy 46.843 -159.146575) (xy 46.931349 -159.171955) (xy 47.017189 -159.204835) (xy 47.099885 -159.244973)
			(xy 47.178825 -159.292072) (xy 47.253423 -159.345782) (xy 47.323129 -159.405706) (xy 47.387424 -159.4714)
			(xy 47.445835 -159.542378) (xy 47.497927 -159.618115) (xy 47.543316 -159.69805) (xy 47.581666 -159.78159)
			(xy 47.612691 -159.868118) (xy 47.636164 -159.956993) (xy 47.65191 -160.047557) (xy 47.659812 -160.139139)
			(xy 47.660306 -160.1851) (xy 69.888875 -160.1851) (xy 69.892831 -160.093241) (xy 69.904668 -160.002062)
			(xy 69.9243 -159.912238) (xy 69.951581 -159.824435) (xy 69.986309 -159.739302) (xy 70.028227 -159.657469)
			(xy 70.077025 -159.579542) (xy 70.13234 -159.506099) (xy 70.193765 -159.437683) (xy 70.260844 -159.374801)
			(xy 70.333079 -159.317918) (xy 70.409938 -159.267455) (xy 70.49085 -159.223786) (xy 70.575216 -159.187234)
			(xy 70.662412 -159.15807) (xy 70.751793 -159.13651) (xy 70.842696 -159.122714) (xy 70.934449 -159.116782)
			(xy 71.026371 -159.118761) (xy 71.117784 -159.128634) (xy 71.208009 -159.146329) (xy 71.29638 -159.171714)
			(xy 71.38224 -159.204602) (xy 71.464956 -159.24475) (xy 71.543914 -159.291859) (xy 71.618531 -159.345582)
			(xy 71.688252 -159.40552) (xy 71.752563 -159.47123) (xy 71.810988 -159.542226) (xy 71.863093 -159.61798)
			(xy 71.908492 -159.697934) (xy 71.946851 -159.781494) (xy 71.977884 -159.868043) (xy 72.001362 -159.956939)
			(xy 72.017112 -160.047524) (xy 72.025016 -160.139128) (xy 72.02551 -160.1851) (xy 161.624277 -160.1851)
			(xy 161.628232 -160.093263) (xy 161.640067 -160.002106) (xy 161.659694 -159.912303) (xy 161.686968 -159.824521)
			(xy 161.721688 -159.739407) (xy 161.763596 -159.657594) (xy 161.812382 -159.579686) (xy 161.867685 -159.506261)
			(xy 161.929095 -159.437861) (xy 161.996157 -159.374994) (xy 162.068376 -159.318124) (xy 162.145216 -159.267673)
			(xy 162.226109 -159.224014) (xy 162.310455 -159.187471) (xy 162.397631 -159.158314) (xy 162.48699 -159.13676)
			(xy 162.577871 -159.122966) (xy 162.669602 -159.117036) (xy 162.761503 -159.119014) (xy 162.852894 -159.128885)
			(xy 162.943098 -159.146575) (xy 163.031447 -159.171955) (xy 163.117287 -159.204835) (xy 163.199983 -159.244973)
			(xy 163.278923 -159.292072) (xy 163.353521 -159.345782) (xy 163.423227 -159.405706) (xy 163.487522 -159.4714)
			(xy 163.545933 -159.542378) (xy 163.598025 -159.618115) (xy 163.643414 -159.69805) (xy 163.681764 -159.78159)
			(xy 163.712789 -159.868118) (xy 163.736262 -159.956993) (xy 163.752008 -160.047557) (xy 163.75991 -160.139139)
			(xy 163.760404 -160.1851) (xy 185.988973 -160.1851) (xy 185.992929 -160.093241) (xy 186.004766 -160.002062)
			(xy 186.024398 -159.912238) (xy 186.051679 -159.824435) (xy 186.086407 -159.739302) (xy 186.128325 -159.657469)
			(xy 186.177123 -159.579542) (xy 186.232438 -159.506099) (xy 186.293863 -159.437683) (xy 186.360942 -159.374801)
			(xy 186.433177 -159.317918) (xy 186.510036 -159.267455) (xy 186.590948 -159.223786) (xy 186.675314 -159.187234)
			(xy 186.76251 -159.15807) (xy 186.851891 -159.13651) (xy 186.942794 -159.122714) (xy 187.034547 -159.116782)
			(xy 187.126469 -159.118761) (xy 187.217882 -159.128634) (xy 187.308107 -159.146329) (xy 187.396478 -159.171714)
			(xy 187.482338 -159.204602) (xy 187.565054 -159.24475) (xy 187.644012 -159.291859) (xy 187.718629 -159.345582)
			(xy 187.78835 -159.40552) (xy 187.852661 -159.47123) (xy 187.911086 -159.542226) (xy 187.963191 -159.61798)
			(xy 188.00859 -159.697934) (xy 188.046949 -159.781494) (xy 188.077982 -159.868043) (xy 188.10146 -159.956939)
			(xy 188.11721 -160.047524) (xy 188.125114 -160.139128) (xy 188.125608 -160.1851) (xy 277.724121 -160.1851)
			(xy 277.728076 -160.093263) (xy 277.739911 -160.002106) (xy 277.759538 -159.912303) (xy 277.786812 -159.824521)
			(xy 277.821532 -159.739407) (xy 277.86344 -159.657594) (xy 277.912226 -159.579686) (xy 277.967529 -159.506261)
			(xy 278.028939 -159.437861) (xy 278.096001 -159.374994) (xy 278.16822 -159.318124) (xy 278.24506 -159.267673)
			(xy 278.325953 -159.224014) (xy 278.410299 -159.187471) (xy 278.497475 -159.158314) (xy 278.586834 -159.13676)
			(xy 278.677715 -159.122966) (xy 278.769446 -159.117036) (xy 278.861347 -159.119014) (xy 278.952738 -159.128885)
			(xy 279.042942 -159.146575) (xy 279.131291 -159.171955) (xy 279.217131 -159.204835) (xy 279.299827 -159.244973)
			(xy 279.378767 -159.292072) (xy 279.453365 -159.345782) (xy 279.523071 -159.405706) (xy 279.587366 -159.4714)
			(xy 279.645777 -159.542378) (xy 279.697869 -159.618115) (xy 279.743258 -159.69805) (xy 279.781608 -159.78159)
			(xy 279.812633 -159.868118) (xy 279.836106 -159.956993) (xy 279.851852 -160.047557) (xy 279.859754 -160.139139)
			(xy 279.860248 -160.1851) (xy 302.088817 -160.1851) (xy 302.092773 -160.093241) (xy 302.10461 -160.002062)
			(xy 302.124242 -159.912238) (xy 302.151523 -159.824435) (xy 302.186251 -159.739302) (xy 302.228169 -159.657469)
			(xy 302.276967 -159.579542) (xy 302.332282 -159.506099) (xy 302.393707 -159.437683) (xy 302.460786 -159.374801)
			(xy 302.533021 -159.317918) (xy 302.60988 -159.267455) (xy 302.690792 -159.223786) (xy 302.775158 -159.187234)
			(xy 302.862354 -159.15807) (xy 302.951735 -159.13651) (xy 303.042638 -159.122714) (xy 303.134391 -159.116782)
			(xy 303.226313 -159.118761) (xy 303.317726 -159.128634) (xy 303.407951 -159.146329) (xy 303.496322 -159.171714)
			(xy 303.582182 -159.204602) (xy 303.664898 -159.24475) (xy 303.743856 -159.291859) (xy 303.818473 -159.345582)
			(xy 303.888194 -159.40552) (xy 303.952505 -159.47123) (xy 304.01093 -159.542226) (xy 304.063035 -159.61798)
			(xy 304.108434 -159.697934) (xy 304.146793 -159.781494) (xy 304.177826 -159.868043) (xy 304.201304 -159.956939)
			(xy 304.217054 -160.047524) (xy 304.224958 -160.139128) (xy 304.225452 -160.1851) (xy 393.824219 -160.1851)
			(xy 393.828174 -160.093263) (xy 393.840009 -160.002106) (xy 393.859636 -159.912303) (xy 393.88691 -159.824521)
			(xy 393.92163 -159.739407) (xy 393.963538 -159.657594) (xy 394.012324 -159.579686) (xy 394.067627 -159.506261)
			(xy 394.129037 -159.437861) (xy 394.196099 -159.374994) (xy 394.268318 -159.318124) (xy 394.345158 -159.267673)
			(xy 394.426051 -159.224014) (xy 394.510397 -159.187471) (xy 394.597573 -159.158314) (xy 394.686932 -159.13676)
			(xy 394.777813 -159.122966) (xy 394.869544 -159.117036) (xy 394.961445 -159.119014) (xy 395.052836 -159.128885)
			(xy 395.14304 -159.146575) (xy 395.231389 -159.171955) (xy 395.317229 -159.204835) (xy 395.399925 -159.244973)
			(xy 395.478865 -159.292072) (xy 395.553463 -159.345782) (xy 395.623169 -159.405706) (xy 395.687464 -159.4714)
			(xy 395.745875 -159.542378) (xy 395.797967 -159.618115) (xy 395.843356 -159.69805) (xy 395.881706 -159.78159)
			(xy 395.912731 -159.868118) (xy 395.936204 -159.956993) (xy 395.95195 -160.047557) (xy 395.959852 -160.139139)
			(xy 395.960346 -160.1851) (xy 418.188915 -160.1851) (xy 418.192871 -160.093241) (xy 418.204708 -160.002062)
			(xy 418.22434 -159.912238) (xy 418.251621 -159.824435) (xy 418.286349 -159.739302) (xy 418.328267 -159.657469)
			(xy 418.377065 -159.579542) (xy 418.43238 -159.506099) (xy 418.493805 -159.437683) (xy 418.560884 -159.374801)
			(xy 418.633119 -159.317918) (xy 418.709978 -159.267455) (xy 418.79089 -159.223786) (xy 418.875256 -159.187234)
			(xy 418.962452 -159.15807) (xy 419.051833 -159.13651) (xy 419.142736 -159.122714) (xy 419.234489 -159.116782)
			(xy 419.326411 -159.118761) (xy 419.417824 -159.128634) (xy 419.508049 -159.146329) (xy 419.59642 -159.171714)
			(xy 419.68228 -159.204602) (xy 419.764996 -159.24475) (xy 419.843954 -159.291859) (xy 419.918571 -159.345582)
			(xy 419.988292 -159.40552) (xy 420.052603 -159.47123) (xy 420.111028 -159.542226) (xy 420.163133 -159.61798)
			(xy 420.208532 -159.697934) (xy 420.246891 -159.781494) (xy 420.277924 -159.868043) (xy 420.301402 -159.956939)
			(xy 420.317152 -160.047524) (xy 420.325056 -160.139128) (xy 420.32555 -160.1851) (xy 420.325056 -160.231072)
			(xy 420.317152 -160.322676) (xy 420.301402 -160.413261) (xy 420.277924 -160.502157) (xy 420.246891 -160.588706)
			(xy 420.208532 -160.672266) (xy 420.163133 -160.75222) (xy 420.111028 -160.827974) (xy 420.052603 -160.89897)
			(xy 419.988292 -160.96468) (xy 419.918571 -161.024618) (xy 419.843954 -161.078341) (xy 419.764996 -161.12545)
			(xy 419.68228 -161.165598) (xy 419.59642 -161.198486) (xy 419.508049 -161.223871) (xy 419.417824 -161.241566)
			(xy 419.326411 -161.251439) (xy 419.234489 -161.253418) (xy 419.142736 -161.247486) (xy 419.051833 -161.23369)
			(xy 418.962452 -161.21213) (xy 418.875256 -161.182966) (xy 418.79089 -161.146414) (xy 418.709978 -161.102745)
			(xy 418.633119 -161.052282) (xy 418.560884 -160.995399) (xy 418.493805 -160.932517) (xy 418.43238 -160.864101)
			(xy 418.377065 -160.790658) (xy 418.328267 -160.712731) (xy 418.286349 -160.630898) (xy 418.251621 -160.545765)
			(xy 418.22434 -160.457962) (xy 418.204708 -160.368138) (xy 418.192871 -160.276959) (xy 418.188915 -160.1851)
			(xy 395.960346 -160.1851) (xy 395.959852 -160.231061) (xy 395.95195 -160.322643) (xy 395.936204 -160.413207)
			(xy 395.912731 -160.502082) (xy 395.881706 -160.58861) (xy 395.843356 -160.67215) (xy 395.797967 -160.752085)
			(xy 395.745875 -160.827822) (xy 395.687464 -160.8988) (xy 395.623169 -160.964494) (xy 395.553463 -161.024418)
			(xy 395.478865 -161.078128) (xy 395.399925 -161.125227) (xy 395.317229 -161.165365) (xy 395.231389 -161.198245)
			(xy 395.14304 -161.223625) (xy 395.052836 -161.241315) (xy 394.961445 -161.251186) (xy 394.869544 -161.253164)
			(xy 394.777813 -161.247234) (xy 394.686932 -161.23344) (xy 394.597573 -161.211886) (xy 394.510397 -161.182729)
			(xy 394.426051 -161.146186) (xy 394.345158 -161.102527) (xy 394.268318 -161.052076) (xy 394.196099 -160.995206)
			(xy 394.129037 -160.932339) (xy 394.067627 -160.863939) (xy 394.012324 -160.790514) (xy 393.963538 -160.712606)
			(xy 393.92163 -160.630793) (xy 393.88691 -160.545679) (xy 393.859636 -160.457897) (xy 393.840009 -160.368094)
			(xy 393.828174 -160.276937) (xy 393.824219 -160.1851) (xy 304.225452 -160.1851) (xy 304.224958 -160.231072)
			(xy 304.217054 -160.322676) (xy 304.201304 -160.413261) (xy 304.177826 -160.502157) (xy 304.146793 -160.588706)
			(xy 304.108434 -160.672266) (xy 304.063035 -160.75222) (xy 304.01093 -160.827974) (xy 303.952505 -160.89897)
			(xy 303.888194 -160.96468) (xy 303.818473 -161.024618) (xy 303.743856 -161.078341) (xy 303.664898 -161.12545)
			(xy 303.582182 -161.165598) (xy 303.496322 -161.198486) (xy 303.407951 -161.223871) (xy 303.317726 -161.241566)
			(xy 303.226313 -161.251439) (xy 303.134391 -161.253418) (xy 303.042638 -161.247486) (xy 302.951735 -161.23369)
			(xy 302.862354 -161.21213) (xy 302.775158 -161.182966) (xy 302.690792 -161.146414) (xy 302.60988 -161.102745)
			(xy 302.533021 -161.052282) (xy 302.460786 -160.995399) (xy 302.393707 -160.932517) (xy 302.332282 -160.864101)
			(xy 302.276967 -160.790658) (xy 302.228169 -160.712731) (xy 302.186251 -160.630898) (xy 302.151523 -160.545765)
			(xy 302.124242 -160.457962) (xy 302.10461 -160.368138) (xy 302.092773 -160.276959) (xy 302.088817 -160.1851)
			(xy 279.860248 -160.1851) (xy 279.859754 -160.231061) (xy 279.851852 -160.322643) (xy 279.836106 -160.413207)
			(xy 279.812633 -160.502082) (xy 279.781608 -160.58861) (xy 279.743258 -160.67215) (xy 279.697869 -160.752085)
			(xy 279.645777 -160.827822) (xy 279.587366 -160.8988) (xy 279.523071 -160.964494) (xy 279.453365 -161.024418)
			(xy 279.378767 -161.078128) (xy 279.299827 -161.125227) (xy 279.217131 -161.165365) (xy 279.131291 -161.198245)
			(xy 279.042942 -161.223625) (xy 278.952738 -161.241315) (xy 278.861347 -161.251186) (xy 278.769446 -161.253164)
			(xy 278.677715 -161.247234) (xy 278.586834 -161.23344) (xy 278.497475 -161.211886) (xy 278.410299 -161.182729)
			(xy 278.325953 -161.146186) (xy 278.24506 -161.102527) (xy 278.16822 -161.052076) (xy 278.096001 -160.995206)
			(xy 278.028939 -160.932339) (xy 277.967529 -160.863939) (xy 277.912226 -160.790514) (xy 277.86344 -160.712606)
			(xy 277.821532 -160.630793) (xy 277.786812 -160.545679) (xy 277.759538 -160.457897) (xy 277.739911 -160.368094)
			(xy 277.728076 -160.276937) (xy 277.724121 -160.1851) (xy 188.125608 -160.1851) (xy 188.125114 -160.231072)
			(xy 188.11721 -160.322676) (xy 188.10146 -160.413261) (xy 188.077982 -160.502157) (xy 188.046949 -160.588706)
			(xy 188.00859 -160.672266) (xy 187.963191 -160.75222) (xy 187.911086 -160.827974) (xy 187.852661 -160.89897)
			(xy 187.78835 -160.96468) (xy 187.718629 -161.024618) (xy 187.644012 -161.078341) (xy 187.565054 -161.12545)
			(xy 187.482338 -161.165598) (xy 187.396478 -161.198486) (xy 187.308107 -161.223871) (xy 187.217882 -161.241566)
			(xy 187.126469 -161.251439) (xy 187.034547 -161.253418) (xy 186.942794 -161.247486) (xy 186.851891 -161.23369)
			(xy 186.76251 -161.21213) (xy 186.675314 -161.182966) (xy 186.590948 -161.146414) (xy 186.510036 -161.102745)
			(xy 186.433177 -161.052282) (xy 186.360942 -160.995399) (xy 186.293863 -160.932517) (xy 186.232438 -160.864101)
			(xy 186.177123 -160.790658) (xy 186.128325 -160.712731) (xy 186.086407 -160.630898) (xy 186.051679 -160.545765)
			(xy 186.024398 -160.457962) (xy 186.004766 -160.368138) (xy 185.992929 -160.276959) (xy 185.988973 -160.1851)
			(xy 163.760404 -160.1851) (xy 163.75991 -160.231061) (xy 163.752008 -160.322643) (xy 163.736262 -160.413207)
			(xy 163.712789 -160.502082) (xy 163.681764 -160.58861) (xy 163.643414 -160.67215) (xy 163.598025 -160.752085)
			(xy 163.545933 -160.827822) (xy 163.487522 -160.8988) (xy 163.423227 -160.964494) (xy 163.353521 -161.024418)
			(xy 163.278923 -161.078128) (xy 163.199983 -161.125227) (xy 163.117287 -161.165365) (xy 163.031447 -161.198245)
			(xy 162.943098 -161.223625) (xy 162.852894 -161.241315) (xy 162.761503 -161.251186) (xy 162.669602 -161.253164)
			(xy 162.577871 -161.247234) (xy 162.48699 -161.23344) (xy 162.397631 -161.211886) (xy 162.310455 -161.182729)
			(xy 162.226109 -161.146186) (xy 162.145216 -161.102527) (xy 162.068376 -161.052076) (xy 161.996157 -160.995206)
			(xy 161.929095 -160.932339) (xy 161.867685 -160.863939) (xy 161.812382 -160.790514) (xy 161.763596 -160.712606)
			(xy 161.721688 -160.630793) (xy 161.686968 -160.545679) (xy 161.659694 -160.457897) (xy 161.640067 -160.368094)
			(xy 161.628232 -160.276937) (xy 161.624277 -160.1851) (xy 72.02551 -160.1851) (xy 72.025016 -160.231072)
			(xy 72.017112 -160.322676) (xy 72.001362 -160.413261) (xy 71.977884 -160.502157) (xy 71.946851 -160.588706)
			(xy 71.908492 -160.672266) (xy 71.863093 -160.75222) (xy 71.810988 -160.827974) (xy 71.752563 -160.89897)
			(xy 71.688252 -160.96468) (xy 71.618531 -161.024618) (xy 71.543914 -161.078341) (xy 71.464956 -161.12545)
			(xy 71.38224 -161.165598) (xy 71.29638 -161.198486) (xy 71.208009 -161.223871) (xy 71.117784 -161.241566)
			(xy 71.026371 -161.251439) (xy 70.934449 -161.253418) (xy 70.842696 -161.247486) (xy 70.751793 -161.23369)
			(xy 70.662412 -161.21213) (xy 70.575216 -161.182966) (xy 70.49085 -161.146414) (xy 70.409938 -161.102745)
			(xy 70.333079 -161.052282) (xy 70.260844 -160.995399) (xy 70.193765 -160.932517) (xy 70.13234 -160.864101)
			(xy 70.077025 -160.790658) (xy 70.028227 -160.712731) (xy 69.986309 -160.630898) (xy 69.951581 -160.545765)
			(xy 69.9243 -160.457962) (xy 69.904668 -160.368138) (xy 69.892831 -160.276959) (xy 69.888875 -160.1851)
			(xy 47.660306 -160.1851) (xy 47.659812 -160.231061) (xy 47.65191 -160.322643) (xy 47.636164 -160.413207)
			(xy 47.612691 -160.502082) (xy 47.581666 -160.58861) (xy 47.543316 -160.67215) (xy 47.497927 -160.752085)
			(xy 47.445835 -160.827822) (xy 47.387424 -160.8988) (xy 47.323129 -160.964494) (xy 47.253423 -161.024418)
			(xy 47.178825 -161.078128) (xy 47.099885 -161.125227) (xy 47.017189 -161.165365) (xy 46.931349 -161.198245)
			(xy 46.843 -161.223625) (xy 46.752796 -161.241315) (xy 46.661405 -161.251186) (xy 46.569504 -161.253164)
			(xy 46.477773 -161.247234) (xy 46.386892 -161.23344) (xy 46.297533 -161.211886) (xy 46.210357 -161.182729)
			(xy 46.126011 -161.146186) (xy 46.045118 -161.102527) (xy 45.968278 -161.052076) (xy 45.896059 -160.995206)
			(xy 45.828997 -160.932339) (xy 45.767587 -160.863939) (xy 45.712284 -160.790514) (xy 45.663498 -160.712606)
			(xy 45.62159 -160.630793) (xy 45.58687 -160.545679) (xy 45.559596 -160.457897) (xy 45.539969 -160.368094)
			(xy 45.528134 -160.276937) (xy 45.524179 -160.1851) (xy 4.30911 -160.1851) (xy 4.30911 -168.065164)
			(xy 135.245906 -168.065164) (xy 135.245906 -168.005236) (xy 135.253728 -167.94582) (xy 135.269237 -167.887933)
			(xy 135.29217 -167.832566) (xy 135.322132 -167.780665) (xy 135.358612 -167.733119) (xy 135.400986 -167.690742)
			(xy 135.448529 -167.654257) (xy 135.500426 -167.624289) (xy 135.555791 -167.601351) (xy 135.613677 -167.585836)
			(xy 135.673092 -167.578009) (xy 135.703056 -167.577516) (xy 136.566656 -167.577516) (xy 136.596628 -167.577934)
			(xy 136.656061 -167.585754) (xy 136.713965 -167.601264) (xy 136.769348 -167.6242) (xy 136.821264 -167.654169)
			(xy 136.868823 -167.690658) (xy 136.911213 -167.733044) (xy 136.947707 -167.7806) (xy 136.977681 -167.832512)
			(xy 137.000622 -167.887894) (xy 137.016138 -167.945796) (xy 137.023963 -168.005228) (xy 137.023963 -168.065172)
			(xy 137.016138 -168.124604) (xy 137.000622 -168.182506) (xy 136.977681 -168.237888) (xy 136.947707 -168.2898)
			(xy 136.911213 -168.337356) (xy 136.868823 -168.379742) (xy 136.821264 -168.416231) (xy 136.769348 -168.4462)
			(xy 136.713965 -168.469136) (xy 136.656061 -168.484646) (xy 136.596628 -168.492466) (xy 136.566656 -168.492932)
			(xy 135.703056 -168.492932) (xy 135.673092 -168.492391) (xy 135.613677 -168.484564) (xy 135.555791 -168.469049)
			(xy 135.500426 -168.446111) (xy 135.448529 -168.416143) (xy 135.400986 -168.379658) (xy 135.358612 -168.337281)
			(xy 135.322132 -168.289735) (xy 135.29217 -168.237834) (xy 135.269237 -168.182467) (xy 135.253728 -168.12458)
			(xy 135.245906 -168.065164) (xy 4.30911 -168.065164) (xy 4.30911 -168.700164) (xy 133.213906 -168.700164)
			(xy 133.213906 -168.640236) (xy 133.221728 -168.58082) (xy 133.237237 -168.522933) (xy 133.26017 -168.467566)
			(xy 133.290132 -168.415665) (xy 133.326612 -168.368119) (xy 133.368986 -168.325742) (xy 133.416529 -168.289257)
			(xy 133.468426 -168.259289) (xy 133.523791 -168.236351) (xy 133.581677 -168.220836) (xy 133.641092 -168.213009)
			(xy 133.671056 -168.212516) (xy 134.534656 -168.212516) (xy 134.564628 -168.212934) (xy 134.624061 -168.220754)
			(xy 134.681965 -168.236264) (xy 134.737348 -168.2592) (xy 134.789264 -168.289169) (xy 134.836823 -168.325658)
			(xy 134.879213 -168.368044) (xy 134.915707 -168.4156) (xy 134.945681 -168.467512) (xy 134.968622 -168.522894)
			(xy 134.984138 -168.580796) (xy 134.991963 -168.640228) (xy 134.991963 -168.700172) (xy 134.984138 -168.759604)
			(xy 134.968622 -168.817506) (xy 134.945681 -168.872888) (xy 134.915707 -168.9248) (xy 134.879213 -168.972356)
			(xy 134.836823 -169.014742) (xy 134.789264 -169.051231) (xy 134.737348 -169.0812) (xy 134.681965 -169.104136)
			(xy 134.624061 -169.119646) (xy 134.564628 -169.127466) (xy 134.534656 -169.127932) (xy 133.671056 -169.127932)
			(xy 133.641092 -169.127391) (xy 133.581677 -169.119564) (xy 133.523791 -169.104049) (xy 133.468426 -169.081111)
			(xy 133.416529 -169.051143) (xy 133.368986 -169.014658) (xy 133.326612 -168.972281) (xy 133.290132 -168.924735)
			(xy 133.26017 -168.872834) (xy 133.237237 -168.817467) (xy 133.221728 -168.75958) (xy 133.213906 -168.700164)
			(xy 4.30911 -168.700164) (xy 4.30911 -169.61389) (xy 245.108869 -169.61389) (xy 245.108869 -169.55391)
			(xy 245.116699 -169.494444) (xy 245.132223 -169.436508) (xy 245.155178 -169.381095) (xy 245.185169 -169.329152)
			(xy 245.221684 -169.281569) (xy 245.264097 -169.239158) (xy 245.311684 -169.202648) (xy 245.363629 -169.172661)
			(xy 245.419045 -169.149711) (xy 245.476981 -169.134191) (xy 245.536448 -169.126367) (xy 245.566438 -169.1259)
			(xy 246.430038 -169.1259) (xy 246.460018 -169.126468) (xy 246.519465 -169.134299) (xy 246.577381 -169.149822)
			(xy 246.632776 -169.172772) (xy 246.684702 -169.202755) (xy 246.73227 -169.239259) (xy 246.774667 -169.281659)
			(xy 246.811166 -169.32923) (xy 246.841145 -169.381158) (xy 246.86409 -169.436555) (xy 246.879608 -169.494472)
			(xy 246.887434 -169.55392) (xy 246.887434 -169.61388) (xy 246.879608 -169.673328) (xy 246.86409 -169.731245)
			(xy 246.841145 -169.786642) (xy 246.811166 -169.83857) (xy 246.774667 -169.886141) (xy 246.73227 -169.928541)
			(xy 246.684702 -169.965045) (xy 246.632776 -169.995028) (xy 246.577381 -170.017978) (xy 246.519465 -170.033501)
			(xy 246.460018 -170.041332) (xy 246.430038 -170.041824) (xy 245.566438 -170.041824) (xy 245.536448 -170.041433)
			(xy 245.476981 -170.033609) (xy 245.419045 -170.018089) (xy 245.363629 -169.995139) (xy 245.311684 -169.965152)
			(xy 245.264097 -169.928642) (xy 245.221684 -169.886231) (xy 245.185169 -169.838648) (xy 245.155178 -169.786705)
			(xy 245.132223 -169.731292) (xy 245.116699 -169.673356) (xy 245.108869 -169.61389) (xy 4.30911 -169.61389)
			(xy 4.30911 -174.805086) (xy 141.546072 -174.805086) (xy 141.546072 -173.941486) (xy 141.546562 -173.911518)
			(xy 141.554385 -173.852096) (xy 141.569898 -173.794203) (xy 141.592834 -173.73883) (xy 141.622801 -173.686924)
			(xy 141.659288 -173.639374) (xy 141.701668 -173.596994) (xy 141.749218 -173.560507) (xy 141.801124 -173.53054)
			(xy 141.856497 -173.507604) (xy 141.91439 -173.492091) (xy 141.973812 -173.484268) (xy 142.033748 -173.484268)
			(xy 142.09317 -173.492091) (xy 142.106698 -173.495716) (xy 257.519424 -173.495716) (xy 257.519424 -172.632116)
			(xy 257.519914 -172.602132) (xy 257.527742 -172.542676) (xy 257.543263 -172.484751) (xy 257.566212 -172.429347)
			(xy 257.596196 -172.377413) (xy 257.632702 -172.329837) (xy 257.675107 -172.287432) (xy 257.722683 -172.250926)
			(xy 257.774617 -172.220942) (xy 257.830021 -172.197993) (xy 257.887946 -172.182472) (xy 257.947402 -172.174644)
			(xy 258.00737 -172.174644) (xy 258.066826 -172.182472) (xy 258.124751 -172.197993) (xy 258.180155 -172.220942)
			(xy 258.232089 -172.250926) (xy 258.279665 -172.287432) (xy 258.32207 -172.329837) (xy 258.358576 -172.377413)
			(xy 258.38856 -172.429347) (xy 258.411509 -172.484751) (xy 258.42703 -172.542676) (xy 258.434858 -172.602132)
			(xy 258.435348 -172.632116) (xy 258.435348 -173.495716) (xy 258.434858 -173.5257) (xy 258.42703 -173.585156)
			(xy 258.411509 -173.643081) (xy 258.38856 -173.698485) (xy 258.358576 -173.750419) (xy 258.32207 -173.797995)
			(xy 258.279665 -173.8404) (xy 258.232089 -173.876906) (xy 258.180155 -173.90689) (xy 258.124751 -173.929839)
			(xy 258.066826 -173.94536) (xy 258.00737 -173.953188) (xy 257.947402 -173.953188) (xy 257.887946 -173.94536)
			(xy 257.830021 -173.929839) (xy 257.774617 -173.90689) (xy 257.722683 -173.876906) (xy 257.675107 -173.8404)
			(xy 257.632702 -173.797995) (xy 257.596196 -173.750419) (xy 257.566212 -173.698485) (xy 257.543263 -173.643081)
			(xy 257.527742 -173.585156) (xy 257.519914 -173.5257) (xy 257.519424 -173.495716) (xy 142.106698 -173.495716)
			(xy 142.151063 -173.507604) (xy 142.206436 -173.53054) (xy 142.258342 -173.560507) (xy 142.305892 -173.596994)
			(xy 142.348272 -173.639374) (xy 142.384759 -173.686924) (xy 142.414726 -173.73883) (xy 142.437662 -173.794203)
			(xy 142.453175 -173.852096) (xy 142.460998 -173.911518) (xy 142.461488 -173.941486) (xy 142.461488 -174.805086)
			(xy 142.460998 -174.835054) (xy 142.453175 -174.894476) (xy 142.437662 -174.952369) (xy 142.414726 -175.007742)
			(xy 142.384759 -175.059648) (xy 142.348272 -175.107198) (xy 142.305892 -175.149578) (xy 142.258342 -175.186065)
			(xy 142.206436 -175.216032) (xy 142.151063 -175.238968) (xy 142.09317 -175.254481) (xy 142.033748 -175.262304)
			(xy 141.973812 -175.262304) (xy 141.91439 -175.254481) (xy 141.856497 -175.238968) (xy 141.801124 -175.216032)
			(xy 141.749218 -175.186065) (xy 141.701668 -175.149578) (xy 141.659288 -175.107198) (xy 141.622801 -175.059648)
			(xy 141.592834 -175.007742) (xy 141.569898 -174.952369) (xy 141.554385 -174.894476) (xy 141.546562 -174.835054)
			(xy 141.546072 -174.805086) (xy 4.30911 -174.805086) (xy 4.30911 -176.837086) (xy 142.181072 -176.837086)
			(xy 142.181072 -175.973486) (xy 142.181562 -175.943518) (xy 142.189385 -175.884096) (xy 142.204898 -175.826203)
			(xy 142.227834 -175.77083) (xy 142.257801 -175.718924) (xy 142.294288 -175.671374) (xy 142.336668 -175.628994)
			(xy 142.384218 -175.592507) (xy 142.436124 -175.56254) (xy 142.491497 -175.539604) (xy 142.54939 -175.524091)
			(xy 142.608812 -175.516268) (xy 142.668748 -175.516268) (xy 142.72817 -175.524091) (xy 142.786063 -175.539604)
			(xy 142.841436 -175.56254) (xy 142.893342 -175.592507) (xy 142.940892 -175.628994) (xy 142.983272 -175.671374)
			(xy 143.019759 -175.718924) (xy 143.049726 -175.77083) (xy 143.072662 -175.826203) (xy 143.088175 -175.884096)
			(xy 143.095998 -175.943518) (xy 143.096488 -175.973486) (xy 143.096488 -176.837086) (xy 143.095998 -176.867054)
			(xy 143.088175 -176.926476) (xy 143.072662 -176.984369) (xy 143.049726 -177.039742) (xy 143.019759 -177.091648)
			(xy 142.983272 -177.139198) (xy 142.940892 -177.181578) (xy 142.893342 -177.218065) (xy 142.841436 -177.248032)
			(xy 142.786063 -177.270968) (xy 142.72817 -177.286481) (xy 142.668748 -177.294304) (xy 142.608812 -177.294304)
			(xy 142.54939 -177.286481) (xy 142.491497 -177.270968) (xy 142.436124 -177.248032) (xy 142.384218 -177.218065)
			(xy 142.336668 -177.181578) (xy 142.294288 -177.139198) (xy 142.257801 -177.091648) (xy 142.227834 -177.039742)
			(xy 142.204898 -176.984369) (xy 142.189385 -176.926476) (xy 142.181562 -176.867054) (xy 142.181072 -176.837086)
			(xy 4.30911 -176.837086) (xy 4.30911 -178.995324) (xy 123.198636 -178.995324) (xy 123.198636 -178.131724)
			(xy 123.199126 -178.10174) (xy 123.206954 -178.042284) (xy 123.222475 -177.984359) (xy 123.245424 -177.928955)
			(xy 123.275408 -177.877021) (xy 123.311914 -177.829445) (xy 123.354319 -177.78704) (xy 123.401895 -177.750534)
			(xy 123.453829 -177.72055) (xy 123.509233 -177.697601) (xy 123.567158 -177.68208) (xy 123.626614 -177.674252)
			(xy 123.686582 -177.674252) (xy 123.746038 -177.68208) (xy 123.803963 -177.697601) (xy 123.859367 -177.72055)
			(xy 123.911301 -177.750534) (xy 123.958877 -177.78704) (xy 124.001282 -177.829445) (xy 124.037788 -177.877021)
			(xy 124.067772 -177.928955) (xy 124.090721 -177.984359) (xy 124.106242 -178.042284) (xy 124.11407 -178.10174)
			(xy 124.11456 -178.131724) (xy 124.11456 -178.869086) (xy 141.546072 -178.869086) (xy 141.546072 -178.005486)
			(xy 141.546562 -177.975518) (xy 141.554385 -177.916096) (xy 141.569898 -177.858203) (xy 141.592834 -177.80283)
			(xy 141.622801 -177.750924) (xy 141.659288 -177.703374) (xy 141.701668 -177.660994) (xy 141.749218 -177.624507)
			(xy 141.801124 -177.59454) (xy 141.856497 -177.571604) (xy 141.91439 -177.556091) (xy 141.973812 -177.548268)
			(xy 142.033748 -177.548268) (xy 142.09317 -177.556091) (xy 142.151063 -177.571604) (xy 142.206436 -177.59454)
			(xy 142.258342 -177.624507) (xy 142.305892 -177.660994) (xy 142.348272 -177.703374) (xy 142.384759 -177.750924)
			(xy 142.414726 -177.80283) (xy 142.437662 -177.858203) (xy 142.453175 -177.916096) (xy 142.460998 -177.975518)
			(xy 142.461488 -178.005486) (xy 142.461488 -178.869086) (xy 142.460998 -178.899054) (xy 142.453175 -178.958476)
			(xy 142.437662 -179.016369) (xy 142.414726 -179.071742) (xy 142.384759 -179.123648) (xy 142.348272 -179.171198)
			(xy 142.305892 -179.213578) (xy 142.258342 -179.250065) (xy 142.206436 -179.280032) (xy 142.151063 -179.302968)
			(xy 142.09317 -179.318481) (xy 142.033748 -179.326304) (xy 141.973812 -179.326304) (xy 141.91439 -179.318481)
			(xy 141.856497 -179.302968) (xy 141.801124 -179.280032) (xy 141.749218 -179.250065) (xy 141.701668 -179.213578)
			(xy 141.659288 -179.171198) (xy 141.622801 -179.123648) (xy 141.592834 -179.071742) (xy 141.569898 -179.016369)
			(xy 141.554385 -178.958476) (xy 141.546562 -178.899054) (xy 141.546072 -178.869086) (xy 124.11456 -178.869086)
			(xy 124.11456 -178.995324) (xy 124.11407 -179.025308) (xy 124.106242 -179.084764) (xy 124.090721 -179.142689)
			(xy 124.067772 -179.198093) (xy 124.037788 -179.250027) (xy 124.001282 -179.297603) (xy 123.958877 -179.340008)
			(xy 123.911301 -179.376514) (xy 123.859367 -179.406498) (xy 123.803963 -179.429447) (xy 123.746038 -179.444968)
			(xy 123.686582 -179.452796) (xy 123.626614 -179.452796) (xy 123.567158 -179.444968) (xy 123.509233 -179.429447)
			(xy 123.453829 -179.406498) (xy 123.401895 -179.376514) (xy 123.354319 -179.340008) (xy 123.311914 -179.297603)
			(xy 123.275408 -179.250027) (xy 123.245424 -179.198093) (xy 123.222475 -179.142689) (xy 123.206954 -179.084764)
			(xy 123.199126 -179.025308) (xy 123.198636 -178.995324) (xy 4.30911 -178.995324) (xy 4.30911 -180.901086)
			(xy 142.181072 -180.901086) (xy 142.181072 -180.037486) (xy 142.181562 -180.007518) (xy 142.189385 -179.948096)
			(xy 142.204898 -179.890203) (xy 142.227834 -179.83483) (xy 142.257801 -179.782924) (xy 142.294288 -179.735374)
			(xy 142.336668 -179.692994) (xy 142.384218 -179.656507) (xy 142.436124 -179.62654) (xy 142.491497 -179.603604)
			(xy 142.54939 -179.588091) (xy 142.608812 -179.580268) (xy 142.668748 -179.580268) (xy 142.72817 -179.588091)
			(xy 142.786063 -179.603604) (xy 142.841436 -179.62654) (xy 142.893342 -179.656507) (xy 142.940892 -179.692994)
			(xy 142.983272 -179.735374) (xy 143.019759 -179.782924) (xy 143.049726 -179.83483) (xy 143.072662 -179.890203)
			(xy 143.088175 -179.948096) (xy 143.095998 -180.007518) (xy 143.096488 -180.037486) (xy 143.096488 -180.901086)
			(xy 143.095998 -180.931054) (xy 143.088175 -180.990476) (xy 143.072662 -181.048369) (xy 143.049726 -181.103742)
			(xy 143.019759 -181.155648) (xy 142.983272 -181.203198) (xy 142.940892 -181.245578) (xy 142.893342 -181.282065)
			(xy 142.841436 -181.312032) (xy 142.786063 -181.334968) (xy 142.72817 -181.350481) (xy 142.668748 -181.358304)
			(xy 142.608812 -181.358304) (xy 142.54939 -181.350481) (xy 142.491497 -181.334968) (xy 142.436124 -181.312032)
			(xy 142.384218 -181.282065) (xy 142.336668 -181.245578) (xy 142.294288 -181.203198) (xy 142.257801 -181.155648)
			(xy 142.227834 -181.103742) (xy 142.204898 -181.048369) (xy 142.189385 -180.990476) (xy 142.181562 -180.931054)
			(xy 142.181072 -180.901086) (xy 4.30911 -180.901086) (xy 4.30911 -182.933086) (xy 141.546072 -182.933086)
			(xy 141.546072 -182.069486) (xy 141.546562 -182.039518) (xy 141.554385 -181.980096) (xy 141.569898 -181.922203)
			(xy 141.592834 -181.86683) (xy 141.622801 -181.814924) (xy 141.659288 -181.767374) (xy 141.701668 -181.724994)
			(xy 141.749218 -181.688507) (xy 141.801124 -181.65854) (xy 141.856497 -181.635604) (xy 141.91439 -181.620091)
			(xy 141.973812 -181.612268) (xy 142.033748 -181.612268) (xy 142.09317 -181.620091) (xy 142.151063 -181.635604)
			(xy 142.206436 -181.65854) (xy 142.258342 -181.688507) (xy 142.305892 -181.724994) (xy 142.348272 -181.767374)
			(xy 142.384759 -181.814924) (xy 142.414726 -181.86683) (xy 142.437662 -181.922203) (xy 142.453175 -181.980096)
			(xy 142.460998 -182.039518) (xy 142.461488 -182.069486) (xy 142.461488 -182.933086) (xy 142.460998 -182.963054)
			(xy 142.453175 -183.022476) (xy 142.437662 -183.080369) (xy 142.414726 -183.135742) (xy 142.384759 -183.187648)
			(xy 142.348272 -183.235198) (xy 142.305892 -183.277578) (xy 142.258342 -183.314065) (xy 142.206436 -183.344032)
			(xy 142.151063 -183.366968) (xy 142.09317 -183.382481) (xy 142.033748 -183.390304) (xy 141.973812 -183.390304)
			(xy 141.91439 -183.382481) (xy 141.856497 -183.366968) (xy 141.801124 -183.344032) (xy 141.749218 -183.314065)
			(xy 141.701668 -183.277578) (xy 141.659288 -183.235198) (xy 141.622801 -183.187648) (xy 141.592834 -183.135742)
			(xy 141.569898 -183.080369) (xy 141.554385 -183.022476) (xy 141.546562 -182.963054) (xy 141.546072 -182.933086)
			(xy 4.30911 -182.933086) (xy 4.30911 -187.124582) (xy 135.58115 -187.124582) (xy 135.58115 -187.064618)
			(xy 135.588977 -187.005166) (xy 135.604497 -186.947244) (xy 135.627444 -186.891844) (xy 135.657426 -186.839912)
			(xy 135.69393 -186.792339) (xy 135.736331 -186.749937) (xy 135.783904 -186.713432) (xy 135.835835 -186.683448)
			(xy 135.891235 -186.6605) (xy 135.949156 -186.644979) (xy 136.008608 -186.637151) (xy 136.03859 -186.63666)
			(xy 136.90219 -186.63666) (xy 136.932178 -186.637085) (xy 136.99164 -186.644912) (xy 137.049571 -186.660433)
			(xy 137.104981 -186.683384) (xy 137.156922 -186.713371) (xy 137.204504 -186.749881) (xy 137.246913 -186.792289)
			(xy 137.283424 -186.83987) (xy 137.313412 -186.89181) (xy 137.336363 -186.947219) (xy 137.351886 -187.005151)
			(xy 137.359715 -187.064612) (xy 137.359715 -187.124588) (xy 137.351886 -187.184049) (xy 137.336363 -187.241981)
			(xy 137.313412 -187.29739) (xy 137.283424 -187.34933) (xy 137.246913 -187.396911) (xy 137.204504 -187.439319)
			(xy 137.156922 -187.475829) (xy 137.104981 -187.505816) (xy 137.049571 -187.528767) (xy 136.99164 -187.544288)
			(xy 136.932178 -187.552115) (xy 136.90219 -187.552584) (xy 136.03859 -187.552584) (xy 136.008608 -187.552049)
			(xy 135.949156 -187.544221) (xy 135.891235 -187.5287) (xy 135.835835 -187.505752) (xy 135.783904 -187.475768)
			(xy 135.736331 -187.439263) (xy 135.69393 -187.396861) (xy 135.657426 -187.349288) (xy 135.627444 -187.297356)
			(xy 135.604497 -187.241956) (xy 135.588977 -187.184034) (xy 135.58115 -187.124582) (xy 4.30911 -187.124582)
			(xy 4.30911 -188.252885) (xy 128.656818 -188.252885) (xy 128.656818 -188.192915) (xy 128.664646 -188.133459)
			(xy 128.680167 -188.075533) (xy 128.703116 -188.020128) (xy 128.733101 -187.968193) (xy 128.769608 -187.920615)
			(xy 128.812012 -187.87821) (xy 128.859589 -187.841703) (xy 128.911524 -187.811718) (xy 128.966929 -187.788768)
			(xy 129.024855 -187.773246) (xy 129.084311 -187.765418) (xy 129.114296 -187.764928) (xy 129.977896 -187.764928)
			(xy 130.007881 -187.765417) (xy 130.067339 -187.773244) (xy 130.125266 -187.788765) (xy 130.180671 -187.811714)
			(xy 130.232607 -187.841699) (xy 130.280185 -187.878207) (xy 130.322591 -187.920612) (xy 130.359098 -187.96819)
			(xy 130.389084 -188.020125) (xy 130.412034 -188.075531) (xy 130.427555 -188.133458) (xy 130.435383 -188.192915)
			(xy 130.435383 -188.252885) (xy 130.434185 -188.261981) (xy 131.046262 -188.261981) (xy 131.046262 -188.202019)
			(xy 131.054088 -188.14257) (xy 131.069607 -188.084651) (xy 131.092553 -188.029253) (xy 131.122533 -187.977324)
			(xy 131.159034 -187.929752) (xy 131.201432 -187.887351) (xy 131.249002 -187.850847) (xy 131.30093 -187.820864)
			(xy 131.356326 -187.797915) (xy 131.414244 -187.782393) (xy 131.473693 -187.774564) (xy 131.503674 -187.774072)
			(xy 132.367274 -187.774072) (xy 132.397263 -187.774472) (xy 132.456728 -187.782297) (xy 132.514663 -187.797818)
			(xy 132.570077 -187.820768) (xy 132.62202 -187.850755) (xy 132.669605 -187.887266) (xy 132.712017 -187.929675)
			(xy 132.74853 -187.977258) (xy 132.77852 -188.0292) (xy 132.801474 -188.084612) (xy 132.816998 -188.142546)
			(xy 132.824827 -188.202011) (xy 132.824827 -188.261989) (xy 132.816998 -188.321454) (xy 132.801474 -188.379388)
			(xy 132.79518 -188.394582) (xy 133.54915 -188.394582) (xy 133.54915 -188.334618) (xy 133.556977 -188.275166)
			(xy 133.572497 -188.217244) (xy 133.595444 -188.161844) (xy 133.625426 -188.109912) (xy 133.66193 -188.062339)
			(xy 133.704331 -188.019937) (xy 133.751904 -187.983432) (xy 133.803835 -187.953448) (xy 133.859235 -187.9305)
			(xy 133.917156 -187.914979) (xy 133.976608 -187.907151) (xy 134.00659 -187.90666) (xy 134.87019 -187.90666)
			(xy 134.900178 -187.907085) (xy 134.95964 -187.914912) (xy 135.017571 -187.930433) (xy 135.072981 -187.953384)
			(xy 135.124922 -187.983371) (xy 135.172504 -188.019881) (xy 135.214913 -188.062289) (xy 135.251424 -188.10987)
			(xy 135.281412 -188.16181) (xy 135.304363 -188.217219) (xy 135.319886 -188.275151) (xy 135.327715 -188.334612)
			(xy 135.327715 -188.394588) (xy 135.319886 -188.454049) (xy 135.304363 -188.511981) (xy 135.281412 -188.56739)
			(xy 135.251424 -188.61933) (xy 135.214913 -188.666911) (xy 135.172504 -188.709319) (xy 135.124922 -188.745829)
			(xy 135.072981 -188.775816) (xy 135.017571 -188.798767) (xy 134.95964 -188.814288) (xy 134.900178 -188.822115)
			(xy 134.87019 -188.822584) (xy 134.00659 -188.822584) (xy 133.976608 -188.822049) (xy 133.917156 -188.814221)
			(xy 133.859235 -188.7987) (xy 133.803835 -188.775752) (xy 133.751904 -188.745768) (xy 133.704331 -188.709263)
			(xy 133.66193 -188.666861) (xy 133.625426 -188.619288) (xy 133.595444 -188.567356) (xy 133.572497 -188.511956)
			(xy 133.556977 -188.454034) (xy 133.54915 -188.394582) (xy 132.79518 -188.394582) (xy 132.77852 -188.4348)
			(xy 132.74853 -188.486742) (xy 132.712017 -188.534325) (xy 132.669605 -188.576734) (xy 132.62202 -188.613245)
			(xy 132.570077 -188.643232) (xy 132.514663 -188.666182) (xy 132.456728 -188.681703) (xy 132.397263 -188.689528)
			(xy 132.367274 -188.689996) (xy 131.503674 -188.689996) (xy 131.473693 -188.689436) (xy 131.414244 -188.681607)
			(xy 131.356326 -188.666085) (xy 131.30093 -188.643136) (xy 131.249002 -188.613153) (xy 131.201432 -188.576649)
			(xy 131.159034 -188.534248) (xy 131.122533 -188.486676) (xy 131.092553 -188.434747) (xy 131.069607 -188.379349)
			(xy 131.054088 -188.32143) (xy 131.046262 -188.261981) (xy 130.434185 -188.261981) (xy 130.427555 -188.312342)
			(xy 130.412034 -188.370269) (xy 130.389084 -188.425675) (xy 130.359098 -188.47761) (xy 130.322591 -188.525188)
			(xy 130.280185 -188.567593) (xy 130.232607 -188.604101) (xy 130.180671 -188.634086) (xy 130.125266 -188.657035)
			(xy 130.067339 -188.672556) (xy 130.007881 -188.680383) (xy 129.977896 -188.680852) (xy 129.114296 -188.680852)
			(xy 129.084311 -188.680382) (xy 129.024855 -188.672554) (xy 128.966929 -188.657032) (xy 128.911524 -188.634082)
			(xy 128.859589 -188.604097) (xy 128.812012 -188.56759) (xy 128.769608 -188.525185) (xy 128.733101 -188.477607)
			(xy 128.703116 -188.425672) (xy 128.680167 -188.370267) (xy 128.664646 -188.312341) (xy 128.656818 -188.252885)
			(xy 4.30911 -188.252885) (xy 4.30911 -195.726088) (xy 126.922185 -195.726088) (xy 126.922185 -195.666112)
			(xy 126.930014 -195.606648) (xy 126.945538 -195.548715) (xy 126.968491 -195.493304) (xy 126.99848 -195.441364)
			(xy 127.034993 -195.393782) (xy 127.077404 -195.351373) (xy 127.124989 -195.314864) (xy 127.176931 -195.284878)
			(xy 127.232344 -195.261928) (xy 127.290278 -195.246408) (xy 127.349742 -195.238583) (xy 127.37973 -195.238116)
			(xy 128.24333 -195.238116) (xy 128.273312 -195.238652) (xy 128.332761 -195.246482) (xy 128.39068 -195.262005)
			(xy 128.446078 -195.284955) (xy 128.498007 -195.314939) (xy 128.545577 -195.351444) (xy 128.587976 -195.393845)
			(xy 128.624478 -195.441418) (xy 128.654459 -195.493349) (xy 128.677405 -195.548748) (xy 128.692924 -195.606668)
			(xy 128.70075 -195.666118) (xy 128.70075 -195.726082) (xy 128.692924 -195.785532) (xy 128.677405 -195.843452)
			(xy 128.654459 -195.898851) (xy 128.624478 -195.950782) (xy 128.587976 -195.998355) (xy 128.545577 -196.040756)
			(xy 128.498007 -196.077261) (xy 128.446078 -196.107245) (xy 128.39068 -196.130195) (xy 128.332761 -196.145718)
			(xy 128.273312 -196.153548) (xy 128.24333 -196.15404) (xy 127.37973 -196.15404) (xy 127.349742 -196.153617)
			(xy 127.290278 -196.145792) (xy 127.232344 -196.130272) (xy 127.176931 -196.107322) (xy 127.124989 -196.077336)
			(xy 127.077404 -196.040827) (xy 127.034993 -195.998418) (xy 126.99848 -195.950836) (xy 126.968491 -195.898896)
			(xy 126.945538 -195.843485) (xy 126.930014 -195.785552) (xy 126.922185 -195.726088) (xy 4.30911 -195.726088)
			(xy 4.30911 -198.543743) (xy 138.243774 -198.543743) (xy 138.24519 -198.489257) (xy 138.254343 -198.435528)
			(xy 138.271047 -198.383647) (xy 138.294963 -198.33467) (xy 138.325603 -198.289594) (xy 138.362344 -198.249336)
			(xy 138.40444 -198.214715) (xy 138.451033 -198.186434) (xy 138.501175 -198.165071) (xy 138.553847 -198.151058)
			(xy 138.607977 -198.144682) (xy 138.635232 -198.144892) (xy 138.636502 -198.144892) (xy 139.488672 -198.144892)
			(xy 139.515926 -198.145353) (xy 139.56988 -198.153107) (xy 139.622181 -198.168461) (xy 139.671765 -198.191102)
			(xy 139.717622 -198.220569) (xy 139.758818 -198.256263) (xy 139.794514 -198.297456) (xy 139.823985 -198.34331)
			(xy 139.846629 -198.392892) (xy 139.861987 -198.445192) (xy 139.869745 -198.499146) (xy 139.869745 -198.553654)
			(xy 139.861987 -198.607608) (xy 139.846629 -198.659908) (xy 139.823985 -198.70949) (xy 139.794514 -198.755344)
			(xy 139.758818 -198.796537) (xy 139.717622 -198.832231) (xy 139.671765 -198.861698) (xy 139.622181 -198.884339)
			(xy 139.56988 -198.899693) (xy 139.515926 -198.907447) (xy 139.488672 -198.907908) (xy 139.477343 -198.907862)
			(xy 139.454723 -198.90659) (xy 139.44346 -198.905368) (xy 139.440412 -198.90486) (xy 138.672824 -198.90486)
			(xy 138.669776 -198.905368) (xy 138.642662 -198.908134) (xy 138.588177 -198.906693) (xy 138.534452 -198.897514)
			(xy 138.482579 -198.880785) (xy 138.433613 -198.856847) (xy 138.388552 -198.826185) (xy 138.348311 -198.789424)
			(xy 138.31371 -198.747312) (xy 138.285452 -198.700706) (xy 138.264112 -198.650554) (xy 138.250125 -198.597875)
			(xy 138.243774 -198.543743) (xy 4.30911 -198.543743) (xy 4.30911 -201.379368) (xy 98.428551 -201.379368)
			(xy 98.428551 -201.324832) (xy 98.436313 -201.270851) (xy 98.451678 -201.218525) (xy 98.474333 -201.168917)
			(xy 98.503818 -201.123039) (xy 98.539531 -201.081824) (xy 98.580747 -201.046112) (xy 98.626626 -201.016628)
			(xy 98.676234 -200.993974) (xy 98.728561 -200.978611) (xy 98.782542 -200.970851) (xy 98.80981 -200.970388)
			(xy 99.67341 -200.970388) (xy 99.700682 -200.970775) (xy 99.754672 -200.978539) (xy 99.807007 -200.993907)
			(xy 99.856623 -201.016567) (xy 99.902508 -201.046057) (xy 99.94373 -201.081777) (xy 99.979449 -201.123)
			(xy 100.008938 -201.168886) (xy 100.031596 -201.218502) (xy 100.046963 -201.270838) (xy 100.054725 -201.324828)
			(xy 100.054725 -201.379372) (xy 100.046963 -201.433362) (xy 100.031596 -201.485698) (xy 100.008938 -201.535314)
			(xy 99.979449 -201.5812) (xy 99.94373 -201.622423) (xy 99.902508 -201.658143) (xy 99.856623 -201.687633)
			(xy 99.807007 -201.710293) (xy 99.754672 -201.725661) (xy 99.700682 -201.733425) (xy 99.67341 -201.733912)
			(xy 98.80981 -201.733912) (xy 98.782542 -201.733349) (xy 98.728561 -201.725589) (xy 98.676234 -201.710226)
			(xy 98.626626 -201.687572) (xy 98.580747 -201.658088) (xy 98.539531 -201.622376) (xy 98.503818 -201.581161)
			(xy 98.474333 -201.535283) (xy 98.451678 -201.485675) (xy 98.436313 -201.433349) (xy 98.428551 -201.379368)
			(xy 4.30911 -201.379368) (xy 4.30911 -209.380836) (xy 445.288416 -209.380836) (xy 445.288416 -208.517236)
			(xy 445.288906 -208.487268) (xy 445.296729 -208.427846) (xy 445.312242 -208.369953) (xy 445.335178 -208.31458)
			(xy 445.365145 -208.262674) (xy 445.401632 -208.215124) (xy 445.444012 -208.172744) (xy 445.491562 -208.136257)
			(xy 445.543468 -208.10629) (xy 445.598841 -208.083354) (xy 445.656734 -208.067841) (xy 445.716156 -208.060018)
			(xy 445.776092 -208.060018) (xy 445.835514 -208.067841) (xy 445.893407 -208.083354) (xy 445.94878 -208.10629)
			(xy 446.000686 -208.136257) (xy 446.048236 -208.172744) (xy 446.090616 -208.215124) (xy 446.127103 -208.262674)
			(xy 446.15707 -208.31458) (xy 446.180006 -208.369953) (xy 446.195519 -208.427846) (xy 446.203342 -208.487268)
			(xy 446.203832 -208.517236) (xy 446.203832 -209.380836) (xy 446.203342 -209.410804) (xy 446.195519 -209.470226)
			(xy 446.180006 -209.528119) (xy 446.15707 -209.583492) (xy 446.127103 -209.635398) (xy 446.090616 -209.682948)
			(xy 446.048236 -209.725328) (xy 446.000686 -209.761815) (xy 445.94878 -209.791782) (xy 445.893407 -209.814718)
			(xy 445.835514 -209.830231) (xy 445.776092 -209.838054) (xy 445.716156 -209.838054) (xy 445.656734 -209.830231)
			(xy 445.598841 -209.814718) (xy 445.543468 -209.791782) (xy 445.491562 -209.761815) (xy 445.444012 -209.725328)
			(xy 445.401632 -209.682948) (xy 445.365145 -209.635398) (xy 445.335178 -209.583492) (xy 445.312242 -209.528119)
			(xy 445.296729 -209.470226) (xy 445.288906 -209.410804) (xy 445.288416 -209.380836) (xy 4.30911 -209.380836)
			(xy 4.30911 -225.261473) (xy 239.822113 -225.261473) (xy 239.822113 -225.201527) (xy 239.829938 -225.142093)
			(xy 239.845454 -225.084189) (xy 239.868395 -225.028806) (xy 239.89837 -224.976891) (xy 239.934864 -224.929333)
			(xy 239.977254 -224.886945) (xy 240.024814 -224.850454) (xy 240.076731 -224.820483) (xy 240.132115 -224.797545)
			(xy 240.19002 -224.782032) (xy 240.249455 -224.774211) (xy 240.279428 -224.773744) (xy 241.143028 -224.773744)
			(xy 241.172991 -224.774332) (xy 241.232405 -224.782157) (xy 241.290289 -224.79767) (xy 241.345653 -224.820606)
			(xy 241.39755 -224.850571) (xy 241.445091 -224.887054) (xy 241.487465 -224.92943) (xy 241.523944 -224.976974)
			(xy 241.553907 -225.028872) (xy 241.576839 -225.084238) (xy 241.592348 -225.142123) (xy 241.60017 -225.201537)
			(xy 241.60017 -225.261463) (xy 241.592348 -225.320877) (xy 241.576839 -225.378762) (xy 241.553907 -225.434128)
			(xy 241.523944 -225.486026) (xy 241.487465 -225.53357) (xy 241.445091 -225.575946) (xy 241.39755 -225.612429)
			(xy 241.345653 -225.642394) (xy 241.290289 -225.66533) (xy 241.232405 -225.680843) (xy 241.172991 -225.688668)
			(xy 241.143028 -225.68916) (xy 240.279428 -225.68916) (xy 240.249455 -225.688789) (xy 240.19002 -225.680968)
			(xy 240.132115 -225.665455) (xy 240.076731 -225.642517) (xy 240.024814 -225.612546) (xy 239.977254 -225.576055)
			(xy 239.934864 -225.533667) (xy 239.89837 -225.486109) (xy 239.868395 -225.434194) (xy 239.845454 -225.378811)
			(xy 239.829938 -225.320907) (xy 239.822113 -225.261473) (xy 4.30911 -225.261473) (xy 4.30911 -230.903589)
			(xy 383.216061 -230.903589) (xy 383.216061 -230.843611) (xy 383.22389 -230.784147) (xy 383.239413 -230.726213)
			(xy 383.262366 -230.670801) (xy 383.292355 -230.618858) (xy 383.328867 -230.571275) (xy 383.371278 -230.528865)
			(xy 383.418862 -230.492353) (xy 383.470804 -230.462364) (xy 383.526216 -230.439412) (xy 383.584151 -230.423889)
			(xy 383.643615 -230.416061) (xy 383.673604 -230.415592) (xy 384.537204 -230.415592) (xy 384.567185 -230.416174)
			(xy 384.626634 -230.424001) (xy 384.684553 -230.439521) (xy 384.739951 -230.462468) (xy 384.79188 -230.492449)
			(xy 384.839451 -230.528952) (xy 384.88185 -230.571352) (xy 384.918353 -230.618924) (xy 384.948334 -230.670853)
			(xy 384.97128 -230.726251) (xy 384.986799 -230.78417) (xy 384.994626 -230.843619) (xy 384.994626 -230.903581)
			(xy 384.986799 -230.96303) (xy 384.97128 -231.020949) (xy 384.948334 -231.076347) (xy 384.918353 -231.128276)
			(xy 384.88185 -231.175848) (xy 384.839451 -231.218248) (xy 384.79188 -231.254751) (xy 384.739951 -231.284732)
			(xy 384.684553 -231.307679) (xy 384.626634 -231.323199) (xy 384.567185 -231.331026) (xy 384.537204 -231.331516)
			(xy 383.673604 -231.331516) (xy 383.643615 -231.331139) (xy 383.584151 -231.323311) (xy 383.526216 -231.307788)
			(xy 383.470804 -231.284836) (xy 383.418862 -231.254847) (xy 383.371278 -231.218335) (xy 383.328867 -231.175925)
			(xy 383.292355 -231.128342) (xy 383.262366 -231.076399) (xy 383.239413 -231.020987) (xy 383.22389 -230.963053)
			(xy 383.216061 -230.903589) (xy 4.30911 -230.903589) (xy 4.30911 -234.655869) (xy 448.021157 -234.655869)
			(xy 448.021157 -234.595931) (xy 448.028981 -234.536505) (xy 448.044494 -234.478608) (xy 448.067432 -234.423232)
			(xy 448.097401 -234.371324) (xy 448.13389 -234.323771) (xy 448.176273 -234.281388) (xy 448.223825 -234.2449)
			(xy 448.275734 -234.214931) (xy 448.33111 -234.191993) (xy 448.389007 -234.17648) (xy 448.448433 -234.168657)
			(xy 448.478402 -234.168188) (xy 449.342002 -234.168188) (xy 449.371969 -234.168686) (xy 449.431391 -234.176509)
			(xy 449.489283 -234.192022) (xy 449.544656 -234.214958) (xy 449.596561 -234.244925) (xy 449.64411 -234.281411)
			(xy 449.68649 -234.323792) (xy 449.722976 -234.371341) (xy 449.752943 -234.423246) (xy 449.775879 -234.478618)
			(xy 449.791391 -234.536511) (xy 449.799214 -234.595933) (xy 449.799214 -234.655867) (xy 449.791391 -234.715289)
			(xy 449.775879 -234.773182) (xy 449.752943 -234.828554) (xy 449.722976 -234.880459) (xy 449.68649 -234.928008)
			(xy 449.64411 -234.970389) (xy 449.596561 -235.006875) (xy 449.544656 -235.036842) (xy 449.489283 -235.059778)
			(xy 449.431391 -235.075291) (xy 449.371969 -235.083114) (xy 449.342002 -235.083604) (xy 448.478402 -235.083604)
			(xy 448.448433 -235.083143) (xy 448.389007 -235.07532) (xy 448.33111 -235.059807) (xy 448.275734 -235.036869)
			(xy 448.223825 -235.0069) (xy 448.176273 -234.970412) (xy 448.13389 -234.928029) (xy 448.097401 -234.880476)
			(xy 448.067432 -234.828568) (xy 448.044494 -234.773192) (xy 448.028981 -234.715295) (xy 448.021157 -234.655869)
			(xy 4.30911 -234.655869) (xy 4.30911 -239.07907) (xy 153.398934 -239.07907) (xy 153.398934 -239.01913)
			(xy 153.406758 -238.959703) (xy 153.422271 -238.901805) (xy 153.445208 -238.846427) (xy 153.475178 -238.794517)
			(xy 153.511666 -238.746963) (xy 153.554049 -238.704578) (xy 153.601602 -238.668088) (xy 153.653511 -238.638116)
			(xy 153.708888 -238.615177) (xy 153.766785 -238.599661) (xy 153.826212 -238.591835) (xy 153.856182 -238.591344)
			(xy 154.719782 -238.591344) (xy 154.749749 -238.591908) (xy 154.809169 -238.599729) (xy 154.867061 -238.615239)
			(xy 154.922433 -238.638172) (xy 154.974337 -238.668138) (xy 155.021886 -238.704622) (xy 155.064267 -238.747)
			(xy 155.100752 -238.794548) (xy 155.13072 -238.846451) (xy 155.153656 -238.901822) (xy 155.169168 -238.959713)
			(xy 155.176991 -239.019133) (xy 155.176991 -239.079067) (xy 155.169168 -239.138487) (xy 155.153656 -239.196378)
			(xy 155.13072 -239.251749) (xy 155.100752 -239.303652) (xy 155.064267 -239.3512) (xy 155.021886 -239.393578)
			(xy 154.974337 -239.430062) (xy 154.922433 -239.460028) (xy 154.867061 -239.482961) (xy 154.809169 -239.498471)
			(xy 154.749749 -239.506292) (xy 154.719782 -239.50676) (xy 153.856182 -239.50676) (xy 153.826212 -239.506365)
			(xy 153.766785 -239.498539) (xy 153.708888 -239.483023) (xy 153.653511 -239.460084) (xy 153.601602 -239.430112)
			(xy 153.554049 -239.393622) (xy 153.511666 -239.351237) (xy 153.475178 -239.303683) (xy 153.445208 -239.251773)
			(xy 153.422271 -239.196395) (xy 153.406758 -239.138497) (xy 153.398934 -239.07907) (xy 4.30911 -239.07907)
			(xy 4.30911 -241.031522) (xy 4.308609 -241.101909) (xy 4.300702 -241.24246) (xy 4.284927 -241.382347)
			(xy 4.261334 -241.521129) (xy 4.229996 -241.65837) (xy 4.191013 -241.793638) (xy 4.144506 -241.926507)
			(xy 4.090623 -242.05656) (xy 4.029533 -242.183387) (xy 3.961428 -242.30659) (xy 3.886522 -242.42578)
			(xy 3.805051 -242.540582) (xy 3.717272 -242.650636) (xy 3.623459 -242.755596) (xy 3.574034 -242.805712)
			(xy 0.945642 -245.434104) (xy 0.908331 -245.472065) (xy 0.838615 -245.55251) (xy 0.774816 -245.637725)
			(xy 0.717261 -245.727274) (xy 0.666242 -245.820703) (xy 0.62202 -245.917533) (xy 0.584819 -246.017272)
			(xy 0.554831 -246.119412) (xy 0.532207 -246.22343) (xy 0.517063 -246.328799) (xy 0.509476 -246.434979)
			(xy 0.509016 -246.488204) (xy 0.509016 -270.89989) (xy 26.882353 -270.89989) (xy 26.886342 -270.75135)
			(xy 26.898299 -270.603237) (xy 26.918189 -270.45598) (xy 26.945954 -270.310004) (xy 26.981515 -270.165727)
			(xy 27.024769 -270.023568) (xy 27.075591 -269.883935) (xy 27.133835 -269.747232) (xy 27.199333 -269.613852)
			(xy 27.271896 -269.48418) (xy 27.351314 -269.35859) (xy 27.437359 -269.237443) (xy 27.529783 -269.12109)
			(xy 27.628319 -269.009866) (xy 27.732683 -268.904091) (xy 27.842575 -268.804071) (xy 27.957676 -268.710093)
			(xy 28.077656 -268.622429) (xy 28.202169 -268.541332) (xy 28.330855 -268.467035) (xy 28.463344 -268.399753)
			(xy 28.599253 -268.339679) (xy 28.738191 -268.286987) (xy 28.879757 -268.241828) (xy 29.023543 -268.204333)
			(xy 29.169134 -268.174611) (xy 29.31611 -268.152746) (xy 29.464049 -268.138802) (xy 29.612522 -268.132818)
			(xy 29.761103 -268.134813) (xy 29.909362 -268.144781) (xy 30.056873 -268.162692) (xy 30.203209 -268.188495)
			(xy 30.34795 -268.222115) (xy 30.490677 -268.263457) (xy 30.63098 -268.3124) (xy 30.768453 -268.368803)
			(xy 30.9027 -268.432504) (xy 31.033335 -268.50332) (xy 31.15998 -268.581045) (xy 31.28227 -268.665456)
			(xy 31.399853 -268.756309) (xy 31.51239 -268.853343) (xy 31.619557 -268.956278) (xy 31.721044 -269.064817)
			(xy 31.816558 -269.178646) (xy 31.905825 -269.297439) (xy 31.988586 -269.420851) (xy 32.064604 -269.548529)
			(xy 32.133659 -269.680102) (xy 32.195552 -269.815193) (xy 32.250105 -269.95341) (xy 32.29716 -270.094357)
			(xy 32.336582 -270.237627) (xy 32.368256 -270.382806) (xy 32.392092 -270.529475) (xy 32.408021 -270.677213)
			(xy 32.415997 -270.825593) (xy 32.416496 -270.89989) (xy 86.882487 -270.89989) (xy 86.886476 -270.75135)
			(xy 86.898433 -270.603237) (xy 86.918323 -270.45598) (xy 86.946088 -270.310004) (xy 86.981649 -270.165727)
			(xy 87.024903 -270.023568) (xy 87.075725 -269.883935) (xy 87.133969 -269.747232) (xy 87.199467 -269.613852)
			(xy 87.27203 -269.48418) (xy 87.351448 -269.35859) (xy 87.437493 -269.237443) (xy 87.529917 -269.12109)
			(xy 87.628453 -269.009866) (xy 87.732817 -268.904091) (xy 87.842709 -268.804071) (xy 87.95781 -268.710093)
			(xy 88.07779 -268.622429) (xy 88.202303 -268.541332) (xy 88.330989 -268.467035) (xy 88.463478 -268.399753)
			(xy 88.599387 -268.339679) (xy 88.738325 -268.286987) (xy 88.879891 -268.241828) (xy 89.023677 -268.204333)
			(xy 89.169268 -268.174611) (xy 89.316244 -268.152746) (xy 89.464183 -268.138802) (xy 89.612656 -268.132818)
			(xy 89.761237 -268.134813) (xy 89.909496 -268.144781) (xy 90.057007 -268.162692) (xy 90.203343 -268.188495)
			(xy 90.348084 -268.222115) (xy 90.490811 -268.263457) (xy 90.631114 -268.3124) (xy 90.768587 -268.368803)
			(xy 90.902834 -268.432504) (xy 91.033469 -268.50332) (xy 91.160114 -268.581045) (xy 91.282404 -268.665456)
			(xy 91.399987 -268.756309) (xy 91.512524 -268.853343) (xy 91.619691 -268.956278) (xy 91.721178 -269.064817)
			(xy 91.816692 -269.178646) (xy 91.905959 -269.297439) (xy 91.98872 -269.420851) (xy 92.064738 -269.548529)
			(xy 92.133793 -269.680102) (xy 92.195686 -269.815193) (xy 92.250239 -269.95341) (xy 92.297294 -270.094357)
			(xy 92.336716 -270.237627) (xy 92.36839 -270.382806) (xy 92.392226 -270.529475) (xy 92.408155 -270.677213)
			(xy 92.416131 -270.825593) (xy 92.41663 -270.89989) (xy 142.982451 -270.89989) (xy 142.98644 -270.75135)
			(xy 142.998397 -270.603237) (xy 143.018287 -270.45598) (xy 143.046052 -270.310004) (xy 143.081613 -270.165727)
			(xy 143.124867 -270.023568) (xy 143.175689 -269.883935) (xy 143.233933 -269.747232) (xy 143.299431 -269.613852)
			(xy 143.371994 -269.48418) (xy 143.451412 -269.35859) (xy 143.537457 -269.237443) (xy 143.629881 -269.12109)
			(xy 143.728417 -269.009866) (xy 143.832781 -268.904091) (xy 143.942673 -268.804071) (xy 144.057774 -268.710093)
			(xy 144.177754 -268.622429) (xy 144.302267 -268.541332) (xy 144.430953 -268.467035) (xy 144.563442 -268.399753)
			(xy 144.699351 -268.339679) (xy 144.838289 -268.286987) (xy 144.979855 -268.241828) (xy 145.123641 -268.204333)
			(xy 145.269232 -268.174611) (xy 145.416208 -268.152746) (xy 145.564147 -268.138802) (xy 145.71262 -268.132818)
			(xy 145.861201 -268.134813) (xy 146.00946 -268.144781) (xy 146.156971 -268.162692) (xy 146.303307 -268.188495)
			(xy 146.448048 -268.222115) (xy 146.590775 -268.263457) (xy 146.731078 -268.3124) (xy 146.868551 -268.368803)
			(xy 147.002798 -268.432504) (xy 147.133433 -268.50332) (xy 147.260078 -268.581045) (xy 147.382368 -268.665456)
			(xy 147.499951 -268.756309) (xy 147.612488 -268.853343) (xy 147.719655 -268.956278) (xy 147.821142 -269.064817)
			(xy 147.916656 -269.178646) (xy 148.005923 -269.297439) (xy 148.088684 -269.420851) (xy 148.164702 -269.548529)
			(xy 148.233757 -269.680102) (xy 148.29565 -269.815193) (xy 148.350203 -269.95341) (xy 148.397258 -270.094357)
			(xy 148.43668 -270.237627) (xy 148.468354 -270.382806) (xy 148.49219 -270.529475) (xy 148.508119 -270.677213)
			(xy 148.516095 -270.825593) (xy 148.516594 -270.89989) (xy 202.982331 -270.89989) (xy 202.98632 -270.75135)
			(xy 202.998277 -270.603237) (xy 203.018167 -270.45598) (xy 203.045932 -270.310004) (xy 203.081493 -270.165727)
			(xy 203.124747 -270.023568) (xy 203.175569 -269.883935) (xy 203.233813 -269.747232) (xy 203.299311 -269.613852)
			(xy 203.371874 -269.48418) (xy 203.451292 -269.35859) (xy 203.537337 -269.237443) (xy 203.629761 -269.12109)
			(xy 203.728297 -269.009866) (xy 203.832661 -268.904091) (xy 203.942553 -268.804071) (xy 204.057654 -268.710093)
			(xy 204.177634 -268.622429) (xy 204.302147 -268.541332) (xy 204.430833 -268.467035) (xy 204.563322 -268.399753)
			(xy 204.699231 -268.339679) (xy 204.838169 -268.286987) (xy 204.979735 -268.241828) (xy 205.123521 -268.204333)
			(xy 205.269112 -268.174611) (xy 205.416088 -268.152746) (xy 205.564027 -268.138802) (xy 205.7125 -268.132818)
			(xy 205.861081 -268.134813) (xy 206.00934 -268.144781) (xy 206.156851 -268.162692) (xy 206.303187 -268.188495)
			(xy 206.447928 -268.222115) (xy 206.590655 -268.263457) (xy 206.730958 -268.3124) (xy 206.868431 -268.368803)
			(xy 207.002678 -268.432504) (xy 207.133313 -268.50332) (xy 207.259958 -268.581045) (xy 207.382248 -268.665456)
			(xy 207.499831 -268.756309) (xy 207.612368 -268.853343) (xy 207.719535 -268.956278) (xy 207.821022 -269.064817)
			(xy 207.916536 -269.178646) (xy 208.005803 -269.297439) (xy 208.088564 -269.420851) (xy 208.164582 -269.548529)
			(xy 208.233637 -269.680102) (xy 208.29553 -269.815193) (xy 208.350083 -269.95341) (xy 208.397138 -270.094357)
			(xy 208.43656 -270.237627) (xy 208.468234 -270.382806) (xy 208.49207 -270.529475) (xy 208.507999 -270.677213)
			(xy 208.515975 -270.825593) (xy 208.516474 -270.89989) (xy 259.082549 -270.89989) (xy 259.086538 -270.75135)
			(xy 259.098495 -270.603237) (xy 259.118385 -270.45598) (xy 259.14615 -270.310004) (xy 259.181711 -270.165727)
			(xy 259.224965 -270.023568) (xy 259.275787 -269.883935) (xy 259.334031 -269.747232) (xy 259.399529 -269.613852)
			(xy 259.472092 -269.48418) (xy 259.55151 -269.35859) (xy 259.637555 -269.237443) (xy 259.729979 -269.12109)
			(xy 259.828515 -269.009866) (xy 259.932879 -268.904091) (xy 260.042771 -268.804071) (xy 260.157872 -268.710093)
			(xy 260.277852 -268.622429) (xy 260.402365 -268.541332) (xy 260.531051 -268.467035) (xy 260.66354 -268.399753)
			(xy 260.799449 -268.339679) (xy 260.938387 -268.286987) (xy 261.079953 -268.241828) (xy 261.223739 -268.204333)
			(xy 261.36933 -268.174611) (xy 261.516306 -268.152746) (xy 261.664245 -268.138802) (xy 261.812718 -268.132818)
			(xy 261.961299 -268.134813) (xy 262.109558 -268.144781) (xy 262.257069 -268.162692) (xy 262.403405 -268.188495)
			(xy 262.548146 -268.222115) (xy 262.690873 -268.263457) (xy 262.831176 -268.3124) (xy 262.968649 -268.368803)
			(xy 263.102896 -268.432504) (xy 263.233531 -268.50332) (xy 263.360176 -268.581045) (xy 263.482466 -268.665456)
			(xy 263.600049 -268.756309) (xy 263.712586 -268.853343) (xy 263.819753 -268.956278) (xy 263.92124 -269.064817)
			(xy 264.016754 -269.178646) (xy 264.106021 -269.297439) (xy 264.188782 -269.420851) (xy 264.2648 -269.548529)
			(xy 264.333855 -269.680102) (xy 264.395748 -269.815193) (xy 264.450301 -269.95341) (xy 264.497356 -270.094357)
			(xy 264.536778 -270.237627) (xy 264.568452 -270.382806) (xy 264.592288 -270.529475) (xy 264.608217 -270.677213)
			(xy 264.616193 -270.825593) (xy 264.616692 -270.89989) (xy 319.082429 -270.89989) (xy 319.086418 -270.75135)
			(xy 319.098375 -270.603237) (xy 319.118265 -270.45598) (xy 319.14603 -270.310004) (xy 319.181591 -270.165727)
			(xy 319.224845 -270.023568) (xy 319.275667 -269.883935) (xy 319.333911 -269.747232) (xy 319.399409 -269.613852)
			(xy 319.471972 -269.48418) (xy 319.55139 -269.35859) (xy 319.637435 -269.237443) (xy 319.729859 -269.12109)
			(xy 319.828395 -269.009866) (xy 319.932759 -268.904091) (xy 320.042651 -268.804071) (xy 320.157752 -268.710093)
			(xy 320.277732 -268.622429) (xy 320.402245 -268.541332) (xy 320.530931 -268.467035) (xy 320.66342 -268.399753)
			(xy 320.799329 -268.339679) (xy 320.938267 -268.286987) (xy 321.079833 -268.241828) (xy 321.223619 -268.204333)
			(xy 321.36921 -268.174611) (xy 321.516186 -268.152746) (xy 321.664125 -268.138802) (xy 321.812598 -268.132818)
			(xy 321.961179 -268.134813) (xy 322.109438 -268.144781) (xy 322.256949 -268.162692) (xy 322.403285 -268.188495)
			(xy 322.548026 -268.222115) (xy 322.690753 -268.263457) (xy 322.831056 -268.3124) (xy 322.968529 -268.368803)
			(xy 323.102776 -268.432504) (xy 323.233411 -268.50332) (xy 323.360056 -268.581045) (xy 323.482346 -268.665456)
			(xy 323.599929 -268.756309) (xy 323.712466 -268.853343) (xy 323.819633 -268.956278) (xy 323.92112 -269.064817)
			(xy 324.016634 -269.178646) (xy 324.105901 -269.297439) (xy 324.188662 -269.420851) (xy 324.26468 -269.548529)
			(xy 324.333735 -269.680102) (xy 324.395628 -269.815193) (xy 324.450181 -269.95341) (xy 324.497236 -270.094357)
			(xy 324.536658 -270.237627) (xy 324.568332 -270.382806) (xy 324.592168 -270.529475) (xy 324.608097 -270.677213)
			(xy 324.616073 -270.825593) (xy 324.616572 -270.89989) (xy 375.182393 -270.89989) (xy 375.186382 -270.75135)
			(xy 375.198339 -270.603237) (xy 375.218229 -270.45598) (xy 375.245994 -270.310004) (xy 375.281555 -270.165727)
			(xy 375.324809 -270.023568) (xy 375.375631 -269.883935) (xy 375.433875 -269.747232) (xy 375.499373 -269.613852)
			(xy 375.571936 -269.48418) (xy 375.651354 -269.35859) (xy 375.737399 -269.237443) (xy 375.829823 -269.12109)
			(xy 375.928359 -269.009866) (xy 376.032723 -268.904091) (xy 376.142615 -268.804071) (xy 376.257716 -268.710093)
			(xy 376.377696 -268.622429) (xy 376.502209 -268.541332) (xy 376.630895 -268.467035) (xy 376.763384 -268.399753)
			(xy 376.899293 -268.339679) (xy 377.038231 -268.286987) (xy 377.179797 -268.241828) (xy 377.323583 -268.204333)
			(xy 377.469174 -268.174611) (xy 377.61615 -268.152746) (xy 377.764089 -268.138802) (xy 377.912562 -268.132818)
			(xy 378.061143 -268.134813) (xy 378.209402 -268.144781) (xy 378.356913 -268.162692) (xy 378.503249 -268.188495)
			(xy 378.64799 -268.222115) (xy 378.790717 -268.263457) (xy 378.93102 -268.3124) (xy 379.068493 -268.368803)
			(xy 379.20274 -268.432504) (xy 379.333375 -268.50332) (xy 379.46002 -268.581045) (xy 379.58231 -268.665456)
			(xy 379.699893 -268.756309) (xy 379.81243 -268.853343) (xy 379.919597 -268.956278) (xy 380.021084 -269.064817)
			(xy 380.116598 -269.178646) (xy 380.205865 -269.297439) (xy 380.288626 -269.420851) (xy 380.364644 -269.548529)
			(xy 380.433699 -269.680102) (xy 380.495592 -269.815193) (xy 380.550145 -269.95341) (xy 380.5972 -270.094357)
			(xy 380.636622 -270.237627) (xy 380.668296 -270.382806) (xy 380.692132 -270.529475) (xy 380.708061 -270.677213)
			(xy 380.716037 -270.825593) (xy 380.716536 -270.89989) (xy 435.182527 -270.89989) (xy 435.186516 -270.75135)
			(xy 435.198473 -270.603237) (xy 435.218363 -270.45598) (xy 435.246128 -270.310004) (xy 435.281689 -270.165727)
			(xy 435.324943 -270.023568) (xy 435.375765 -269.883935) (xy 435.434009 -269.747232) (xy 435.499507 -269.613852)
			(xy 435.57207 -269.48418) (xy 435.651488 -269.35859) (xy 435.737533 -269.237443) (xy 435.829957 -269.12109)
			(xy 435.928493 -269.009866) (xy 436.032857 -268.904091) (xy 436.142749 -268.804071) (xy 436.25785 -268.710093)
			(xy 436.37783 -268.622429) (xy 436.502343 -268.541332) (xy 436.631029 -268.467035) (xy 436.763518 -268.399753)
			(xy 436.899427 -268.339679) (xy 437.038365 -268.286987) (xy 437.179931 -268.241828) (xy 437.323717 -268.204333)
			(xy 437.469308 -268.174611) (xy 437.616284 -268.152746) (xy 437.764223 -268.138802) (xy 437.912696 -268.132818)
			(xy 438.061277 -268.134813) (xy 438.209536 -268.144781) (xy 438.357047 -268.162692) (xy 438.503383 -268.188495)
			(xy 438.648124 -268.222115) (xy 438.790851 -268.263457) (xy 438.931154 -268.3124) (xy 439.068627 -268.368803)
			(xy 439.202874 -268.432504) (xy 439.333509 -268.50332) (xy 439.460154 -268.581045) (xy 439.582444 -268.665456)
			(xy 439.700027 -268.756309) (xy 439.812564 -268.853343) (xy 439.919731 -268.956278) (xy 440.021218 -269.064817)
			(xy 440.116732 -269.178646) (xy 440.205999 -269.297439) (xy 440.28876 -269.420851) (xy 440.364778 -269.548529)
			(xy 440.433833 -269.680102) (xy 440.495726 -269.815193) (xy 440.550279 -269.95341) (xy 440.597334 -270.094357)
			(xy 440.636756 -270.237627) (xy 440.66843 -270.382806) (xy 440.692266 -270.529475) (xy 440.708195 -270.677213)
			(xy 440.716171 -270.825593) (xy 440.71667 -270.89989) (xy 440.716171 -270.974187) (xy 440.708195 -271.122567)
			(xy 440.692266 -271.270305) (xy 440.66843 -271.416974) (xy 440.636756 -271.562153) (xy 440.597334 -271.705423)
			(xy 440.550279 -271.84637) (xy 440.495726 -271.984587) (xy 440.433833 -272.119678) (xy 440.364778 -272.251251)
			(xy 440.28876 -272.378929) (xy 440.205999 -272.502341) (xy 440.116732 -272.621134) (xy 440.021218 -272.734963)
			(xy 439.919731 -272.843502) (xy 439.812564 -272.946437) (xy 439.700027 -273.043471) (xy 439.582444 -273.134324)
			(xy 439.460154 -273.218735) (xy 439.333509 -273.29646) (xy 439.202874 -273.367276) (xy 439.068627 -273.430977)
			(xy 438.931154 -273.48738) (xy 438.790851 -273.536323) (xy 438.648124 -273.577665) (xy 438.503383 -273.611285)
			(xy 438.357047 -273.637088) (xy 438.209536 -273.654999) (xy 438.061277 -273.664967) (xy 437.912696 -273.666962)
			(xy 437.764223 -273.660978) (xy 437.616284 -273.647034) (xy 437.469308 -273.625169) (xy 437.323717 -273.595447)
			(xy 437.179931 -273.557952) (xy 437.038365 -273.512793) (xy 436.899427 -273.460101) (xy 436.763518 -273.400027)
			(xy 436.631029 -273.332745) (xy 436.502343 -273.258448) (xy 436.37783 -273.177351) (xy 436.25785 -273.089687)
			(xy 436.142749 -272.995709) (xy 436.032857 -272.895689) (xy 435.928493 -272.789914) (xy 435.829957 -272.67869)
			(xy 435.737533 -272.562337) (xy 435.651488 -272.44119) (xy 435.57207 -272.3156) (xy 435.499507 -272.185928)
			(xy 435.434009 -272.052548) (xy 435.375765 -271.915845) (xy 435.324943 -271.776212) (xy 435.281689 -271.634053)
			(xy 435.246128 -271.489776) (xy 435.218363 -271.3438) (xy 435.198473 -271.196543) (xy 435.186516 -271.04843)
			(xy 435.182527 -270.89989) (xy 380.716536 -270.89989) (xy 380.716037 -270.974187) (xy 380.708061 -271.122567)
			(xy 380.692132 -271.270305) (xy 380.668296 -271.416974) (xy 380.636622 -271.562153) (xy 380.5972 -271.705423)
			(xy 380.550145 -271.84637) (xy 380.495592 -271.984587) (xy 380.433699 -272.119678) (xy 380.364644 -272.251251)
			(xy 380.288626 -272.378929) (xy 380.205865 -272.502341) (xy 380.116598 -272.621134) (xy 380.021084 -272.734963)
			(xy 379.919597 -272.843502) (xy 379.81243 -272.946437) (xy 379.699893 -273.043471) (xy 379.58231 -273.134324)
			(xy 379.46002 -273.218735) (xy 379.333375 -273.29646) (xy 379.20274 -273.367276) (xy 379.068493 -273.430977)
			(xy 378.93102 -273.48738) (xy 378.790717 -273.536323) (xy 378.64799 -273.577665) (xy 378.503249 -273.611285)
			(xy 378.356913 -273.637088) (xy 378.209402 -273.654999) (xy 378.061143 -273.664967) (xy 377.912562 -273.666962)
			(xy 377.764089 -273.660978) (xy 377.61615 -273.647034) (xy 377.469174 -273.625169) (xy 377.323583 -273.595447)
			(xy 377.179797 -273.557952) (xy 377.038231 -273.512793) (xy 376.899293 -273.460101) (xy 376.763384 -273.400027)
			(xy 376.630895 -273.332745) (xy 376.502209 -273.258448) (xy 376.377696 -273.177351) (xy 376.257716 -273.089687)
			(xy 376.142615 -272.995709) (xy 376.032723 -272.895689) (xy 375.928359 -272.789914) (xy 375.829823 -272.67869)
			(xy 375.737399 -272.562337) (xy 375.651354 -272.44119) (xy 375.571936 -272.3156) (xy 375.499373 -272.185928)
			(xy 375.433875 -272.052548) (xy 375.375631 -271.915845) (xy 375.324809 -271.776212) (xy 375.281555 -271.634053)
			(xy 375.245994 -271.489776) (xy 375.218229 -271.3438) (xy 375.198339 -271.196543) (xy 375.186382 -271.04843)
			(xy 375.182393 -270.89989) (xy 324.616572 -270.89989) (xy 324.616073 -270.974187) (xy 324.608097 -271.122567)
			(xy 324.592168 -271.270305) (xy 324.568332 -271.416974) (xy 324.536658 -271.562153) (xy 324.497236 -271.705423)
			(xy 324.450181 -271.84637) (xy 324.395628 -271.984587) (xy 324.333735 -272.119678) (xy 324.26468 -272.251251)
			(xy 324.188662 -272.378929) (xy 324.105901 -272.502341) (xy 324.016634 -272.621134) (xy 323.92112 -272.734963)
			(xy 323.819633 -272.843502) (xy 323.712466 -272.946437) (xy 323.599929 -273.043471) (xy 323.482346 -273.134324)
			(xy 323.360056 -273.218735) (xy 323.233411 -273.29646) (xy 323.102776 -273.367276) (xy 322.968529 -273.430977)
			(xy 322.831056 -273.48738) (xy 322.690753 -273.536323) (xy 322.548026 -273.577665) (xy 322.403285 -273.611285)
			(xy 322.256949 -273.637088) (xy 322.109438 -273.654999) (xy 321.961179 -273.664967) (xy 321.812598 -273.666962)
			(xy 321.664125 -273.660978) (xy 321.516186 -273.647034) (xy 321.36921 -273.625169) (xy 321.223619 -273.595447)
			(xy 321.079833 -273.557952) (xy 320.938267 -273.512793) (xy 320.799329 -273.460101) (xy 320.66342 -273.400027)
			(xy 320.530931 -273.332745) (xy 320.402245 -273.258448) (xy 320.277732 -273.177351) (xy 320.157752 -273.089687)
			(xy 320.042651 -272.995709) (xy 319.932759 -272.895689) (xy 319.828395 -272.789914) (xy 319.729859 -272.67869)
			(xy 319.637435 -272.562337) (xy 319.55139 -272.44119) (xy 319.471972 -272.3156) (xy 319.399409 -272.185928)
			(xy 319.333911 -272.052548) (xy 319.275667 -271.915845) (xy 319.224845 -271.776212) (xy 319.181591 -271.634053)
			(xy 319.14603 -271.489776) (xy 319.118265 -271.3438) (xy 319.098375 -271.196543) (xy 319.086418 -271.04843)
			(xy 319.082429 -270.89989) (xy 264.616692 -270.89989) (xy 264.616193 -270.974187) (xy 264.608217 -271.122567)
			(xy 264.592288 -271.270305) (xy 264.568452 -271.416974) (xy 264.536778 -271.562153) (xy 264.497356 -271.705423)
			(xy 264.450301 -271.84637) (xy 264.395748 -271.984587) (xy 264.333855 -272.119678) (xy 264.2648 -272.251251)
			(xy 264.188782 -272.378929) (xy 264.106021 -272.502341) (xy 264.016754 -272.621134) (xy 263.92124 -272.734963)
			(xy 263.819753 -272.843502) (xy 263.712586 -272.946437) (xy 263.600049 -273.043471) (xy 263.482466 -273.134324)
			(xy 263.360176 -273.218735) (xy 263.233531 -273.29646) (xy 263.102896 -273.367276) (xy 262.968649 -273.430977)
			(xy 262.831176 -273.48738) (xy 262.690873 -273.536323) (xy 262.548146 -273.577665) (xy 262.403405 -273.611285)
			(xy 262.257069 -273.637088) (xy 262.109558 -273.654999) (xy 261.961299 -273.664967) (xy 261.812718 -273.666962)
			(xy 261.664245 -273.660978) (xy 261.516306 -273.647034) (xy 261.36933 -273.625169) (xy 261.223739 -273.595447)
			(xy 261.079953 -273.557952) (xy 260.938387 -273.512793) (xy 260.799449 -273.460101) (xy 260.66354 -273.400027)
			(xy 260.531051 -273.332745) (xy 260.402365 -273.258448) (xy 260.277852 -273.177351) (xy 260.157872 -273.089687)
			(xy 260.042771 -272.995709) (xy 259.932879 -272.895689) (xy 259.828515 -272.789914) (xy 259.729979 -272.67869)
			(xy 259.637555 -272.562337) (xy 259.55151 -272.44119) (xy 259.472092 -272.3156) (xy 259.399529 -272.185928)
			(xy 259.334031 -272.052548) (xy 259.275787 -271.915845) (xy 259.224965 -271.776212) (xy 259.181711 -271.634053)
			(xy 259.14615 -271.489776) (xy 259.118385 -271.3438) (xy 259.098495 -271.196543) (xy 259.086538 -271.04843)
			(xy 259.082549 -270.89989) (xy 208.516474 -270.89989) (xy 208.515975 -270.974187) (xy 208.507999 -271.122567)
			(xy 208.49207 -271.270305) (xy 208.468234 -271.416974) (xy 208.43656 -271.562153) (xy 208.397138 -271.705423)
			(xy 208.350083 -271.84637) (xy 208.29553 -271.984587) (xy 208.233637 -272.119678) (xy 208.164582 -272.251251)
			(xy 208.088564 -272.378929) (xy 208.005803 -272.502341) (xy 207.916536 -272.621134) (xy 207.821022 -272.734963)
			(xy 207.719535 -272.843502) (xy 207.612368 -272.946437) (xy 207.499831 -273.043471) (xy 207.382248 -273.134324)
			(xy 207.259958 -273.218735) (xy 207.133313 -273.29646) (xy 207.002678 -273.367276) (xy 206.868431 -273.430977)
			(xy 206.730958 -273.48738) (xy 206.590655 -273.536323) (xy 206.447928 -273.577665) (xy 206.303187 -273.611285)
			(xy 206.156851 -273.637088) (xy 206.00934 -273.654999) (xy 205.861081 -273.664967) (xy 205.7125 -273.666962)
			(xy 205.564027 -273.660978) (xy 205.416088 -273.647034) (xy 205.269112 -273.625169) (xy 205.123521 -273.595447)
			(xy 204.979735 -273.557952) (xy 204.838169 -273.512793) (xy 204.699231 -273.460101) (xy 204.563322 -273.400027)
			(xy 204.430833 -273.332745) (xy 204.302147 -273.258448) (xy 204.177634 -273.177351) (xy 204.057654 -273.089687)
			(xy 203.942553 -272.995709) (xy 203.832661 -272.895689) (xy 203.728297 -272.789914) (xy 203.629761 -272.67869)
			(xy 203.537337 -272.562337) (xy 203.451292 -272.44119) (xy 203.371874 -272.3156) (xy 203.299311 -272.185928)
			(xy 203.233813 -272.052548) (xy 203.175569 -271.915845) (xy 203.124747 -271.776212) (xy 203.081493 -271.634053)
			(xy 203.045932 -271.489776) (xy 203.018167 -271.3438) (xy 202.998277 -271.196543) (xy 202.98632 -271.04843)
			(xy 202.982331 -270.89989) (xy 148.516594 -270.89989) (xy 148.516095 -270.974187) (xy 148.508119 -271.122567)
			(xy 148.49219 -271.270305) (xy 148.468354 -271.416974) (xy 148.43668 -271.562153) (xy 148.397258 -271.705423)
			(xy 148.350203 -271.84637) (xy 148.29565 -271.984587) (xy 148.233757 -272.119678) (xy 148.164702 -272.251251)
			(xy 148.088684 -272.378929) (xy 148.005923 -272.502341) (xy 147.916656 -272.621134) (xy 147.821142 -272.734963)
			(xy 147.719655 -272.843502) (xy 147.612488 -272.946437) (xy 147.499951 -273.043471) (xy 147.382368 -273.134324)
			(xy 147.260078 -273.218735) (xy 147.133433 -273.29646) (xy 147.002798 -273.367276) (xy 146.868551 -273.430977)
			(xy 146.731078 -273.48738) (xy 146.590775 -273.536323) (xy 146.448048 -273.577665) (xy 146.303307 -273.611285)
			(xy 146.156971 -273.637088) (xy 146.00946 -273.654999) (xy 145.861201 -273.664967) (xy 145.71262 -273.666962)
			(xy 145.564147 -273.660978) (xy 145.416208 -273.647034) (xy 145.269232 -273.625169) (xy 145.123641 -273.595447)
			(xy 144.979855 -273.557952) (xy 144.838289 -273.512793) (xy 144.699351 -273.460101) (xy 144.563442 -273.400027)
			(xy 144.430953 -273.332745) (xy 144.302267 -273.258448) (xy 144.177754 -273.177351) (xy 144.057774 -273.089687)
			(xy 143.942673 -272.995709) (xy 143.832781 -272.895689) (xy 143.728417 -272.789914) (xy 143.629881 -272.67869)
			(xy 143.537457 -272.562337) (xy 143.451412 -272.44119) (xy 143.371994 -272.3156) (xy 143.299431 -272.185928)
			(xy 143.233933 -272.052548) (xy 143.175689 -271.915845) (xy 143.124867 -271.776212) (xy 143.081613 -271.634053)
			(xy 143.046052 -271.489776) (xy 143.018287 -271.3438) (xy 142.998397 -271.196543) (xy 142.98644 -271.04843)
			(xy 142.982451 -270.89989) (xy 92.41663 -270.89989) (xy 92.416131 -270.974187) (xy 92.408155 -271.122567)
			(xy 92.392226 -271.270305) (xy 92.36839 -271.416974) (xy 92.336716 -271.562153) (xy 92.297294 -271.705423)
			(xy 92.250239 -271.84637) (xy 92.195686 -271.984587) (xy 92.133793 -272.119678) (xy 92.064738 -272.251251)
			(xy 91.98872 -272.378929) (xy 91.905959 -272.502341) (xy 91.816692 -272.621134) (xy 91.721178 -272.734963)
			(xy 91.619691 -272.843502) (xy 91.512524 -272.946437) (xy 91.399987 -273.043471) (xy 91.282404 -273.134324)
			(xy 91.160114 -273.218735) (xy 91.033469 -273.29646) (xy 90.902834 -273.367276) (xy 90.768587 -273.430977)
			(xy 90.631114 -273.48738) (xy 90.490811 -273.536323) (xy 90.348084 -273.577665) (xy 90.203343 -273.611285)
			(xy 90.057007 -273.637088) (xy 89.909496 -273.654999) (xy 89.761237 -273.664967) (xy 89.612656 -273.666962)
			(xy 89.464183 -273.660978) (xy 89.316244 -273.647034) (xy 89.169268 -273.625169) (xy 89.023677 -273.595447)
			(xy 88.879891 -273.557952) (xy 88.738325 -273.512793) (xy 88.599387 -273.460101) (xy 88.463478 -273.400027)
			(xy 88.330989 -273.332745) (xy 88.202303 -273.258448) (xy 88.07779 -273.177351) (xy 87.95781 -273.089687)
			(xy 87.842709 -272.995709) (xy 87.732817 -272.895689) (xy 87.628453 -272.789914) (xy 87.529917 -272.67869)
			(xy 87.437493 -272.562337) (xy 87.351448 -272.44119) (xy 87.27203 -272.3156) (xy 87.199467 -272.185928)
			(xy 87.133969 -272.052548) (xy 87.075725 -271.915845) (xy 87.024903 -271.776212) (xy 86.981649 -271.634053)
			(xy 86.946088 -271.489776) (xy 86.918323 -271.3438) (xy 86.898433 -271.196543) (xy 86.886476 -271.04843)
			(xy 86.882487 -270.89989) (xy 32.416496 -270.89989) (xy 32.415997 -270.974187) (xy 32.408021 -271.122567)
			(xy 32.392092 -271.270305) (xy 32.368256 -271.416974) (xy 32.336582 -271.562153) (xy 32.29716 -271.705423)
			(xy 32.250105 -271.84637) (xy 32.195552 -271.984587) (xy 32.133659 -272.119678) (xy 32.064604 -272.251251)
			(xy 31.988586 -272.378929) (xy 31.905825 -272.502341) (xy 31.816558 -272.621134) (xy 31.721044 -272.734963)
			(xy 31.619557 -272.843502) (xy 31.51239 -272.946437) (xy 31.399853 -273.043471) (xy 31.28227 -273.134324)
			(xy 31.15998 -273.218735) (xy 31.033335 -273.29646) (xy 30.9027 -273.367276) (xy 30.768453 -273.430977)
			(xy 30.63098 -273.48738) (xy 30.490677 -273.536323) (xy 30.34795 -273.577665) (xy 30.203209 -273.611285)
			(xy 30.056873 -273.637088) (xy 29.909362 -273.654999) (xy 29.761103 -273.664967) (xy 29.612522 -273.666962)
			(xy 29.464049 -273.660978) (xy 29.31611 -273.647034) (xy 29.169134 -273.625169) (xy 29.023543 -273.595447)
			(xy 28.879757 -273.557952) (xy 28.738191 -273.512793) (xy 28.599253 -273.460101) (xy 28.463344 -273.400027)
			(xy 28.330855 -273.332745) (xy 28.202169 -273.258448) (xy 28.077656 -273.177351) (xy 27.957676 -273.089687)
			(xy 27.842575 -272.995709) (xy 27.732683 -272.895689) (xy 27.628319 -272.789914) (xy 27.529783 -272.67869)
			(xy 27.437359 -272.562337) (xy 27.351314 -272.44119) (xy 27.271896 -272.3156) (xy 27.199333 -272.185928)
			(xy 27.133835 -272.052548) (xy 27.075591 -271.915845) (xy 27.024769 -271.776212) (xy 26.981515 -271.634053)
			(xy 26.945954 -271.489776) (xy 26.918189 -271.3438) (xy 26.898299 -271.196543) (xy 26.886342 -271.04843)
			(xy 26.882353 -270.89989) (xy 0.509016 -270.89989) (xy 0.509016 -287.850408) (xy 37.944539 -287.850408)
			(xy 37.944539 -287.798392) (xy 37.952677 -287.747016) (xy 37.968751 -287.697546) (xy 37.992366 -287.651199)
			(xy 38.02294 -287.609117) (xy 38.059722 -287.572337) (xy 38.101804 -287.541763) (xy 38.148151 -287.518148)
			(xy 38.197622 -287.502075) (xy 38.248998 -287.493939) (xy 38.275006 -287.493456) (xy 39.224966 -287.493456)
			(xy 39.250978 -287.493901) (xy 39.302363 -287.502035) (xy 39.351843 -287.518107) (xy 39.398199 -287.541722)
			(xy 39.44029 -287.572299) (xy 39.477079 -287.609084) (xy 39.50766 -287.651172) (xy 39.53128 -287.697525)
			(xy 39.547357 -287.747004) (xy 39.555496 -287.798388) (xy 39.555496 -287.850405) (xy 40.794466 -287.850405)
			(xy 40.794466 -287.798395) (xy 40.802602 -287.747025) (xy 40.818674 -287.697561) (xy 40.842285 -287.651219)
			(xy 40.872855 -287.609142) (xy 40.909631 -287.572364) (xy 40.951707 -287.541792) (xy 40.998048 -287.518179)
			(xy 41.047512 -287.502105) (xy 41.098881 -287.493967) (xy 41.124886 -287.493456) (xy 42.074846 -287.493456)
			(xy 42.100852 -287.493934) (xy 42.152223 -287.502077) (xy 42.201688 -287.518155) (xy 42.248029 -287.541773)
			(xy 42.290106 -287.572348) (xy 42.326882 -287.609129) (xy 42.357451 -287.65121) (xy 42.381063 -287.697554)
			(xy 42.397134 -287.747022) (xy 42.40527 -287.798394) (xy 42.40527 -287.850406) (xy 42.397134 -287.901778)
			(xy 42.381063 -287.951246) (xy 42.357451 -287.99759) (xy 42.326882 -288.039671) (xy 42.290106 -288.076452)
			(xy 42.248029 -288.107027) (xy 42.201688 -288.130645) (xy 42.152223 -288.146723) (xy 42.100852 -288.154866)
			(xy 42.074846 -288.15538) (xy 41.124886 -288.15538) (xy 41.098881 -288.154833) (xy 41.047512 -288.146695)
			(xy 40.998048 -288.130621) (xy 40.951707 -288.107008) (xy 40.909631 -288.076436) (xy 40.872855 -288.039658)
			(xy 40.842285 -287.997581) (xy 40.818674 -287.951239) (xy 40.802602 -287.901775) (xy 40.794466 -287.850405)
			(xy 39.555496 -287.850405) (xy 39.555496 -287.850412) (xy 39.547357 -287.901796) (xy 39.53128 -287.951275)
			(xy 39.50766 -287.997628) (xy 39.477079 -288.039716) (xy 39.44029 -288.076501) (xy 39.398199 -288.107078)
			(xy 39.351843 -288.130693) (xy 39.302363 -288.146765) (xy 39.250978 -288.154899) (xy 39.224966 -288.15538)
			(xy 38.275006 -288.15538) (xy 38.248998 -288.154861) (xy 38.197622 -288.146725) (xy 38.148151 -288.130652)
			(xy 38.101804 -288.107037) (xy 38.059722 -288.076463) (xy 38.02294 -288.039683) (xy 37.992366 -287.997601)
			(xy 37.968751 -287.951254) (xy 37.952677 -287.901784) (xy 37.944539 -287.850408) (xy 0.509016 -287.850408)
			(xy 0.509016 -288.800413) (xy 36.0443 -288.800413) (xy 36.0443 -288.748387) (xy 36.052439 -288.697003)
			(xy 36.068516 -288.647524) (xy 36.092136 -288.60117) (xy 36.122718 -288.559082) (xy 36.159507 -288.522297)
			(xy 36.201598 -288.49172) (xy 36.247954 -288.468104) (xy 36.297434 -288.452031) (xy 36.348819 -288.443897)
			(xy 36.374832 -288.443416) (xy 37.324792 -288.443416) (xy 37.3508 -288.443943) (xy 37.402175 -288.452079)
			(xy 37.451646 -288.468151) (xy 37.497993 -288.491765) (xy 37.540075 -288.522339) (xy 37.576856 -288.559119)
			(xy 37.60743 -288.601201) (xy 37.631045 -288.647547) (xy 37.647119 -288.697017) (xy 37.655257 -288.748392)
			(xy 37.655257 -288.800408) (xy 37.655257 -288.800411) (xy 42.694299 -288.800411) (xy 42.694299 -288.748389)
			(xy 42.702438 -288.697007) (xy 42.718514 -288.64753) (xy 42.742132 -288.601178) (xy 42.77271 -288.559091)
			(xy 42.809496 -288.522306) (xy 42.851583 -288.491729) (xy 42.897936 -288.468111) (xy 42.947413 -288.452036)
			(xy 42.998795 -288.443899) (xy 43.024806 -288.443416) (xy 43.974766 -288.443416) (xy 44.000775 -288.443941)
			(xy 44.052154 -288.452074) (xy 44.101628 -288.468144) (xy 44.147978 -288.491757) (xy 44.190064 -288.52233)
			(xy 44.226848 -288.55911) (xy 44.257426 -288.601193) (xy 44.281043 -288.647541) (xy 44.297119 -288.697013)
			(xy 44.305257 -288.748391) (xy 44.305257 -288.800409) (xy 44.297119 -288.851787) (xy 44.281043 -288.901259)
			(xy 44.257426 -288.947607) (xy 44.226848 -288.98969) (xy 44.190064 -289.02647) (xy 44.147978 -289.057043)
			(xy 44.101628 -289.080656) (xy 44.052154 -289.096726) (xy 44.000775 -289.104859) (xy 43.974766 -289.10534)
			(xy 43.024806 -289.10534) (xy 42.998795 -289.104901) (xy 42.947413 -289.096764) (xy 42.897936 -289.080689)
			(xy 42.851583 -289.057071) (xy 42.809496 -289.026494) (xy 42.77271 -288.989709) (xy 42.742132 -288.947622)
			(xy 42.718514 -288.90127) (xy 42.702438 -288.851793) (xy 42.694299 -288.800411) (xy 37.655257 -288.800411)
			(xy 37.647119 -288.851783) (xy 37.631045 -288.901253) (xy 37.60743 -288.947599) (xy 37.576856 -288.989681)
			(xy 37.540075 -289.026461) (xy 37.497993 -289.057035) (xy 37.451646 -289.080649) (xy 37.402175 -289.096721)
			(xy 37.3508 -289.104857) (xy 37.324792 -289.10534) (xy 36.374832 -289.10534) (xy 36.348819 -289.104903)
			(xy 36.297434 -289.096769) (xy 36.247954 -289.080696) (xy 36.201598 -289.05708) (xy 36.159507 -289.026503)
			(xy 36.122718 -288.989718) (xy 36.092136 -288.94763) (xy 36.068516 -288.901276) (xy 36.052439 -288.851797)
			(xy 36.0443 -288.800413) (xy 0.509016 -288.800413) (xy 0.509016 -297.350788) (xy 36.044382 -297.350788)
			(xy 36.044382 -297.298812) (xy 36.052512 -297.247477) (xy 36.068572 -297.198045) (xy 36.092168 -297.151734)
			(xy 36.122717 -297.109685) (xy 36.159468 -297.072931) (xy 36.201516 -297.042379) (xy 36.247825 -297.018781)
			(xy 36.297255 -297.002717) (xy 36.34859 -296.994583) (xy 36.374578 -296.994072) (xy 37.324538 -296.994072)
			(xy 37.350522 -296.994624) (xy 37.401848 -297.002759) (xy 37.451271 -297.018822) (xy 37.497572 -297.042419)
			(xy 37.539613 -297.072968) (xy 37.576357 -297.109716) (xy 37.606901 -297.15176) (xy 37.630492 -297.198064)
			(xy 37.64655 -297.247489) (xy 37.654679 -297.298816) (xy 37.654679 -297.350784) (xy 37.654678 -297.350788)
			(xy 152.144482 -297.350788) (xy 152.144482 -297.298812) (xy 152.152612 -297.247477) (xy 152.168672 -297.198046)
			(xy 152.192268 -297.151735) (xy 152.222816 -297.109685) (xy 152.259567 -297.072932) (xy 152.301615 -297.04238)
			(xy 152.347923 -297.018782) (xy 152.397354 -297.002717) (xy 152.448688 -296.994583) (xy 152.474676 -296.994072)
			(xy 153.424636 -296.994072) (xy 153.45062 -296.994624) (xy 153.501947 -297.002759) (xy 153.55137 -297.018822)
			(xy 153.597671 -297.042418) (xy 153.639712 -297.072967) (xy 153.676457 -297.109715) (xy 153.707001 -297.151759)
			(xy 153.730592 -297.198064) (xy 153.74665 -297.247488) (xy 153.754779 -297.298816) (xy 153.754779 -297.350784)
			(xy 153.754778 -297.350792) (xy 268.244255 -297.350792) (xy 268.244255 -297.298808) (xy 268.252388 -297.247465)
			(xy 268.268452 -297.198025) (xy 268.292053 -297.151708) (xy 268.322609 -297.109653) (xy 268.359368 -297.072896)
			(xy 268.401425 -297.042342) (xy 268.447744 -297.018744) (xy 268.497184 -297.002683) (xy 268.548528 -296.994554)
			(xy 268.57452 -296.994072) (xy 269.52448 -296.994072) (xy 269.550469 -296.994594) (xy 269.601807 -297.002722)
			(xy 269.651241 -297.018781) (xy 269.697554 -297.042377) (xy 269.739606 -297.072927) (xy 269.77636 -297.109679)
			(xy 269.806913 -297.151729) (xy 269.830511 -297.198041) (xy 269.846573 -297.247474) (xy 269.854705 -297.298811)
			(xy 269.854705 -297.350789) (xy 269.854705 -297.350792) (xy 384.344355 -297.350792) (xy 384.344355 -297.298808)
			(xy 384.352488 -297.247465) (xy 384.368552 -297.198026) (xy 384.392153 -297.151709) (xy 384.422709 -297.109654)
			(xy 384.459467 -297.072897) (xy 384.501524 -297.042343) (xy 384.547842 -297.018745) (xy 384.597282 -297.002683)
			(xy 384.648626 -296.994554) (xy 384.674618 -296.994072) (xy 385.624578 -296.994072) (xy 385.650567 -296.994593)
			(xy 385.701905 -297.002721) (xy 385.751339 -297.018781) (xy 385.797653 -297.042376) (xy 385.839705 -297.072926)
			(xy 385.87646 -297.109678) (xy 385.907013 -297.151728) (xy 385.930611 -297.19804) (xy 385.946673 -297.247474)
			(xy 385.954805 -297.298811) (xy 385.954805 -297.350789) (xy 385.946673 -297.402126) (xy 385.930611 -297.45156)
			(xy 385.907013 -297.497872) (xy 385.87646 -297.539922) (xy 385.839705 -297.576674) (xy 385.797653 -297.607224)
			(xy 385.751339 -297.630819) (xy 385.701905 -297.646879) (xy 385.650567 -297.655007) (xy 385.624578 -297.655488)
			(xy 384.674618 -297.655488) (xy 384.648626 -297.655046) (xy 384.597282 -297.646917) (xy 384.547842 -297.630855)
			(xy 384.501524 -297.607257) (xy 384.459467 -297.576703) (xy 384.422709 -297.539946) (xy 384.392153 -297.497891)
			(xy 384.368552 -297.451574) (xy 384.352488 -297.402135) (xy 384.344355 -297.350792) (xy 269.854705 -297.350792)
			(xy 269.846573 -297.402126) (xy 269.830511 -297.451559) (xy 269.806913 -297.497871) (xy 269.77636 -297.539921)
			(xy 269.739606 -297.576673) (xy 269.697554 -297.607223) (xy 269.651241 -297.630819) (xy 269.601807 -297.646878)
			(xy 269.550469 -297.655006) (xy 269.52448 -297.655488) (xy 268.57452 -297.655488) (xy 268.548528 -297.655046)
			(xy 268.497184 -297.646917) (xy 268.447744 -297.630856) (xy 268.401425 -297.607258) (xy 268.359368 -297.576704)
			(xy 268.322609 -297.539947) (xy 268.292053 -297.497892) (xy 268.268452 -297.451575) (xy 268.252388 -297.402135)
			(xy 268.244255 -297.350792) (xy 153.754778 -297.350792) (xy 153.74665 -297.402112) (xy 153.730592 -297.451536)
			(xy 153.707001 -297.497841) (xy 153.676457 -297.539885) (xy 153.639712 -297.576633) (xy 153.597671 -297.607182)
			(xy 153.55137 -297.630778) (xy 153.501947 -297.646841) (xy 153.45062 -297.654976) (xy 153.424636 -297.655488)
			(xy 152.474676 -297.655488) (xy 152.448688 -297.655017) (xy 152.397354 -297.646883) (xy 152.347923 -297.630818)
			(xy 152.301615 -297.60722) (xy 152.259567 -297.576668) (xy 152.222816 -297.539915) (xy 152.192268 -297.497865)
			(xy 152.168672 -297.451554) (xy 152.152612 -297.402123) (xy 152.144482 -297.350788) (xy 37.654678 -297.350788)
			(xy 37.64655 -297.402111) (xy 37.630492 -297.451536) (xy 37.606901 -297.49784) (xy 37.576357 -297.539884)
			(xy 37.539613 -297.576632) (xy 37.497572 -297.607181) (xy 37.451271 -297.630778) (xy 37.401848 -297.646841)
			(xy 37.350522 -297.654976) (xy 37.324538 -297.655488) (xy 36.374578 -297.655488) (xy 36.34859 -297.655017)
			(xy 36.297255 -297.646883) (xy 36.247825 -297.630819) (xy 36.201516 -297.607221) (xy 36.159468 -297.576669)
			(xy 36.122717 -297.539915) (xy 36.092168 -297.497866) (xy 36.068572 -297.451555) (xy 36.052512 -297.402123)
			(xy 36.044382 -297.350788) (xy 0.509016 -297.350788) (xy 0.509016 -298.77569) (xy 39.369695 -298.77569)
			(xy 39.369695 -298.72371) (xy 39.377827 -298.67237) (xy 39.393891 -298.622935) (xy 39.417492 -298.576621)
			(xy 39.448047 -298.53457) (xy 39.484805 -298.497817) (xy 39.52686 -298.467268) (xy 39.573177 -298.443674)
			(xy 39.622615 -298.427617) (xy 39.673956 -298.419492) (xy 39.699946 -298.419012) (xy 40.649906 -298.419012)
			(xy 40.675894 -298.419482) (xy 40.727231 -298.427614) (xy 40.776664 -298.443676) (xy 40.822975 -298.467274)
			(xy 40.865025 -298.497826) (xy 40.901778 -298.534579) (xy 40.932329 -298.57663) (xy 40.955926 -298.622942)
			(xy 40.971988 -298.672375) (xy 40.980118 -298.723712) (xy 40.980118 -298.775685) (xy 387.669821 -298.775685)
			(xy 387.669821 -298.723715) (xy 387.677951 -298.672385) (xy 387.69401 -298.622959) (xy 387.717603 -298.576653)
			(xy 387.74815 -298.534608) (xy 387.784897 -298.497859) (xy 387.826941 -298.467311) (xy 387.873246 -298.443716)
			(xy 387.922671 -298.427654) (xy 387.974001 -298.419523) (xy 387.999986 -298.419012) (xy 388.949946 -298.419012)
			(xy 388.975932 -298.419485) (xy 389.027264 -298.427622) (xy 389.076692 -298.443688) (xy 389.122998 -298.467288)
			(xy 389.165042 -298.49784) (xy 389.20179 -298.534593) (xy 389.232337 -298.576642) (xy 389.25593 -298.622951)
			(xy 389.271989 -298.67238) (xy 389.280119 -298.723714) (xy 389.280119 -298.775686) (xy 389.271989 -298.82702)
			(xy 389.25593 -298.876449) (xy 389.232337 -298.922758) (xy 389.20179 -298.964807) (xy 389.165042 -299.00156)
			(xy 389.122998 -299.032112) (xy 389.076692 -299.055712) (xy 389.027264 -299.071778) (xy 388.975932 -299.079915)
			(xy 388.949946 -299.080428) (xy 387.999986 -299.080428) (xy 387.974001 -299.079877) (xy 387.922671 -299.071746)
			(xy 387.873246 -299.055684) (xy 387.826941 -299.032089) (xy 387.784897 -299.001541) (xy 387.74815 -298.964792)
			(xy 387.717603 -298.922747) (xy 387.69401 -298.876441) (xy 387.677951 -298.827015) (xy 387.669821 -298.775685)
			(xy 40.980118 -298.775685) (xy 40.980118 -298.775688) (xy 40.971988 -298.827025) (xy 40.955926 -298.876458)
			(xy 40.932329 -298.92277) (xy 40.901778 -298.964821) (xy 40.865025 -299.001574) (xy 40.822975 -299.032126)
			(xy 40.776664 -299.055724) (xy 40.727231 -299.071786) (xy 40.675894 -299.079918) (xy 40.649906 -299.080428)
			(xy 39.699946 -299.080428) (xy 39.673956 -299.079908) (xy 39.622615 -299.071783) (xy 39.573177 -299.055726)
			(xy 39.52686 -299.032132) (xy 39.484805 -299.001583) (xy 39.448047 -298.96483) (xy 39.417492 -298.922779)
			(xy 39.393891 -298.876465) (xy 39.377827 -298.82703) (xy 39.369695 -298.77569) (xy 0.509016 -298.77569)
			(xy 0.509016 -299.25101) (xy 36.044102 -299.25101) (xy 36.044102 -299.19899) (xy 36.052239 -299.147611)
			(xy 36.068313 -299.098138) (xy 36.091929 -299.051788) (xy 36.122504 -299.009703) (xy 36.159286 -298.972918)
			(xy 36.201369 -298.94234) (xy 36.247718 -298.918722) (xy 36.29719 -298.902644) (xy 36.348568 -298.894504)
			(xy 36.374578 -298.893992) (xy 37.324538 -298.893992) (xy 37.35054 -298.894597) (xy 37.401902 -298.902737)
			(xy 37.451358 -298.918812) (xy 37.497691 -298.942425) (xy 37.539761 -298.972994) (xy 37.576531 -299.009768)
			(xy 37.607095 -299.051841) (xy 37.630703 -299.098177) (xy 37.646771 -299.147635) (xy 37.654906 -299.198998)
			(xy 37.654906 -299.251002) (xy 37.654905 -299.25101) (xy 152.144202 -299.25101) (xy 152.144202 -299.19899)
			(xy 152.152339 -299.147612) (xy 152.168413 -299.098138) (xy 152.192028 -299.051788) (xy 152.222603 -299.009703)
			(xy 152.259385 -298.972919) (xy 152.301468 -298.942341) (xy 152.347816 -298.918722) (xy 152.397288 -298.902645)
			(xy 152.448666 -298.894504) (xy 152.474676 -298.893992) (xy 153.424636 -298.893992) (xy 153.450638 -298.894597)
			(xy 153.502 -298.902737) (xy 153.551457 -298.918811) (xy 153.59779 -298.942424) (xy 153.63986 -298.972993)
			(xy 153.67663 -299.009767) (xy 153.707195 -299.05184) (xy 153.730803 -299.098177) (xy 153.746871 -299.147635)
			(xy 153.755006 -299.198998) (xy 153.755006 -299.251002) (xy 153.755005 -299.251009) (xy 154.994602 -299.251009)
			(xy 154.994602 -299.198991) (xy 155.002739 -299.147613) (xy 155.018812 -299.098141) (xy 155.042426 -299.051792)
			(xy 155.073 -299.009707) (xy 155.10978 -298.972923) (xy 155.151861 -298.942345) (xy 155.198208 -298.918726)
			(xy 155.247678 -298.902647) (xy 155.299055 -298.894505) (xy 155.325064 -298.893992) (xy 156.275024 -298.893992)
			(xy 156.301026 -298.894596) (xy 156.35239 -298.902735) (xy 156.401848 -298.918808) (xy 156.448184 -298.94242)
			(xy 156.490255 -298.972989) (xy 156.527026 -299.009763) (xy 156.557593 -299.051837) (xy 156.581201 -299.098174)
			(xy 156.597271 -299.147633) (xy 156.605406 -299.198998) (xy 156.605406 -299.251002) (xy 156.605404 -299.251014)
			(xy 268.243976 -299.251014) (xy 268.243976 -299.198986) (xy 268.252115 -299.147599) (xy 268.268193 -299.098118)
			(xy 268.291814 -299.051761) (xy 268.322396 -299.009671) (xy 268.359186 -298.972883) (xy 268.401279 -298.942303)
			(xy 268.447637 -298.918685) (xy 268.497119 -298.90261) (xy 268.548506 -298.894474) (xy 268.57452 -298.893992)
			(xy 269.52448 -298.893992) (xy 269.550487 -298.894566) (xy 269.60186 -298.9027) (xy 269.651328 -298.91877)
			(xy 269.697673 -298.942382) (xy 269.739754 -298.972953) (xy 269.776534 -299.009731) (xy 269.807108 -299.05181)
			(xy 269.830722 -299.098153) (xy 269.846796 -299.147621) (xy 269.854933 -299.198993) (xy 269.854933 -299.251007)
			(xy 269.854932 -299.251013) (xy 271.094376 -299.251013) (xy 271.094376 -299.198987) (xy 271.102514 -299.147601)
			(xy 271.118592 -299.098121) (xy 271.142212 -299.051765) (xy 271.172792 -299.009675) (xy 271.209581 -298.972887)
			(xy 271.251672 -298.942307) (xy 271.298028 -298.918689) (xy 271.347509 -298.902613) (xy 271.398895 -298.894475)
			(xy 271.424908 -298.893992) (xy 272.374868 -298.893992) (xy 272.400875 -298.894565) (xy 272.45225 -298.902697)
			(xy 272.50172 -298.918767) (xy 272.548067 -298.942378) (xy 272.590149 -298.972949) (xy 272.626931 -299.009727)
			(xy 272.657506 -299.051806) (xy 272.681121 -299.09815) (xy 272.697195 -299.147619) (xy 272.705333 -299.198993)
			(xy 272.705333 -299.251007) (xy 272.705332 -299.251014) (xy 384.344076 -299.251014) (xy 384.344076 -299.198986)
			(xy 384.352215 -299.147599) (xy 384.368293 -299.098118) (xy 384.391913 -299.051762) (xy 384.422495 -299.009672)
			(xy 384.459285 -298.972884) (xy 384.501377 -298.942304) (xy 384.547735 -298.918686) (xy 384.597217 -298.902611)
			(xy 384.648604 -298.894474) (xy 384.674618 -298.893992) (xy 385.624578 -298.893992) (xy 385.650585 -298.894566)
			(xy 385.701958 -298.902699) (xy 385.751427 -298.91877) (xy 385.797772 -298.942381) (xy 385.839853 -298.972952)
			(xy 385.876634 -299.00973) (xy 385.907207 -299.051809) (xy 385.930822 -299.098153) (xy 385.946896 -299.14762)
			(xy 385.955033 -299.198993) (xy 385.955033 -299.251007) (xy 385.946896 -299.30238) (xy 385.930822 -299.351847)
			(xy 385.907207 -299.398191) (xy 385.876634 -299.44027) (xy 385.839853 -299.477048) (xy 385.797772 -299.507619)
			(xy 385.751427 -299.53123) (xy 385.701958 -299.547301) (xy 385.650585 -299.555434) (xy 385.624578 -299.555916)
			(xy 384.674618 -299.555916) (xy 384.648604 -299.555526) (xy 384.597217 -299.547389) (xy 384.547735 -299.531314)
			(xy 384.501377 -299.507696) (xy 384.459285 -299.477116) (xy 384.422495 -299.440328) (xy 384.391913 -299.398238)
			(xy 384.368293 -299.351882) (xy 384.352215 -299.302401) (xy 384.344076 -299.251014) (xy 272.705332 -299.251014)
			(xy 272.697195 -299.302381) (xy 272.681121 -299.35185) (xy 272.657506 -299.398194) (xy 272.626931 -299.440273)
			(xy 272.590149 -299.477051) (xy 272.548067 -299.507622) (xy 272.50172 -299.531233) (xy 272.45225 -299.547303)
			(xy 272.400875 -299.555435) (xy 272.374868 -299.555916) (xy 271.424908 -299.555916) (xy 271.398895 -299.555525)
			(xy 271.347509 -299.547387) (xy 271.298028 -299.531311) (xy 271.251672 -299.507693) (xy 271.209581 -299.477113)
			(xy 271.172792 -299.440325) (xy 271.142212 -299.398235) (xy 271.118592 -299.351879) (xy 271.102514 -299.302399)
			(xy 271.094376 -299.251013) (xy 269.854932 -299.251013) (xy 269.846796 -299.302379) (xy 269.830722 -299.351847)
			(xy 269.807108 -299.39819) (xy 269.776534 -299.440269) (xy 269.739754 -299.477047) (xy 269.697673 -299.507618)
			(xy 269.651328 -299.53123) (xy 269.60186 -299.5473) (xy 269.550487 -299.555434) (xy 269.52448 -299.555916)
			(xy 268.57452 -299.555916) (xy 268.548506 -299.555526) (xy 268.497119 -299.54739) (xy 268.447637 -299.531315)
			(xy 268.401279 -299.507697) (xy 268.359186 -299.477117) (xy 268.322396 -299.440329) (xy 268.291814 -299.398239)
			(xy 268.268193 -299.351882) (xy 268.252115 -299.302401) (xy 268.243976 -299.251014) (xy 156.605404 -299.251014)
			(xy 156.597271 -299.302367) (xy 156.581201 -299.351826) (xy 156.557593 -299.398163) (xy 156.527026 -299.440237)
			(xy 156.490255 -299.477011) (xy 156.448184 -299.50758) (xy 156.401848 -299.531192) (xy 156.35239 -299.547265)
			(xy 156.301026 -299.555404) (xy 156.275024 -299.555916) (xy 155.325064 -299.555916) (xy 155.299055 -299.555495)
			(xy 155.247678 -299.547353) (xy 155.198208 -299.531274) (xy 155.151861 -299.507655) (xy 155.10978 -299.477077)
			(xy 155.073 -299.440293) (xy 155.042426 -299.398208) (xy 155.018812 -299.351859) (xy 155.002739 -299.302387)
			(xy 154.994602 -299.251009) (xy 153.755005 -299.251009) (xy 153.746871 -299.302365) (xy 153.730803 -299.351823)
			(xy 153.707195 -299.39816) (xy 153.67663 -299.440233) (xy 153.63986 -299.477007) (xy 153.59779 -299.507576)
			(xy 153.551457 -299.531189) (xy 153.502 -299.547263) (xy 153.450638 -299.555403) (xy 153.424636 -299.555916)
			(xy 152.474676 -299.555916) (xy 152.448666 -299.555496) (xy 152.397288 -299.547355) (xy 152.347816 -299.531278)
			(xy 152.301468 -299.507659) (xy 152.259385 -299.477081) (xy 152.222603 -299.440297) (xy 152.192028 -299.398212)
			(xy 152.168413 -299.351862) (xy 152.152339 -299.302388) (xy 152.144202 -299.25101) (xy 37.654905 -299.25101)
			(xy 37.646771 -299.302365) (xy 37.630703 -299.351823) (xy 37.607095 -299.398159) (xy 37.576531 -299.440232)
			(xy 37.539761 -299.477006) (xy 37.497691 -299.507575) (xy 37.451358 -299.531188) (xy 37.401902 -299.547263)
			(xy 37.35054 -299.555403) (xy 37.324538 -299.555916) (xy 36.374578 -299.555916) (xy 36.348568 -299.555496)
			(xy 36.29719 -299.547356) (xy 36.247718 -299.531278) (xy 36.201369 -299.50766) (xy 36.159286 -299.477082)
			(xy 36.122504 -299.440297) (xy 36.091929 -299.398212) (xy 36.068313 -299.351862) (xy 36.052239 -299.302389)
			(xy 36.044102 -299.25101) (xy 0.509016 -299.25101) (xy 0.509016 -305.19751) (xy 17.638266 -305.19751)
			(xy 17.642339 -305.141851) (xy 17.654474 -305.087378) (xy 17.67441 -305.035252) (xy 17.701724 -304.986584)
			(xy 17.735832 -304.942412) (xy 17.776009 -304.903677) (xy 17.821397 -304.871205) (xy 17.871029 -304.845687)
			(xy 17.923849 -304.827668) (xy 17.978728 -304.817531) (xy 18.034499 -304.815493) (xy 18.089973 -304.821596)
			(xy 18.143966 -304.835712) (xy 18.195329 -304.857539) (xy 18.242967 -304.886612) (xy 18.285863 -304.922311)
			(xy 18.323105 -304.963875) (xy 18.353899 -305.010419) (xy 18.377587 -305.06095) (xy 18.393665 -305.114392)
			(xy 18.401791 -305.169606) (xy 18.4023 -305.19751) (xy 18.401791 -305.225414) (xy 18.393665 -305.280628)
			(xy 18.377587 -305.33407) (xy 18.353899 -305.384601) (xy 18.323105 -305.431145) (xy 18.285863 -305.472709)
			(xy 18.242967 -305.508408) (xy 18.195329 -305.537481) (xy 18.143966 -305.559308) (xy 18.089973 -305.573424)
			(xy 18.034499 -305.579527) (xy 17.978728 -305.577489) (xy 17.923849 -305.567352) (xy 17.871029 -305.549333)
			(xy 17.821397 -305.523815) (xy 17.776009 -305.491343) (xy 17.735832 -305.452608) (xy 17.701724 -305.408436)
			(xy 17.67441 -305.359768) (xy 17.654474 -305.307642) (xy 17.642339 -305.253169) (xy 17.638266 -305.19751)
			(xy 0.509016 -305.19751) (xy 0.509016 -306.28209) (xy 17.638266 -306.28209) (xy 17.642339 -306.226431)
			(xy 17.654474 -306.171958) (xy 17.67441 -306.119832) (xy 17.701724 -306.071164) (xy 17.735832 -306.026992)
			(xy 17.776009 -305.988257) (xy 17.821397 -305.955785) (xy 17.871029 -305.930267) (xy 17.923849 -305.912248)
			(xy 17.978728 -305.902111) (xy 18.034499 -305.900073) (xy 18.089973 -305.906176) (xy 18.143966 -305.920292)
			(xy 18.195329 -305.942119) (xy 18.242967 -305.971192) (xy 18.285863 -306.006891) (xy 18.323105 -306.048455)
			(xy 18.353899 -306.094999) (xy 18.377587 -306.14553) (xy 18.393665 -306.198972) (xy 18.401791 -306.254186)
			(xy 18.4023 -306.28209) (xy 18.401791 -306.309994) (xy 18.393665 -306.365208) (xy 18.377587 -306.41865)
			(xy 18.353899 -306.469181) (xy 18.323105 -306.515725) (xy 18.285863 -306.557289) (xy 18.242967 -306.592988)
			(xy 18.195329 -306.622061) (xy 18.143966 -306.643888) (xy 18.089973 -306.658004) (xy 18.034499 -306.664107)
			(xy 17.978728 -306.662069) (xy 17.923849 -306.651932) (xy 17.871029 -306.633913) (xy 17.821397 -306.608395)
			(xy 17.776009 -306.575923) (xy 17.735832 -306.537188) (xy 17.701724 -306.493016) (xy 17.67441 -306.444348)
			(xy 17.654474 -306.392222) (xy 17.642339 -306.337749) (xy 17.638266 -306.28209) (xy 0.509016 -306.28209)
			(xy 0.509016 -307.484272) (xy 231.935526 -307.484272) (xy 231.939599 -307.428613) (xy 231.951734 -307.37414)
			(xy 231.97167 -307.322014) (xy 231.998984 -307.273346) (xy 232.033092 -307.229174) (xy 232.073269 -307.190439)
			(xy 232.118657 -307.157967) (xy 232.168289 -307.132449) (xy 232.221109 -307.11443) (xy 232.275988 -307.104293)
			(xy 232.331759 -307.102255) (xy 232.387233 -307.108358) (xy 232.441226 -307.122474) (xy 232.492589 -307.144301)
			(xy 232.540227 -307.173374) (xy 232.583123 -307.209073) (xy 232.620365 -307.250637) (xy 232.651159 -307.297181)
			(xy 232.674847 -307.347712) (xy 232.690925 -307.401154) (xy 232.699051 -307.456368) (xy 232.69956 -307.484272)
			(xy 248.185684 -307.484272) (xy 248.189757 -307.428613) (xy 248.201892 -307.37414) (xy 248.221828 -307.322014)
			(xy 248.249142 -307.273346) (xy 248.28325 -307.229174) (xy 248.323427 -307.190439) (xy 248.368815 -307.157967)
			(xy 248.418447 -307.132449) (xy 248.471267 -307.11443) (xy 248.526146 -307.104293) (xy 248.581917 -307.102255)
			(xy 248.637391 -307.108358) (xy 248.691384 -307.122474) (xy 248.742747 -307.144301) (xy 248.790385 -307.173374)
			(xy 248.833281 -307.209073) (xy 248.870523 -307.250637) (xy 248.901317 -307.297181) (xy 248.925005 -307.347712)
			(xy 248.941083 -307.401154) (xy 248.949209 -307.456368) (xy 248.949718 -307.484272) (xy 248.949209 -307.512176)
			(xy 248.941083 -307.56739) (xy 248.928951 -307.607716) (xy 462.556604 -307.607716) (xy 462.560677 -307.552057)
			(xy 462.572812 -307.497584) (xy 462.592748 -307.445458) (xy 462.620062 -307.39679) (xy 462.65417 -307.352618)
			(xy 462.694347 -307.313883) (xy 462.739735 -307.281411) (xy 462.789367 -307.255893) (xy 462.842187 -307.237874)
			(xy 462.897066 -307.227737) (xy 462.952837 -307.225699) (xy 463.008311 -307.231802) (xy 463.062304 -307.245918)
			(xy 463.113667 -307.267745) (xy 463.161305 -307.296818) (xy 463.204201 -307.332517) (xy 463.241443 -307.374081)
			(xy 463.272237 -307.420625) (xy 463.295925 -307.471156) (xy 463.312003 -307.524598) (xy 463.320129 -307.579812)
			(xy 463.320638 -307.607716) (xy 463.320129 -307.63562) (xy 463.312003 -307.690834) (xy 463.295925 -307.744276)
			(xy 463.272237 -307.794807) (xy 463.241443 -307.841351) (xy 463.204201 -307.882915) (xy 463.161305 -307.918614)
			(xy 463.113667 -307.947687) (xy 463.062304 -307.969514) (xy 463.008311 -307.98363) (xy 462.952837 -307.989733)
			(xy 462.897066 -307.987695) (xy 462.842187 -307.977558) (xy 462.789367 -307.959539) (xy 462.739735 -307.934021)
			(xy 462.694347 -307.901549) (xy 462.65417 -307.862814) (xy 462.620062 -307.818642) (xy 462.592748 -307.769974)
			(xy 462.572812 -307.717848) (xy 462.560677 -307.663375) (xy 462.556604 -307.607716) (xy 248.928951 -307.607716)
			(xy 248.925005 -307.620832) (xy 248.901317 -307.671363) (xy 248.870523 -307.717907) (xy 248.833281 -307.759471)
			(xy 248.790385 -307.79517) (xy 248.742747 -307.824243) (xy 248.691384 -307.84607) (xy 248.637391 -307.860186)
			(xy 248.581917 -307.866289) (xy 248.526146 -307.864251) (xy 248.471267 -307.854114) (xy 248.418447 -307.836095)
			(xy 248.368815 -307.810577) (xy 248.323427 -307.778105) (xy 248.28325 -307.73937) (xy 248.249142 -307.695198)
			(xy 248.221828 -307.64653) (xy 248.201892 -307.594404) (xy 248.189757 -307.539931) (xy 248.185684 -307.484272)
			(xy 232.69956 -307.484272) (xy 232.699051 -307.512176) (xy 232.690925 -307.56739) (xy 232.674847 -307.620832)
			(xy 232.651159 -307.671363) (xy 232.620365 -307.717907) (xy 232.583123 -307.759471) (xy 232.540227 -307.79517)
			(xy 232.492589 -307.824243) (xy 232.441226 -307.84607) (xy 232.387233 -307.860186) (xy 232.331759 -307.866289)
			(xy 232.275988 -307.864251) (xy 232.221109 -307.854114) (xy 232.168289 -307.836095) (xy 232.118657 -307.810577)
			(xy 232.073269 -307.778105) (xy 232.033092 -307.73937) (xy 231.998984 -307.695198) (xy 231.97167 -307.64653)
			(xy 231.951734 -307.594404) (xy 231.939599 -307.539931) (xy 231.935526 -307.484272) (xy 0.509016 -307.484272)
			(xy 0.509016 -308.568852) (xy 231.935526 -308.568852) (xy 231.939599 -308.513193) (xy 231.951734 -308.45872)
			(xy 231.97167 -308.406594) (xy 231.998984 -308.357926) (xy 232.033092 -308.313754) (xy 232.073269 -308.275019)
			(xy 232.118657 -308.242547) (xy 232.168289 -308.217029) (xy 232.221109 -308.19901) (xy 232.275988 -308.188873)
			(xy 232.331759 -308.186835) (xy 232.387233 -308.192938) (xy 232.441226 -308.207054) (xy 232.492589 -308.228881)
			(xy 232.540227 -308.257954) (xy 232.583123 -308.293653) (xy 232.620365 -308.335217) (xy 232.651159 -308.381761)
			(xy 232.674847 -308.432292) (xy 232.690925 -308.485734) (xy 232.699051 -308.540948) (xy 232.69956 -308.568852)
			(xy 248.185684 -308.568852) (xy 248.189757 -308.513193) (xy 248.201892 -308.45872) (xy 248.221828 -308.406594)
			(xy 248.249142 -308.357926) (xy 248.28325 -308.313754) (xy 248.323427 -308.275019) (xy 248.368815 -308.242547)
			(xy 248.418447 -308.217029) (xy 248.471267 -308.19901) (xy 248.526146 -308.188873) (xy 248.581917 -308.186835)
			(xy 248.637391 -308.192938) (xy 248.691384 -308.207054) (xy 248.742747 -308.228881) (xy 248.790385 -308.257954)
			(xy 248.833281 -308.293653) (xy 248.870523 -308.335217) (xy 248.901317 -308.381761) (xy 248.925005 -308.432292)
			(xy 248.941083 -308.485734) (xy 248.949209 -308.540948) (xy 248.949718 -308.568852) (xy 248.949209 -308.596756)
			(xy 248.941083 -308.65197) (xy 248.928951 -308.692296) (xy 462.556604 -308.692296) (xy 462.560677 -308.636637)
			(xy 462.572812 -308.582164) (xy 462.592748 -308.530038) (xy 462.620062 -308.48137) (xy 462.65417 -308.437198)
			(xy 462.694347 -308.398463) (xy 462.739735 -308.365991) (xy 462.789367 -308.340473) (xy 462.842187 -308.322454)
			(xy 462.897066 -308.312317) (xy 462.952837 -308.310279) (xy 463.008311 -308.316382) (xy 463.062304 -308.330498)
			(xy 463.113667 -308.352325) (xy 463.161305 -308.381398) (xy 463.204201 -308.417097) (xy 463.241443 -308.458661)
			(xy 463.272237 -308.505205) (xy 463.295925 -308.555736) (xy 463.312003 -308.609178) (xy 463.320129 -308.664392)
			(xy 463.320638 -308.692296) (xy 463.320129 -308.7202) (xy 463.312003 -308.775414) (xy 463.295925 -308.828856)
			(xy 463.272237 -308.879387) (xy 463.241443 -308.925931) (xy 463.204201 -308.967495) (xy 463.161305 -309.003194)
			(xy 463.113667 -309.032267) (xy 463.062304 -309.054094) (xy 463.008311 -309.06821) (xy 462.952837 -309.074313)
			(xy 462.897066 -309.072275) (xy 462.842187 -309.062138) (xy 462.789367 -309.044119) (xy 462.739735 -309.018601)
			(xy 462.694347 -308.986129) (xy 462.65417 -308.947394) (xy 462.620062 -308.903222) (xy 462.592748 -308.854554)
			(xy 462.572812 -308.802428) (xy 462.560677 -308.747955) (xy 462.556604 -308.692296) (xy 248.928951 -308.692296)
			(xy 248.925005 -308.705412) (xy 248.901317 -308.755943) (xy 248.870523 -308.802487) (xy 248.833281 -308.844051)
			(xy 248.790385 -308.87975) (xy 248.742747 -308.908823) (xy 248.691384 -308.93065) (xy 248.637391 -308.944766)
			(xy 248.581917 -308.950869) (xy 248.526146 -308.948831) (xy 248.471267 -308.938694) (xy 248.418447 -308.920675)
			(xy 248.368815 -308.895157) (xy 248.323427 -308.862685) (xy 248.28325 -308.82395) (xy 248.249142 -308.779778)
			(xy 248.221828 -308.73111) (xy 248.201892 -308.678984) (xy 248.189757 -308.624511) (xy 248.185684 -308.568852)
			(xy 232.69956 -308.568852) (xy 232.699051 -308.596756) (xy 232.690925 -308.65197) (xy 232.674847 -308.705412)
			(xy 232.651159 -308.755943) (xy 232.620365 -308.802487) (xy 232.583123 -308.844051) (xy 232.540227 -308.87975)
			(xy 232.492589 -308.908823) (xy 232.441226 -308.93065) (xy 232.387233 -308.944766) (xy 232.331759 -308.950869)
			(xy 232.275988 -308.948831) (xy 232.221109 -308.938694) (xy 232.168289 -308.920675) (xy 232.118657 -308.895157)
			(xy 232.073269 -308.862685) (xy 232.033092 -308.82395) (xy 231.998984 -308.779778) (xy 231.97167 -308.73111)
			(xy 231.951734 -308.678984) (xy 231.939599 -308.624511) (xy 231.935526 -308.568852) (xy 0.509016 -308.568852)
			(xy 0.509016 -320.900044) (xy 26.882353 -320.900044) (xy 26.886342 -320.751504) (xy 26.898299 -320.603391)
			(xy 26.918189 -320.456134) (xy 26.945954 -320.310158) (xy 26.981515 -320.165881) (xy 27.024769 -320.023722)
			(xy 27.075591 -319.884089) (xy 27.133835 -319.747386) (xy 27.199333 -319.614006) (xy 27.271896 -319.484334)
			(xy 27.351314 -319.358744) (xy 27.437359 -319.237597) (xy 27.529783 -319.121244) (xy 27.628319 -319.01002)
			(xy 27.732683 -318.904245) (xy 27.842575 -318.804225) (xy 27.957676 -318.710247) (xy 28.077656 -318.622583)
			(xy 28.202169 -318.541486) (xy 28.330855 -318.467189) (xy 28.463344 -318.399907) (xy 28.599253 -318.339833)
			(xy 28.738191 -318.287141) (xy 28.879757 -318.241982) (xy 29.023543 -318.204487) (xy 29.169134 -318.174765)
			(xy 29.31611 -318.1529) (xy 29.464049 -318.138956) (xy 29.612522 -318.132972) (xy 29.761103 -318.134967)
			(xy 29.909362 -318.144935) (xy 30.056873 -318.162846) (xy 30.203209 -318.188649) (xy 30.34795 -318.222269)
			(xy 30.490677 -318.263611) (xy 30.63098 -318.312554) (xy 30.768453 -318.368957) (xy 30.9027 -318.432658)
			(xy 31.033335 -318.503474) (xy 31.15998 -318.581199) (xy 31.28227 -318.66561) (xy 31.399853 -318.756463)
			(xy 31.51239 -318.853497) (xy 31.619557 -318.956432) (xy 31.721044 -319.064971) (xy 31.816558 -319.1788)
			(xy 31.905825 -319.297593) (xy 31.988586 -319.421005) (xy 32.064604 -319.548683) (xy 32.133659 -319.680256)
			(xy 32.195552 -319.815347) (xy 32.250105 -319.953564) (xy 32.29716 -320.094511) (xy 32.336582 -320.237781)
			(xy 32.368256 -320.38296) (xy 32.392092 -320.529629) (xy 32.408021 -320.677367) (xy 32.415997 -320.825747)
			(xy 32.416496 -320.900044) (xy 86.882487 -320.900044) (xy 86.886476 -320.751504) (xy 86.898433 -320.603391)
			(xy 86.918323 -320.456134) (xy 86.946088 -320.310158) (xy 86.981649 -320.165881) (xy 87.024903 -320.023722)
			(xy 87.075725 -319.884089) (xy 87.133969 -319.747386) (xy 87.199467 -319.614006) (xy 87.27203 -319.484334)
			(xy 87.351448 -319.358744) (xy 87.437493 -319.237597) (xy 87.529917 -319.121244) (xy 87.628453 -319.01002)
			(xy 87.732817 -318.904245) (xy 87.842709 -318.804225) (xy 87.95781 -318.710247) (xy 88.07779 -318.622583)
			(xy 88.202303 -318.541486) (xy 88.330989 -318.467189) (xy 88.463478 -318.399907) (xy 88.599387 -318.339833)
			(xy 88.738325 -318.287141) (xy 88.879891 -318.241982) (xy 89.023677 -318.204487) (xy 89.169268 -318.174765)
			(xy 89.316244 -318.1529) (xy 89.464183 -318.138956) (xy 89.612656 -318.132972) (xy 89.761237 -318.134967)
			(xy 89.909496 -318.144935) (xy 90.057007 -318.162846) (xy 90.203343 -318.188649) (xy 90.348084 -318.222269)
			(xy 90.490811 -318.263611) (xy 90.631114 -318.312554) (xy 90.768587 -318.368957) (xy 90.902834 -318.432658)
			(xy 91.033469 -318.503474) (xy 91.160114 -318.581199) (xy 91.282404 -318.66561) (xy 91.399987 -318.756463)
			(xy 91.512524 -318.853497) (xy 91.619691 -318.956432) (xy 91.721178 -319.064971) (xy 91.816692 -319.1788)
			(xy 91.905959 -319.297593) (xy 91.98872 -319.421005) (xy 92.064738 -319.548683) (xy 92.133793 -319.680256)
			(xy 92.195686 -319.815347) (xy 92.250239 -319.953564) (xy 92.297294 -320.094511) (xy 92.336716 -320.237781)
			(xy 92.36839 -320.38296) (xy 92.392226 -320.529629) (xy 92.408155 -320.677367) (xy 92.416131 -320.825747)
			(xy 92.41663 -320.900044) (xy 142.982451 -320.900044) (xy 142.98644 -320.751504) (xy 142.998397 -320.603391)
			(xy 143.018287 -320.456134) (xy 143.046052 -320.310158) (xy 143.081613 -320.165881) (xy 143.124867 -320.023722)
			(xy 143.175689 -319.884089) (xy 143.233933 -319.747386) (xy 143.299431 -319.614006) (xy 143.371994 -319.484334)
			(xy 143.451412 -319.358744) (xy 143.537457 -319.237597) (xy 143.629881 -319.121244) (xy 143.728417 -319.01002)
			(xy 143.832781 -318.904245) (xy 143.942673 -318.804225) (xy 144.057774 -318.710247) (xy 144.177754 -318.622583)
			(xy 144.302267 -318.541486) (xy 144.430953 -318.467189) (xy 144.563442 -318.399907) (xy 144.699351 -318.339833)
			(xy 144.838289 -318.287141) (xy 144.979855 -318.241982) (xy 145.123641 -318.204487) (xy 145.269232 -318.174765)
			(xy 145.416208 -318.1529) (xy 145.564147 -318.138956) (xy 145.71262 -318.132972) (xy 145.861201 -318.134967)
			(xy 146.00946 -318.144935) (xy 146.156971 -318.162846) (xy 146.303307 -318.188649) (xy 146.448048 -318.222269)
			(xy 146.590775 -318.263611) (xy 146.731078 -318.312554) (xy 146.868551 -318.368957) (xy 147.002798 -318.432658)
			(xy 147.133433 -318.503474) (xy 147.260078 -318.581199) (xy 147.382368 -318.66561) (xy 147.499951 -318.756463)
			(xy 147.612488 -318.853497) (xy 147.719655 -318.956432) (xy 147.821142 -319.064971) (xy 147.916656 -319.1788)
			(xy 148.005923 -319.297593) (xy 148.088684 -319.421005) (xy 148.164702 -319.548683) (xy 148.233757 -319.680256)
			(xy 148.29565 -319.815347) (xy 148.350203 -319.953564) (xy 148.397258 -320.094511) (xy 148.43668 -320.237781)
			(xy 148.468354 -320.38296) (xy 148.49219 -320.529629) (xy 148.508119 -320.677367) (xy 148.516095 -320.825747)
			(xy 148.516594 -320.900044) (xy 202.982331 -320.900044) (xy 202.98632 -320.751504) (xy 202.998277 -320.603391)
			(xy 203.018167 -320.456134) (xy 203.045932 -320.310158) (xy 203.081493 -320.165881) (xy 203.124747 -320.023722)
			(xy 203.175569 -319.884089) (xy 203.233813 -319.747386) (xy 203.299311 -319.614006) (xy 203.371874 -319.484334)
			(xy 203.451292 -319.358744) (xy 203.537337 -319.237597) (xy 203.629761 -319.121244) (xy 203.728297 -319.01002)
			(xy 203.832661 -318.904245) (xy 203.942553 -318.804225) (xy 204.057654 -318.710247) (xy 204.177634 -318.622583)
			(xy 204.302147 -318.541486) (xy 204.430833 -318.467189) (xy 204.563322 -318.399907) (xy 204.699231 -318.339833)
			(xy 204.838169 -318.287141) (xy 204.979735 -318.241982) (xy 205.123521 -318.204487) (xy 205.269112 -318.174765)
			(xy 205.416088 -318.1529) (xy 205.564027 -318.138956) (xy 205.7125 -318.132972) (xy 205.861081 -318.134967)
			(xy 206.00934 -318.144935) (xy 206.156851 -318.162846) (xy 206.303187 -318.188649) (xy 206.447928 -318.222269)
			(xy 206.590655 -318.263611) (xy 206.730958 -318.312554) (xy 206.868431 -318.368957) (xy 207.002678 -318.432658)
			(xy 207.133313 -318.503474) (xy 207.259958 -318.581199) (xy 207.382248 -318.66561) (xy 207.499831 -318.756463)
			(xy 207.612368 -318.853497) (xy 207.719535 -318.956432) (xy 207.821022 -319.064971) (xy 207.916536 -319.1788)
			(xy 208.005803 -319.297593) (xy 208.088564 -319.421005) (xy 208.164582 -319.548683) (xy 208.233637 -319.680256)
			(xy 208.29553 -319.815347) (xy 208.350083 -319.953564) (xy 208.397138 -320.094511) (xy 208.43656 -320.237781)
			(xy 208.468234 -320.38296) (xy 208.49207 -320.529629) (xy 208.507999 -320.677367) (xy 208.515975 -320.825747)
			(xy 208.516474 -320.900044) (xy 259.082549 -320.900044) (xy 259.086538 -320.751504) (xy 259.098495 -320.603391)
			(xy 259.118385 -320.456134) (xy 259.14615 -320.310158) (xy 259.181711 -320.165881) (xy 259.224965 -320.023722)
			(xy 259.275787 -319.884089) (xy 259.334031 -319.747386) (xy 259.399529 -319.614006) (xy 259.472092 -319.484334)
			(xy 259.55151 -319.358744) (xy 259.637555 -319.237597) (xy 259.729979 -319.121244) (xy 259.828515 -319.01002)
			(xy 259.932879 -318.904245) (xy 260.042771 -318.804225) (xy 260.157872 -318.710247) (xy 260.277852 -318.622583)
			(xy 260.402365 -318.541486) (xy 260.531051 -318.467189) (xy 260.66354 -318.399907) (xy 260.799449 -318.339833)
			(xy 260.938387 -318.287141) (xy 261.079953 -318.241982) (xy 261.223739 -318.204487) (xy 261.36933 -318.174765)
			(xy 261.516306 -318.1529) (xy 261.664245 -318.138956) (xy 261.812718 -318.132972) (xy 261.961299 -318.134967)
			(xy 262.109558 -318.144935) (xy 262.257069 -318.162846) (xy 262.403405 -318.188649) (xy 262.548146 -318.222269)
			(xy 262.690873 -318.263611) (xy 262.831176 -318.312554) (xy 262.968649 -318.368957) (xy 263.102896 -318.432658)
			(xy 263.233531 -318.503474) (xy 263.360176 -318.581199) (xy 263.482466 -318.66561) (xy 263.600049 -318.756463)
			(xy 263.712586 -318.853497) (xy 263.819753 -318.956432) (xy 263.92124 -319.064971) (xy 264.016754 -319.1788)
			(xy 264.106021 -319.297593) (xy 264.188782 -319.421005) (xy 264.2648 -319.548683) (xy 264.333855 -319.680256)
			(xy 264.395748 -319.815347) (xy 264.450301 -319.953564) (xy 264.497356 -320.094511) (xy 264.536778 -320.237781)
			(xy 264.568452 -320.38296) (xy 264.592288 -320.529629) (xy 264.608217 -320.677367) (xy 264.616193 -320.825747)
			(xy 264.616692 -320.900044) (xy 319.082429 -320.900044) (xy 319.086418 -320.751504) (xy 319.098375 -320.603391)
			(xy 319.118265 -320.456134) (xy 319.14603 -320.310158) (xy 319.181591 -320.165881) (xy 319.224845 -320.023722)
			(xy 319.275667 -319.884089) (xy 319.333911 -319.747386) (xy 319.399409 -319.614006) (xy 319.471972 -319.484334)
			(xy 319.55139 -319.358744) (xy 319.637435 -319.237597) (xy 319.729859 -319.121244) (xy 319.828395 -319.01002)
			(xy 319.932759 -318.904245) (xy 320.042651 -318.804225) (xy 320.157752 -318.710247) (xy 320.277732 -318.622583)
			(xy 320.402245 -318.541486) (xy 320.530931 -318.467189) (xy 320.66342 -318.399907) (xy 320.799329 -318.339833)
			(xy 320.938267 -318.287141) (xy 321.079833 -318.241982) (xy 321.223619 -318.204487) (xy 321.36921 -318.174765)
			(xy 321.516186 -318.1529) (xy 321.664125 -318.138956) (xy 321.812598 -318.132972) (xy 321.961179 -318.134967)
			(xy 322.109438 -318.144935) (xy 322.256949 -318.162846) (xy 322.403285 -318.188649) (xy 322.548026 -318.222269)
			(xy 322.690753 -318.263611) (xy 322.831056 -318.312554) (xy 322.968529 -318.368957) (xy 323.102776 -318.432658)
			(xy 323.233411 -318.503474) (xy 323.360056 -318.581199) (xy 323.482346 -318.66561) (xy 323.599929 -318.756463)
			(xy 323.712466 -318.853497) (xy 323.819633 -318.956432) (xy 323.92112 -319.064971) (xy 324.016634 -319.1788)
			(xy 324.105901 -319.297593) (xy 324.188662 -319.421005) (xy 324.26468 -319.548683) (xy 324.333735 -319.680256)
			(xy 324.395628 -319.815347) (xy 324.450181 -319.953564) (xy 324.497236 -320.094511) (xy 324.536658 -320.237781)
			(xy 324.568332 -320.38296) (xy 324.592168 -320.529629) (xy 324.608097 -320.677367) (xy 324.616073 -320.825747)
			(xy 324.616572 -320.900044) (xy 375.182393 -320.900044) (xy 375.186382 -320.751504) (xy 375.198339 -320.603391)
			(xy 375.218229 -320.456134) (xy 375.245994 -320.310158) (xy 375.281555 -320.165881) (xy 375.324809 -320.023722)
			(xy 375.375631 -319.884089) (xy 375.433875 -319.747386) (xy 375.499373 -319.614006) (xy 375.571936 -319.484334)
			(xy 375.651354 -319.358744) (xy 375.737399 -319.237597) (xy 375.829823 -319.121244) (xy 375.928359 -319.01002)
			(xy 376.032723 -318.904245) (xy 376.142615 -318.804225) (xy 376.257716 -318.710247) (xy 376.377696 -318.622583)
			(xy 376.502209 -318.541486) (xy 376.630895 -318.467189) (xy 376.763384 -318.399907) (xy 376.899293 -318.339833)
			(xy 377.038231 -318.287141) (xy 377.179797 -318.241982) (xy 377.323583 -318.204487) (xy 377.469174 -318.174765)
			(xy 377.61615 -318.1529) (xy 377.764089 -318.138956) (xy 377.912562 -318.132972) (xy 378.061143 -318.134967)
			(xy 378.209402 -318.144935) (xy 378.356913 -318.162846) (xy 378.503249 -318.188649) (xy 378.64799 -318.222269)
			(xy 378.790717 -318.263611) (xy 378.93102 -318.312554) (xy 379.068493 -318.368957) (xy 379.20274 -318.432658)
			(xy 379.333375 -318.503474) (xy 379.46002 -318.581199) (xy 379.58231 -318.66561) (xy 379.699893 -318.756463)
			(xy 379.81243 -318.853497) (xy 379.919597 -318.956432) (xy 380.021084 -319.064971) (xy 380.116598 -319.1788)
			(xy 380.205865 -319.297593) (xy 380.288626 -319.421005) (xy 380.364644 -319.548683) (xy 380.433699 -319.680256)
			(xy 380.495592 -319.815347) (xy 380.550145 -319.953564) (xy 380.5972 -320.094511) (xy 380.636622 -320.237781)
			(xy 380.668296 -320.38296) (xy 380.692132 -320.529629) (xy 380.708061 -320.677367) (xy 380.716037 -320.825747)
			(xy 380.716536 -320.900044) (xy 435.182527 -320.900044) (xy 435.186516 -320.751504) (xy 435.198473 -320.603391)
			(xy 435.218363 -320.456134) (xy 435.246128 -320.310158) (xy 435.281689 -320.165881) (xy 435.324943 -320.023722)
			(xy 435.375765 -319.884089) (xy 435.434009 -319.747386) (xy 435.499507 -319.614006) (xy 435.57207 -319.484334)
			(xy 435.651488 -319.358744) (xy 435.737533 -319.237597) (xy 435.829957 -319.121244) (xy 435.928493 -319.01002)
			(xy 436.032857 -318.904245) (xy 436.142749 -318.804225) (xy 436.25785 -318.710247) (xy 436.37783 -318.622583)
			(xy 436.502343 -318.541486) (xy 436.631029 -318.467189) (xy 436.763518 -318.399907) (xy 436.899427 -318.339833)
			(xy 437.038365 -318.287141) (xy 437.179931 -318.241982) (xy 437.323717 -318.204487) (xy 437.469308 -318.174765)
			(xy 437.616284 -318.1529) (xy 437.764223 -318.138956) (xy 437.912696 -318.132972) (xy 438.061277 -318.134967)
			(xy 438.209536 -318.144935) (xy 438.357047 -318.162846) (xy 438.503383 -318.188649) (xy 438.648124 -318.222269)
			(xy 438.790851 -318.263611) (xy 438.931154 -318.312554) (xy 439.068627 -318.368957) (xy 439.202874 -318.432658)
			(xy 439.333509 -318.503474) (xy 439.460154 -318.581199) (xy 439.582444 -318.66561) (xy 439.700027 -318.756463)
			(xy 439.812564 -318.853497) (xy 439.919731 -318.956432) (xy 440.021218 -319.064971) (xy 440.116732 -319.1788)
			(xy 440.205999 -319.297593) (xy 440.28876 -319.421005) (xy 440.364778 -319.548683) (xy 440.433833 -319.680256)
			(xy 440.495726 -319.815347) (xy 440.550279 -319.953564) (xy 440.597334 -320.094511) (xy 440.636756 -320.237781)
			(xy 440.66843 -320.38296) (xy 440.692266 -320.529629) (xy 440.708195 -320.677367) (xy 440.716171 -320.825747)
			(xy 440.71667 -320.900044) (xy 440.716171 -320.974341) (xy 440.708195 -321.122721) (xy 440.692266 -321.270459)
			(xy 440.66843 -321.417128) (xy 440.636756 -321.562307) (xy 440.597334 -321.705577) (xy 440.550279 -321.846524)
			(xy 440.495726 -321.984741) (xy 440.433833 -322.119832) (xy 440.364778 -322.251405) (xy 440.28876 -322.379083)
			(xy 440.205999 -322.502495) (xy 440.116732 -322.621288) (xy 440.021218 -322.735117) (xy 439.919731 -322.843656)
			(xy 439.812564 -322.946591) (xy 439.700027 -323.043625) (xy 439.582444 -323.134478) (xy 439.460154 -323.218889)
			(xy 439.333509 -323.296614) (xy 439.202874 -323.36743) (xy 439.068627 -323.431131) (xy 438.931154 -323.487534)
			(xy 438.790851 -323.536477) (xy 438.648124 -323.577819) (xy 438.503383 -323.611439) (xy 438.357047 -323.637242)
			(xy 438.209536 -323.655153) (xy 438.061277 -323.665121) (xy 437.912696 -323.667116) (xy 437.764223 -323.661132)
			(xy 437.616284 -323.647188) (xy 437.469308 -323.625323) (xy 437.323717 -323.595601) (xy 437.179931 -323.558106)
			(xy 437.038365 -323.512947) (xy 436.899427 -323.460255) (xy 436.763518 -323.400181) (xy 436.631029 -323.332899)
			(xy 436.502343 -323.258602) (xy 436.37783 -323.177505) (xy 436.25785 -323.089841) (xy 436.142749 -322.995863)
			(xy 436.032857 -322.895843) (xy 435.928493 -322.790068) (xy 435.829957 -322.678844) (xy 435.737533 -322.562491)
			(xy 435.651488 -322.441344) (xy 435.57207 -322.315754) (xy 435.499507 -322.186082) (xy 435.434009 -322.052702)
			(xy 435.375765 -321.915999) (xy 435.324943 -321.776366) (xy 435.281689 -321.634207) (xy 435.246128 -321.48993)
			(xy 435.218363 -321.343954) (xy 435.198473 -321.196697) (xy 435.186516 -321.048584) (xy 435.182527 -320.900044)
			(xy 380.716536 -320.900044) (xy 380.716037 -320.974341) (xy 380.708061 -321.122721) (xy 380.692132 -321.270459)
			(xy 380.668296 -321.417128) (xy 380.636622 -321.562307) (xy 380.5972 -321.705577) (xy 380.550145 -321.846524)
			(xy 380.495592 -321.984741) (xy 380.433699 -322.119832) (xy 380.364644 -322.251405) (xy 380.288626 -322.379083)
			(xy 380.205865 -322.502495) (xy 380.116598 -322.621288) (xy 380.021084 -322.735117) (xy 379.919597 -322.843656)
			(xy 379.81243 -322.946591) (xy 379.699893 -323.043625) (xy 379.58231 -323.134478) (xy 379.46002 -323.218889)
			(xy 379.333375 -323.296614) (xy 379.20274 -323.36743) (xy 379.068493 -323.431131) (xy 378.93102 -323.487534)
			(xy 378.790717 -323.536477) (xy 378.64799 -323.577819) (xy 378.503249 -323.611439) (xy 378.356913 -323.637242)
			(xy 378.209402 -323.655153) (xy 378.061143 -323.665121) (xy 377.912562 -323.667116) (xy 377.764089 -323.661132)
			(xy 377.61615 -323.647188) (xy 377.469174 -323.625323) (xy 377.323583 -323.595601) (xy 377.179797 -323.558106)
			(xy 377.038231 -323.512947) (xy 376.899293 -323.460255) (xy 376.763384 -323.400181) (xy 376.630895 -323.332899)
			(xy 376.502209 -323.258602) (xy 376.377696 -323.177505) (xy 376.257716 -323.089841) (xy 376.142615 -322.995863)
			(xy 376.032723 -322.895843) (xy 375.928359 -322.790068) (xy 375.829823 -322.678844) (xy 375.737399 -322.562491)
			(xy 375.651354 -322.441344) (xy 375.571936 -322.315754) (xy 375.499373 -322.186082) (xy 375.433875 -322.052702)
			(xy 375.375631 -321.915999) (xy 375.324809 -321.776366) (xy 375.281555 -321.634207) (xy 375.245994 -321.48993)
			(xy 375.218229 -321.343954) (xy 375.198339 -321.196697) (xy 375.186382 -321.048584) (xy 375.182393 -320.900044)
			(xy 324.616572 -320.900044) (xy 324.616073 -320.974341) (xy 324.608097 -321.122721) (xy 324.592168 -321.270459)
			(xy 324.568332 -321.417128) (xy 324.536658 -321.562307) (xy 324.497236 -321.705577) (xy 324.450181 -321.846524)
			(xy 324.395628 -321.984741) (xy 324.333735 -322.119832) (xy 324.26468 -322.251405) (xy 324.188662 -322.379083)
			(xy 324.105901 -322.502495) (xy 324.016634 -322.621288) (xy 323.92112 -322.735117) (xy 323.819633 -322.843656)
			(xy 323.712466 -322.946591) (xy 323.599929 -323.043625) (xy 323.482346 -323.134478) (xy 323.360056 -323.218889)
			(xy 323.233411 -323.296614) (xy 323.102776 -323.36743) (xy 322.968529 -323.431131) (xy 322.831056 -323.487534)
			(xy 322.690753 -323.536477) (xy 322.548026 -323.577819) (xy 322.403285 -323.611439) (xy 322.256949 -323.637242)
			(xy 322.109438 -323.655153) (xy 321.961179 -323.665121) (xy 321.812598 -323.667116) (xy 321.664125 -323.661132)
			(xy 321.516186 -323.647188) (xy 321.36921 -323.625323) (xy 321.223619 -323.595601) (xy 321.079833 -323.558106)
			(xy 320.938267 -323.512947) (xy 320.799329 -323.460255) (xy 320.66342 -323.400181) (xy 320.530931 -323.332899)
			(xy 320.402245 -323.258602) (xy 320.277732 -323.177505) (xy 320.157752 -323.089841) (xy 320.042651 -322.995863)
			(xy 319.932759 -322.895843) (xy 319.828395 -322.790068) (xy 319.729859 -322.678844) (xy 319.637435 -322.562491)
			(xy 319.55139 -322.441344) (xy 319.471972 -322.315754) (xy 319.399409 -322.186082) (xy 319.333911 -322.052702)
			(xy 319.275667 -321.915999) (xy 319.224845 -321.776366) (xy 319.181591 -321.634207) (xy 319.14603 -321.48993)
			(xy 319.118265 -321.343954) (xy 319.098375 -321.196697) (xy 319.086418 -321.048584) (xy 319.082429 -320.900044)
			(xy 264.616692 -320.900044) (xy 264.616193 -320.974341) (xy 264.608217 -321.122721) (xy 264.592288 -321.270459)
			(xy 264.568452 -321.417128) (xy 264.536778 -321.562307) (xy 264.497356 -321.705577) (xy 264.450301 -321.846524)
			(xy 264.395748 -321.984741) (xy 264.333855 -322.119832) (xy 264.2648 -322.251405) (xy 264.188782 -322.379083)
			(xy 264.106021 -322.502495) (xy 264.016754 -322.621288) (xy 263.92124 -322.735117) (xy 263.819753 -322.843656)
			(xy 263.712586 -322.946591) (xy 263.600049 -323.043625) (xy 263.482466 -323.134478) (xy 263.360176 -323.218889)
			(xy 263.233531 -323.296614) (xy 263.102896 -323.36743) (xy 262.968649 -323.431131) (xy 262.831176 -323.487534)
			(xy 262.690873 -323.536477) (xy 262.548146 -323.577819) (xy 262.403405 -323.611439) (xy 262.257069 -323.637242)
			(xy 262.109558 -323.655153) (xy 261.961299 -323.665121) (xy 261.812718 -323.667116) (xy 261.664245 -323.661132)
			(xy 261.516306 -323.647188) (xy 261.36933 -323.625323) (xy 261.223739 -323.595601) (xy 261.079953 -323.558106)
			(xy 260.938387 -323.512947) (xy 260.799449 -323.460255) (xy 260.66354 -323.400181) (xy 260.531051 -323.332899)
			(xy 260.402365 -323.258602) (xy 260.277852 -323.177505) (xy 260.157872 -323.089841) (xy 260.042771 -322.995863)
			(xy 259.932879 -322.895843) (xy 259.828515 -322.790068) (xy 259.729979 -322.678844) (xy 259.637555 -322.562491)
			(xy 259.55151 -322.441344) (xy 259.472092 -322.315754) (xy 259.399529 -322.186082) (xy 259.334031 -322.052702)
			(xy 259.275787 -321.915999) (xy 259.224965 -321.776366) (xy 259.181711 -321.634207) (xy 259.14615 -321.48993)
			(xy 259.118385 -321.343954) (xy 259.098495 -321.196697) (xy 259.086538 -321.048584) (xy 259.082549 -320.900044)
			(xy 208.516474 -320.900044) (xy 208.515975 -320.974341) (xy 208.507999 -321.122721) (xy 208.49207 -321.270459)
			(xy 208.468234 -321.417128) (xy 208.43656 -321.562307) (xy 208.397138 -321.705577) (xy 208.350083 -321.846524)
			(xy 208.29553 -321.984741) (xy 208.233637 -322.119832) (xy 208.164582 -322.251405) (xy 208.088564 -322.379083)
			(xy 208.005803 -322.502495) (xy 207.916536 -322.621288) (xy 207.821022 -322.735117) (xy 207.719535 -322.843656)
			(xy 207.612368 -322.946591) (xy 207.499831 -323.043625) (xy 207.382248 -323.134478) (xy 207.259958 -323.218889)
			(xy 207.133313 -323.296614) (xy 207.002678 -323.36743) (xy 206.868431 -323.431131) (xy 206.730958 -323.487534)
			(xy 206.590655 -323.536477) (xy 206.447928 -323.577819) (xy 206.303187 -323.611439) (xy 206.156851 -323.637242)
			(xy 206.00934 -323.655153) (xy 205.861081 -323.665121) (xy 205.7125 -323.667116) (xy 205.564027 -323.661132)
			(xy 205.416088 -323.647188) (xy 205.269112 -323.625323) (xy 205.123521 -323.595601) (xy 204.979735 -323.558106)
			(xy 204.838169 -323.512947) (xy 204.699231 -323.460255) (xy 204.563322 -323.400181) (xy 204.430833 -323.332899)
			(xy 204.302147 -323.258602) (xy 204.177634 -323.177505) (xy 204.057654 -323.089841) (xy 203.942553 -322.995863)
			(xy 203.832661 -322.895843) (xy 203.728297 -322.790068) (xy 203.629761 -322.678844) (xy 203.537337 -322.562491)
			(xy 203.451292 -322.441344) (xy 203.371874 -322.315754) (xy 203.299311 -322.186082) (xy 203.233813 -322.052702)
			(xy 203.175569 -321.915999) (xy 203.124747 -321.776366) (xy 203.081493 -321.634207) (xy 203.045932 -321.48993)
			(xy 203.018167 -321.343954) (xy 202.998277 -321.196697) (xy 202.98632 -321.048584) (xy 202.982331 -320.900044)
			(xy 148.516594 -320.900044) (xy 148.516095 -320.974341) (xy 148.508119 -321.122721) (xy 148.49219 -321.270459)
			(xy 148.468354 -321.417128) (xy 148.43668 -321.562307) (xy 148.397258 -321.705577) (xy 148.350203 -321.846524)
			(xy 148.29565 -321.984741) (xy 148.233757 -322.119832) (xy 148.164702 -322.251405) (xy 148.088684 -322.379083)
			(xy 148.005923 -322.502495) (xy 147.916656 -322.621288) (xy 147.821142 -322.735117) (xy 147.719655 -322.843656)
			(xy 147.612488 -322.946591) (xy 147.499951 -323.043625) (xy 147.382368 -323.134478) (xy 147.260078 -323.218889)
			(xy 147.133433 -323.296614) (xy 147.002798 -323.36743) (xy 146.868551 -323.431131) (xy 146.731078 -323.487534)
			(xy 146.590775 -323.536477) (xy 146.448048 -323.577819) (xy 146.303307 -323.611439) (xy 146.156971 -323.637242)
			(xy 146.00946 -323.655153) (xy 145.861201 -323.665121) (xy 145.71262 -323.667116) (xy 145.564147 -323.661132)
			(xy 145.416208 -323.647188) (xy 145.269232 -323.625323) (xy 145.123641 -323.595601) (xy 144.979855 -323.558106)
			(xy 144.838289 -323.512947) (xy 144.699351 -323.460255) (xy 144.563442 -323.400181) (xy 144.430953 -323.332899)
			(xy 144.302267 -323.258602) (xy 144.177754 -323.177505) (xy 144.057774 -323.089841) (xy 143.942673 -322.995863)
			(xy 143.832781 -322.895843) (xy 143.728417 -322.790068) (xy 143.629881 -322.678844) (xy 143.537457 -322.562491)
			(xy 143.451412 -322.441344) (xy 143.371994 -322.315754) (xy 143.299431 -322.186082) (xy 143.233933 -322.052702)
			(xy 143.175689 -321.915999) (xy 143.124867 -321.776366) (xy 143.081613 -321.634207) (xy 143.046052 -321.48993)
			(xy 143.018287 -321.343954) (xy 142.998397 -321.196697) (xy 142.98644 -321.048584) (xy 142.982451 -320.900044)
			(xy 92.41663 -320.900044) (xy 92.416131 -320.974341) (xy 92.408155 -321.122721) (xy 92.392226 -321.270459)
			(xy 92.36839 -321.417128) (xy 92.336716 -321.562307) (xy 92.297294 -321.705577) (xy 92.250239 -321.846524)
			(xy 92.195686 -321.984741) (xy 92.133793 -322.119832) (xy 92.064738 -322.251405) (xy 91.98872 -322.379083)
			(xy 91.905959 -322.502495) (xy 91.816692 -322.621288) (xy 91.721178 -322.735117) (xy 91.619691 -322.843656)
			(xy 91.512524 -322.946591) (xy 91.399987 -323.043625) (xy 91.282404 -323.134478) (xy 91.160114 -323.218889)
			(xy 91.033469 -323.296614) (xy 90.902834 -323.36743) (xy 90.768587 -323.431131) (xy 90.631114 -323.487534)
			(xy 90.490811 -323.536477) (xy 90.348084 -323.577819) (xy 90.203343 -323.611439) (xy 90.057007 -323.637242)
			(xy 89.909496 -323.655153) (xy 89.761237 -323.665121) (xy 89.612656 -323.667116) (xy 89.464183 -323.661132)
			(xy 89.316244 -323.647188) (xy 89.169268 -323.625323) (xy 89.023677 -323.595601) (xy 88.879891 -323.558106)
			(xy 88.738325 -323.512947) (xy 88.599387 -323.460255) (xy 88.463478 -323.400181) (xy 88.330989 -323.332899)
			(xy 88.202303 -323.258602) (xy 88.07779 -323.177505) (xy 87.95781 -323.089841) (xy 87.842709 -322.995863)
			(xy 87.732817 -322.895843) (xy 87.628453 -322.790068) (xy 87.529917 -322.678844) (xy 87.437493 -322.562491)
			(xy 87.351448 -322.441344) (xy 87.27203 -322.315754) (xy 87.199467 -322.186082) (xy 87.133969 -322.052702)
			(xy 87.075725 -321.915999) (xy 87.024903 -321.776366) (xy 86.981649 -321.634207) (xy 86.946088 -321.48993)
			(xy 86.918323 -321.343954) (xy 86.898433 -321.196697) (xy 86.886476 -321.048584) (xy 86.882487 -320.900044)
			(xy 32.416496 -320.900044) (xy 32.415997 -320.974341) (xy 32.408021 -321.122721) (xy 32.392092 -321.270459)
			(xy 32.368256 -321.417128) (xy 32.336582 -321.562307) (xy 32.29716 -321.705577) (xy 32.250105 -321.846524)
			(xy 32.195552 -321.984741) (xy 32.133659 -322.119832) (xy 32.064604 -322.251405) (xy 31.988586 -322.379083)
			(xy 31.905825 -322.502495) (xy 31.816558 -322.621288) (xy 31.721044 -322.735117) (xy 31.619557 -322.843656)
			(xy 31.51239 -322.946591) (xy 31.399853 -323.043625) (xy 31.28227 -323.134478) (xy 31.15998 -323.218889)
			(xy 31.033335 -323.296614) (xy 30.9027 -323.36743) (xy 30.768453 -323.431131) (xy 30.63098 -323.487534)
			(xy 30.490677 -323.536477) (xy 30.34795 -323.577819) (xy 30.203209 -323.611439) (xy 30.056873 -323.637242)
			(xy 29.909362 -323.655153) (xy 29.761103 -323.665121) (xy 29.612522 -323.667116) (xy 29.464049 -323.661132)
			(xy 29.31611 -323.647188) (xy 29.169134 -323.625323) (xy 29.023543 -323.595601) (xy 28.879757 -323.558106)
			(xy 28.738191 -323.512947) (xy 28.599253 -323.460255) (xy 28.463344 -323.400181) (xy 28.330855 -323.332899)
			(xy 28.202169 -323.258602) (xy 28.077656 -323.177505) (xy 27.957676 -323.089841) (xy 27.842575 -322.995863)
			(xy 27.732683 -322.895843) (xy 27.628319 -322.790068) (xy 27.529783 -322.678844) (xy 27.437359 -322.562491)
			(xy 27.351314 -322.441344) (xy 27.271896 -322.315754) (xy 27.199333 -322.186082) (xy 27.133835 -322.052702)
			(xy 27.075591 -321.915999) (xy 27.024769 -321.776366) (xy 26.981515 -321.634207) (xy 26.945954 -321.48993)
			(xy 26.918189 -321.343954) (xy 26.898299 -321.196697) (xy 26.886342 -321.048584) (xy 26.882353 -320.900044)
			(xy 0.509016 -320.900044) (xy 0.509016 -330.416662) (xy 97.355152 -330.416662) (xy 97.355152 -329.553062)
			(xy 97.355642 -329.523078) (xy 97.36347 -329.463622) (xy 97.378991 -329.405697) (xy 97.40194 -329.350293)
			(xy 97.431924 -329.298359) (xy 97.46843 -329.250783) (xy 97.510835 -329.208378) (xy 97.558411 -329.171872)
			(xy 97.610345 -329.141888) (xy 97.665749 -329.118939) (xy 97.723674 -329.103418) (xy 97.78313 -329.09559)
			(xy 97.843098 -329.09559) (xy 97.902554 -329.103418) (xy 97.960479 -329.118939) (xy 98.015883 -329.141888)
			(xy 98.067817 -329.171872) (xy 98.115393 -329.208378) (xy 98.157798 -329.250783) (xy 98.194304 -329.298359)
			(xy 98.224288 -329.350293) (xy 98.247237 -329.405697) (xy 98.262758 -329.463622) (xy 98.270586 -329.523078)
			(xy 98.271076 -329.553062) (xy 98.271076 -330.416662) (xy 98.270586 -330.446646) (xy 98.262758 -330.506102)
			(xy 98.247237 -330.564027) (xy 98.224288 -330.619431) (xy 98.194304 -330.671365) (xy 98.157798 -330.718941)
			(xy 98.115393 -330.761346) (xy 98.067817 -330.797852) (xy 98.015883 -330.827836) (xy 97.960479 -330.850785)
			(xy 97.902554 -330.866306) (xy 97.843098 -330.874134) (xy 97.78313 -330.874134) (xy 97.723674 -330.866306)
			(xy 97.665749 -330.850785) (xy 97.610345 -330.827836) (xy 97.558411 -330.797852) (xy 97.510835 -330.761346)
			(xy 97.46843 -330.718941) (xy 97.431924 -330.671365) (xy 97.40194 -330.619431) (xy 97.378991 -330.564027)
			(xy 97.36347 -330.506102) (xy 97.355642 -330.446646) (xy 97.355152 -330.416662) (xy 0.509016 -330.416662)
			(xy 0.509016 -331.53223) (xy 114.955828 -331.53223) (xy 114.955828 -330.66863) (xy 114.956318 -330.638646)
			(xy 114.964146 -330.57919) (xy 114.979667 -330.521265) (xy 115.002616 -330.465861) (xy 115.0326 -330.413927)
			(xy 115.069106 -330.366351) (xy 115.111511 -330.323946) (xy 115.159087 -330.28744) (xy 115.211021 -330.257456)
			(xy 115.266425 -330.234507) (xy 115.32435 -330.218986) (xy 115.383806 -330.211158) (xy 115.443774 -330.211158)
			(xy 115.50323 -330.218986) (xy 115.561155 -330.234507) (xy 115.616559 -330.257456) (xy 115.668493 -330.28744)
			(xy 115.716069 -330.323946) (xy 115.758474 -330.366351) (xy 115.79498 -330.413927) (xy 115.824964 -330.465861)
			(xy 115.847913 -330.521265) (xy 115.863434 -330.57919) (xy 115.871262 -330.638646) (xy 115.871752 -330.66863)
			(xy 115.871752 -331.53223) (xy 115.871262 -331.562214) (xy 115.863434 -331.62167) (xy 115.847913 -331.679595)
			(xy 115.824964 -331.734999) (xy 115.79498 -331.786933) (xy 115.758474 -331.834509) (xy 115.716069 -331.876914)
			(xy 115.668493 -331.91342) (xy 115.616559 -331.943404) (xy 115.561155 -331.966353) (xy 115.50323 -331.981874)
			(xy 115.443774 -331.989702) (xy 115.383806 -331.989702) (xy 115.32435 -331.981874) (xy 115.266425 -331.966353)
			(xy 115.211021 -331.943404) (xy 115.159087 -331.91342) (xy 115.111511 -331.876914) (xy 115.069106 -331.834509)
			(xy 115.0326 -331.786933) (xy 115.002616 -331.734999) (xy 114.979667 -331.679595) (xy 114.964146 -331.62167)
			(xy 114.956318 -331.562214) (xy 114.955828 -331.53223) (xy 0.509016 -331.53223) (xy 0.509016 -333.950056)
			(xy 93.5736 -333.950056) (xy 93.5736 -333.086456) (xy 93.57409 -333.056488) (xy 93.581913 -332.997066)
			(xy 93.597426 -332.939173) (xy 93.620362 -332.8838) (xy 93.650329 -332.831894) (xy 93.686816 -332.784344)
			(xy 93.729196 -332.741964) (xy 93.776746 -332.705477) (xy 93.828652 -332.67551) (xy 93.884025 -332.652574)
			(xy 93.941918 -332.637061) (xy 94.00134 -332.629238) (xy 94.061276 -332.629238) (xy 94.120698 -332.637061)
			(xy 94.178591 -332.652574) (xy 94.233964 -332.67551) (xy 94.28587 -332.705477) (xy 94.33342 -332.741964)
			(xy 94.3758 -332.784344) (xy 94.412287 -332.831894) (xy 94.442254 -332.8838) (xy 94.46519 -332.939173)
			(xy 94.46736 -332.947271) (xy 365.368753 -332.947271) (xy 365.368753 -332.887329) (xy 365.376578 -332.827899)
			(xy 365.392093 -332.77) (xy 365.415033 -332.71462) (xy 365.445006 -332.66271) (xy 365.481498 -332.615155)
			(xy 365.523886 -332.572772) (xy 365.571443 -332.536283) (xy 365.623356 -332.506315) (xy 365.678737 -332.48338)
			(xy 365.736639 -332.46787) (xy 365.796069 -332.460051) (xy 365.82604 -332.459584) (xy 366.68964 -332.459584)
			(xy 366.719605 -332.460093) (xy 366.779023 -332.46792) (xy 366.836911 -332.483435) (xy 366.892278 -332.506374)
			(xy 366.944178 -332.536342) (xy 366.991723 -332.572828) (xy 367.034098 -332.615207) (xy 367.07058 -332.662755)
			(xy 367.100544 -332.714658) (xy 367.123478 -332.770027) (xy 367.138988 -332.827916) (xy 367.14681 -332.887335)
			(xy 367.14681 -332.947265) (xy 367.138988 -333.006684) (xy 367.123478 -333.064573) (xy 367.100544 -333.119942)
			(xy 367.07058 -333.171845) (xy 367.034098 -333.219393) (xy 366.991723 -333.261772) (xy 366.944178 -333.298258)
			(xy 366.892278 -333.328226) (xy 366.836911 -333.351165) (xy 366.779023 -333.36668) (xy 366.719605 -333.374507)
			(xy 366.68964 -333.375) (xy 365.82604 -333.375) (xy 365.796069 -333.374549) (xy 365.736639 -333.36673)
			(xy 365.678737 -333.35122) (xy 365.623356 -333.328285) (xy 365.571443 -333.298317) (xy 365.523886 -333.261828)
			(xy 365.481498 -333.219445) (xy 365.445006 -333.17189) (xy 365.415033 -333.11998) (xy 365.392093 -333.0646)
			(xy 365.376578 -333.006701) (xy 365.368753 -332.947271) (xy 94.46736 -332.947271) (xy 94.480703 -332.997066)
			(xy 94.488526 -333.056488) (xy 94.489016 -333.086456) (xy 94.489016 -333.950056) (xy 94.488526 -333.980024)
			(xy 94.480703 -334.039446) (xy 94.46519 -334.097339) (xy 94.442254 -334.152712) (xy 94.412287 -334.204618)
			(xy 94.3758 -334.252168) (xy 94.33342 -334.294548) (xy 94.28587 -334.331035) (xy 94.233964 -334.361002)
			(xy 94.178591 -334.383938) (xy 94.120698 -334.399451) (xy 94.061276 -334.407274) (xy 94.00134 -334.407274)
			(xy 93.941918 -334.399451) (xy 93.884025 -334.383938) (xy 93.828652 -334.361002) (xy 93.776746 -334.331035)
			(xy 93.729196 -334.294548) (xy 93.686816 -334.252168) (xy 93.650329 -334.204618) (xy 93.620362 -334.152712)
			(xy 93.597426 -334.097339) (xy 93.581913 -334.039446) (xy 93.57409 -333.980024) (xy 93.5736 -333.950056)
			(xy 0.509016 -333.950056) (xy 0.509016 -337.266026) (xy 234.403392 -337.266026) (xy 234.403392 -336.402426)
			(xy 234.403882 -336.372458) (xy 234.411705 -336.313036) (xy 234.427218 -336.255143) (xy 234.450154 -336.19977)
			(xy 234.480121 -336.147864) (xy 234.516608 -336.100314) (xy 234.558988 -336.057934) (xy 234.606538 -336.021447)
			(xy 234.658444 -335.99148) (xy 234.713817 -335.968544) (xy 234.77171 -335.953031) (xy 234.831132 -335.945208)
			(xy 234.891068 -335.945208) (xy 234.95049 -335.953031) (xy 235.008383 -335.968544) (xy 235.063756 -335.99148)
			(xy 235.115662 -336.021447) (xy 235.163212 -336.057934) (xy 235.205592 -336.100314) (xy 235.242079 -336.147864)
			(xy 235.272046 -336.19977) (xy 235.294982 -336.255143) (xy 235.310495 -336.313036) (xy 235.318318 -336.372458)
			(xy 235.318808 -336.402426) (xy 235.318808 -337.266026) (xy 235.318318 -337.295994) (xy 235.310495 -337.355416)
			(xy 235.294982 -337.413309) (xy 235.272046 -337.468682) (xy 235.242079 -337.520588) (xy 235.205592 -337.568138)
			(xy 235.163212 -337.610518) (xy 235.115662 -337.647005) (xy 235.063756 -337.676972) (xy 235.008383 -337.699908)
			(xy 234.95049 -337.715421) (xy 234.891068 -337.723244) (xy 234.831132 -337.723244) (xy 234.77171 -337.715421)
			(xy 234.713817 -337.699908) (xy 234.658444 -337.676972) (xy 234.606538 -337.647005) (xy 234.558988 -337.610518)
			(xy 234.516608 -337.568138) (xy 234.480121 -337.520588) (xy 234.450154 -337.468682) (xy 234.427218 -337.413309)
			(xy 234.411705 -337.355416) (xy 234.403882 -337.295994) (xy 234.403392 -337.266026) (xy 0.509016 -337.266026)
			(xy 0.509016 -342.466769) (xy 18.951172 -342.466769) (xy 18.951172 -342.412231) (xy 18.958934 -342.358247)
			(xy 18.974299 -342.305917) (xy 18.996956 -342.256307) (xy 19.026441 -342.210426) (xy 19.062157 -342.169208)
			(xy 19.103374 -342.133493) (xy 19.149255 -342.104007) (xy 19.198865 -342.08135) (xy 19.251195 -342.065985)
			(xy 19.305179 -342.058223) (xy 19.332448 -342.057736) (xy 20.196048 -342.057736) (xy 20.223319 -342.058203)
			(xy 20.277306 -342.065965) (xy 20.329638 -342.081331) (xy 20.379252 -342.103989) (xy 20.425135 -342.133476)
			(xy 20.466355 -342.169193) (xy 20.502073 -342.210413) (xy 20.53156 -342.256297) (xy 20.554218 -342.30591)
			(xy 20.569584 -342.358242) (xy 20.577347 -342.412229) (xy 20.577347 -342.466771) (xy 20.577347 -342.466772)
			(xy 22.0601 -342.466772) (xy 22.0601 -342.412228) (xy 22.067862 -342.358241) (xy 22.083229 -342.305907)
			(xy 22.105887 -342.256293) (xy 22.135375 -342.210409) (xy 22.171094 -342.169188) (xy 22.212315 -342.133471)
			(xy 22.2582 -342.103983) (xy 22.307815 -342.081326) (xy 22.360148 -342.06596) (xy 22.414136 -342.058199)
			(xy 22.441408 -342.057736) (xy 23.305008 -342.057736) (xy 23.332277 -342.058227) (xy 23.386259 -342.06599)
			(xy 23.438588 -342.081355) (xy 23.488197 -342.104012) (xy 23.534076 -342.133498) (xy 23.575293 -342.169213)
			(xy 23.611007 -342.21043) (xy 23.640492 -342.256311) (xy 23.663147 -342.30592) (xy 23.678512 -342.358249)
			(xy 23.686274 -342.412231) (xy 23.686274 -342.466768) (xy 25.169122 -342.466768) (xy 25.169122 -342.412232)
			(xy 25.176883 -342.358251) (xy 25.192247 -342.305924) (xy 25.214901 -342.256315) (xy 25.244384 -342.210436)
			(xy 25.280096 -342.169219) (xy 25.32131 -342.133503) (xy 25.367187 -342.104016) (xy 25.416794 -342.081358)
			(xy 25.46912 -342.06599) (xy 25.5231 -342.058225) (xy 25.550368 -342.057736) (xy 26.413968 -342.057736)
			(xy 26.44124 -342.058201) (xy 26.49523 -342.06596) (xy 26.547567 -342.081323) (xy 26.597184 -342.103979)
			(xy 26.643071 -342.133465) (xy 26.684295 -342.169183) (xy 26.720015 -342.210403) (xy 26.749506 -342.256288)
			(xy 26.772166 -342.305903) (xy 26.787533 -342.358238) (xy 26.795296 -342.412228) (xy 26.795296 -342.466772)
			(xy 28.278 -342.466772) (xy 28.278 -342.412228) (xy 28.285762 -342.358238) (xy 28.30113 -342.305903)
			(xy 28.32379 -342.256288) (xy 28.35328 -342.210402) (xy 28.389001 -342.169181) (xy 28.430225 -342.133464)
			(xy 28.476112 -342.103977) (xy 28.525729 -342.08132) (xy 28.578065 -342.065957) (xy 28.632056 -342.058198)
			(xy 28.659328 -342.057736) (xy 29.522928 -342.057736) (xy 29.550196 -342.058228) (xy 29.604176 -342.065993)
			(xy 29.656502 -342.081361) (xy 29.706109 -342.104019) (xy 29.751986 -342.133505) (xy 29.7932 -342.16922)
			(xy 29.828912 -342.210437) (xy 29.858395 -342.256316) (xy 29.881049 -342.305924) (xy 29.896413 -342.358251)
			(xy 29.904174 -342.412232) (xy 29.904174 -342.466768) (xy 29.904174 -342.466769) (xy 31.387022 -342.466769)
			(xy 31.387022 -342.412231) (xy 31.394784 -342.358248) (xy 31.410149 -342.305919) (xy 31.432804 -342.25631)
			(xy 31.462289 -342.210429) (xy 31.498003 -342.169212) (xy 31.53922 -342.133496) (xy 31.585099 -342.10401)
			(xy 31.634708 -342.081353) (xy 31.687036 -342.065986) (xy 31.741019 -342.058223) (xy 31.768288 -342.057736)
			(xy 32.631888 -342.057736) (xy 32.659159 -342.058203) (xy 32.713147 -342.065963) (xy 32.765481 -342.081329)
			(xy 32.815096 -342.103985) (xy 32.86098 -342.133472) (xy 32.902202 -342.16919) (xy 32.93792 -342.21041)
			(xy 32.967409 -342.256294) (xy 32.990067 -342.305908) (xy 33.005434 -342.358241) (xy 33.013196 -342.412229)
			(xy 33.013196 -342.466771) (xy 33.013196 -342.466773) (xy 34.4959 -342.466773) (xy 34.4959 -342.412227)
			(xy 34.503663 -342.358235) (xy 34.519032 -342.305899) (xy 34.541693 -342.256282) (xy 34.571185 -342.210396)
			(xy 34.606908 -342.169174) (xy 34.648134 -342.133456) (xy 34.694024 -342.10397) (xy 34.743644 -342.081315)
			(xy 34.795982 -342.065953) (xy 34.849975 -342.058196) (xy 34.877248 -342.057736) (xy 35.740848 -342.057736)
			(xy 35.768115 -342.05823) (xy 35.822093 -342.065997) (xy 35.874417 -342.081366) (xy 35.92402 -342.104025)
			(xy 35.969895 -342.133512) (xy 36.011107 -342.169227) (xy 36.046817 -342.210443) (xy 36.076298 -342.256322)
			(xy 36.098951 -342.305928) (xy 36.114313 -342.358254) (xy 36.122074 -342.412233) (xy 36.122074 -342.466767)
			(xy 36.122073 -342.466772) (xy 37.6049 -342.466772) (xy 37.6049 -342.412228) (xy 37.612662 -342.358241)
			(xy 37.628029 -342.305907) (xy 37.650687 -342.256293) (xy 37.680175 -342.210409) (xy 37.715894 -342.169188)
			(xy 37.757115 -342.133471) (xy 37.803 -342.103983) (xy 37.852615 -342.081326) (xy 37.904948 -342.06596)
			(xy 37.958936 -342.058199) (xy 37.986208 -342.057736) (xy 38.849808 -342.057736) (xy 38.877077 -342.058227)
			(xy 38.931059 -342.06599) (xy 38.983388 -342.081355) (xy 39.032997 -342.104012) (xy 39.078876 -342.133498)
			(xy 39.120093 -342.169213) (xy 39.155807 -342.21043) (xy 39.185292 -342.256311) (xy 39.207947 -342.30592)
			(xy 39.223312 -342.358249) (xy 39.231074 -342.412231) (xy 39.231074 -342.466768) (xy 40.713922 -342.466768)
			(xy 40.713922 -342.412232) (xy 40.721683 -342.358251) (xy 40.737047 -342.305924) (xy 40.759701 -342.256315)
			(xy 40.789184 -342.210436) (xy 40.824896 -342.169219) (xy 40.86611 -342.133503) (xy 40.911987 -342.104016)
			(xy 40.961594 -342.081358) (xy 41.01392 -342.06599) (xy 41.0679 -342.058225) (xy 41.095168 -342.057736)
			(xy 41.958768 -342.057736) (xy 41.98604 -342.058201) (xy 42.04003 -342.06596) (xy 42.092367 -342.081323)
			(xy 42.141984 -342.103979) (xy 42.187871 -342.133465) (xy 42.229095 -342.169183) (xy 42.264815 -342.210403)
			(xy 42.294306 -342.256288) (xy 42.316966 -342.305903) (xy 42.332333 -342.358238) (xy 42.340096 -342.412228)
			(xy 42.340096 -342.466772) (xy 43.8228 -342.466772) (xy 43.8228 -342.412228) (xy 43.830562 -342.358238)
			(xy 43.84593 -342.305903) (xy 43.86859 -342.256288) (xy 43.89808 -342.210402) (xy 43.933801 -342.169181)
			(xy 43.975025 -342.133464) (xy 44.020912 -342.103977) (xy 44.070529 -342.08132) (xy 44.122865 -342.065957)
			(xy 44.176856 -342.058198) (xy 44.204128 -342.057736) (xy 45.067728 -342.057736) (xy 45.094996 -342.058228)
			(xy 45.148976 -342.065993) (xy 45.201302 -342.081361) (xy 45.250909 -342.104019) (xy 45.296786 -342.133505)
			(xy 45.338 -342.16922) (xy 45.373712 -342.210437) (xy 45.403195 -342.256316) (xy 45.425849 -342.305924)
			(xy 45.441213 -342.358251) (xy 45.448974 -342.412232) (xy 45.448974 -342.466768) (xy 45.448974 -342.466769)
			(xy 46.931822 -342.466769) (xy 46.931822 -342.412231) (xy 46.939584 -342.358248) (xy 46.954949 -342.305919)
			(xy 46.977604 -342.25631) (xy 47.007089 -342.210429) (xy 47.042803 -342.169212) (xy 47.08402 -342.133496)
			(xy 47.129899 -342.10401) (xy 47.179508 -342.081353) (xy 47.231836 -342.065986) (xy 47.285819 -342.058223)
			(xy 47.313088 -342.057736) (xy 48.176688 -342.057736) (xy 48.203959 -342.058203) (xy 48.257947 -342.065963)
			(xy 48.310281 -342.081329) (xy 48.359896 -342.103985) (xy 48.40578 -342.133472) (xy 48.447002 -342.16919)
			(xy 48.48272 -342.21041) (xy 48.512209 -342.256294) (xy 48.534867 -342.305908) (xy 48.550234 -342.358241)
			(xy 48.557996 -342.412229) (xy 48.557996 -342.466771) (xy 48.557996 -342.466773) (xy 50.0407 -342.466773)
			(xy 50.0407 -342.412227) (xy 50.048463 -342.358235) (xy 50.063832 -342.305899) (xy 50.086493 -342.256282)
			(xy 50.115985 -342.210396) (xy 50.151708 -342.169174) (xy 50.192934 -342.133456) (xy 50.238824 -342.10397)
			(xy 50.288444 -342.081315) (xy 50.340782 -342.065953) (xy 50.394775 -342.058196) (xy 50.422048 -342.057736)
			(xy 51.285648 -342.057736) (xy 51.312915 -342.05823) (xy 51.366893 -342.065997) (xy 51.419217 -342.081366)
			(xy 51.46882 -342.104025) (xy 51.514695 -342.133512) (xy 51.555907 -342.169227) (xy 51.591617 -342.210443)
			(xy 51.621098 -342.256322) (xy 51.643751 -342.305928) (xy 51.659113 -342.358254) (xy 51.666874 -342.412233)
			(xy 51.666874 -342.466767) (xy 51.666873 -342.466773) (xy 60.9909 -342.466773) (xy 60.9909 -342.412227)
			(xy 60.998663 -342.358236) (xy 61.014031 -342.3059) (xy 61.036692 -342.256284) (xy 61.066184 -342.210398)
			(xy 61.101906 -342.169176) (xy 61.143131 -342.133459) (xy 61.18902 -342.103972) (xy 61.238639 -342.081317)
			(xy 61.290977 -342.065954) (xy 61.344969 -342.058197) (xy 61.372242 -342.057736) (xy 62.235842 -342.057736)
			(xy 62.263109 -342.058229) (xy 62.317088 -342.065996) (xy 62.369412 -342.081365) (xy 62.419017 -342.104023)
			(xy 62.464892 -342.13351) (xy 62.506105 -342.169225) (xy 62.541815 -342.210441) (xy 62.571297 -342.25632)
			(xy 62.59395 -342.305927) (xy 62.609313 -342.358253) (xy 62.617074 -342.412233) (xy 62.617074 -342.466767)
			(xy 62.617073 -342.466771) (xy 64.099899 -342.466771) (xy 64.099899 -342.412229) (xy 64.107662 -342.358241)
			(xy 64.123028 -342.305908) (xy 64.145686 -342.256295) (xy 64.175174 -342.210411) (xy 64.210892 -342.16919)
			(xy 64.252112 -342.133473) (xy 64.297997 -342.103985) (xy 64.34761 -342.081327) (xy 64.399943 -342.065961)
			(xy 64.453931 -342.058199) (xy 64.481202 -342.057736) (xy 65.344802 -342.057736) (xy 65.372071 -342.058227)
			(xy 65.426054 -342.065988) (xy 65.478383 -342.081354) (xy 65.527993 -342.10401) (xy 65.573873 -342.133496)
			(xy 65.615091 -342.169211) (xy 65.650805 -342.210428) (xy 65.680291 -342.256309) (xy 65.702947 -342.305919)
			(xy 65.718312 -342.358248) (xy 65.726074 -342.412231) (xy 65.726074 -342.466768) (xy 67.208922 -342.466768)
			(xy 67.208922 -342.412232) (xy 67.216683 -342.358252) (xy 67.232047 -342.305925) (xy 67.2547 -342.256317)
			(xy 67.284183 -342.210438) (xy 67.319894 -342.169221) (xy 67.361107 -342.133505) (xy 67.406984 -342.104018)
			(xy 67.456589 -342.08136) (xy 67.508914 -342.065991) (xy 67.562894 -342.058225) (xy 67.590162 -342.057736)
			(xy 68.453762 -342.057736) (xy 68.481035 -342.058201) (xy 68.535025 -342.065959) (xy 68.587362 -342.081321)
			(xy 68.63698 -342.103977) (xy 68.682868 -342.133463) (xy 68.724093 -342.16918) (xy 68.759814 -342.210401)
			(xy 68.789305 -342.256287) (xy 68.811965 -342.305902) (xy 68.827333 -342.358237) (xy 68.835096 -342.412227)
			(xy 68.835096 -342.466772) (xy 70.3178 -342.466772) (xy 70.3178 -342.412228) (xy 70.325562 -342.358239)
			(xy 70.34093 -342.305904) (xy 70.363589 -342.256289) (xy 70.393079 -342.210404) (xy 70.428799 -342.169183)
			(xy 70.470022 -342.133466) (xy 70.515909 -342.103979) (xy 70.565525 -342.081322) (xy 70.61786 -342.065958)
			(xy 70.67185 -342.058198) (xy 70.699122 -342.057736) (xy 71.562722 -342.057736) (xy 71.58999 -342.058228)
			(xy 71.643971 -342.065992) (xy 71.696298 -342.081359) (xy 71.745905 -342.104017) (xy 71.791783 -342.133503)
			(xy 71.832998 -342.169218) (xy 71.86871 -342.210435) (xy 71.898194 -342.256314) (xy 71.920848 -342.305923)
			(xy 71.936213 -342.35825) (xy 71.943974 -342.412232) (xy 71.943974 -342.466768) (xy 71.943974 -342.466769)
			(xy 73.426822 -342.466769) (xy 73.426822 -342.412231) (xy 73.434584 -342.358249) (xy 73.449948 -342.305921)
			(xy 73.472603 -342.256311) (xy 73.502087 -342.210431) (xy 73.537801 -342.169214) (xy 73.579017 -342.133498)
			(xy 73.624896 -342.104012) (xy 73.674504 -342.081354) (xy 73.726831 -342.065987) (xy 73.780813 -342.058224)
			(xy 73.808082 -342.057736) (xy 74.671682 -342.057736) (xy 74.698954 -342.058202) (xy 74.752942 -342.065962)
			(xy 74.805277 -342.081327) (xy 74.854892 -342.103983) (xy 74.900778 -342.13347) (xy 74.942 -342.169188)
			(xy 74.977719 -342.210408) (xy 75.007208 -342.256292) (xy 75.029867 -342.305906) (xy 75.045234 -342.35824)
			(xy 75.052996 -342.412228) (xy 75.052996 -342.466772) (xy 75.052996 -342.466773) (xy 76.5357 -342.466773)
			(xy 76.5357 -342.412227) (xy 76.543463 -342.358236) (xy 76.558831 -342.3059) (xy 76.581492 -342.256284)
			(xy 76.610984 -342.210398) (xy 76.646706 -342.169176) (xy 76.687931 -342.133459) (xy 76.73382 -342.103972)
			(xy 76.783439 -342.081317) (xy 76.835777 -342.065954) (xy 76.889769 -342.058197) (xy 76.917042 -342.057736)
			(xy 77.780642 -342.057736) (xy 77.807909 -342.058229) (xy 77.861888 -342.065996) (xy 77.914212 -342.081365)
			(xy 77.963817 -342.104023) (xy 78.009692 -342.13351) (xy 78.050905 -342.169225) (xy 78.086615 -342.210441)
			(xy 78.116097 -342.25632) (xy 78.13875 -342.305927) (xy 78.154113 -342.358253) (xy 78.161874 -342.412233)
			(xy 78.161874 -342.466767) (xy 78.161873 -342.466771) (xy 79.644699 -342.466771) (xy 79.644699 -342.412229)
			(xy 79.652462 -342.358241) (xy 79.667828 -342.305908) (xy 79.690486 -342.256295) (xy 79.719974 -342.210411)
			(xy 79.755692 -342.16919) (xy 79.796912 -342.133473) (xy 79.842797 -342.103985) (xy 79.89241 -342.081327)
			(xy 79.944743 -342.065961) (xy 79.998731 -342.058199) (xy 80.026002 -342.057736) (xy 80.889602 -342.057736)
			(xy 80.916871 -342.058227) (xy 80.970854 -342.065988) (xy 81.023183 -342.081354) (xy 81.072793 -342.10401)
			(xy 81.118673 -342.133496) (xy 81.159891 -342.169211) (xy 81.195605 -342.210428) (xy 81.225091 -342.256309)
			(xy 81.247747 -342.305919) (xy 81.263112 -342.358248) (xy 81.270874 -342.412231) (xy 81.270874 -342.466768)
			(xy 82.753722 -342.466768) (xy 82.753722 -342.412232) (xy 82.761483 -342.358252) (xy 82.776847 -342.305925)
			(xy 82.7995 -342.256317) (xy 82.828983 -342.210438) (xy 82.864694 -342.169221) (xy 82.905907 -342.133505)
			(xy 82.951784 -342.104018) (xy 83.001389 -342.08136) (xy 83.053714 -342.065991) (xy 83.107694 -342.058225)
			(xy 83.134962 -342.057736) (xy 83.998562 -342.057736) (xy 84.025835 -342.058201) (xy 84.079825 -342.065959)
			(xy 84.132162 -342.081321) (xy 84.18178 -342.103977) (xy 84.227668 -342.133463) (xy 84.268893 -342.16918)
			(xy 84.304614 -342.210401) (xy 84.334105 -342.256287) (xy 84.356765 -342.305902) (xy 84.372133 -342.358237)
			(xy 84.379896 -342.412227) (xy 84.379896 -342.466772) (xy 85.8626 -342.466772) (xy 85.8626 -342.412228)
			(xy 85.870362 -342.358239) (xy 85.88573 -342.305904) (xy 85.908389 -342.256289) (xy 85.937879 -342.210404)
			(xy 85.973599 -342.169183) (xy 86.014822 -342.133466) (xy 86.060709 -342.103979) (xy 86.110325 -342.081322)
			(xy 86.16266 -342.065958) (xy 86.21665 -342.058198) (xy 86.243922 -342.057736) (xy 87.107522 -342.057736)
			(xy 87.13479 -342.058228) (xy 87.188771 -342.065992) (xy 87.241098 -342.081359) (xy 87.290705 -342.104017)
			(xy 87.336583 -342.133503) (xy 87.377798 -342.169218) (xy 87.41351 -342.210435) (xy 87.442994 -342.256314)
			(xy 87.465648 -342.305923) (xy 87.481013 -342.35825) (xy 87.488774 -342.412232) (xy 87.488774 -342.466768)
			(xy 87.488774 -342.466769) (xy 88.971622 -342.466769) (xy 88.971622 -342.412231) (xy 88.979384 -342.358249)
			(xy 88.994748 -342.305921) (xy 89.017403 -342.256311) (xy 89.046887 -342.210431) (xy 89.082601 -342.169214)
			(xy 89.123817 -342.133498) (xy 89.169696 -342.104012) (xy 89.219304 -342.081354) (xy 89.271631 -342.065987)
			(xy 89.325613 -342.058224) (xy 89.352882 -342.057736) (xy 90.216482 -342.057736) (xy 90.243754 -342.058202)
			(xy 90.297742 -342.065962) (xy 90.350077 -342.081327) (xy 90.399692 -342.103983) (xy 90.445578 -342.13347)
			(xy 90.4868 -342.169188) (xy 90.522519 -342.210408) (xy 90.552008 -342.256292) (xy 90.574667 -342.305906)
			(xy 90.590034 -342.35824) (xy 90.597796 -342.412228) (xy 90.597796 -342.466772) (xy 90.597796 -342.466773)
			(xy 92.0805 -342.466773) (xy 92.0805 -342.412227) (xy 92.088263 -342.358236) (xy 92.103631 -342.3059)
			(xy 92.126292 -342.256284) (xy 92.155784 -342.210398) (xy 92.191506 -342.169176) (xy 92.232731 -342.133459)
			(xy 92.27862 -342.103972) (xy 92.328239 -342.081317) (xy 92.380577 -342.065954) (xy 92.434569 -342.058197)
			(xy 92.461842 -342.057736) (xy 93.325442 -342.057736) (xy 93.352709 -342.058229) (xy 93.406688 -342.065996)
			(xy 93.459012 -342.081365) (xy 93.508617 -342.104023) (xy 93.554492 -342.13351) (xy 93.595705 -342.169225)
			(xy 93.631415 -342.210441) (xy 93.660897 -342.25632) (xy 93.68355 -342.305927) (xy 93.698913 -342.358253)
			(xy 93.706674 -342.412233) (xy 93.706674 -342.466767) (xy 93.698913 -342.520747) (xy 93.68355 -342.573073)
			(xy 93.660897 -342.62268) (xy 93.631415 -342.668559) (xy 93.60914 -342.694268) (xy 102.35157 -342.694268)
			(xy 102.35157 -342.634332) (xy 102.359393 -342.574909) (xy 102.374905 -342.517016) (xy 102.397841 -342.461642)
			(xy 102.427809 -342.409736) (xy 102.464294 -342.362185) (xy 102.506675 -342.319804) (xy 102.554224 -342.283316)
			(xy 102.60613 -342.253347) (xy 102.661502 -342.23041) (xy 102.719395 -342.214896) (xy 102.778818 -342.207071)
			(xy 102.808786 -342.20658) (xy 103.672386 -342.20658) (xy 103.702355 -342.207072) (xy 103.76178 -342.214894)
			(xy 103.819676 -342.230405) (xy 103.875051 -342.253341) (xy 103.926959 -342.283309) (xy 103.974512 -342.319796)
			(xy 104.016895 -342.362178) (xy 104.053383 -342.409729) (xy 104.083352 -342.461636) (xy 104.085479 -342.466772)
			(xy 111.4808 -342.466772) (xy 111.4808 -342.412228) (xy 111.488562 -342.358241) (xy 111.503929 -342.305907)
			(xy 111.526587 -342.256293) (xy 111.556075 -342.210409) (xy 111.591794 -342.169188) (xy 111.633015 -342.133471)
			(xy 111.6789 -342.103983) (xy 111.728515 -342.081326) (xy 111.780848 -342.06596) (xy 111.834836 -342.058199)
			(xy 111.862108 -342.057736) (xy 112.725708 -342.057736) (xy 112.752977 -342.058227) (xy 112.806959 -342.06599)
			(xy 112.859288 -342.081355) (xy 112.908897 -342.104012) (xy 112.954776 -342.133498) (xy 112.995993 -342.169213)
			(xy 113.031707 -342.21043) (xy 113.061192 -342.256311) (xy 113.083847 -342.30592) (xy 113.099212 -342.358249)
			(xy 113.106974 -342.412231) (xy 113.106974 -342.466768) (xy 114.589822 -342.466768) (xy 114.589822 -342.412232)
			(xy 114.597583 -342.358251) (xy 114.612947 -342.305924) (xy 114.635601 -342.256315) (xy 114.665084 -342.210436)
			(xy 114.700796 -342.169219) (xy 114.74201 -342.133503) (xy 114.787887 -342.104016) (xy 114.837494 -342.081358)
			(xy 114.88982 -342.06599) (xy 114.9438 -342.058225) (xy 114.971068 -342.057736) (xy 115.834668 -342.057736)
			(xy 115.86194 -342.058201) (xy 115.91593 -342.06596) (xy 115.968267 -342.081323) (xy 116.017884 -342.103979)
			(xy 116.063771 -342.133465) (xy 116.104995 -342.169183) (xy 116.140715 -342.210403) (xy 116.170206 -342.256288)
			(xy 116.192866 -342.305903) (xy 116.208233 -342.358238) (xy 116.215996 -342.412228) (xy 116.215996 -342.466772)
			(xy 117.6987 -342.466772) (xy 117.6987 -342.412228) (xy 117.706462 -342.358238) (xy 117.72183 -342.305903)
			(xy 117.74449 -342.256288) (xy 117.77398 -342.210402) (xy 117.809701 -342.169181) (xy 117.850925 -342.133464)
			(xy 117.896812 -342.103977) (xy 117.946429 -342.08132) (xy 117.998765 -342.065957) (xy 118.052756 -342.058198)
			(xy 118.080028 -342.057736) (xy 118.943628 -342.057736) (xy 118.970896 -342.058228) (xy 119.024876 -342.065993)
			(xy 119.077202 -342.081361) (xy 119.126809 -342.104019) (xy 119.172686 -342.133505) (xy 119.2139 -342.16922)
			(xy 119.249612 -342.210437) (xy 119.279095 -342.256316) (xy 119.301749 -342.305924) (xy 119.317113 -342.358251)
			(xy 119.324874 -342.412232) (xy 119.324874 -342.466768) (xy 119.324874 -342.466769) (xy 120.807722 -342.466769)
			(xy 120.807722 -342.412231) (xy 120.815484 -342.358248) (xy 120.830849 -342.305919) (xy 120.853504 -342.25631)
			(xy 120.882989 -342.210429) (xy 120.918703 -342.169212) (xy 120.95992 -342.133496) (xy 121.005799 -342.10401)
			(xy 121.055408 -342.081353) (xy 121.107736 -342.065986) (xy 121.161719 -342.058223) (xy 121.188988 -342.057736)
			(xy 122.052588 -342.057736) (xy 122.079859 -342.058203) (xy 122.133847 -342.065963) (xy 122.186181 -342.081329)
			(xy 122.235796 -342.103985) (xy 122.28168 -342.133472) (xy 122.322902 -342.16919) (xy 122.35862 -342.21041)
			(xy 122.388109 -342.256294) (xy 122.410767 -342.305908) (xy 122.426134 -342.358241) (xy 122.433896 -342.412229)
			(xy 122.433896 -342.466771) (xy 122.433896 -342.466773) (xy 123.9166 -342.466773) (xy 123.9166 -342.412227)
			(xy 123.924363 -342.358235) (xy 123.939732 -342.305899) (xy 123.962393 -342.256282) (xy 123.991885 -342.210396)
			(xy 124.027608 -342.169174) (xy 124.068834 -342.133456) (xy 124.114724 -342.10397) (xy 124.164344 -342.081315)
			(xy 124.216682 -342.065953) (xy 124.270675 -342.058196) (xy 124.297948 -342.057736) (xy 125.161548 -342.057736)
			(xy 125.188815 -342.05823) (xy 125.242793 -342.065997) (xy 125.295117 -342.081366) (xy 125.34472 -342.104025)
			(xy 125.390595 -342.133512) (xy 125.431807 -342.169227) (xy 125.467517 -342.210443) (xy 125.496998 -342.256322)
			(xy 125.519651 -342.305928) (xy 125.535013 -342.358254) (xy 125.542774 -342.412233) (xy 125.542774 -342.466767)
			(xy 125.542773 -342.466772) (xy 127.0256 -342.466772) (xy 127.0256 -342.412228) (xy 127.033362 -342.358241)
			(xy 127.048729 -342.305907) (xy 127.071387 -342.256293) (xy 127.100875 -342.210409) (xy 127.136594 -342.169188)
			(xy 127.177815 -342.133471) (xy 127.2237 -342.103983) (xy 127.273315 -342.081326) (xy 127.325648 -342.06596)
			(xy 127.379636 -342.058199) (xy 127.406908 -342.057736) (xy 128.270508 -342.057736) (xy 128.297777 -342.058227)
			(xy 128.351759 -342.06599) (xy 128.404088 -342.081355) (xy 128.453697 -342.104012) (xy 128.499576 -342.133498)
			(xy 128.540793 -342.169213) (xy 128.576507 -342.21043) (xy 128.605992 -342.256311) (xy 128.628647 -342.30592)
			(xy 128.644012 -342.358249) (xy 128.651774 -342.412231) (xy 128.651774 -342.466768) (xy 130.134622 -342.466768)
			(xy 130.134622 -342.412232) (xy 130.142383 -342.358251) (xy 130.157747 -342.305924) (xy 130.180401 -342.256315)
			(xy 130.209884 -342.210436) (xy 130.245596 -342.169219) (xy 130.28681 -342.133503) (xy 130.332687 -342.104016)
			(xy 130.382294 -342.081358) (xy 130.43462 -342.06599) (xy 130.4886 -342.058225) (xy 130.515868 -342.057736)
			(xy 131.379468 -342.057736) (xy 131.40674 -342.058201) (xy 131.46073 -342.06596) (xy 131.513067 -342.081323)
			(xy 131.562684 -342.103979) (xy 131.608571 -342.133465) (xy 131.649795 -342.169183) (xy 131.685515 -342.210403)
			(xy 131.715006 -342.256288) (xy 131.737666 -342.305903) (xy 131.753033 -342.358238) (xy 131.760796 -342.412228)
			(xy 131.760796 -342.466772) (xy 133.2435 -342.466772) (xy 133.2435 -342.412228) (xy 133.251262 -342.358238)
			(xy 133.26663 -342.305903) (xy 133.28929 -342.256288) (xy 133.31878 -342.210402) (xy 133.354501 -342.169181)
			(xy 133.395725 -342.133464) (xy 133.441612 -342.103977) (xy 133.491229 -342.08132) (xy 133.543565 -342.065957)
			(xy 133.597556 -342.058198) (xy 133.624828 -342.057736) (xy 134.488428 -342.057736) (xy 134.515696 -342.058228)
			(xy 134.569676 -342.065993) (xy 134.622002 -342.081361) (xy 134.671609 -342.104019) (xy 134.717486 -342.133505)
			(xy 134.7587 -342.16922) (xy 134.794412 -342.210437) (xy 134.823895 -342.256316) (xy 134.846549 -342.305924)
			(xy 134.861913 -342.358251) (xy 134.869674 -342.412232) (xy 134.869674 -342.466768) (xy 134.869674 -342.466769)
			(xy 136.352522 -342.466769) (xy 136.352522 -342.412231) (xy 136.360284 -342.358248) (xy 136.375649 -342.305919)
			(xy 136.398304 -342.25631) (xy 136.427789 -342.210429) (xy 136.463503 -342.169212) (xy 136.50472 -342.133496)
			(xy 136.550599 -342.10401) (xy 136.600208 -342.081353) (xy 136.652536 -342.065986) (xy 136.706519 -342.058223)
			(xy 136.733788 -342.057736) (xy 137.597388 -342.057736) (xy 137.624659 -342.058203) (xy 137.678647 -342.065963)
			(xy 137.730981 -342.081329) (xy 137.780596 -342.103985) (xy 137.82648 -342.133472) (xy 137.867702 -342.16919)
			(xy 137.90342 -342.21041) (xy 137.932909 -342.256294) (xy 137.955567 -342.305908) (xy 137.970934 -342.358241)
			(xy 137.978696 -342.412229) (xy 137.978696 -342.466771) (xy 137.978696 -342.466773) (xy 139.4614 -342.466773)
			(xy 139.4614 -342.412227) (xy 139.469163 -342.358235) (xy 139.484532 -342.305899) (xy 139.507193 -342.256282)
			(xy 139.536685 -342.210396) (xy 139.572408 -342.169174) (xy 139.613634 -342.133456) (xy 139.659524 -342.10397)
			(xy 139.709144 -342.081315) (xy 139.761482 -342.065953) (xy 139.815475 -342.058196) (xy 139.842748 -342.057736)
			(xy 140.706348 -342.057736) (xy 140.733615 -342.05823) (xy 140.787593 -342.065997) (xy 140.839917 -342.081366)
			(xy 140.88952 -342.104025) (xy 140.935395 -342.133512) (xy 140.976607 -342.169227) (xy 141.012317 -342.210443)
			(xy 141.041798 -342.256322) (xy 141.064451 -342.305928) (xy 141.079813 -342.358254) (xy 141.087574 -342.412233)
			(xy 141.087574 -342.466767) (xy 141.087573 -342.466772) (xy 142.5704 -342.466772) (xy 142.5704 -342.412228)
			(xy 142.578162 -342.358241) (xy 142.593529 -342.305907) (xy 142.616187 -342.256293) (xy 142.645675 -342.210409)
			(xy 142.681394 -342.169188) (xy 142.722615 -342.133471) (xy 142.7685 -342.103983) (xy 142.818115 -342.081326)
			(xy 142.870448 -342.06596) (xy 142.924436 -342.058199) (xy 142.951708 -342.057736) (xy 143.815308 -342.057736)
			(xy 143.842577 -342.058227) (xy 143.896559 -342.06599) (xy 143.948888 -342.081355) (xy 143.998497 -342.104012)
			(xy 144.044376 -342.133498) (xy 144.085593 -342.169213) (xy 144.121307 -342.21043) (xy 144.150792 -342.256311)
			(xy 144.173447 -342.30592) (xy 144.188812 -342.358249) (xy 144.196574 -342.412231) (xy 144.196574 -342.466768)
			(xy 164.913822 -342.466768) (xy 164.913822 -342.412232) (xy 164.921583 -342.35825) (xy 164.936947 -342.305923)
			(xy 164.959602 -342.256314) (xy 164.989085 -342.210434) (xy 165.024797 -342.169217) (xy 165.066012 -342.133502)
			(xy 165.11189 -342.104015) (xy 165.161496 -342.081357) (xy 165.213823 -342.065989) (xy 165.267804 -342.058224)
			(xy 165.295072 -342.057736) (xy 166.158672 -342.057736) (xy 166.185944 -342.058202) (xy 166.239934 -342.06596)
			(xy 166.29227 -342.081324) (xy 166.341886 -342.10398) (xy 166.387773 -342.133467) (xy 166.428996 -342.169184)
			(xy 166.464716 -342.210405) (xy 166.494207 -342.256289) (xy 166.516866 -342.305904) (xy 166.532234 -342.358239)
			(xy 166.539996 -342.412228) (xy 166.539996 -342.466772) (xy 166.539996 -342.466773) (xy 168.0227 -342.466773)
			(xy 168.0227 -342.412227) (xy 168.030463 -342.358237) (xy 168.045831 -342.305902) (xy 168.068491 -342.256286)
			(xy 168.097981 -342.210401) (xy 168.133702 -342.16918) (xy 168.174927 -342.133462) (xy 168.220815 -342.103975)
			(xy 168.270432 -342.081319) (xy 168.322769 -342.065956) (xy 168.376759 -342.058197) (xy 168.404032 -342.057736)
			(xy 169.267632 -342.057736) (xy 169.2949 -342.058229) (xy 169.34888 -342.065994) (xy 169.401205 -342.081362)
			(xy 169.450811 -342.10402) (xy 169.496688 -342.133506) (xy 169.537901 -342.169222) (xy 169.573613 -342.210438)
			(xy 169.603095 -342.256317) (xy 169.625749 -342.305925) (xy 169.641113 -342.358252) (xy 169.648874 -342.412232)
			(xy 169.648874 -342.466768) (xy 169.648874 -342.466769) (xy 171.131722 -342.466769) (xy 171.131722 -342.412231)
			(xy 171.139484 -342.358248) (xy 171.154849 -342.305918) (xy 171.177505 -342.256309) (xy 171.20699 -342.210428)
			(xy 171.242705 -342.16921) (xy 171.283921 -342.133495) (xy 171.329802 -342.104009) (xy 171.379411 -342.081352)
			(xy 171.43174 -342.065986) (xy 171.485723 -342.058223) (xy 171.512992 -342.057736) (xy 172.376592 -342.057736)
			(xy 172.403863 -342.058203) (xy 172.457851 -342.065964) (xy 172.510184 -342.08133) (xy 172.559798 -342.103987)
			(xy 172.605682 -342.133474) (xy 172.646903 -342.169191) (xy 172.682621 -342.210411) (xy 172.71211 -342.256295)
			(xy 172.734768 -342.305908) (xy 172.750134 -342.358241) (xy 172.757896 -342.412229) (xy 172.757896 -342.466767)
			(xy 174.240722 -342.466767) (xy 174.240722 -342.412233) (xy 174.248483 -342.358253) (xy 174.263846 -342.305927)
			(xy 174.286499 -342.25632) (xy 174.31598 -342.210441) (xy 174.35169 -342.169224) (xy 174.392902 -342.133509)
			(xy 174.438778 -342.104022) (xy 174.488382 -342.081363) (xy 174.540706 -342.065993) (xy 174.594685 -342.058226)
			(xy 174.621952 -342.057736) (xy 175.485552 -342.057736) (xy 175.512825 -342.0582) (xy 175.566817 -342.065957)
			(xy 175.619155 -342.081319) (xy 175.668774 -342.103974) (xy 175.714663 -342.13346) (xy 175.755889 -342.169177)
			(xy 175.791612 -342.210398) (xy 175.821103 -342.256284) (xy 175.843764 -342.3059) (xy 175.859133 -342.358236)
			(xy 175.866896 -342.412227) (xy 175.866896 -342.466772) (xy 177.3496 -342.466772) (xy 177.3496 -342.412228)
			(xy 177.357362 -342.35824) (xy 177.372729 -342.305906) (xy 177.395388 -342.256292) (xy 177.424876 -342.210407)
			(xy 177.460595 -342.169187) (xy 177.501817 -342.133469) (xy 177.547703 -342.103982) (xy 177.597317 -342.081325)
			(xy 177.649652 -342.065959) (xy 177.70364 -342.058199) (xy 177.730912 -342.057736) (xy 178.594512 -342.057736)
			(xy 178.621781 -342.058227) (xy 178.675763 -342.06599) (xy 178.728091 -342.081357) (xy 178.777699 -342.104013)
			(xy 178.823578 -342.133499) (xy 178.864794 -342.169214) (xy 178.900508 -342.210432) (xy 178.929992 -342.256312)
			(xy 178.952648 -342.305921) (xy 178.968012 -342.358249) (xy 178.975774 -342.412231) (xy 178.975774 -342.466768)
			(xy 180.458622 -342.466768) (xy 180.458622 -342.412232) (xy 180.466383 -342.35825) (xy 180.481747 -342.305923)
			(xy 180.504402 -342.256314) (xy 180.533885 -342.210434) (xy 180.569597 -342.169217) (xy 180.610812 -342.133502)
			(xy 180.65669 -342.104015) (xy 180.706296 -342.081357) (xy 180.758623 -342.065989) (xy 180.812604 -342.058224)
			(xy 180.839872 -342.057736) (xy 181.703472 -342.057736) (xy 181.730744 -342.058202) (xy 181.784734 -342.06596)
			(xy 181.83707 -342.081324) (xy 181.886686 -342.10398) (xy 181.932573 -342.133467) (xy 181.973796 -342.169184)
			(xy 182.009516 -342.210405) (xy 182.039007 -342.256289) (xy 182.061666 -342.305904) (xy 182.077034 -342.358239)
			(xy 182.084796 -342.412228) (xy 182.084796 -342.466772) (xy 182.084796 -342.466773) (xy 183.5675 -342.466773)
			(xy 183.5675 -342.412227) (xy 183.575263 -342.358237) (xy 183.590631 -342.305902) (xy 183.613291 -342.256286)
			(xy 183.642781 -342.210401) (xy 183.678502 -342.16918) (xy 183.719727 -342.133462) (xy 183.765615 -342.103975)
			(xy 183.815232 -342.081319) (xy 183.867569 -342.065956) (xy 183.921559 -342.058197) (xy 183.948832 -342.057736)
			(xy 184.812432 -342.057736) (xy 184.8397 -342.058229) (xy 184.89368 -342.065994) (xy 184.946005 -342.081362)
			(xy 184.995611 -342.10402) (xy 185.041488 -342.133506) (xy 185.082701 -342.169222) (xy 185.118413 -342.210438)
			(xy 185.147895 -342.256317) (xy 185.170549 -342.305925) (xy 185.185913 -342.358252) (xy 185.193674 -342.412232)
			(xy 185.193674 -342.466768) (xy 185.193674 -342.466769) (xy 186.676522 -342.466769) (xy 186.676522 -342.412231)
			(xy 186.684284 -342.358248) (xy 186.699649 -342.305918) (xy 186.722305 -342.256309) (xy 186.75179 -342.210428)
			(xy 186.787505 -342.16921) (xy 186.828721 -342.133495) (xy 186.874602 -342.104009) (xy 186.924211 -342.081352)
			(xy 186.97654 -342.065986) (xy 187.030523 -342.058223) (xy 187.057792 -342.057736) (xy 187.921392 -342.057736)
			(xy 187.948663 -342.058203) (xy 188.002651 -342.065964) (xy 188.054984 -342.08133) (xy 188.104598 -342.103987)
			(xy 188.150482 -342.133474) (xy 188.191703 -342.169191) (xy 188.227421 -342.210411) (xy 188.25691 -342.256295)
			(xy 188.279568 -342.305908) (xy 188.294934 -342.358241) (xy 188.302696 -342.412229) (xy 188.302696 -342.466767)
			(xy 189.785522 -342.466767) (xy 189.785522 -342.412233) (xy 189.793283 -342.358253) (xy 189.808646 -342.305927)
			(xy 189.831299 -342.25632) (xy 189.86078 -342.210441) (xy 189.89649 -342.169224) (xy 189.937702 -342.133509)
			(xy 189.983578 -342.104022) (xy 190.033182 -342.081363) (xy 190.085506 -342.065993) (xy 190.139485 -342.058226)
			(xy 190.166752 -342.057736) (xy 191.030352 -342.057736) (xy 191.057625 -342.0582) (xy 191.111617 -342.065957)
			(xy 191.163955 -342.081319) (xy 191.213574 -342.103974) (xy 191.259463 -342.13346) (xy 191.300689 -342.169177)
			(xy 191.336412 -342.210398) (xy 191.365903 -342.256284) (xy 191.388564 -342.3059) (xy 191.403933 -342.358236)
			(xy 191.411696 -342.412227) (xy 191.411696 -342.466772) (xy 192.8944 -342.466772) (xy 192.8944 -342.412228)
			(xy 192.902162 -342.35824) (xy 192.917529 -342.305906) (xy 192.940188 -342.256292) (xy 192.969676 -342.210407)
			(xy 193.005395 -342.169187) (xy 193.046617 -342.133469) (xy 193.092503 -342.103982) (xy 193.142117 -342.081325)
			(xy 193.194452 -342.065959) (xy 193.24844 -342.058199) (xy 193.275712 -342.057736) (xy 194.139312 -342.057736)
			(xy 194.166581 -342.058227) (xy 194.220563 -342.06599) (xy 194.272891 -342.081357) (xy 194.322499 -342.104013)
			(xy 194.368378 -342.133499) (xy 194.409594 -342.169214) (xy 194.445308 -342.210432) (xy 194.474792 -342.256312)
			(xy 194.497448 -342.305921) (xy 194.512812 -342.358249) (xy 194.520574 -342.412231) (xy 194.520574 -342.466768)
			(xy 196.003422 -342.466768) (xy 196.003422 -342.412232) (xy 196.011183 -342.35825) (xy 196.026547 -342.305923)
			(xy 196.049202 -342.256314) (xy 196.078685 -342.210434) (xy 196.114397 -342.169217) (xy 196.155612 -342.133502)
			(xy 196.20149 -342.104015) (xy 196.251096 -342.081357) (xy 196.303423 -342.065989) (xy 196.357404 -342.058224)
			(xy 196.384672 -342.057736) (xy 197.248272 -342.057736) (xy 197.275544 -342.058202) (xy 197.28821 -342.060022)
			(xy 255.91262 -342.060022) (xy 255.91262 -341.196422) (xy 255.91311 -341.166438) (xy 255.920938 -341.106982)
			(xy 255.936459 -341.049057) (xy 255.959408 -340.993653) (xy 255.989392 -340.941719) (xy 256.025898 -340.894143)
			(xy 256.068303 -340.851738) (xy 256.115879 -340.815232) (xy 256.167813 -340.785248) (xy 256.223217 -340.762299)
			(xy 256.281142 -340.746778) (xy 256.340598 -340.73895) (xy 256.400566 -340.73895) (xy 256.460022 -340.746778)
			(xy 256.517947 -340.762299) (xy 256.573351 -340.785248) (xy 256.625285 -340.815232) (xy 256.672861 -340.851738)
			(xy 256.715266 -340.894143) (xy 256.751772 -340.941719) (xy 256.781756 -340.993653) (xy 256.804705 -341.049057)
			(xy 256.820226 -341.106982) (xy 256.828054 -341.166438) (xy 256.828544 -341.196422) (xy 256.828544 -342.060022)
			(xy 256.828054 -342.090006) (xy 256.820226 -342.149462) (xy 256.804705 -342.207387) (xy 256.781756 -342.262791)
			(xy 256.751772 -342.314725) (xy 256.715266 -342.362301) (xy 256.672861 -342.404706) (xy 256.625285 -342.441212)
			(xy 256.581015 -342.466771) (xy 267.515799 -342.466771) (xy 267.515799 -342.412229) (xy 267.523562 -342.358241)
			(xy 267.538928 -342.305908) (xy 267.561586 -342.256295) (xy 267.591074 -342.210411) (xy 267.626792 -342.16919)
			(xy 267.668012 -342.133473) (xy 267.713897 -342.103985) (xy 267.76351 -342.081327) (xy 267.815843 -342.065961)
			(xy 267.869831 -342.058199) (xy 267.897102 -342.057736) (xy 268.760702 -342.057736) (xy 268.787971 -342.058227)
			(xy 268.841954 -342.065988) (xy 268.894283 -342.081354) (xy 268.943893 -342.10401) (xy 268.989773 -342.133496)
			(xy 269.030991 -342.169211) (xy 269.066705 -342.210428) (xy 269.096191 -342.256309) (xy 269.118847 -342.305919)
			(xy 269.134212 -342.358248) (xy 269.141974 -342.412231) (xy 269.141974 -342.466768) (xy 270.624822 -342.466768)
			(xy 270.624822 -342.412232) (xy 270.632583 -342.358252) (xy 270.647947 -342.305925) (xy 270.6706 -342.256317)
			(xy 270.700083 -342.210438) (xy 270.735794 -342.169221) (xy 270.777007 -342.133505) (xy 270.822884 -342.104018)
			(xy 270.872489 -342.08136) (xy 270.924814 -342.065991) (xy 270.978794 -342.058225) (xy 271.006062 -342.057736)
			(xy 271.869662 -342.057736) (xy 271.896935 -342.058201) (xy 271.950925 -342.065959) (xy 272.003262 -342.081321)
			(xy 272.05288 -342.103977) (xy 272.098768 -342.133463) (xy 272.139993 -342.16918) (xy 272.175714 -342.210401)
			(xy 272.205205 -342.256287) (xy 272.227865 -342.305902) (xy 272.243233 -342.358237) (xy 272.250996 -342.412227)
			(xy 272.250996 -342.466772) (xy 273.7337 -342.466772) (xy 273.7337 -342.412228) (xy 273.741462 -342.358239)
			(xy 273.75683 -342.305904) (xy 273.779489 -342.256289) (xy 273.808979 -342.210404) (xy 273.844699 -342.169183)
			(xy 273.885922 -342.133466) (xy 273.931809 -342.103979) (xy 273.981425 -342.081322) (xy 274.03376 -342.065958)
			(xy 274.08775 -342.058198) (xy 274.115022 -342.057736) (xy 274.978622 -342.057736) (xy 275.00589 -342.058228)
			(xy 275.059871 -342.065992) (xy 275.112198 -342.081359) (xy 275.161805 -342.104017) (xy 275.207683 -342.133503)
			(xy 275.248898 -342.169218) (xy 275.28461 -342.210435) (xy 275.314094 -342.256314) (xy 275.336748 -342.305923)
			(xy 275.352113 -342.35825) (xy 275.359874 -342.412232) (xy 275.359874 -342.466768) (xy 275.359874 -342.466769)
			(xy 276.842722 -342.466769) (xy 276.842722 -342.412231) (xy 276.850484 -342.358249) (xy 276.865848 -342.305921)
			(xy 276.888503 -342.256311) (xy 276.917987 -342.210431) (xy 276.953701 -342.169214) (xy 276.994917 -342.133498)
			(xy 277.040796 -342.104012) (xy 277.090404 -342.081354) (xy 277.142731 -342.065987) (xy 277.196713 -342.058224)
			(xy 277.223982 -342.057736) (xy 278.087582 -342.057736) (xy 278.114854 -342.058202) (xy 278.168842 -342.065962)
			(xy 278.221177 -342.081327) (xy 278.270792 -342.103983) (xy 278.316678 -342.13347) (xy 278.3579 -342.169188)
			(xy 278.393619 -342.210408) (xy 278.423108 -342.256292) (xy 278.445767 -342.305906) (xy 278.461134 -342.35824)
			(xy 278.468896 -342.412228) (xy 278.468896 -342.466772) (xy 278.468896 -342.466773) (xy 279.9516 -342.466773)
			(xy 279.9516 -342.412227) (xy 279.959363 -342.358236) (xy 279.974731 -342.3059) (xy 279.997392 -342.256284)
			(xy 280.026884 -342.210398) (xy 280.062606 -342.169176) (xy 280.103831 -342.133459) (xy 280.14972 -342.103972)
			(xy 280.199339 -342.081317) (xy 280.251677 -342.065954) (xy 280.305669 -342.058197) (xy 280.332942 -342.057736)
			(xy 281.196542 -342.057736) (xy 281.223809 -342.058229) (xy 281.277788 -342.065996) (xy 281.330112 -342.081365)
			(xy 281.379717 -342.104023) (xy 281.425592 -342.13351) (xy 281.466805 -342.169225) (xy 281.502515 -342.210441)
			(xy 281.531997 -342.25632) (xy 281.55465 -342.305927) (xy 281.570013 -342.358253) (xy 281.577774 -342.412233)
			(xy 281.577774 -342.466767) (xy 281.577773 -342.466771) (xy 283.060599 -342.466771) (xy 283.060599 -342.412229)
			(xy 283.068362 -342.358241) (xy 283.083728 -342.305908) (xy 283.106386 -342.256295) (xy 283.135874 -342.210411)
			(xy 283.171592 -342.16919) (xy 283.212812 -342.133473) (xy 283.258697 -342.103985) (xy 283.30831 -342.081327)
			(xy 283.360643 -342.065961) (xy 283.414631 -342.058199) (xy 283.441902 -342.057736) (xy 284.305502 -342.057736)
			(xy 284.332771 -342.058227) (xy 284.386754 -342.065988) (xy 284.439083 -342.081354) (xy 284.488693 -342.10401)
			(xy 284.534573 -342.133496) (xy 284.575791 -342.169211) (xy 284.611505 -342.210428) (xy 284.640991 -342.256309)
			(xy 284.663647 -342.305919) (xy 284.679012 -342.358248) (xy 284.686774 -342.412231) (xy 284.686774 -342.466768)
			(xy 286.169622 -342.466768) (xy 286.169622 -342.412232) (xy 286.177383 -342.358252) (xy 286.192747 -342.305925)
			(xy 286.2154 -342.256317) (xy 286.244883 -342.210438) (xy 286.280594 -342.169221) (xy 286.321807 -342.133505)
			(xy 286.367684 -342.104018) (xy 286.417289 -342.08136) (xy 286.469614 -342.065991) (xy 286.523594 -342.058225)
			(xy 286.550862 -342.057736) (xy 287.414462 -342.057736) (xy 287.441735 -342.058201) (xy 287.495725 -342.065959)
			(xy 287.548062 -342.081321) (xy 287.59768 -342.103977) (xy 287.643568 -342.133463) (xy 287.684793 -342.16918)
			(xy 287.720514 -342.210401) (xy 287.750005 -342.256287) (xy 287.772665 -342.305902) (xy 287.788033 -342.358237)
			(xy 287.795796 -342.412227) (xy 287.795796 -342.466772) (xy 289.2785 -342.466772) (xy 289.2785 -342.412228)
			(xy 289.286262 -342.358239) (xy 289.30163 -342.305904) (xy 289.324289 -342.256289) (xy 289.353779 -342.210404)
			(xy 289.389499 -342.169183) (xy 289.430722 -342.133466) (xy 289.476609 -342.103979) (xy 289.526225 -342.081322)
			(xy 289.57856 -342.065958) (xy 289.63255 -342.058198) (xy 289.659822 -342.057736) (xy 290.523422 -342.057736)
			(xy 290.55069 -342.058228) (xy 290.604671 -342.065992) (xy 290.656998 -342.081359) (xy 290.706605 -342.104017)
			(xy 290.752483 -342.133503) (xy 290.793698 -342.169218) (xy 290.82941 -342.210435) (xy 290.858894 -342.256314)
			(xy 290.881548 -342.305923) (xy 290.896913 -342.35825) (xy 290.904674 -342.412232) (xy 290.904674 -342.466768)
			(xy 290.904674 -342.466769) (xy 292.387522 -342.466769) (xy 292.387522 -342.412231) (xy 292.395284 -342.358249)
			(xy 292.410648 -342.305921) (xy 292.433303 -342.256311) (xy 292.462787 -342.210431) (xy 292.498501 -342.169214)
			(xy 292.539717 -342.133498) (xy 292.585596 -342.104012) (xy 292.635204 -342.081354) (xy 292.687531 -342.065987)
			(xy 292.741513 -342.058224) (xy 292.768782 -342.057736) (xy 293.632382 -342.057736) (xy 293.659654 -342.058202)
			(xy 293.713642 -342.065962) (xy 293.765977 -342.081327) (xy 293.815592 -342.103983) (xy 293.861478 -342.13347)
			(xy 293.9027 -342.169188) (xy 293.938419 -342.210408) (xy 293.967908 -342.256292) (xy 293.990567 -342.305906)
			(xy 294.005934 -342.35824) (xy 294.013696 -342.412228) (xy 294.013696 -342.466772) (xy 294.013696 -342.466773)
			(xy 295.4964 -342.466773) (xy 295.4964 -342.412227) (xy 295.504163 -342.358236) (xy 295.519531 -342.3059)
			(xy 295.542192 -342.256284) (xy 295.571684 -342.210398) (xy 295.607406 -342.169176) (xy 295.648631 -342.133459)
			(xy 295.69452 -342.103972) (xy 295.744139 -342.081317) (xy 295.796477 -342.065954) (xy 295.850469 -342.058197)
			(xy 295.877742 -342.057736) (xy 296.741342 -342.057736) (xy 296.768609 -342.058229) (xy 296.822588 -342.065996)
			(xy 296.874912 -342.081365) (xy 296.924517 -342.104023) (xy 296.970392 -342.13351) (xy 297.011605 -342.169225)
			(xy 297.047315 -342.210441) (xy 297.076797 -342.25632) (xy 297.09945 -342.305927) (xy 297.114813 -342.358253)
			(xy 297.122574 -342.412233) (xy 297.122574 -342.466767) (xy 297.122573 -342.466771) (xy 298.605399 -342.466771)
			(xy 298.605399 -342.412229) (xy 298.613162 -342.358241) (xy 298.628528 -342.305908) (xy 298.651186 -342.256295)
			(xy 298.680674 -342.210411) (xy 298.716392 -342.16919) (xy 298.757612 -342.133473) (xy 298.803497 -342.103985)
			(xy 298.85311 -342.081327) (xy 298.905443 -342.065961) (xy 298.959431 -342.058199) (xy 298.986702 -342.057736)
			(xy 299.850302 -342.057736) (xy 299.877571 -342.058227) (xy 299.931554 -342.065988) (xy 299.983883 -342.081354)
			(xy 300.033493 -342.10401) (xy 300.079373 -342.133496) (xy 300.120591 -342.169211) (xy 300.156305 -342.210428)
			(xy 300.185791 -342.256309) (xy 300.208447 -342.305919) (xy 300.223812 -342.358248) (xy 300.231574 -342.412231)
			(xy 300.231574 -342.466769) (xy 300.231574 -342.466771) (xy 312.1215 -342.466771) (xy 312.1215 -342.412229)
			(xy 312.129262 -342.358241) (xy 312.144628 -342.305908) (xy 312.167286 -342.256294) (xy 312.196774 -342.21041)
			(xy 312.232493 -342.16919) (xy 312.273713 -342.133472) (xy 312.319598 -342.103984) (xy 312.369212 -342.081327)
			(xy 312.421545 -342.065961) (xy 312.475533 -342.058199) (xy 312.502804 -342.057736) (xy 313.366404 -342.057736)
			(xy 313.393673 -342.058227) (xy 313.447656 -342.065989) (xy 313.499985 -342.081354) (xy 313.549594 -342.104011)
			(xy 313.595474 -342.133497) (xy 313.636691 -342.169212) (xy 313.672406 -342.210429) (xy 313.701891 -342.256309)
			(xy 313.724547 -342.305919) (xy 313.739912 -342.358248) (xy 313.747674 -342.412231) (xy 313.747674 -342.466768)
			(xy 315.230522 -342.466768) (xy 315.230522 -342.412232) (xy 315.238283 -342.358251) (xy 315.253647 -342.305924)
			(xy 315.2763 -342.256316) (xy 315.305783 -342.210437) (xy 315.341495 -342.16922) (xy 315.382708 -342.133505)
			(xy 315.428585 -342.104018) (xy 315.478191 -342.081359) (xy 315.530516 -342.065991) (xy 315.584496 -342.058225)
			(xy 315.611764 -342.057736) (xy 316.475364 -342.057736) (xy 316.502637 -342.058201) (xy 316.556627 -342.065959)
			(xy 316.608964 -342.081322) (xy 316.658581 -342.103977) (xy 316.704469 -342.133464) (xy 316.745693 -342.169181)
			(xy 316.781414 -342.210402) (xy 316.810905 -342.256287) (xy 316.833565 -342.305902) (xy 316.848933 -342.358238)
			(xy 316.856696 -342.412228) (xy 316.856696 -342.466772) (xy 318.3394 -342.466772) (xy 318.3394 -342.412228)
			(xy 318.347162 -342.358239) (xy 318.36253 -342.305904) (xy 318.385189 -342.256289) (xy 318.414679 -342.210404)
			(xy 318.4504 -342.169183) (xy 318.491623 -342.133465) (xy 318.53751 -342.103978) (xy 318.587126 -342.081322)
			(xy 318.639462 -342.065957) (xy 318.693452 -342.058198) (xy 318.720724 -342.057736) (xy 319.584324 -342.057736)
			(xy 319.611592 -342.058228) (xy 319.665573 -342.065992) (xy 319.717899 -342.08136) (xy 319.767506 -342.104017)
			(xy 319.813384 -342.133504) (xy 319.854598 -342.169219) (xy 319.890311 -342.210435) (xy 319.919794 -342.256315)
			(xy 319.942449 -342.305923) (xy 319.957813 -342.358251) (xy 319.965574 -342.412232) (xy 319.965574 -342.466768)
			(xy 319.965574 -342.466769) (xy 321.448422 -342.466769) (xy 321.448422 -342.412231) (xy 321.456184 -342.358249)
			(xy 321.471548 -342.30592) (xy 321.494203 -342.256311) (xy 321.523688 -342.21043) (xy 321.559402 -342.169213)
			(xy 321.600618 -342.133498) (xy 321.646497 -342.104011) (xy 321.696105 -342.081354) (xy 321.748433 -342.065987)
			(xy 321.802415 -342.058224) (xy 321.829684 -342.057736) (xy 322.693284 -342.057736) (xy 322.720556 -342.058202)
			(xy 322.774544 -342.065963) (xy 322.826878 -342.081327) (xy 322.876493 -342.103984) (xy 322.922379 -342.133471)
			(xy 322.9636 -342.169188) (xy 322.999319 -342.210409) (xy 323.028808 -342.256293) (xy 323.051467 -342.305907)
			(xy 323.066834 -342.35824) (xy 323.074596 -342.412228) (xy 323.074596 -342.466772) (xy 323.074596 -342.466773)
			(xy 324.5573 -342.466773) (xy 324.5573 -342.412227) (xy 324.565063 -342.358236) (xy 324.580432 -342.305899)
			(xy 324.603092 -342.256283) (xy 324.632584 -342.210397) (xy 324.668307 -342.169176) (xy 324.709532 -342.133458)
			(xy 324.755422 -342.103971) (xy 324.805041 -342.081316) (xy 324.857379 -342.065954) (xy 324.911371 -342.058196)
			(xy 324.938644 -342.057736) (xy 325.802244 -342.057736) (xy 325.829511 -342.058229) (xy 325.88349 -342.065996)
			(xy 325.935814 -342.081365) (xy 325.985418 -342.104024) (xy 326.031293 -342.133511) (xy 326.072505 -342.169226)
			(xy 326.108216 -342.210442) (xy 326.137697 -342.256321) (xy 326.16035 -342.305928) (xy 326.175713 -342.358253)
			(xy 326.183474 -342.412233) (xy 326.183474 -342.466767) (xy 326.183473 -342.466771) (xy 327.6663 -342.466771)
			(xy 327.6663 -342.412229) (xy 327.674062 -342.358241) (xy 327.689428 -342.305908) (xy 327.712086 -342.256294)
			(xy 327.741574 -342.21041) (xy 327.777293 -342.16919) (xy 327.818513 -342.133472) (xy 327.864398 -342.103984)
			(xy 327.914012 -342.081327) (xy 327.966345 -342.065961) (xy 328.020333 -342.058199) (xy 328.047604 -342.057736)
			(xy 328.911204 -342.057736) (xy 328.938473 -342.058227) (xy 328.992456 -342.065989) (xy 329.044785 -342.081354)
			(xy 329.094394 -342.104011) (xy 329.140274 -342.133497) (xy 329.181491 -342.169212) (xy 329.217206 -342.210429)
			(xy 329.246691 -342.256309) (xy 329.269347 -342.305919) (xy 329.284712 -342.358248) (xy 329.292474 -342.412231)
			(xy 329.292474 -342.466768) (xy 330.775322 -342.466768) (xy 330.775322 -342.412232) (xy 330.783083 -342.358251)
			(xy 330.798447 -342.305924) (xy 330.8211 -342.256316) (xy 330.850583 -342.210437) (xy 330.886295 -342.16922)
			(xy 330.927508 -342.133505) (xy 330.973385 -342.104018) (xy 331.022991 -342.081359) (xy 331.075316 -342.065991)
			(xy 331.129296 -342.058225) (xy 331.156564 -342.057736) (xy 332.020164 -342.057736) (xy 332.047437 -342.058201)
			(xy 332.101427 -342.065959) (xy 332.153764 -342.081322) (xy 332.203381 -342.103977) (xy 332.249269 -342.133464)
			(xy 332.290493 -342.169181) (xy 332.326214 -342.210402) (xy 332.355705 -342.256287) (xy 332.378365 -342.305902)
			(xy 332.393733 -342.358238) (xy 332.401496 -342.412228) (xy 332.401496 -342.466772) (xy 333.8842 -342.466772)
			(xy 333.8842 -342.412228) (xy 333.891962 -342.358239) (xy 333.90733 -342.305904) (xy 333.929989 -342.256289)
			(xy 333.959479 -342.210404) (xy 333.9952 -342.169183) (xy 334.036423 -342.133465) (xy 334.08231 -342.103978)
			(xy 334.131926 -342.081322) (xy 334.184262 -342.065957) (xy 334.238252 -342.058198) (xy 334.265524 -342.057736)
			(xy 335.129124 -342.057736) (xy 335.156392 -342.058228) (xy 335.210373 -342.065992) (xy 335.262699 -342.08136)
			(xy 335.312306 -342.104017) (xy 335.358184 -342.133504) (xy 335.399398 -342.169219) (xy 335.435111 -342.210435)
			(xy 335.464594 -342.256315) (xy 335.487249 -342.305923) (xy 335.502613 -342.358251) (xy 335.510374 -342.412232)
			(xy 335.510374 -342.466768) (xy 335.510374 -342.466769) (xy 336.993222 -342.466769) (xy 336.993222 -342.412231)
			(xy 337.000984 -342.358249) (xy 337.016348 -342.30592) (xy 337.039003 -342.256311) (xy 337.068488 -342.21043)
			(xy 337.104202 -342.169213) (xy 337.145418 -342.133498) (xy 337.191297 -342.104011) (xy 337.240905 -342.081354)
			(xy 337.293233 -342.065987) (xy 337.347215 -342.058224) (xy 337.374484 -342.057736) (xy 338.238084 -342.057736)
			(xy 338.265356 -342.058202) (xy 338.319344 -342.065963) (xy 338.371678 -342.081327) (xy 338.421293 -342.103984)
			(xy 338.467179 -342.133471) (xy 338.5084 -342.169188) (xy 338.544119 -342.210409) (xy 338.573608 -342.256293)
			(xy 338.596267 -342.305907) (xy 338.611634 -342.35824) (xy 338.619396 -342.412228) (xy 338.619396 -342.466772)
			(xy 338.619396 -342.466773) (xy 340.1021 -342.466773) (xy 340.1021 -342.412227) (xy 340.109863 -342.358236)
			(xy 340.125232 -342.305899) (xy 340.147892 -342.256283) (xy 340.177384 -342.210397) (xy 340.213107 -342.169176)
			(xy 340.254332 -342.133458) (xy 340.300222 -342.103971) (xy 340.349841 -342.081316) (xy 340.402179 -342.065954)
			(xy 340.456171 -342.058196) (xy 340.483444 -342.057736) (xy 341.347044 -342.057736) (xy 341.374311 -342.058229)
			(xy 341.42829 -342.065996) (xy 341.480614 -342.081365) (xy 341.530218 -342.104024) (xy 341.576093 -342.133511)
			(xy 341.617305 -342.169226) (xy 341.653016 -342.210442) (xy 341.682497 -342.256321) (xy 341.70515 -342.305928)
			(xy 341.720513 -342.358253) (xy 341.728274 -342.412233) (xy 341.728274 -342.466767) (xy 341.728273 -342.466771)
			(xy 343.2111 -342.466771) (xy 343.2111 -342.412229) (xy 343.218862 -342.358241) (xy 343.234228 -342.305908)
			(xy 343.256886 -342.256294) (xy 343.286374 -342.21041) (xy 343.322093 -342.16919) (xy 343.363313 -342.133472)
			(xy 343.409198 -342.103984) (xy 343.458812 -342.081327) (xy 343.511145 -342.065961) (xy 343.565133 -342.058199)
			(xy 343.592404 -342.057736) (xy 344.456004 -342.057736) (xy 344.483273 -342.058227) (xy 344.537256 -342.065989)
			(xy 344.589585 -342.081354) (xy 344.639194 -342.104011) (xy 344.685074 -342.133497) (xy 344.726291 -342.169212)
			(xy 344.762006 -342.210429) (xy 344.791491 -342.256309) (xy 344.814147 -342.305919) (xy 344.829512 -342.358248)
			(xy 344.837274 -342.412231) (xy 344.837274 -342.466769) (xy 370.806722 -342.466769) (xy 370.806722 -342.412231)
			(xy 370.814484 -342.358249) (xy 370.829848 -342.305921) (xy 370.852503 -342.256312) (xy 370.881987 -342.210432)
			(xy 370.9177 -342.169214) (xy 370.958916 -342.133499) (xy 371.004794 -342.104012) (xy 371.054402 -342.081355)
			(xy 371.10673 -342.065988) (xy 371.160711 -342.058224) (xy 371.18798 -342.057736) (xy 372.05158 -342.057736)
			(xy 372.078852 -342.058202) (xy 372.132841 -342.065962) (xy 372.185175 -342.081326) (xy 372.234791 -342.103983)
			(xy 372.280677 -342.13347) (xy 372.321899 -342.169187) (xy 372.357618 -342.210407) (xy 372.387108 -342.256292)
			(xy 372.409767 -342.305906) (xy 372.425134 -342.35824) (xy 372.432896 -342.412228) (xy 372.432896 -342.466772)
			(xy 372.432896 -342.466773) (xy 373.9156 -342.466773) (xy 373.9156 -342.412227) (xy 373.923363 -342.358236)
			(xy 373.938731 -342.3059) (xy 373.961392 -342.256284) (xy 373.990883 -342.210398) (xy 374.026605 -342.169177)
			(xy 374.06783 -342.133459) (xy 374.113719 -342.103973) (xy 374.163338 -342.081317) (xy 374.215676 -342.065954)
			(xy 374.269667 -342.058197) (xy 374.29694 -342.057736) (xy 375.16054 -342.057736) (xy 375.187807 -342.058229)
			(xy 375.241786 -342.065995) (xy 375.294111 -342.081364) (xy 375.343716 -342.104022) (xy 375.389591 -342.133509)
			(xy 375.430804 -342.169224) (xy 375.466515 -342.210441) (xy 375.495997 -342.256319) (xy 375.51865 -342.305927)
			(xy 375.534013 -342.358253) (xy 375.541774 -342.412233) (xy 375.541774 -342.466767) (xy 375.541774 -342.46677)
			(xy 377.024622 -342.46677) (xy 377.024622 -342.41223) (xy 377.032384 -342.358247) (xy 377.04775 -342.305917)
			(xy 377.070406 -342.256306) (xy 377.099892 -342.210425) (xy 377.135607 -342.169207) (xy 377.176825 -342.133492)
			(xy 377.222706 -342.104006) (xy 377.272317 -342.08135) (xy 377.324647 -342.065984) (xy 377.37863 -342.058222)
			(xy 377.4059 -342.057736) (xy 378.2695 -342.057736) (xy 378.296769 -342.058226) (xy 378.350753 -342.065988)
			(xy 378.403082 -342.081353) (xy 378.452692 -342.104009) (xy 378.498572 -342.133495) (xy 378.53979 -342.16921)
			(xy 378.575505 -342.210428) (xy 378.604991 -342.256308) (xy 378.627647 -342.305918) (xy 378.643012 -342.358247)
			(xy 378.650774 -342.412231) (xy 378.650774 -342.466768) (xy 380.133622 -342.466768) (xy 380.133622 -342.412232)
			(xy 380.141383 -342.358252) (xy 380.156746 -342.305925) (xy 380.1794 -342.256318) (xy 380.208882 -342.210438)
			(xy 380.244593 -342.169222) (xy 380.285806 -342.133506) (xy 380.331682 -342.104019) (xy 380.381288 -342.08136)
			(xy 380.433613 -342.065991) (xy 380.487592 -342.058225) (xy 380.51486 -342.057736) (xy 381.37846 -342.057736)
			(xy 381.405733 -342.058201) (xy 381.459724 -342.065958) (xy 381.512061 -342.081321) (xy 381.561679 -342.103976)
			(xy 381.607567 -342.133463) (xy 381.648792 -342.16918) (xy 381.684513 -342.210401) (xy 381.714005 -342.256286)
			(xy 381.736665 -342.305902) (xy 381.752033 -342.358237) (xy 381.759796 -342.412227) (xy 381.759796 -342.466772)
			(xy 383.2425 -342.466772) (xy 383.2425 -342.412228) (xy 383.250262 -342.358239) (xy 383.26563 -342.305904)
			(xy 383.288289 -342.25629) (xy 383.317778 -342.210405) (xy 383.353498 -342.169184) (xy 383.394721 -342.133466)
			(xy 383.440607 -342.103979) (xy 383.490223 -342.081323) (xy 383.542559 -342.065958) (xy 383.596548 -342.058198)
			(xy 383.62382 -342.057736) (xy 384.48742 -342.057736) (xy 384.514688 -342.058228) (xy 384.568669 -342.065992)
			(xy 384.620996 -342.081359) (xy 384.670604 -342.104016) (xy 384.716482 -342.133502) (xy 384.757697 -342.169217)
			(xy 384.79341 -342.210434) (xy 384.822894 -342.256314) (xy 384.845548 -342.305922) (xy 384.860913 -342.35825)
			(xy 384.868674 -342.412232) (xy 384.868674 -342.466768) (xy 384.868674 -342.466769) (xy 386.351522 -342.466769)
			(xy 386.351522 -342.412231) (xy 386.359284 -342.358249) (xy 386.374648 -342.305921) (xy 386.397303 -342.256312)
			(xy 386.426787 -342.210432) (xy 386.4625 -342.169214) (xy 386.503716 -342.133499) (xy 386.549594 -342.104012)
			(xy 386.599202 -342.081355) (xy 386.65153 -342.065988) (xy 386.705511 -342.058224) (xy 386.73278 -342.057736)
			(xy 387.59638 -342.057736) (xy 387.623652 -342.058202) (xy 387.677641 -342.065962) (xy 387.729975 -342.081326)
			(xy 387.779591 -342.103983) (xy 387.825477 -342.13347) (xy 387.866699 -342.169187) (xy 387.902418 -342.210407)
			(xy 387.931908 -342.256292) (xy 387.954567 -342.305906) (xy 387.969934 -342.35824) (xy 387.977696 -342.412228)
			(xy 387.977696 -342.466772) (xy 387.977696 -342.466773) (xy 389.4604 -342.466773) (xy 389.4604 -342.412227)
			(xy 389.468163 -342.358236) (xy 389.483531 -342.3059) (xy 389.506192 -342.256284) (xy 389.535683 -342.210398)
			(xy 389.571405 -342.169177) (xy 389.61263 -342.133459) (xy 389.658519 -342.103973) (xy 389.708138 -342.081317)
			(xy 389.760476 -342.065954) (xy 389.814467 -342.058197) (xy 389.84174 -342.057736) (xy 390.70534 -342.057736)
			(xy 390.732607 -342.058229) (xy 390.786586 -342.065995) (xy 390.838911 -342.081364) (xy 390.888516 -342.104022)
			(xy 390.934391 -342.133509) (xy 390.975604 -342.169224) (xy 391.011315 -342.210441) (xy 391.040797 -342.256319)
			(xy 391.06345 -342.305927) (xy 391.078813 -342.358253) (xy 391.086574 -342.412233) (xy 391.086574 -342.466767)
			(xy 391.086574 -342.46677) (xy 392.569422 -342.46677) (xy 392.569422 -342.41223) (xy 392.577184 -342.358247)
			(xy 392.59255 -342.305917) (xy 392.615206 -342.256306) (xy 392.644692 -342.210425) (xy 392.680407 -342.169207)
			(xy 392.721625 -342.133492) (xy 392.767506 -342.104006) (xy 392.817117 -342.08135) (xy 392.869447 -342.065984)
			(xy 392.92343 -342.058222) (xy 392.9507 -342.057736) (xy 393.8143 -342.057736) (xy 393.841569 -342.058226)
			(xy 393.895553 -342.065988) (xy 393.947882 -342.081353) (xy 393.997492 -342.104009) (xy 394.043372 -342.133495)
			(xy 394.08459 -342.16921) (xy 394.120305 -342.210428) (xy 394.149791 -342.256308) (xy 394.172447 -342.305918)
			(xy 394.187812 -342.358247) (xy 394.195574 -342.412231) (xy 394.195574 -342.466768) (xy 395.678422 -342.466768)
			(xy 395.678422 -342.412232) (xy 395.686183 -342.358252) (xy 395.701546 -342.305925) (xy 395.7242 -342.256318)
			(xy 395.753682 -342.210438) (xy 395.789393 -342.169222) (xy 395.830606 -342.133506) (xy 395.876482 -342.104019)
			(xy 395.926088 -342.08136) (xy 395.978413 -342.065991) (xy 396.032392 -342.058225) (xy 396.05966 -342.057736)
			(xy 396.92326 -342.057736) (xy 396.950533 -342.058201) (xy 397.004524 -342.065958) (xy 397.056861 -342.081321)
			(xy 397.106479 -342.103976) (xy 397.152367 -342.133463) (xy 397.193592 -342.16918) (xy 397.229313 -342.210401)
			(xy 397.258805 -342.256286) (xy 397.281465 -342.305902) (xy 397.296833 -342.358237) (xy 397.304596 -342.412227)
			(xy 397.304596 -342.466772) (xy 398.7873 -342.466772) (xy 398.7873 -342.412228) (xy 398.795062 -342.358239)
			(xy 398.81043 -342.305904) (xy 398.833089 -342.25629) (xy 398.862578 -342.210405) (xy 398.898298 -342.169184)
			(xy 398.939521 -342.133466) (xy 398.985407 -342.103979) (xy 399.035023 -342.081323) (xy 399.087359 -342.065958)
			(xy 399.141348 -342.058198) (xy 399.16862 -342.057736) (xy 400.03222 -342.057736) (xy 400.059488 -342.058228)
			(xy 400.113469 -342.065992) (xy 400.165796 -342.081359) (xy 400.215404 -342.104016) (xy 400.261282 -342.133502)
			(xy 400.302497 -342.169217) (xy 400.33821 -342.210434) (xy 400.367694 -342.256314) (xy 400.390348 -342.305922)
			(xy 400.405713 -342.35825) (xy 400.413474 -342.412232) (xy 400.413474 -342.466768) (xy 400.413474 -342.466769)
			(xy 401.896322 -342.466769) (xy 401.896322 -342.412231) (xy 401.904084 -342.358249) (xy 401.919448 -342.305921)
			(xy 401.942103 -342.256312) (xy 401.971587 -342.210432) (xy 402.0073 -342.169214) (xy 402.048516 -342.133499)
			(xy 402.094394 -342.104012) (xy 402.144002 -342.081355) (xy 402.19633 -342.065988) (xy 402.250311 -342.058224)
			(xy 402.27758 -342.057736) (xy 403.14118 -342.057736) (xy 403.168452 -342.058202) (xy 403.222441 -342.065962)
			(xy 403.274775 -342.081326) (xy 403.324391 -342.103983) (xy 403.370277 -342.13347) (xy 403.411499 -342.169187)
			(xy 403.447218 -342.210407) (xy 403.476708 -342.256292) (xy 403.499367 -342.305906) (xy 403.514734 -342.35824)
			(xy 403.522496 -342.412228) (xy 403.522496 -342.466769) (xy 408.913822 -342.466769) (xy 408.913822 -342.412231)
			(xy 408.921584 -342.358248) (xy 408.936949 -342.305918) (xy 408.959605 -342.256309) (xy 408.98909 -342.210428)
			(xy 409.024805 -342.16921) (xy 409.066021 -342.133495) (xy 409.111902 -342.104009) (xy 409.161511 -342.081352)
			(xy 409.21384 -342.065986) (xy 409.267823 -342.058223) (xy 409.295092 -342.057736) (xy 410.158692 -342.057736)
			(xy 410.185963 -342.058203) (xy 410.239951 -342.065964) (xy 410.292284 -342.08133) (xy 410.341898 -342.103987)
			(xy 410.387782 -342.133474) (xy 410.429003 -342.169191) (xy 410.464721 -342.210411) (xy 410.49421 -342.256295)
			(xy 410.516868 -342.305908) (xy 410.532234 -342.358241) (xy 410.539996 -342.412229) (xy 410.539996 -342.466767)
			(xy 412.022822 -342.466767) (xy 412.022822 -342.412233) (xy 412.030583 -342.358253) (xy 412.045946 -342.305927)
			(xy 412.068599 -342.25632) (xy 412.09808 -342.210441) (xy 412.13379 -342.169224) (xy 412.175002 -342.133509)
			(xy 412.220878 -342.104022) (xy 412.270482 -342.081363) (xy 412.322806 -342.065993) (xy 412.376785 -342.058226)
			(xy 412.404052 -342.057736) (xy 413.267652 -342.057736) (xy 413.294925 -342.0582) (xy 413.348917 -342.065957)
			(xy 413.401255 -342.081319) (xy 413.450874 -342.103974) (xy 413.496763 -342.13346) (xy 413.537989 -342.169177)
			(xy 413.573712 -342.210398) (xy 413.603203 -342.256284) (xy 413.625864 -342.3059) (xy 413.641233 -342.358236)
			(xy 413.648996 -342.412227) (xy 413.648996 -342.466772) (xy 415.1317 -342.466772) (xy 415.1317 -342.412228)
			(xy 415.139462 -342.35824) (xy 415.154829 -342.305906) (xy 415.177488 -342.256292) (xy 415.206976 -342.210407)
			(xy 415.242695 -342.169187) (xy 415.283917 -342.133469) (xy 415.329803 -342.103982) (xy 415.379417 -342.081325)
			(xy 415.431752 -342.065959) (xy 415.48574 -342.058199) (xy 415.513012 -342.057736) (xy 416.376612 -342.057736)
			(xy 416.403881 -342.058227) (xy 416.457863 -342.06599) (xy 416.510191 -342.081357) (xy 416.559799 -342.104013)
			(xy 416.605678 -342.133499) (xy 416.646894 -342.169214) (xy 416.682608 -342.210432) (xy 416.712092 -342.256312)
			(xy 416.734748 -342.305921) (xy 416.750112 -342.358249) (xy 416.757874 -342.412231) (xy 416.757874 -342.466768)
			(xy 418.240722 -342.466768) (xy 418.240722 -342.412232) (xy 418.248483 -342.35825) (xy 418.263847 -342.305923)
			(xy 418.286502 -342.256314) (xy 418.315985 -342.210434) (xy 418.351697 -342.169217) (xy 418.392912 -342.133502)
			(xy 418.43879 -342.104015) (xy 418.488396 -342.081357) (xy 418.540723 -342.065989) (xy 418.594704 -342.058224)
			(xy 418.621972 -342.057736) (xy 419.485572 -342.057736) (xy 419.512844 -342.058202) (xy 419.566834 -342.06596)
			(xy 419.61917 -342.081324) (xy 419.668786 -342.10398) (xy 419.714673 -342.133467) (xy 419.755896 -342.169184)
			(xy 419.791616 -342.210405) (xy 419.821107 -342.256289) (xy 419.843766 -342.305904) (xy 419.859134 -342.358239)
			(xy 419.866896 -342.412228) (xy 419.866896 -342.466772) (xy 419.866896 -342.466773) (xy 421.3496 -342.466773)
			(xy 421.3496 -342.412227) (xy 421.357363 -342.358237) (xy 421.372731 -342.305902) (xy 421.395391 -342.256286)
			(xy 421.424881 -342.210401) (xy 421.460602 -342.16918) (xy 421.501827 -342.133462) (xy 421.547715 -342.103975)
			(xy 421.597332 -342.081319) (xy 421.649669 -342.065956) (xy 421.703659 -342.058197) (xy 421.730932 -342.057736)
			(xy 422.594532 -342.057736) (xy 422.6218 -342.058229) (xy 422.67578 -342.065994) (xy 422.728105 -342.081362)
			(xy 422.777711 -342.10402) (xy 422.823588 -342.133506) (xy 422.864801 -342.169222) (xy 422.900513 -342.210438)
			(xy 422.929995 -342.256317) (xy 422.952649 -342.305925) (xy 422.968013 -342.358252) (xy 422.975774 -342.412232)
			(xy 422.975774 -342.466768) (xy 422.975774 -342.466769) (xy 424.458622 -342.466769) (xy 424.458622 -342.412231)
			(xy 424.466384 -342.358248) (xy 424.481749 -342.305918) (xy 424.504405 -342.256309) (xy 424.53389 -342.210428)
			(xy 424.569605 -342.16921) (xy 424.610821 -342.133495) (xy 424.656702 -342.104009) (xy 424.706311 -342.081352)
			(xy 424.75864 -342.065986) (xy 424.812623 -342.058223) (xy 424.839892 -342.057736) (xy 425.703492 -342.057736)
			(xy 425.730763 -342.058203) (xy 425.784751 -342.065964) (xy 425.837084 -342.08133) (xy 425.886698 -342.103987)
			(xy 425.932582 -342.133474) (xy 425.973803 -342.169191) (xy 426.009521 -342.210411) (xy 426.03901 -342.256295)
			(xy 426.061668 -342.305908) (xy 426.077034 -342.358241) (xy 426.084796 -342.412229) (xy 426.084796 -342.466767)
			(xy 427.567622 -342.466767) (xy 427.567622 -342.412233) (xy 427.575383 -342.358253) (xy 427.590746 -342.305927)
			(xy 427.613399 -342.25632) (xy 427.64288 -342.210441) (xy 427.67859 -342.169224) (xy 427.719802 -342.133509)
			(xy 427.765678 -342.104022) (xy 427.815282 -342.081363) (xy 427.867606 -342.065993) (xy 427.921585 -342.058226)
			(xy 427.948852 -342.057736) (xy 428.812452 -342.057736) (xy 428.839725 -342.0582) (xy 428.893717 -342.065957)
			(xy 428.946055 -342.081319) (xy 428.995674 -342.103974) (xy 429.041563 -342.13346) (xy 429.082789 -342.169177)
			(xy 429.118512 -342.210398) (xy 429.148003 -342.256284) (xy 429.170664 -342.3059) (xy 429.186033 -342.358236)
			(xy 429.193796 -342.412227) (xy 429.193796 -342.466772) (xy 430.6765 -342.466772) (xy 430.6765 -342.412228)
			(xy 430.684262 -342.35824) (xy 430.699629 -342.305906) (xy 430.722288 -342.256292) (xy 430.751776 -342.210407)
			(xy 430.787495 -342.169187) (xy 430.828717 -342.133469) (xy 430.874603 -342.103982) (xy 430.924217 -342.081325)
			(xy 430.976552 -342.065959) (xy 431.03054 -342.058199) (xy 431.057812 -342.057736) (xy 431.921412 -342.057736)
			(xy 431.948681 -342.058227) (xy 432.002663 -342.06599) (xy 432.054991 -342.081357) (xy 432.104599 -342.104013)
			(xy 432.150478 -342.133499) (xy 432.191694 -342.169214) (xy 432.227408 -342.210432) (xy 432.256892 -342.256312)
			(xy 432.279548 -342.305921) (xy 432.294912 -342.358249) (xy 432.302674 -342.412231) (xy 432.302674 -342.466768)
			(xy 433.785522 -342.466768) (xy 433.785522 -342.412232) (xy 433.793283 -342.35825) (xy 433.808647 -342.305923)
			(xy 433.831302 -342.256314) (xy 433.860785 -342.210434) (xy 433.896497 -342.169217) (xy 433.937712 -342.133502)
			(xy 433.98359 -342.104015) (xy 434.033196 -342.081357) (xy 434.085523 -342.065989) (xy 434.139504 -342.058224)
			(xy 434.166772 -342.057736) (xy 435.030372 -342.057736) (xy 435.057644 -342.058202) (xy 435.111634 -342.06596)
			(xy 435.16397 -342.081324) (xy 435.213586 -342.10398) (xy 435.259473 -342.133467) (xy 435.300696 -342.169184)
			(xy 435.336416 -342.210405) (xy 435.365907 -342.256289) (xy 435.388566 -342.305904) (xy 435.403934 -342.358239)
			(xy 435.411696 -342.412228) (xy 435.411696 -342.466772) (xy 435.411696 -342.466773) (xy 436.8944 -342.466773)
			(xy 436.8944 -342.412227) (xy 436.902163 -342.358237) (xy 436.917531 -342.305902) (xy 436.940191 -342.256286)
			(xy 436.969681 -342.210401) (xy 437.005402 -342.16918) (xy 437.046627 -342.133462) (xy 437.092515 -342.103975)
			(xy 437.142132 -342.081319) (xy 437.194469 -342.065956) (xy 437.248459 -342.058197) (xy 437.275732 -342.057736)
			(xy 438.139332 -342.057736) (xy 438.1666 -342.058229) (xy 438.22058 -342.065994) (xy 438.272905 -342.081362)
			(xy 438.322511 -342.10402) (xy 438.368388 -342.133506) (xy 438.409601 -342.169222) (xy 438.445313 -342.210438)
			(xy 438.474795 -342.256317) (xy 438.497449 -342.305925) (xy 438.512813 -342.358252) (xy 438.520574 -342.412232)
			(xy 438.520574 -342.466768) (xy 438.520574 -342.466769) (xy 440.003422 -342.466769) (xy 440.003422 -342.412231)
			(xy 440.011184 -342.358248) (xy 440.026549 -342.305918) (xy 440.049205 -342.256309) (xy 440.07869 -342.210428)
			(xy 440.114405 -342.16921) (xy 440.155621 -342.133495) (xy 440.201502 -342.104009) (xy 440.251111 -342.081352)
			(xy 440.30344 -342.065986) (xy 440.357423 -342.058223) (xy 440.384692 -342.057736) (xy 441.248292 -342.057736)
			(xy 441.275563 -342.058203) (xy 441.329551 -342.065964) (xy 441.381884 -342.08133) (xy 441.431498 -342.103987)
			(xy 441.477382 -342.133474) (xy 441.518603 -342.169191) (xy 441.554321 -342.210411) (xy 441.58381 -342.256295)
			(xy 441.606468 -342.305908) (xy 441.621834 -342.358241) (xy 441.629596 -342.412229) (xy 441.629596 -342.466771)
			(xy 441.621834 -342.520759) (xy 441.606468 -342.573092) (xy 441.58381 -342.622705) (xy 441.554321 -342.668589)
			(xy 441.518603 -342.709809) (xy 441.477382 -342.745526) (xy 441.431498 -342.775013) (xy 441.381884 -342.79767)
			(xy 441.329551 -342.813036) (xy 441.275563 -342.820797) (xy 441.248292 -342.82126) (xy 440.384692 -342.82126)
			(xy 440.357423 -342.820777) (xy 440.30344 -342.813014) (xy 440.251111 -342.797648) (xy 440.201502 -342.774991)
			(xy 440.155621 -342.745505) (xy 440.114405 -342.70979) (xy 440.07869 -342.668572) (xy 440.049205 -342.622691)
			(xy 440.026549 -342.573082) (xy 440.011184 -342.520752) (xy 440.003422 -342.466769) (xy 438.520574 -342.466769)
			(xy 438.512813 -342.520748) (xy 438.497449 -342.573075) (xy 438.474795 -342.622683) (xy 438.445313 -342.668562)
			(xy 438.409601 -342.709778) (xy 438.368388 -342.745494) (xy 438.322511 -342.77498) (xy 438.272905 -342.797638)
			(xy 438.22058 -342.813006) (xy 438.1666 -342.820771) (xy 438.139332 -342.82126) (xy 437.275732 -342.82126)
			(xy 437.248459 -342.820803) (xy 437.194469 -342.813044) (xy 437.142132 -342.797681) (xy 437.092515 -342.775025)
			(xy 437.046627 -342.745538) (xy 437.005402 -342.70982) (xy 436.969681 -342.668599) (xy 436.940191 -342.622714)
			(xy 436.917531 -342.573098) (xy 436.902163 -342.520763) (xy 436.8944 -342.466773) (xy 435.411696 -342.466773)
			(xy 435.403934 -342.520761) (xy 435.388566 -342.573096) (xy 435.365907 -342.622711) (xy 435.336416 -342.668595)
			(xy 435.300696 -342.709816) (xy 435.259473 -342.745533) (xy 435.213586 -342.77502) (xy 435.16397 -342.797676)
			(xy 435.111634 -342.81304) (xy 435.057644 -342.820798) (xy 435.030372 -342.82126) (xy 434.166772 -342.82126)
			(xy 434.139504 -342.820776) (xy 434.085523 -342.813011) (xy 434.033196 -342.797643) (xy 433.98359 -342.774985)
			(xy 433.937712 -342.745498) (xy 433.896497 -342.709783) (xy 433.860785 -342.668566) (xy 433.831302 -342.622686)
			(xy 433.808647 -342.573077) (xy 433.793283 -342.52075) (xy 433.785522 -342.466768) (xy 432.302674 -342.466768)
			(xy 432.302674 -342.466769) (xy 432.294912 -342.520751) (xy 432.279548 -342.573079) (xy 432.256892 -342.622688)
			(xy 432.227408 -342.668568) (xy 432.191694 -342.709786) (xy 432.150478 -342.745501) (xy 432.104599 -342.774987)
			(xy 432.054991 -342.797643) (xy 432.002663 -342.81301) (xy 431.948681 -342.820773) (xy 431.921412 -342.82126)
			(xy 431.057812 -342.82126) (xy 431.03054 -342.820801) (xy 430.976552 -342.813041) (xy 430.924217 -342.797675)
			(xy 430.874603 -342.775018) (xy 430.828717 -342.745531) (xy 430.787495 -342.709813) (xy 430.751776 -342.668593)
			(xy 430.722288 -342.622708) (xy 430.699629 -342.573094) (xy 430.684262 -342.52076) (xy 430.6765 -342.466772)
			(xy 429.193796 -342.466772) (xy 429.193796 -342.466773) (xy 429.186033 -342.520764) (xy 429.170664 -342.5731)
			(xy 429.148003 -342.622716) (xy 429.118512 -342.668602) (xy 429.082789 -342.709823) (xy 429.041563 -342.74554)
			(xy 428.995674 -342.775026) (xy 428.946055 -342.797681) (xy 428.893717 -342.813043) (xy 428.839725 -342.8208)
			(xy 428.812452 -342.82126) (xy 427.948852 -342.82126) (xy 427.921585 -342.820774) (xy 427.867606 -342.813007)
			(xy 427.815282 -342.797637) (xy 427.765678 -342.774978) (xy 427.719802 -342.745491) (xy 427.67859 -342.709776)
			(xy 427.64288 -342.668559) (xy 427.613399 -342.62268) (xy 427.590746 -342.573073) (xy 427.575383 -342.520747)
			(xy 427.567622 -342.466767) (xy 426.084796 -342.466767) (xy 426.084796 -342.466771) (xy 426.077034 -342.520759)
			(xy 426.061668 -342.573092) (xy 426.03901 -342.622705) (xy 426.009521 -342.668589) (xy 425.973803 -342.709809)
			(xy 425.932582 -342.745526) (xy 425.886698 -342.775013) (xy 425.837084 -342.79767) (xy 425.784751 -342.813036)
			(xy 425.730763 -342.820797) (xy 425.703492 -342.82126) (xy 424.839892 -342.82126) (xy 424.812623 -342.820777)
			(xy 424.75864 -342.813014) (xy 424.706311 -342.797648) (xy 424.656702 -342.774991) (xy 424.610821 -342.745505)
			(xy 424.569605 -342.70979) (xy 424.53389 -342.668572) (xy 424.504405 -342.622691) (xy 424.481749 -342.573082)
			(xy 424.466384 -342.520752) (xy 424.458622 -342.466769) (xy 422.975774 -342.466769) (xy 422.968013 -342.520748)
			(xy 422.952649 -342.573075) (xy 422.929995 -342.622683) (xy 422.900513 -342.668562) (xy 422.864801 -342.709778)
			(xy 422.823588 -342.745494) (xy 422.777711 -342.77498) (xy 422.728105 -342.797638) (xy 422.67578 -342.813006)
			(xy 422.6218 -342.820771) (xy 422.594532 -342.82126) (xy 421.730932 -342.82126) (xy 421.703659 -342.820803)
			(xy 421.649669 -342.813044) (xy 421.597332 -342.797681) (xy 421.547715 -342.775025) (xy 421.501827 -342.745538)
			(xy 421.460602 -342.70982) (xy 421.424881 -342.668599) (xy 421.395391 -342.622714) (xy 421.372731 -342.573098)
			(xy 421.357363 -342.520763) (xy 421.3496 -342.466773) (xy 419.866896 -342.466773) (xy 419.859134 -342.520761)
			(xy 419.843766 -342.573096) (xy 419.821107 -342.622711) (xy 419.791616 -342.668595) (xy 419.755896 -342.709816)
			(xy 419.714673 -342.745533) (xy 419.668786 -342.77502) (xy 419.61917 -342.797676) (xy 419.566834 -342.81304)
			(xy 419.512844 -342.820798) (xy 419.485572 -342.82126) (xy 418.621972 -342.82126) (xy 418.594704 -342.820776)
			(xy 418.540723 -342.813011) (xy 418.488396 -342.797643) (xy 418.43879 -342.774985) (xy 418.392912 -342.745498)
			(xy 418.351697 -342.709783) (xy 418.315985 -342.668566) (xy 418.286502 -342.622686) (xy 418.263847 -342.573077)
			(xy 418.248483 -342.52075) (xy 418.240722 -342.466768) (xy 416.757874 -342.466768) (xy 416.757874 -342.466769)
			(xy 416.750112 -342.520751) (xy 416.734748 -342.573079) (xy 416.712092 -342.622688) (xy 416.682608 -342.668568)
			(xy 416.646894 -342.709786) (xy 416.605678 -342.745501) (xy 416.559799 -342.774987) (xy 416.510191 -342.797643)
			(xy 416.457863 -342.81301) (xy 416.403881 -342.820773) (xy 416.376612 -342.82126) (xy 415.513012 -342.82126)
			(xy 415.48574 -342.820801) (xy 415.431752 -342.813041) (xy 415.379417 -342.797675) (xy 415.329803 -342.775018)
			(xy 415.283917 -342.745531) (xy 415.242695 -342.709813) (xy 415.206976 -342.668593) (xy 415.177488 -342.622708)
			(xy 415.154829 -342.573094) (xy 415.139462 -342.52076) (xy 415.1317 -342.466772) (xy 413.648996 -342.466772)
			(xy 413.648996 -342.466773) (xy 413.641233 -342.520764) (xy 413.625864 -342.5731) (xy 413.603203 -342.622716)
			(xy 413.573712 -342.668602) (xy 413.537989 -342.709823) (xy 413.496763 -342.74554) (xy 413.450874 -342.775026)
			(xy 413.401255 -342.797681) (xy 413.348917 -342.813043) (xy 413.294925 -342.8208) (xy 413.267652 -342.82126)
			(xy 412.404052 -342.82126) (xy 412.376785 -342.820774) (xy 412.322806 -342.813007) (xy 412.270482 -342.797637)
			(xy 412.220878 -342.774978) (xy 412.175002 -342.745491) (xy 412.13379 -342.709776) (xy 412.09808 -342.668559)
			(xy 412.068599 -342.62268) (xy 412.045946 -342.573073) (xy 412.030583 -342.520747) (xy 412.022822 -342.466767)
			(xy 410.539996 -342.466767) (xy 410.539996 -342.466771) (xy 410.532234 -342.520759) (xy 410.516868 -342.573092)
			(xy 410.49421 -342.622705) (xy 410.464721 -342.668589) (xy 410.429003 -342.709809) (xy 410.387782 -342.745526)
			(xy 410.341898 -342.775013) (xy 410.292284 -342.79767) (xy 410.239951 -342.813036) (xy 410.185963 -342.820797)
			(xy 410.158692 -342.82126) (xy 409.295092 -342.82126) (xy 409.267823 -342.820777) (xy 409.21384 -342.813014)
			(xy 409.161511 -342.797648) (xy 409.111902 -342.774991) (xy 409.066021 -342.745505) (xy 409.024805 -342.70979)
			(xy 408.98909 -342.668572) (xy 408.959605 -342.622691) (xy 408.936949 -342.573082) (xy 408.921584 -342.520752)
			(xy 408.913822 -342.466769) (xy 403.522496 -342.466769) (xy 403.522496 -342.466772) (xy 403.514734 -342.52076)
			(xy 403.499367 -342.573094) (xy 403.476708 -342.622708) (xy 403.447218 -342.668593) (xy 403.411499 -342.709813)
			(xy 403.370277 -342.74553) (xy 403.324391 -342.775017) (xy 403.274775 -342.797674) (xy 403.222441 -342.813038)
			(xy 403.168452 -342.820798) (xy 403.14118 -342.82126) (xy 402.27758 -342.82126) (xy 402.250311 -342.820776)
			(xy 402.19633 -342.813012) (xy 402.144002 -342.797645) (xy 402.094394 -342.774988) (xy 402.048516 -342.745501)
			(xy 402.0073 -342.709786) (xy 401.971587 -342.668568) (xy 401.942103 -342.622688) (xy 401.919448 -342.573079)
			(xy 401.904084 -342.520751) (xy 401.896322 -342.466769) (xy 400.413474 -342.466769) (xy 400.405713 -342.52075)
			(xy 400.390348 -342.573078) (xy 400.367694 -342.622686) (xy 400.33821 -342.668566) (xy 400.302497 -342.709783)
			(xy 400.261282 -342.745498) (xy 400.215404 -342.774984) (xy 400.165796 -342.797641) (xy 400.113469 -342.813008)
			(xy 400.059488 -342.820772) (xy 400.03222 -342.82126) (xy 399.16862 -342.82126) (xy 399.141348 -342.820802)
			(xy 399.087359 -342.813042) (xy 399.035023 -342.797677) (xy 398.985407 -342.775021) (xy 398.939521 -342.745534)
			(xy 398.898298 -342.709816) (xy 398.862578 -342.668595) (xy 398.833089 -342.62271) (xy 398.81043 -342.573096)
			(xy 398.795062 -342.520761) (xy 398.7873 -342.466772) (xy 397.304596 -342.466772) (xy 397.304596 -342.466773)
			(xy 397.296833 -342.520763) (xy 397.281465 -342.573098) (xy 397.258805 -342.622714) (xy 397.229313 -342.668599)
			(xy 397.193592 -342.70982) (xy 397.152367 -342.745537) (xy 397.106479 -342.775024) (xy 397.056861 -342.797679)
			(xy 397.004524 -342.813042) (xy 396.950533 -342.820799) (xy 396.92326 -342.82126) (xy 396.05966 -342.82126)
			(xy 396.032392 -342.820775) (xy 395.978413 -342.813009) (xy 395.926088 -342.79764) (xy 395.876482 -342.774981)
			(xy 395.830606 -342.745494) (xy 395.789393 -342.709778) (xy 395.753682 -342.668562) (xy 395.7242 -342.622682)
			(xy 395.701546 -342.573075) (xy 395.686183 -342.520748) (xy 395.678422 -342.466768) (xy 394.195574 -342.466768)
			(xy 394.195574 -342.466769) (xy 394.187812 -342.520753) (xy 394.172447 -342.573082) (xy 394.149791 -342.622692)
			(xy 394.120305 -342.668572) (xy 394.08459 -342.70979) (xy 394.043372 -342.745505) (xy 393.997492 -342.774991)
			(xy 393.947882 -342.797647) (xy 393.895553 -342.813012) (xy 393.841569 -342.820774) (xy 393.8143 -342.82126)
			(xy 392.9507 -342.82126) (xy 392.92343 -342.820778) (xy 392.869447 -342.813016) (xy 392.817117 -342.79765)
			(xy 392.767506 -342.774994) (xy 392.721625 -342.745508) (xy 392.680407 -342.709793) (xy 392.644692 -342.668575)
			(xy 392.615206 -342.622694) (xy 392.59255 -342.573083) (xy 392.577184 -342.520753) (xy 392.569422 -342.46677)
			(xy 391.086574 -342.46677) (xy 391.078813 -342.520747) (xy 391.06345 -342.573073) (xy 391.040797 -342.622681)
			(xy 391.011315 -342.668559) (xy 390.975604 -342.709776) (xy 390.934391 -342.745491) (xy 390.888516 -342.774978)
			(xy 390.838911 -342.797636) (xy 390.786586 -342.813005) (xy 390.732607 -342.820771) (xy 390.70534 -342.82126)
			(xy 389.84174 -342.82126) (xy 389.814467 -342.820803) (xy 389.760476 -342.813046) (xy 389.708138 -342.797683)
			(xy 389.658519 -342.775027) (xy 389.61263 -342.745541) (xy 389.571405 -342.709823) (xy 389.535683 -342.668602)
			(xy 389.506192 -342.622716) (xy 389.483531 -342.5731) (xy 389.468163 -342.520764) (xy 389.4604 -342.466773)
			(xy 387.977696 -342.466773) (xy 387.969934 -342.52076) (xy 387.954567 -342.573094) (xy 387.931908 -342.622708)
			(xy 387.902418 -342.668593) (xy 387.866699 -342.709813) (xy 387.825477 -342.74553) (xy 387.779591 -342.775017)
			(xy 387.729975 -342.797674) (xy 387.677641 -342.813038) (xy 387.623652 -342.820798) (xy 387.59638 -342.82126)
			(xy 386.73278 -342.82126) (xy 386.705511 -342.820776) (xy 386.65153 -342.813012) (xy 386.599202 -342.797645)
			(xy 386.549594 -342.774988) (xy 386.503716 -342.745501) (xy 386.4625 -342.709786) (xy 386.426787 -342.668568)
			(xy 386.397303 -342.622688) (xy 386.374648 -342.573079) (xy 386.359284 -342.520751) (xy 386.351522 -342.466769)
			(xy 384.868674 -342.466769) (xy 384.860913 -342.52075) (xy 384.845548 -342.573078) (xy 384.822894 -342.622686)
			(xy 384.79341 -342.668566) (xy 384.757697 -342.709783) (xy 384.716482 -342.745498) (xy 384.670604 -342.774984)
			(xy 384.620996 -342.797641) (xy 384.568669 -342.813008) (xy 384.514688 -342.820772) (xy 384.48742 -342.82126)
			(xy 383.62382 -342.82126) (xy 383.596548 -342.820802) (xy 383.542559 -342.813042) (xy 383.490223 -342.797677)
			(xy 383.440607 -342.775021) (xy 383.394721 -342.745534) (xy 383.353498 -342.709816) (xy 383.317778 -342.668595)
			(xy 383.288289 -342.62271) (xy 383.26563 -342.573096) (xy 383.250262 -342.520761) (xy 383.2425 -342.466772)
			(xy 381.759796 -342.466772) (xy 381.759796 -342.466773) (xy 381.752033 -342.520763) (xy 381.736665 -342.573098)
			(xy 381.714005 -342.622714) (xy 381.684513 -342.668599) (xy 381.648792 -342.70982) (xy 381.607567 -342.745537)
			(xy 381.561679 -342.775024) (xy 381.512061 -342.797679) (xy 381.459724 -342.813042) (xy 381.405733 -342.820799)
			(xy 381.37846 -342.82126) (xy 380.51486 -342.82126) (xy 380.487592 -342.820775) (xy 380.433613 -342.813009)
			(xy 380.381288 -342.79764) (xy 380.331682 -342.774981) (xy 380.285806 -342.745494) (xy 380.244593 -342.709778)
			(xy 380.208882 -342.668562) (xy 380.1794 -342.622682) (xy 380.156746 -342.573075) (xy 380.141383 -342.520748)
			(xy 380.133622 -342.466768) (xy 378.650774 -342.466768) (xy 378.650774 -342.466769) (xy 378.643012 -342.520753)
			(xy 378.627647 -342.573082) (xy 378.604991 -342.622692) (xy 378.575505 -342.668572) (xy 378.53979 -342.70979)
			(xy 378.498572 -342.745505) (xy 378.452692 -342.774991) (xy 378.403082 -342.797647) (xy 378.350753 -342.813012)
			(xy 378.296769 -342.820774) (xy 378.2695 -342.82126) (xy 377.4059 -342.82126) (xy 377.37863 -342.820778)
			(xy 377.324647 -342.813016) (xy 377.272317 -342.79765) (xy 377.222706 -342.774994) (xy 377.176825 -342.745508)
			(xy 377.135607 -342.709793) (xy 377.099892 -342.668575) (xy 377.070406 -342.622694) (xy 377.04775 -342.573083)
			(xy 377.032384 -342.520753) (xy 377.024622 -342.46677) (xy 375.541774 -342.46677) (xy 375.534013 -342.520747)
			(xy 375.51865 -342.573073) (xy 375.495997 -342.622681) (xy 375.466515 -342.668559) (xy 375.430804 -342.709776)
			(xy 375.389591 -342.745491) (xy 375.343716 -342.774978) (xy 375.294111 -342.797636) (xy 375.241786 -342.813005)
			(xy 375.187807 -342.820771) (xy 375.16054 -342.82126) (xy 374.29694 -342.82126) (xy 374.269667 -342.820803)
			(xy 374.215676 -342.813046) (xy 374.163338 -342.797683) (xy 374.113719 -342.775027) (xy 374.06783 -342.745541)
			(xy 374.026605 -342.709823) (xy 373.990883 -342.668602) (xy 373.961392 -342.622716) (xy 373.938731 -342.5731)
			(xy 373.923363 -342.520764) (xy 373.9156 -342.466773) (xy 372.432896 -342.466773) (xy 372.425134 -342.52076)
			(xy 372.409767 -342.573094) (xy 372.387108 -342.622708) (xy 372.357618 -342.668593) (xy 372.321899 -342.709813)
			(xy 372.280677 -342.74553) (xy 372.234791 -342.775017) (xy 372.185175 -342.797674) (xy 372.132841 -342.813038)
			(xy 372.078852 -342.820798) (xy 372.05158 -342.82126) (xy 371.18798 -342.82126) (xy 371.160711 -342.820776)
			(xy 371.10673 -342.813012) (xy 371.054402 -342.797645) (xy 371.004794 -342.774988) (xy 370.958916 -342.745501)
			(xy 370.9177 -342.709786) (xy 370.881987 -342.668568) (xy 370.852503 -342.622688) (xy 370.829848 -342.573079)
			(xy 370.814484 -342.520751) (xy 370.806722 -342.466769) (xy 344.837274 -342.466769) (xy 344.829512 -342.520752)
			(xy 344.814147 -342.573081) (xy 344.791491 -342.622691) (xy 344.762006 -342.668571) (xy 344.726291 -342.709788)
			(xy 344.685074 -342.745503) (xy 344.639194 -342.774989) (xy 344.589585 -342.797646) (xy 344.537256 -342.813011)
			(xy 344.483273 -342.820773) (xy 344.456004 -342.82126) (xy 343.592404 -342.82126) (xy 343.565133 -342.820801)
			(xy 343.511145 -342.813039) (xy 343.458812 -342.797673) (xy 343.409198 -342.775016) (xy 343.363313 -342.745528)
			(xy 343.322093 -342.70981) (xy 343.286374 -342.66859) (xy 343.256886 -342.622706) (xy 343.234228 -342.573092)
			(xy 343.218862 -342.520759) (xy 343.2111 -342.466771) (xy 341.728273 -342.466771) (xy 341.720513 -342.520747)
			(xy 341.70515 -342.573072) (xy 341.682497 -342.622679) (xy 341.653016 -342.668558) (xy 341.617305 -342.709774)
			(xy 341.576093 -342.745489) (xy 341.530218 -342.774976) (xy 341.480614 -342.797635) (xy 341.42829 -342.813004)
			(xy 341.374311 -342.820771) (xy 341.347044 -342.82126) (xy 340.483444 -342.82126) (xy 340.456171 -342.820804)
			(xy 340.402179 -342.813046) (xy 340.349841 -342.797684) (xy 340.300222 -342.775029) (xy 340.254332 -342.745542)
			(xy 340.213107 -342.709824) (xy 340.177384 -342.668603) (xy 340.147892 -342.622717) (xy 340.125232 -342.573101)
			(xy 340.109863 -342.520764) (xy 340.1021 -342.466773) (xy 338.619396 -342.466773) (xy 338.611634 -342.52076)
			(xy 338.596267 -342.573093) (xy 338.573608 -342.622707) (xy 338.544119 -342.668591) (xy 338.5084 -342.709812)
			(xy 338.467179 -342.745529) (xy 338.421293 -342.775016) (xy 338.371678 -342.797673) (xy 338.319344 -342.813037)
			(xy 338.265356 -342.820798) (xy 338.238084 -342.82126) (xy 337.374484 -342.82126) (xy 337.347215 -342.820776)
			(xy 337.293233 -342.813013) (xy 337.240905 -342.797646) (xy 337.191297 -342.774989) (xy 337.145418 -342.745502)
			(xy 337.104202 -342.709787) (xy 337.068488 -342.66857) (xy 337.039003 -342.622689) (xy 337.016348 -342.57308)
			(xy 337.000984 -342.520751) (xy 336.993222 -342.466769) (xy 335.510374 -342.466769) (xy 335.502613 -342.520749)
			(xy 335.487249 -342.573077) (xy 335.464594 -342.622685) (xy 335.435111 -342.668565) (xy 335.399398 -342.709781)
			(xy 335.358184 -342.745496) (xy 335.312306 -342.774983) (xy 335.262699 -342.79764) (xy 335.210373 -342.813008)
			(xy 335.156392 -342.820772) (xy 335.129124 -342.82126) (xy 334.265524 -342.82126) (xy 334.238252 -342.820802)
			(xy 334.184262 -342.813043) (xy 334.131926 -342.797678) (xy 334.08231 -342.775022) (xy 334.036423 -342.745535)
			(xy 333.9952 -342.709817) (xy 333.959479 -342.668596) (xy 333.929989 -342.622711) (xy 333.90733 -342.573096)
			(xy 333.891962 -342.520761) (xy 333.8842 -342.466772) (xy 332.401496 -342.466772) (xy 332.393733 -342.520762)
			(xy 332.378365 -342.573098) (xy 332.355705 -342.622713) (xy 332.326214 -342.668598) (xy 332.290493 -342.709819)
			(xy 332.249269 -342.745536) (xy 332.203381 -342.775023) (xy 332.153764 -342.797678) (xy 332.101427 -342.813041)
			(xy 332.047437 -342.820799) (xy 332.020164 -342.82126) (xy 331.156564 -342.82126) (xy 331.129296 -342.820775)
			(xy 331.075316 -342.813009) (xy 331.022991 -342.797641) (xy 330.973385 -342.774982) (xy 330.927508 -342.745495)
			(xy 330.886295 -342.70978) (xy 330.850583 -342.668563) (xy 330.8211 -342.622684) (xy 330.798447 -342.573076)
			(xy 330.783083 -342.520749) (xy 330.775322 -342.466768) (xy 329.292474 -342.466768) (xy 329.292474 -342.466769)
			(xy 329.284712 -342.520752) (xy 329.269347 -342.573081) (xy 329.246691 -342.622691) (xy 329.217206 -342.668571)
			(xy 329.181491 -342.709788) (xy 329.140274 -342.745503) (xy 329.094394 -342.774989) (xy 329.044785 -342.797646)
			(xy 328.992456 -342.813011) (xy 328.938473 -342.820773) (xy 328.911204 -342.82126) (xy 328.047604 -342.82126)
			(xy 328.020333 -342.820801) (xy 327.966345 -342.813039) (xy 327.914012 -342.797673) (xy 327.864398 -342.775016)
			(xy 327.818513 -342.745528) (xy 327.777293 -342.70981) (xy 327.741574 -342.66859) (xy 327.712086 -342.622706)
			(xy 327.689428 -342.573092) (xy 327.674062 -342.520759) (xy 327.6663 -342.466771) (xy 326.183473 -342.466771)
			(xy 326.175713 -342.520747) (xy 326.16035 -342.573072) (xy 326.137697 -342.622679) (xy 326.108216 -342.668558)
			(xy 326.072505 -342.709774) (xy 326.031293 -342.745489) (xy 325.985418 -342.774976) (xy 325.935814 -342.797635)
			(xy 325.88349 -342.813004) (xy 325.829511 -342.820771) (xy 325.802244 -342.82126) (xy 324.938644 -342.82126)
			(xy 324.911371 -342.820804) (xy 324.857379 -342.813046) (xy 324.805041 -342.797684) (xy 324.755422 -342.775029)
			(xy 324.709532 -342.745542) (xy 324.668307 -342.709824) (xy 324.632584 -342.668603) (xy 324.603092 -342.622717)
			(xy 324.580432 -342.573101) (xy 324.565063 -342.520764) (xy 324.5573 -342.466773) (xy 323.074596 -342.466773)
			(xy 323.066834 -342.52076) (xy 323.051467 -342.573093) (xy 323.028808 -342.622707) (xy 322.999319 -342.668591)
			(xy 322.9636 -342.709812) (xy 322.922379 -342.745529) (xy 322.876493 -342.775016) (xy 322.826878 -342.797673)
			(xy 322.774544 -342.813037) (xy 322.720556 -342.820798) (xy 322.693284 -342.82126) (xy 321.829684 -342.82126)
			(xy 321.802415 -342.820776) (xy 321.748433 -342.813013) (xy 321.696105 -342.797646) (xy 321.646497 -342.774989)
			(xy 321.600618 -342.745502) (xy 321.559402 -342.709787) (xy 321.523688 -342.66857) (xy 321.494203 -342.622689)
			(xy 321.471548 -342.57308) (xy 321.456184 -342.520751) (xy 321.448422 -342.466769) (xy 319.965574 -342.466769)
			(xy 319.957813 -342.520749) (xy 319.942449 -342.573077) (xy 319.919794 -342.622685) (xy 319.890311 -342.668565)
			(xy 319.854598 -342.709781) (xy 319.813384 -342.745496) (xy 319.767506 -342.774983) (xy 319.717899 -342.79764)
			(xy 319.665573 -342.813008) (xy 319.611592 -342.820772) (xy 319.584324 -342.82126) (xy 318.720724 -342.82126)
			(xy 318.693452 -342.820802) (xy 318.639462 -342.813043) (xy 318.587126 -342.797678) (xy 318.53751 -342.775022)
			(xy 318.491623 -342.745535) (xy 318.4504 -342.709817) (xy 318.414679 -342.668596) (xy 318.385189 -342.622711)
			(xy 318.36253 -342.573096) (xy 318.347162 -342.520761) (xy 318.3394 -342.466772) (xy 316.856696 -342.466772)
			(xy 316.848933 -342.520762) (xy 316.833565 -342.573098) (xy 316.810905 -342.622713) (xy 316.781414 -342.668598)
			(xy 316.745693 -342.709819) (xy 316.704469 -342.745536) (xy 316.658581 -342.775023) (xy 316.608964 -342.797678)
			(xy 316.556627 -342.813041) (xy 316.502637 -342.820799) (xy 316.475364 -342.82126) (xy 315.611764 -342.82126)
			(xy 315.584496 -342.820775) (xy 315.530516 -342.813009) (xy 315.478191 -342.797641) (xy 315.428585 -342.774982)
			(xy 315.382708 -342.745495) (xy 315.341495 -342.70978) (xy 315.305783 -342.668563) (xy 315.2763 -342.622684)
			(xy 315.253647 -342.573076) (xy 315.238283 -342.520749) (xy 315.230522 -342.466768) (xy 313.747674 -342.466768)
			(xy 313.747674 -342.466769) (xy 313.739912 -342.520752) (xy 313.724547 -342.573081) (xy 313.701891 -342.622691)
			(xy 313.672406 -342.668571) (xy 313.636691 -342.709788) (xy 313.595474 -342.745503) (xy 313.549594 -342.774989)
			(xy 313.499985 -342.797646) (xy 313.447656 -342.813011) (xy 313.393673 -342.820773) (xy 313.366404 -342.82126)
			(xy 312.502804 -342.82126) (xy 312.475533 -342.820801) (xy 312.421545 -342.813039) (xy 312.369212 -342.797673)
			(xy 312.319598 -342.775016) (xy 312.273713 -342.745528) (xy 312.232493 -342.70981) (xy 312.196774 -342.66859)
			(xy 312.167286 -342.622706) (xy 312.144628 -342.573092) (xy 312.129262 -342.520759) (xy 312.1215 -342.466771)
			(xy 300.231574 -342.466771) (xy 300.223812 -342.520752) (xy 300.208447 -342.573081) (xy 300.185791 -342.622691)
			(xy 300.156305 -342.668572) (xy 300.120591 -342.709789) (xy 300.079373 -342.745504) (xy 300.033493 -342.77499)
			(xy 299.983883 -342.797646) (xy 299.931554 -342.813012) (xy 299.877571 -342.820773) (xy 299.850302 -342.82126)
			(xy 298.986702 -342.82126) (xy 298.959431 -342.820801) (xy 298.905443 -342.813039) (xy 298.85311 -342.797673)
			(xy 298.803497 -342.775015) (xy 298.757612 -342.745527) (xy 298.716392 -342.70981) (xy 298.680674 -342.668589)
			(xy 298.651186 -342.622705) (xy 298.628528 -342.573092) (xy 298.613162 -342.520759) (xy 298.605399 -342.466771)
			(xy 297.122573 -342.466771) (xy 297.114813 -342.520747) (xy 297.09945 -342.573073) (xy 297.076797 -342.62268)
			(xy 297.047315 -342.668559) (xy 297.011605 -342.709775) (xy 296.970392 -342.74549) (xy 296.924517 -342.774977)
			(xy 296.874912 -342.797635) (xy 296.822588 -342.813004) (xy 296.768609 -342.820771) (xy 296.741342 -342.82126)
			(xy 295.877742 -342.82126) (xy 295.850469 -342.820803) (xy 295.796477 -342.813046) (xy 295.744139 -342.797683)
			(xy 295.694521 -342.775028) (xy 295.648631 -342.745541) (xy 295.607406 -342.709824) (xy 295.571684 -342.668602)
			(xy 295.542192 -342.622716) (xy 295.519531 -342.5731) (xy 295.504163 -342.520764) (xy 295.4964 -342.466773)
			(xy 294.013696 -342.466773) (xy 294.005934 -342.52076) (xy 293.990567 -342.573094) (xy 293.967908 -342.622708)
			(xy 293.938419 -342.668592) (xy 293.9027 -342.709812) (xy 293.861478 -342.74553) (xy 293.815592 -342.775017)
			(xy 293.765977 -342.797673) (xy 293.713642 -342.813038) (xy 293.659654 -342.820798) (xy 293.632382 -342.82126)
			(xy 292.768782 -342.82126) (xy 292.741513 -342.820776) (xy 292.687531 -342.813013) (xy 292.635204 -342.797646)
			(xy 292.585596 -342.774988) (xy 292.539717 -342.745502) (xy 292.498501 -342.709786) (xy 292.462787 -342.668569)
			(xy 292.433303 -342.622689) (xy 292.410648 -342.573079) (xy 292.395284 -342.520751) (xy 292.387522 -342.466769)
			(xy 290.904674 -342.466769) (xy 290.896913 -342.52075) (xy 290.881548 -342.573077) (xy 290.858894 -342.622686)
			(xy 290.82941 -342.668565) (xy 290.793698 -342.709782) (xy 290.752483 -342.745497) (xy 290.706605 -342.774983)
			(xy 290.656998 -342.797641) (xy 290.604671 -342.813008) (xy 290.55069 -342.820772) (xy 290.523422 -342.82126)
			(xy 289.659822 -342.82126) (xy 289.63255 -342.820802) (xy 289.57856 -342.813042) (xy 289.526225 -342.797678)
			(xy 289.476609 -342.775021) (xy 289.430722 -342.745534) (xy 289.389499 -342.709817) (xy 289.353779 -342.668596)
			(xy 289.324289 -342.622711) (xy 289.30163 -342.573096) (xy 289.286262 -342.520761) (xy 289.2785 -342.466772)
			(xy 287.795796 -342.466772) (xy 287.795796 -342.466773) (xy 287.788033 -342.520763) (xy 287.772665 -342.573098)
			(xy 287.750005 -342.622713) (xy 287.720514 -342.668599) (xy 287.684793 -342.70982) (xy 287.643568 -342.745537)
			(xy 287.59768 -342.775023) (xy 287.548062 -342.797679) (xy 287.495725 -342.813041) (xy 287.441735 -342.820799)
			(xy 287.414462 -342.82126) (xy 286.550862 -342.82126) (xy 286.523594 -342.820775) (xy 286.469614 -342.813009)
			(xy 286.417289 -342.79764) (xy 286.367684 -342.774982) (xy 286.321807 -342.745495) (xy 286.280594 -342.709779)
			(xy 286.244883 -342.668562) (xy 286.2154 -342.622683) (xy 286.192747 -342.573075) (xy 286.177383 -342.520748)
			(xy 286.169622 -342.466768) (xy 284.686774 -342.466768) (xy 284.686774 -342.466769) (xy 284.679012 -342.520752)
			(xy 284.663647 -342.573081) (xy 284.640991 -342.622691) (xy 284.611505 -342.668572) (xy 284.575791 -342.709789)
			(xy 284.534573 -342.745504) (xy 284.488693 -342.77499) (xy 284.439083 -342.797646) (xy 284.386754 -342.813012)
			(xy 284.332771 -342.820773) (xy 284.305502 -342.82126) (xy 283.441902 -342.82126) (xy 283.414631 -342.820801)
			(xy 283.360643 -342.813039) (xy 283.30831 -342.797673) (xy 283.258697 -342.775015) (xy 283.212812 -342.745527)
			(xy 283.171592 -342.70981) (xy 283.135874 -342.668589) (xy 283.106386 -342.622705) (xy 283.083728 -342.573092)
			(xy 283.068362 -342.520759) (xy 283.060599 -342.466771) (xy 281.577773 -342.466771) (xy 281.570013 -342.520747)
			(xy 281.55465 -342.573073) (xy 281.531997 -342.62268) (xy 281.502515 -342.668559) (xy 281.466805 -342.709775)
			(xy 281.425592 -342.74549) (xy 281.379717 -342.774977) (xy 281.330112 -342.797635) (xy 281.277788 -342.813004)
			(xy 281.223809 -342.820771) (xy 281.196542 -342.82126) (xy 280.332942 -342.82126) (xy 280.305669 -342.820803)
			(xy 280.251677 -342.813046) (xy 280.199339 -342.797683) (xy 280.149721 -342.775028) (xy 280.103831 -342.745541)
			(xy 280.062606 -342.709824) (xy 280.026884 -342.668602) (xy 279.997392 -342.622716) (xy 279.974731 -342.5731)
			(xy 279.959363 -342.520764) (xy 279.9516 -342.466773) (xy 278.468896 -342.466773) (xy 278.461134 -342.52076)
			(xy 278.445767 -342.573094) (xy 278.423108 -342.622708) (xy 278.393619 -342.668592) (xy 278.3579 -342.709812)
			(xy 278.316678 -342.74553) (xy 278.270792 -342.775017) (xy 278.221177 -342.797673) (xy 278.168842 -342.813038)
			(xy 278.114854 -342.820798) (xy 278.087582 -342.82126) (xy 277.223982 -342.82126) (xy 277.196713 -342.820776)
			(xy 277.142731 -342.813013) (xy 277.090404 -342.797646) (xy 277.040796 -342.774988) (xy 276.994917 -342.745502)
			(xy 276.953701 -342.709786) (xy 276.917987 -342.668569) (xy 276.888503 -342.622689) (xy 276.865848 -342.573079)
			(xy 276.850484 -342.520751) (xy 276.842722 -342.466769) (xy 275.359874 -342.466769) (xy 275.352113 -342.52075)
			(xy 275.336748 -342.573077) (xy 275.314094 -342.622686) (xy 275.28461 -342.668565) (xy 275.248898 -342.709782)
			(xy 275.207683 -342.745497) (xy 275.161805 -342.774983) (xy 275.112198 -342.797641) (xy 275.059871 -342.813008)
			(xy 275.00589 -342.820772) (xy 274.978622 -342.82126) (xy 274.115022 -342.82126) (xy 274.08775 -342.820802)
			(xy 274.03376 -342.813042) (xy 273.981425 -342.797678) (xy 273.931809 -342.775021) (xy 273.885922 -342.745534)
			(xy 273.844699 -342.709817) (xy 273.808979 -342.668596) (xy 273.779489 -342.622711) (xy 273.75683 -342.573096)
			(xy 273.741462 -342.520761) (xy 273.7337 -342.466772) (xy 272.250996 -342.466772) (xy 272.250996 -342.466773)
			(xy 272.243233 -342.520763) (xy 272.227865 -342.573098) (xy 272.205205 -342.622713) (xy 272.175714 -342.668599)
			(xy 272.139993 -342.70982) (xy 272.098768 -342.745537) (xy 272.05288 -342.775023) (xy 272.003262 -342.797679)
			(xy 271.950925 -342.813041) (xy 271.896935 -342.820799) (xy 271.869662 -342.82126) (xy 271.006062 -342.82126)
			(xy 270.978794 -342.820775) (xy 270.924814 -342.813009) (xy 270.872489 -342.79764) (xy 270.822884 -342.774982)
			(xy 270.777007 -342.745495) (xy 270.735794 -342.709779) (xy 270.700083 -342.668562) (xy 270.6706 -342.622683)
			(xy 270.647947 -342.573075) (xy 270.632583 -342.520748) (xy 270.624822 -342.466768) (xy 269.141974 -342.466768)
			(xy 269.141974 -342.466769) (xy 269.134212 -342.520752) (xy 269.118847 -342.573081) (xy 269.096191 -342.622691)
			(xy 269.066705 -342.668572) (xy 269.030991 -342.709789) (xy 268.989773 -342.745504) (xy 268.943893 -342.77499)
			(xy 268.894283 -342.797646) (xy 268.841954 -342.813012) (xy 268.787971 -342.820773) (xy 268.760702 -342.82126)
			(xy 267.897102 -342.82126) (xy 267.869831 -342.820801) (xy 267.815843 -342.813039) (xy 267.76351 -342.797673)
			(xy 267.713897 -342.775015) (xy 267.668012 -342.745527) (xy 267.626792 -342.70981) (xy 267.591074 -342.668589)
			(xy 267.561586 -342.622705) (xy 267.538928 -342.573092) (xy 267.523562 -342.520759) (xy 267.515799 -342.466771)
			(xy 256.581015 -342.466771) (xy 256.573351 -342.471196) (xy 256.517947 -342.494145) (xy 256.460022 -342.509666)
			(xy 256.400566 -342.517494) (xy 256.340598 -342.517494) (xy 256.281142 -342.509666) (xy 256.223217 -342.494145)
			(xy 256.167813 -342.471196) (xy 256.115879 -342.441212) (xy 256.068303 -342.404706) (xy 256.025898 -342.362301)
			(xy 255.989392 -342.314725) (xy 255.959408 -342.262791) (xy 255.936459 -342.207387) (xy 255.920938 -342.149462)
			(xy 255.91311 -342.090006) (xy 255.91262 -342.060022) (xy 197.28821 -342.060022) (xy 197.329534 -342.06596)
			(xy 197.38187 -342.081324) (xy 197.431486 -342.10398) (xy 197.477373 -342.133467) (xy 197.518596 -342.169184)
			(xy 197.554316 -342.210405) (xy 197.583807 -342.256289) (xy 197.606466 -342.305904) (xy 197.621834 -342.358239)
			(xy 197.629596 -342.412228) (xy 197.629596 -342.466772) (xy 197.621834 -342.520761) (xy 197.606466 -342.573096)
			(xy 197.583807 -342.622711) (xy 197.554316 -342.668595) (xy 197.518596 -342.709816) (xy 197.477373 -342.745533)
			(xy 197.431486 -342.77502) (xy 197.38187 -342.797676) (xy 197.329534 -342.81304) (xy 197.275544 -342.820798)
			(xy 197.248272 -342.82126) (xy 196.384672 -342.82126) (xy 196.357404 -342.820776) (xy 196.303423 -342.813011)
			(xy 196.251096 -342.797643) (xy 196.20149 -342.774985) (xy 196.155612 -342.745498) (xy 196.114397 -342.709783)
			(xy 196.078685 -342.668566) (xy 196.049202 -342.622686) (xy 196.026547 -342.573077) (xy 196.011183 -342.52075)
			(xy 196.003422 -342.466768) (xy 194.520574 -342.466768) (xy 194.520574 -342.466769) (xy 194.512812 -342.520751)
			(xy 194.497448 -342.573079) (xy 194.474792 -342.622688) (xy 194.445308 -342.668568) (xy 194.409594 -342.709786)
			(xy 194.368378 -342.745501) (xy 194.322499 -342.774987) (xy 194.272891 -342.797643) (xy 194.220563 -342.81301)
			(xy 194.166581 -342.820773) (xy 194.139312 -342.82126) (xy 193.275712 -342.82126) (xy 193.24844 -342.820801)
			(xy 193.194452 -342.813041) (xy 193.142117 -342.797675) (xy 193.092503 -342.775018) (xy 193.046617 -342.745531)
			(xy 193.005395 -342.709813) (xy 192.969676 -342.668593) (xy 192.940188 -342.622708) (xy 192.917529 -342.573094)
			(xy 192.902162 -342.52076) (xy 192.8944 -342.466772) (xy 191.411696 -342.466772) (xy 191.411696 -342.466773)
			(xy 191.403933 -342.520764) (xy 191.388564 -342.5731) (xy 191.365903 -342.622716) (xy 191.336412 -342.668602)
			(xy 191.300689 -342.709823) (xy 191.259463 -342.74554) (xy 191.213574 -342.775026) (xy 191.163955 -342.797681)
			(xy 191.111617 -342.813043) (xy 191.057625 -342.8208) (xy 191.030352 -342.82126) (xy 190.166752 -342.82126)
			(xy 190.139485 -342.820774) (xy 190.085506 -342.813007) (xy 190.033182 -342.797637) (xy 189.983578 -342.774978)
			(xy 189.937702 -342.745491) (xy 189.89649 -342.709776) (xy 189.86078 -342.668559) (xy 189.831299 -342.62268)
			(xy 189.808646 -342.573073) (xy 189.793283 -342.520747) (xy 189.785522 -342.466767) (xy 188.302696 -342.466767)
			(xy 188.302696 -342.466771) (xy 188.294934 -342.520759) (xy 188.279568 -342.573092) (xy 188.25691 -342.622705)
			(xy 188.227421 -342.668589) (xy 188.191703 -342.709809) (xy 188.150482 -342.745526) (xy 188.104598 -342.775013)
			(xy 188.054984 -342.79767) (xy 188.002651 -342.813036) (xy 187.948663 -342.820797) (xy 187.921392 -342.82126)
			(xy 187.057792 -342.82126) (xy 187.030523 -342.820777) (xy 186.97654 -342.813014) (xy 186.924211 -342.797648)
			(xy 186.874602 -342.774991) (xy 186.828721 -342.745505) (xy 186.787505 -342.70979) (xy 186.75179 -342.668572)
			(xy 186.722305 -342.622691) (xy 186.699649 -342.573082) (xy 186.684284 -342.520752) (xy 186.676522 -342.466769)
			(xy 185.193674 -342.466769) (xy 185.185913 -342.520748) (xy 185.170549 -342.573075) (xy 185.147895 -342.622683)
			(xy 185.118413 -342.668562) (xy 185.082701 -342.709778) (xy 185.041488 -342.745494) (xy 184.995611 -342.77498)
			(xy 184.946005 -342.797638) (xy 184.89368 -342.813006) (xy 184.8397 -342.820771) (xy 184.812432 -342.82126)
			(xy 183.948832 -342.82126) (xy 183.921559 -342.820803) (xy 183.867569 -342.813044) (xy 183.815232 -342.797681)
			(xy 183.765615 -342.775025) (xy 183.719727 -342.745538) (xy 183.678502 -342.70982) (xy 183.642781 -342.668599)
			(xy 183.613291 -342.622714) (xy 183.590631 -342.573098) (xy 183.575263 -342.520763) (xy 183.5675 -342.466773)
			(xy 182.084796 -342.466773) (xy 182.077034 -342.520761) (xy 182.061666 -342.573096) (xy 182.039007 -342.622711)
			(xy 182.009516 -342.668595) (xy 181.973796 -342.709816) (xy 181.932573 -342.745533) (xy 181.886686 -342.77502)
			(xy 181.83707 -342.797676) (xy 181.784734 -342.81304) (xy 181.730744 -342.820798) (xy 181.703472 -342.82126)
			(xy 180.839872 -342.82126) (xy 180.812604 -342.820776) (xy 180.758623 -342.813011) (xy 180.706296 -342.797643)
			(xy 180.65669 -342.774985) (xy 180.610812 -342.745498) (xy 180.569597 -342.709783) (xy 180.533885 -342.668566)
			(xy 180.504402 -342.622686) (xy 180.481747 -342.573077) (xy 180.466383 -342.52075) (xy 180.458622 -342.466768)
			(xy 178.975774 -342.466768) (xy 178.975774 -342.466769) (xy 178.968012 -342.520751) (xy 178.952648 -342.573079)
			(xy 178.929992 -342.622688) (xy 178.900508 -342.668568) (xy 178.864794 -342.709786) (xy 178.823578 -342.745501)
			(xy 178.777699 -342.774987) (xy 178.728091 -342.797643) (xy 178.675763 -342.81301) (xy 178.621781 -342.820773)
			(xy 178.594512 -342.82126) (xy 177.730912 -342.82126) (xy 177.70364 -342.820801) (xy 177.649652 -342.813041)
			(xy 177.597317 -342.797675) (xy 177.547703 -342.775018) (xy 177.501817 -342.745531) (xy 177.460595 -342.709813)
			(xy 177.424876 -342.668593) (xy 177.395388 -342.622708) (xy 177.372729 -342.573094) (xy 177.357362 -342.52076)
			(xy 177.3496 -342.466772) (xy 175.866896 -342.466772) (xy 175.866896 -342.466773) (xy 175.859133 -342.520764)
			(xy 175.843764 -342.5731) (xy 175.821103 -342.622716) (xy 175.791612 -342.668602) (xy 175.755889 -342.709823)
			(xy 175.714663 -342.74554) (xy 175.668774 -342.775026) (xy 175.619155 -342.797681) (xy 175.566817 -342.813043)
			(xy 175.512825 -342.8208) (xy 175.485552 -342.82126) (xy 174.621952 -342.82126) (xy 174.594685 -342.820774)
			(xy 174.540706 -342.813007) (xy 174.488382 -342.797637) (xy 174.438778 -342.774978) (xy 174.392902 -342.745491)
			(xy 174.35169 -342.709776) (xy 174.31598 -342.668559) (xy 174.286499 -342.62268) (xy 174.263846 -342.573073)
			(xy 174.248483 -342.520747) (xy 174.240722 -342.466767) (xy 172.757896 -342.466767) (xy 172.757896 -342.466771)
			(xy 172.750134 -342.520759) (xy 172.734768 -342.573092) (xy 172.71211 -342.622705) (xy 172.682621 -342.668589)
			(xy 172.646903 -342.709809) (xy 172.605682 -342.745526) (xy 172.559798 -342.775013) (xy 172.510184 -342.79767)
			(xy 172.457851 -342.813036) (xy 172.403863 -342.820797) (xy 172.376592 -342.82126) (xy 171.512992 -342.82126)
			(xy 171.485723 -342.820777) (xy 171.43174 -342.813014) (xy 171.379411 -342.797648) (xy 171.329802 -342.774991)
			(xy 171.283921 -342.745505) (xy 171.242705 -342.70979) (xy 171.20699 -342.668572) (xy 171.177505 -342.622691)
			(xy 171.154849 -342.573082) (xy 171.139484 -342.520752) (xy 171.131722 -342.466769) (xy 169.648874 -342.466769)
			(xy 169.641113 -342.520748) (xy 169.625749 -342.573075) (xy 169.603095 -342.622683) (xy 169.573613 -342.668562)
			(xy 169.537901 -342.709778) (xy 169.496688 -342.745494) (xy 169.450811 -342.77498) (xy 169.401205 -342.797638)
			(xy 169.34888 -342.813006) (xy 169.2949 -342.820771) (xy 169.267632 -342.82126) (xy 168.404032 -342.82126)
			(xy 168.376759 -342.820803) (xy 168.322769 -342.813044) (xy 168.270432 -342.797681) (xy 168.220815 -342.775025)
			(xy 168.174927 -342.745538) (xy 168.133702 -342.70982) (xy 168.097981 -342.668599) (xy 168.068491 -342.622714)
			(xy 168.045831 -342.573098) (xy 168.030463 -342.520763) (xy 168.0227 -342.466773) (xy 166.539996 -342.466773)
			(xy 166.532234 -342.520761) (xy 166.516866 -342.573096) (xy 166.494207 -342.622711) (xy 166.464716 -342.668595)
			(xy 166.428996 -342.709816) (xy 166.387773 -342.745533) (xy 166.341886 -342.77502) (xy 166.29227 -342.797676)
			(xy 166.239934 -342.81304) (xy 166.185944 -342.820798) (xy 166.158672 -342.82126) (xy 165.295072 -342.82126)
			(xy 165.267804 -342.820776) (xy 165.213823 -342.813011) (xy 165.161496 -342.797643) (xy 165.11189 -342.774985)
			(xy 165.066012 -342.745498) (xy 165.024797 -342.709783) (xy 164.989085 -342.668566) (xy 164.959602 -342.622686)
			(xy 164.936947 -342.573077) (xy 164.921583 -342.52075) (xy 164.913822 -342.466768) (xy 144.196574 -342.466768)
			(xy 144.196574 -342.466769) (xy 144.188812 -342.520751) (xy 144.173447 -342.57308) (xy 144.150792 -342.622689)
			(xy 144.121307 -342.66857) (xy 144.085593 -342.709787) (xy 144.044376 -342.745502) (xy 143.998497 -342.774988)
			(xy 143.948888 -342.797645) (xy 143.896559 -342.81301) (xy 143.842577 -342.820773) (xy 143.815308 -342.82126)
			(xy 142.951708 -342.82126) (xy 142.924436 -342.820801) (xy 142.870448 -342.81304) (xy 142.818115 -342.797674)
			(xy 142.7685 -342.775017) (xy 142.722615 -342.745529) (xy 142.681394 -342.709812) (xy 142.645675 -342.668591)
			(xy 142.616187 -342.622707) (xy 142.593529 -342.573093) (xy 142.578162 -342.520759) (xy 142.5704 -342.466772)
			(xy 141.087573 -342.466772) (xy 141.079813 -342.520746) (xy 141.064451 -342.573072) (xy 141.041798 -342.622678)
			(xy 141.012317 -342.668557) (xy 140.976607 -342.709773) (xy 140.935395 -342.745488) (xy 140.88952 -342.774975)
			(xy 140.839917 -342.797634) (xy 140.787593 -342.813003) (xy 140.733615 -342.82077) (xy 140.706348 -342.82126)
			(xy 139.842748 -342.82126) (xy 139.815475 -342.820804) (xy 139.761482 -342.813047) (xy 139.709144 -342.797685)
			(xy 139.659524 -342.77503) (xy 139.613634 -342.745544) (xy 139.572408 -342.709826) (xy 139.536685 -342.668604)
			(xy 139.507193 -342.622718) (xy 139.484532 -342.573101) (xy 139.469163 -342.520765) (xy 139.4614 -342.466773)
			(xy 137.978696 -342.466773) (xy 137.970934 -342.520759) (xy 137.955567 -342.573092) (xy 137.932909 -342.622706)
			(xy 137.90342 -342.66859) (xy 137.867702 -342.70981) (xy 137.82648 -342.745528) (xy 137.780596 -342.775015)
			(xy 137.730981 -342.797671) (xy 137.678647 -342.813037) (xy 137.624659 -342.820797) (xy 137.597388 -342.82126)
			(xy 136.733788 -342.82126) (xy 136.706519 -342.820777) (xy 136.652536 -342.813014) (xy 136.600208 -342.797647)
			(xy 136.550599 -342.77499) (xy 136.50472 -342.745504) (xy 136.463503 -342.709788) (xy 136.427789 -342.668571)
			(xy 136.398304 -342.62269) (xy 136.375649 -342.573081) (xy 136.360284 -342.520752) (xy 136.352522 -342.466769)
			(xy 134.869674 -342.466769) (xy 134.861913 -342.520749) (xy 134.846549 -342.573076) (xy 134.823895 -342.622684)
			(xy 134.794412 -342.668563) (xy 134.7587 -342.70978) (xy 134.717486 -342.745495) (xy 134.671609 -342.774981)
			(xy 134.622002 -342.797639) (xy 134.569676 -342.813007) (xy 134.515696 -342.820772) (xy 134.488428 -342.82126)
			(xy 133.624828 -342.82126) (xy 133.597556 -342.820802) (xy 133.543565 -342.813043) (xy 133.491229 -342.79768)
			(xy 133.441612 -342.775023) (xy 133.395725 -342.745536) (xy 133.354501 -342.709819) (xy 133.31878 -342.668598)
			(xy 133.28929 -342.622712) (xy 133.26663 -342.573097) (xy 133.251262 -342.520762) (xy 133.2435 -342.466772)
			(xy 131.760796 -342.466772) (xy 131.753033 -342.520762) (xy 131.737666 -342.573097) (xy 131.715006 -342.622712)
			(xy 131.685515 -342.668597) (xy 131.649795 -342.709817) (xy 131.608571 -342.745535) (xy 131.562684 -342.775021)
			(xy 131.513067 -342.797677) (xy 131.46073 -342.81304) (xy 131.40674 -342.820799) (xy 131.379468 -342.82126)
			(xy 130.515868 -342.82126) (xy 130.4886 -342.820775) (xy 130.43462 -342.81301) (xy 130.382294 -342.797642)
			(xy 130.332687 -342.774984) (xy 130.28681 -342.745497) (xy 130.245596 -342.709781) (xy 130.209884 -342.668564)
			(xy 130.180401 -342.622685) (xy 130.157747 -342.573076) (xy 130.142383 -342.520749) (xy 130.134622 -342.466768)
			(xy 128.651774 -342.466768) (xy 128.651774 -342.466769) (xy 128.644012 -342.520751) (xy 128.628647 -342.57308)
			(xy 128.605992 -342.622689) (xy 128.576507 -342.66857) (xy 128.540793 -342.709787) (xy 128.499576 -342.745502)
			(xy 128.453697 -342.774988) (xy 128.404088 -342.797645) (xy 128.351759 -342.81301) (xy 128.297777 -342.820773)
			(xy 128.270508 -342.82126) (xy 127.406908 -342.82126) (xy 127.379636 -342.820801) (xy 127.325648 -342.81304)
			(xy 127.273315 -342.797674) (xy 127.2237 -342.775017) (xy 127.177815 -342.745529) (xy 127.136594 -342.709812)
			(xy 127.100875 -342.668591) (xy 127.071387 -342.622707) (xy 127.048729 -342.573093) (xy 127.033362 -342.520759)
			(xy 127.0256 -342.466772) (xy 125.542773 -342.466772) (xy 125.535013 -342.520746) (xy 125.519651 -342.573072)
			(xy 125.496998 -342.622678) (xy 125.467517 -342.668557) (xy 125.431807 -342.709773) (xy 125.390595 -342.745488)
			(xy 125.34472 -342.774975) (xy 125.295117 -342.797634) (xy 125.242793 -342.813003) (xy 125.188815 -342.82077)
			(xy 125.161548 -342.82126) (xy 124.297948 -342.82126) (xy 124.270675 -342.820804) (xy 124.216682 -342.813047)
			(xy 124.164344 -342.797685) (xy 124.114724 -342.77503) (xy 124.068834 -342.745544) (xy 124.027608 -342.709826)
			(xy 123.991885 -342.668604) (xy 123.962393 -342.622718) (xy 123.939732 -342.573101) (xy 123.924363 -342.520765)
			(xy 123.9166 -342.466773) (xy 122.433896 -342.466773) (xy 122.426134 -342.520759) (xy 122.410767 -342.573092)
			(xy 122.388109 -342.622706) (xy 122.35862 -342.66859) (xy 122.322902 -342.70981) (xy 122.28168 -342.745528)
			(xy 122.235796 -342.775015) (xy 122.186181 -342.797671) (xy 122.133847 -342.813037) (xy 122.079859 -342.820797)
			(xy 122.052588 -342.82126) (xy 121.188988 -342.82126) (xy 121.161719 -342.820777) (xy 121.107736 -342.813014)
			(xy 121.055408 -342.797647) (xy 121.005799 -342.77499) (xy 120.95992 -342.745504) (xy 120.918703 -342.709788)
			(xy 120.882989 -342.668571) (xy 120.853504 -342.62269) (xy 120.830849 -342.573081) (xy 120.815484 -342.520752)
			(xy 120.807722 -342.466769) (xy 119.324874 -342.466769) (xy 119.317113 -342.520749) (xy 119.301749 -342.573076)
			(xy 119.279095 -342.622684) (xy 119.249612 -342.668563) (xy 119.2139 -342.70978) (xy 119.172686 -342.745495)
			(xy 119.126809 -342.774981) (xy 119.077202 -342.797639) (xy 119.024876 -342.813007) (xy 118.970896 -342.820772)
			(xy 118.943628 -342.82126) (xy 118.080028 -342.82126) (xy 118.052756 -342.820802) (xy 117.998765 -342.813043)
			(xy 117.946429 -342.79768) (xy 117.896812 -342.775023) (xy 117.850925 -342.745536) (xy 117.809701 -342.709819)
			(xy 117.77398 -342.668598) (xy 117.74449 -342.622712) (xy 117.72183 -342.573097) (xy 117.706462 -342.520762)
			(xy 117.6987 -342.466772) (xy 116.215996 -342.466772) (xy 116.208233 -342.520762) (xy 116.192866 -342.573097)
			(xy 116.170206 -342.622712) (xy 116.140715 -342.668597) (xy 116.104995 -342.709817) (xy 116.063771 -342.745535)
			(xy 116.017884 -342.775021) (xy 115.968267 -342.797677) (xy 115.91593 -342.81304) (xy 115.86194 -342.820799)
			(xy 115.834668 -342.82126) (xy 114.971068 -342.82126) (xy 114.9438 -342.820775) (xy 114.88982 -342.81301)
			(xy 114.837494 -342.797642) (xy 114.787887 -342.774984) (xy 114.74201 -342.745497) (xy 114.700796 -342.709781)
			(xy 114.665084 -342.668564) (xy 114.635601 -342.622685) (xy 114.612947 -342.573076) (xy 114.597583 -342.520749)
			(xy 114.589822 -342.466768) (xy 113.106974 -342.466768) (xy 113.106974 -342.466769) (xy 113.099212 -342.520751)
			(xy 113.083847 -342.57308) (xy 113.061192 -342.622689) (xy 113.031707 -342.66857) (xy 112.995993 -342.709787)
			(xy 112.954776 -342.745502) (xy 112.908897 -342.774988) (xy 112.859288 -342.797645) (xy 112.806959 -342.81301)
			(xy 112.752977 -342.820773) (xy 112.725708 -342.82126) (xy 111.862108 -342.82126) (xy 111.834836 -342.820801)
			(xy 111.780848 -342.81304) (xy 111.728515 -342.797674) (xy 111.6789 -342.775017) (xy 111.633015 -342.745529)
			(xy 111.591794 -342.709812) (xy 111.556075 -342.668591) (xy 111.526587 -342.622707) (xy 111.503929 -342.573093)
			(xy 111.488562 -342.520759) (xy 111.4808 -342.466772) (xy 104.085479 -342.466772) (xy 104.10629 -342.517011)
			(xy 104.121803 -342.574906) (xy 104.129627 -342.634331) (xy 104.129627 -342.694269) (xy 104.121803 -342.753694)
			(xy 104.10629 -342.811589) (xy 104.083352 -342.866964) (xy 104.053383 -342.918871) (xy 104.016895 -342.966422)
			(xy 103.974512 -343.008804) (xy 103.926959 -343.045291) (xy 103.875051 -343.075259) (xy 103.819676 -343.098195)
			(xy 103.76178 -343.113706) (xy 103.702355 -343.121528) (xy 103.672386 -343.121996) (xy 102.808786 -343.121996)
			(xy 102.778818 -343.121529) (xy 102.719395 -343.113704) (xy 102.661502 -343.09819) (xy 102.60613 -343.075253)
			(xy 102.554224 -343.045284) (xy 102.506675 -343.008796) (xy 102.464294 -342.966415) (xy 102.427809 -342.918864)
			(xy 102.397841 -342.866958) (xy 102.374905 -342.811584) (xy 102.359393 -342.753691) (xy 102.35157 -342.694268)
			(xy 93.60914 -342.694268) (xy 93.595705 -342.709775) (xy 93.554492 -342.74549) (xy 93.508617 -342.774977)
			(xy 93.459012 -342.797635) (xy 93.406688 -342.813004) (xy 93.352709 -342.820771) (xy 93.325442 -342.82126)
			(xy 92.461842 -342.82126) (xy 92.434569 -342.820803) (xy 92.380577 -342.813046) (xy 92.328239 -342.797683)
			(xy 92.278621 -342.775028) (xy 92.232731 -342.745541) (xy 92.191506 -342.709824) (xy 92.155784 -342.668602)
			(xy 92.126292 -342.622716) (xy 92.103631 -342.5731) (xy 92.088263 -342.520764) (xy 92.0805 -342.466773)
			(xy 90.597796 -342.466773) (xy 90.590034 -342.52076) (xy 90.574667 -342.573094) (xy 90.552008 -342.622708)
			(xy 90.522519 -342.668592) (xy 90.4868 -342.709812) (xy 90.445578 -342.74553) (xy 90.399692 -342.775017)
			(xy 90.350077 -342.797673) (xy 90.297742 -342.813038) (xy 90.243754 -342.820798) (xy 90.216482 -342.82126)
			(xy 89.352882 -342.82126) (xy 89.325613 -342.820776) (xy 89.271631 -342.813013) (xy 89.219304 -342.797646)
			(xy 89.169696 -342.774988) (xy 89.123817 -342.745502) (xy 89.082601 -342.709786) (xy 89.046887 -342.668569)
			(xy 89.017403 -342.622689) (xy 88.994748 -342.573079) (xy 88.979384 -342.520751) (xy 88.971622 -342.466769)
			(xy 87.488774 -342.466769) (xy 87.481013 -342.52075) (xy 87.465648 -342.573077) (xy 87.442994 -342.622686)
			(xy 87.41351 -342.668565) (xy 87.377798 -342.709782) (xy 87.336583 -342.745497) (xy 87.290705 -342.774983)
			(xy 87.241098 -342.797641) (xy 87.188771 -342.813008) (xy 87.13479 -342.820772) (xy 87.107522 -342.82126)
			(xy 86.243922 -342.82126) (xy 86.21665 -342.820802) (xy 86.16266 -342.813042) (xy 86.110325 -342.797678)
			(xy 86.060709 -342.775021) (xy 86.014822 -342.745534) (xy 85.973599 -342.709817) (xy 85.937879 -342.668596)
			(xy 85.908389 -342.622711) (xy 85.88573 -342.573096) (xy 85.870362 -342.520761) (xy 85.8626 -342.466772)
			(xy 84.379896 -342.466772) (xy 84.379896 -342.466773) (xy 84.372133 -342.520763) (xy 84.356765 -342.573098)
			(xy 84.334105 -342.622713) (xy 84.304614 -342.668599) (xy 84.268893 -342.70982) (xy 84.227668 -342.745537)
			(xy 84.18178 -342.775023) (xy 84.132162 -342.797679) (xy 84.079825 -342.813041) (xy 84.025835 -342.820799)
			(xy 83.998562 -342.82126) (xy 83.134962 -342.82126) (xy 83.107694 -342.820775) (xy 83.053714 -342.813009)
			(xy 83.001389 -342.79764) (xy 82.951784 -342.774982) (xy 82.905907 -342.745495) (xy 82.864694 -342.709779)
			(xy 82.828983 -342.668562) (xy 82.7995 -342.622683) (xy 82.776847 -342.573075) (xy 82.761483 -342.520748)
			(xy 82.753722 -342.466768) (xy 81.270874 -342.466768) (xy 81.270874 -342.466769) (xy 81.263112 -342.520752)
			(xy 81.247747 -342.573081) (xy 81.225091 -342.622691) (xy 81.195605 -342.668572) (xy 81.159891 -342.709789)
			(xy 81.118673 -342.745504) (xy 81.072793 -342.77499) (xy 81.023183 -342.797646) (xy 80.970854 -342.813012)
			(xy 80.916871 -342.820773) (xy 80.889602 -342.82126) (xy 80.026002 -342.82126) (xy 79.998731 -342.820801)
			(xy 79.944743 -342.813039) (xy 79.89241 -342.797673) (xy 79.842797 -342.775015) (xy 79.796912 -342.745527)
			(xy 79.755692 -342.70981) (xy 79.719974 -342.668589) (xy 79.690486 -342.622705) (xy 79.667828 -342.573092)
			(xy 79.652462 -342.520759) (xy 79.644699 -342.466771) (xy 78.161873 -342.466771) (xy 78.154113 -342.520747)
			(xy 78.13875 -342.573073) (xy 78.116097 -342.62268) (xy 78.086615 -342.668559) (xy 78.050905 -342.709775)
			(xy 78.009692 -342.74549) (xy 77.963817 -342.774977) (xy 77.914212 -342.797635) (xy 77.861888 -342.813004)
			(xy 77.807909 -342.820771) (xy 77.780642 -342.82126) (xy 76.917042 -342.82126) (xy 76.889769 -342.820803)
			(xy 76.835777 -342.813046) (xy 76.783439 -342.797683) (xy 76.733821 -342.775028) (xy 76.687931 -342.745541)
			(xy 76.646706 -342.709824) (xy 76.610984 -342.668602) (xy 76.581492 -342.622716) (xy 76.558831 -342.5731)
			(xy 76.543463 -342.520764) (xy 76.5357 -342.466773) (xy 75.052996 -342.466773) (xy 75.045234 -342.52076)
			(xy 75.029867 -342.573094) (xy 75.007208 -342.622708) (xy 74.977719 -342.668592) (xy 74.942 -342.709812)
			(xy 74.900778 -342.74553) (xy 74.854892 -342.775017) (xy 74.805277 -342.797673) (xy 74.752942 -342.813038)
			(xy 74.698954 -342.820798) (xy 74.671682 -342.82126) (xy 73.808082 -342.82126) (xy 73.780813 -342.820776)
			(xy 73.726831 -342.813013) (xy 73.674504 -342.797646) (xy 73.624896 -342.774988) (xy 73.579017 -342.745502)
			(xy 73.537801 -342.709786) (xy 73.502087 -342.668569) (xy 73.472603 -342.622689) (xy 73.449948 -342.573079)
			(xy 73.434584 -342.520751) (xy 73.426822 -342.466769) (xy 71.943974 -342.466769) (xy 71.936213 -342.52075)
			(xy 71.920848 -342.573077) (xy 71.898194 -342.622686) (xy 71.86871 -342.668565) (xy 71.832998 -342.709782)
			(xy 71.791783 -342.745497) (xy 71.745905 -342.774983) (xy 71.696298 -342.797641) (xy 71.643971 -342.813008)
			(xy 71.58999 -342.820772) (xy 71.562722 -342.82126) (xy 70.699122 -342.82126) (xy 70.67185 -342.820802)
			(xy 70.61786 -342.813042) (xy 70.565525 -342.797678) (xy 70.515909 -342.775021) (xy 70.470022 -342.745534)
			(xy 70.428799 -342.709817) (xy 70.393079 -342.668596) (xy 70.363589 -342.622711) (xy 70.34093 -342.573096)
			(xy 70.325562 -342.520761) (xy 70.3178 -342.466772) (xy 68.835096 -342.466772) (xy 68.835096 -342.466773)
			(xy 68.827333 -342.520763) (xy 68.811965 -342.573098) (xy 68.789305 -342.622713) (xy 68.759814 -342.668599)
			(xy 68.724093 -342.70982) (xy 68.682868 -342.745537) (xy 68.63698 -342.775023) (xy 68.587362 -342.797679)
			(xy 68.535025 -342.813041) (xy 68.481035 -342.820799) (xy 68.453762 -342.82126) (xy 67.590162 -342.82126)
			(xy 67.562894 -342.820775) (xy 67.508914 -342.813009) (xy 67.456589 -342.79764) (xy 67.406984 -342.774982)
			(xy 67.361107 -342.745495) (xy 67.319894 -342.709779) (xy 67.284183 -342.668562) (xy 67.2547 -342.622683)
			(xy 67.232047 -342.573075) (xy 67.216683 -342.520748) (xy 67.208922 -342.466768) (xy 65.726074 -342.466768)
			(xy 65.726074 -342.466769) (xy 65.718312 -342.520752) (xy 65.702947 -342.573081) (xy 65.680291 -342.622691)
			(xy 65.650805 -342.668572) (xy 65.615091 -342.709789) (xy 65.573873 -342.745504) (xy 65.527993 -342.77499)
			(xy 65.478383 -342.797646) (xy 65.426054 -342.813012) (xy 65.372071 -342.820773) (xy 65.344802 -342.82126)
			(xy 64.481202 -342.82126) (xy 64.453931 -342.820801) (xy 64.399943 -342.813039) (xy 64.34761 -342.797673)
			(xy 64.297997 -342.775015) (xy 64.252112 -342.745527) (xy 64.210892 -342.70981) (xy 64.175174 -342.668589)
			(xy 64.145686 -342.622705) (xy 64.123028 -342.573092) (xy 64.107662 -342.520759) (xy 64.099899 -342.466771)
			(xy 62.617073 -342.466771) (xy 62.609313 -342.520747) (xy 62.59395 -342.573073) (xy 62.571297 -342.62268)
			(xy 62.541815 -342.668559) (xy 62.506105 -342.709775) (xy 62.464892 -342.74549) (xy 62.419017 -342.774977)
			(xy 62.369412 -342.797635) (xy 62.317088 -342.813004) (xy 62.263109 -342.820771) (xy 62.235842 -342.82126)
			(xy 61.372242 -342.82126) (xy 61.344969 -342.820803) (xy 61.290977 -342.813046) (xy 61.238639 -342.797683)
			(xy 61.189021 -342.775028) (xy 61.143131 -342.745541) (xy 61.101906 -342.709824) (xy 61.066184 -342.668602)
			(xy 61.036692 -342.622716) (xy 61.014031 -342.5731) (xy 60.998663 -342.520764) (xy 60.9909 -342.466773)
			(xy 51.666873 -342.466773) (xy 51.659113 -342.520746) (xy 51.643751 -342.573072) (xy 51.621098 -342.622678)
			(xy 51.591617 -342.668557) (xy 51.555907 -342.709773) (xy 51.514695 -342.745488) (xy 51.46882 -342.774975)
			(xy 51.419217 -342.797634) (xy 51.366893 -342.813003) (xy 51.312915 -342.82077) (xy 51.285648 -342.82126)
			(xy 50.422048 -342.82126) (xy 50.394775 -342.820804) (xy 50.340782 -342.813047) (xy 50.288444 -342.797685)
			(xy 50.238824 -342.77503) (xy 50.192934 -342.745544) (xy 50.151708 -342.709826) (xy 50.115985 -342.668604)
			(xy 50.086493 -342.622718) (xy 50.063832 -342.573101) (xy 50.048463 -342.520765) (xy 50.0407 -342.466773)
			(xy 48.557996 -342.466773) (xy 48.550234 -342.520759) (xy 48.534867 -342.573092) (xy 48.512209 -342.622706)
			(xy 48.48272 -342.66859) (xy 48.447002 -342.70981) (xy 48.40578 -342.745528) (xy 48.359896 -342.775015)
			(xy 48.310281 -342.797671) (xy 48.257947 -342.813037) (xy 48.203959 -342.820797) (xy 48.176688 -342.82126)
			(xy 47.313088 -342.82126) (xy 47.285819 -342.820777) (xy 47.231836 -342.813014) (xy 47.179508 -342.797647)
			(xy 47.129899 -342.77499) (xy 47.08402 -342.745504) (xy 47.042803 -342.709788) (xy 47.007089 -342.668571)
			(xy 46.977604 -342.62269) (xy 46.954949 -342.573081) (xy 46.939584 -342.520752) (xy 46.931822 -342.466769)
			(xy 45.448974 -342.466769) (xy 45.441213 -342.520749) (xy 45.425849 -342.573076) (xy 45.403195 -342.622684)
			(xy 45.373712 -342.668563) (xy 45.338 -342.70978) (xy 45.296786 -342.745495) (xy 45.250909 -342.774981)
			(xy 45.201302 -342.797639) (xy 45.148976 -342.813007) (xy 45.094996 -342.820772) (xy 45.067728 -342.82126)
			(xy 44.204128 -342.82126) (xy 44.176856 -342.820802) (xy 44.122865 -342.813043) (xy 44.070529 -342.79768)
			(xy 44.020912 -342.775023) (xy 43.975025 -342.745536) (xy 43.933801 -342.709819) (xy 43.89808 -342.668598)
			(xy 43.86859 -342.622712) (xy 43.84593 -342.573097) (xy 43.830562 -342.520762) (xy 43.8228 -342.466772)
			(xy 42.340096 -342.466772) (xy 42.332333 -342.520762) (xy 42.316966 -342.573097) (xy 42.294306 -342.622712)
			(xy 42.264815 -342.668597) (xy 42.229095 -342.709817) (xy 42.187871 -342.745535) (xy 42.141984 -342.775021)
			(xy 42.092367 -342.797677) (xy 42.04003 -342.81304) (xy 41.98604 -342.820799) (xy 41.958768 -342.82126)
			(xy 41.095168 -342.82126) (xy 41.0679 -342.820775) (xy 41.01392 -342.81301) (xy 40.961594 -342.797642)
			(xy 40.911987 -342.774984) (xy 40.86611 -342.745497) (xy 40.824896 -342.709781) (xy 40.789184 -342.668564)
			(xy 40.759701 -342.622685) (xy 40.737047 -342.573076) (xy 40.721683 -342.520749) (xy 40.713922 -342.466768)
			(xy 39.231074 -342.466768) (xy 39.231074 -342.466769) (xy 39.223312 -342.520751) (xy 39.207947 -342.57308)
			(xy 39.185292 -342.622689) (xy 39.155807 -342.66857) (xy 39.120093 -342.709787) (xy 39.078876 -342.745502)
			(xy 39.032997 -342.774988) (xy 38.983388 -342.797645) (xy 38.931059 -342.81301) (xy 38.877077 -342.820773)
			(xy 38.849808 -342.82126) (xy 37.986208 -342.82126) (xy 37.958936 -342.820801) (xy 37.904948 -342.81304)
			(xy 37.852615 -342.797674) (xy 37.803 -342.775017) (xy 37.757115 -342.745529) (xy 37.715894 -342.709812)
			(xy 37.680175 -342.668591) (xy 37.650687 -342.622707) (xy 37.628029 -342.573093) (xy 37.612662 -342.520759)
			(xy 37.6049 -342.466772) (xy 36.122073 -342.466772) (xy 36.114313 -342.520746) (xy 36.098951 -342.573072)
			(xy 36.076298 -342.622678) (xy 36.046817 -342.668557) (xy 36.011107 -342.709773) (xy 35.969895 -342.745488)
			(xy 35.92402 -342.774975) (xy 35.874417 -342.797634) (xy 35.822093 -342.813003) (xy 35.768115 -342.82077)
			(xy 35.740848 -342.82126) (xy 34.877248 -342.82126) (xy 34.849975 -342.820804) (xy 34.795982 -342.813047)
			(xy 34.743644 -342.797685) (xy 34.694024 -342.77503) (xy 34.648134 -342.745544) (xy 34.606908 -342.709826)
			(xy 34.571185 -342.668604) (xy 34.541693 -342.622718) (xy 34.519032 -342.573101) (xy 34.503663 -342.520765)
			(xy 34.4959 -342.466773) (xy 33.013196 -342.466773) (xy 33.005434 -342.520759) (xy 32.990067 -342.573092)
			(xy 32.967409 -342.622706) (xy 32.93792 -342.66859) (xy 32.902202 -342.70981) (xy 32.86098 -342.745528)
			(xy 32.815096 -342.775015) (xy 32.765481 -342.797671) (xy 32.713147 -342.813037) (xy 32.659159 -342.820797)
			(xy 32.631888 -342.82126) (xy 31.768288 -342.82126) (xy 31.741019 -342.820777) (xy 31.687036 -342.813014)
			(xy 31.634708 -342.797647) (xy 31.585099 -342.77499) (xy 31.53922 -342.745504) (xy 31.498003 -342.709788)
			(xy 31.462289 -342.668571) (xy 31.432804 -342.62269) (xy 31.410149 -342.573081) (xy 31.394784 -342.520752)
			(xy 31.387022 -342.466769) (xy 29.904174 -342.466769) (xy 29.896413 -342.520749) (xy 29.881049 -342.573076)
			(xy 29.858395 -342.622684) (xy 29.828912 -342.668563) (xy 29.7932 -342.70978) (xy 29.751986 -342.745495)
			(xy 29.706109 -342.774981) (xy 29.656502 -342.797639) (xy 29.604176 -342.813007) (xy 29.550196 -342.820772)
			(xy 29.522928 -342.82126) (xy 28.659328 -342.82126) (xy 28.632056 -342.820802) (xy 28.578065 -342.813043)
			(xy 28.525729 -342.79768) (xy 28.476112 -342.775023) (xy 28.430225 -342.745536) (xy 28.389001 -342.709819)
			(xy 28.35328 -342.668598) (xy 28.32379 -342.622712) (xy 28.30113 -342.573097) (xy 28.285762 -342.520762)
			(xy 28.278 -342.466772) (xy 26.795296 -342.466772) (xy 26.787533 -342.520762) (xy 26.772166 -342.573097)
			(xy 26.749506 -342.622712) (xy 26.720015 -342.668597) (xy 26.684295 -342.709817) (xy 26.643071 -342.745535)
			(xy 26.597184 -342.775021) (xy 26.547567 -342.797677) (xy 26.49523 -342.81304) (xy 26.44124 -342.820799)
			(xy 26.413968 -342.82126) (xy 25.550368 -342.82126) (xy 25.5231 -342.820775) (xy 25.46912 -342.81301)
			(xy 25.416794 -342.797642) (xy 25.367187 -342.774984) (xy 25.32131 -342.745497) (xy 25.280096 -342.709781)
			(xy 25.244384 -342.668564) (xy 25.214901 -342.622685) (xy 25.192247 -342.573076) (xy 25.176883 -342.520749)
			(xy 25.169122 -342.466768) (xy 23.686274 -342.466768) (xy 23.686274 -342.466769) (xy 23.678512 -342.520751)
			(xy 23.663147 -342.57308) (xy 23.640492 -342.622689) (xy 23.611007 -342.66857) (xy 23.575293 -342.709787)
			(xy 23.534076 -342.745502) (xy 23.488197 -342.774988) (xy 23.438588 -342.797645) (xy 23.386259 -342.81301)
			(xy 23.332277 -342.820773) (xy 23.305008 -342.82126) (xy 22.441408 -342.82126) (xy 22.414136 -342.820801)
			(xy 22.360148 -342.81304) (xy 22.307815 -342.797674) (xy 22.2582 -342.775017) (xy 22.212315 -342.745529)
			(xy 22.171094 -342.709812) (xy 22.135375 -342.668591) (xy 22.105887 -342.622707) (xy 22.083229 -342.573093)
			(xy 22.067862 -342.520759) (xy 22.0601 -342.466772) (xy 20.577347 -342.466772) (xy 20.569584 -342.520758)
			(xy 20.554218 -342.57309) (xy 20.53156 -342.622703) (xy 20.502073 -342.668587) (xy 20.466355 -342.709807)
			(xy 20.425135 -342.745524) (xy 20.379252 -342.775011) (xy 20.329638 -342.797669) (xy 20.277306 -342.813035)
			(xy 20.223319 -342.820797) (xy 20.196048 -342.82126) (xy 19.332448 -342.82126) (xy 19.305179 -342.820777)
			(xy 19.251195 -342.813015) (xy 19.198865 -342.79765) (xy 19.149255 -342.774993) (xy 19.103374 -342.745507)
			(xy 19.062157 -342.709792) (xy 19.026441 -342.668574) (xy 18.996956 -342.622693) (xy 18.974299 -342.573083)
			(xy 18.958934 -342.520753) (xy 18.951172 -342.466769) (xy 0.509016 -342.466769) (xy 0.509016 -345.49242)
			(xy 18.95117 -345.49242) (xy 18.95117 -345.43788) (xy 18.958932 -345.383896) (xy 18.974298 -345.331567)
			(xy 18.996954 -345.281956) (xy 19.02644 -345.236075) (xy 19.062155 -345.194857) (xy 19.103373 -345.159141)
			(xy 19.149254 -345.129655) (xy 19.198865 -345.106998) (xy 19.251194 -345.091633) (xy 19.305178 -345.083871)
			(xy 19.332448 -345.083384) (xy 20.196048 -345.083384) (xy 20.223319 -345.083855) (xy 20.277305 -345.091617)
			(xy 20.329638 -345.106983) (xy 20.379251 -345.12964) (xy 20.425134 -345.159128) (xy 20.466354 -345.194845)
			(xy 20.502071 -345.236064) (xy 20.531559 -345.281948) (xy 20.554216 -345.33156) (xy 20.569582 -345.383893)
			(xy 20.577345 -345.437879) (xy 20.577345 -345.49242) (xy 22.06013 -345.49242) (xy 22.06013 -345.43788)
			(xy 22.067892 -345.383896) (xy 22.083258 -345.331567) (xy 22.105914 -345.281956) (xy 22.1354 -345.236075)
			(xy 22.171115 -345.194857) (xy 22.212333 -345.159141) (xy 22.258214 -345.129655) (xy 22.307825 -345.106998)
			(xy 22.360154 -345.091633) (xy 22.414138 -345.083871) (xy 22.441408 -345.083384) (xy 23.305008 -345.083384)
			(xy 23.332279 -345.083855) (xy 23.386265 -345.091617) (xy 23.438598 -345.106983) (xy 23.488211 -345.12964)
			(xy 23.534094 -345.159128) (xy 23.575314 -345.194845) (xy 23.611031 -345.236064) (xy 23.640519 -345.281948)
			(xy 23.663176 -345.33156) (xy 23.678542 -345.383893) (xy 23.686305 -345.437879) (xy 23.686305 -345.492365)
			(xy 25.16917 -345.492365) (xy 25.16917 -345.437835) (xy 25.17693 -345.383861) (xy 25.192292 -345.33154)
			(xy 25.214943 -345.281938) (xy 25.244422 -345.236064) (xy 25.28013 -345.194853) (xy 25.321339 -345.159142)
			(xy 25.36721 -345.129658) (xy 25.41681 -345.107003) (xy 25.46913 -345.091637) (xy 25.523103 -345.083872)
			(xy 25.550368 -345.083384) (xy 26.413968 -345.083384) (xy 26.441244 -345.083753) (xy 26.495241 -345.091513)
			(xy 26.547583 -345.106878) (xy 26.597207 -345.129537) (xy 26.6431 -345.159027) (xy 26.684329 -345.194749)
			(xy 26.720054 -345.235975) (xy 26.749548 -345.281865) (xy 26.772211 -345.331487) (xy 26.78758 -345.383828)
			(xy 26.795344 -345.437824) (xy 26.795344 -345.492369) (xy 28.278047 -345.492369) (xy 28.278047 -345.437831)
			(xy 28.285809 -345.383848) (xy 28.301175 -345.33152) (xy 28.323832 -345.281911) (xy 28.353319 -345.236031)
			(xy 28.389035 -345.194815) (xy 28.430253 -345.159102) (xy 28.476135 -345.129619) (xy 28.525746 -345.106965)
			(xy 28.578076 -345.091603) (xy 28.632059 -345.083845) (xy 28.659328 -345.083384) (xy 29.522928 -345.083384)
			(xy 29.550199 -345.08378) (xy 29.604186 -345.091546) (xy 29.656519 -345.106916) (xy 29.706132 -345.129576)
			(xy 29.752014 -345.159067) (xy 29.793234 -345.194786) (xy 29.82895 -345.236008) (xy 29.858437 -345.281893)
			(xy 29.881094 -345.331507) (xy 29.89646 -345.383841) (xy 29.904222 -345.437829) (xy 29.904222 -345.492366)
			(xy 31.38707 -345.492366) (xy 31.38707 -345.437834) (xy 31.394831 -345.383858) (xy 31.410194 -345.331536)
			(xy 31.432846 -345.281933) (xy 31.462327 -345.236058) (xy 31.498037 -345.194846) (xy 31.539248 -345.159135)
			(xy 31.585122 -345.129652) (xy 31.634725 -345.106998) (xy 31.687047 -345.091633) (xy 31.741022 -345.083871)
			(xy 31.768288 -345.083384) (xy 32.631888 -345.083384) (xy 32.659163 -345.083755) (xy 32.713157 -345.091516)
			(xy 32.765498 -345.106884) (xy 32.815119 -345.129543) (xy 32.861009 -345.159034) (xy 32.902236 -345.194756)
			(xy 32.937959 -345.235981) (xy 32.967451 -345.281871) (xy 32.990112 -345.331491) (xy 33.005481 -345.383831)
			(xy 33.013244 -345.437825) (xy 33.013244 -345.49237) (xy 34.495948 -345.49237) (xy 34.495948 -345.43783)
			(xy 34.50371 -345.383846) (xy 34.519077 -345.331515) (xy 34.541735 -345.281905) (xy 34.571224 -345.236024)
			(xy 34.606942 -345.194808) (xy 34.648163 -345.159095) (xy 34.694047 -345.129612) (xy 34.74366 -345.10696)
			(xy 34.795992 -345.0916) (xy 34.849978 -345.083844) (xy 34.877248 -345.083384) (xy 35.740848 -345.083384)
			(xy 35.768118 -345.083782) (xy 35.822103 -345.09155) (xy 35.874433 -345.106921) (xy 35.924044 -345.129583)
			(xy 35.969924 -345.159074) (xy 36.011141 -345.194793) (xy 36.046855 -345.236015) (xy 36.07634 -345.281899)
			(xy 36.098995 -345.331512) (xy 36.11436 -345.383844) (xy 36.122122 -345.43783) (xy 36.122122 -345.492368)
			(xy 37.604947 -345.492368) (xy 37.604947 -345.437832) (xy 37.612709 -345.383851) (xy 37.628074 -345.331524)
			(xy 37.650729 -345.281916) (xy 37.680214 -345.236038) (xy 37.715928 -345.194822) (xy 37.757144 -345.159109)
			(xy 37.803023 -345.129625) (xy 37.852631 -345.106971) (xy 37.904959 -345.091607) (xy 37.95894 -345.083847)
			(xy 37.986208 -345.083384) (xy 38.849808 -345.083384) (xy 38.87708 -345.083779) (xy 38.93107 -345.091543)
			(xy 38.983404 -345.106911) (xy 39.03302 -345.12957) (xy 39.078905 -345.15906) (xy 39.120127 -345.194779)
			(xy 39.155845 -345.236001) (xy 39.185334 -345.281888) (xy 39.207992 -345.331503) (xy 39.223359 -345.383838)
			(xy 39.231121 -345.437828) (xy 39.231121 -345.492365) (xy 40.71397 -345.492365) (xy 40.71397 -345.437835)
			(xy 40.72173 -345.383861) (xy 40.737092 -345.33154) (xy 40.759743 -345.281938) (xy 40.789222 -345.236064)
			(xy 40.82493 -345.194853) (xy 40.866139 -345.159142) (xy 40.91201 -345.129658) (xy 40.96161 -345.107003)
			(xy 41.01393 -345.091637) (xy 41.067903 -345.083872) (xy 41.095168 -345.083384) (xy 41.958768 -345.083384)
			(xy 41.986044 -345.083753) (xy 42.040041 -345.091513) (xy 42.092383 -345.106878) (xy 42.142007 -345.129537)
			(xy 42.1879 -345.159027) (xy 42.229129 -345.194749) (xy 42.264854 -345.235975) (xy 42.294348 -345.281865)
			(xy 42.317011 -345.331487) (xy 42.33238 -345.383828) (xy 42.340144 -345.437824) (xy 42.340144 -345.492369)
			(xy 43.822847 -345.492369) (xy 43.822847 -345.437831) (xy 43.830609 -345.383848) (xy 43.845975 -345.33152)
			(xy 43.868632 -345.281911) (xy 43.898119 -345.236031) (xy 43.933835 -345.194815) (xy 43.975053 -345.159102)
			(xy 44.020935 -345.129619) (xy 44.070546 -345.106965) (xy 44.122876 -345.091603) (xy 44.176859 -345.083845)
			(xy 44.204128 -345.083384) (xy 45.067728 -345.083384) (xy 45.094999 -345.08378) (xy 45.148986 -345.091546)
			(xy 45.201319 -345.106916) (xy 45.250932 -345.129576) (xy 45.296814 -345.159067) (xy 45.338034 -345.194786)
			(xy 45.37375 -345.236008) (xy 45.403237 -345.281893) (xy 45.425894 -345.331507) (xy 45.44126 -345.383841)
			(xy 45.449022 -345.437829) (xy 45.449022 -345.492366) (xy 46.93187 -345.492366) (xy 46.93187 -345.437834)
			(xy 46.939631 -345.383858) (xy 46.954994 -345.331536) (xy 46.977646 -345.281933) (xy 47.007127 -345.236058)
			(xy 47.042837 -345.194846) (xy 47.084048 -345.159135) (xy 47.129922 -345.129652) (xy 47.179525 -345.106998)
			(xy 47.231847 -345.091633) (xy 47.285822 -345.083871) (xy 47.313088 -345.083384) (xy 48.176688 -345.083384)
			(xy 48.203963 -345.083755) (xy 48.257957 -345.091516) (xy 48.310298 -345.106884) (xy 48.359919 -345.129543)
			(xy 48.405809 -345.159034) (xy 48.447036 -345.194756) (xy 48.482759 -345.235981) (xy 48.512251 -345.281871)
			(xy 48.534912 -345.331491) (xy 48.550281 -345.383831) (xy 48.558044 -345.437825) (xy 48.558044 -345.49237)
			(xy 50.040748 -345.49237) (xy 50.040748 -345.43783) (xy 50.04851 -345.383846) (xy 50.063877 -345.331515)
			(xy 50.086535 -345.281905) (xy 50.116024 -345.236024) (xy 50.151742 -345.194808) (xy 50.192963 -345.159095)
			(xy 50.238847 -345.129612) (xy 50.28846 -345.10696) (xy 50.340792 -345.0916) (xy 50.394778 -345.083844)
			(xy 50.422048 -345.083384) (xy 51.285648 -345.083384) (xy 51.312918 -345.083782) (xy 51.366903 -345.09155)
			(xy 51.419233 -345.106921) (xy 51.468844 -345.129583) (xy 51.514724 -345.159074) (xy 51.555941 -345.194793)
			(xy 51.591655 -345.236015) (xy 51.62114 -345.281899) (xy 51.643795 -345.331512) (xy 51.65916 -345.383844)
			(xy 51.666922 -345.43783) (xy 51.666922 -345.49237) (xy 60.990948 -345.49237) (xy 60.990948 -345.43783)
			(xy 60.99871 -345.383846) (xy 61.014076 -345.331517) (xy 61.036734 -345.281907) (xy 61.066222 -345.236026)
			(xy 61.10194 -345.19481) (xy 61.14316 -345.159097) (xy 61.189044 -345.129614) (xy 61.238656 -345.106962)
			(xy 61.290987 -345.091601) (xy 61.344972 -345.083845) (xy 61.372242 -345.083384) (xy 62.235842 -345.083384)
			(xy 62.263113 -345.083781) (xy 62.317098 -345.091549) (xy 62.369429 -345.10692) (xy 62.41904 -345.129581)
			(xy 62.464921 -345.159072) (xy 62.506139 -345.194791) (xy 62.541854 -345.236013) (xy 62.571339 -345.281897)
			(xy 62.593995 -345.33151) (xy 62.60936 -345.383843) (xy 62.617122 -345.437829) (xy 62.617122 -345.492368)
			(xy 64.099947 -345.492368) (xy 64.099947 -345.437832) (xy 64.107709 -345.383852) (xy 64.123073 -345.331525)
			(xy 64.145728 -345.281918) (xy 64.175212 -345.23604) (xy 64.210926 -345.194824) (xy 64.252141 -345.159111)
			(xy 64.29802 -345.129627) (xy 64.347627 -345.106972) (xy 64.399954 -345.091608) (xy 64.453934 -345.083847)
			(xy 64.481202 -345.083384) (xy 65.344802 -345.083384) (xy 65.372075 -345.083779) (xy 65.426064 -345.091542)
			(xy 65.4784 -345.106909) (xy 65.528016 -345.129568) (xy 65.573902 -345.159057) (xy 65.615124 -345.194777)
			(xy 65.650844 -345.236) (xy 65.680333 -345.281886) (xy 65.702992 -345.331502) (xy 65.718359 -345.383838)
			(xy 65.726121 -345.437827) (xy 65.726121 -345.492364) (xy 67.20897 -345.492364) (xy 67.20897 -345.437836)
			(xy 67.21673 -345.383862) (xy 67.232092 -345.331542) (xy 67.254742 -345.28194) (xy 67.284221 -345.236066)
			(xy 67.319928 -345.194855) (xy 67.361136 -345.159144) (xy 67.407007 -345.12966) (xy 67.456606 -345.107005)
			(xy 67.508925 -345.091638) (xy 67.562898 -345.083873) (xy 67.590162 -345.083384) (xy 68.453762 -345.083384)
			(xy 68.481038 -345.083753) (xy 68.535036 -345.091512) (xy 68.587379 -345.106877) (xy 68.637003 -345.129535)
			(xy 68.682897 -345.159025) (xy 68.724127 -345.194747) (xy 68.759852 -345.235973) (xy 68.789347 -345.281864)
			(xy 68.81201 -345.331485) (xy 68.82738 -345.383827) (xy 68.835144 -345.437824) (xy 68.835144 -345.492369)
			(xy 70.317847 -345.492369) (xy 70.317847 -345.437831) (xy 70.325609 -345.383849) (xy 70.340975 -345.331521)
			(xy 70.363631 -345.281912) (xy 70.393117 -345.236033) (xy 70.428833 -345.194817) (xy 70.470051 -345.159104)
			(xy 70.515932 -345.129621) (xy 70.565541 -345.106967) (xy 70.617871 -345.091605) (xy 70.671853 -345.083846)
			(xy 70.699122 -345.083384) (xy 71.562722 -345.083384) (xy 71.589994 -345.08378) (xy 71.643981 -345.091545)
			(xy 71.696315 -345.106914) (xy 71.745928 -345.129574) (xy 71.791812 -345.159064) (xy 71.833032 -345.194784)
			(xy 71.868749 -345.236006) (xy 71.898236 -345.281891) (xy 71.920893 -345.331506) (xy 71.936259 -345.38384)
			(xy 71.944022 -345.437828) (xy 71.944022 -345.492365) (xy 73.42687 -345.492365) (xy 73.42687 -345.437835)
			(xy 73.434631 -345.383859) (xy 73.449993 -345.331537) (xy 73.472645 -345.281934) (xy 73.502126 -345.23606)
			(xy 73.537835 -345.194848) (xy 73.579045 -345.159137) (xy 73.624919 -345.129654) (xy 73.674521 -345.106999)
			(xy 73.726842 -345.091634) (xy 73.780817 -345.083872) (xy 73.808082 -345.083384) (xy 74.671682 -345.083384)
			(xy 74.698957 -345.083754) (xy 74.752952 -345.091515) (xy 74.805294 -345.106882) (xy 74.854915 -345.129541)
			(xy 74.900806 -345.159032) (xy 74.942034 -345.194754) (xy 74.977757 -345.235979) (xy 75.00725 -345.281869)
			(xy 75.029912 -345.33149) (xy 75.045281 -345.38383) (xy 75.053044 -345.437825) (xy 75.053044 -345.49237)
			(xy 76.535748 -345.49237) (xy 76.535748 -345.43783) (xy 76.54351 -345.383846) (xy 76.558876 -345.331517)
			(xy 76.581534 -345.281907) (xy 76.611022 -345.236026) (xy 76.64674 -345.19481) (xy 76.68796 -345.159097)
			(xy 76.733844 -345.129614) (xy 76.783456 -345.106962) (xy 76.835787 -345.091601) (xy 76.889772 -345.083845)
			(xy 76.917042 -345.083384) (xy 77.780642 -345.083384) (xy 77.807913 -345.083781) (xy 77.861898 -345.091549)
			(xy 77.914229 -345.10692) (xy 77.96384 -345.129581) (xy 78.009721 -345.159072) (xy 78.050939 -345.194791)
			(xy 78.086654 -345.236013) (xy 78.116139 -345.281897) (xy 78.138795 -345.33151) (xy 78.15416 -345.383843)
			(xy 78.161922 -345.437829) (xy 78.161922 -345.492368) (xy 79.644747 -345.492368) (xy 79.644747 -345.437832)
			(xy 79.652509 -345.383852) (xy 79.667873 -345.331525) (xy 79.690528 -345.281918) (xy 79.720012 -345.23604)
			(xy 79.755726 -345.194824) (xy 79.796941 -345.159111) (xy 79.84282 -345.129627) (xy 79.892427 -345.106972)
			(xy 79.944754 -345.091608) (xy 79.998734 -345.083847) (xy 80.026002 -345.083384) (xy 80.889602 -345.083384)
			(xy 80.916875 -345.083779) (xy 80.970864 -345.091542) (xy 81.0232 -345.106909) (xy 81.072816 -345.129568)
			(xy 81.118702 -345.159057) (xy 81.159924 -345.194777) (xy 81.195644 -345.236) (xy 81.225133 -345.281886)
			(xy 81.247792 -345.331502) (xy 81.263159 -345.383838) (xy 81.270921 -345.437827) (xy 81.270921 -345.492364)
			(xy 82.75377 -345.492364) (xy 82.75377 -345.437836) (xy 82.76153 -345.383862) (xy 82.776892 -345.331542)
			(xy 82.799542 -345.28194) (xy 82.829021 -345.236066) (xy 82.864728 -345.194855) (xy 82.905936 -345.159144)
			(xy 82.951807 -345.12966) (xy 83.001406 -345.107005) (xy 83.053725 -345.091638) (xy 83.107698 -345.083873)
			(xy 83.134962 -345.083384) (xy 83.998562 -345.083384) (xy 84.025838 -345.083753) (xy 84.079836 -345.091512)
			(xy 84.132179 -345.106877) (xy 84.181803 -345.129535) (xy 84.227697 -345.159025) (xy 84.268927 -345.194747)
			(xy 84.304652 -345.235973) (xy 84.334147 -345.281864) (xy 84.35681 -345.331485) (xy 84.37218 -345.383827)
			(xy 84.379944 -345.437824) (xy 84.379944 -345.492369) (xy 85.862647 -345.492369) (xy 85.862647 -345.437831)
			(xy 85.870409 -345.383849) (xy 85.885775 -345.331521) (xy 85.908431 -345.281912) (xy 85.937917 -345.236033)
			(xy 85.973633 -345.194817) (xy 86.014851 -345.159104) (xy 86.060732 -345.129621) (xy 86.110341 -345.106967)
			(xy 86.162671 -345.091605) (xy 86.216653 -345.083846) (xy 86.243922 -345.083384) (xy 87.107522 -345.083384)
			(xy 87.134794 -345.08378) (xy 87.188781 -345.091545) (xy 87.241115 -345.106914) (xy 87.290728 -345.129574)
			(xy 87.336612 -345.159064) (xy 87.377832 -345.194784) (xy 87.413549 -345.236006) (xy 87.443036 -345.281891)
			(xy 87.465693 -345.331506) (xy 87.481059 -345.38384) (xy 87.488822 -345.437828) (xy 87.488822 -345.492365)
			(xy 88.97167 -345.492365) (xy 88.97167 -345.437835) (xy 88.979431 -345.383859) (xy 88.994793 -345.331537)
			(xy 89.017445 -345.281934) (xy 89.046926 -345.23606) (xy 89.082635 -345.194848) (xy 89.123845 -345.159137)
			(xy 89.169719 -345.129654) (xy 89.219321 -345.106999) (xy 89.271642 -345.091634) (xy 89.325617 -345.083872)
			(xy 89.352882 -345.083384) (xy 90.216482 -345.083384) (xy 90.243757 -345.083754) (xy 90.297752 -345.091515)
			(xy 90.350094 -345.106882) (xy 90.399715 -345.129541) (xy 90.445606 -345.159032) (xy 90.486834 -345.194754)
			(xy 90.522557 -345.235979) (xy 90.55205 -345.281869) (xy 90.574712 -345.33149) (xy 90.590081 -345.38383)
			(xy 90.597844 -345.437825) (xy 90.597844 -345.49237) (xy 92.080548 -345.49237) (xy 92.080548 -345.43783)
			(xy 92.08831 -345.383846) (xy 92.103676 -345.331517) (xy 92.126334 -345.281907) (xy 92.155822 -345.236026)
			(xy 92.19154 -345.19481) (xy 92.23276 -345.159097) (xy 92.278644 -345.129614) (xy 92.328256 -345.106962)
			(xy 92.380587 -345.091601) (xy 92.434572 -345.083845) (xy 92.461842 -345.083384) (xy 93.325442 -345.083384)
			(xy 93.352713 -345.083781) (xy 93.406698 -345.091549) (xy 93.459029 -345.10692) (xy 93.50864 -345.129581)
			(xy 93.554521 -345.159072) (xy 93.595739 -345.194791) (xy 93.631454 -345.236013) (xy 93.660939 -345.281897)
			(xy 93.683595 -345.33151) (xy 93.69896 -345.383843) (xy 93.706722 -345.437829) (xy 93.706722 -345.492368)
			(xy 111.480847 -345.492368) (xy 111.480847 -345.437832) (xy 111.488609 -345.383851) (xy 111.503974 -345.331524)
			(xy 111.526629 -345.281916) (xy 111.556114 -345.236038) (xy 111.591828 -345.194822) (xy 111.633044 -345.159109)
			(xy 111.678923 -345.129625) (xy 111.728531 -345.106971) (xy 111.780859 -345.091607) (xy 111.83484 -345.083847)
			(xy 111.862108 -345.083384) (xy 112.725708 -345.083384) (xy 112.75298 -345.083779) (xy 112.80697 -345.091543)
			(xy 112.859304 -345.106911) (xy 112.90892 -345.12957) (xy 112.954805 -345.15906) (xy 112.996027 -345.194779)
			(xy 113.031745 -345.236001) (xy 113.061234 -345.281888) (xy 113.083892 -345.331503) (xy 113.099259 -345.383838)
			(xy 113.107021 -345.437828) (xy 113.107021 -345.492365) (xy 114.58987 -345.492365) (xy 114.58987 -345.437835)
			(xy 114.59763 -345.383861) (xy 114.612992 -345.33154) (xy 114.635643 -345.281938) (xy 114.665122 -345.236064)
			(xy 114.70083 -345.194853) (xy 114.742039 -345.159142) (xy 114.78791 -345.129658) (xy 114.83751 -345.107003)
			(xy 114.88983 -345.091637) (xy 114.943803 -345.083872) (xy 114.971068 -345.083384) (xy 115.834668 -345.083384)
			(xy 115.861944 -345.083753) (xy 115.915941 -345.091513) (xy 115.968283 -345.106878) (xy 116.017907 -345.129537)
			(xy 116.0638 -345.159027) (xy 116.105029 -345.194749) (xy 116.140754 -345.235975) (xy 116.170248 -345.281865)
			(xy 116.192911 -345.331487) (xy 116.20828 -345.383828) (xy 116.216044 -345.437824) (xy 116.216044 -345.492369)
			(xy 117.698747 -345.492369) (xy 117.698747 -345.437831) (xy 117.706509 -345.383848) (xy 117.721875 -345.33152)
			(xy 117.744532 -345.281911) (xy 117.774019 -345.236031) (xy 117.809735 -345.194815) (xy 117.850953 -345.159102)
			(xy 117.896835 -345.129619) (xy 117.946446 -345.106965) (xy 117.998776 -345.091603) (xy 118.052759 -345.083845)
			(xy 118.080028 -345.083384) (xy 118.943628 -345.083384) (xy 118.970899 -345.08378) (xy 119.024886 -345.091546)
			(xy 119.077219 -345.106916) (xy 119.126832 -345.129576) (xy 119.172714 -345.159067) (xy 119.213934 -345.194786)
			(xy 119.24965 -345.236008) (xy 119.279137 -345.281893) (xy 119.301794 -345.331507) (xy 119.31716 -345.383841)
			(xy 119.324922 -345.437829) (xy 119.324922 -345.492366) (xy 120.80777 -345.492366) (xy 120.80777 -345.437834)
			(xy 120.815531 -345.383858) (xy 120.830894 -345.331536) (xy 120.853546 -345.281933) (xy 120.883027 -345.236058)
			(xy 120.918737 -345.194846) (xy 120.959948 -345.159135) (xy 121.005822 -345.129652) (xy 121.055425 -345.106998)
			(xy 121.107747 -345.091633) (xy 121.161722 -345.083871) (xy 121.188988 -345.083384) (xy 122.052588 -345.083384)
			(xy 122.079863 -345.083755) (xy 122.133857 -345.091516) (xy 122.186198 -345.106884) (xy 122.235819 -345.129543)
			(xy 122.281709 -345.159034) (xy 122.322936 -345.194756) (xy 122.358659 -345.235981) (xy 122.388151 -345.281871)
			(xy 122.410812 -345.331491) (xy 122.426181 -345.383831) (xy 122.433944 -345.437825) (xy 122.433944 -345.49237)
			(xy 123.916648 -345.49237) (xy 123.916648 -345.43783) (xy 123.92441 -345.383846) (xy 123.939777 -345.331515)
			(xy 123.962435 -345.281905) (xy 123.991924 -345.236024) (xy 124.027642 -345.194808) (xy 124.068863 -345.159095)
			(xy 124.114747 -345.129612) (xy 124.16436 -345.10696) (xy 124.216692 -345.0916) (xy 124.270678 -345.083844)
			(xy 124.297948 -345.083384) (xy 125.161548 -345.083384) (xy 125.188818 -345.083782) (xy 125.242803 -345.09155)
			(xy 125.295133 -345.106921) (xy 125.344744 -345.129583) (xy 125.390624 -345.159074) (xy 125.431841 -345.194793)
			(xy 125.467555 -345.236015) (xy 125.49704 -345.281899) (xy 125.519695 -345.331512) (xy 125.53506 -345.383844)
			(xy 125.542822 -345.43783) (xy 125.542822 -345.492368) (xy 127.025647 -345.492368) (xy 127.025647 -345.437832)
			(xy 127.033409 -345.383851) (xy 127.048774 -345.331524) (xy 127.071429 -345.281916) (xy 127.100914 -345.236038)
			(xy 127.136628 -345.194822) (xy 127.177844 -345.159109) (xy 127.223723 -345.129625) (xy 127.273331 -345.106971)
			(xy 127.325659 -345.091607) (xy 127.37964 -345.083847) (xy 127.406908 -345.083384) (xy 128.270508 -345.083384)
			(xy 128.29778 -345.083779) (xy 128.35177 -345.091543) (xy 128.404104 -345.106911) (xy 128.45372 -345.12957)
			(xy 128.499605 -345.15906) (xy 128.540827 -345.194779) (xy 128.576545 -345.236001) (xy 128.606034 -345.281888)
			(xy 128.628692 -345.331503) (xy 128.644059 -345.383838) (xy 128.651821 -345.437828) (xy 128.651821 -345.492365)
			(xy 130.13467 -345.492365) (xy 130.13467 -345.437835) (xy 130.14243 -345.383861) (xy 130.157792 -345.33154)
			(xy 130.180443 -345.281938) (xy 130.209922 -345.236064) (xy 130.24563 -345.194853) (xy 130.286839 -345.159142)
			(xy 130.33271 -345.129658) (xy 130.38231 -345.107003) (xy 130.43463 -345.091637) (xy 130.488603 -345.083872)
			(xy 130.515868 -345.083384) (xy 131.379468 -345.083384) (xy 131.406744 -345.083753) (xy 131.460741 -345.091513)
			(xy 131.513083 -345.106878) (xy 131.562707 -345.129537) (xy 131.6086 -345.159027) (xy 131.649829 -345.194749)
			(xy 131.685554 -345.235975) (xy 131.715048 -345.281865) (xy 131.737711 -345.331487) (xy 131.75308 -345.383828)
			(xy 131.760844 -345.437824) (xy 131.760844 -345.492369) (xy 133.243547 -345.492369) (xy 133.243547 -345.437831)
			(xy 133.251309 -345.383848) (xy 133.266675 -345.33152) (xy 133.289332 -345.281911) (xy 133.318819 -345.236031)
			(xy 133.354535 -345.194815) (xy 133.395753 -345.159102) (xy 133.441635 -345.129619) (xy 133.491246 -345.106965)
			(xy 133.543576 -345.091603) (xy 133.597559 -345.083845) (xy 133.624828 -345.083384) (xy 134.488428 -345.083384)
			(xy 134.515699 -345.08378) (xy 134.569686 -345.091546) (xy 134.622019 -345.106916) (xy 134.671632 -345.129576)
			(xy 134.717514 -345.159067) (xy 134.758734 -345.194786) (xy 134.79445 -345.236008) (xy 134.823937 -345.281893)
			(xy 134.846594 -345.331507) (xy 134.86196 -345.383841) (xy 134.869722 -345.437829) (xy 134.869722 -345.492366)
			(xy 136.35257 -345.492366) (xy 136.35257 -345.437834) (xy 136.360331 -345.383858) (xy 136.375694 -345.331536)
			(xy 136.398346 -345.281933) (xy 136.427827 -345.236058) (xy 136.463537 -345.194846) (xy 136.504748 -345.159135)
			(xy 136.550622 -345.129652) (xy 136.600225 -345.106998) (xy 136.652547 -345.091633) (xy 136.706522 -345.083871)
			(xy 136.733788 -345.083384) (xy 137.597388 -345.083384) (xy 137.624663 -345.083755) (xy 137.678657 -345.091516)
			(xy 137.730998 -345.106884) (xy 137.780619 -345.129543) (xy 137.826509 -345.159034) (xy 137.867736 -345.194756)
			(xy 137.903459 -345.235981) (xy 137.932951 -345.281871) (xy 137.955612 -345.331491) (xy 137.970981 -345.383831)
			(xy 137.978744 -345.437825) (xy 137.978744 -345.49237) (xy 139.461448 -345.49237) (xy 139.461448 -345.43783)
			(xy 139.46921 -345.383846) (xy 139.484577 -345.331515) (xy 139.507235 -345.281905) (xy 139.536724 -345.236024)
			(xy 139.572442 -345.194808) (xy 139.613663 -345.159095) (xy 139.659547 -345.129612) (xy 139.70916 -345.10696)
			(xy 139.761492 -345.0916) (xy 139.815478 -345.083844) (xy 139.842748 -345.083384) (xy 140.706348 -345.083384)
			(xy 140.733618 -345.083782) (xy 140.787603 -345.09155) (xy 140.839933 -345.106921) (xy 140.889544 -345.129583)
			(xy 140.935424 -345.159074) (xy 140.976641 -345.194793) (xy 141.012355 -345.236015) (xy 141.04184 -345.281899)
			(xy 141.064495 -345.331512) (xy 141.07986 -345.383844) (xy 141.087622 -345.43783) (xy 141.087622 -345.492368)
			(xy 142.570447 -345.492368) (xy 142.570447 -345.437832) (xy 142.578209 -345.383851) (xy 142.593574 -345.331524)
			(xy 142.616229 -345.281916) (xy 142.645714 -345.236038) (xy 142.681428 -345.194822) (xy 142.722644 -345.159109)
			(xy 142.768523 -345.129625) (xy 142.818131 -345.106971) (xy 142.870459 -345.091607) (xy 142.92444 -345.083847)
			(xy 142.951708 -345.083384) (xy 143.815308 -345.083384) (xy 143.84258 -345.083779) (xy 143.89657 -345.091543)
			(xy 143.948904 -345.106911) (xy 143.99852 -345.12957) (xy 144.044405 -345.15906) (xy 144.085627 -345.194779)
			(xy 144.121345 -345.236001) (xy 144.150834 -345.281888) (xy 144.173492 -345.331503) (xy 144.188859 -345.383838)
			(xy 144.196621 -345.437828) (xy 144.196621 -345.492365) (xy 164.91387 -345.492365) (xy 164.91387 -345.437835)
			(xy 164.92163 -345.383861) (xy 164.936992 -345.33154) (xy 164.959644 -345.281937) (xy 164.989123 -345.236063)
			(xy 165.024831 -345.194851) (xy 165.066041 -345.15914) (xy 165.111913 -345.129657) (xy 165.161513 -345.107002)
			(xy 165.213833 -345.091636) (xy 165.267807 -345.083872) (xy 165.295072 -345.083384) (xy 166.158672 -345.083384)
			(xy 166.185948 -345.083754) (xy 166.239944 -345.091514) (xy 166.292286 -345.106879) (xy 166.341909 -345.129538)
			(xy 166.387802 -345.159028) (xy 166.42903 -345.19475) (xy 166.464755 -345.235976) (xy 166.494249 -345.281866)
			(xy 166.516911 -345.331487) (xy 166.532281 -345.383829) (xy 166.540044 -345.437824) (xy 166.540044 -345.492369)
			(xy 168.022747 -345.492369) (xy 168.022747 -345.437831) (xy 168.03051 -345.383848) (xy 168.045876 -345.331519)
			(xy 168.068533 -345.281909) (xy 168.09802 -345.23603) (xy 168.133736 -345.194814) (xy 168.174955 -345.159101)
			(xy 168.220838 -345.129617) (xy 168.270449 -345.106964) (xy 168.322779 -345.091603) (xy 168.376763 -345.083845)
			(xy 168.404032 -345.083384) (xy 169.267632 -345.083384) (xy 169.294903 -345.083781) (xy 169.34889 -345.091547)
			(xy 169.401222 -345.106917) (xy 169.450834 -345.129578) (xy 169.496716 -345.159068) (xy 169.537935 -345.194788)
			(xy 169.573651 -345.236009) (xy 169.603138 -345.281894) (xy 169.625794 -345.331508) (xy 169.64116 -345.383842)
			(xy 169.648922 -345.437829) (xy 169.648922 -345.492366) (xy 171.13177 -345.492366) (xy 171.13177 -345.437834)
			(xy 171.139531 -345.383858) (xy 171.154894 -345.331535) (xy 171.177547 -345.281932) (xy 171.207028 -345.236057)
			(xy 171.242738 -345.194844) (xy 171.28395 -345.159133) (xy 171.329825 -345.129651) (xy 171.379428 -345.106997)
			(xy 171.43175 -345.091633) (xy 171.485726 -345.083871) (xy 171.512992 -345.083384) (xy 172.376592 -345.083384)
			(xy 172.403867 -345.083755) (xy 172.457861 -345.091517) (xy 172.510201 -345.106885) (xy 172.559821 -345.129544)
			(xy 172.605711 -345.159035) (xy 172.646937 -345.194757) (xy 172.68266 -345.235982) (xy 172.712152 -345.281872)
			(xy 172.734813 -345.331492) (xy 172.750181 -345.383831) (xy 172.757944 -345.437825) (xy 172.757944 -345.492364)
			(xy 174.24077 -345.492364) (xy 174.24077 -345.437836) (xy 174.24853 -345.383863) (xy 174.263891 -345.331544)
			(xy 174.286541 -345.281943) (xy 174.316019 -345.23607) (xy 174.351724 -345.194858) (xy 174.392931 -345.159147)
			(xy 174.438801 -345.129664) (xy 174.488399 -345.107008) (xy 174.540716 -345.09164) (xy 174.594688 -345.083874)
			(xy 174.621952 -345.083384) (xy 175.485552 -345.083384) (xy 175.512829 -345.083752) (xy 175.566827 -345.09151)
			(xy 175.619172 -345.106874) (xy 175.668797 -345.129531) (xy 175.714692 -345.159021) (xy 175.755923 -345.194743)
			(xy 175.79165 -345.235969) (xy 175.821146 -345.281861) (xy 175.843809 -345.331483) (xy 175.85918 -345.383826)
			(xy 175.866944 -345.437824) (xy 175.866944 -345.492368) (xy 177.349647 -345.492368) (xy 177.349647 -345.437832)
			(xy 177.357409 -345.38385) (xy 177.372774 -345.331523) (xy 177.39543 -345.281915) (xy 177.424915 -345.236036)
			(xy 177.460629 -345.194821) (xy 177.501846 -345.159108) (xy 177.547726 -345.129624) (xy 177.597334 -345.10697)
			(xy 177.649662 -345.091606) (xy 177.703644 -345.083847) (xy 177.730912 -345.083384) (xy 178.594512 -345.083384)
			(xy 178.621784 -345.083779) (xy 178.675773 -345.091543) (xy 178.728107 -345.106912) (xy 178.777722 -345.129571)
			(xy 178.823607 -345.159061) (xy 178.864828 -345.194781) (xy 178.900546 -345.236003) (xy 178.930035 -345.281889)
			(xy 178.952693 -345.331504) (xy 178.968059 -345.383839) (xy 178.975821 -345.437828) (xy 178.975821 -345.492365)
			(xy 180.45867 -345.492365) (xy 180.45867 -345.437835) (xy 180.46643 -345.383861) (xy 180.481792 -345.33154)
			(xy 180.504444 -345.281937) (xy 180.533923 -345.236063) (xy 180.569631 -345.194851) (xy 180.610841 -345.15914)
			(xy 180.656713 -345.129657) (xy 180.706313 -345.107002) (xy 180.758633 -345.091636) (xy 180.812607 -345.083872)
			(xy 180.839872 -345.083384) (xy 181.703472 -345.083384) (xy 181.730748 -345.083754) (xy 181.784744 -345.091514)
			(xy 181.837086 -345.106879) (xy 181.886709 -345.129538) (xy 181.932602 -345.159028) (xy 181.97383 -345.19475)
			(xy 182.009555 -345.235976) (xy 182.039049 -345.281866) (xy 182.061711 -345.331487) (xy 182.077081 -345.383829)
			(xy 182.084844 -345.437824) (xy 182.084844 -345.492369) (xy 183.567547 -345.492369) (xy 183.567547 -345.437831)
			(xy 183.57531 -345.383848) (xy 183.590676 -345.331519) (xy 183.613333 -345.281909) (xy 183.64282 -345.23603)
			(xy 183.678536 -345.194814) (xy 183.719755 -345.159101) (xy 183.765638 -345.129617) (xy 183.815249 -345.106964)
			(xy 183.867579 -345.091603) (xy 183.921563 -345.083845) (xy 183.948832 -345.083384) (xy 184.812432 -345.083384)
			(xy 184.839703 -345.083781) (xy 184.89369 -345.091547) (xy 184.946022 -345.106917) (xy 184.995634 -345.129578)
			(xy 185.041516 -345.159068) (xy 185.082735 -345.194788) (xy 185.118451 -345.236009) (xy 185.147938 -345.281894)
			(xy 185.170594 -345.331508) (xy 185.18596 -345.383842) (xy 185.193722 -345.437829) (xy 185.193722 -345.492366)
			(xy 186.67657 -345.492366) (xy 186.67657 -345.437834) (xy 186.684331 -345.383858) (xy 186.699694 -345.331535)
			(xy 186.722347 -345.281932) (xy 186.751828 -345.236057) (xy 186.787538 -345.194844) (xy 186.82875 -345.159133)
			(xy 186.874625 -345.129651) (xy 186.924228 -345.106997) (xy 186.97655 -345.091633) (xy 187.030526 -345.083871)
			(xy 187.057792 -345.083384) (xy 187.921392 -345.083384) (xy 187.948667 -345.083755) (xy 188.002661 -345.091517)
			(xy 188.055001 -345.106885) (xy 188.104621 -345.129544) (xy 188.150511 -345.159035) (xy 188.191737 -345.194757)
			(xy 188.22746 -345.235982) (xy 188.256952 -345.281872) (xy 188.279613 -345.331492) (xy 188.294981 -345.383831)
			(xy 188.302744 -345.437825) (xy 188.302744 -345.492364) (xy 189.78557 -345.492364) (xy 189.78557 -345.437836)
			(xy 189.79333 -345.383863) (xy 189.808691 -345.331544) (xy 189.831341 -345.281943) (xy 189.860819 -345.23607)
			(xy 189.896524 -345.194858) (xy 189.937731 -345.159147) (xy 189.983601 -345.129664) (xy 190.033199 -345.107008)
			(xy 190.085516 -345.09164) (xy 190.139488 -345.083874) (xy 190.166752 -345.083384) (xy 191.030352 -345.083384)
			(xy 191.057629 -345.083752) (xy 191.111627 -345.09151) (xy 191.163972 -345.106874) (xy 191.213597 -345.129531)
			(xy 191.259492 -345.159021) (xy 191.300723 -345.194743) (xy 191.33645 -345.235969) (xy 191.365946 -345.281861)
			(xy 191.388609 -345.331483) (xy 191.40398 -345.383826) (xy 191.411744 -345.437824) (xy 191.411744 -345.492368)
			(xy 192.894447 -345.492368) (xy 192.894447 -345.437832) (xy 192.902209 -345.38385) (xy 192.917574 -345.331523)
			(xy 192.94023 -345.281915) (xy 192.969715 -345.236036) (xy 193.005429 -345.194821) (xy 193.046646 -345.159108)
			(xy 193.092526 -345.129624) (xy 193.142134 -345.10697) (xy 193.194462 -345.091606) (xy 193.248444 -345.083847)
			(xy 193.275712 -345.083384) (xy 194.139312 -345.083384) (xy 194.166584 -345.083779) (xy 194.220573 -345.091543)
			(xy 194.272907 -345.106912) (xy 194.322522 -345.129571) (xy 194.368407 -345.159061) (xy 194.409628 -345.194781)
			(xy 194.445346 -345.236003) (xy 194.474835 -345.281889) (xy 194.497493 -345.331504) (xy 194.512859 -345.383839)
			(xy 194.520621 -345.437828) (xy 194.520621 -345.492365) (xy 196.00347 -345.492365) (xy 196.00347 -345.437835)
			(xy 196.01123 -345.383861) (xy 196.026592 -345.33154) (xy 196.049244 -345.281937) (xy 196.078723 -345.236063)
			(xy 196.114431 -345.194851) (xy 196.155641 -345.15914) (xy 196.201513 -345.129657) (xy 196.251113 -345.107002)
			(xy 196.303433 -345.091636) (xy 196.357407 -345.083872) (xy 196.384672 -345.083384) (xy 197.248272 -345.083384)
			(xy 197.275548 -345.083754) (xy 197.329544 -345.091514) (xy 197.381886 -345.106879) (xy 197.431509 -345.129538)
			(xy 197.477402 -345.159028) (xy 197.51863 -345.19475) (xy 197.554355 -345.235976) (xy 197.583849 -345.281866)
			(xy 197.606511 -345.331487) (xy 197.621881 -345.383829) (xy 197.629644 -345.437824) (xy 197.629644 -345.492368)
			(xy 267.515847 -345.492368) (xy 267.515847 -345.437832) (xy 267.523609 -345.383852) (xy 267.538973 -345.331525)
			(xy 267.561628 -345.281918) (xy 267.591112 -345.23604) (xy 267.626826 -345.194824) (xy 267.668041 -345.159111)
			(xy 267.71392 -345.129627) (xy 267.763527 -345.106972) (xy 267.815854 -345.091608) (xy 267.869834 -345.083847)
			(xy 267.897102 -345.083384) (xy 268.760702 -345.083384) (xy 268.787975 -345.083779) (xy 268.841964 -345.091542)
			(xy 268.8943 -345.106909) (xy 268.943916 -345.129568) (xy 268.989802 -345.159057) (xy 269.031024 -345.194777)
			(xy 269.066744 -345.236) (xy 269.096233 -345.281886) (xy 269.118892 -345.331502) (xy 269.134259 -345.383838)
			(xy 269.142021 -345.437827) (xy 269.142021 -345.492364) (xy 270.62487 -345.492364) (xy 270.62487 -345.437836)
			(xy 270.63263 -345.383862) (xy 270.647992 -345.331542) (xy 270.670642 -345.28194) (xy 270.700121 -345.236066)
			(xy 270.735828 -345.194855) (xy 270.777036 -345.159144) (xy 270.822907 -345.12966) (xy 270.872506 -345.107005)
			(xy 270.924825 -345.091638) (xy 270.978798 -345.083873) (xy 271.006062 -345.083384) (xy 271.869662 -345.083384)
			(xy 271.896938 -345.083753) (xy 271.950936 -345.091512) (xy 272.003279 -345.106877) (xy 272.052903 -345.129535)
			(xy 272.098797 -345.159025) (xy 272.140027 -345.194747) (xy 272.175752 -345.235973) (xy 272.205247 -345.281864)
			(xy 272.22791 -345.331485) (xy 272.24328 -345.383827) (xy 272.251044 -345.437824) (xy 272.251044 -345.492369)
			(xy 273.733747 -345.492369) (xy 273.733747 -345.437831) (xy 273.741509 -345.383849) (xy 273.756875 -345.331521)
			(xy 273.779531 -345.281912) (xy 273.809017 -345.236033) (xy 273.844733 -345.194817) (xy 273.885951 -345.159104)
			(xy 273.931832 -345.129621) (xy 273.981441 -345.106967) (xy 274.033771 -345.091605) (xy 274.087753 -345.083846)
			(xy 274.115022 -345.083384) (xy 274.978622 -345.083384) (xy 275.005894 -345.08378) (xy 275.059881 -345.091545)
			(xy 275.112215 -345.106914) (xy 275.161828 -345.129574) (xy 275.207712 -345.159064) (xy 275.248932 -345.194784)
			(xy 275.284649 -345.236006) (xy 275.314136 -345.281891) (xy 275.336793 -345.331506) (xy 275.352159 -345.38384)
			(xy 275.359922 -345.437828) (xy 275.359922 -345.492365) (xy 276.84277 -345.492365) (xy 276.84277 -345.437835)
			(xy 276.850531 -345.383859) (xy 276.865893 -345.331537) (xy 276.888545 -345.281934) (xy 276.918026 -345.23606)
			(xy 276.953735 -345.194848) (xy 276.994945 -345.159137) (xy 277.040819 -345.129654) (xy 277.090421 -345.106999)
			(xy 277.142742 -345.091634) (xy 277.196717 -345.083872) (xy 277.223982 -345.083384) (xy 278.087582 -345.083384)
			(xy 278.114857 -345.083754) (xy 278.168852 -345.091515) (xy 278.221194 -345.106882) (xy 278.270815 -345.129541)
			(xy 278.316706 -345.159032) (xy 278.357934 -345.194754) (xy 278.393657 -345.235979) (xy 278.42315 -345.281869)
			(xy 278.445812 -345.33149) (xy 278.461181 -345.38383) (xy 278.468944 -345.437825) (xy 278.468944 -345.49237)
			(xy 279.951648 -345.49237) (xy 279.951648 -345.43783) (xy 279.95941 -345.383846) (xy 279.974776 -345.331517)
			(xy 279.997434 -345.281907) (xy 280.026922 -345.236026) (xy 280.06264 -345.19481) (xy 280.10386 -345.159097)
			(xy 280.149744 -345.129614) (xy 280.199356 -345.106962) (xy 280.251687 -345.091601) (xy 280.305672 -345.083845)
			(xy 280.332942 -345.083384) (xy 281.196542 -345.083384) (xy 281.223813 -345.083781) (xy 281.277798 -345.091549)
			(xy 281.330129 -345.10692) (xy 281.37974 -345.129581) (xy 281.425621 -345.159072) (xy 281.466839 -345.194791)
			(xy 281.502554 -345.236013) (xy 281.532039 -345.281897) (xy 281.554695 -345.33151) (xy 281.57006 -345.383843)
			(xy 281.577822 -345.437829) (xy 281.577822 -345.492368) (xy 283.060647 -345.492368) (xy 283.060647 -345.437832)
			(xy 283.068409 -345.383852) (xy 283.083773 -345.331525) (xy 283.106428 -345.281918) (xy 283.135912 -345.23604)
			(xy 283.171626 -345.194824) (xy 283.212841 -345.159111) (xy 283.25872 -345.129627) (xy 283.308327 -345.106972)
			(xy 283.360654 -345.091608) (xy 283.414634 -345.083847) (xy 283.441902 -345.083384) (xy 284.305502 -345.083384)
			(xy 284.332775 -345.083779) (xy 284.386764 -345.091542) (xy 284.4391 -345.106909) (xy 284.488716 -345.129568)
			(xy 284.534602 -345.159057) (xy 284.575824 -345.194777) (xy 284.611544 -345.236) (xy 284.641033 -345.281886)
			(xy 284.663692 -345.331502) (xy 284.679059 -345.383838) (xy 284.686821 -345.437827) (xy 284.686821 -345.492364)
			(xy 286.16967 -345.492364) (xy 286.16967 -345.437836) (xy 286.17743 -345.383862) (xy 286.192792 -345.331542)
			(xy 286.215442 -345.28194) (xy 286.244921 -345.236066) (xy 286.280628 -345.194855) (xy 286.321836 -345.159144)
			(xy 286.367707 -345.12966) (xy 286.417306 -345.107005) (xy 286.469625 -345.091638) (xy 286.523598 -345.083873)
			(xy 286.550862 -345.083384) (xy 287.414462 -345.083384) (xy 287.441738 -345.083753) (xy 287.495736 -345.091512)
			(xy 287.548079 -345.106877) (xy 287.597703 -345.129535) (xy 287.643597 -345.159025) (xy 287.684827 -345.194747)
			(xy 287.720552 -345.235973) (xy 287.750047 -345.281864) (xy 287.77271 -345.331485) (xy 287.78808 -345.383827)
			(xy 287.795844 -345.437824) (xy 287.795844 -345.492369) (xy 289.278547 -345.492369) (xy 289.278547 -345.437831)
			(xy 289.286309 -345.383849) (xy 289.301675 -345.331521) (xy 289.324331 -345.281912) (xy 289.353817 -345.236033)
			(xy 289.389533 -345.194817) (xy 289.430751 -345.159104) (xy 289.476632 -345.129621) (xy 289.526241 -345.106967)
			(xy 289.578571 -345.091605) (xy 289.632553 -345.083846) (xy 289.659822 -345.083384) (xy 290.523422 -345.083384)
			(xy 290.550694 -345.08378) (xy 290.604681 -345.091545) (xy 290.657015 -345.106914) (xy 290.706628 -345.129574)
			(xy 290.752512 -345.159064) (xy 290.793732 -345.194784) (xy 290.829449 -345.236006) (xy 290.858936 -345.281891)
			(xy 290.881593 -345.331506) (xy 290.896959 -345.38384) (xy 290.904722 -345.437828) (xy 290.904722 -345.492365)
			(xy 292.38757 -345.492365) (xy 292.38757 -345.437835) (xy 292.395331 -345.383859) (xy 292.410693 -345.331537)
			(xy 292.433345 -345.281934) (xy 292.462826 -345.23606) (xy 292.498535 -345.194848) (xy 292.539745 -345.159137)
			(xy 292.585619 -345.129654) (xy 292.635221 -345.106999) (xy 292.687542 -345.091634) (xy 292.741517 -345.083872)
			(xy 292.768782 -345.083384) (xy 293.632382 -345.083384) (xy 293.659657 -345.083754) (xy 293.713652 -345.091515)
			(xy 293.765994 -345.106882) (xy 293.815615 -345.129541) (xy 293.861506 -345.159032) (xy 293.902734 -345.194754)
			(xy 293.938457 -345.235979) (xy 293.96795 -345.281869) (xy 293.990612 -345.33149) (xy 294.005981 -345.38383)
			(xy 294.013744 -345.437825) (xy 294.013744 -345.49237) (xy 295.496448 -345.49237) (xy 295.496448 -345.43783)
			(xy 295.50421 -345.383846) (xy 295.519576 -345.331517) (xy 295.542234 -345.281907) (xy 295.571722 -345.236026)
			(xy 295.60744 -345.19481) (xy 295.64866 -345.159097) (xy 295.694544 -345.129614) (xy 295.744156 -345.106962)
			(xy 295.796487 -345.091601) (xy 295.850472 -345.083845) (xy 295.877742 -345.083384) (xy 296.741342 -345.083384)
			(xy 296.768613 -345.083781) (xy 296.822598 -345.091549) (xy 296.874929 -345.10692) (xy 296.92454 -345.129581)
			(xy 296.970421 -345.159072) (xy 297.011639 -345.194791) (xy 297.047354 -345.236013) (xy 297.076839 -345.281897)
			(xy 297.099495 -345.33151) (xy 297.11486 -345.383843) (xy 297.122622 -345.437829) (xy 297.122622 -345.492368)
			(xy 298.605447 -345.492368) (xy 298.605447 -345.437832) (xy 298.613209 -345.383852) (xy 298.628573 -345.331525)
			(xy 298.651228 -345.281918) (xy 298.680712 -345.23604) (xy 298.716426 -345.194824) (xy 298.757641 -345.159111)
			(xy 298.80352 -345.129627) (xy 298.853127 -345.106972) (xy 298.905454 -345.091608) (xy 298.959434 -345.083847)
			(xy 298.986702 -345.083384) (xy 299.850302 -345.083384) (xy 299.877575 -345.083779) (xy 299.931564 -345.091542)
			(xy 299.9839 -345.106909) (xy 300.033516 -345.129568) (xy 300.079402 -345.159057) (xy 300.120624 -345.194777)
			(xy 300.156344 -345.236) (xy 300.185833 -345.281886) (xy 300.208492 -345.331502) (xy 300.223859 -345.383838)
			(xy 300.231621 -345.437827) (xy 300.231621 -345.492368) (xy 312.121547 -345.492368) (xy 312.121547 -345.437832)
			(xy 312.129309 -345.383851) (xy 312.144673 -345.331525) (xy 312.167328 -345.281917) (xy 312.196813 -345.236039)
			(xy 312.232526 -345.194824) (xy 312.273742 -345.159111) (xy 312.319621 -345.129627) (xy 312.369228 -345.106972)
			(xy 312.421555 -345.091608) (xy 312.475536 -345.083847) (xy 312.502804 -345.083384) (xy 313.366404 -345.083384)
			(xy 313.393676 -345.083779) (xy 313.447666 -345.091542) (xy 313.500001 -345.106909) (xy 313.549617 -345.129569)
			(xy 313.595503 -345.159058) (xy 313.636725 -345.194778) (xy 313.672444 -345.236) (xy 313.701933 -345.281886)
			(xy 313.724592 -345.331502) (xy 313.739959 -345.383838) (xy 313.747721 -345.437828) (xy 313.747721 -345.492364)
			(xy 315.23057 -345.492364) (xy 315.23057 -345.437836) (xy 315.23833 -345.383862) (xy 315.253692 -345.331541)
			(xy 315.276343 -345.281939) (xy 315.305821 -345.236066) (xy 315.341529 -345.194854) (xy 315.382737 -345.159143)
			(xy 315.428608 -345.12966) (xy 315.478207 -345.107004) (xy 315.530526 -345.091638) (xy 315.5845 -345.083873)
			(xy 315.611764 -345.083384) (xy 316.475364 -345.083384) (xy 316.50264 -345.083753) (xy 316.556637 -345.091512)
			(xy 316.608981 -345.106877) (xy 316.658604 -345.129535) (xy 316.704498 -345.159026) (xy 316.745727 -345.194747)
			(xy 316.781453 -345.235973) (xy 316.810947 -345.281864) (xy 316.83361 -345.331486) (xy 316.84898 -345.383828)
			(xy 316.856744 -345.437824) (xy 316.856744 -345.492369) (xy 318.339447 -345.492369) (xy 318.339447 -345.437831)
			(xy 318.347209 -345.383849) (xy 318.362575 -345.33152) (xy 318.385231 -345.281912) (xy 318.414718 -345.236032)
			(xy 318.450434 -345.194817) (xy 318.491652 -345.159103) (xy 318.537533 -345.12962) (xy 318.587143 -345.106966)
			(xy 318.639472 -345.091604) (xy 318.693455 -345.083846) (xy 318.720724 -345.083384) (xy 319.584324 -345.083384)
			(xy 319.611596 -345.08378) (xy 319.665583 -345.091546) (xy 319.717916 -345.106915) (xy 319.767529 -345.129575)
			(xy 319.813413 -345.159065) (xy 319.854632 -345.194785) (xy 319.890349 -345.236007) (xy 319.919836 -345.281892)
			(xy 319.942494 -345.331507) (xy 319.95786 -345.38384) (xy 319.965622 -345.437828) (xy 319.965622 -345.492365)
			(xy 321.44847 -345.492365) (xy 321.44847 -345.437835) (xy 321.456231 -345.383859) (xy 321.471593 -345.331537)
			(xy 321.494246 -345.281934) (xy 321.523726 -345.236059) (xy 321.559436 -345.194847) (xy 321.600646 -345.159136)
			(xy 321.64652 -345.129653) (xy 321.696122 -345.106999) (xy 321.748443 -345.091634) (xy 321.802419 -345.083871)
			(xy 321.829684 -345.083384) (xy 322.693284 -345.083384) (xy 322.720559 -345.083755) (xy 322.774554 -345.091516)
			(xy 322.826895 -345.106882) (xy 322.876516 -345.129542) (xy 322.922407 -345.159033) (xy 322.963634 -345.194754)
			(xy 322.999358 -345.23598) (xy 323.02885 -345.28187) (xy 323.051512 -345.33149) (xy 323.066881 -345.38383)
			(xy 323.074644 -345.437825) (xy 323.074644 -345.49237) (xy 324.557348 -345.49237) (xy 324.557348 -345.43783)
			(xy 324.56511 -345.383846) (xy 324.580476 -345.331516) (xy 324.603135 -345.281906) (xy 324.632623 -345.236026)
			(xy 324.668341 -345.194809) (xy 324.709561 -345.159096) (xy 324.755445 -345.129613) (xy 324.805057 -345.106961)
			(xy 324.857389 -345.0916) (xy 324.911374 -345.083844) (xy 324.938644 -345.083384) (xy 325.802244 -345.083384)
			(xy 325.829515 -345.083782) (xy 325.8835 -345.091549) (xy 325.93583 -345.10692) (xy 325.985441 -345.129582)
			(xy 326.031322 -345.159072) (xy 326.072539 -345.194792) (xy 326.108254 -345.236013) (xy 326.137739 -345.281898)
			(xy 326.160395 -345.331511) (xy 326.17576 -345.383843) (xy 326.183522 -345.437829) (xy 326.183522 -345.492368)
			(xy 327.666347 -345.492368) (xy 327.666347 -345.437832) (xy 327.674109 -345.383851) (xy 327.689473 -345.331525)
			(xy 327.712128 -345.281917) (xy 327.741613 -345.236039) (xy 327.777326 -345.194824) (xy 327.818542 -345.159111)
			(xy 327.864421 -345.129627) (xy 327.914028 -345.106972) (xy 327.966355 -345.091608) (xy 328.020336 -345.083847)
			(xy 328.047604 -345.083384) (xy 328.911204 -345.083384) (xy 328.938476 -345.083779) (xy 328.992466 -345.091542)
			(xy 329.044801 -345.106909) (xy 329.094417 -345.129569) (xy 329.140303 -345.159058) (xy 329.181525 -345.194778)
			(xy 329.217244 -345.236) (xy 329.246733 -345.281886) (xy 329.269392 -345.331502) (xy 329.284759 -345.383838)
			(xy 329.292521 -345.437828) (xy 329.292521 -345.492364) (xy 330.77537 -345.492364) (xy 330.77537 -345.437836)
			(xy 330.78313 -345.383862) (xy 330.798492 -345.331541) (xy 330.821143 -345.281939) (xy 330.850621 -345.236066)
			(xy 330.886329 -345.194854) (xy 330.927537 -345.159143) (xy 330.973408 -345.12966) (xy 331.023007 -345.107004)
			(xy 331.075326 -345.091638) (xy 331.1293 -345.083873) (xy 331.156564 -345.083384) (xy 332.020164 -345.083384)
			(xy 332.04744 -345.083753) (xy 332.101437 -345.091512) (xy 332.153781 -345.106877) (xy 332.203404 -345.129535)
			(xy 332.249298 -345.159026) (xy 332.290527 -345.194747) (xy 332.326253 -345.235973) (xy 332.355747 -345.281864)
			(xy 332.37841 -345.331486) (xy 332.39378 -345.383828) (xy 332.401544 -345.437824) (xy 332.401544 -345.492369)
			(xy 333.884247 -345.492369) (xy 333.884247 -345.437831) (xy 333.892009 -345.383849) (xy 333.907375 -345.33152)
			(xy 333.930031 -345.281912) (xy 333.959518 -345.236032) (xy 333.995234 -345.194817) (xy 334.036452 -345.159103)
			(xy 334.082333 -345.12962) (xy 334.131943 -345.106966) (xy 334.184272 -345.091604) (xy 334.238255 -345.083846)
			(xy 334.265524 -345.083384) (xy 335.129124 -345.083384) (xy 335.156396 -345.08378) (xy 335.210383 -345.091546)
			(xy 335.262716 -345.106915) (xy 335.312329 -345.129575) (xy 335.358213 -345.159065) (xy 335.399432 -345.194785)
			(xy 335.435149 -345.236007) (xy 335.464636 -345.281892) (xy 335.487294 -345.331507) (xy 335.50266 -345.38384)
			(xy 335.510422 -345.437828) (xy 335.510422 -345.492365) (xy 336.99327 -345.492365) (xy 336.99327 -345.437835)
			(xy 337.001031 -345.383859) (xy 337.016393 -345.331537) (xy 337.039046 -345.281934) (xy 337.068526 -345.236059)
			(xy 337.104236 -345.194847) (xy 337.145446 -345.159136) (xy 337.19132 -345.129653) (xy 337.240922 -345.106999)
			(xy 337.293243 -345.091634) (xy 337.347219 -345.083871) (xy 337.374484 -345.083384) (xy 338.238084 -345.083384)
			(xy 338.265359 -345.083755) (xy 338.319354 -345.091516) (xy 338.371695 -345.106882) (xy 338.421316 -345.129542)
			(xy 338.467207 -345.159033) (xy 338.508434 -345.194754) (xy 338.544158 -345.23598) (xy 338.57365 -345.28187)
			(xy 338.596312 -345.33149) (xy 338.611681 -345.38383) (xy 338.619444 -345.437825) (xy 338.619444 -345.49237)
			(xy 340.102148 -345.49237) (xy 340.102148 -345.43783) (xy 340.10991 -345.383846) (xy 340.125276 -345.331516)
			(xy 340.147935 -345.281906) (xy 340.177423 -345.236026) (xy 340.213141 -345.194809) (xy 340.254361 -345.159096)
			(xy 340.300245 -345.129613) (xy 340.349857 -345.106961) (xy 340.402189 -345.0916) (xy 340.456174 -345.083844)
			(xy 340.483444 -345.083384) (xy 341.347044 -345.083384) (xy 341.374315 -345.083782) (xy 341.4283 -345.091549)
			(xy 341.48063 -345.10692) (xy 341.530241 -345.129582) (xy 341.576122 -345.159072) (xy 341.617339 -345.194792)
			(xy 341.653054 -345.236013) (xy 341.682539 -345.281898) (xy 341.705195 -345.331511) (xy 341.72056 -345.383843)
			(xy 341.728322 -345.437829) (xy 341.728322 -345.492368) (xy 343.211147 -345.492368) (xy 343.211147 -345.437832)
			(xy 343.218909 -345.383851) (xy 343.234273 -345.331525) (xy 343.256928 -345.281917) (xy 343.286413 -345.236039)
			(xy 343.322126 -345.194824) (xy 343.363342 -345.159111) (xy 343.409221 -345.129627) (xy 343.458828 -345.106972)
			(xy 343.511155 -345.091608) (xy 343.565136 -345.083847) (xy 343.592404 -345.083384) (xy 344.456004 -345.083384)
			(xy 344.483276 -345.083779) (xy 344.537266 -345.091542) (xy 344.589601 -345.106909) (xy 344.639217 -345.129569)
			(xy 344.685103 -345.159058) (xy 344.726325 -345.194778) (xy 344.762044 -345.236) (xy 344.791533 -345.281886)
			(xy 344.814192 -345.331502) (xy 344.829559 -345.383838) (xy 344.837321 -345.437828) (xy 344.837321 -345.492365)
			(xy 370.80677 -345.492365) (xy 370.80677 -345.437835) (xy 370.81453 -345.383859) (xy 370.829893 -345.331538)
			(xy 370.852545 -345.281935) (xy 370.882025 -345.236061) (xy 370.917734 -345.194848) (xy 370.958945 -345.159137)
			(xy 371.004817 -345.129655) (xy 371.054419 -345.107) (xy 371.10674 -345.091635) (xy 371.160715 -345.083872)
			(xy 371.18798 -345.083384) (xy 372.05158 -345.083384) (xy 372.078855 -345.083754) (xy 372.132851 -345.091515)
			(xy 372.185192 -345.106881) (xy 372.234814 -345.129541) (xy 372.280705 -345.159031) (xy 372.321933 -345.194753)
			(xy 372.357657 -345.235978) (xy 372.38715 -345.281869) (xy 372.409812 -345.331489) (xy 372.425181 -345.38383)
			(xy 372.432944 -345.437825) (xy 372.432944 -345.49237) (xy 373.915647 -345.49237) (xy 373.915647 -345.43783)
			(xy 373.92341 -345.383847) (xy 373.938776 -345.331517) (xy 373.961434 -345.281907) (xy 373.990922 -345.236027)
			(xy 374.026639 -345.194811) (xy 374.067859 -345.159098) (xy 374.113742 -345.129615) (xy 374.163355 -345.106962)
			(xy 374.215686 -345.091601) (xy 374.26967 -345.083845) (xy 374.29694 -345.083384) (xy 375.16054 -345.083384)
			(xy 375.187811 -345.083781) (xy 375.241797 -345.091549) (xy 375.294128 -345.106919) (xy 375.343739 -345.12958)
			(xy 375.38962 -345.159071) (xy 375.430838 -345.19479) (xy 375.466553 -345.236012) (xy 375.496039 -345.281896)
			(xy 375.518695 -345.33151) (xy 375.53406 -345.383843) (xy 375.541822 -345.437829) (xy 375.541822 -345.492366)
			(xy 377.02467 -345.492366) (xy 377.02467 -345.437834) (xy 377.032431 -345.383857) (xy 377.047795 -345.331534)
			(xy 377.070448 -345.281929) (xy 377.09993 -345.236054) (xy 377.135641 -345.194841) (xy 377.176854 -345.15913)
			(xy 377.222729 -345.129648) (xy 377.272334 -345.106995) (xy 377.324657 -345.091631) (xy 377.378634 -345.08387)
			(xy 377.4059 -345.083384) (xy 378.2695 -345.083384) (xy 378.296773 -345.083779) (xy 378.350763 -345.091541)
			(xy 378.403099 -345.106908) (xy 378.452715 -345.129567) (xy 378.498601 -345.159057) (xy 378.539824 -345.194776)
			(xy 378.575543 -345.235999) (xy 378.605033 -345.281885) (xy 378.627692 -345.331501) (xy 378.643059 -345.383837)
			(xy 378.650821 -345.437827) (xy 378.650821 -345.492364) (xy 380.13367 -345.492364) (xy 380.13367 -345.437836)
			(xy 380.14143 -345.383862) (xy 380.156791 -345.331542) (xy 380.179442 -345.281941) (xy 380.208921 -345.236067)
			(xy 380.244627 -345.194855) (xy 380.285835 -345.159145) (xy 380.331705 -345.129661) (xy 380.381305 -345.107005)
			(xy 380.433623 -345.091638) (xy 380.487596 -345.083873) (xy 380.51486 -345.083384) (xy 381.37846 -345.083384)
			(xy 381.405736 -345.083753) (xy 381.459734 -345.091511) (xy 381.512078 -345.106876) (xy 381.561702 -345.129534)
			(xy 381.607596 -345.159024) (xy 381.648826 -345.194746) (xy 381.684552 -345.235972) (xy 381.714047 -345.281863)
			(xy 381.73671 -345.331485) (xy 381.75208 -345.383827) (xy 381.759844 -345.437824) (xy 381.759844 -345.492369)
			(xy 383.242547 -345.492369) (xy 383.242547 -345.437831) (xy 383.250309 -345.383849) (xy 383.265675 -345.331521)
			(xy 383.288331 -345.281913) (xy 383.317817 -345.236034) (xy 383.353532 -345.194818) (xy 383.39475 -345.159105)
			(xy 383.44063 -345.129621) (xy 383.49024 -345.106968) (xy 383.542569 -345.091605) (xy 383.596551 -345.083846)
			(xy 383.62382 -345.083384) (xy 384.48742 -345.083384) (xy 384.514692 -345.08378) (xy 384.56868 -345.091545)
			(xy 384.621013 -345.106914) (xy 384.670627 -345.129574) (xy 384.716511 -345.159064) (xy 384.757731 -345.194783)
			(xy 384.793448 -345.236005) (xy 384.822936 -345.281891) (xy 384.845593 -345.331506) (xy 384.860959 -345.38384)
			(xy 384.868722 -345.437828) (xy 384.868722 -345.492365) (xy 386.35157 -345.492365) (xy 386.35157 -345.437835)
			(xy 386.35933 -345.383859) (xy 386.374693 -345.331538) (xy 386.397345 -345.281935) (xy 386.426825 -345.236061)
			(xy 386.462534 -345.194848) (xy 386.503745 -345.159137) (xy 386.549617 -345.129655) (xy 386.599219 -345.107)
			(xy 386.65154 -345.091635) (xy 386.705515 -345.083872) (xy 386.73278 -345.083384) (xy 387.59638 -345.083384)
			(xy 387.623655 -345.083754) (xy 387.677651 -345.091515) (xy 387.729992 -345.106881) (xy 387.779614 -345.129541)
			(xy 387.825505 -345.159031) (xy 387.866733 -345.194753) (xy 387.902457 -345.235978) (xy 387.93195 -345.281869)
			(xy 387.954612 -345.331489) (xy 387.969981 -345.38383) (xy 387.977744 -345.437825) (xy 387.977744 -345.49237)
			(xy 389.460447 -345.49237) (xy 389.460447 -345.43783) (xy 389.46821 -345.383847) (xy 389.483576 -345.331517)
			(xy 389.506234 -345.281907) (xy 389.535722 -345.236027) (xy 389.571439 -345.194811) (xy 389.612659 -345.159098)
			(xy 389.658542 -345.129615) (xy 389.708155 -345.106962) (xy 389.760486 -345.091601) (xy 389.81447 -345.083845)
			(xy 389.84174 -345.083384) (xy 390.70534 -345.083384) (xy 390.732611 -345.083781) (xy 390.786597 -345.091549)
			(xy 390.838928 -345.106919) (xy 390.888539 -345.12958) (xy 390.93442 -345.159071) (xy 390.975638 -345.19479)
			(xy 391.011353 -345.236012) (xy 391.040839 -345.281896) (xy 391.063495 -345.33151) (xy 391.07886 -345.383843)
			(xy 391.086622 -345.437829) (xy 391.086622 -345.492366) (xy 392.56947 -345.492366) (xy 392.56947 -345.437834)
			(xy 392.577231 -345.383857) (xy 392.592595 -345.331534) (xy 392.615248 -345.281929) (xy 392.64473 -345.236054)
			(xy 392.680441 -345.194841) (xy 392.721654 -345.15913) (xy 392.767529 -345.129648) (xy 392.817134 -345.106995)
			(xy 392.869457 -345.091631) (xy 392.923434 -345.08387) (xy 392.9507 -345.083384) (xy 393.8143 -345.083384)
			(xy 393.841573 -345.083779) (xy 393.895563 -345.091541) (xy 393.947899 -345.106908) (xy 393.997515 -345.129567)
			(xy 394.043401 -345.159057) (xy 394.084624 -345.194776) (xy 394.120343 -345.235999) (xy 394.149833 -345.281885)
			(xy 394.172492 -345.331501) (xy 394.187859 -345.383837) (xy 394.195621 -345.437827) (xy 394.195621 -345.492364)
			(xy 395.67847 -345.492364) (xy 395.67847 -345.437836) (xy 395.68623 -345.383862) (xy 395.701591 -345.331542)
			(xy 395.724242 -345.281941) (xy 395.753721 -345.236067) (xy 395.789427 -345.194855) (xy 395.830635 -345.159145)
			(xy 395.876505 -345.129661) (xy 395.926105 -345.107005) (xy 395.978423 -345.091638) (xy 396.032396 -345.083873)
			(xy 396.05966 -345.083384) (xy 396.92326 -345.083384) (xy 396.950536 -345.083753) (xy 397.004534 -345.091511)
			(xy 397.056878 -345.106876) (xy 397.106502 -345.129534) (xy 397.152396 -345.159024) (xy 397.193626 -345.194746)
			(xy 397.229352 -345.235972) (xy 397.258847 -345.281863) (xy 397.28151 -345.331485) (xy 397.29688 -345.383827)
			(xy 397.304644 -345.437824) (xy 397.304644 -345.492369) (xy 398.787347 -345.492369) (xy 398.787347 -345.437831)
			(xy 398.795109 -345.383849) (xy 398.810475 -345.331521) (xy 398.833131 -345.281913) (xy 398.862617 -345.236034)
			(xy 398.898332 -345.194818) (xy 398.93955 -345.159105) (xy 398.98543 -345.129621) (xy 399.03504 -345.106968)
			(xy 399.087369 -345.091605) (xy 399.141351 -345.083846) (xy 399.16862 -345.083384) (xy 400.03222 -345.083384)
			(xy 400.059492 -345.08378) (xy 400.11348 -345.091545) (xy 400.165813 -345.106914) (xy 400.215427 -345.129574)
			(xy 400.261311 -345.159064) (xy 400.302531 -345.194783) (xy 400.338248 -345.236005) (xy 400.367736 -345.281891)
			(xy 400.390393 -345.331506) (xy 400.405759 -345.38384) (xy 400.413522 -345.437828) (xy 400.413522 -345.492365)
			(xy 401.89637 -345.492365) (xy 401.89637 -345.437835) (xy 401.90413 -345.383859) (xy 401.919493 -345.331538)
			(xy 401.942145 -345.281935) (xy 401.971625 -345.236061) (xy 402.007334 -345.194848) (xy 402.048545 -345.159137)
			(xy 402.094417 -345.129655) (xy 402.144019 -345.107) (xy 402.19634 -345.091635) (xy 402.250315 -345.083872)
			(xy 402.27758 -345.083384) (xy 403.14118 -345.083384) (xy 403.168455 -345.083754) (xy 403.222451 -345.091515)
			(xy 403.274792 -345.106881) (xy 403.324414 -345.129541) (xy 403.370305 -345.159031) (xy 403.411533 -345.194753)
			(xy 403.447257 -345.235978) (xy 403.47675 -345.281869) (xy 403.499412 -345.331489) (xy 403.514781 -345.38383)
			(xy 403.522544 -345.437825) (xy 403.522544 -345.492366) (xy 408.91387 -345.492366) (xy 408.91387 -345.437834)
			(xy 408.921631 -345.383858) (xy 408.936994 -345.331535) (xy 408.959647 -345.281932) (xy 408.989128 -345.236057)
			(xy 409.024838 -345.194844) (xy 409.06605 -345.159133) (xy 409.111925 -345.129651) (xy 409.161528 -345.106997)
			(xy 409.21385 -345.091633) (xy 409.267826 -345.083871) (xy 409.295092 -345.083384) (xy 410.158692 -345.083384)
			(xy 410.185967 -345.083755) (xy 410.239961 -345.091517) (xy 410.292301 -345.106885) (xy 410.341921 -345.129544)
			(xy 410.387811 -345.159035) (xy 410.429037 -345.194757) (xy 410.46476 -345.235982) (xy 410.494252 -345.281872)
			(xy 410.516913 -345.331492) (xy 410.532281 -345.383831) (xy 410.540044 -345.437825) (xy 410.540044 -345.492364)
			(xy 412.02287 -345.492364) (xy 412.02287 -345.437836) (xy 412.03063 -345.383863) (xy 412.045991 -345.331544)
			(xy 412.068641 -345.281943) (xy 412.098119 -345.23607) (xy 412.133824 -345.194858) (xy 412.175031 -345.159147)
			(xy 412.220901 -345.129664) (xy 412.270499 -345.107008) (xy 412.322816 -345.09164) (xy 412.376788 -345.083874)
			(xy 412.404052 -345.083384) (xy 413.267652 -345.083384) (xy 413.294929 -345.083752) (xy 413.348927 -345.09151)
			(xy 413.401272 -345.106874) (xy 413.450897 -345.129531) (xy 413.496792 -345.159021) (xy 413.538023 -345.194743)
			(xy 413.57375 -345.235969) (xy 413.603246 -345.281861) (xy 413.625909 -345.331483) (xy 413.64128 -345.383826)
			(xy 413.649044 -345.437824) (xy 413.649044 -345.492368) (xy 415.131747 -345.492368) (xy 415.131747 -345.437832)
			(xy 415.139509 -345.38385) (xy 415.154874 -345.331523) (xy 415.17753 -345.281915) (xy 415.207015 -345.236036)
			(xy 415.242729 -345.194821) (xy 415.283946 -345.159108) (xy 415.329826 -345.129624) (xy 415.379434 -345.10697)
			(xy 415.431762 -345.091606) (xy 415.485744 -345.083847) (xy 415.513012 -345.083384) (xy 416.376612 -345.083384)
			(xy 416.403884 -345.083779) (xy 416.457873 -345.091543) (xy 416.510207 -345.106912) (xy 416.559822 -345.129571)
			(xy 416.605707 -345.159061) (xy 416.646928 -345.194781) (xy 416.682646 -345.236003) (xy 416.712135 -345.281889)
			(xy 416.734793 -345.331504) (xy 416.750159 -345.383839) (xy 416.757921 -345.437828) (xy 416.757921 -345.492365)
			(xy 418.24077 -345.492365) (xy 418.24077 -345.437835) (xy 418.24853 -345.383861) (xy 418.263892 -345.33154)
			(xy 418.286544 -345.281937) (xy 418.316023 -345.236063) (xy 418.351731 -345.194851) (xy 418.392941 -345.15914)
			(xy 418.438813 -345.129657) (xy 418.488413 -345.107002) (xy 418.540733 -345.091636) (xy 418.594707 -345.083872)
			(xy 418.621972 -345.083384) (xy 419.485572 -345.083384) (xy 419.512848 -345.083754) (xy 419.566844 -345.091514)
			(xy 419.619186 -345.106879) (xy 419.668809 -345.129538) (xy 419.714702 -345.159028) (xy 419.75593 -345.19475)
			(xy 419.791655 -345.235976) (xy 419.821149 -345.281866) (xy 419.843811 -345.331487) (xy 419.859181 -345.383829)
			(xy 419.866944 -345.437824) (xy 419.866944 -345.492369) (xy 421.349647 -345.492369) (xy 421.349647 -345.437831)
			(xy 421.35741 -345.383848) (xy 421.372776 -345.331519) (xy 421.395433 -345.281909) (xy 421.42492 -345.23603)
			(xy 421.460636 -345.194814) (xy 421.501855 -345.159101) (xy 421.547738 -345.129617) (xy 421.597349 -345.106964)
			(xy 421.649679 -345.091603) (xy 421.703663 -345.083845) (xy 421.730932 -345.083384) (xy 422.594532 -345.083384)
			(xy 422.621803 -345.083781) (xy 422.67579 -345.091547) (xy 422.728122 -345.106917) (xy 422.777734 -345.129578)
			(xy 422.823616 -345.159068) (xy 422.864835 -345.194788) (xy 422.900551 -345.236009) (xy 422.930038 -345.281894)
			(xy 422.952694 -345.331508) (xy 422.96806 -345.383842) (xy 422.975822 -345.437829) (xy 422.975822 -345.492366)
			(xy 424.45867 -345.492366) (xy 424.45867 -345.437834) (xy 424.466431 -345.383858) (xy 424.481794 -345.331535)
			(xy 424.504447 -345.281932) (xy 424.533928 -345.236057) (xy 424.569638 -345.194844) (xy 424.61085 -345.159133)
			(xy 424.656725 -345.129651) (xy 424.706328 -345.106997) (xy 424.75865 -345.091633) (xy 424.812626 -345.083871)
			(xy 424.839892 -345.083384) (xy 425.703492 -345.083384) (xy 425.730767 -345.083755) (xy 425.784761 -345.091517)
			(xy 425.837101 -345.106885) (xy 425.886721 -345.129544) (xy 425.932611 -345.159035) (xy 425.973837 -345.194757)
			(xy 426.00956 -345.235982) (xy 426.039052 -345.281872) (xy 426.061713 -345.331492) (xy 426.077081 -345.383831)
			(xy 426.084844 -345.437825) (xy 426.084844 -345.492364) (xy 427.56767 -345.492364) (xy 427.56767 -345.437836)
			(xy 427.57543 -345.383863) (xy 427.590791 -345.331544) (xy 427.613441 -345.281943) (xy 427.642919 -345.23607)
			(xy 427.678624 -345.194858) (xy 427.719831 -345.159147) (xy 427.765701 -345.129664) (xy 427.815299 -345.107008)
			(xy 427.867616 -345.09164) (xy 427.921588 -345.083874) (xy 427.948852 -345.083384) (xy 428.812452 -345.083384)
			(xy 428.839729 -345.083752) (xy 428.893727 -345.09151) (xy 428.946072 -345.106874) (xy 428.995697 -345.129531)
			(xy 429.041592 -345.159021) (xy 429.082823 -345.194743) (xy 429.11855 -345.235969) (xy 429.148046 -345.281861)
			(xy 429.170709 -345.331483) (xy 429.18608 -345.383826) (xy 429.193844 -345.437824) (xy 429.193844 -345.492368)
			(xy 430.676547 -345.492368) (xy 430.676547 -345.437832) (xy 430.684309 -345.38385) (xy 430.699674 -345.331523)
			(xy 430.72233 -345.281915) (xy 430.751815 -345.236036) (xy 430.787529 -345.194821) (xy 430.828746 -345.159108)
			(xy 430.874626 -345.129624) (xy 430.924234 -345.10697) (xy 430.976562 -345.091606) (xy 431.030544 -345.083847)
			(xy 431.057812 -345.083384) (xy 431.921412 -345.083384) (xy 431.948684 -345.083779) (xy 432.002673 -345.091543)
			(xy 432.055007 -345.106912) (xy 432.104622 -345.129571) (xy 432.150507 -345.159061) (xy 432.191728 -345.194781)
			(xy 432.227446 -345.236003) (xy 432.256935 -345.281889) (xy 432.279593 -345.331504) (xy 432.294959 -345.383839)
			(xy 432.302721 -345.437828) (xy 432.302721 -345.492365) (xy 433.78557 -345.492365) (xy 433.78557 -345.437835)
			(xy 433.79333 -345.383861) (xy 433.808692 -345.33154) (xy 433.831344 -345.281937) (xy 433.860823 -345.236063)
			(xy 433.896531 -345.194851) (xy 433.937741 -345.15914) (xy 433.983613 -345.129657) (xy 434.033213 -345.107002)
			(xy 434.085533 -345.091636) (xy 434.139507 -345.083872) (xy 434.166772 -345.083384) (xy 435.030372 -345.083384)
			(xy 435.057648 -345.083754) (xy 435.111644 -345.091514) (xy 435.163986 -345.106879) (xy 435.213609 -345.129538)
			(xy 435.259502 -345.159028) (xy 435.30073 -345.19475) (xy 435.336455 -345.235976) (xy 435.365949 -345.281866)
			(xy 435.388611 -345.331487) (xy 435.403981 -345.383829) (xy 435.411744 -345.437824) (xy 435.411744 -345.492369)
			(xy 436.894447 -345.492369) (xy 436.894447 -345.437831) (xy 436.90221 -345.383848) (xy 436.917576 -345.331519)
			(xy 436.940233 -345.281909) (xy 436.96972 -345.23603) (xy 437.005436 -345.194814) (xy 437.046655 -345.159101)
			(xy 437.092538 -345.129617) (xy 437.142149 -345.106964) (xy 437.194479 -345.091603) (xy 437.248463 -345.083845)
			(xy 437.275732 -345.083384) (xy 438.139332 -345.083384) (xy 438.166603 -345.083781) (xy 438.22059 -345.091547)
			(xy 438.272922 -345.106917) (xy 438.322534 -345.129578) (xy 438.368416 -345.159068) (xy 438.409635 -345.194788)
			(xy 438.445351 -345.236009) (xy 438.474838 -345.281894) (xy 438.497494 -345.331508) (xy 438.51286 -345.383842)
			(xy 438.520622 -345.437829) (xy 438.520622 -345.492366) (xy 440.00347 -345.492366) (xy 440.00347 -345.437834)
			(xy 440.011231 -345.383858) (xy 440.026594 -345.331535) (xy 440.049247 -345.281932) (xy 440.078728 -345.236057)
			(xy 440.114438 -345.194844) (xy 440.15565 -345.159133) (xy 440.201525 -345.129651) (xy 440.251128 -345.106997)
			(xy 440.30345 -345.091633) (xy 440.357426 -345.083871) (xy 440.384692 -345.083384) (xy 441.248292 -345.083384)
			(xy 441.275567 -345.083755) (xy 441.329561 -345.091517) (xy 441.381901 -345.106885) (xy 441.431521 -345.129544)
			(xy 441.477411 -345.159035) (xy 441.518637 -345.194757) (xy 441.55436 -345.235982) (xy 441.583852 -345.281872)
			(xy 441.606513 -345.331492) (xy 441.621881 -345.383831) (xy 441.629644 -345.437825) (xy 441.629644 -345.492375)
			(xy 441.621881 -345.546369) (xy 441.606513 -345.598708) (xy 441.583852 -345.648328) (xy 441.55436 -345.694218)
			(xy 441.518637 -345.735443) (xy 441.477411 -345.771165) (xy 441.431521 -345.800656) (xy 441.381901 -345.823315)
			(xy 441.329561 -345.838683) (xy 441.275567 -345.846445) (xy 441.248292 -345.846908) (xy 440.384692 -345.846908)
			(xy 440.357426 -345.846329) (xy 440.30345 -345.838567) (xy 440.251128 -345.823203) (xy 440.201525 -345.800549)
			(xy 440.15565 -345.771067) (xy 440.114438 -345.735356) (xy 440.078728 -345.694143) (xy 440.049247 -345.648268)
			(xy 440.026594 -345.598665) (xy 440.011231 -345.546342) (xy 440.00347 -345.492366) (xy 438.520622 -345.492366)
			(xy 438.520622 -345.492371) (xy 438.51286 -345.546358) (xy 438.497494 -345.598692) (xy 438.474838 -345.648306)
			(xy 438.445351 -345.694191) (xy 438.409635 -345.735412) (xy 438.368416 -345.771132) (xy 438.322534 -345.800622)
			(xy 438.272922 -345.823283) (xy 438.22059 -345.838653) (xy 438.166603 -345.846419) (xy 438.139332 -345.846908)
			(xy 437.275732 -345.846908) (xy 437.248463 -345.846355) (xy 437.194479 -345.838597) (xy 437.142149 -345.823236)
			(xy 437.092538 -345.800583) (xy 437.046655 -345.771099) (xy 437.005436 -345.735386) (xy 436.96972 -345.69417)
			(xy 436.940233 -345.648291) (xy 436.917576 -345.598681) (xy 436.90221 -345.546352) (xy 436.894447 -345.492369)
			(xy 435.411744 -345.492369) (xy 435.411744 -345.492376) (xy 435.403981 -345.546371) (xy 435.388611 -345.598713)
			(xy 435.365949 -345.648334) (xy 435.336455 -345.694224) (xy 435.30073 -345.73545) (xy 435.259502 -345.771172)
			(xy 435.213609 -345.800662) (xy 435.163986 -345.823321) (xy 435.111644 -345.838686) (xy 435.057648 -345.846446)
			(xy 435.030372 -345.846908) (xy 434.166772 -345.846908) (xy 434.139507 -345.846328) (xy 434.085533 -345.838564)
			(xy 434.033213 -345.823198) (xy 433.983613 -345.800543) (xy 433.937741 -345.77106) (xy 433.896531 -345.735349)
			(xy 433.860823 -345.694137) (xy 433.831344 -345.648263) (xy 433.808692 -345.59866) (xy 433.79333 -345.546339)
			(xy 433.78557 -345.492365) (xy 432.302721 -345.492365) (xy 432.302721 -345.492372) (xy 432.294959 -345.546361)
			(xy 432.279593 -345.598696) (xy 432.256935 -345.648311) (xy 432.227446 -345.694197) (xy 432.191728 -345.735419)
			(xy 432.150507 -345.771139) (xy 432.104622 -345.800629) (xy 432.055007 -345.823288) (xy 432.002673 -345.838657)
			(xy 431.948684 -345.846421) (xy 431.921412 -345.846908) (xy 431.057812 -345.846908) (xy 431.030544 -345.846353)
			(xy 430.976562 -345.838594) (xy 430.924234 -345.82323) (xy 430.874626 -345.800576) (xy 430.828746 -345.771092)
			(xy 430.787529 -345.735379) (xy 430.751815 -345.694164) (xy 430.72233 -345.648285) (xy 430.699674 -345.598677)
			(xy 430.684309 -345.54635) (xy 430.676547 -345.492368) (xy 429.193844 -345.492368) (xy 429.193844 -345.492376)
			(xy 429.18608 -345.546374) (xy 429.170709 -345.598717) (xy 429.148046 -345.648339) (xy 429.11855 -345.694231)
			(xy 429.082823 -345.735457) (xy 429.041592 -345.771179) (xy 428.995697 -345.800669) (xy 428.946072 -345.823326)
			(xy 428.893727 -345.83869) (xy 428.839729 -345.846448) (xy 428.812452 -345.846908) (xy 427.948852 -345.846908)
			(xy 427.921588 -345.846326) (xy 427.867616 -345.83856) (xy 427.815299 -345.823192) (xy 427.765701 -345.800536)
			(xy 427.719831 -345.771053) (xy 427.678624 -345.735342) (xy 427.642919 -345.69413) (xy 427.613441 -345.648257)
			(xy 427.590791 -345.598656) (xy 427.57543 -345.546337) (xy 427.56767 -345.492364) (xy 426.084844 -345.492364)
			(xy 426.084844 -345.492375) (xy 426.077081 -345.546369) (xy 426.061713 -345.598708) (xy 426.039052 -345.648328)
			(xy 426.00956 -345.694218) (xy 425.973837 -345.735443) (xy 425.932611 -345.771165) (xy 425.886721 -345.800656)
			(xy 425.837101 -345.823315) (xy 425.784761 -345.838683) (xy 425.730767 -345.846445) (xy 425.703492 -345.846908)
			(xy 424.839892 -345.846908) (xy 424.812626 -345.846329) (xy 424.75865 -345.838567) (xy 424.706328 -345.823203)
			(xy 424.656725 -345.800549) (xy 424.61085 -345.771067) (xy 424.569638 -345.735356) (xy 424.533928 -345.694143)
			(xy 424.504447 -345.648268) (xy 424.481794 -345.598665) (xy 424.466431 -345.546342) (xy 424.45867 -345.492366)
			(xy 422.975822 -345.492366) (xy 422.975822 -345.492371) (xy 422.96806 -345.546358) (xy 422.952694 -345.598692)
			(xy 422.930038 -345.648306) (xy 422.900551 -345.694191) (xy 422.864835 -345.735412) (xy 422.823616 -345.771132)
			(xy 422.777734 -345.800622) (xy 422.728122 -345.823283) (xy 422.67579 -345.838653) (xy 422.621803 -345.846419)
			(xy 422.594532 -345.846908) (xy 421.730932 -345.846908) (xy 421.703663 -345.846355) (xy 421.649679 -345.838597)
			(xy 421.597349 -345.823236) (xy 421.547738 -345.800583) (xy 421.501855 -345.771099) (xy 421.460636 -345.735386)
			(xy 421.42492 -345.69417) (xy 421.395433 -345.648291) (xy 421.372776 -345.598681) (xy 421.35741 -345.546352)
			(xy 421.349647 -345.492369) (xy 419.866944 -345.492369) (xy 419.866944 -345.492376) (xy 419.859181 -345.546371)
			(xy 419.843811 -345.598713) (xy 419.821149 -345.648334) (xy 419.791655 -345.694224) (xy 419.75593 -345.73545)
			(xy 419.714702 -345.771172) (xy 419.668809 -345.800662) (xy 419.619186 -345.823321) (xy 419.566844 -345.838686)
			(xy 419.512848 -345.846446) (xy 419.485572 -345.846908) (xy 418.621972 -345.846908) (xy 418.594707 -345.846328)
			(xy 418.540733 -345.838564) (xy 418.488413 -345.823198) (xy 418.438813 -345.800543) (xy 418.392941 -345.77106)
			(xy 418.351731 -345.735349) (xy 418.316023 -345.694137) (xy 418.286544 -345.648263) (xy 418.263892 -345.59866)
			(xy 418.24853 -345.546339) (xy 418.24077 -345.492365) (xy 416.757921 -345.492365) (xy 416.757921 -345.492372)
			(xy 416.750159 -345.546361) (xy 416.734793 -345.598696) (xy 416.712135 -345.648311) (xy 416.682646 -345.694197)
			(xy 416.646928 -345.735419) (xy 416.605707 -345.771139) (xy 416.559822 -345.800629) (xy 416.510207 -345.823288)
			(xy 416.457873 -345.838657) (xy 416.403884 -345.846421) (xy 416.376612 -345.846908) (xy 415.513012 -345.846908)
			(xy 415.485744 -345.846353) (xy 415.431762 -345.838594) (xy 415.379434 -345.82323) (xy 415.329826 -345.800576)
			(xy 415.283946 -345.771092) (xy 415.242729 -345.735379) (xy 415.207015 -345.694164) (xy 415.17753 -345.648285)
			(xy 415.154874 -345.598677) (xy 415.139509 -345.54635) (xy 415.131747 -345.492368) (xy 413.649044 -345.492368)
			(xy 413.649044 -345.492376) (xy 413.64128 -345.546374) (xy 413.625909 -345.598717) (xy 413.603246 -345.648339)
			(xy 413.57375 -345.694231) (xy 413.538023 -345.735457) (xy 413.496792 -345.771179) (xy 413.450897 -345.800669)
			(xy 413.401272 -345.823326) (xy 413.348927 -345.83869) (xy 413.294929 -345.846448) (xy 413.267652 -345.846908)
			(xy 412.404052 -345.846908) (xy 412.376788 -345.846326) (xy 412.322816 -345.83856) (xy 412.270499 -345.823192)
			(xy 412.220901 -345.800536) (xy 412.175031 -345.771053) (xy 412.133824 -345.735342) (xy 412.098119 -345.69413)
			(xy 412.068641 -345.648257) (xy 412.045991 -345.598656) (xy 412.03063 -345.546337) (xy 412.02287 -345.492364)
			(xy 410.540044 -345.492364) (xy 410.540044 -345.492375) (xy 410.532281 -345.546369) (xy 410.516913 -345.598708)
			(xy 410.494252 -345.648328) (xy 410.46476 -345.694218) (xy 410.429037 -345.735443) (xy 410.387811 -345.771165)
			(xy 410.341921 -345.800656) (xy 410.292301 -345.823315) (xy 410.239961 -345.838683) (xy 410.185967 -345.846445)
			(xy 410.158692 -345.846908) (xy 409.295092 -345.846908) (xy 409.267826 -345.846329) (xy 409.21385 -345.838567)
			(xy 409.161528 -345.823203) (xy 409.111925 -345.800549) (xy 409.06605 -345.771067) (xy 409.024838 -345.735356)
			(xy 408.989128 -345.694143) (xy 408.959647 -345.648268) (xy 408.936994 -345.598665) (xy 408.921631 -345.546342)
			(xy 408.91387 -345.492366) (xy 403.522544 -345.492366) (xy 403.522544 -345.492375) (xy 403.514781 -345.54637)
			(xy 403.499412 -345.598711) (xy 403.47675 -345.648331) (xy 403.447257 -345.694221) (xy 403.411533 -345.735447)
			(xy 403.370305 -345.771169) (xy 403.324414 -345.800659) (xy 403.274792 -345.823319) (xy 403.222451 -345.838685)
			(xy 403.168455 -345.846446) (xy 403.14118 -345.846908) (xy 402.27758 -345.846908) (xy 402.250315 -345.846328)
			(xy 402.19634 -345.838565) (xy 402.144019 -345.8232) (xy 402.094417 -345.800545) (xy 402.048545 -345.771063)
			(xy 402.007334 -345.735352) (xy 401.971625 -345.694139) (xy 401.942145 -345.648265) (xy 401.919493 -345.598662)
			(xy 401.90413 -345.546341) (xy 401.89637 -345.492365) (xy 400.413522 -345.492365) (xy 400.413522 -345.492372)
			(xy 400.405759 -345.54636) (xy 400.390393 -345.598694) (xy 400.367736 -345.648309) (xy 400.338248 -345.694195)
			(xy 400.302531 -345.735417) (xy 400.261311 -345.771136) (xy 400.215427 -345.800626) (xy 400.165813 -345.823286)
			(xy 400.11348 -345.838655) (xy 400.059492 -345.84642) (xy 400.03222 -345.846908) (xy 399.16862 -345.846908)
			(xy 399.141351 -345.846354) (xy 399.087369 -345.838595) (xy 399.03504 -345.823232) (xy 398.98543 -345.800579)
			(xy 398.93955 -345.771095) (xy 398.898332 -345.735382) (xy 398.862617 -345.694166) (xy 398.833131 -345.648287)
			(xy 398.810475 -345.598679) (xy 398.795109 -345.546351) (xy 398.787347 -345.492369) (xy 397.304644 -345.492369)
			(xy 397.304644 -345.492376) (xy 397.29688 -345.546373) (xy 397.28151 -345.598715) (xy 397.258847 -345.648337)
			(xy 397.229352 -345.694228) (xy 397.193626 -345.735454) (xy 397.152396 -345.771176) (xy 397.106502 -345.800666)
			(xy 397.056878 -345.823324) (xy 397.004534 -345.838689) (xy 396.950536 -345.846447) (xy 396.92326 -345.846908)
			(xy 396.05966 -345.846908) (xy 396.032396 -345.846327) (xy 395.978423 -345.838562) (xy 395.926105 -345.823195)
			(xy 395.876505 -345.800539) (xy 395.830635 -345.771055) (xy 395.789427 -345.735345) (xy 395.753721 -345.694133)
			(xy 395.724242 -345.648259) (xy 395.701591 -345.598658) (xy 395.68623 -345.546338) (xy 395.67847 -345.492364)
			(xy 394.195621 -345.492364) (xy 394.195621 -345.492373) (xy 394.187859 -345.546363) (xy 394.172492 -345.598699)
			(xy 394.149833 -345.648315) (xy 394.120343 -345.694201) (xy 394.084624 -345.735424) (xy 394.043401 -345.771143)
			(xy 393.997515 -345.800633) (xy 393.947899 -345.823292) (xy 393.895563 -345.838659) (xy 393.841573 -345.846421)
			(xy 393.8143 -345.846908) (xy 392.9507 -345.846908) (xy 392.923434 -345.84633) (xy 392.869457 -345.838569)
			(xy 392.817134 -345.823205) (xy 392.767529 -345.800552) (xy 392.721654 -345.77107) (xy 392.680441 -345.735359)
			(xy 392.64473 -345.694146) (xy 392.615248 -345.648271) (xy 392.592595 -345.598666) (xy 392.577231 -345.546343)
			(xy 392.56947 -345.492366) (xy 391.086622 -345.492366) (xy 391.086622 -345.492371) (xy 391.07886 -345.546357)
			(xy 391.063495 -345.59869) (xy 391.040839 -345.648304) (xy 391.011353 -345.694188) (xy 390.975638 -345.73541)
			(xy 390.93442 -345.771129) (xy 390.888539 -345.80062) (xy 390.838928 -345.823281) (xy 390.786597 -345.838651)
			(xy 390.732611 -345.846419) (xy 390.70534 -345.846908) (xy 389.84174 -345.846908) (xy 389.81447 -345.846355)
			(xy 389.760486 -345.838599) (xy 389.708155 -345.823238) (xy 389.658542 -345.800585) (xy 389.612659 -345.771102)
			(xy 389.571439 -345.735389) (xy 389.535722 -345.694173) (xy 389.506234 -345.648293) (xy 389.483576 -345.598683)
			(xy 389.46821 -345.546353) (xy 389.460447 -345.49237) (xy 387.977744 -345.49237) (xy 387.977744 -345.492375)
			(xy 387.969981 -345.54637) (xy 387.954612 -345.598711) (xy 387.93195 -345.648331) (xy 387.902457 -345.694221)
			(xy 387.866733 -345.735447) (xy 387.825505 -345.771169) (xy 387.779614 -345.800659) (xy 387.729992 -345.823319)
			(xy 387.677651 -345.838685) (xy 387.623655 -345.846446) (xy 387.59638 -345.846908) (xy 386.73278 -345.846908)
			(xy 386.705515 -345.846328) (xy 386.65154 -345.838565) (xy 386.599219 -345.8232) (xy 386.549617 -345.800545)
			(xy 386.503745 -345.771063) (xy 386.462534 -345.735352) (xy 386.426825 -345.694139) (xy 386.397345 -345.648265)
			(xy 386.374693 -345.598662) (xy 386.35933 -345.546341) (xy 386.35157 -345.492365) (xy 384.868722 -345.492365)
			(xy 384.868722 -345.492372) (xy 384.860959 -345.54636) (xy 384.845593 -345.598694) (xy 384.822936 -345.648309)
			(xy 384.793448 -345.694195) (xy 384.757731 -345.735417) (xy 384.716511 -345.771136) (xy 384.670627 -345.800626)
			(xy 384.621013 -345.823286) (xy 384.56868 -345.838655) (xy 384.514692 -345.84642) (xy 384.48742 -345.846908)
			(xy 383.62382 -345.846908) (xy 383.596551 -345.846354) (xy 383.542569 -345.838595) (xy 383.49024 -345.823232)
			(xy 383.44063 -345.800579) (xy 383.39475 -345.771095) (xy 383.353532 -345.735382) (xy 383.317817 -345.694166)
			(xy 383.288331 -345.648287) (xy 383.265675 -345.598679) (xy 383.250309 -345.546351) (xy 383.242547 -345.492369)
			(xy 381.759844 -345.492369) (xy 381.759844 -345.492376) (xy 381.75208 -345.546373) (xy 381.73671 -345.598715)
			(xy 381.714047 -345.648337) (xy 381.684552 -345.694228) (xy 381.648826 -345.735454) (xy 381.607596 -345.771176)
			(xy 381.561702 -345.800666) (xy 381.512078 -345.823324) (xy 381.459734 -345.838689) (xy 381.405736 -345.846447)
			(xy 381.37846 -345.846908) (xy 380.51486 -345.846908) (xy 380.487596 -345.846327) (xy 380.433623 -345.838562)
			(xy 380.381305 -345.823195) (xy 380.331705 -345.800539) (xy 380.285835 -345.771055) (xy 380.244627 -345.735345)
			(xy 380.208921 -345.694133) (xy 380.179442 -345.648259) (xy 380.156791 -345.598658) (xy 380.14143 -345.546338)
			(xy 380.13367 -345.492364) (xy 378.650821 -345.492364) (xy 378.650821 -345.492373) (xy 378.643059 -345.546363)
			(xy 378.627692 -345.598699) (xy 378.605033 -345.648315) (xy 378.575543 -345.694201) (xy 378.539824 -345.735424)
			(xy 378.498601 -345.771143) (xy 378.452715 -345.800633) (xy 378.403099 -345.823292) (xy 378.350763 -345.838659)
			(xy 378.296773 -345.846421) (xy 378.2695 -345.846908) (xy 377.4059 -345.846908) (xy 377.378634 -345.84633)
			(xy 377.324657 -345.838569) (xy 377.272334 -345.823205) (xy 377.222729 -345.800552) (xy 377.176854 -345.77107)
			(xy 377.135641 -345.735359) (xy 377.09993 -345.694146) (xy 377.070448 -345.648271) (xy 377.047795 -345.598666)
			(xy 377.032431 -345.546343) (xy 377.02467 -345.492366) (xy 375.541822 -345.492366) (xy 375.541822 -345.492371)
			(xy 375.53406 -345.546357) (xy 375.518695 -345.59869) (xy 375.496039 -345.648304) (xy 375.466553 -345.694188)
			(xy 375.430838 -345.73541) (xy 375.38962 -345.771129) (xy 375.343739 -345.80062) (xy 375.294128 -345.823281)
			(xy 375.241797 -345.838651) (xy 375.187811 -345.846419) (xy 375.16054 -345.846908) (xy 374.29694 -345.846908)
			(xy 374.26967 -345.846355) (xy 374.215686 -345.838599) (xy 374.163355 -345.823238) (xy 374.113742 -345.800585)
			(xy 374.067859 -345.771102) (xy 374.026639 -345.735389) (xy 373.990922 -345.694173) (xy 373.961434 -345.648293)
			(xy 373.938776 -345.598683) (xy 373.92341 -345.546353) (xy 373.915647 -345.49237) (xy 372.432944 -345.49237)
			(xy 372.432944 -345.492375) (xy 372.425181 -345.54637) (xy 372.409812 -345.598711) (xy 372.38715 -345.648331)
			(xy 372.357657 -345.694221) (xy 372.321933 -345.735447) (xy 372.280705 -345.771169) (xy 372.234814 -345.800659)
			(xy 372.185192 -345.823319) (xy 372.132851 -345.838685) (xy 372.078855 -345.846446) (xy 372.05158 -345.846908)
			(xy 371.18798 -345.846908) (xy 371.160715 -345.846328) (xy 371.10674 -345.838565) (xy 371.054419 -345.8232)
			(xy 371.004817 -345.800545) (xy 370.958945 -345.771063) (xy 370.917734 -345.735352) (xy 370.882025 -345.694139)
			(xy 370.852545 -345.648265) (xy 370.829893 -345.598662) (xy 370.81453 -345.546341) (xy 370.80677 -345.492365)
			(xy 344.837321 -345.492365) (xy 344.837321 -345.492372) (xy 344.829559 -345.546362) (xy 344.814192 -345.598698)
			(xy 344.791533 -345.648314) (xy 344.762044 -345.6942) (xy 344.726325 -345.735422) (xy 344.685103 -345.771142)
			(xy 344.639217 -345.800631) (xy 344.589601 -345.823291) (xy 344.537266 -345.838658) (xy 344.483276 -345.846421)
			(xy 344.456004 -345.846908) (xy 343.592404 -345.846908) (xy 343.565136 -345.846353) (xy 343.511155 -345.838592)
			(xy 343.458828 -345.823228) (xy 343.409221 -345.800573) (xy 343.363342 -345.771089) (xy 343.322126 -345.735376)
			(xy 343.286413 -345.694161) (xy 343.256928 -345.648283) (xy 343.234273 -345.598675) (xy 343.218909 -345.546349)
			(xy 343.211147 -345.492368) (xy 341.728322 -345.492368) (xy 341.728322 -345.492371) (xy 341.72056 -345.546357)
			(xy 341.705195 -345.598689) (xy 341.682539 -345.648302) (xy 341.653054 -345.694187) (xy 341.617339 -345.735408)
			(xy 341.576122 -345.771128) (xy 341.530241 -345.800618) (xy 341.48063 -345.82328) (xy 341.4283 -345.838651)
			(xy 341.374315 -345.846418) (xy 341.347044 -345.846908) (xy 340.483444 -345.846908) (xy 340.456174 -345.846356)
			(xy 340.402189 -345.8386) (xy 340.349857 -345.823239) (xy 340.300245 -345.800587) (xy 340.254361 -345.771104)
			(xy 340.213141 -345.735391) (xy 340.177423 -345.694174) (xy 340.147935 -345.648294) (xy 340.125276 -345.598684)
			(xy 340.10991 -345.546354) (xy 340.102148 -345.49237) (xy 338.619444 -345.49237) (xy 338.619444 -345.492375)
			(xy 338.611681 -345.54637) (xy 338.596312 -345.59871) (xy 338.57365 -345.64833) (xy 338.544158 -345.69422)
			(xy 338.508434 -345.735446) (xy 338.467207 -345.771167) (xy 338.421316 -345.800658) (xy 338.371695 -345.823318)
			(xy 338.319354 -345.838684) (xy 338.265359 -345.846445) (xy 338.238084 -345.846908) (xy 337.374484 -345.846908)
			(xy 337.347219 -345.846329) (xy 337.293243 -345.838566) (xy 337.240922 -345.823201) (xy 337.19132 -345.800547)
			(xy 337.145446 -345.771064) (xy 337.104236 -345.735353) (xy 337.068526 -345.694141) (xy 337.039046 -345.648266)
			(xy 337.016393 -345.598663) (xy 337.001031 -345.546341) (xy 336.99327 -345.492365) (xy 335.510422 -345.492365)
			(xy 335.510422 -345.492372) (xy 335.50266 -345.54636) (xy 335.487294 -345.598693) (xy 335.464636 -345.648308)
			(xy 335.435149 -345.694193) (xy 335.399432 -345.735415) (xy 335.358213 -345.771135) (xy 335.312329 -345.800625)
			(xy 335.262716 -345.823285) (xy 335.210383 -345.838654) (xy 335.156396 -345.84642) (xy 335.129124 -345.846908)
			(xy 334.265524 -345.846908) (xy 334.238255 -345.846354) (xy 334.184272 -345.838596) (xy 334.131943 -345.823234)
			(xy 334.082333 -345.80058) (xy 334.036452 -345.771097) (xy 333.995234 -345.735383) (xy 333.959518 -345.694168)
			(xy 333.930031 -345.648288) (xy 333.907375 -345.59868) (xy 333.892009 -345.546351) (xy 333.884247 -345.492369)
			(xy 332.401544 -345.492369) (xy 332.401544 -345.492376) (xy 332.39378 -345.546372) (xy 332.37841 -345.598714)
			(xy 332.355747 -345.648336) (xy 332.326253 -345.694227) (xy 332.290527 -345.735453) (xy 332.249298 -345.771174)
			(xy 332.203404 -345.800665) (xy 332.153781 -345.823323) (xy 332.101437 -345.838688) (xy 332.04744 -345.846447)
			(xy 332.020164 -345.846908) (xy 331.156564 -345.846908) (xy 331.1293 -345.846327) (xy 331.075326 -345.838562)
			(xy 331.023007 -345.823196) (xy 330.973408 -345.80054) (xy 330.927537 -345.771057) (xy 330.886329 -345.735346)
			(xy 330.850622 -345.694134) (xy 330.821143 -345.648261) (xy 330.798492 -345.598659) (xy 330.78313 -345.546338)
			(xy 330.77537 -345.492364) (xy 329.292521 -345.492364) (xy 329.292521 -345.492372) (xy 329.284759 -345.546362)
			(xy 329.269392 -345.598698) (xy 329.246733 -345.648314) (xy 329.217244 -345.6942) (xy 329.181525 -345.735422)
			(xy 329.140303 -345.771142) (xy 329.094417 -345.800631) (xy 329.044801 -345.823291) (xy 328.992466 -345.838658)
			(xy 328.938476 -345.846421) (xy 328.911204 -345.846908) (xy 328.047604 -345.846908) (xy 328.020336 -345.846353)
			(xy 327.966355 -345.838592) (xy 327.914028 -345.823228) (xy 327.864421 -345.800573) (xy 327.818542 -345.771089)
			(xy 327.777326 -345.735376) (xy 327.741613 -345.694161) (xy 327.712128 -345.648283) (xy 327.689473 -345.598675)
			(xy 327.674109 -345.546349) (xy 327.666347 -345.492368) (xy 326.183522 -345.492368) (xy 326.183522 -345.492371)
			(xy 326.17576 -345.546357) (xy 326.160395 -345.598689) (xy 326.137739 -345.648302) (xy 326.108254 -345.694187)
			(xy 326.072539 -345.735408) (xy 326.031322 -345.771128) (xy 325.985441 -345.800618) (xy 325.93583 -345.82328)
			(xy 325.8835 -345.838651) (xy 325.829515 -345.846418) (xy 325.802244 -345.846908) (xy 324.938644 -345.846908)
			(xy 324.911374 -345.846356) (xy 324.857389 -345.8386) (xy 324.805057 -345.823239) (xy 324.755445 -345.800587)
			(xy 324.709561 -345.771104) (xy 324.668341 -345.735391) (xy 324.632623 -345.694174) (xy 324.603135 -345.648294)
			(xy 324.580476 -345.598684) (xy 324.56511 -345.546354) (xy 324.557348 -345.49237) (xy 323.074644 -345.49237)
			(xy 323.074644 -345.492375) (xy 323.066881 -345.54637) (xy 323.051512 -345.59871) (xy 323.02885 -345.64833)
			(xy 322.999358 -345.69422) (xy 322.963634 -345.735446) (xy 322.922407 -345.771167) (xy 322.876516 -345.800658)
			(xy 322.826895 -345.823318) (xy 322.774554 -345.838684) (xy 322.720559 -345.846445) (xy 322.693284 -345.846908)
			(xy 321.829684 -345.846908) (xy 321.802419 -345.846329) (xy 321.748443 -345.838566) (xy 321.696122 -345.823201)
			(xy 321.64652 -345.800547) (xy 321.600646 -345.771064) (xy 321.559436 -345.735353) (xy 321.523726 -345.694141)
			(xy 321.494246 -345.648266) (xy 321.471593 -345.598663) (xy 321.456231 -345.546341) (xy 321.44847 -345.492365)
			(xy 319.965622 -345.492365) (xy 319.965622 -345.492372) (xy 319.95786 -345.54636) (xy 319.942494 -345.598693)
			(xy 319.919836 -345.648308) (xy 319.890349 -345.694193) (xy 319.854632 -345.735415) (xy 319.813413 -345.771135)
			(xy 319.767529 -345.800625) (xy 319.717916 -345.823285) (xy 319.665583 -345.838654) (xy 319.611596 -345.84642)
			(xy 319.584324 -345.846908) (xy 318.720724 -345.846908) (xy 318.693455 -345.846354) (xy 318.639472 -345.838596)
			(xy 318.587143 -345.823234) (xy 318.537533 -345.80058) (xy 318.491652 -345.771097) (xy 318.450434 -345.735383)
			(xy 318.414718 -345.694168) (xy 318.385231 -345.648288) (xy 318.362575 -345.59868) (xy 318.347209 -345.546351)
			(xy 318.339447 -345.492369) (xy 316.856744 -345.492369) (xy 316.856744 -345.492376) (xy 316.84898 -345.546372)
			(xy 316.83361 -345.598714) (xy 316.810947 -345.648336) (xy 316.781453 -345.694227) (xy 316.745727 -345.735453)
			(xy 316.704498 -345.771174) (xy 316.658604 -345.800665) (xy 316.608981 -345.823323) (xy 316.556637 -345.838688)
			(xy 316.50264 -345.846447) (xy 316.475364 -345.846908) (xy 315.611764 -345.846908) (xy 315.5845 -345.846327)
			(xy 315.530526 -345.838562) (xy 315.478207 -345.823196) (xy 315.428608 -345.80054) (xy 315.382737 -345.771057)
			(xy 315.341529 -345.735346) (xy 315.305822 -345.694134) (xy 315.276343 -345.648261) (xy 315.253692 -345.598659)
			(xy 315.23833 -345.546338) (xy 315.23057 -345.492364) (xy 313.747721 -345.492364) (xy 313.747721 -345.492372)
			(xy 313.739959 -345.546362) (xy 313.724592 -345.598698) (xy 313.701933 -345.648314) (xy 313.672444 -345.6942)
			(xy 313.636725 -345.735422) (xy 313.595503 -345.771142) (xy 313.549617 -345.800631) (xy 313.500001 -345.823291)
			(xy 313.447666 -345.838658) (xy 313.393676 -345.846421) (xy 313.366404 -345.846908) (xy 312.502804 -345.846908)
			(xy 312.475536 -345.846353) (xy 312.421555 -345.838592) (xy 312.369228 -345.823228) (xy 312.319621 -345.800573)
			(xy 312.273742 -345.771089) (xy 312.232526 -345.735376) (xy 312.196813 -345.694161) (xy 312.167328 -345.648283)
			(xy 312.144673 -345.598675) (xy 312.129309 -345.546349) (xy 312.121547 -345.492368) (xy 300.231621 -345.492368)
			(xy 300.231621 -345.492373) (xy 300.223859 -345.546362) (xy 300.208492 -345.598698) (xy 300.185833 -345.648314)
			(xy 300.156344 -345.6942) (xy 300.120624 -345.735423) (xy 300.079402 -345.771143) (xy 300.033516 -345.800632)
			(xy 299.9839 -345.823291) (xy 299.931564 -345.838658) (xy 299.877575 -345.846421) (xy 299.850302 -345.846908)
			(xy 298.986702 -345.846908) (xy 298.959434 -345.846353) (xy 298.905454 -345.838592) (xy 298.853127 -345.823228)
			(xy 298.80352 -345.800573) (xy 298.757641 -345.771089) (xy 298.716426 -345.735376) (xy 298.680712 -345.69416)
			(xy 298.651228 -345.648282) (xy 298.628573 -345.598675) (xy 298.613209 -345.546348) (xy 298.605447 -345.492368)
			(xy 297.122622 -345.492368) (xy 297.122622 -345.492371) (xy 297.11486 -345.546357) (xy 297.099495 -345.59869)
			(xy 297.076839 -345.648303) (xy 297.047354 -345.694187) (xy 297.011639 -345.735409) (xy 296.970421 -345.771128)
			(xy 296.92454 -345.800619) (xy 296.874929 -345.82328) (xy 296.822598 -345.838651) (xy 296.768613 -345.846419)
			(xy 296.741342 -345.846908) (xy 295.877742 -345.846908) (xy 295.850472 -345.846355) (xy 295.796487 -345.838599)
			(xy 295.744156 -345.823238) (xy 295.694543 -345.800586) (xy 295.64866 -345.771103) (xy 295.60744 -345.73539)
			(xy 295.571722 -345.694174) (xy 295.542234 -345.648293) (xy 295.519576 -345.598683) (xy 295.50421 -345.546354)
			(xy 295.496448 -345.49237) (xy 294.013744 -345.49237) (xy 294.013744 -345.492375) (xy 294.005981 -345.54637)
			(xy 293.990612 -345.59871) (xy 293.96795 -345.648331) (xy 293.938457 -345.694221) (xy 293.902734 -345.735446)
			(xy 293.861506 -345.771168) (xy 293.815615 -345.800659) (xy 293.765994 -345.823318) (xy 293.713652 -345.838685)
			(xy 293.659657 -345.846446) (xy 293.632382 -345.846908) (xy 292.768782 -345.846908) (xy 292.741517 -345.846328)
			(xy 292.687542 -345.838566) (xy 292.635221 -345.823201) (xy 292.585619 -345.800546) (xy 292.539745 -345.771063)
			(xy 292.498535 -345.735352) (xy 292.462826 -345.69414) (xy 292.433345 -345.648266) (xy 292.410693 -345.598663)
			(xy 292.395331 -345.546341) (xy 292.38757 -345.492365) (xy 290.904722 -345.492365) (xy 290.904722 -345.492372)
			(xy 290.896959 -345.54636) (xy 290.881593 -345.598694) (xy 290.858936 -345.648309) (xy 290.829449 -345.694194)
			(xy 290.793732 -345.735416) (xy 290.752512 -345.771136) (xy 290.706628 -345.800626) (xy 290.657015 -345.823286)
			(xy 290.604681 -345.838655) (xy 290.550694 -345.84642) (xy 290.523422 -345.846908) (xy 289.659822 -345.846908)
			(xy 289.632553 -345.846354) (xy 289.57857 -345.838595) (xy 289.526241 -345.823233) (xy 289.476632 -345.800579)
			(xy 289.430751 -345.771096) (xy 289.389533 -345.735383) (xy 289.353817 -345.694167) (xy 289.324331 -345.648288)
			(xy 289.301675 -345.598679) (xy 289.286309 -345.546351) (xy 289.278547 -345.492369) (xy 287.795844 -345.492369)
			(xy 287.795844 -345.492376) (xy 287.78808 -345.546373) (xy 287.77271 -345.598715) (xy 287.750047 -345.648336)
			(xy 287.720552 -345.694227) (xy 287.684827 -345.735453) (xy 287.643597 -345.771175) (xy 287.597703 -345.800665)
			(xy 287.548079 -345.823323) (xy 287.495736 -345.838688) (xy 287.441738 -345.846447) (xy 287.414462 -345.846908)
			(xy 286.550862 -345.846908) (xy 286.523598 -345.846327) (xy 286.469625 -345.838562) (xy 286.417306 -345.823195)
			(xy 286.367707 -345.80054) (xy 286.321836 -345.771056) (xy 286.280628 -345.735345) (xy 286.244921 -345.694134)
			(xy 286.215442 -345.64826) (xy 286.192792 -345.598658) (xy 286.17743 -345.546338) (xy 286.16967 -345.492364)
			(xy 284.686821 -345.492364) (xy 284.686821 -345.492373) (xy 284.679059 -345.546362) (xy 284.663692 -345.598698)
			(xy 284.641033 -345.648314) (xy 284.611544 -345.6942) (xy 284.575824 -345.735423) (xy 284.534602 -345.771143)
			(xy 284.488716 -345.800632) (xy 284.4391 -345.823291) (xy 284.386764 -345.838658) (xy 284.332775 -345.846421)
			(xy 284.305502 -345.846908) (xy 283.441902 -345.846908) (xy 283.414634 -345.846353) (xy 283.360654 -345.838592)
			(xy 283.308327 -345.823228) (xy 283.25872 -345.800573) (xy 283.212841 -345.771089) (xy 283.171626 -345.735376)
			(xy 283.135912 -345.69416) (xy 283.106428 -345.648282) (xy 283.083773 -345.598675) (xy 283.068409 -345.546348)
			(xy 283.060647 -345.492368) (xy 281.577822 -345.492368) (xy 281.577822 -345.492371) (xy 281.57006 -345.546357)
			(xy 281.554695 -345.59869) (xy 281.532039 -345.648303) (xy 281.502554 -345.694187) (xy 281.466839 -345.735409)
			(xy 281.425621 -345.771128) (xy 281.37974 -345.800619) (xy 281.330129 -345.82328) (xy 281.277798 -345.838651)
			(xy 281.223813 -345.846419) (xy 281.196542 -345.846908) (xy 280.332942 -345.846908) (xy 280.305672 -345.846355)
			(xy 280.251687 -345.838599) (xy 280.199356 -345.823238) (xy 280.149743 -345.800586) (xy 280.10386 -345.771103)
			(xy 280.06264 -345.73539) (xy 280.026922 -345.694174) (xy 279.997434 -345.648293) (xy 279.974776 -345.598683)
			(xy 279.95941 -345.546354) (xy 279.951648 -345.49237) (xy 278.468944 -345.49237) (xy 278.468944 -345.492375)
			(xy 278.461181 -345.54637) (xy 278.445812 -345.59871) (xy 278.42315 -345.648331) (xy 278.393657 -345.694221)
			(xy 278.357934 -345.735446) (xy 278.316706 -345.771168) (xy 278.270815 -345.800659) (xy 278.221194 -345.823318)
			(xy 278.168852 -345.838685) (xy 278.114857 -345.846446) (xy 278.087582 -345.846908) (xy 277.223982 -345.846908)
			(xy 277.196717 -345.846328) (xy 277.142742 -345.838566) (xy 277.090421 -345.823201) (xy 277.040819 -345.800546)
			(xy 276.994945 -345.771063) (xy 276.953735 -345.735352) (xy 276.918026 -345.69414) (xy 276.888545 -345.648266)
			(xy 276.865893 -345.598663) (xy 276.850531 -345.546341) (xy 276.84277 -345.492365) (xy 275.359922 -345.492365)
			(xy 275.359922 -345.492372) (xy 275.352159 -345.54636) (xy 275.336793 -345.598694) (xy 275.314136 -345.648309)
			(xy 275.284649 -345.694194) (xy 275.248932 -345.735416) (xy 275.207712 -345.771136) (xy 275.161828 -345.800626)
			(xy 275.112215 -345.823286) (xy 275.059881 -345.838655) (xy 275.005894 -345.84642) (xy 274.978622 -345.846908)
			(xy 274.115022 -345.846908) (xy 274.087753 -345.846354) (xy 274.03377 -345.838595) (xy 273.981441 -345.823233)
			(xy 273.931832 -345.800579) (xy 273.885951 -345.771096) (xy 273.844733 -345.735383) (xy 273.809017 -345.694167)
			(xy 273.779531 -345.648288) (xy 273.756875 -345.598679) (xy 273.741509 -345.546351) (xy 273.733747 -345.492369)
			(xy 272.251044 -345.492369) (xy 272.251044 -345.492376) (xy 272.24328 -345.546373) (xy 272.22791 -345.598715)
			(xy 272.205247 -345.648336) (xy 272.175752 -345.694227) (xy 272.140027 -345.735453) (xy 272.098797 -345.771175)
			(xy 272.052903 -345.800665) (xy 272.003279 -345.823323) (xy 271.950936 -345.838688) (xy 271.896938 -345.846447)
			(xy 271.869662 -345.846908) (xy 271.006062 -345.846908) (xy 270.978798 -345.846327) (xy 270.924825 -345.838562)
			(xy 270.872506 -345.823195) (xy 270.822907 -345.80054) (xy 270.777036 -345.771056) (xy 270.735828 -345.735345)
			(xy 270.700121 -345.694134) (xy 270.670642 -345.64826) (xy 270.647992 -345.598658) (xy 270.63263 -345.546338)
			(xy 270.62487 -345.492364) (xy 269.142021 -345.492364) (xy 269.142021 -345.492373) (xy 269.134259 -345.546362)
			(xy 269.118892 -345.598698) (xy 269.096233 -345.648314) (xy 269.066744 -345.6942) (xy 269.031024 -345.735423)
			(xy 268.989802 -345.771143) (xy 268.943916 -345.800632) (xy 268.8943 -345.823291) (xy 268.841964 -345.838658)
			(xy 268.787975 -345.846421) (xy 268.760702 -345.846908) (xy 267.897102 -345.846908) (xy 267.869834 -345.846353)
			(xy 267.815854 -345.838592) (xy 267.763527 -345.823228) (xy 267.71392 -345.800573) (xy 267.668041 -345.771089)
			(xy 267.626826 -345.735376) (xy 267.591112 -345.69416) (xy 267.561628 -345.648282) (xy 267.538973 -345.598675)
			(xy 267.523609 -345.546348) (xy 267.515847 -345.492368) (xy 197.629644 -345.492368) (xy 197.629644 -345.492376)
			(xy 197.621881 -345.546371) (xy 197.606511 -345.598713) (xy 197.583849 -345.648334) (xy 197.554355 -345.694224)
			(xy 197.51863 -345.73545) (xy 197.477402 -345.771172) (xy 197.431509 -345.800662) (xy 197.381886 -345.823321)
			(xy 197.329544 -345.838686) (xy 197.275548 -345.846446) (xy 197.248272 -345.846908) (xy 196.384672 -345.846908)
			(xy 196.357407 -345.846328) (xy 196.303433 -345.838564) (xy 196.251113 -345.823198) (xy 196.201513 -345.800543)
			(xy 196.155641 -345.77106) (xy 196.114431 -345.735349) (xy 196.078723 -345.694137) (xy 196.049244 -345.648263)
			(xy 196.026592 -345.59866) (xy 196.01123 -345.546339) (xy 196.00347 -345.492365) (xy 194.520621 -345.492365)
			(xy 194.520621 -345.492372) (xy 194.512859 -345.546361) (xy 194.497493 -345.598696) (xy 194.474835 -345.648311)
			(xy 194.445346 -345.694197) (xy 194.409628 -345.735419) (xy 194.368407 -345.771139) (xy 194.322522 -345.800629)
			(xy 194.272907 -345.823288) (xy 194.220573 -345.838657) (xy 194.166584 -345.846421) (xy 194.139312 -345.846908)
			(xy 193.275712 -345.846908) (xy 193.248444 -345.846353) (xy 193.194462 -345.838594) (xy 193.142134 -345.82323)
			(xy 193.092526 -345.800576) (xy 193.046646 -345.771092) (xy 193.005429 -345.735379) (xy 192.969715 -345.694164)
			(xy 192.94023 -345.648285) (xy 192.917574 -345.598677) (xy 192.902209 -345.54635) (xy 192.894447 -345.492368)
			(xy 191.411744 -345.492368) (xy 191.411744 -345.492376) (xy 191.40398 -345.546374) (xy 191.388609 -345.598717)
			(xy 191.365946 -345.648339) (xy 191.33645 -345.694231) (xy 191.300723 -345.735457) (xy 191.259492 -345.771179)
			(xy 191.213597 -345.800669) (xy 191.163972 -345.823326) (xy 191.111627 -345.83869) (xy 191.057629 -345.846448)
			(xy 191.030352 -345.846908) (xy 190.166752 -345.846908) (xy 190.139488 -345.846326) (xy 190.085516 -345.83856)
			(xy 190.033199 -345.823192) (xy 189.983601 -345.800536) (xy 189.937731 -345.771053) (xy 189.896524 -345.735342)
			(xy 189.860819 -345.69413) (xy 189.831341 -345.648257) (xy 189.808691 -345.598656) (xy 189.79333 -345.546337)
			(xy 189.78557 -345.492364) (xy 188.302744 -345.492364) (xy 188.302744 -345.492375) (xy 188.294981 -345.546369)
			(xy 188.279613 -345.598708) (xy 188.256952 -345.648328) (xy 188.22746 -345.694218) (xy 188.191737 -345.735443)
			(xy 188.150511 -345.771165) (xy 188.104621 -345.800656) (xy 188.055001 -345.823315) (xy 188.002661 -345.838683)
			(xy 187.948667 -345.846445) (xy 187.921392 -345.846908) (xy 187.057792 -345.846908) (xy 187.030526 -345.846329)
			(xy 186.97655 -345.838567) (xy 186.924228 -345.823203) (xy 186.874625 -345.800549) (xy 186.82875 -345.771067)
			(xy 186.787538 -345.735356) (xy 186.751828 -345.694143) (xy 186.722347 -345.648268) (xy 186.699694 -345.598665)
			(xy 186.684331 -345.546342) (xy 186.67657 -345.492366) (xy 185.193722 -345.492366) (xy 185.193722 -345.492371)
			(xy 185.18596 -345.546358) (xy 185.170594 -345.598692) (xy 185.147938 -345.648306) (xy 185.118451 -345.694191)
			(xy 185.082735 -345.735412) (xy 185.041516 -345.771132) (xy 184.995634 -345.800622) (xy 184.946022 -345.823283)
			(xy 184.89369 -345.838653) (xy 184.839703 -345.846419) (xy 184.812432 -345.846908) (xy 183.948832 -345.846908)
			(xy 183.921563 -345.846355) (xy 183.867579 -345.838597) (xy 183.815249 -345.823236) (xy 183.765638 -345.800583)
			(xy 183.719755 -345.771099) (xy 183.678536 -345.735386) (xy 183.64282 -345.69417) (xy 183.613333 -345.648291)
			(xy 183.590676 -345.598681) (xy 183.57531 -345.546352) (xy 183.567547 -345.492369) (xy 182.084844 -345.492369)
			(xy 182.084844 -345.492376) (xy 182.077081 -345.546371) (xy 182.061711 -345.598713) (xy 182.039049 -345.648334)
			(xy 182.009555 -345.694224) (xy 181.97383 -345.73545) (xy 181.932602 -345.771172) (xy 181.886709 -345.800662)
			(xy 181.837086 -345.823321) (xy 181.784744 -345.838686) (xy 181.730748 -345.846446) (xy 181.703472 -345.846908)
			(xy 180.839872 -345.846908) (xy 180.812607 -345.846328) (xy 180.758633 -345.838564) (xy 180.706313 -345.823198)
			(xy 180.656713 -345.800543) (xy 180.610841 -345.77106) (xy 180.569631 -345.735349) (xy 180.533923 -345.694137)
			(xy 180.504444 -345.648263) (xy 180.481792 -345.59866) (xy 180.46643 -345.546339) (xy 180.45867 -345.492365)
			(xy 178.975821 -345.492365) (xy 178.975821 -345.492372) (xy 178.968059 -345.546361) (xy 178.952693 -345.598696)
			(xy 178.930035 -345.648311) (xy 178.900546 -345.694197) (xy 178.864828 -345.735419) (xy 178.823607 -345.771139)
			(xy 178.777722 -345.800629) (xy 178.728107 -345.823288) (xy 178.675773 -345.838657) (xy 178.621784 -345.846421)
			(xy 178.594512 -345.846908) (xy 177.730912 -345.846908) (xy 177.703644 -345.846353) (xy 177.649662 -345.838594)
			(xy 177.597334 -345.82323) (xy 177.547726 -345.800576) (xy 177.501846 -345.771092) (xy 177.460629 -345.735379)
			(xy 177.424915 -345.694164) (xy 177.39543 -345.648285) (xy 177.372774 -345.598677) (xy 177.357409 -345.54635)
			(xy 177.349647 -345.492368) (xy 175.866944 -345.492368) (xy 175.866944 -345.492376) (xy 175.85918 -345.546374)
			(xy 175.843809 -345.598717) (xy 175.821146 -345.648339) (xy 175.79165 -345.694231) (xy 175.755923 -345.735457)
			(xy 175.714692 -345.771179) (xy 175.668797 -345.800669) (xy 175.619172 -345.823326) (xy 175.566827 -345.83869)
			(xy 175.512829 -345.846448) (xy 175.485552 -345.846908) (xy 174.621952 -345.846908) (xy 174.594688 -345.846326)
			(xy 174.540716 -345.83856) (xy 174.488399 -345.823192) (xy 174.438801 -345.800536) (xy 174.392931 -345.771053)
			(xy 174.351724 -345.735342) (xy 174.316019 -345.69413) (xy 174.286541 -345.648257) (xy 174.263891 -345.598656)
			(xy 174.24853 -345.546337) (xy 174.24077 -345.492364) (xy 172.757944 -345.492364) (xy 172.757944 -345.492375)
			(xy 172.750181 -345.546369) (xy 172.734813 -345.598708) (xy 172.712152 -345.648328) (xy 172.68266 -345.694218)
			(xy 172.646937 -345.735443) (xy 172.605711 -345.771165) (xy 172.559821 -345.800656) (xy 172.510201 -345.823315)
			(xy 172.457861 -345.838683) (xy 172.403867 -345.846445) (xy 172.376592 -345.846908) (xy 171.512992 -345.846908)
			(xy 171.485726 -345.846329) (xy 171.43175 -345.838567) (xy 171.379428 -345.823203) (xy 171.329825 -345.800549)
			(xy 171.28395 -345.771067) (xy 171.242738 -345.735356) (xy 171.207028 -345.694143) (xy 171.177547 -345.648268)
			(xy 171.154894 -345.598665) (xy 171.139531 -345.546342) (xy 171.13177 -345.492366) (xy 169.648922 -345.492366)
			(xy 169.648922 -345.492371) (xy 169.64116 -345.546358) (xy 169.625794 -345.598692) (xy 169.603138 -345.648306)
			(xy 169.573651 -345.694191) (xy 169.537935 -345.735412) (xy 169.496716 -345.771132) (xy 169.450834 -345.800622)
			(xy 169.401222 -345.823283) (xy 169.34889 -345.838653) (xy 169.294903 -345.846419) (xy 169.267632 -345.846908)
			(xy 168.404032 -345.846908) (xy 168.376763 -345.846355) (xy 168.322779 -345.838597) (xy 168.270449 -345.823236)
			(xy 168.220838 -345.800583) (xy 168.174955 -345.771099) (xy 168.133736 -345.735386) (xy 168.09802 -345.69417)
			(xy 168.068533 -345.648291) (xy 168.045876 -345.598681) (xy 168.03051 -345.546352) (xy 168.022747 -345.492369)
			(xy 166.540044 -345.492369) (xy 166.540044 -345.492376) (xy 166.532281 -345.546371) (xy 166.516911 -345.598713)
			(xy 166.494249 -345.648334) (xy 166.464755 -345.694224) (xy 166.42903 -345.73545) (xy 166.387802 -345.771172)
			(xy 166.341909 -345.800662) (xy 166.292286 -345.823321) (xy 166.239944 -345.838686) (xy 166.185948 -345.846446)
			(xy 166.158672 -345.846908) (xy 165.295072 -345.846908) (xy 165.267807 -345.846328) (xy 165.213833 -345.838564)
			(xy 165.161513 -345.823198) (xy 165.111913 -345.800543) (xy 165.066041 -345.77106) (xy 165.024831 -345.735349)
			(xy 164.989123 -345.694137) (xy 164.959644 -345.648263) (xy 164.936992 -345.59866) (xy 164.92163 -345.546339)
			(xy 164.91387 -345.492365) (xy 144.196621 -345.492365) (xy 144.196621 -345.492372) (xy 144.188859 -345.546362)
			(xy 144.173492 -345.598697) (xy 144.150834 -345.648312) (xy 144.121345 -345.694199) (xy 144.085627 -345.735421)
			(xy 144.044405 -345.77114) (xy 143.99852 -345.80063) (xy 143.948904 -345.82329) (xy 143.89657 -345.838657)
			(xy 143.84258 -345.846421) (xy 143.815308 -345.846908) (xy 142.951708 -345.846908) (xy 142.92444 -345.846353)
			(xy 142.870459 -345.838593) (xy 142.818131 -345.823229) (xy 142.768523 -345.800575) (xy 142.722644 -345.771091)
			(xy 142.681428 -345.735378) (xy 142.645714 -345.694162) (xy 142.616229 -345.648284) (xy 142.593574 -345.598676)
			(xy 142.578209 -345.546349) (xy 142.570447 -345.492368) (xy 141.087622 -345.492368) (xy 141.087622 -345.49237)
			(xy 141.07986 -345.546356) (xy 141.064495 -345.598688) (xy 141.04184 -345.648301) (xy 141.012355 -345.694185)
			(xy 140.976641 -345.735407) (xy 140.935424 -345.771126) (xy 140.889543 -345.800617) (xy 140.839933 -345.823279)
			(xy 140.787603 -345.83865) (xy 140.733618 -345.846418) (xy 140.706348 -345.846908) (xy 139.842748 -345.846908)
			(xy 139.815478 -345.846356) (xy 139.761492 -345.8386) (xy 139.70916 -345.82324) (xy 139.659547 -345.800588)
			(xy 139.613663 -345.771105) (xy 139.572442 -345.735392) (xy 139.536724 -345.694176) (xy 139.507235 -345.648295)
			(xy 139.484577 -345.598685) (xy 139.46921 -345.546354) (xy 139.461448 -345.49237) (xy 137.978744 -345.49237)
			(xy 137.978744 -345.492375) (xy 137.970981 -345.546369) (xy 137.955612 -345.598709) (xy 137.932951 -345.648329)
			(xy 137.903459 -345.694219) (xy 137.867736 -345.735444) (xy 137.826509 -345.771166) (xy 137.780619 -345.800657)
			(xy 137.730998 -345.823316) (xy 137.678658 -345.838684) (xy 137.624663 -345.846445) (xy 137.597388 -345.846908)
			(xy 136.733788 -345.846908) (xy 136.706522 -345.846329) (xy 136.652547 -345.838567) (xy 136.600225 -345.823202)
			(xy 136.550622 -345.800548) (xy 136.504748 -345.771065) (xy 136.463537 -345.735354) (xy 136.427827 -345.694142)
			(xy 136.398346 -345.648267) (xy 136.375694 -345.598664) (xy 136.360331 -345.546342) (xy 136.35257 -345.492366)
			(xy 134.869722 -345.492366) (xy 134.869722 -345.492371) (xy 134.86196 -345.546359) (xy 134.846594 -345.598693)
			(xy 134.823937 -345.648307) (xy 134.79445 -345.694192) (xy 134.758734 -345.735414) (xy 134.717514 -345.771133)
			(xy 134.671632 -345.800624) (xy 134.622019 -345.823284) (xy 134.569686 -345.838654) (xy 134.515699 -345.84642)
			(xy 134.488428 -345.846908) (xy 133.624828 -345.846908) (xy 133.597559 -345.846355) (xy 133.543576 -345.838597)
			(xy 133.491246 -345.823235) (xy 133.441635 -345.800581) (xy 133.395753 -345.771098) (xy 133.354535 -345.735385)
			(xy 133.318819 -345.694169) (xy 133.289332 -345.648289) (xy 133.266675 -345.59868) (xy 133.251309 -345.546352)
			(xy 133.243547 -345.492369) (xy 131.760844 -345.492369) (xy 131.760844 -345.492376) (xy 131.75308 -345.546372)
			(xy 131.737711 -345.598713) (xy 131.715048 -345.648335) (xy 131.685554 -345.694225) (xy 131.649829 -345.735451)
			(xy 131.6086 -345.771173) (xy 131.562707 -345.800663) (xy 131.513083 -345.823322) (xy 131.460741 -345.838687)
			(xy 131.406744 -345.846447) (xy 131.379468 -345.846908) (xy 130.515868 -345.846908) (xy 130.488603 -345.846328)
			(xy 130.43463 -345.838563) (xy 130.38231 -345.823197) (xy 130.33271 -345.800542) (xy 130.286839 -345.771058)
			(xy 130.24563 -345.735347) (xy 130.209922 -345.694136) (xy 130.180443 -345.648262) (xy 130.157792 -345.59866)
			(xy 130.14243 -345.546339) (xy 130.13467 -345.492365) (xy 128.651821 -345.492365) (xy 128.651821 -345.492372)
			(xy 128.644059 -345.546362) (xy 128.628692 -345.598697) (xy 128.606034 -345.648312) (xy 128.576545 -345.694199)
			(xy 128.540827 -345.735421) (xy 128.499605 -345.77114) (xy 128.45372 -345.80063) (xy 128.404104 -345.82329)
			(xy 128.35177 -345.838657) (xy 128.29778 -345.846421) (xy 128.270508 -345.846908) (xy 127.406908 -345.846908)
			(xy 127.37964 -345.846353) (xy 127.325659 -345.838593) (xy 127.273331 -345.823229) (xy 127.223723 -345.800575)
			(xy 127.177844 -345.771091) (xy 127.136628 -345.735378) (xy 127.100914 -345.694162) (xy 127.071429 -345.648284)
			(xy 127.048774 -345.598676) (xy 127.033409 -345.546349) (xy 127.025647 -345.492368) (xy 125.542822 -345.492368)
			(xy 125.542822 -345.49237) (xy 125.53506 -345.546356) (xy 125.519695 -345.598688) (xy 125.49704 -345.648301)
			(xy 125.467555 -345.694185) (xy 125.431841 -345.735407) (xy 125.390624 -345.771126) (xy 125.344743 -345.800617)
			(xy 125.295133 -345.823279) (xy 125.242803 -345.83865) (xy 125.188818 -345.846418) (xy 125.161548 -345.846908)
			(xy 124.297948 -345.846908) (xy 124.270678 -345.846356) (xy 124.216692 -345.8386) (xy 124.16436 -345.82324)
			(xy 124.114747 -345.800588) (xy 124.068863 -345.771105) (xy 124.027642 -345.735392) (xy 123.991924 -345.694176)
			(xy 123.962435 -345.648295) (xy 123.939777 -345.598685) (xy 123.92441 -345.546354) (xy 123.916648 -345.49237)
			(xy 122.433944 -345.49237) (xy 122.433944 -345.492375) (xy 122.426181 -345.546369) (xy 122.410812 -345.598709)
			(xy 122.388151 -345.648329) (xy 122.358659 -345.694219) (xy 122.322936 -345.735444) (xy 122.281709 -345.771166)
			(xy 122.235819 -345.800657) (xy 122.186198 -345.823316) (xy 122.133858 -345.838684) (xy 122.079863 -345.846445)
			(xy 122.052588 -345.846908) (xy 121.188988 -345.846908) (xy 121.161722 -345.846329) (xy 121.107747 -345.838567)
			(xy 121.055425 -345.823202) (xy 121.005822 -345.800548) (xy 120.959948 -345.771065) (xy 120.918737 -345.735354)
			(xy 120.883027 -345.694142) (xy 120.853546 -345.648267) (xy 120.830894 -345.598664) (xy 120.815531 -345.546342)
			(xy 120.80777 -345.492366) (xy 119.324922 -345.492366) (xy 119.324922 -345.492371) (xy 119.31716 -345.546359)
			(xy 119.301794 -345.598693) (xy 119.279137 -345.648307) (xy 119.24965 -345.694192) (xy 119.213934 -345.735414)
			(xy 119.172714 -345.771133) (xy 119.126832 -345.800624) (xy 119.077219 -345.823284) (xy 119.024886 -345.838654)
			(xy 118.970899 -345.84642) (xy 118.943628 -345.846908) (xy 118.080028 -345.846908) (xy 118.052759 -345.846355)
			(xy 117.998776 -345.838597) (xy 117.946446 -345.823235) (xy 117.896835 -345.800581) (xy 117.850953 -345.771098)
			(xy 117.809735 -345.735385) (xy 117.774019 -345.694169) (xy 117.744532 -345.648289) (xy 117.721875 -345.59868)
			(xy 117.706509 -345.546352) (xy 117.698747 -345.492369) (xy 116.216044 -345.492369) (xy 116.216044 -345.492376)
			(xy 116.20828 -345.546372) (xy 116.192911 -345.598713) (xy 116.170248 -345.648335) (xy 116.140754 -345.694225)
			(xy 116.105029 -345.735451) (xy 116.0638 -345.771173) (xy 116.017907 -345.800663) (xy 115.968283 -345.823322)
			(xy 115.915941 -345.838687) (xy 115.861944 -345.846447) (xy 115.834668 -345.846908) (xy 114.971068 -345.846908)
			(xy 114.943803 -345.846328) (xy 114.88983 -345.838563) (xy 114.83751 -345.823197) (xy 114.78791 -345.800542)
			(xy 114.742039 -345.771058) (xy 114.70083 -345.735347) (xy 114.665122 -345.694136) (xy 114.635643 -345.648262)
			(xy 114.612992 -345.59866) (xy 114.59763 -345.546339) (xy 114.58987 -345.492365) (xy 113.107021 -345.492365)
			(xy 113.107021 -345.492372) (xy 113.099259 -345.546362) (xy 113.083892 -345.598697) (xy 113.061234 -345.648312)
			(xy 113.031745 -345.694199) (xy 112.996027 -345.735421) (xy 112.954805 -345.77114) (xy 112.90892 -345.80063)
			(xy 112.859304 -345.82329) (xy 112.80697 -345.838657) (xy 112.75298 -345.846421) (xy 112.725708 -345.846908)
			(xy 111.862108 -345.846908) (xy 111.83484 -345.846353) (xy 111.780859 -345.838593) (xy 111.728531 -345.823229)
			(xy 111.678923 -345.800575) (xy 111.633044 -345.771091) (xy 111.591828 -345.735378) (xy 111.556114 -345.694162)
			(xy 111.526629 -345.648284) (xy 111.503974 -345.598676) (xy 111.488609 -345.546349) (xy 111.480847 -345.492368)
			(xy 93.706722 -345.492368) (xy 93.706722 -345.492371) (xy 93.69896 -345.546357) (xy 93.683595 -345.59869)
			(xy 93.660939 -345.648303) (xy 93.631454 -345.694187) (xy 93.595739 -345.735409) (xy 93.554521 -345.771128)
			(xy 93.50864 -345.800619) (xy 93.459029 -345.82328) (xy 93.406698 -345.838651) (xy 93.352713 -345.846419)
			(xy 93.325442 -345.846908) (xy 92.461842 -345.846908) (xy 92.434572 -345.846355) (xy 92.380587 -345.838599)
			(xy 92.328256 -345.823238) (xy 92.278643 -345.800586) (xy 92.23276 -345.771103) (xy 92.19154 -345.73539)
			(xy 92.155822 -345.694174) (xy 92.126334 -345.648293) (xy 92.103676 -345.598683) (xy 92.08831 -345.546354)
			(xy 92.080548 -345.49237) (xy 90.597844 -345.49237) (xy 90.597844 -345.492375) (xy 90.590081 -345.54637)
			(xy 90.574712 -345.59871) (xy 90.55205 -345.648331) (xy 90.522557 -345.694221) (xy 90.486834 -345.735446)
			(xy 90.445606 -345.771168) (xy 90.399715 -345.800659) (xy 90.350094 -345.823318) (xy 90.297752 -345.838685)
			(xy 90.243757 -345.846446) (xy 90.216482 -345.846908) (xy 89.352882 -345.846908) (xy 89.325617 -345.846328)
			(xy 89.271642 -345.838566) (xy 89.219321 -345.823201) (xy 89.169719 -345.800546) (xy 89.123845 -345.771063)
			(xy 89.082635 -345.735352) (xy 89.046926 -345.69414) (xy 89.017445 -345.648266) (xy 88.994793 -345.598663)
			(xy 88.979431 -345.546341) (xy 88.97167 -345.492365) (xy 87.488822 -345.492365) (xy 87.488822 -345.492372)
			(xy 87.481059 -345.54636) (xy 87.465693 -345.598694) (xy 87.443036 -345.648309) (xy 87.413549 -345.694194)
			(xy 87.377832 -345.735416) (xy 87.336612 -345.771136) (xy 87.290728 -345.800626) (xy 87.241115 -345.823286)
			(xy 87.188781 -345.838655) (xy 87.134794 -345.84642) (xy 87.107522 -345.846908) (xy 86.243922 -345.846908)
			(xy 86.216653 -345.846354) (xy 86.16267 -345.838595) (xy 86.110341 -345.823233) (xy 86.060732 -345.800579)
			(xy 86.014851 -345.771096) (xy 85.973633 -345.735383) (xy 85.937917 -345.694167) (xy 85.908431 -345.648288)
			(xy 85.885775 -345.598679) (xy 85.870409 -345.546351) (xy 85.862647 -345.492369) (xy 84.379944 -345.492369)
			(xy 84.379944 -345.492376) (xy 84.37218 -345.546373) (xy 84.35681 -345.598715) (xy 84.334147 -345.648336)
			(xy 84.304652 -345.694227) (xy 84.268927 -345.735453) (xy 84.227697 -345.771175) (xy 84.181803 -345.800665)
			(xy 84.132179 -345.823323) (xy 84.079836 -345.838688) (xy 84.025838 -345.846447) (xy 83.998562 -345.846908)
			(xy 83.134962 -345.846908) (xy 83.107698 -345.846327) (xy 83.053725 -345.838562) (xy 83.001406 -345.823195)
			(xy 82.951807 -345.80054) (xy 82.905936 -345.771056) (xy 82.864728 -345.735345) (xy 82.829021 -345.694134)
			(xy 82.799542 -345.64826) (xy 82.776892 -345.598658) (xy 82.76153 -345.546338) (xy 82.75377 -345.492364)
			(xy 81.270921 -345.492364) (xy 81.270921 -345.492373) (xy 81.263159 -345.546362) (xy 81.247792 -345.598698)
			(xy 81.225133 -345.648314) (xy 81.195644 -345.6942) (xy 81.159924 -345.735423) (xy 81.118702 -345.771143)
			(xy 81.072816 -345.800632) (xy 81.0232 -345.823291) (xy 80.970864 -345.838658) (xy 80.916875 -345.846421)
			(xy 80.889602 -345.846908) (xy 80.026002 -345.846908) (xy 79.998734 -345.846353) (xy 79.944754 -345.838592)
			(xy 79.892427 -345.823228) (xy 79.84282 -345.800573) (xy 79.796941 -345.771089) (xy 79.755726 -345.735376)
			(xy 79.720012 -345.69416) (xy 79.690528 -345.648282) (xy 79.667873 -345.598675) (xy 79.652509 -345.546348)
			(xy 79.644747 -345.492368) (xy 78.161922 -345.492368) (xy 78.161922 -345.492371) (xy 78.15416 -345.546357)
			(xy 78.138795 -345.59869) (xy 78.116139 -345.648303) (xy 78.086654 -345.694187) (xy 78.050939 -345.735409)
			(xy 78.009721 -345.771128) (xy 77.96384 -345.800619) (xy 77.914229 -345.82328) (xy 77.861898 -345.838651)
			(xy 77.807913 -345.846419) (xy 77.780642 -345.846908) (xy 76.917042 -345.846908) (xy 76.889772 -345.846355)
			(xy 76.835787 -345.838599) (xy 76.783456 -345.823238) (xy 76.733843 -345.800586) (xy 76.68796 -345.771103)
			(xy 76.64674 -345.73539) (xy 76.611022 -345.694174) (xy 76.581534 -345.648293) (xy 76.558876 -345.598683)
			(xy 76.54351 -345.546354) (xy 76.535748 -345.49237) (xy 75.053044 -345.49237) (xy 75.053044 -345.492375)
			(xy 75.045281 -345.54637) (xy 75.029912 -345.59871) (xy 75.00725 -345.648331) (xy 74.977757 -345.694221)
			(xy 74.942034 -345.735446) (xy 74.900806 -345.771168) (xy 74.854915 -345.800659) (xy 74.805294 -345.823318)
			(xy 74.752952 -345.838685) (xy 74.698957 -345.846446) (xy 74.671682 -345.846908) (xy 73.808082 -345.846908)
			(xy 73.780817 -345.846328) (xy 73.726842 -345.838566) (xy 73.674521 -345.823201) (xy 73.624919 -345.800546)
			(xy 73.579045 -345.771063) (xy 73.537835 -345.735352) (xy 73.502126 -345.69414) (xy 73.472645 -345.648266)
			(xy 73.449993 -345.598663) (xy 73.434631 -345.546341) (xy 73.42687 -345.492365) (xy 71.944022 -345.492365)
			(xy 71.944022 -345.492372) (xy 71.936259 -345.54636) (xy 71.920893 -345.598694) (xy 71.898236 -345.648309)
			(xy 71.868749 -345.694194) (xy 71.833032 -345.735416) (xy 71.791812 -345.771136) (xy 71.745928 -345.800626)
			(xy 71.696315 -345.823286) (xy 71.643981 -345.838655) (xy 71.589994 -345.84642) (xy 71.562722 -345.846908)
			(xy 70.699122 -345.846908) (xy 70.671853 -345.846354) (xy 70.61787 -345.838595) (xy 70.565541 -345.823233)
			(xy 70.515932 -345.800579) (xy 70.470051 -345.771096) (xy 70.428833 -345.735383) (xy 70.393117 -345.694167)
			(xy 70.363631 -345.648288) (xy 70.340975 -345.598679) (xy 70.325609 -345.546351) (xy 70.317847 -345.492369)
			(xy 68.835144 -345.492369) (xy 68.835144 -345.492376) (xy 68.82738 -345.546373) (xy 68.81201 -345.598715)
			(xy 68.789347 -345.648336) (xy 68.759852 -345.694227) (xy 68.724127 -345.735453) (xy 68.682897 -345.771175)
			(xy 68.637003 -345.800665) (xy 68.587379 -345.823323) (xy 68.535036 -345.838688) (xy 68.481038 -345.846447)
			(xy 68.453762 -345.846908) (xy 67.590162 -345.846908) (xy 67.562898 -345.846327) (xy 67.508925 -345.838562)
			(xy 67.456606 -345.823195) (xy 67.407007 -345.80054) (xy 67.361136 -345.771056) (xy 67.319928 -345.735345)
			(xy 67.284221 -345.694134) (xy 67.254742 -345.64826) (xy 67.232092 -345.598658) (xy 67.21673 -345.546338)
			(xy 67.20897 -345.492364) (xy 65.726121 -345.492364) (xy 65.726121 -345.492373) (xy 65.718359 -345.546362)
			(xy 65.702992 -345.598698) (xy 65.680333 -345.648314) (xy 65.650844 -345.6942) (xy 65.615124 -345.735423)
			(xy 65.573902 -345.771143) (xy 65.528016 -345.800632) (xy 65.4784 -345.823291) (xy 65.426064 -345.838658)
			(xy 65.372075 -345.846421) (xy 65.344802 -345.846908) (xy 64.481202 -345.846908) (xy 64.453934 -345.846353)
			(xy 64.399954 -345.838592) (xy 64.347627 -345.823228) (xy 64.29802 -345.800573) (xy 64.252141 -345.771089)
			(xy 64.210926 -345.735376) (xy 64.175212 -345.69416) (xy 64.145728 -345.648282) (xy 64.123073 -345.598675)
			(xy 64.107709 -345.546348) (xy 64.099947 -345.492368) (xy 62.617122 -345.492368) (xy 62.617122 -345.492371)
			(xy 62.60936 -345.546357) (xy 62.593995 -345.59869) (xy 62.571339 -345.648303) (xy 62.541854 -345.694187)
			(xy 62.506139 -345.735409) (xy 62.464921 -345.771128) (xy 62.41904 -345.800619) (xy 62.369429 -345.82328)
			(xy 62.317098 -345.838651) (xy 62.263113 -345.846419) (xy 62.235842 -345.846908) (xy 61.372242 -345.846908)
			(xy 61.344972 -345.846355) (xy 61.290987 -345.838599) (xy 61.238656 -345.823238) (xy 61.189043 -345.800586)
			(xy 61.14316 -345.771103) (xy 61.10194 -345.73539) (xy 61.066222 -345.694174) (xy 61.036734 -345.648293)
			(xy 61.014076 -345.598683) (xy 60.99871 -345.546354) (xy 60.990948 -345.49237) (xy 51.666922 -345.49237)
			(xy 51.65916 -345.546356) (xy 51.643795 -345.598688) (xy 51.62114 -345.648301) (xy 51.591655 -345.694185)
			(xy 51.555941 -345.735407) (xy 51.514724 -345.771126) (xy 51.468843 -345.800617) (xy 51.419233 -345.823279)
			(xy 51.366903 -345.83865) (xy 51.312918 -345.846418) (xy 51.285648 -345.846908) (xy 50.422048 -345.846908)
			(xy 50.394778 -345.846356) (xy 50.340792 -345.8386) (xy 50.28846 -345.82324) (xy 50.238847 -345.800588)
			(xy 50.192963 -345.771105) (xy 50.151742 -345.735392) (xy 50.116024 -345.694176) (xy 50.086535 -345.648295)
			(xy 50.063877 -345.598685) (xy 50.04851 -345.546354) (xy 50.040748 -345.49237) (xy 48.558044 -345.49237)
			(xy 48.558044 -345.492375) (xy 48.550281 -345.546369) (xy 48.534912 -345.598709) (xy 48.512251 -345.648329)
			(xy 48.482759 -345.694219) (xy 48.447036 -345.735444) (xy 48.405809 -345.771166) (xy 48.359919 -345.800657)
			(xy 48.310298 -345.823316) (xy 48.257958 -345.838684) (xy 48.203963 -345.846445) (xy 48.176688 -345.846908)
			(xy 47.313088 -345.846908) (xy 47.285822 -345.846329) (xy 47.231847 -345.838567) (xy 47.179525 -345.823202)
			(xy 47.129922 -345.800548) (xy 47.084048 -345.771065) (xy 47.042837 -345.735354) (xy 47.007127 -345.694142)
			(xy 46.977646 -345.648267) (xy 46.954994 -345.598664) (xy 46.939631 -345.546342) (xy 46.93187 -345.492366)
			(xy 45.449022 -345.492366) (xy 45.449022 -345.492371) (xy 45.44126 -345.546359) (xy 45.425894 -345.598693)
			(xy 45.403237 -345.648307) (xy 45.37375 -345.694192) (xy 45.338034 -345.735414) (xy 45.296814 -345.771133)
			(xy 45.250932 -345.800624) (xy 45.201319 -345.823284) (xy 45.148986 -345.838654) (xy 45.094999 -345.84642)
			(xy 45.067728 -345.846908) (xy 44.204128 -345.846908) (xy 44.176859 -345.846355) (xy 44.122876 -345.838597)
			(xy 44.070546 -345.823235) (xy 44.020935 -345.800581) (xy 43.975053 -345.771098) (xy 43.933835 -345.735385)
			(xy 43.898119 -345.694169) (xy 43.868632 -345.648289) (xy 43.845975 -345.59868) (xy 43.830609 -345.546352)
			(xy 43.822847 -345.492369) (xy 42.340144 -345.492369) (xy 42.340144 -345.492376) (xy 42.33238 -345.546372)
			(xy 42.317011 -345.598713) (xy 42.294348 -345.648335) (xy 42.264854 -345.694225) (xy 42.229129 -345.735451)
			(xy 42.1879 -345.771173) (xy 42.142007 -345.800663) (xy 42.092383 -345.823322) (xy 42.040041 -345.838687)
			(xy 41.986044 -345.846447) (xy 41.958768 -345.846908) (xy 41.095168 -345.846908) (xy 41.067903 -345.846328)
			(xy 41.01393 -345.838563) (xy 40.96161 -345.823197) (xy 40.91201 -345.800542) (xy 40.866139 -345.771058)
			(xy 40.82493 -345.735347) (xy 40.789222 -345.694136) (xy 40.759743 -345.648262) (xy 40.737092 -345.59866)
			(xy 40.72173 -345.546339) (xy 40.71397 -345.492365) (xy 39.231121 -345.492365) (xy 39.231121 -345.492372)
			(xy 39.223359 -345.546362) (xy 39.207992 -345.598697) (xy 39.185334 -345.648312) (xy 39.155845 -345.694199)
			(xy 39.120127 -345.735421) (xy 39.078905 -345.77114) (xy 39.03302 -345.80063) (xy 38.983404 -345.82329)
			(xy 38.93107 -345.838657) (xy 38.87708 -345.846421) (xy 38.849808 -345.846908) (xy 37.986208 -345.846908)
			(xy 37.95894 -345.846353) (xy 37.904959 -345.838593) (xy 37.852631 -345.823229) (xy 37.803023 -345.800575)
			(xy 37.757144 -345.771091) (xy 37.715928 -345.735378) (xy 37.680214 -345.694162) (xy 37.650729 -345.648284)
			(xy 37.628074 -345.598676) (xy 37.612709 -345.546349) (xy 37.604947 -345.492368) (xy 36.122122 -345.492368)
			(xy 36.122122 -345.49237) (xy 36.11436 -345.546356) (xy 36.098995 -345.598688) (xy 36.07634 -345.648301)
			(xy 36.046855 -345.694185) (xy 36.011141 -345.735407) (xy 35.969924 -345.771126) (xy 35.924043 -345.800617)
			(xy 35.874433 -345.823279) (xy 35.822103 -345.83865) (xy 35.768118 -345.846418) (xy 35.740848 -345.846908)
			(xy 34.877248 -345.846908) (xy 34.849978 -345.846356) (xy 34.795992 -345.8386) (xy 34.74366 -345.82324)
			(xy 34.694047 -345.800588) (xy 34.648163 -345.771105) (xy 34.606942 -345.735392) (xy 34.571224 -345.694176)
			(xy 34.541735 -345.648295) (xy 34.519077 -345.598685) (xy 34.50371 -345.546354) (xy 34.495948 -345.49237)
			(xy 33.013244 -345.49237) (xy 33.013244 -345.492375) (xy 33.005481 -345.546369) (xy 32.990112 -345.598709)
			(xy 32.967451 -345.648329) (xy 32.937959 -345.694219) (xy 32.902236 -345.735444) (xy 32.861009 -345.771166)
			(xy 32.815119 -345.800657) (xy 32.765498 -345.823316) (xy 32.713158 -345.838684) (xy 32.659163 -345.846445)
			(xy 32.631888 -345.846908) (xy 31.768288 -345.846908) (xy 31.741022 -345.846329) (xy 31.687047 -345.838567)
			(xy 31.634725 -345.823202) (xy 31.585122 -345.800548) (xy 31.539248 -345.771065) (xy 31.498037 -345.735354)
			(xy 31.462327 -345.694142) (xy 31.432846 -345.648267) (xy 31.410194 -345.598664) (xy 31.394831 -345.546342)
			(xy 31.38707 -345.492366) (xy 29.904222 -345.492366) (xy 29.904222 -345.492371) (xy 29.89646 -345.546359)
			(xy 29.881094 -345.598693) (xy 29.858437 -345.648307) (xy 29.82895 -345.694192) (xy 29.793234 -345.735414)
			(xy 29.752014 -345.771133) (xy 29.706132 -345.800624) (xy 29.656519 -345.823284) (xy 29.604186 -345.838654)
			(xy 29.550199 -345.84642) (xy 29.522928 -345.846908) (xy 28.659328 -345.846908) (xy 28.632059 -345.846355)
			(xy 28.578076 -345.838597) (xy 28.525746 -345.823235) (xy 28.476135 -345.800581) (xy 28.430253 -345.771098)
			(xy 28.389035 -345.735385) (xy 28.353319 -345.694169) (xy 28.323832 -345.648289) (xy 28.301175 -345.59868)
			(xy 28.285809 -345.546352) (xy 28.278047 -345.492369) (xy 26.795344 -345.492369) (xy 26.795344 -345.492376)
			(xy 26.78758 -345.546372) (xy 26.772211 -345.598713) (xy 26.749548 -345.648335) (xy 26.720054 -345.694225)
			(xy 26.684329 -345.735451) (xy 26.6431 -345.771173) (xy 26.597207 -345.800663) (xy 26.547583 -345.823322)
			(xy 26.495241 -345.838687) (xy 26.441244 -345.846447) (xy 26.413968 -345.846908) (xy 25.550368 -345.846908)
			(xy 25.523103 -345.846328) (xy 25.46913 -345.838563) (xy 25.41681 -345.823197) (xy 25.36721 -345.800542)
			(xy 25.321339 -345.771058) (xy 25.28013 -345.735347) (xy 25.244422 -345.694136) (xy 25.214943 -345.648262)
			(xy 25.192292 -345.59866) (xy 25.17693 -345.546339) (xy 25.16917 -345.492365) (xy 23.686305 -345.492365)
			(xy 23.686305 -345.492421) (xy 23.678542 -345.546407) (xy 23.663176 -345.59874) (xy 23.640519 -345.648352)
			(xy 23.611031 -345.694236) (xy 23.575314 -345.735455) (xy 23.534094 -345.771172) (xy 23.488211 -345.80066)
			(xy 23.438598 -345.823317) (xy 23.386265 -345.838683) (xy 23.332279 -345.846445) (xy 23.305008 -345.846908)
			(xy 22.441408 -345.846908) (xy 22.414138 -345.846429) (xy 22.360154 -345.838667) (xy 22.307825 -345.823302)
			(xy 22.258214 -345.800645) (xy 22.212333 -345.771159) (xy 22.171115 -345.735443) (xy 22.1354 -345.694225)
			(xy 22.105914 -345.648344) (xy 22.083258 -345.598733) (xy 22.067892 -345.546404) (xy 22.06013 -345.49242)
			(xy 20.577345 -345.49242) (xy 20.577345 -345.492421) (xy 20.569582 -345.546407) (xy 20.554216 -345.59874)
			(xy 20.531559 -345.648352) (xy 20.502071 -345.694236) (xy 20.466354 -345.735455) (xy 20.425134 -345.771172)
			(xy 20.379251 -345.80066) (xy 20.329638 -345.823317) (xy 20.277305 -345.838683) (xy 20.223319 -345.846445)
			(xy 20.196048 -345.846908) (xy 19.332448 -345.846908) (xy 19.305178 -345.846429) (xy 19.251194 -345.838667)
			(xy 19.198865 -345.823302) (xy 19.149254 -345.800645) (xy 19.103373 -345.771159) (xy 19.062155 -345.735443)
			(xy 19.02644 -345.694225) (xy 18.996954 -345.648344) (xy 18.974298 -345.598733) (xy 18.958932 -345.546404)
			(xy 18.95117 -345.49242) (xy 0.509016 -345.49242) (xy 0.509016 -348.976496) (xy 4.708641 -348.976496)
			(xy 4.708641 -348.847356) (xy 4.716591 -348.718461) (xy 4.732461 -348.590301) (xy 4.75619 -348.46336)
			(xy 4.787689 -348.338121) (xy 4.826838 -348.215058) (xy 4.873489 -348.094639) (xy 4.927464 -347.97732)
			(xy 4.988559 -347.863546) (xy 5.056542 -347.753749) (xy 5.131156 -347.648346) (xy 5.212117 -347.547736)
			(xy 5.299117 -347.452301) (xy 5.391828 -347.362402) (xy 5.489898 -347.278381) (xy 5.592953 -347.200557)
			(xy 5.700604 -347.129225) (xy 5.812443 -347.064655) (xy 5.928044 -347.007093) (xy 6.046969 -346.956756)
			(xy 6.168768 -346.913836) (xy 6.292978 -346.878495) (xy 6.419127 -346.850868) (xy 6.546739 -346.831059)
			(xy 6.675328 -346.819143) (xy 6.804406 -346.815167) (xy 6.933484 -346.819143) (xy 7.062073 -346.831059)
			(xy 7.189685 -346.850868) (xy 7.315834 -346.878495) (xy 7.440044 -346.913836) (xy 7.451736 -346.917956)
			(xy 245.50903 -346.917956) (xy 245.50903 -346.83326) (xy 245.517081 -346.748946) (xy 245.53311 -346.66578)
			(xy 245.556971 -346.584513) (xy 245.58845 -346.505883) (xy 245.627261 -346.430602) (xy 245.673051 -346.35935)
			(xy 245.725407 -346.292774) (xy 245.783855 -346.231476) (xy 245.847865 -346.176011) (xy 245.916857 -346.126882)
			(xy 245.990207 -346.084533) (xy 246.06725 -346.049349) (xy 246.147289 -346.021647) (xy 246.229598 -346.001679)
			(xy 246.313433 -345.989626) (xy 246.398034 -345.985596) (xy 246.482635 -345.989626) (xy 246.56647 -346.001679)
			(xy 246.648779 -346.021647) (xy 246.728818 -346.049349) (xy 246.805861 -346.084533) (xy 246.879211 -346.126882)
			(xy 246.948203 -346.176011) (xy 247.012213 -346.231476) (xy 247.070661 -346.292774) (xy 247.123017 -346.35935)
			(xy 247.168807 -346.430602) (xy 247.207618 -346.505883) (xy 247.239097 -346.584513) (xy 247.262958 -346.66578)
			(xy 247.278987 -346.748946) (xy 247.287038 -346.83326) (xy 247.287542 -346.875608) (xy 247.287038 -346.917956)
			(xy 247.278987 -347.00227) (xy 247.262958 -347.085436) (xy 247.239097 -347.166703) (xy 247.207618 -347.245333)
			(xy 247.168807 -347.320614) (xy 247.123017 -347.391866) (xy 247.070661 -347.458442) (xy 247.012213 -347.51974)
			(xy 246.948203 -347.575205) (xy 246.879211 -347.624334) (xy 246.805861 -347.666683) (xy 246.728818 -347.701867)
			(xy 246.648779 -347.729569) (xy 246.56647 -347.749537) (xy 246.482635 -347.76159) (xy 246.398034 -347.765621)
			(xy 246.313433 -347.76159) (xy 246.229598 -347.749537) (xy 246.147289 -347.729569) (xy 246.06725 -347.701867)
			(xy 245.990207 -347.666683) (xy 245.916857 -347.624334) (xy 245.847865 -347.575205) (xy 245.783855 -347.51974)
			(xy 245.725407 -347.458442) (xy 245.673051 -347.391866) (xy 245.627261 -347.320614) (xy 245.58845 -347.245333)
			(xy 245.556971 -347.166703) (xy 245.53311 -347.085436) (xy 245.517081 -347.00227) (xy 245.50903 -346.917956)
			(xy 7.451736 -346.917956) (xy 7.561843 -346.956756) (xy 7.680768 -347.007093) (xy 7.796369 -347.064655)
			(xy 7.908208 -347.129225) (xy 8.015859 -347.200557) (xy 8.118914 -347.278381) (xy 8.216984 -347.362402)
			(xy 8.309695 -347.452301) (xy 8.396695 -347.547736) (xy 8.477656 -347.648346) (xy 8.55227 -347.753749)
			(xy 8.620253 -347.863546) (xy 8.681348 -347.97732) (xy 8.735323 -348.094639) (xy 8.781974 -348.215058)
			(xy 8.821123 -348.338121) (xy 8.852622 -348.46336) (xy 8.876351 -348.590301) (xy 8.879169 -348.613059)
			(xy 18.951174 -348.613059) (xy 18.951174 -348.558521) (xy 18.958936 -348.504537) (xy 18.974301 -348.452208)
			(xy 18.996957 -348.402598) (xy 19.026443 -348.356717) (xy 19.062158 -348.315499) (xy 19.103375 -348.279784)
			(xy 19.149256 -348.250298) (xy 19.198866 -348.227642) (xy 19.251195 -348.212276) (xy 19.305179 -348.204515)
			(xy 19.332448 -348.204028) (xy 20.196048 -348.204028) (xy 20.223319 -348.204491) (xy 20.277306 -348.212253)
			(xy 20.329639 -348.227619) (xy 20.379253 -348.250277) (xy 20.425136 -348.279764) (xy 20.466357 -348.315482)
			(xy 20.502074 -348.356702) (xy 20.531562 -348.402586) (xy 20.55422 -348.452199) (xy 20.569586 -348.504532)
			(xy 20.577349 -348.558519) (xy 20.577349 -348.613061) (xy 20.577347 -348.613072) (xy 22.060092 -348.613072)
			(xy 22.060092 -348.558528) (xy 22.067854 -348.504539) (xy 22.083221 -348.452204) (xy 22.10588 -348.402589)
			(xy 22.135369 -348.356704) (xy 22.171088 -348.315483) (xy 22.21231 -348.279764) (xy 22.258196 -348.250276)
			(xy 22.307812 -348.227618) (xy 22.360147 -348.212252) (xy 22.414136 -348.204491) (xy 22.441408 -348.204028)
			(xy 23.305008 -348.204028) (xy 23.332276 -348.204535) (xy 23.386258 -348.212297) (xy 23.438585 -348.227663)
			(xy 23.488193 -348.250319) (xy 23.534071 -348.279804) (xy 23.575287 -348.315519) (xy 23.611 -348.356735)
			(xy 23.640485 -348.402614) (xy 23.66314 -348.452223) (xy 23.678504 -348.50455) (xy 23.686266 -348.558532)
			(xy 23.686266 -348.613068) (xy 23.686266 -348.613069) (xy 25.169114 -348.613069) (xy 25.169114 -348.558531)
			(xy 25.176875 -348.504549) (xy 25.19224 -348.452221) (xy 25.214894 -348.402611) (xy 25.244378 -348.356731)
			(xy 25.28009 -348.315513) (xy 25.321305 -348.279797) (xy 25.367183 -348.250309) (xy 25.416791 -348.227651)
			(xy 25.469118 -348.212282) (xy 25.523099 -348.204517) (xy 25.550368 -348.204028) (xy 26.413968 -348.204028)
			(xy 26.44124 -348.204509) (xy 26.495229 -348.212268) (xy 26.547564 -348.227631) (xy 26.59718 -348.250286)
			(xy 26.643066 -348.279772) (xy 26.684289 -348.315488) (xy 26.720009 -348.356708) (xy 26.749499 -348.402592)
			(xy 26.772158 -348.452206) (xy 26.787526 -348.50454) (xy 26.795288 -348.558528) (xy 26.795288 -348.613072)
			(xy 26.795288 -348.613073) (xy 28.277992 -348.613073) (xy 28.277992 -348.558527) (xy 28.285755 -348.504536)
			(xy 28.301123 -348.4522) (xy 28.323783 -348.402584) (xy 28.353274 -348.356697) (xy 28.388995 -348.315476)
			(xy 28.43022 -348.279757) (xy 28.476108 -348.25027) (xy 28.525726 -348.227613) (xy 28.578064 -348.212249)
			(xy 28.632055 -348.20449) (xy 28.659328 -348.204028) (xy 29.522928 -348.204028) (xy 29.550195 -348.204536)
			(xy 29.604175 -348.212301) (xy 29.656499 -348.227668) (xy 29.706105 -348.250326) (xy 29.751981 -348.279811)
			(xy 29.793194 -348.315526) (xy 29.828905 -348.356742) (xy 29.858388 -348.40262) (xy 29.881041 -348.452227)
			(xy 29.896405 -348.504553) (xy 29.904166 -348.558533) (xy 29.904166 -348.613067) (xy 29.904166 -348.61307)
			(xy 31.387014 -348.61307) (xy 31.387014 -348.55853) (xy 31.394776 -348.504546) (xy 31.410141 -348.452217)
			(xy 31.432797 -348.402606) (xy 31.462283 -348.356724) (xy 31.497997 -348.315506) (xy 31.539215 -348.27979)
			(xy 31.585095 -348.250303) (xy 31.634705 -348.227645) (xy 31.687035 -348.212279) (xy 31.741018 -348.204515)
			(xy 31.768288 -348.204028) (xy 32.631888 -348.204028) (xy 32.659159 -348.204511) (xy 32.713146 -348.212271)
			(xy 32.765478 -348.227636) (xy 32.815092 -348.250292) (xy 32.860976 -348.279779) (xy 32.902196 -348.315495)
			(xy 32.937914 -348.356715) (xy 32.967402 -348.402598) (xy 32.99006 -348.45221) (xy 33.005426 -348.504543)
			(xy 33.013189 -348.558529) (xy 33.013189 -348.613071) (xy 33.013189 -348.613074) (xy 34.495892 -348.613074)
			(xy 34.495892 -348.558526) (xy 34.503655 -348.504534) (xy 34.519024 -348.452196) (xy 34.541686 -348.402578)
			(xy 34.571179 -348.356691) (xy 34.606902 -348.315468) (xy 34.648129 -348.27975) (xy 34.69402 -348.250263)
			(xy 34.743641 -348.227608) (xy 34.795981 -348.212245) (xy 34.849974 -348.204488) (xy 34.877248 -348.204028)
			(xy 35.740848 -348.204028) (xy 35.768114 -348.204538) (xy 35.822091 -348.212305) (xy 35.874414 -348.227674)
			(xy 35.924017 -348.250332) (xy 35.96989 -348.279819) (xy 36.011101 -348.315533) (xy 36.04681 -348.356748)
			(xy 36.076291 -348.402626) (xy 36.098943 -348.452231) (xy 36.114306 -348.504556) (xy 36.122066 -348.558534)
			(xy 36.122066 -348.613066) (xy 36.122065 -348.613072) (xy 37.604892 -348.613072) (xy 37.604892 -348.558528)
			(xy 37.612654 -348.504539) (xy 37.628021 -348.452204) (xy 37.65068 -348.402589) (xy 37.680169 -348.356704)
			(xy 37.715888 -348.315483) (xy 37.75711 -348.279764) (xy 37.802996 -348.250276) (xy 37.852612 -348.227618)
			(xy 37.904947 -348.212252) (xy 37.958936 -348.204491) (xy 37.986208 -348.204028) (xy 38.849808 -348.204028)
			(xy 38.877076 -348.204535) (xy 38.931058 -348.212297) (xy 38.983385 -348.227663) (xy 39.032993 -348.250319)
			(xy 39.078871 -348.279804) (xy 39.120087 -348.315519) (xy 39.1558 -348.356735) (xy 39.185285 -348.402614)
			(xy 39.20794 -348.452223) (xy 39.223304 -348.50455) (xy 39.231066 -348.558532) (xy 39.231066 -348.613068)
			(xy 39.231066 -348.613069) (xy 40.713914 -348.613069) (xy 40.713914 -348.558531) (xy 40.721675 -348.504549)
			(xy 40.73704 -348.452221) (xy 40.759694 -348.402611) (xy 40.789178 -348.356731) (xy 40.82489 -348.315513)
			(xy 40.866105 -348.279797) (xy 40.911983 -348.250309) (xy 40.961591 -348.227651) (xy 41.013918 -348.212282)
			(xy 41.067899 -348.204517) (xy 41.095168 -348.204028) (xy 41.958768 -348.204028) (xy 41.98604 -348.204509)
			(xy 42.040029 -348.212268) (xy 42.092364 -348.227631) (xy 42.14198 -348.250286) (xy 42.187866 -348.279772)
			(xy 42.229089 -348.315488) (xy 42.264809 -348.356708) (xy 42.294299 -348.402592) (xy 42.316958 -348.452206)
			(xy 42.332326 -348.50454) (xy 42.340088 -348.558528) (xy 42.340088 -348.613072) (xy 42.340088 -348.613073)
			(xy 43.822792 -348.613073) (xy 43.822792 -348.558527) (xy 43.830555 -348.504536) (xy 43.845923 -348.4522)
			(xy 43.868583 -348.402584) (xy 43.898074 -348.356697) (xy 43.933795 -348.315476) (xy 43.97502 -348.279757)
			(xy 44.020908 -348.25027) (xy 44.070526 -348.227613) (xy 44.122864 -348.212249) (xy 44.176855 -348.20449)
			(xy 44.204128 -348.204028) (xy 45.067728 -348.204028) (xy 45.094995 -348.204536) (xy 45.148975 -348.212301)
			(xy 45.201299 -348.227668) (xy 45.250905 -348.250326) (xy 45.296781 -348.279811) (xy 45.337994 -348.315526)
			(xy 45.373705 -348.356742) (xy 45.403188 -348.40262) (xy 45.425841 -348.452227) (xy 45.441205 -348.504553)
			(xy 45.448966 -348.558533) (xy 45.448966 -348.613067) (xy 45.448966 -348.61307) (xy 46.931814 -348.61307)
			(xy 46.931814 -348.55853) (xy 46.939576 -348.504546) (xy 46.954941 -348.452217) (xy 46.977597 -348.402606)
			(xy 47.007083 -348.356724) (xy 47.042797 -348.315506) (xy 47.084015 -348.27979) (xy 47.129895 -348.250303)
			(xy 47.179505 -348.227645) (xy 47.231835 -348.212279) (xy 47.285818 -348.204515) (xy 47.313088 -348.204028)
			(xy 48.176688 -348.204028) (xy 48.203959 -348.204511) (xy 48.257946 -348.212271) (xy 48.310278 -348.227636)
			(xy 48.359892 -348.250292) (xy 48.405776 -348.279779) (xy 48.446996 -348.315495) (xy 48.482714 -348.356715)
			(xy 48.512202 -348.402598) (xy 48.53486 -348.45221) (xy 48.550226 -348.504543) (xy 48.557989 -348.558529)
			(xy 48.557989 -348.613071) (xy 48.557989 -348.613074) (xy 50.040692 -348.613074) (xy 50.040692 -348.558526)
			(xy 50.048455 -348.504534) (xy 50.063824 -348.452196) (xy 50.086486 -348.402578) (xy 50.115979 -348.356691)
			(xy 50.151702 -348.315468) (xy 50.192929 -348.27975) (xy 50.23882 -348.250263) (xy 50.288441 -348.227608)
			(xy 50.340781 -348.212245) (xy 50.394774 -348.204488) (xy 50.422048 -348.204028) (xy 51.285648 -348.204028)
			(xy 51.312914 -348.204538) (xy 51.366891 -348.212305) (xy 51.419214 -348.227674) (xy 51.468817 -348.250332)
			(xy 51.51469 -348.279819) (xy 51.555901 -348.315533) (xy 51.59161 -348.356748) (xy 51.621091 -348.402626)
			(xy 51.643743 -348.452231) (xy 51.659106 -348.504556) (xy 51.666866 -348.558534) (xy 51.666866 -348.613066)
			(xy 51.666865 -348.613074) (xy 60.990892 -348.613074) (xy 60.990892 -348.558526) (xy 60.998655 -348.504534)
			(xy 61.014024 -348.452197) (xy 61.036685 -348.40258) (xy 61.066177 -348.356693) (xy 61.1019 -348.315471)
			(xy 61.143127 -348.279752) (xy 61.189017 -348.250265) (xy 61.238636 -348.227609) (xy 61.290976 -348.212246)
			(xy 61.344968 -348.204489) (xy 61.372242 -348.204028) (xy 62.235842 -348.204028) (xy 62.263109 -348.204537)
			(xy 62.317086 -348.212304) (xy 62.369409 -348.227672) (xy 62.419013 -348.25033) (xy 62.464887 -348.279816)
			(xy 62.506099 -348.315531) (xy 62.541809 -348.356746) (xy 62.57129 -348.402624) (xy 62.593943 -348.45223)
			(xy 62.609305 -348.504555) (xy 62.617066 -348.558533) (xy 62.617066 -348.613067) (xy 62.617065 -348.613072)
			(xy 64.099892 -348.613072) (xy 64.099892 -348.558528) (xy 64.107654 -348.50454) (xy 64.123021 -348.452206)
			(xy 64.145679 -348.402591) (xy 64.175168 -348.356706) (xy 64.210886 -348.315485) (xy 64.252108 -348.279766)
			(xy 64.297993 -348.250278) (xy 64.347607 -348.22762) (xy 64.399942 -348.212253) (xy 64.45393 -348.204491)
			(xy 64.481202 -348.204028) (xy 65.344802 -348.204028) (xy 65.372071 -348.204535) (xy 65.426053 -348.212296)
			(xy 65.47838 -348.227661) (xy 65.527989 -348.250317) (xy 65.573869 -348.279802) (xy 65.615085 -348.315517)
			(xy 65.650799 -348.356733) (xy 65.680284 -348.402613) (xy 65.702939 -348.452221) (xy 65.718304 -348.504549)
			(xy 65.726066 -348.558531) (xy 65.726066 -348.613068) (xy 67.208914 -348.613068) (xy 67.208914 -348.558532)
			(xy 67.216675 -348.50455) (xy 67.232039 -348.452222) (xy 67.254693 -348.402613) (xy 67.284176 -348.356733)
			(xy 67.319888 -348.315515) (xy 67.361102 -348.279799) (xy 67.40698 -348.250311) (xy 67.456586 -348.227652)
			(xy 67.508913 -348.212283) (xy 67.562894 -348.204517) (xy 67.590162 -348.204028) (xy 68.453762 -348.204028)
			(xy 68.481034 -348.204509) (xy 68.535024 -348.212266) (xy 68.58736 -348.227629) (xy 68.636976 -348.250284)
			(xy 68.682863 -348.27977) (xy 68.724087 -348.315486) (xy 68.759808 -348.356706) (xy 68.789298 -348.40259)
			(xy 68.811958 -348.452205) (xy 68.827326 -348.504539) (xy 68.835088 -348.558528) (xy 68.835088 -348.613072)
			(xy 68.835088 -348.613073) (xy 70.317792 -348.613073) (xy 70.317792 -348.558527) (xy 70.325554 -348.504537)
			(xy 70.340922 -348.452201) (xy 70.363582 -348.402585) (xy 70.393072 -348.356699) (xy 70.428793 -348.315478)
			(xy 70.470017 -348.279759) (xy 70.515905 -348.250271) (xy 70.565522 -348.227615) (xy 70.617859 -348.21225)
			(xy 70.671849 -348.20449) (xy 70.699122 -348.204028) (xy 71.562722 -348.204028) (xy 71.58999 -348.204536)
			(xy 71.643969 -348.2123) (xy 71.696295 -348.227667) (xy 71.745901 -348.250324) (xy 71.791778 -348.279809)
			(xy 71.832992 -348.315524) (xy 71.868704 -348.35674) (xy 71.898187 -348.402618) (xy 71.920841 -348.452226)
			(xy 71.936205 -348.504552) (xy 71.943966 -348.558532) (xy 71.943966 -348.613068) (xy 71.943966 -348.613069)
			(xy 73.426814 -348.613069) (xy 73.426814 -348.558531) (xy 73.434576 -348.504547) (xy 73.449941 -348.452218)
			(xy 73.472596 -348.402608) (xy 73.502081 -348.356726) (xy 73.537795 -348.315508) (xy 73.579012 -348.279792)
			(xy 73.624892 -348.250305) (xy 73.674501 -348.227647) (xy 73.72683 -348.21228) (xy 73.780813 -348.204516)
			(xy 73.808082 -348.204028) (xy 74.671682 -348.204028) (xy 74.698953 -348.20451) (xy 74.752941 -348.21227)
			(xy 74.805274 -348.227634) (xy 74.854888 -348.25029) (xy 74.900773 -348.279777) (xy 74.941994 -348.315493)
			(xy 74.977712 -348.356713) (xy 75.007201 -348.402596) (xy 75.029859 -348.452209) (xy 75.045226 -348.504542)
			(xy 75.052988 -348.558529) (xy 75.052988 -348.613071) (xy 75.052988 -348.613074) (xy 76.535692 -348.613074)
			(xy 76.535692 -348.558526) (xy 76.543455 -348.504534) (xy 76.558824 -348.452197) (xy 76.581485 -348.40258)
			(xy 76.610977 -348.356693) (xy 76.6467 -348.315471) (xy 76.687927 -348.279752) (xy 76.733817 -348.250265)
			(xy 76.783436 -348.227609) (xy 76.835776 -348.212246) (xy 76.889768 -348.204489) (xy 76.917042 -348.204028)
			(xy 77.780642 -348.204028) (xy 77.807909 -348.204537) (xy 77.861886 -348.212304) (xy 77.914209 -348.227672)
			(xy 77.963813 -348.25033) (xy 78.009687 -348.279816) (xy 78.050899 -348.315531) (xy 78.086609 -348.356746)
			(xy 78.11609 -348.402624) (xy 78.138743 -348.45223) (xy 78.154105 -348.504555) (xy 78.161866 -348.558533)
			(xy 78.161866 -348.613067) (xy 78.161865 -348.613072) (xy 79.644692 -348.613072) (xy 79.644692 -348.558528)
			(xy 79.652454 -348.50454) (xy 79.667821 -348.452206) (xy 79.690479 -348.402591) (xy 79.719968 -348.356706)
			(xy 79.755686 -348.315485) (xy 79.796908 -348.279766) (xy 79.842793 -348.250278) (xy 79.892407 -348.22762)
			(xy 79.944742 -348.212253) (xy 79.99873 -348.204491) (xy 80.026002 -348.204028) (xy 80.889602 -348.204028)
			(xy 80.916871 -348.204535) (xy 80.970853 -348.212296) (xy 81.02318 -348.227661) (xy 81.072789 -348.250317)
			(xy 81.118669 -348.279802) (xy 81.159885 -348.315517) (xy 81.195599 -348.356733) (xy 81.225084 -348.402613)
			(xy 81.247739 -348.452221) (xy 81.263104 -348.504549) (xy 81.270866 -348.558531) (xy 81.270866 -348.613068)
			(xy 82.753714 -348.613068) (xy 82.753714 -348.558532) (xy 82.761475 -348.50455) (xy 82.776839 -348.452222)
			(xy 82.799493 -348.402613) (xy 82.828976 -348.356733) (xy 82.864688 -348.315515) (xy 82.905902 -348.279799)
			(xy 82.95178 -348.250311) (xy 83.001386 -348.227652) (xy 83.053713 -348.212283) (xy 83.107694 -348.204517)
			(xy 83.134962 -348.204028) (xy 83.998562 -348.204028) (xy 84.025834 -348.204509) (xy 84.079824 -348.212266)
			(xy 84.13216 -348.227629) (xy 84.181776 -348.250284) (xy 84.227663 -348.27977) (xy 84.268887 -348.315486)
			(xy 84.304608 -348.356706) (xy 84.334098 -348.40259) (xy 84.356758 -348.452205) (xy 84.372126 -348.504539)
			(xy 84.379888 -348.558528) (xy 84.379888 -348.613072) (xy 84.379888 -348.613073) (xy 85.862592 -348.613073)
			(xy 85.862592 -348.558527) (xy 85.870354 -348.504537) (xy 85.885722 -348.452201) (xy 85.908382 -348.402585)
			(xy 85.937872 -348.356699) (xy 85.973593 -348.315478) (xy 86.014817 -348.279759) (xy 86.060705 -348.250271)
			(xy 86.110322 -348.227615) (xy 86.162659 -348.21225) (xy 86.216649 -348.20449) (xy 86.243922 -348.204028)
			(xy 87.107522 -348.204028) (xy 87.13479 -348.204536) (xy 87.188769 -348.2123) (xy 87.241095 -348.227667)
			(xy 87.290701 -348.250324) (xy 87.336578 -348.279809) (xy 87.377792 -348.315524) (xy 87.413504 -348.35674)
			(xy 87.442987 -348.402618) (xy 87.465641 -348.452226) (xy 87.481005 -348.504552) (xy 87.488766 -348.558532)
			(xy 87.488766 -348.613068) (xy 87.488766 -348.613069) (xy 88.971614 -348.613069) (xy 88.971614 -348.558531)
			(xy 88.979376 -348.504547) (xy 88.994741 -348.452218) (xy 89.017396 -348.402608) (xy 89.046881 -348.356726)
			(xy 89.082595 -348.315508) (xy 89.123812 -348.279792) (xy 89.169692 -348.250305) (xy 89.219301 -348.227647)
			(xy 89.27163 -348.21228) (xy 89.325613 -348.204516) (xy 89.352882 -348.204028) (xy 90.216482 -348.204028)
			(xy 90.243753 -348.20451) (xy 90.297741 -348.21227) (xy 90.350074 -348.227634) (xy 90.399688 -348.25029)
			(xy 90.445573 -348.279777) (xy 90.486794 -348.315493) (xy 90.522512 -348.356713) (xy 90.552001 -348.402596)
			(xy 90.574659 -348.452209) (xy 90.590026 -348.504542) (xy 90.597788 -348.558529) (xy 90.597788 -348.613071)
			(xy 90.597788 -348.613074) (xy 92.080492 -348.613074) (xy 92.080492 -348.558526) (xy 92.088255 -348.504534)
			(xy 92.103624 -348.452197) (xy 92.126285 -348.40258) (xy 92.155777 -348.356693) (xy 92.1915 -348.315471)
			(xy 92.232727 -348.279752) (xy 92.278617 -348.250265) (xy 92.328236 -348.227609) (xy 92.380576 -348.212246)
			(xy 92.434568 -348.204489) (xy 92.461842 -348.204028) (xy 93.325442 -348.204028) (xy 93.352709 -348.204537)
			(xy 93.406686 -348.212304) (xy 93.459009 -348.227672) (xy 93.508613 -348.25033) (xy 93.554487 -348.279816)
			(xy 93.595699 -348.315531) (xy 93.631409 -348.356746) (xy 93.66089 -348.402624) (xy 93.683543 -348.45223)
			(xy 93.698905 -348.504555) (xy 93.706666 -348.558533) (xy 93.706666 -348.613067) (xy 93.706665 -348.613072)
			(xy 111.480792 -348.613072) (xy 111.480792 -348.558528) (xy 111.488554 -348.504539) (xy 111.503921 -348.452204)
			(xy 111.52658 -348.402589) (xy 111.556069 -348.356704) (xy 111.591788 -348.315483) (xy 111.63301 -348.279764)
			(xy 111.678896 -348.250276) (xy 111.728512 -348.227618) (xy 111.780847 -348.212252) (xy 111.834836 -348.204491)
			(xy 111.862108 -348.204028) (xy 112.725708 -348.204028) (xy 112.752976 -348.204535) (xy 112.806958 -348.212297)
			(xy 112.859285 -348.227663) (xy 112.908893 -348.250319) (xy 112.954771 -348.279804) (xy 112.995987 -348.315519)
			(xy 113.0317 -348.356735) (xy 113.061185 -348.402614) (xy 113.08384 -348.452223) (xy 113.099204 -348.50455)
			(xy 113.106966 -348.558532) (xy 113.106966 -348.613068) (xy 113.106966 -348.613069) (xy 114.589814 -348.613069)
			(xy 114.589814 -348.558531) (xy 114.597575 -348.504549) (xy 114.61294 -348.452221) (xy 114.635594 -348.402611)
			(xy 114.665078 -348.356731) (xy 114.70079 -348.315513) (xy 114.742005 -348.279797) (xy 114.787883 -348.250309)
			(xy 114.837491 -348.227651) (xy 114.889818 -348.212282) (xy 114.943799 -348.204517) (xy 114.971068 -348.204028)
			(xy 115.834668 -348.204028) (xy 115.86194 -348.204509) (xy 115.915929 -348.212268) (xy 115.968264 -348.227631)
			(xy 116.01788 -348.250286) (xy 116.063766 -348.279772) (xy 116.104989 -348.315488) (xy 116.140709 -348.356708)
			(xy 116.170199 -348.402592) (xy 116.192858 -348.452206) (xy 116.208226 -348.50454) (xy 116.215988 -348.558528)
			(xy 116.215988 -348.613072) (xy 116.215988 -348.613073) (xy 117.698692 -348.613073) (xy 117.698692 -348.558527)
			(xy 117.706455 -348.504536) (xy 117.721823 -348.4522) (xy 117.744483 -348.402584) (xy 117.773974 -348.356697)
			(xy 117.809695 -348.315476) (xy 117.85092 -348.279757) (xy 117.896808 -348.25027) (xy 117.946426 -348.227613)
			(xy 117.998764 -348.212249) (xy 118.052755 -348.20449) (xy 118.080028 -348.204028) (xy 118.943628 -348.204028)
			(xy 118.970895 -348.204536) (xy 119.024875 -348.212301) (xy 119.077199 -348.227668) (xy 119.126805 -348.250326)
			(xy 119.172681 -348.279811) (xy 119.213894 -348.315526) (xy 119.249605 -348.356742) (xy 119.279088 -348.40262)
			(xy 119.301741 -348.452227) (xy 119.317105 -348.504553) (xy 119.324866 -348.558533) (xy 119.324866 -348.613067)
			(xy 119.324866 -348.61307) (xy 120.807714 -348.61307) (xy 120.807714 -348.55853) (xy 120.815476 -348.504546)
			(xy 120.830841 -348.452217) (xy 120.853497 -348.402606) (xy 120.882983 -348.356724) (xy 120.918697 -348.315506)
			(xy 120.959915 -348.27979) (xy 121.005795 -348.250303) (xy 121.055405 -348.227645) (xy 121.107735 -348.212279)
			(xy 121.161718 -348.204515) (xy 121.188988 -348.204028) (xy 122.052588 -348.204028) (xy 122.079859 -348.204511)
			(xy 122.133846 -348.212271) (xy 122.186178 -348.227636) (xy 122.235792 -348.250292) (xy 122.281676 -348.279779)
			(xy 122.322896 -348.315495) (xy 122.358614 -348.356715) (xy 122.388102 -348.402598) (xy 122.41076 -348.45221)
			(xy 122.426126 -348.504543) (xy 122.433889 -348.558529) (xy 122.433889 -348.613071) (xy 122.433889 -348.613074)
			(xy 123.916592 -348.613074) (xy 123.916592 -348.558526) (xy 123.924355 -348.504534) (xy 123.939724 -348.452196)
			(xy 123.962386 -348.402578) (xy 123.991879 -348.356691) (xy 124.027602 -348.315468) (xy 124.068829 -348.27975)
			(xy 124.11472 -348.250263) (xy 124.164341 -348.227608) (xy 124.216681 -348.212245) (xy 124.270674 -348.204488)
			(xy 124.297948 -348.204028) (xy 125.161548 -348.204028) (xy 125.188814 -348.204538) (xy 125.242791 -348.212305)
			(xy 125.295114 -348.227674) (xy 125.344717 -348.250332) (xy 125.39059 -348.279819) (xy 125.431801 -348.315533)
			(xy 125.46751 -348.356748) (xy 125.496991 -348.402626) (xy 125.519643 -348.452231) (xy 125.535006 -348.504556)
			(xy 125.542766 -348.558534) (xy 125.542766 -348.613066) (xy 125.542765 -348.613072) (xy 127.025592 -348.613072)
			(xy 127.025592 -348.558528) (xy 127.033354 -348.504539) (xy 127.048721 -348.452204) (xy 127.07138 -348.402589)
			(xy 127.100869 -348.356704) (xy 127.136588 -348.315483) (xy 127.17781 -348.279764) (xy 127.223696 -348.250276)
			(xy 127.273312 -348.227618) (xy 127.325647 -348.212252) (xy 127.379636 -348.204491) (xy 127.406908 -348.204028)
			(xy 128.270508 -348.204028) (xy 128.297776 -348.204535) (xy 128.351758 -348.212297) (xy 128.404085 -348.227663)
			(xy 128.453693 -348.250319) (xy 128.499571 -348.279804) (xy 128.540787 -348.315519) (xy 128.5765 -348.356735)
			(xy 128.605985 -348.402614) (xy 128.62864 -348.452223) (xy 128.644004 -348.50455) (xy 128.651766 -348.558532)
			(xy 128.651766 -348.613068) (xy 128.651766 -348.613069) (xy 130.134614 -348.613069) (xy 130.134614 -348.558531)
			(xy 130.142375 -348.504549) (xy 130.15774 -348.452221) (xy 130.180394 -348.402611) (xy 130.209878 -348.356731)
			(xy 130.24559 -348.315513) (xy 130.286805 -348.279797) (xy 130.332683 -348.250309) (xy 130.382291 -348.227651)
			(xy 130.434618 -348.212282) (xy 130.488599 -348.204517) (xy 130.515868 -348.204028) (xy 131.379468 -348.204028)
			(xy 131.40674 -348.204509) (xy 131.460729 -348.212268) (xy 131.513064 -348.227631) (xy 131.56268 -348.250286)
			(xy 131.608566 -348.279772) (xy 131.649789 -348.315488) (xy 131.685509 -348.356708) (xy 131.714999 -348.402592)
			(xy 131.737658 -348.452206) (xy 131.753026 -348.50454) (xy 131.760788 -348.558528) (xy 131.760788 -348.613072)
			(xy 131.760788 -348.613073) (xy 133.243492 -348.613073) (xy 133.243492 -348.558527) (xy 133.251255 -348.504536)
			(xy 133.266623 -348.4522) (xy 133.289283 -348.402584) (xy 133.318774 -348.356697) (xy 133.354495 -348.315476)
			(xy 133.39572 -348.279757) (xy 133.441608 -348.25027) (xy 133.491226 -348.227613) (xy 133.543564 -348.212249)
			(xy 133.597555 -348.20449) (xy 133.624828 -348.204028) (xy 134.488428 -348.204028) (xy 134.515695 -348.204536)
			(xy 134.569675 -348.212301) (xy 134.621999 -348.227668) (xy 134.671605 -348.250326) (xy 134.717481 -348.279811)
			(xy 134.758694 -348.315526) (xy 134.794405 -348.356742) (xy 134.823888 -348.40262) (xy 134.846541 -348.452227)
			(xy 134.861905 -348.504553) (xy 134.869666 -348.558533) (xy 134.869666 -348.613067) (xy 134.869666 -348.61307)
			(xy 136.352514 -348.61307) (xy 136.352514 -348.55853) (xy 136.360276 -348.504546) (xy 136.375641 -348.452217)
			(xy 136.398297 -348.402606) (xy 136.427783 -348.356724) (xy 136.463497 -348.315506) (xy 136.504715 -348.27979)
			(xy 136.550595 -348.250303) (xy 136.600205 -348.227645) (xy 136.652535 -348.212279) (xy 136.706518 -348.204515)
			(xy 136.733788 -348.204028) (xy 137.597388 -348.204028) (xy 137.624659 -348.204511) (xy 137.678646 -348.212271)
			(xy 137.730978 -348.227636) (xy 137.780592 -348.250292) (xy 137.826476 -348.279779) (xy 137.867696 -348.315495)
			(xy 137.903414 -348.356715) (xy 137.932902 -348.402598) (xy 137.95556 -348.45221) (xy 137.970926 -348.504543)
			(xy 137.978689 -348.558529) (xy 137.978689 -348.613071) (xy 137.978689 -348.613074) (xy 139.461392 -348.613074)
			(xy 139.461392 -348.558526) (xy 139.469155 -348.504534) (xy 139.484524 -348.452196) (xy 139.507186 -348.402578)
			(xy 139.536679 -348.356691) (xy 139.572402 -348.315468) (xy 139.613629 -348.27975) (xy 139.65952 -348.250263)
			(xy 139.709141 -348.227608) (xy 139.761481 -348.212245) (xy 139.815474 -348.204488) (xy 139.842748 -348.204028)
			(xy 140.706348 -348.204028) (xy 140.733614 -348.204538) (xy 140.787591 -348.212305) (xy 140.839914 -348.227674)
			(xy 140.889517 -348.250332) (xy 140.93539 -348.279819) (xy 140.976601 -348.315533) (xy 141.01231 -348.356748)
			(xy 141.041791 -348.402626) (xy 141.064443 -348.452231) (xy 141.079806 -348.504556) (xy 141.087566 -348.558534)
			(xy 141.087566 -348.613066) (xy 141.087565 -348.613072) (xy 142.570392 -348.613072) (xy 142.570392 -348.558528)
			(xy 142.578154 -348.504539) (xy 142.593521 -348.452204) (xy 142.61618 -348.402589) (xy 142.645669 -348.356704)
			(xy 142.681388 -348.315483) (xy 142.72261 -348.279764) (xy 142.768496 -348.250276) (xy 142.818112 -348.227618)
			(xy 142.870447 -348.212252) (xy 142.924436 -348.204491) (xy 142.951708 -348.204028) (xy 143.815308 -348.204028)
			(xy 143.842576 -348.204535) (xy 143.896558 -348.212297) (xy 143.948885 -348.227663) (xy 143.998493 -348.250319)
			(xy 144.044371 -348.279804) (xy 144.085587 -348.315519) (xy 144.1213 -348.356735) (xy 144.150785 -348.402614)
			(xy 144.17344 -348.452223) (xy 144.188804 -348.50455) (xy 144.196566 -348.558532) (xy 144.196566 -348.613068)
			(xy 144.196565 -348.613072) (xy 161.804792 -348.613072) (xy 161.804792 -348.558528) (xy 161.812554 -348.504538)
			(xy 161.827921 -348.452203) (xy 161.850581 -348.402588) (xy 161.88007 -348.356703) (xy 161.91579 -348.315481)
			(xy 161.957012 -348.279763) (xy 162.002899 -348.250275) (xy 162.052515 -348.227617) (xy 162.10485 -348.212252)
			(xy 162.15884 -348.204491) (xy 162.186112 -348.204028) (xy 163.049712 -348.204028) (xy 163.07698 -348.204535)
			(xy 163.130961 -348.212298) (xy 163.183288 -348.227664) (xy 163.232895 -348.25032) (xy 163.278773 -348.279806)
			(xy 163.319988 -348.31552) (xy 163.355701 -348.356736) (xy 163.385185 -348.402615) (xy 163.40784 -348.452224)
			(xy 163.423204 -348.504551) (xy 163.430966 -348.558532) (xy 163.430966 -348.613068) (xy 163.430966 -348.613069)
			(xy 164.913814 -348.613069) (xy 164.913814 -348.558531) (xy 164.921576 -348.504549) (xy 164.93694 -348.45222)
			(xy 164.959595 -348.40261) (xy 164.989079 -348.35673) (xy 165.024792 -348.315512) (xy 165.066007 -348.279795)
			(xy 165.111886 -348.250308) (xy 165.161494 -348.22765) (xy 165.213821 -348.212281) (xy 165.267803 -348.204516)
			(xy 165.295072 -348.204028) (xy 166.158672 -348.204028) (xy 166.185944 -348.20451) (xy 166.239932 -348.212268)
			(xy 166.292267 -348.227632) (xy 166.341882 -348.250287) (xy 166.387768 -348.279773) (xy 166.42899 -348.31549)
			(xy 166.46471 -348.356709) (xy 166.494199 -348.402593) (xy 166.516859 -348.452207) (xy 166.532226 -348.504541)
			(xy 166.539988 -348.558528) (xy 166.539988 -348.613072) (xy 166.539988 -348.613073) (xy 168.022692 -348.613073)
			(xy 168.022692 -348.558527) (xy 168.030455 -348.504536) (xy 168.045823 -348.452199) (xy 168.068484 -348.402583)
			(xy 168.097975 -348.356696) (xy 168.133697 -348.315474) (xy 168.174922 -348.279756) (xy 168.220811 -348.250268)
			(xy 168.270429 -348.227612) (xy 168.322767 -348.212248) (xy 168.376759 -348.204489) (xy 168.404032 -348.204028)
			(xy 169.267632 -348.204028) (xy 169.294899 -348.204537) (xy 169.348878 -348.212302) (xy 169.401202 -348.227669)
			(xy 169.450807 -348.250327) (xy 169.496683 -348.279813) (xy 169.537895 -348.315527) (xy 169.573606 -348.356743)
			(xy 169.603088 -348.402621) (xy 169.625742 -348.452228) (xy 169.641105 -348.504553) (xy 169.648866 -348.558533)
			(xy 169.648866 -348.613067) (xy 169.648866 -348.61307) (xy 171.131714 -348.61307) (xy 171.131714 -348.55853)
			(xy 171.139476 -348.504546) (xy 171.154841 -348.452216) (xy 171.177498 -348.402605) (xy 171.206984 -348.356723)
			(xy 171.242699 -348.315505) (xy 171.283917 -348.279788) (xy 171.329798 -348.250301) (xy 171.379408 -348.227644)
			(xy 171.431738 -348.212278) (xy 171.485722 -348.204515) (xy 171.512992 -348.204028) (xy 172.376592 -348.204028)
			(xy 172.403863 -348.204511) (xy 172.457849 -348.212272) (xy 172.510181 -348.227637) (xy 172.559794 -348.250294)
			(xy 172.605678 -348.27978) (xy 172.646898 -348.315497) (xy 172.682615 -348.356716) (xy 172.712103 -348.402599)
			(xy 172.73476 -348.452211) (xy 172.750126 -348.504543) (xy 172.757889 -348.558529) (xy 172.757889 -348.613068)
			(xy 174.240714 -348.613068) (xy 174.240714 -348.558532) (xy 174.248475 -348.504551) (xy 174.263838 -348.452224)
			(xy 174.286492 -348.402616) (xy 174.315974 -348.356736) (xy 174.351685 -348.315519) (xy 174.392898 -348.279803)
			(xy 174.438774 -348.250315) (xy 174.488379 -348.227655) (xy 174.540704 -348.212285) (xy 174.594684 -348.204518)
			(xy 174.621952 -348.204028) (xy 175.485552 -348.204028) (xy 175.512825 -348.204508) (xy 175.566815 -348.212265)
			(xy 175.619152 -348.227626) (xy 175.66877 -348.250281) (xy 175.714659 -348.279766) (xy 175.755883 -348.315483)
			(xy 175.791605 -348.356703) (xy 175.821096 -348.402588) (xy 175.843757 -348.452203) (xy 175.859125 -348.504538)
			(xy 175.866888 -348.558528) (xy 175.866888 -348.613072) (xy 177.349592 -348.613072) (xy 177.349592 -348.558528)
			(xy 177.357354 -348.504538) (xy 177.372721 -348.452203) (xy 177.395381 -348.402588) (xy 177.42487 -348.356703)
			(xy 177.46059 -348.315481) (xy 177.501812 -348.279763) (xy 177.547699 -348.250275) (xy 177.597315 -348.227617)
			(xy 177.64965 -348.212252) (xy 177.70364 -348.204491) (xy 177.730912 -348.204028) (xy 178.594512 -348.204028)
			(xy 178.62178 -348.204535) (xy 178.675761 -348.212298) (xy 178.728088 -348.227664) (xy 178.777695 -348.25032)
			(xy 178.823573 -348.279806) (xy 178.864788 -348.31552) (xy 178.900501 -348.356736) (xy 178.929985 -348.402615)
			(xy 178.95264 -348.452224) (xy 178.968004 -348.504551) (xy 178.975766 -348.558532) (xy 178.975766 -348.613068)
			(xy 178.975766 -348.613069) (xy 180.458614 -348.613069) (xy 180.458614 -348.558531) (xy 180.466376 -348.504549)
			(xy 180.48174 -348.45222) (xy 180.504395 -348.40261) (xy 180.533879 -348.35673) (xy 180.569592 -348.315512)
			(xy 180.610807 -348.279795) (xy 180.656686 -348.250308) (xy 180.706294 -348.22765) (xy 180.758621 -348.212281)
			(xy 180.812603 -348.204516) (xy 180.839872 -348.204028) (xy 181.703472 -348.204028) (xy 181.730744 -348.20451)
			(xy 181.784732 -348.212268) (xy 181.837067 -348.227632) (xy 181.886682 -348.250287) (xy 181.932568 -348.279773)
			(xy 181.97379 -348.31549) (xy 182.00951 -348.356709) (xy 182.038999 -348.402593) (xy 182.061659 -348.452207)
			(xy 182.077026 -348.504541) (xy 182.084788 -348.558528) (xy 182.084788 -348.613072) (xy 182.084788 -348.613073)
			(xy 183.567492 -348.613073) (xy 183.567492 -348.558527) (xy 183.575255 -348.504536) (xy 183.590623 -348.452199)
			(xy 183.613284 -348.402583) (xy 183.642775 -348.356696) (xy 183.678497 -348.315474) (xy 183.719722 -348.279756)
			(xy 183.765611 -348.250268) (xy 183.815229 -348.227612) (xy 183.867567 -348.212248) (xy 183.921559 -348.204489)
			(xy 183.948832 -348.204028) (xy 184.812432 -348.204028) (xy 184.839699 -348.204537) (xy 184.893678 -348.212302)
			(xy 184.946002 -348.227669) (xy 184.995607 -348.250327) (xy 185.041483 -348.279813) (xy 185.082695 -348.315527)
			(xy 185.118406 -348.356743) (xy 185.147888 -348.402621) (xy 185.170542 -348.452228) (xy 185.185905 -348.504553)
			(xy 185.193666 -348.558533) (xy 185.193666 -348.613067) (xy 185.193666 -348.61307) (xy 186.676514 -348.61307)
			(xy 186.676514 -348.55853) (xy 186.684276 -348.504546) (xy 186.699641 -348.452216) (xy 186.722298 -348.402605)
			(xy 186.751784 -348.356723) (xy 186.787499 -348.315505) (xy 186.828717 -348.279788) (xy 186.874598 -348.250301)
			(xy 186.924208 -348.227644) (xy 186.976538 -348.212278) (xy 187.030522 -348.204515) (xy 187.057792 -348.204028)
			(xy 187.921392 -348.204028) (xy 187.948663 -348.204511) (xy 188.002649 -348.212272) (xy 188.054981 -348.227637)
			(xy 188.104594 -348.250294) (xy 188.150478 -348.27978) (xy 188.191698 -348.315497) (xy 188.227415 -348.356716)
			(xy 188.256903 -348.402599) (xy 188.27956 -348.452211) (xy 188.294926 -348.504543) (xy 188.302689 -348.558529)
			(xy 188.302689 -348.613068) (xy 189.785514 -348.613068) (xy 189.785514 -348.558532) (xy 189.793275 -348.504551)
			(xy 189.808638 -348.452224) (xy 189.831292 -348.402616) (xy 189.860774 -348.356736) (xy 189.896485 -348.315519)
			(xy 189.937698 -348.279803) (xy 189.983574 -348.250315) (xy 190.033179 -348.227655) (xy 190.085504 -348.212285)
			(xy 190.139484 -348.204518) (xy 190.166752 -348.204028) (xy 191.030352 -348.204028) (xy 191.057625 -348.204508)
			(xy 191.111615 -348.212265) (xy 191.163952 -348.227626) (xy 191.21357 -348.250281) (xy 191.259459 -348.279766)
			(xy 191.300683 -348.315483) (xy 191.336405 -348.356703) (xy 191.365896 -348.402588) (xy 191.388557 -348.452203)
			(xy 191.403925 -348.504538) (xy 191.411688 -348.558528) (xy 191.411688 -348.613072) (xy 192.894392 -348.613072)
			(xy 192.894392 -348.558528) (xy 192.902154 -348.504538) (xy 192.917521 -348.452203) (xy 192.940181 -348.402588)
			(xy 192.96967 -348.356703) (xy 193.00539 -348.315481) (xy 193.046612 -348.279763) (xy 193.092499 -348.250275)
			(xy 193.142115 -348.227617) (xy 193.19445 -348.212252) (xy 193.24844 -348.204491) (xy 193.275712 -348.204028)
			(xy 194.139312 -348.204028) (xy 194.16658 -348.204535) (xy 194.220561 -348.212298) (xy 194.272888 -348.227664)
			(xy 194.322495 -348.25032) (xy 194.368373 -348.279806) (xy 194.409588 -348.31552) (xy 194.445301 -348.356736)
			(xy 194.474785 -348.402615) (xy 194.49744 -348.452224) (xy 194.512804 -348.504551) (xy 194.520566 -348.558532)
			(xy 194.520566 -348.613068) (xy 194.520565 -348.613072) (xy 267.515792 -348.613072) (xy 267.515792 -348.558528)
			(xy 267.523554 -348.50454) (xy 267.538921 -348.452206) (xy 267.561579 -348.402591) (xy 267.591068 -348.356706)
			(xy 267.626786 -348.315485) (xy 267.668008 -348.279766) (xy 267.713893 -348.250278) (xy 267.763507 -348.22762)
			(xy 267.815842 -348.212253) (xy 267.86983 -348.204491) (xy 267.897102 -348.204028) (xy 268.760702 -348.204028)
			(xy 268.787971 -348.204535) (xy 268.841953 -348.212296) (xy 268.89428 -348.227661) (xy 268.943889 -348.250317)
			(xy 268.989769 -348.279802) (xy 269.030985 -348.315517) (xy 269.066699 -348.356733) (xy 269.096184 -348.402613)
			(xy 269.118839 -348.452221) (xy 269.134204 -348.504549) (xy 269.141966 -348.558531) (xy 269.141966 -348.613068)
			(xy 270.624814 -348.613068) (xy 270.624814 -348.558532) (xy 270.632575 -348.50455) (xy 270.647939 -348.452222)
			(xy 270.670593 -348.402613) (xy 270.700076 -348.356733) (xy 270.735788 -348.315515) (xy 270.777002 -348.279799)
			(xy 270.82288 -348.250311) (xy 270.872486 -348.227652) (xy 270.924813 -348.212283) (xy 270.978794 -348.204517)
			(xy 271.006062 -348.204028) (xy 271.869662 -348.204028) (xy 271.896934 -348.204509) (xy 271.950924 -348.212266)
			(xy 272.00326 -348.227629) (xy 272.052876 -348.250284) (xy 272.098763 -348.27977) (xy 272.139987 -348.315486)
			(xy 272.175708 -348.356706) (xy 272.205198 -348.40259) (xy 272.227858 -348.452205) (xy 272.243226 -348.504539)
			(xy 272.250988 -348.558528) (xy 272.250988 -348.613072) (xy 272.250988 -348.613073) (xy 273.733692 -348.613073)
			(xy 273.733692 -348.558527) (xy 273.741454 -348.504537) (xy 273.756822 -348.452201) (xy 273.779482 -348.402585)
			(xy 273.808972 -348.356699) (xy 273.844693 -348.315478) (xy 273.885917 -348.279759) (xy 273.931805 -348.250271)
			(xy 273.981422 -348.227615) (xy 274.033759 -348.21225) (xy 274.087749 -348.20449) (xy 274.115022 -348.204028)
			(xy 274.978622 -348.204028) (xy 275.00589 -348.204536) (xy 275.059869 -348.2123) (xy 275.112195 -348.227667)
			(xy 275.161801 -348.250324) (xy 275.207678 -348.279809) (xy 275.248892 -348.315524) (xy 275.284604 -348.35674)
			(xy 275.314087 -348.402618) (xy 275.336741 -348.452226) (xy 275.352105 -348.504552) (xy 275.359866 -348.558532)
			(xy 275.359866 -348.613068) (xy 275.359866 -348.613069) (xy 276.842714 -348.613069) (xy 276.842714 -348.558531)
			(xy 276.850476 -348.504547) (xy 276.865841 -348.452218) (xy 276.888496 -348.402608) (xy 276.917981 -348.356726)
			(xy 276.953695 -348.315508) (xy 276.994912 -348.279792) (xy 277.040792 -348.250305) (xy 277.090401 -348.227647)
			(xy 277.14273 -348.21228) (xy 277.196713 -348.204516) (xy 277.223982 -348.204028) (xy 278.087582 -348.204028)
			(xy 278.114853 -348.20451) (xy 278.168841 -348.21227) (xy 278.221174 -348.227634) (xy 278.270788 -348.25029)
			(xy 278.316673 -348.279777) (xy 278.357894 -348.315493) (xy 278.393612 -348.356713) (xy 278.423101 -348.402596)
			(xy 278.445759 -348.452209) (xy 278.461126 -348.504542) (xy 278.468888 -348.558529) (xy 278.468888 -348.613071)
			(xy 278.468888 -348.613074) (xy 279.951592 -348.613074) (xy 279.951592 -348.558526) (xy 279.959355 -348.504534)
			(xy 279.974724 -348.452197) (xy 279.997385 -348.40258) (xy 280.026877 -348.356693) (xy 280.0626 -348.315471)
			(xy 280.103827 -348.279752) (xy 280.149717 -348.250265) (xy 280.199336 -348.227609) (xy 280.251676 -348.212246)
			(xy 280.305668 -348.204489) (xy 280.332942 -348.204028) (xy 281.196542 -348.204028) (xy 281.223809 -348.204537)
			(xy 281.277786 -348.212304) (xy 281.330109 -348.227672) (xy 281.379713 -348.25033) (xy 281.425587 -348.279816)
			(xy 281.466799 -348.315531) (xy 281.502509 -348.356746) (xy 281.53199 -348.402624) (xy 281.554643 -348.45223)
			(xy 281.570005 -348.504555) (xy 281.577766 -348.558533) (xy 281.577766 -348.613067) (xy 281.577765 -348.613072)
			(xy 283.060592 -348.613072) (xy 283.060592 -348.558528) (xy 283.068354 -348.50454) (xy 283.083721 -348.452206)
			(xy 283.106379 -348.402591) (xy 283.135868 -348.356706) (xy 283.171586 -348.315485) (xy 283.212808 -348.279766)
			(xy 283.258693 -348.250278) (xy 283.308307 -348.22762) (xy 283.360642 -348.212253) (xy 283.41463 -348.204491)
			(xy 283.441902 -348.204028) (xy 284.305502 -348.204028) (xy 284.332771 -348.204535) (xy 284.386753 -348.212296)
			(xy 284.43908 -348.227661) (xy 284.488689 -348.250317) (xy 284.534569 -348.279802) (xy 284.575785 -348.315517)
			(xy 284.611499 -348.356733) (xy 284.640984 -348.402613) (xy 284.663639 -348.452221) (xy 284.679004 -348.504549)
			(xy 284.686766 -348.558531) (xy 284.686766 -348.613068) (xy 286.169614 -348.613068) (xy 286.169614 -348.558532)
			(xy 286.177375 -348.50455) (xy 286.192739 -348.452222) (xy 286.215393 -348.402613) (xy 286.244876 -348.356733)
			(xy 286.280588 -348.315515) (xy 286.321802 -348.279799) (xy 286.36768 -348.250311) (xy 286.417286 -348.227652)
			(xy 286.469613 -348.212283) (xy 286.523594 -348.204517) (xy 286.550862 -348.204028) (xy 287.414462 -348.204028)
			(xy 287.441734 -348.204509) (xy 287.495724 -348.212266) (xy 287.54806 -348.227629) (xy 287.597676 -348.250284)
			(xy 287.643563 -348.27977) (xy 287.684787 -348.315486) (xy 287.720508 -348.356706) (xy 287.749998 -348.40259)
			(xy 287.772658 -348.452205) (xy 287.788026 -348.504539) (xy 287.795788 -348.558528) (xy 287.795788 -348.613072)
			(xy 287.795788 -348.613073) (xy 289.278492 -348.613073) (xy 289.278492 -348.558527) (xy 289.286254 -348.504537)
			(xy 289.301622 -348.452201) (xy 289.324282 -348.402585) (xy 289.353772 -348.356699) (xy 289.389493 -348.315478)
			(xy 289.430717 -348.279759) (xy 289.476605 -348.250271) (xy 289.526222 -348.227615) (xy 289.578559 -348.21225)
			(xy 289.632549 -348.20449) (xy 289.659822 -348.204028) (xy 290.523422 -348.204028) (xy 290.55069 -348.204536)
			(xy 290.604669 -348.2123) (xy 290.656995 -348.227667) (xy 290.706601 -348.250324) (xy 290.752478 -348.279809)
			(xy 290.793692 -348.315524) (xy 290.829404 -348.35674) (xy 290.858887 -348.402618) (xy 290.881541 -348.452226)
			(xy 290.896905 -348.504552) (xy 290.904666 -348.558532) (xy 290.904666 -348.613068) (xy 290.904666 -348.613069)
			(xy 292.387514 -348.613069) (xy 292.387514 -348.558531) (xy 292.395276 -348.504547) (xy 292.410641 -348.452218)
			(xy 292.433296 -348.402608) (xy 292.462781 -348.356726) (xy 292.498495 -348.315508) (xy 292.539712 -348.279792)
			(xy 292.585592 -348.250305) (xy 292.635201 -348.227647) (xy 292.68753 -348.21228) (xy 292.741513 -348.204516)
			(xy 292.768782 -348.204028) (xy 293.632382 -348.204028) (xy 293.659653 -348.20451) (xy 293.713641 -348.21227)
			(xy 293.765974 -348.227634) (xy 293.815588 -348.25029) (xy 293.861473 -348.279777) (xy 293.902694 -348.315493)
			(xy 293.938412 -348.356713) (xy 293.967901 -348.402596) (xy 293.990559 -348.452209) (xy 294.005926 -348.504542)
			(xy 294.013688 -348.558529) (xy 294.013688 -348.613071) (xy 294.013688 -348.613074) (xy 295.496392 -348.613074)
			(xy 295.496392 -348.558526) (xy 295.504155 -348.504534) (xy 295.519524 -348.452197) (xy 295.542185 -348.40258)
			(xy 295.571677 -348.356693) (xy 295.6074 -348.315471) (xy 295.648627 -348.279752) (xy 295.694517 -348.250265)
			(xy 295.744136 -348.227609) (xy 295.796476 -348.212246) (xy 295.850468 -348.204489) (xy 295.877742 -348.204028)
			(xy 296.741342 -348.204028) (xy 296.768609 -348.204537) (xy 296.822586 -348.212304) (xy 296.874909 -348.227672)
			(xy 296.924513 -348.25033) (xy 296.970387 -348.279816) (xy 297.011599 -348.315531) (xy 297.047309 -348.356746)
			(xy 297.07679 -348.402624) (xy 297.099443 -348.45223) (xy 297.114805 -348.504555) (xy 297.122566 -348.558533)
			(xy 297.122566 -348.613067) (xy 297.122565 -348.613072) (xy 298.605392 -348.613072) (xy 298.605392 -348.558528)
			(xy 298.613154 -348.50454) (xy 298.628521 -348.452206) (xy 298.651179 -348.402591) (xy 298.680668 -348.356706)
			(xy 298.716386 -348.315485) (xy 298.757608 -348.279766) (xy 298.803493 -348.250278) (xy 298.853107 -348.22762)
			(xy 298.905442 -348.212253) (xy 298.95943 -348.204491) (xy 298.986702 -348.204028) (xy 299.850302 -348.204028)
			(xy 299.877571 -348.204535) (xy 299.931553 -348.212296) (xy 299.98388 -348.227661) (xy 300.033489 -348.250317)
			(xy 300.079369 -348.279802) (xy 300.120585 -348.315517) (xy 300.156299 -348.356733) (xy 300.185784 -348.402613)
			(xy 300.208439 -348.452221) (xy 300.223804 -348.504549) (xy 300.231566 -348.558531) (xy 300.231566 -348.613069)
			(xy 300.231566 -348.613072) (xy 312.121492 -348.613072) (xy 312.121492 -348.558528) (xy 312.129254 -348.504539)
			(xy 312.144621 -348.452205) (xy 312.167279 -348.40259) (xy 312.196768 -348.356705) (xy 312.232487 -348.315484)
			(xy 312.273709 -348.279766) (xy 312.319594 -348.250277) (xy 312.369209 -348.227619) (xy 312.421543 -348.212253)
			(xy 312.475532 -348.204491) (xy 312.502804 -348.204028) (xy 313.366404 -348.204028) (xy 313.393672 -348.204535)
			(xy 313.447654 -348.212297) (xy 313.499982 -348.227662) (xy 313.54959 -348.250318) (xy 313.595469 -348.279803)
			(xy 313.636686 -348.315517) (xy 313.672399 -348.356734) (xy 313.701884 -348.402613) (xy 313.72454 -348.452222)
			(xy 313.739904 -348.50455) (xy 313.747666 -348.558532) (xy 313.747666 -348.613068) (xy 315.230514 -348.613068)
			(xy 315.230514 -348.558532) (xy 315.238275 -348.50455) (xy 315.253639 -348.452222) (xy 315.276293 -348.402613)
			(xy 315.305777 -348.356732) (xy 315.341489 -348.315514) (xy 315.382703 -348.279798) (xy 315.428581 -348.250311)
			(xy 315.478188 -348.227652) (xy 315.530514 -348.212283) (xy 315.584496 -348.204517) (xy 315.611764 -348.204028)
			(xy 316.475364 -348.204028) (xy 316.502636 -348.204509) (xy 316.556625 -348.212267) (xy 316.608961 -348.22763)
			(xy 316.658577 -348.250284) (xy 316.704464 -348.27977) (xy 316.745688 -348.315487) (xy 316.781408 -348.356707)
			(xy 316.810898 -348.402591) (xy 316.833558 -348.452205) (xy 316.848926 -348.504539) (xy 316.856688 -348.558528)
			(xy 316.856688 -348.613072) (xy 316.856688 -348.613073) (xy 318.339392 -348.613073) (xy 318.339392 -348.558527)
			(xy 318.347155 -348.504537) (xy 318.362522 -348.452201) (xy 318.385182 -348.402585) (xy 318.414673 -348.356699)
			(xy 318.450394 -348.315477) (xy 318.491618 -348.279759) (xy 318.537506 -348.250271) (xy 318.587123 -348.227614)
			(xy 318.63946 -348.212249) (xy 318.693451 -348.20449) (xy 318.720724 -348.204028) (xy 319.584324 -348.204028)
			(xy 319.611592 -348.204536) (xy 319.665571 -348.2123) (xy 319.717896 -348.227667) (xy 319.767502 -348.250324)
			(xy 319.813379 -348.27981) (xy 319.854593 -348.315524) (xy 319.890304 -348.35674) (xy 319.919787 -348.402619)
			(xy 319.942441 -348.452226) (xy 319.957805 -348.504552) (xy 319.965566 -348.558532) (xy 319.965566 -348.613068)
			(xy 319.965566 -348.613069) (xy 321.448414 -348.613069) (xy 321.448414 -348.558531) (xy 321.456176 -348.504547)
			(xy 321.471541 -348.452217) (xy 321.494196 -348.402607) (xy 321.523682 -348.356726) (xy 321.559396 -348.315507)
			(xy 321.600613 -348.279791) (xy 321.646493 -348.250304) (xy 321.696102 -348.227646) (xy 321.748431 -348.212279)
			(xy 321.802415 -348.204516) (xy 321.829684 -348.204028) (xy 322.693284 -348.204028) (xy 322.720555 -348.20451)
			(xy 322.774542 -348.21227) (xy 322.826875 -348.227635) (xy 322.876489 -348.250291) (xy 322.922374 -348.279777)
			(xy 322.963595 -348.315494) (xy 322.999313 -348.356713) (xy 323.028801 -348.402597) (xy 323.051459 -348.45221)
			(xy 323.066826 -348.504542) (xy 323.074588 -348.558529) (xy 323.074588 -348.613071) (xy 323.074588 -348.613074)
			(xy 324.557292 -348.613074) (xy 324.557292 -348.558526) (xy 324.565055 -348.504534) (xy 324.580424 -348.452197)
			(xy 324.603085 -348.402579) (xy 324.632578 -348.356692) (xy 324.668301 -348.31547) (xy 324.709527 -348.279751)
			(xy 324.755418 -348.250264) (xy 324.805038 -348.227609) (xy 324.857377 -348.212246) (xy 324.91137 -348.204489)
			(xy 324.938644 -348.204028) (xy 325.802244 -348.204028) (xy 325.829511 -348.204537) (xy 325.883488 -348.212304)
			(xy 325.935811 -348.227673) (xy 325.985414 -348.250331) (xy 326.031288 -348.279817) (xy 326.0725 -348.315531)
			(xy 326.108209 -348.356747) (xy 326.13769 -348.402624) (xy 326.160343 -348.45223) (xy 326.175705 -348.504555)
			(xy 326.183466 -348.558533) (xy 326.183466 -348.613067) (xy 326.183465 -348.613072) (xy 327.666292 -348.613072)
			(xy 327.666292 -348.558528) (xy 327.674054 -348.504539) (xy 327.689421 -348.452205) (xy 327.712079 -348.40259)
			(xy 327.741568 -348.356705) (xy 327.777287 -348.315484) (xy 327.818509 -348.279766) (xy 327.864394 -348.250277)
			(xy 327.914009 -348.227619) (xy 327.966343 -348.212253) (xy 328.020332 -348.204491) (xy 328.047604 -348.204028)
			(xy 328.911204 -348.204028) (xy 328.938472 -348.204535) (xy 328.992454 -348.212297) (xy 329.044782 -348.227662)
			(xy 329.09439 -348.250318) (xy 329.140269 -348.279803) (xy 329.181486 -348.315517) (xy 329.217199 -348.356734)
			(xy 329.246684 -348.402613) (xy 329.26934 -348.452222) (xy 329.284704 -348.50455) (xy 329.292466 -348.558532)
			(xy 329.292466 -348.613068) (xy 330.775314 -348.613068) (xy 330.775314 -348.558532) (xy 330.783075 -348.50455)
			(xy 330.798439 -348.452222) (xy 330.821093 -348.402613) (xy 330.850577 -348.356732) (xy 330.886289 -348.315514)
			(xy 330.927503 -348.279798) (xy 330.973381 -348.250311) (xy 331.022988 -348.227652) (xy 331.075314 -348.212283)
			(xy 331.129296 -348.204517) (xy 331.156564 -348.204028) (xy 332.020164 -348.204028) (xy 332.047436 -348.204509)
			(xy 332.101425 -348.212267) (xy 332.153761 -348.22763) (xy 332.203377 -348.250284) (xy 332.249264 -348.27977)
			(xy 332.290488 -348.315487) (xy 332.326208 -348.356707) (xy 332.355698 -348.402591) (xy 332.378358 -348.452205)
			(xy 332.393726 -348.504539) (xy 332.401488 -348.558528) (xy 332.401488 -348.613072) (xy 332.401488 -348.613073)
			(xy 333.884192 -348.613073) (xy 333.884192 -348.558527) (xy 333.891955 -348.504537) (xy 333.907322 -348.452201)
			(xy 333.929982 -348.402585) (xy 333.959473 -348.356699) (xy 333.995194 -348.315477) (xy 334.036418 -348.279759)
			(xy 334.082306 -348.250271) (xy 334.131923 -348.227614) (xy 334.18426 -348.212249) (xy 334.238251 -348.20449)
			(xy 334.265524 -348.204028) (xy 335.129124 -348.204028) (xy 335.156392 -348.204536) (xy 335.210371 -348.2123)
			(xy 335.262696 -348.227667) (xy 335.312302 -348.250324) (xy 335.358179 -348.27981) (xy 335.399393 -348.315524)
			(xy 335.435104 -348.35674) (xy 335.464587 -348.402619) (xy 335.487241 -348.452226) (xy 335.502605 -348.504552)
			(xy 335.510366 -348.558532) (xy 335.510366 -348.613068) (xy 335.510366 -348.613069) (xy 336.993214 -348.613069)
			(xy 336.993214 -348.558531) (xy 337.000976 -348.504547) (xy 337.016341 -348.452217) (xy 337.038996 -348.402607)
			(xy 337.068482 -348.356726) (xy 337.104196 -348.315507) (xy 337.145413 -348.279791) (xy 337.191293 -348.250304)
			(xy 337.240902 -348.227646) (xy 337.293231 -348.212279) (xy 337.347215 -348.204516) (xy 337.374484 -348.204028)
			(xy 338.238084 -348.204028) (xy 338.265355 -348.20451) (xy 338.319342 -348.21227) (xy 338.371675 -348.227635)
			(xy 338.421289 -348.250291) (xy 338.467174 -348.279777) (xy 338.508395 -348.315494) (xy 338.544113 -348.356713)
			(xy 338.573601 -348.402597) (xy 338.596259 -348.45221) (xy 338.611626 -348.504542) (xy 338.619388 -348.558529)
			(xy 338.619388 -348.613071) (xy 338.619388 -348.613074) (xy 340.102092 -348.613074) (xy 340.102092 -348.558526)
			(xy 340.109855 -348.504534) (xy 340.125224 -348.452197) (xy 340.147885 -348.402579) (xy 340.177378 -348.356692)
			(xy 340.213101 -348.31547) (xy 340.254327 -348.279751) (xy 340.300218 -348.250264) (xy 340.349838 -348.227609)
			(xy 340.402177 -348.212246) (xy 340.45617 -348.204489) (xy 340.483444 -348.204028) (xy 341.347044 -348.204028)
			(xy 341.374311 -348.204537) (xy 341.428288 -348.212304) (xy 341.480611 -348.227673) (xy 341.530214 -348.250331)
			(xy 341.576088 -348.279817) (xy 341.6173 -348.315531) (xy 341.653009 -348.356747) (xy 341.68249 -348.402624)
			(xy 341.705143 -348.45223) (xy 341.720505 -348.504555) (xy 341.728266 -348.558533) (xy 341.728266 -348.613067)
			(xy 341.728265 -348.613072) (xy 343.211092 -348.613072) (xy 343.211092 -348.558528) (xy 343.218854 -348.504539)
			(xy 343.234221 -348.452205) (xy 343.256879 -348.40259) (xy 343.286368 -348.356705) (xy 343.322087 -348.315484)
			(xy 343.363309 -348.279766) (xy 343.409194 -348.250277) (xy 343.458809 -348.227619) (xy 343.511143 -348.212253)
			(xy 343.565132 -348.204491) (xy 343.592404 -348.204028) (xy 344.456004 -348.204028) (xy 344.483272 -348.204535)
			(xy 344.537254 -348.212297) (xy 344.589582 -348.227662) (xy 344.63919 -348.250318) (xy 344.685069 -348.279803)
			(xy 344.726286 -348.315517) (xy 344.761999 -348.356734) (xy 344.791484 -348.402613) (xy 344.81414 -348.452222)
			(xy 344.829504 -348.50455) (xy 344.837266 -348.558532) (xy 344.837266 -348.613068) (xy 344.837266 -348.613069)
			(xy 370.806714 -348.613069) (xy 370.806714 -348.558531) (xy 370.814476 -348.504548) (xy 370.82984 -348.452218)
			(xy 370.852496 -348.402608) (xy 370.881981 -348.356727) (xy 370.917695 -348.315509) (xy 370.958911 -348.279793)
			(xy 371.004791 -348.250305) (xy 371.054399 -348.227647) (xy 371.106728 -348.21228) (xy 371.160711 -348.204516)
			(xy 371.18798 -348.204028) (xy 372.05158 -348.204028) (xy 372.078851 -348.20451) (xy 372.132839 -348.21227)
			(xy 372.185173 -348.227634) (xy 372.234787 -348.25029) (xy 372.280672 -348.279776) (xy 372.321893 -348.315493)
			(xy 372.357612 -348.356712) (xy 372.387101 -348.402595) (xy 372.409759 -348.452209) (xy 372.425126 -348.504542)
			(xy 372.432888 -348.558529) (xy 372.432888 -348.613071) (xy 372.432888 -348.613074) (xy 373.915592 -348.613074)
			(xy 373.915592 -348.558526) (xy 373.923355 -348.504535) (xy 373.938724 -348.452197) (xy 373.961385 -348.40258)
			(xy 373.990877 -348.356694) (xy 374.0266 -348.315471) (xy 374.067826 -348.279753) (xy 374.113715 -348.250266)
			(xy 374.163335 -348.22761) (xy 374.215674 -348.212246) (xy 374.269666 -348.204489) (xy 374.29694 -348.204028)
			(xy 375.16054 -348.204028) (xy 375.187807 -348.204537) (xy 375.241785 -348.212303) (xy 375.294108 -348.227672)
			(xy 375.343712 -348.25033) (xy 375.389587 -348.279816) (xy 375.430798 -348.31553) (xy 375.466508 -348.356746)
			(xy 375.49599 -348.402623) (xy 375.518642 -348.45223) (xy 375.534005 -348.504554) (xy 375.541766 -348.558533)
			(xy 375.541766 -348.613067) (xy 375.541766 -348.61307) (xy 377.024614 -348.61307) (xy 377.024614 -348.55853)
			(xy 377.032376 -348.504545) (xy 377.047742 -348.452214) (xy 377.070399 -348.402603) (xy 377.099886 -348.35672)
			(xy 377.135602 -348.315502) (xy 377.17682 -348.279786) (xy 377.222703 -348.250299) (xy 377.272314 -348.227642)
			(xy 377.324645 -348.212276) (xy 377.37863 -348.204514) (xy 377.4059 -348.204028) (xy 378.2695 -348.204028)
			(xy 378.296769 -348.204534) (xy 378.350751 -348.212296) (xy 378.403079 -348.227661) (xy 378.452688 -348.250316)
			(xy 378.498568 -348.279802) (xy 378.539784 -348.315516) (xy 378.575498 -348.356732) (xy 378.604984 -348.402612)
			(xy 378.627639 -348.452221) (xy 378.643004 -348.504549) (xy 378.650766 -348.558531) (xy 378.650766 -348.613068)
			(xy 380.133614 -348.613068) (xy 380.133614 -348.558532) (xy 380.141375 -348.50455) (xy 380.156739 -348.452223)
			(xy 380.179393 -348.402614) (xy 380.208876 -348.356734) (xy 380.244588 -348.315516) (xy 380.285801 -348.2798)
			(xy 380.331679 -348.250312) (xy 380.381285 -348.227653) (xy 380.433611 -348.212284) (xy 380.487592 -348.204517)
			(xy 380.51486 -348.204028) (xy 381.37846 -348.204028) (xy 381.405732 -348.204509) (xy 381.459722 -348.212266)
			(xy 381.512058 -348.227628) (xy 381.561675 -348.250283) (xy 381.607562 -348.279769) (xy 381.648786 -348.315485)
			(xy 381.684507 -348.356706) (xy 381.713998 -348.40259) (xy 381.736658 -348.452204) (xy 381.752025 -348.504539)
			(xy 381.759788 -348.558528) (xy 381.759788 -348.613072) (xy 381.759788 -348.613073) (xy 383.242492 -348.613073)
			(xy 383.242492 -348.558527) (xy 383.250254 -348.504537) (xy 383.265622 -348.452202) (xy 383.288282 -348.402586)
			(xy 383.317772 -348.3567) (xy 383.353493 -348.315478) (xy 383.394716 -348.27976) (xy 383.440603 -348.250272)
			(xy 383.49022 -348.227615) (xy 383.542557 -348.21225) (xy 383.596547 -348.20449) (xy 383.62382 -348.204028)
			(xy 384.48742 -348.204028) (xy 384.514688 -348.204536) (xy 384.568668 -348.2123) (xy 384.620994 -348.227666)
			(xy 384.6706 -348.250323) (xy 384.716477 -348.279809) (xy 384.757691 -348.315523) (xy 384.793403 -348.356739)
			(xy 384.822887 -348.402618) (xy 384.845541 -348.452225) (xy 384.860905 -348.504552) (xy 384.868666 -348.558532)
			(xy 384.868666 -348.613068) (xy 384.868666 -348.613069) (xy 386.351514 -348.613069) (xy 386.351514 -348.558531)
			(xy 386.359276 -348.504548) (xy 386.37464 -348.452218) (xy 386.397296 -348.402608) (xy 386.426781 -348.356727)
			(xy 386.462495 -348.315509) (xy 386.503711 -348.279793) (xy 386.549591 -348.250305) (xy 386.599199 -348.227647)
			(xy 386.651528 -348.21228) (xy 386.705511 -348.204516) (xy 386.73278 -348.204028) (xy 387.59638 -348.204028)
			(xy 387.623651 -348.20451) (xy 387.677639 -348.21227) (xy 387.729973 -348.227634) (xy 387.779587 -348.25029)
			(xy 387.825472 -348.279776) (xy 387.866693 -348.315493) (xy 387.902412 -348.356712) (xy 387.931901 -348.402595)
			(xy 387.954559 -348.452209) (xy 387.969926 -348.504542) (xy 387.977688 -348.558529) (xy 387.977688 -348.613071)
			(xy 387.977688 -348.613074) (xy 389.460392 -348.613074) (xy 389.460392 -348.558526) (xy 389.468155 -348.504535)
			(xy 389.483524 -348.452197) (xy 389.506185 -348.40258) (xy 389.535677 -348.356694) (xy 389.5714 -348.315471)
			(xy 389.612626 -348.279753) (xy 389.658515 -348.250266) (xy 389.708135 -348.22761) (xy 389.760474 -348.212246)
			(xy 389.814466 -348.204489) (xy 389.84174 -348.204028) (xy 390.70534 -348.204028) (xy 390.732607 -348.204537)
			(xy 390.786585 -348.212303) (xy 390.838908 -348.227672) (xy 390.888512 -348.25033) (xy 390.934387 -348.279816)
			(xy 390.975598 -348.31553) (xy 391.011308 -348.356746) (xy 391.04079 -348.402623) (xy 391.063442 -348.45223)
			(xy 391.078805 -348.504554) (xy 391.086566 -348.558533) (xy 391.086566 -348.613067) (xy 391.086566 -348.61307)
			(xy 392.569414 -348.61307) (xy 392.569414 -348.55853) (xy 392.577176 -348.504545) (xy 392.592542 -348.452214)
			(xy 392.615199 -348.402603) (xy 392.644686 -348.35672) (xy 392.680402 -348.315502) (xy 392.72162 -348.279786)
			(xy 392.767503 -348.250299) (xy 392.817114 -348.227642) (xy 392.869445 -348.212276) (xy 392.92343 -348.204514)
			(xy 392.9507 -348.204028) (xy 393.8143 -348.204028) (xy 393.841569 -348.204534) (xy 393.895551 -348.212296)
			(xy 393.947879 -348.227661) (xy 393.997488 -348.250316) (xy 394.043368 -348.279802) (xy 394.084584 -348.315516)
			(xy 394.120298 -348.356732) (xy 394.149784 -348.402612) (xy 394.172439 -348.452221) (xy 394.187804 -348.504549)
			(xy 394.195566 -348.558531) (xy 394.195566 -348.613068) (xy 395.678414 -348.613068) (xy 395.678414 -348.558532)
			(xy 395.686175 -348.50455) (xy 395.701539 -348.452223) (xy 395.724193 -348.402614) (xy 395.753676 -348.356734)
			(xy 395.789388 -348.315516) (xy 395.830601 -348.2798) (xy 395.876479 -348.250312) (xy 395.926085 -348.227653)
			(xy 395.978411 -348.212284) (xy 396.032392 -348.204517) (xy 396.05966 -348.204028) (xy 396.92326 -348.204028)
			(xy 396.950532 -348.204509) (xy 397.004522 -348.212266) (xy 397.056858 -348.227628) (xy 397.106475 -348.250283)
			(xy 397.152362 -348.279769) (xy 397.193586 -348.315485) (xy 397.229307 -348.356706) (xy 397.258798 -348.40259)
			(xy 397.281458 -348.452204) (xy 397.296825 -348.504539) (xy 397.304588 -348.558528) (xy 397.304588 -348.613072)
			(xy 397.304588 -348.613073) (xy 398.787292 -348.613073) (xy 398.787292 -348.558527) (xy 398.795054 -348.504537)
			(xy 398.810422 -348.452202) (xy 398.833082 -348.402586) (xy 398.862572 -348.3567) (xy 398.898293 -348.315478)
			(xy 398.939516 -348.27976) (xy 398.985403 -348.250272) (xy 399.03502 -348.227615) (xy 399.087357 -348.21225)
			(xy 399.141347 -348.20449) (xy 399.16862 -348.204028) (xy 400.03222 -348.204028) (xy 400.059488 -348.204536)
			(xy 400.113468 -348.2123) (xy 400.165794 -348.227666) (xy 400.2154 -348.250323) (xy 400.261277 -348.279809)
			(xy 400.302491 -348.315523) (xy 400.338203 -348.356739) (xy 400.367687 -348.402618) (xy 400.390341 -348.452225)
			(xy 400.405705 -348.504552) (xy 400.413466 -348.558532) (xy 400.413466 -348.613068) (xy 400.413466 -348.613069)
			(xy 401.896314 -348.613069) (xy 401.896314 -348.558531) (xy 401.904076 -348.504548) (xy 401.91944 -348.452218)
			(xy 401.942096 -348.402608) (xy 401.971581 -348.356727) (xy 402.007295 -348.315509) (xy 402.048511 -348.279793)
			(xy 402.094391 -348.250305) (xy 402.143999 -348.227647) (xy 402.196328 -348.21228) (xy 402.250311 -348.204516)
			(xy 402.27758 -348.204028) (xy 403.14118 -348.204028) (xy 403.168451 -348.20451) (xy 403.222439 -348.21227)
			(xy 403.274773 -348.227634) (xy 403.324387 -348.25029) (xy 403.370272 -348.279776) (xy 403.411493 -348.315493)
			(xy 403.447212 -348.356712) (xy 403.476701 -348.402595) (xy 403.499359 -348.452209) (xy 403.514726 -348.504542)
			(xy 403.522488 -348.558529) (xy 403.522488 -348.61307) (xy 408.913814 -348.61307) (xy 408.913814 -348.55853)
			(xy 408.921576 -348.504546) (xy 408.936941 -348.452216) (xy 408.959598 -348.402605) (xy 408.989084 -348.356723)
			(xy 409.024799 -348.315505) (xy 409.066017 -348.279788) (xy 409.111898 -348.250301) (xy 409.161508 -348.227644)
			(xy 409.213838 -348.212278) (xy 409.267822 -348.204515) (xy 409.295092 -348.204028) (xy 410.158692 -348.204028)
			(xy 410.185963 -348.204511) (xy 410.239949 -348.212272) (xy 410.292281 -348.227637) (xy 410.341894 -348.250294)
			(xy 410.387778 -348.27978) (xy 410.428998 -348.315497) (xy 410.464715 -348.356716) (xy 410.494203 -348.402599)
			(xy 410.51686 -348.452211) (xy 410.532226 -348.504543) (xy 410.539989 -348.558529) (xy 410.539989 -348.613068)
			(xy 412.022814 -348.613068) (xy 412.022814 -348.558532) (xy 412.030575 -348.504551) (xy 412.045938 -348.452224)
			(xy 412.068592 -348.402616) (xy 412.098074 -348.356736) (xy 412.133785 -348.315519) (xy 412.174998 -348.279803)
			(xy 412.220874 -348.250315) (xy 412.270479 -348.227655) (xy 412.322804 -348.212285) (xy 412.376784 -348.204518)
			(xy 412.404052 -348.204028) (xy 413.267652 -348.204028) (xy 413.294925 -348.204508) (xy 413.348915 -348.212265)
			(xy 413.401252 -348.227626) (xy 413.45087 -348.250281) (xy 413.496759 -348.279766) (xy 413.537983 -348.315483)
			(xy 413.573705 -348.356703) (xy 413.603196 -348.402588) (xy 413.625857 -348.452203) (xy 413.641225 -348.504538)
			(xy 413.648988 -348.558528) (xy 413.648988 -348.613072) (xy 415.131692 -348.613072) (xy 415.131692 -348.558528)
			(xy 415.139454 -348.504538) (xy 415.154821 -348.452203) (xy 415.177481 -348.402588) (xy 415.20697 -348.356703)
			(xy 415.24269 -348.315481) (xy 415.283912 -348.279763) (xy 415.329799 -348.250275) (xy 415.379415 -348.227617)
			(xy 415.43175 -348.212252) (xy 415.48574 -348.204491) (xy 415.513012 -348.204028) (xy 416.376612 -348.204028)
			(xy 416.40388 -348.204535) (xy 416.457861 -348.212298) (xy 416.510188 -348.227664) (xy 416.559795 -348.25032)
			(xy 416.605673 -348.279806) (xy 416.646888 -348.31552) (xy 416.682601 -348.356736) (xy 416.712085 -348.402615)
			(xy 416.73474 -348.452224) (xy 416.750104 -348.504551) (xy 416.757866 -348.558532) (xy 416.757866 -348.613068)
			(xy 416.757866 -348.613069) (xy 418.240714 -348.613069) (xy 418.240714 -348.558531) (xy 418.248476 -348.504549)
			(xy 418.26384 -348.45222) (xy 418.286495 -348.40261) (xy 418.315979 -348.35673) (xy 418.351692 -348.315512)
			(xy 418.392907 -348.279795) (xy 418.438786 -348.250308) (xy 418.488394 -348.22765) (xy 418.540721 -348.212281)
			(xy 418.594703 -348.204516) (xy 418.621972 -348.204028) (xy 419.485572 -348.204028) (xy 419.512844 -348.20451)
			(xy 419.566832 -348.212268) (xy 419.619167 -348.227632) (xy 419.668782 -348.250287) (xy 419.714668 -348.279773)
			(xy 419.75589 -348.31549) (xy 419.79161 -348.356709) (xy 419.821099 -348.402593) (xy 419.843759 -348.452207)
			(xy 419.859126 -348.504541) (xy 419.866888 -348.558528) (xy 419.866888 -348.613072) (xy 419.866888 -348.613073)
			(xy 421.349592 -348.613073) (xy 421.349592 -348.558527) (xy 421.357355 -348.504536) (xy 421.372723 -348.452199)
			(xy 421.395384 -348.402583) (xy 421.424875 -348.356696) (xy 421.460597 -348.315474) (xy 421.501822 -348.279756)
			(xy 421.547711 -348.250268) (xy 421.597329 -348.227612) (xy 421.649667 -348.212248) (xy 421.703659 -348.204489)
			(xy 421.730932 -348.204028) (xy 422.594532 -348.204028) (xy 422.621799 -348.204537) (xy 422.675778 -348.212302)
			(xy 422.728102 -348.227669) (xy 422.777707 -348.250327) (xy 422.823583 -348.279813) (xy 422.864795 -348.315527)
			(xy 422.900506 -348.356743) (xy 422.929988 -348.402621) (xy 422.952642 -348.452228) (xy 422.968005 -348.504553)
			(xy 422.975766 -348.558533) (xy 422.975766 -348.613067) (xy 422.975766 -348.61307) (xy 424.458614 -348.61307)
			(xy 424.458614 -348.55853) (xy 424.466376 -348.504546) (xy 424.481741 -348.452216) (xy 424.504398 -348.402605)
			(xy 424.533884 -348.356723) (xy 424.569599 -348.315505) (xy 424.610817 -348.279788) (xy 424.656698 -348.250301)
			(xy 424.706308 -348.227644) (xy 424.758638 -348.212278) (xy 424.812622 -348.204515) (xy 424.839892 -348.204028)
			(xy 425.703492 -348.204028) (xy 425.730763 -348.204511) (xy 425.784749 -348.212272) (xy 425.837081 -348.227637)
			(xy 425.886694 -348.250294) (xy 425.932578 -348.27978) (xy 425.973798 -348.315497) (xy 426.009515 -348.356716)
			(xy 426.039003 -348.402599) (xy 426.06166 -348.452211) (xy 426.077026 -348.504543) (xy 426.084789 -348.558529)
			(xy 426.084789 -348.613068) (xy 427.567614 -348.613068) (xy 427.567614 -348.558532) (xy 427.575375 -348.504551)
			(xy 427.590738 -348.452224) (xy 427.613392 -348.402616) (xy 427.642874 -348.356736) (xy 427.678585 -348.315519)
			(xy 427.719798 -348.279803) (xy 427.765674 -348.250315) (xy 427.815279 -348.227655) (xy 427.867604 -348.212285)
			(xy 427.921584 -348.204518) (xy 427.948852 -348.204028) (xy 428.812452 -348.204028) (xy 428.839725 -348.204508)
			(xy 428.893715 -348.212265) (xy 428.946052 -348.227626) (xy 428.99567 -348.250281) (xy 429.041559 -348.279766)
			(xy 429.082783 -348.315483) (xy 429.118505 -348.356703) (xy 429.147996 -348.402588) (xy 429.170657 -348.452203)
			(xy 429.186025 -348.504538) (xy 429.193788 -348.558528) (xy 429.193788 -348.613072) (xy 430.676492 -348.613072)
			(xy 430.676492 -348.558528) (xy 430.684254 -348.504538) (xy 430.699621 -348.452203) (xy 430.722281 -348.402588)
			(xy 430.75177 -348.356703) (xy 430.78749 -348.315481) (xy 430.828712 -348.279763) (xy 430.874599 -348.250275)
			(xy 430.924215 -348.227617) (xy 430.97655 -348.212252) (xy 431.03054 -348.204491) (xy 431.057812 -348.204028)
			(xy 431.921412 -348.204028) (xy 431.94868 -348.204535) (xy 432.002661 -348.212298) (xy 432.054988 -348.227664)
			(xy 432.104595 -348.25032) (xy 432.150473 -348.279806) (xy 432.191688 -348.31552) (xy 432.227401 -348.356736)
			(xy 432.256885 -348.402615) (xy 432.27954 -348.452224) (xy 432.294904 -348.504551) (xy 432.302666 -348.558532)
			(xy 432.302666 -348.613068) (xy 432.302666 -348.613069) (xy 433.785514 -348.613069) (xy 433.785514 -348.558531)
			(xy 433.793276 -348.504549) (xy 433.80864 -348.45222) (xy 433.831295 -348.40261) (xy 433.860779 -348.35673)
			(xy 433.896492 -348.315512) (xy 433.937707 -348.279795) (xy 433.983586 -348.250308) (xy 434.033194 -348.22765)
			(xy 434.085521 -348.212281) (xy 434.139503 -348.204516) (xy 434.166772 -348.204028) (xy 435.030372 -348.204028)
			(xy 435.057644 -348.20451) (xy 435.111632 -348.212268) (xy 435.163967 -348.227632) (xy 435.213582 -348.250287)
			(xy 435.259468 -348.279773) (xy 435.30069 -348.31549) (xy 435.33641 -348.356709) (xy 435.365899 -348.402593)
			(xy 435.388559 -348.452207) (xy 435.403926 -348.504541) (xy 435.411688 -348.558528) (xy 435.411688 -348.613072)
			(xy 435.411688 -348.613073) (xy 436.894392 -348.613073) (xy 436.894392 -348.558527) (xy 436.902155 -348.504536)
			(xy 436.917523 -348.452199) (xy 436.940184 -348.402583) (xy 436.969675 -348.356696) (xy 437.005397 -348.315474)
			(xy 437.046622 -348.279756) (xy 437.092511 -348.250268) (xy 437.142129 -348.227612) (xy 437.194467 -348.212248)
			(xy 437.248459 -348.204489) (xy 437.275732 -348.204028) (xy 438.139332 -348.204028) (xy 438.166599 -348.204537)
			(xy 438.220578 -348.212302) (xy 438.272902 -348.227669) (xy 438.322507 -348.250327) (xy 438.368383 -348.279813)
			(xy 438.409595 -348.315527) (xy 438.445306 -348.356743) (xy 438.474788 -348.402621) (xy 438.497442 -348.452228)
			(xy 438.512805 -348.504553) (xy 438.520566 -348.558533) (xy 438.520566 -348.613067) (xy 438.520566 -348.61307)
			(xy 440.003414 -348.61307) (xy 440.003414 -348.55853) (xy 440.011176 -348.504546) (xy 440.026541 -348.452216)
			(xy 440.049198 -348.402605) (xy 440.078684 -348.356723) (xy 440.114399 -348.315505) (xy 440.155617 -348.279788)
			(xy 440.201498 -348.250301) (xy 440.251108 -348.227644) (xy 440.303438 -348.212278) (xy 440.357422 -348.204515)
			(xy 440.384692 -348.204028) (xy 441.248292 -348.204028) (xy 441.275563 -348.204511) (xy 441.329549 -348.212272)
			(xy 441.381881 -348.227637) (xy 441.431494 -348.250294) (xy 441.477378 -348.27978) (xy 441.518598 -348.315497)
			(xy 441.554315 -348.356716) (xy 441.583803 -348.402599) (xy 441.60646 -348.452211) (xy 441.621826 -348.504543)
			(xy 441.629589 -348.558529) (xy 441.629589 -348.613071) (xy 441.621826 -348.667057) (xy 441.60646 -348.719389)
			(xy 441.583803 -348.769001) (xy 441.554315 -348.814884) (xy 441.518598 -348.856103) (xy 441.477378 -348.89182)
			(xy 441.431494 -348.921306) (xy 441.381881 -348.943963) (xy 441.329549 -348.959328) (xy 441.275563 -348.967089)
			(xy 441.248292 -348.967552) (xy 440.384692 -348.967552) (xy 440.357422 -348.967085) (xy 440.303438 -348.959322)
			(xy 440.251108 -348.943956) (xy 440.201498 -348.921299) (xy 440.155617 -348.891812) (xy 440.114399 -348.856095)
			(xy 440.078684 -348.814877) (xy 440.049198 -348.768995) (xy 440.026541 -348.719384) (xy 440.011176 -348.667054)
			(xy 440.003414 -348.61307) (xy 438.520566 -348.61307) (xy 438.512805 -348.667047) (xy 438.497442 -348.719372)
			(xy 438.474788 -348.768979) (xy 438.445306 -348.814857) (xy 438.409595 -348.856073) (xy 438.368383 -348.891787)
			(xy 438.322507 -348.921273) (xy 438.272902 -348.943931) (xy 438.220578 -348.959298) (xy 438.166599 -348.967063)
			(xy 438.139332 -348.967552) (xy 437.275732 -348.967552) (xy 437.248459 -348.967111) (xy 437.194467 -348.959352)
			(xy 437.142129 -348.943988) (xy 437.092511 -348.921332) (xy 437.046622 -348.891844) (xy 437.005397 -348.856126)
			(xy 436.969675 -348.814904) (xy 436.940184 -348.769017) (xy 436.917523 -348.719401) (xy 436.902155 -348.667064)
			(xy 436.894392 -348.613073) (xy 435.411688 -348.613073) (xy 435.403926 -348.667059) (xy 435.388559 -348.719393)
			(xy 435.365899 -348.769007) (xy 435.33641 -348.814891) (xy 435.30069 -348.85611) (xy 435.259468 -348.891827)
			(xy 435.213582 -348.921313) (xy 435.163967 -348.943968) (xy 435.111632 -348.959332) (xy 435.057644 -348.96709)
			(xy 435.030372 -348.967552) (xy 434.166772 -348.967552) (xy 434.139503 -348.967084) (xy 434.085521 -348.959319)
			(xy 434.033194 -348.94395) (xy 433.983586 -348.921292) (xy 433.937707 -348.891805) (xy 433.896492 -348.856088)
			(xy 433.860779 -348.81487) (xy 433.831295 -348.76899) (xy 433.80864 -348.71938) (xy 433.793276 -348.667051)
			(xy 433.785514 -348.613069) (xy 432.302666 -348.613069) (xy 432.294904 -348.667049) (xy 432.27954 -348.719376)
			(xy 432.256885 -348.768985) (xy 432.227401 -348.814864) (xy 432.191688 -348.85608) (xy 432.150473 -348.891794)
			(xy 432.104595 -348.92128) (xy 432.054988 -348.943936) (xy 432.002661 -348.959302) (xy 431.94868 -348.967065)
			(xy 431.921412 -348.967552) (xy 431.057812 -348.967552) (xy 431.03054 -348.967109) (xy 430.97655 -348.959348)
			(xy 430.924215 -348.943983) (xy 430.874599 -348.921325) (xy 430.828712 -348.891837) (xy 430.78749 -348.856119)
			(xy 430.75177 -348.814897) (xy 430.722281 -348.769012) (xy 430.699621 -348.719397) (xy 430.684254 -348.667062)
			(xy 430.676492 -348.613072) (xy 429.193788 -348.613072) (xy 429.186025 -348.667062) (xy 429.170657 -348.719397)
			(xy 429.147996 -348.769012) (xy 429.118505 -348.814897) (xy 429.082783 -348.856117) (xy 429.041559 -348.891834)
			(xy 428.99567 -348.921319) (xy 428.946052 -348.943974) (xy 428.893715 -348.959335) (xy 428.839725 -348.967092)
			(xy 428.812452 -348.967552) (xy 427.948852 -348.967552) (xy 427.921584 -348.967082) (xy 427.867604 -348.959315)
			(xy 427.815279 -348.943945) (xy 427.765674 -348.921285) (xy 427.719798 -348.891797) (xy 427.678585 -348.856081)
			(xy 427.642874 -348.814864) (xy 427.613392 -348.768984) (xy 427.590738 -348.719376) (xy 427.575375 -348.667049)
			(xy 427.567614 -348.613068) (xy 426.084789 -348.613068) (xy 426.084789 -348.613071) (xy 426.077026 -348.667057)
			(xy 426.06166 -348.719389) (xy 426.039003 -348.769001) (xy 426.009515 -348.814884) (xy 425.973798 -348.856103)
			(xy 425.932578 -348.89182) (xy 425.886694 -348.921306) (xy 425.837081 -348.943963) (xy 425.784749 -348.959328)
			(xy 425.730763 -348.967089) (xy 425.703492 -348.967552) (xy 424.839892 -348.967552) (xy 424.812622 -348.967085)
			(xy 424.758638 -348.959322) (xy 424.706308 -348.943956) (xy 424.656698 -348.921299) (xy 424.610817 -348.891812)
			(xy 424.569599 -348.856095) (xy 424.533884 -348.814877) (xy 424.504398 -348.768995) (xy 424.481741 -348.719384)
			(xy 424.466376 -348.667054) (xy 424.458614 -348.61307) (xy 422.975766 -348.61307) (xy 422.968005 -348.667047)
			(xy 422.952642 -348.719372) (xy 422.929988 -348.768979) (xy 422.900506 -348.814857) (xy 422.864795 -348.856073)
			(xy 422.823583 -348.891787) (xy 422.777707 -348.921273) (xy 422.728102 -348.943931) (xy 422.675778 -348.959298)
			(xy 422.621799 -348.967063) (xy 422.594532 -348.967552) (xy 421.730932 -348.967552) (xy 421.703659 -348.967111)
			(xy 421.649667 -348.959352) (xy 421.597329 -348.943988) (xy 421.547711 -348.921332) (xy 421.501822 -348.891844)
			(xy 421.460597 -348.856126) (xy 421.424875 -348.814904) (xy 421.395384 -348.769017) (xy 421.372723 -348.719401)
			(xy 421.357355 -348.667064) (xy 421.349592 -348.613073) (xy 419.866888 -348.613073) (xy 419.859126 -348.667059)
			(xy 419.843759 -348.719393) (xy 419.821099 -348.769007) (xy 419.79161 -348.814891) (xy 419.75589 -348.85611)
			(xy 419.714668 -348.891827) (xy 419.668782 -348.921313) (xy 419.619167 -348.943968) (xy 419.566832 -348.959332)
			(xy 419.512844 -348.96709) (xy 419.485572 -348.967552) (xy 418.621972 -348.967552) (xy 418.594703 -348.967084)
			(xy 418.540721 -348.959319) (xy 418.488394 -348.94395) (xy 418.438786 -348.921292) (xy 418.392907 -348.891805)
			(xy 418.351692 -348.856088) (xy 418.315979 -348.81487) (xy 418.286495 -348.76899) (xy 418.26384 -348.71938)
			(xy 418.248476 -348.667051) (xy 418.240714 -348.613069) (xy 416.757866 -348.613069) (xy 416.750104 -348.667049)
			(xy 416.73474 -348.719376) (xy 416.712085 -348.768985) (xy 416.682601 -348.814864) (xy 416.646888 -348.85608)
			(xy 416.605673 -348.891794) (xy 416.559795 -348.92128) (xy 416.510188 -348.943936) (xy 416.457861 -348.959302)
			(xy 416.40388 -348.967065) (xy 416.376612 -348.967552) (xy 415.513012 -348.967552) (xy 415.48574 -348.967109)
			(xy 415.43175 -348.959348) (xy 415.379415 -348.943983) (xy 415.329799 -348.921325) (xy 415.283912 -348.891837)
			(xy 415.24269 -348.856119) (xy 415.20697 -348.814897) (xy 415.177481 -348.769012) (xy 415.154821 -348.719397)
			(xy 415.139454 -348.667062) (xy 415.131692 -348.613072) (xy 413.648988 -348.613072) (xy 413.641225 -348.667062)
			(xy 413.625857 -348.719397) (xy 413.603196 -348.769012) (xy 413.573705 -348.814897) (xy 413.537983 -348.856117)
			(xy 413.496759 -348.891834) (xy 413.45087 -348.921319) (xy 413.401252 -348.943974) (xy 413.348915 -348.959335)
			(xy 413.294925 -348.967092) (xy 413.267652 -348.967552) (xy 412.404052 -348.967552) (xy 412.376784 -348.967082)
			(xy 412.322804 -348.959315) (xy 412.270479 -348.943945) (xy 412.220874 -348.921285) (xy 412.174998 -348.891797)
			(xy 412.133785 -348.856081) (xy 412.098074 -348.814864) (xy 412.068592 -348.768984) (xy 412.045938 -348.719376)
			(xy 412.030575 -348.667049) (xy 412.022814 -348.613068) (xy 410.539989 -348.613068) (xy 410.539989 -348.613071)
			(xy 410.532226 -348.667057) (xy 410.51686 -348.719389) (xy 410.494203 -348.769001) (xy 410.464715 -348.814884)
			(xy 410.428998 -348.856103) (xy 410.387778 -348.89182) (xy 410.341894 -348.921306) (xy 410.292281 -348.943963)
			(xy 410.239949 -348.959328) (xy 410.185963 -348.967089) (xy 410.158692 -348.967552) (xy 409.295092 -348.967552)
			(xy 409.267822 -348.967085) (xy 409.213838 -348.959322) (xy 409.161508 -348.943956) (xy 409.111898 -348.921299)
			(xy 409.066017 -348.891812) (xy 409.024799 -348.856095) (xy 408.989084 -348.814877) (xy 408.959598 -348.768995)
			(xy 408.936941 -348.719384) (xy 408.921576 -348.667054) (xy 408.913814 -348.61307) (xy 403.522488 -348.61307)
			(xy 403.522488 -348.613071) (xy 403.514726 -348.667058) (xy 403.499359 -348.719391) (xy 403.476701 -348.769005)
			(xy 403.447212 -348.814888) (xy 403.411493 -348.856107) (xy 403.370272 -348.891824) (xy 403.324387 -348.92131)
			(xy 403.274773 -348.943966) (xy 403.222439 -348.95933) (xy 403.168451 -348.96709) (xy 403.14118 -348.967552)
			(xy 402.27758 -348.967552) (xy 402.250311 -348.967084) (xy 402.196328 -348.95932) (xy 402.143999 -348.943953)
			(xy 402.094391 -348.921295) (xy 402.048511 -348.891807) (xy 402.007295 -348.856091) (xy 401.971581 -348.814873)
			(xy 401.942096 -348.768992) (xy 401.91944 -348.719382) (xy 401.904076 -348.667052) (xy 401.896314 -348.613069)
			(xy 400.413466 -348.613069) (xy 400.405705 -348.667048) (xy 400.390341 -348.719375) (xy 400.367687 -348.768982)
			(xy 400.338203 -348.814861) (xy 400.302491 -348.856077) (xy 400.261277 -348.891791) (xy 400.2154 -348.921277)
			(xy 400.165794 -348.943934) (xy 400.113468 -348.9593) (xy 400.059488 -348.967064) (xy 400.03222 -348.967552)
			(xy 399.16862 -348.967552) (xy 399.141347 -348.96711) (xy 399.087357 -348.95935) (xy 399.03502 -348.943985)
			(xy 398.985403 -348.921328) (xy 398.939516 -348.89184) (xy 398.898293 -348.856122) (xy 398.862572 -348.8149)
			(xy 398.833082 -348.769014) (xy 398.810422 -348.719398) (xy 398.795054 -348.667063) (xy 398.787292 -348.613073)
			(xy 397.304588 -348.613073) (xy 397.296825 -348.667061) (xy 397.281458 -348.719396) (xy 397.258798 -348.76901)
			(xy 397.229307 -348.814894) (xy 397.193586 -348.856115) (xy 397.152362 -348.891831) (xy 397.106475 -348.921317)
			(xy 397.056858 -348.943972) (xy 397.004522 -348.959334) (xy 396.950532 -348.967091) (xy 396.92326 -348.967552)
			(xy 396.05966 -348.967552) (xy 396.032392 -348.967083) (xy 395.978411 -348.959316) (xy 395.926085 -348.943947)
			(xy 395.876479 -348.921288) (xy 395.830601 -348.8918) (xy 395.789388 -348.856084) (xy 395.753676 -348.814866)
			(xy 395.724193 -348.768986) (xy 395.701539 -348.719377) (xy 395.686175 -348.66705) (xy 395.678414 -348.613068)
			(xy 394.195566 -348.613068) (xy 394.195566 -348.613069) (xy 394.187804 -348.667051) (xy 394.172439 -348.719379)
			(xy 394.149784 -348.768988) (xy 394.120298 -348.814868) (xy 394.084584 -348.856084) (xy 394.043368 -348.891798)
			(xy 393.997488 -348.921284) (xy 393.947879 -348.943939) (xy 393.895551 -348.959304) (xy 393.841569 -348.967066)
			(xy 393.8143 -348.967552) (xy 392.9507 -348.967552) (xy 392.92343 -348.967086) (xy 392.869445 -348.959324)
			(xy 392.817114 -348.943958) (xy 392.767503 -348.921301) (xy 392.72162 -348.891814) (xy 392.680402 -348.856098)
			(xy 392.644686 -348.81488) (xy 392.615199 -348.768997) (xy 392.592542 -348.719386) (xy 392.577176 -348.667055)
			(xy 392.569414 -348.61307) (xy 391.086566 -348.61307) (xy 391.078805 -348.667046) (xy 391.063442 -348.71937)
			(xy 391.04079 -348.768977) (xy 391.011308 -348.814854) (xy 390.975598 -348.85607) (xy 390.934387 -348.891784)
			(xy 390.888512 -348.92127) (xy 390.838908 -348.943928) (xy 390.786585 -348.959297) (xy 390.732607 -348.967063)
			(xy 390.70534 -348.967552) (xy 389.84174 -348.967552) (xy 389.814466 -348.967111) (xy 389.760474 -348.959354)
			(xy 389.708135 -348.94399) (xy 389.658515 -348.921334) (xy 389.612626 -348.891847) (xy 389.5714 -348.856129)
			(xy 389.535677 -348.814906) (xy 389.506185 -348.76902) (xy 389.483524 -348.719403) (xy 389.468155 -348.667065)
			(xy 389.460392 -348.613074) (xy 387.977688 -348.613074) (xy 387.969926 -348.667058) (xy 387.954559 -348.719391)
			(xy 387.931901 -348.769005) (xy 387.902412 -348.814888) (xy 387.866693 -348.856107) (xy 387.825472 -348.891824)
			(xy 387.779587 -348.92131) (xy 387.729973 -348.943966) (xy 387.677639 -348.95933) (xy 387.623651 -348.96709)
			(xy 387.59638 -348.967552) (xy 386.73278 -348.967552) (xy 386.705511 -348.967084) (xy 386.651528 -348.95932)
			(xy 386.599199 -348.943953) (xy 386.549591 -348.921295) (xy 386.503711 -348.891807) (xy 386.462495 -348.856091)
			(xy 386.426781 -348.814873) (xy 386.397296 -348.768992) (xy 386.37464 -348.719382) (xy 386.359276 -348.667052)
			(xy 386.351514 -348.613069) (xy 384.868666 -348.613069) (xy 384.860905 -348.667048) (xy 384.845541 -348.719375)
			(xy 384.822887 -348.768982) (xy 384.793403 -348.814861) (xy 384.757691 -348.856077) (xy 384.716477 -348.891791)
			(xy 384.6706 -348.921277) (xy 384.620994 -348.943934) (xy 384.568668 -348.9593) (xy 384.514688 -348.967064)
			(xy 384.48742 -348.967552) (xy 383.62382 -348.967552) (xy 383.596547 -348.96711) (xy 383.542557 -348.95935)
			(xy 383.49022 -348.943985) (xy 383.440603 -348.921328) (xy 383.394716 -348.89184) (xy 383.353493 -348.856122)
			(xy 383.317772 -348.8149) (xy 383.288282 -348.769014) (xy 383.265622 -348.719398) (xy 383.250254 -348.667063)
			(xy 383.242492 -348.613073) (xy 381.759788 -348.613073) (xy 381.752025 -348.667061) (xy 381.736658 -348.719396)
			(xy 381.713998 -348.76901) (xy 381.684507 -348.814894) (xy 381.648786 -348.856115) (xy 381.607562 -348.891831)
			(xy 381.561675 -348.921317) (xy 381.512058 -348.943972) (xy 381.459722 -348.959334) (xy 381.405732 -348.967091)
			(xy 381.37846 -348.967552) (xy 380.51486 -348.967552) (xy 380.487592 -348.967083) (xy 380.433611 -348.959316)
			(xy 380.381285 -348.943947) (xy 380.331679 -348.921288) (xy 380.285801 -348.8918) (xy 380.244588 -348.856084)
			(xy 380.208876 -348.814866) (xy 380.179393 -348.768986) (xy 380.156739 -348.719377) (xy 380.141375 -348.66705)
			(xy 380.133614 -348.613068) (xy 378.650766 -348.613068) (xy 378.650766 -348.613069) (xy 378.643004 -348.667051)
			(xy 378.627639 -348.719379) (xy 378.604984 -348.768988) (xy 378.575498 -348.814868) (xy 378.539784 -348.856084)
			(xy 378.498568 -348.891798) (xy 378.452688 -348.921284) (xy 378.403079 -348.943939) (xy 378.350751 -348.959304)
			(xy 378.296769 -348.967066) (xy 378.2695 -348.967552) (xy 377.4059 -348.967552) (xy 377.37863 -348.967086)
			(xy 377.324645 -348.959324) (xy 377.272314 -348.943958) (xy 377.222703 -348.921301) (xy 377.17682 -348.891814)
			(xy 377.135602 -348.856098) (xy 377.099886 -348.81488) (xy 377.070399 -348.768997) (xy 377.047742 -348.719386)
			(xy 377.032376 -348.667055) (xy 377.024614 -348.61307) (xy 375.541766 -348.61307) (xy 375.534005 -348.667046)
			(xy 375.518642 -348.71937) (xy 375.49599 -348.768977) (xy 375.466508 -348.814854) (xy 375.430798 -348.85607)
			(xy 375.389587 -348.891784) (xy 375.343712 -348.92127) (xy 375.294108 -348.943928) (xy 375.241785 -348.959297)
			(xy 375.187807 -348.967063) (xy 375.16054 -348.967552) (xy 374.29694 -348.967552) (xy 374.269666 -348.967111)
			(xy 374.215674 -348.959354) (xy 374.163335 -348.94399) (xy 374.113715 -348.921334) (xy 374.067826 -348.891847)
			(xy 374.0266 -348.856129) (xy 373.990877 -348.814906) (xy 373.961385 -348.76902) (xy 373.938724 -348.719403)
			(xy 373.923355 -348.667065) (xy 373.915592 -348.613074) (xy 372.432888 -348.613074) (xy 372.425126 -348.667058)
			(xy 372.409759 -348.719391) (xy 372.387101 -348.769005) (xy 372.357612 -348.814888) (xy 372.321893 -348.856107)
			(xy 372.280672 -348.891824) (xy 372.234787 -348.92131) (xy 372.185173 -348.943966) (xy 372.132839 -348.95933)
			(xy 372.078851 -348.96709) (xy 372.05158 -348.967552) (xy 371.18798 -348.967552) (xy 371.160711 -348.967084)
			(xy 371.106728 -348.95932) (xy 371.054399 -348.943953) (xy 371.004791 -348.921295) (xy 370.958911 -348.891807)
			(xy 370.917695 -348.856091) (xy 370.881981 -348.814873) (xy 370.852496 -348.768992) (xy 370.82984 -348.719382)
			(xy 370.814476 -348.667052) (xy 370.806714 -348.613069) (xy 344.837266 -348.613069) (xy 344.829504 -348.66705)
			(xy 344.81414 -348.719378) (xy 344.791484 -348.768987) (xy 344.761999 -348.814866) (xy 344.726286 -348.856083)
			(xy 344.685069 -348.891797) (xy 344.63919 -348.921282) (xy 344.589582 -348.943938) (xy 344.537254 -348.959303)
			(xy 344.483272 -348.967065) (xy 344.456004 -348.967552) (xy 343.592404 -348.967552) (xy 343.565132 -348.967109)
			(xy 343.511143 -348.959347) (xy 343.458809 -348.943981) (xy 343.409194 -348.921323) (xy 343.363309 -348.891834)
			(xy 343.322087 -348.856116) (xy 343.286368 -348.814895) (xy 343.256879 -348.76901) (xy 343.234221 -348.719395)
			(xy 343.218854 -348.667061) (xy 343.211092 -348.613072) (xy 341.728265 -348.613072) (xy 341.720505 -348.667045)
			(xy 341.705143 -348.71937) (xy 341.68249 -348.768976) (xy 341.653009 -348.814853) (xy 341.6173 -348.856069)
			(xy 341.576088 -348.891783) (xy 341.530214 -348.921269) (xy 341.480611 -348.943927) (xy 341.428288 -348.959296)
			(xy 341.374311 -348.967063) (xy 341.347044 -348.967552) (xy 340.483444 -348.967552) (xy 340.45617 -348.967111)
			(xy 340.402177 -348.959354) (xy 340.349838 -348.943991) (xy 340.300218 -348.921336) (xy 340.254327 -348.891849)
			(xy 340.213101 -348.85613) (xy 340.177378 -348.814908) (xy 340.147885 -348.769021) (xy 340.125224 -348.719403)
			(xy 340.109855 -348.667066) (xy 340.102092 -348.613074) (xy 338.619388 -348.613074) (xy 338.611626 -348.667058)
			(xy 338.596259 -348.71939) (xy 338.573601 -348.769003) (xy 338.544113 -348.814887) (xy 338.508395 -348.856106)
			(xy 338.467174 -348.891823) (xy 338.421289 -348.921309) (xy 338.371675 -348.943965) (xy 338.319342 -348.95933)
			(xy 338.265355 -348.96709) (xy 338.238084 -348.967552) (xy 337.374484 -348.967552) (xy 337.347215 -348.967084)
			(xy 337.293231 -348.959321) (xy 337.240902 -348.943954) (xy 337.191293 -348.921296) (xy 337.145413 -348.891809)
			(xy 337.104196 -348.856093) (xy 337.068482 -348.814874) (xy 337.038996 -348.768993) (xy 337.016341 -348.719383)
			(xy 337.000976 -348.667053) (xy 336.993214 -348.613069) (xy 335.510366 -348.613069) (xy 335.502605 -348.667048)
			(xy 335.487241 -348.719374) (xy 335.464587 -348.768981) (xy 335.435104 -348.81486) (xy 335.399393 -348.856076)
			(xy 335.358179 -348.89179) (xy 335.312302 -348.921276) (xy 335.262696 -348.943933) (xy 335.210371 -348.9593)
			(xy 335.156392 -348.967064) (xy 335.129124 -348.967552) (xy 334.265524 -348.967552) (xy 334.238251 -348.96711)
			(xy 334.18426 -348.959351) (xy 334.131923 -348.943986) (xy 334.082306 -348.921329) (xy 334.036418 -348.891841)
			(xy 333.995194 -348.856123) (xy 333.959473 -348.814901) (xy 333.929982 -348.769015) (xy 333.907322 -348.719399)
			(xy 333.891955 -348.667063) (xy 333.884192 -348.613073) (xy 332.401488 -348.613073) (xy 332.393726 -348.667061)
			(xy 332.378358 -348.719395) (xy 332.355698 -348.769009) (xy 332.326208 -348.814893) (xy 332.290488 -348.856113)
			(xy 332.249264 -348.89183) (xy 332.203377 -348.921316) (xy 332.153761 -348.94397) (xy 332.101425 -348.959333)
			(xy 332.047436 -348.967091) (xy 332.020164 -348.967552) (xy 331.156564 -348.967552) (xy 331.129296 -348.967083)
			(xy 331.075314 -348.959317) (xy 331.022988 -348.943948) (xy 330.973381 -348.921289) (xy 330.927503 -348.891802)
			(xy 330.886289 -348.856086) (xy 330.850577 -348.814868) (xy 330.821093 -348.768987) (xy 330.798439 -348.719378)
			(xy 330.783075 -348.66705) (xy 330.775314 -348.613068) (xy 329.292466 -348.613068) (xy 329.284704 -348.66705)
			(xy 329.26934 -348.719378) (xy 329.246684 -348.768987) (xy 329.217199 -348.814866) (xy 329.181486 -348.856083)
			(xy 329.140269 -348.891797) (xy 329.09439 -348.921282) (xy 329.044782 -348.943938) (xy 328.992454 -348.959303)
			(xy 328.938472 -348.967065) (xy 328.911204 -348.967552) (xy 328.047604 -348.967552) (xy 328.020332 -348.967109)
			(xy 327.966343 -348.959347) (xy 327.914009 -348.943981) (xy 327.864394 -348.921323) (xy 327.818509 -348.891834)
			(xy 327.777287 -348.856116) (xy 327.741568 -348.814895) (xy 327.712079 -348.76901) (xy 327.689421 -348.719395)
			(xy 327.674054 -348.667061) (xy 327.666292 -348.613072) (xy 326.183465 -348.613072) (xy 326.175705 -348.667045)
			(xy 326.160343 -348.71937) (xy 326.13769 -348.768976) (xy 326.108209 -348.814853) (xy 326.0725 -348.856069)
			(xy 326.031288 -348.891783) (xy 325.985414 -348.921269) (xy 325.935811 -348.943927) (xy 325.883488 -348.959296)
			(xy 325.829511 -348.967063) (xy 325.802244 -348.967552) (xy 324.938644 -348.967552) (xy 324.91137 -348.967111)
			(xy 324.857377 -348.959354) (xy 324.805038 -348.943991) (xy 324.755418 -348.921336) (xy 324.709527 -348.891849)
			(xy 324.668301 -348.85613) (xy 324.632578 -348.814908) (xy 324.603085 -348.769021) (xy 324.580424 -348.719403)
			(xy 324.565055 -348.667066) (xy 324.557292 -348.613074) (xy 323.074588 -348.613074) (xy 323.066826 -348.667058)
			(xy 323.051459 -348.71939) (xy 323.028801 -348.769003) (xy 322.999313 -348.814887) (xy 322.963595 -348.856106)
			(xy 322.922374 -348.891823) (xy 322.876489 -348.921309) (xy 322.826875 -348.943965) (xy 322.774542 -348.95933)
			(xy 322.720555 -348.96709) (xy 322.693284 -348.967552) (xy 321.829684 -348.967552) (xy 321.802415 -348.967084)
			(xy 321.748431 -348.959321) (xy 321.696102 -348.943954) (xy 321.646493 -348.921296) (xy 321.600613 -348.891809)
			(xy 321.559396 -348.856093) (xy 321.523682 -348.814874) (xy 321.494196 -348.768993) (xy 321.471541 -348.719383)
			(xy 321.456176 -348.667053) (xy 321.448414 -348.613069) (xy 319.965566 -348.613069) (xy 319.957805 -348.667048)
			(xy 319.942441 -348.719374) (xy 319.919787 -348.768981) (xy 319.890304 -348.81486) (xy 319.854593 -348.856076)
			(xy 319.813379 -348.89179) (xy 319.767502 -348.921276) (xy 319.717896 -348.943933) (xy 319.665571 -348.9593)
			(xy 319.611592 -348.967064) (xy 319.584324 -348.967552) (xy 318.720724 -348.967552) (xy 318.693451 -348.96711)
			(xy 318.63946 -348.959351) (xy 318.587123 -348.943986) (xy 318.537506 -348.921329) (xy 318.491618 -348.891841)
			(xy 318.450394 -348.856123) (xy 318.414673 -348.814901) (xy 318.385182 -348.769015) (xy 318.362522 -348.719399)
			(xy 318.347155 -348.667063) (xy 318.339392 -348.613073) (xy 316.856688 -348.613073) (xy 316.848926 -348.667061)
			(xy 316.833558 -348.719395) (xy 316.810898 -348.769009) (xy 316.781408 -348.814893) (xy 316.745688 -348.856113)
			(xy 316.704464 -348.89183) (xy 316.658577 -348.921316) (xy 316.608961 -348.94397) (xy 316.556625 -348.959333)
			(xy 316.502636 -348.967091) (xy 316.475364 -348.967552) (xy 315.611764 -348.967552) (xy 315.584496 -348.967083)
			(xy 315.530514 -348.959317) (xy 315.478188 -348.943948) (xy 315.428581 -348.921289) (xy 315.382703 -348.891802)
			(xy 315.341489 -348.856086) (xy 315.305777 -348.814868) (xy 315.276293 -348.768987) (xy 315.253639 -348.719378)
			(xy 315.238275 -348.66705) (xy 315.230514 -348.613068) (xy 313.747666 -348.613068) (xy 313.739904 -348.66705)
			(xy 313.72454 -348.719378) (xy 313.701884 -348.768987) (xy 313.672399 -348.814866) (xy 313.636686 -348.856083)
			(xy 313.595469 -348.891797) (xy 313.54959 -348.921282) (xy 313.499982 -348.943938) (xy 313.447654 -348.959303)
			(xy 313.393672 -348.967065) (xy 313.366404 -348.967552) (xy 312.502804 -348.967552) (xy 312.475532 -348.967109)
			(xy 312.421543 -348.959347) (xy 312.369209 -348.943981) (xy 312.319594 -348.921323) (xy 312.273709 -348.891834)
			(xy 312.232487 -348.856116) (xy 312.196768 -348.814895) (xy 312.167279 -348.76901) (xy 312.144621 -348.719395)
			(xy 312.129254 -348.667061) (xy 312.121492 -348.613072) (xy 300.231566 -348.613072) (xy 300.223804 -348.667051)
			(xy 300.208439 -348.719379) (xy 300.185784 -348.768987) (xy 300.156299 -348.814867) (xy 300.120585 -348.856083)
			(xy 300.079369 -348.891798) (xy 300.033489 -348.921283) (xy 299.98388 -348.943939) (xy 299.931553 -348.959304)
			(xy 299.877571 -348.967065) (xy 299.850302 -348.967552) (xy 298.986702 -348.967552) (xy 298.95943 -348.967109)
			(xy 298.905442 -348.959347) (xy 298.853107 -348.94398) (xy 298.803493 -348.921322) (xy 298.757608 -348.891834)
			(xy 298.716386 -348.856115) (xy 298.680668 -348.814894) (xy 298.651179 -348.769009) (xy 298.628521 -348.719394)
			(xy 298.613154 -348.66706) (xy 298.605392 -348.613072) (xy 297.122565 -348.613072) (xy 297.114805 -348.667045)
			(xy 297.099443 -348.71937) (xy 297.07679 -348.768976) (xy 297.047309 -348.814854) (xy 297.011599 -348.856069)
			(xy 296.970387 -348.891784) (xy 296.924513 -348.92127) (xy 296.874909 -348.943928) (xy 296.822586 -348.959296)
			(xy 296.768609 -348.967063) (xy 296.741342 -348.967552) (xy 295.877742 -348.967552) (xy 295.850468 -348.967111)
			(xy 295.796476 -348.959354) (xy 295.744136 -348.943991) (xy 295.694517 -348.921335) (xy 295.648627 -348.891848)
			(xy 295.6074 -348.856129) (xy 295.571677 -348.814907) (xy 295.542185 -348.76902) (xy 295.519524 -348.719403)
			(xy 295.504155 -348.667066) (xy 295.496392 -348.613074) (xy 294.013688 -348.613074) (xy 294.005926 -348.667058)
			(xy 293.990559 -348.719391) (xy 293.967901 -348.769004) (xy 293.938412 -348.814887) (xy 293.902694 -348.856107)
			(xy 293.861473 -348.891823) (xy 293.815588 -348.92131) (xy 293.765974 -348.943966) (xy 293.713641 -348.95933)
			(xy 293.659653 -348.96709) (xy 293.632382 -348.967552) (xy 292.768782 -348.967552) (xy 292.741513 -348.967084)
			(xy 292.68753 -348.95932) (xy 292.635201 -348.943953) (xy 292.585592 -348.921295) (xy 292.539712 -348.891808)
			(xy 292.498495 -348.856092) (xy 292.462781 -348.814874) (xy 292.433296 -348.768992) (xy 292.410641 -348.719382)
			(xy 292.395276 -348.667053) (xy 292.387514 -348.613069) (xy 290.904666 -348.613069) (xy 290.896905 -348.667048)
			(xy 290.881541 -348.719374) (xy 290.858887 -348.768982) (xy 290.829404 -348.81486) (xy 290.793692 -348.856076)
			(xy 290.752478 -348.891791) (xy 290.706601 -348.921276) (xy 290.656995 -348.943933) (xy 290.604669 -348.9593)
			(xy 290.55069 -348.967064) (xy 290.523422 -348.967552) (xy 289.659822 -348.967552) (xy 289.632549 -348.96711)
			(xy 289.578559 -348.95935) (xy 289.526222 -348.943985) (xy 289.476605 -348.921329) (xy 289.430717 -348.891841)
			(xy 289.389493 -348.856122) (xy 289.353772 -348.814901) (xy 289.324282 -348.769015) (xy 289.301622 -348.719399)
			(xy 289.286254 -348.667063) (xy 289.278492 -348.613073) (xy 287.795788 -348.613073) (xy 287.788026 -348.667061)
			(xy 287.772658 -348.719395) (xy 287.749998 -348.76901) (xy 287.720508 -348.814894) (xy 287.684787 -348.856114)
			(xy 287.643563 -348.89183) (xy 287.597676 -348.921316) (xy 287.54806 -348.943971) (xy 287.495724 -348.959334)
			(xy 287.441734 -348.967091) (xy 287.414462 -348.967552) (xy 286.550862 -348.967552) (xy 286.523594 -348.967083)
			(xy 286.469613 -348.959317) (xy 286.417286 -348.943948) (xy 286.36768 -348.921289) (xy 286.321802 -348.891801)
			(xy 286.280588 -348.856085) (xy 286.244876 -348.814867) (xy 286.215393 -348.768987) (xy 286.192739 -348.719378)
			(xy 286.177375 -348.66705) (xy 286.169614 -348.613068) (xy 284.686766 -348.613068) (xy 284.686766 -348.613069)
			(xy 284.679004 -348.667051) (xy 284.663639 -348.719379) (xy 284.640984 -348.768987) (xy 284.611499 -348.814867)
			(xy 284.575785 -348.856083) (xy 284.534569 -348.891798) (xy 284.488689 -348.921283) (xy 284.43908 -348.943939)
			(xy 284.386753 -348.959304) (xy 284.332771 -348.967065) (xy 284.305502 -348.967552) (xy 283.441902 -348.967552)
			(xy 283.41463 -348.967109) (xy 283.360642 -348.959347) (xy 283.308307 -348.94398) (xy 283.258693 -348.921322)
			(xy 283.212808 -348.891834) (xy 283.171586 -348.856115) (xy 283.135868 -348.814894) (xy 283.106379 -348.769009)
			(xy 283.083721 -348.719394) (xy 283.068354 -348.66706) (xy 283.060592 -348.613072) (xy 281.577765 -348.613072)
			(xy 281.570005 -348.667045) (xy 281.554643 -348.71937) (xy 281.53199 -348.768976) (xy 281.502509 -348.814854)
			(xy 281.466799 -348.856069) (xy 281.425587 -348.891784) (xy 281.379713 -348.92127) (xy 281.330109 -348.943928)
			(xy 281.277786 -348.959296) (xy 281.223809 -348.967063) (xy 281.196542 -348.967552) (xy 280.332942 -348.967552)
			(xy 280.305668 -348.967111) (xy 280.251676 -348.959354) (xy 280.199336 -348.943991) (xy 280.149717 -348.921335)
			(xy 280.103827 -348.891848) (xy 280.0626 -348.856129) (xy 280.026877 -348.814907) (xy 279.997385 -348.76902)
			(xy 279.974724 -348.719403) (xy 279.959355 -348.667066) (xy 279.951592 -348.613074) (xy 278.468888 -348.613074)
			(xy 278.461126 -348.667058) (xy 278.445759 -348.719391) (xy 278.423101 -348.769004) (xy 278.393612 -348.814887)
			(xy 278.357894 -348.856107) (xy 278.316673 -348.891823) (xy 278.270788 -348.92131) (xy 278.221174 -348.943966)
			(xy 278.168841 -348.95933) (xy 278.114853 -348.96709) (xy 278.087582 -348.967552) (xy 277.223982 -348.967552)
			(xy 277.196713 -348.967084) (xy 277.14273 -348.95932) (xy 277.090401 -348.943953) (xy 277.040792 -348.921295)
			(xy 276.994912 -348.891808) (xy 276.953695 -348.856092) (xy 276.917981 -348.814874) (xy 276.888496 -348.768992)
			(xy 276.865841 -348.719382) (xy 276.850476 -348.667053) (xy 276.842714 -348.613069) (xy 275.359866 -348.613069)
			(xy 275.352105 -348.667048) (xy 275.336741 -348.719374) (xy 275.314087 -348.768982) (xy 275.284604 -348.81486)
			(xy 275.248892 -348.856076) (xy 275.207678 -348.891791) (xy 275.161801 -348.921276) (xy 275.112195 -348.943933)
			(xy 275.059869 -348.9593) (xy 275.00589 -348.967064) (xy 274.978622 -348.967552) (xy 274.115022 -348.967552)
			(xy 274.087749 -348.96711) (xy 274.033759 -348.95935) (xy 273.981422 -348.943985) (xy 273.931805 -348.921329)
			(xy 273.885917 -348.891841) (xy 273.844693 -348.856122) (xy 273.808972 -348.814901) (xy 273.779482 -348.769015)
			(xy 273.756822 -348.719399) (xy 273.741454 -348.667063) (xy 273.733692 -348.613073) (xy 272.250988 -348.613073)
			(xy 272.243226 -348.667061) (xy 272.227858 -348.719395) (xy 272.205198 -348.76901) (xy 272.175708 -348.814894)
			(xy 272.139987 -348.856114) (xy 272.098763 -348.89183) (xy 272.052876 -348.921316) (xy 272.00326 -348.943971)
			(xy 271.950924 -348.959334) (xy 271.896934 -348.967091) (xy 271.869662 -348.967552) (xy 271.006062 -348.967552)
			(xy 270.978794 -348.967083) (xy 270.924813 -348.959317) (xy 270.872486 -348.943948) (xy 270.82288 -348.921289)
			(xy 270.777002 -348.891801) (xy 270.735788 -348.856085) (xy 270.700076 -348.814867) (xy 270.670593 -348.768987)
			(xy 270.647939 -348.719378) (xy 270.632575 -348.66705) (xy 270.624814 -348.613068) (xy 269.141966 -348.613068)
			(xy 269.141966 -348.613069) (xy 269.134204 -348.667051) (xy 269.118839 -348.719379) (xy 269.096184 -348.768987)
			(xy 269.066699 -348.814867) (xy 269.030985 -348.856083) (xy 268.989769 -348.891798) (xy 268.943889 -348.921283)
			(xy 268.89428 -348.943939) (xy 268.841953 -348.959304) (xy 268.787971 -348.967065) (xy 268.760702 -348.967552)
			(xy 267.897102 -348.967552) (xy 267.86983 -348.967109) (xy 267.815842 -348.959347) (xy 267.763507 -348.94398)
			(xy 267.713893 -348.921322) (xy 267.668008 -348.891834) (xy 267.626786 -348.856115) (xy 267.591068 -348.814894)
			(xy 267.561579 -348.769009) (xy 267.538921 -348.719394) (xy 267.523554 -348.66706) (xy 267.515792 -348.613072)
			(xy 194.520565 -348.613072) (xy 194.512804 -348.667049) (xy 194.49744 -348.719376) (xy 194.474785 -348.768985)
			(xy 194.445301 -348.814864) (xy 194.409588 -348.85608) (xy 194.368373 -348.891794) (xy 194.322495 -348.92128)
			(xy 194.272888 -348.943936) (xy 194.220561 -348.959302) (xy 194.16658 -348.967065) (xy 194.139312 -348.967552)
			(xy 193.275712 -348.967552) (xy 193.24844 -348.967109) (xy 193.19445 -348.959348) (xy 193.142115 -348.943983)
			(xy 193.092499 -348.921325) (xy 193.046612 -348.891837) (xy 193.00539 -348.856119) (xy 192.96967 -348.814897)
			(xy 192.940181 -348.769012) (xy 192.917521 -348.719397) (xy 192.902154 -348.667062) (xy 192.894392 -348.613072)
			(xy 191.411688 -348.613072) (xy 191.403925 -348.667062) (xy 191.388557 -348.719397) (xy 191.365896 -348.769012)
			(xy 191.336405 -348.814897) (xy 191.300683 -348.856117) (xy 191.259459 -348.891834) (xy 191.21357 -348.921319)
			(xy 191.163952 -348.943974) (xy 191.111615 -348.959335) (xy 191.057625 -348.967092) (xy 191.030352 -348.967552)
			(xy 190.166752 -348.967552) (xy 190.139484 -348.967082) (xy 190.085504 -348.959315) (xy 190.033179 -348.943945)
			(xy 189.983574 -348.921285) (xy 189.937698 -348.891797) (xy 189.896485 -348.856081) (xy 189.860774 -348.814864)
			(xy 189.831292 -348.768984) (xy 189.808638 -348.719376) (xy 189.793275 -348.667049) (xy 189.785514 -348.613068)
			(xy 188.302689 -348.613068) (xy 188.302689 -348.613071) (xy 188.294926 -348.667057) (xy 188.27956 -348.719389)
			(xy 188.256903 -348.769001) (xy 188.227415 -348.814884) (xy 188.191698 -348.856103) (xy 188.150478 -348.89182)
			(xy 188.104594 -348.921306) (xy 188.054981 -348.943963) (xy 188.002649 -348.959328) (xy 187.948663 -348.967089)
			(xy 187.921392 -348.967552) (xy 187.057792 -348.967552) (xy 187.030522 -348.967085) (xy 186.976538 -348.959322)
			(xy 186.924208 -348.943956) (xy 186.874598 -348.921299) (xy 186.828717 -348.891812) (xy 186.787499 -348.856095)
			(xy 186.751784 -348.814877) (xy 186.722298 -348.768995) (xy 186.699641 -348.719384) (xy 186.684276 -348.667054)
			(xy 186.676514 -348.61307) (xy 185.193666 -348.61307) (xy 185.185905 -348.667047) (xy 185.170542 -348.719372)
			(xy 185.147888 -348.768979) (xy 185.118406 -348.814857) (xy 185.082695 -348.856073) (xy 185.041483 -348.891787)
			(xy 184.995607 -348.921273) (xy 184.946002 -348.943931) (xy 184.893678 -348.959298) (xy 184.839699 -348.967063)
			(xy 184.812432 -348.967552) (xy 183.948832 -348.967552) (xy 183.921559 -348.967111) (xy 183.867567 -348.959352)
			(xy 183.815229 -348.943988) (xy 183.765611 -348.921332) (xy 183.719722 -348.891844) (xy 183.678497 -348.856126)
			(xy 183.642775 -348.814904) (xy 183.613284 -348.769017) (xy 183.590623 -348.719401) (xy 183.575255 -348.667064)
			(xy 183.567492 -348.613073) (xy 182.084788 -348.613073) (xy 182.077026 -348.667059) (xy 182.061659 -348.719393)
			(xy 182.038999 -348.769007) (xy 182.00951 -348.814891) (xy 181.97379 -348.85611) (xy 181.932568 -348.891827)
			(xy 181.886682 -348.921313) (xy 181.837067 -348.943968) (xy 181.784732 -348.959332) (xy 181.730744 -348.96709)
			(xy 181.703472 -348.967552) (xy 180.839872 -348.967552) (xy 180.812603 -348.967084) (xy 180.758621 -348.959319)
			(xy 180.706294 -348.94395) (xy 180.656686 -348.921292) (xy 180.610807 -348.891805) (xy 180.569592 -348.856088)
			(xy 180.533879 -348.81487) (xy 180.504395 -348.76899) (xy 180.48174 -348.71938) (xy 180.466376 -348.667051)
			(xy 180.458614 -348.613069) (xy 178.975766 -348.613069) (xy 178.968004 -348.667049) (xy 178.95264 -348.719376)
			(xy 178.929985 -348.768985) (xy 178.900501 -348.814864) (xy 178.864788 -348.85608) (xy 178.823573 -348.891794)
			(xy 178.777695 -348.92128) (xy 178.728088 -348.943936) (xy 178.675761 -348.959302) (xy 178.62178 -348.967065)
			(xy 178.594512 -348.967552) (xy 177.730912 -348.967552) (xy 177.70364 -348.967109) (xy 177.64965 -348.959348)
			(xy 177.597315 -348.943983) (xy 177.547699 -348.921325) (xy 177.501812 -348.891837) (xy 177.46059 -348.856119)
			(xy 177.42487 -348.814897) (xy 177.395381 -348.769012) (xy 177.372721 -348.719397) (xy 177.357354 -348.667062)
			(xy 177.349592 -348.613072) (xy 175.866888 -348.613072) (xy 175.859125 -348.667062) (xy 175.843757 -348.719397)
			(xy 175.821096 -348.769012) (xy 175.791605 -348.814897) (xy 175.755883 -348.856117) (xy 175.714659 -348.891834)
			(xy 175.66877 -348.921319) (xy 175.619152 -348.943974) (xy 175.566815 -348.959335) (xy 175.512825 -348.967092)
			(xy 175.485552 -348.967552) (xy 174.621952 -348.967552) (xy 174.594684 -348.967082) (xy 174.540704 -348.959315)
			(xy 174.488379 -348.943945) (xy 174.438774 -348.921285) (xy 174.392898 -348.891797) (xy 174.351685 -348.856081)
			(xy 174.315974 -348.814864) (xy 174.286492 -348.768984) (xy 174.263838 -348.719376) (xy 174.248475 -348.667049)
			(xy 174.240714 -348.613068) (xy 172.757889 -348.613068) (xy 172.757889 -348.613071) (xy 172.750126 -348.667057)
			(xy 172.73476 -348.719389) (xy 172.712103 -348.769001) (xy 172.682615 -348.814884) (xy 172.646898 -348.856103)
			(xy 172.605678 -348.89182) (xy 172.559794 -348.921306) (xy 172.510181 -348.943963) (xy 172.457849 -348.959328)
			(xy 172.403863 -348.967089) (xy 172.376592 -348.967552) (xy 171.512992 -348.967552) (xy 171.485722 -348.967085)
			(xy 171.431738 -348.959322) (xy 171.379408 -348.943956) (xy 171.329798 -348.921299) (xy 171.283917 -348.891812)
			(xy 171.242699 -348.856095) (xy 171.206984 -348.814877) (xy 171.177498 -348.768995) (xy 171.154841 -348.719384)
			(xy 171.139476 -348.667054) (xy 171.131714 -348.61307) (xy 169.648866 -348.61307) (xy 169.641105 -348.667047)
			(xy 169.625742 -348.719372) (xy 169.603088 -348.768979) (xy 169.573606 -348.814857) (xy 169.537895 -348.856073)
			(xy 169.496683 -348.891787) (xy 169.450807 -348.921273) (xy 169.401202 -348.943931) (xy 169.348878 -348.959298)
			(xy 169.294899 -348.967063) (xy 169.267632 -348.967552) (xy 168.404032 -348.967552) (xy 168.376759 -348.967111)
			(xy 168.322767 -348.959352) (xy 168.270429 -348.943988) (xy 168.220811 -348.921332) (xy 168.174922 -348.891844)
			(xy 168.133697 -348.856126) (xy 168.097975 -348.814904) (xy 168.068484 -348.769017) (xy 168.045823 -348.719401)
			(xy 168.030455 -348.667064) (xy 168.022692 -348.613073) (xy 166.539988 -348.613073) (xy 166.532226 -348.667059)
			(xy 166.516859 -348.719393) (xy 166.494199 -348.769007) (xy 166.46471 -348.814891) (xy 166.42899 -348.85611)
			(xy 166.387768 -348.891827) (xy 166.341882 -348.921313) (xy 166.292267 -348.943968) (xy 166.239932 -348.959332)
			(xy 166.185944 -348.96709) (xy 166.158672 -348.967552) (xy 165.295072 -348.967552) (xy 165.267803 -348.967084)
			(xy 165.213821 -348.959319) (xy 165.161494 -348.94395) (xy 165.111886 -348.921292) (xy 165.066007 -348.891805)
			(xy 165.024792 -348.856088) (xy 164.989079 -348.81487) (xy 164.959595 -348.76899) (xy 164.93694 -348.71938)
			(xy 164.921576 -348.667051) (xy 164.913814 -348.613069) (xy 163.430966 -348.613069) (xy 163.423204 -348.667049)
			(xy 163.40784 -348.719376) (xy 163.385185 -348.768985) (xy 163.355701 -348.814864) (xy 163.319988 -348.85608)
			(xy 163.278773 -348.891794) (xy 163.232895 -348.92128) (xy 163.183288 -348.943936) (xy 163.130961 -348.959302)
			(xy 163.07698 -348.967065) (xy 163.049712 -348.967552) (xy 162.186112 -348.967552) (xy 162.15884 -348.967109)
			(xy 162.10485 -348.959348) (xy 162.052515 -348.943983) (xy 162.002899 -348.921325) (xy 161.957012 -348.891837)
			(xy 161.91579 -348.856119) (xy 161.88007 -348.814897) (xy 161.850581 -348.769012) (xy 161.827921 -348.719397)
			(xy 161.812554 -348.667062) (xy 161.804792 -348.613072) (xy 144.196565 -348.613072) (xy 144.188804 -348.66705)
			(xy 144.17344 -348.719377) (xy 144.150785 -348.768986) (xy 144.1213 -348.814865) (xy 144.085587 -348.856081)
			(xy 144.044371 -348.891796) (xy 143.998493 -348.921281) (xy 143.948885 -348.943937) (xy 143.896558 -348.959303)
			(xy 143.842576 -348.967065) (xy 143.815308 -348.967552) (xy 142.951708 -348.967552) (xy 142.924436 -348.967109)
			(xy 142.870447 -348.959348) (xy 142.818112 -348.943982) (xy 142.768496 -348.921324) (xy 142.72261 -348.891836)
			(xy 142.681388 -348.856117) (xy 142.645669 -348.814896) (xy 142.61618 -348.769011) (xy 142.593521 -348.719396)
			(xy 142.578154 -348.667061) (xy 142.570392 -348.613072) (xy 141.087565 -348.613072) (xy 141.079806 -348.667044)
			(xy 141.064443 -348.719369) (xy 141.041791 -348.768974) (xy 141.01231 -348.814852) (xy 140.976601 -348.856067)
			(xy 140.93539 -348.891781) (xy 140.889517 -348.921268) (xy 140.839914 -348.943926) (xy 140.787591 -348.959295)
			(xy 140.733614 -348.967062) (xy 140.706348 -348.967552) (xy 139.842748 -348.967552) (xy 139.815474 -348.967112)
			(xy 139.761481 -348.959355) (xy 139.709141 -348.943992) (xy 139.65952 -348.921337) (xy 139.613629 -348.89185)
			(xy 139.572402 -348.856132) (xy 139.536679 -348.814909) (xy 139.507186 -348.769022) (xy 139.484524 -348.719404)
			(xy 139.469155 -348.667066) (xy 139.461392 -348.613074) (xy 137.978689 -348.613074) (xy 137.970926 -348.667057)
			(xy 137.95556 -348.71939) (xy 137.932902 -348.769002) (xy 137.903414 -348.814885) (xy 137.867696 -348.856105)
			(xy 137.826476 -348.891821) (xy 137.780592 -348.921308) (xy 137.730978 -348.943964) (xy 137.678646 -348.959329)
			(xy 137.624659 -348.967089) (xy 137.597388 -348.967552) (xy 136.733788 -348.967552) (xy 136.706518 -348.967085)
			(xy 136.652535 -348.959321) (xy 136.600205 -348.943955) (xy 136.550595 -348.921297) (xy 136.504715 -348.89181)
			(xy 136.463497 -348.856094) (xy 136.427783 -348.814876) (xy 136.398297 -348.768994) (xy 136.375641 -348.719383)
			(xy 136.360276 -348.667053) (xy 136.352514 -348.61307) (xy 134.869666 -348.61307) (xy 134.861905 -348.667047)
			(xy 134.846541 -348.719373) (xy 134.823888 -348.76898) (xy 134.794405 -348.814858) (xy 134.758694 -348.856074)
			(xy 134.717481 -348.891789) (xy 134.671605 -348.921274) (xy 134.621999 -348.943932) (xy 134.569675 -348.959299)
			(xy 134.515695 -348.967064) (xy 134.488428 -348.967552) (xy 133.624828 -348.967552) (xy 133.597555 -348.96711)
			(xy 133.543564 -348.959351) (xy 133.491226 -348.943987) (xy 133.441608 -348.92133) (xy 133.39572 -348.891843)
			(xy 133.354495 -348.856124) (xy 133.318774 -348.814903) (xy 133.289283 -348.769016) (xy 133.266623 -348.7194)
			(xy 133.251255 -348.667064) (xy 133.243492 -348.613073) (xy 131.760788 -348.613073) (xy 131.753026 -348.66706)
			(xy 131.737658 -348.719394) (xy 131.714999 -348.769008) (xy 131.685509 -348.814892) (xy 131.649789 -348.856112)
			(xy 131.608566 -348.891828) (xy 131.56268 -348.921314) (xy 131.513064 -348.943969) (xy 131.460729 -348.959332)
			(xy 131.40674 -348.967091) (xy 131.379468 -348.967552) (xy 130.515868 -348.967552) (xy 130.488599 -348.967083)
			(xy 130.434618 -348.959318) (xy 130.382291 -348.943949) (xy 130.332683 -348.921291) (xy 130.286805 -348.891803)
			(xy 130.24559 -348.856087) (xy 130.209878 -348.814869) (xy 130.180394 -348.768989) (xy 130.15774 -348.719379)
			(xy 130.142375 -348.667051) (xy 130.134614 -348.613069) (xy 128.651766 -348.613069) (xy 128.644004 -348.66705)
			(xy 128.62864 -348.719377) (xy 128.605985 -348.768986) (xy 128.5765 -348.814865) (xy 128.540787 -348.856081)
			(xy 128.499571 -348.891796) (xy 128.453693 -348.921281) (xy 128.404085 -348.943937) (xy 128.351758 -348.959303)
			(xy 128.297776 -348.967065) (xy 128.270508 -348.967552) (xy 127.406908 -348.967552) (xy 127.379636 -348.967109)
			(xy 127.325647 -348.959348) (xy 127.273312 -348.943982) (xy 127.223696 -348.921324) (xy 127.17781 -348.891836)
			(xy 127.136588 -348.856117) (xy 127.100869 -348.814896) (xy 127.07138 -348.769011) (xy 127.048721 -348.719396)
			(xy 127.033354 -348.667061) (xy 127.025592 -348.613072) (xy 125.542765 -348.613072) (xy 125.535006 -348.667044)
			(xy 125.519643 -348.719369) (xy 125.496991 -348.768974) (xy 125.46751 -348.814852) (xy 125.431801 -348.856067)
			(xy 125.39059 -348.891781) (xy 125.344717 -348.921268) (xy 125.295114 -348.943926) (xy 125.242791 -348.959295)
			(xy 125.188814 -348.967062) (xy 125.161548 -348.967552) (xy 124.297948 -348.967552) (xy 124.270674 -348.967112)
			(xy 124.216681 -348.959355) (xy 124.164341 -348.943992) (xy 124.11472 -348.921337) (xy 124.068829 -348.89185)
			(xy 124.027602 -348.856132) (xy 123.991879 -348.814909) (xy 123.962386 -348.769022) (xy 123.939724 -348.719404)
			(xy 123.924355 -348.667066) (xy 123.916592 -348.613074) (xy 122.433889 -348.613074) (xy 122.426126 -348.667057)
			(xy 122.41076 -348.71939) (xy 122.388102 -348.769002) (xy 122.358614 -348.814885) (xy 122.322896 -348.856105)
			(xy 122.281676 -348.891821) (xy 122.235792 -348.921308) (xy 122.186178 -348.943964) (xy 122.133846 -348.959329)
			(xy 122.079859 -348.967089) (xy 122.052588 -348.967552) (xy 121.188988 -348.967552) (xy 121.161718 -348.967085)
			(xy 121.107735 -348.959321) (xy 121.055405 -348.943955) (xy 121.005795 -348.921297) (xy 120.959915 -348.89181)
			(xy 120.918697 -348.856094) (xy 120.882983 -348.814876) (xy 120.853497 -348.768994) (xy 120.830841 -348.719383)
			(xy 120.815476 -348.667053) (xy 120.807714 -348.61307) (xy 119.324866 -348.61307) (xy 119.317105 -348.667047)
			(xy 119.301741 -348.719373) (xy 119.279088 -348.76898) (xy 119.249605 -348.814858) (xy 119.213894 -348.856074)
			(xy 119.172681 -348.891789) (xy 119.126805 -348.921274) (xy 119.077199 -348.943932) (xy 119.024875 -348.959299)
			(xy 118.970895 -348.967064) (xy 118.943628 -348.967552) (xy 118.080028 -348.967552) (xy 118.052755 -348.96711)
			(xy 117.998764 -348.959351) (xy 117.946426 -348.943987) (xy 117.896808 -348.92133) (xy 117.85092 -348.891843)
			(xy 117.809695 -348.856124) (xy 117.773974 -348.814903) (xy 117.744483 -348.769016) (xy 117.721823 -348.7194)
			(xy 117.706455 -348.667064) (xy 117.698692 -348.613073) (xy 116.215988 -348.613073) (xy 116.208226 -348.66706)
			(xy 116.192858 -348.719394) (xy 116.170199 -348.769008) (xy 116.140709 -348.814892) (xy 116.104989 -348.856112)
			(xy 116.063766 -348.891828) (xy 116.01788 -348.921314) (xy 115.968264 -348.943969) (xy 115.915929 -348.959332)
			(xy 115.86194 -348.967091) (xy 115.834668 -348.967552) (xy 114.971068 -348.967552) (xy 114.943799 -348.967083)
			(xy 114.889818 -348.959318) (xy 114.837491 -348.943949) (xy 114.787883 -348.921291) (xy 114.742005 -348.891803)
			(xy 114.70079 -348.856087) (xy 114.665078 -348.814869) (xy 114.635594 -348.768989) (xy 114.61294 -348.719379)
			(xy 114.597575 -348.667051) (xy 114.589814 -348.613069) (xy 113.106966 -348.613069) (xy 113.099204 -348.66705)
			(xy 113.08384 -348.719377) (xy 113.061185 -348.768986) (xy 113.0317 -348.814865) (xy 112.995987 -348.856081)
			(xy 112.954771 -348.891796) (xy 112.908893 -348.921281) (xy 112.859285 -348.943937) (xy 112.806958 -348.959303)
			(xy 112.752976 -348.967065) (xy 112.725708 -348.967552) (xy 111.862108 -348.967552) (xy 111.834836 -348.967109)
			(xy 111.780847 -348.959348) (xy 111.728512 -348.943982) (xy 111.678896 -348.921324) (xy 111.63301 -348.891836)
			(xy 111.591788 -348.856117) (xy 111.556069 -348.814896) (xy 111.52658 -348.769011) (xy 111.503921 -348.719396)
			(xy 111.488554 -348.667061) (xy 111.480792 -348.613072) (xy 93.706665 -348.613072) (xy 93.698905 -348.667045)
			(xy 93.683543 -348.71937) (xy 93.66089 -348.768976) (xy 93.631409 -348.814854) (xy 93.595699 -348.856069)
			(xy 93.554487 -348.891784) (xy 93.508613 -348.92127) (xy 93.459009 -348.943928) (xy 93.406686 -348.959296)
			(xy 93.352709 -348.967063) (xy 93.325442 -348.967552) (xy 92.461842 -348.967552) (xy 92.434568 -348.967111)
			(xy 92.380576 -348.959354) (xy 92.328236 -348.943991) (xy 92.278617 -348.921335) (xy 92.232727 -348.891848)
			(xy 92.1915 -348.856129) (xy 92.155777 -348.814907) (xy 92.126285 -348.76902) (xy 92.103624 -348.719403)
			(xy 92.088255 -348.667066) (xy 92.080492 -348.613074) (xy 90.597788 -348.613074) (xy 90.590026 -348.667058)
			(xy 90.574659 -348.719391) (xy 90.552001 -348.769004) (xy 90.522512 -348.814887) (xy 90.486794 -348.856107)
			(xy 90.445573 -348.891823) (xy 90.399688 -348.92131) (xy 90.350074 -348.943966) (xy 90.297741 -348.95933)
			(xy 90.243753 -348.96709) (xy 90.216482 -348.967552) (xy 89.352882 -348.967552) (xy 89.325613 -348.967084)
			(xy 89.27163 -348.95932) (xy 89.219301 -348.943953) (xy 89.169692 -348.921295) (xy 89.123812 -348.891808)
			(xy 89.082595 -348.856092) (xy 89.046881 -348.814874) (xy 89.017396 -348.768992) (xy 88.994741 -348.719382)
			(xy 88.979376 -348.667053) (xy 88.971614 -348.613069) (xy 87.488766 -348.613069) (xy 87.481005 -348.667048)
			(xy 87.465641 -348.719374) (xy 87.442987 -348.768982) (xy 87.413504 -348.81486) (xy 87.377792 -348.856076)
			(xy 87.336578 -348.891791) (xy 87.290701 -348.921276) (xy 87.241095 -348.943933) (xy 87.188769 -348.9593)
			(xy 87.13479 -348.967064) (xy 87.107522 -348.967552) (xy 86.243922 -348.967552) (xy 86.216649 -348.96711)
			(xy 86.162659 -348.95935) (xy 86.110322 -348.943985) (xy 86.060705 -348.921329) (xy 86.014817 -348.891841)
			(xy 85.973593 -348.856122) (xy 85.937872 -348.814901) (xy 85.908382 -348.769015) (xy 85.885722 -348.719399)
			(xy 85.870354 -348.667063) (xy 85.862592 -348.613073) (xy 84.379888 -348.613073) (xy 84.372126 -348.667061)
			(xy 84.356758 -348.719395) (xy 84.334098 -348.76901) (xy 84.304608 -348.814894) (xy 84.268887 -348.856114)
			(xy 84.227663 -348.89183) (xy 84.181776 -348.921316) (xy 84.13216 -348.943971) (xy 84.079824 -348.959334)
			(xy 84.025834 -348.967091) (xy 83.998562 -348.967552) (xy 83.134962 -348.967552) (xy 83.107694 -348.967083)
			(xy 83.053713 -348.959317) (xy 83.001386 -348.943948) (xy 82.95178 -348.921289) (xy 82.905902 -348.891801)
			(xy 82.864688 -348.856085) (xy 82.828976 -348.814867) (xy 82.799493 -348.768987) (xy 82.776839 -348.719378)
			(xy 82.761475 -348.66705) (xy 82.753714 -348.613068) (xy 81.270866 -348.613068) (xy 81.270866 -348.613069)
			(xy 81.263104 -348.667051) (xy 81.247739 -348.719379) (xy 81.225084 -348.768987) (xy 81.195599 -348.814867)
			(xy 81.159885 -348.856083) (xy 81.118669 -348.891798) (xy 81.072789 -348.921283) (xy 81.02318 -348.943939)
			(xy 80.970853 -348.959304) (xy 80.916871 -348.967065) (xy 80.889602 -348.967552) (xy 80.026002 -348.967552)
			(xy 79.99873 -348.967109) (xy 79.944742 -348.959347) (xy 79.892407 -348.94398) (xy 79.842793 -348.921322)
			(xy 79.796908 -348.891834) (xy 79.755686 -348.856115) (xy 79.719968 -348.814894) (xy 79.690479 -348.769009)
			(xy 79.667821 -348.719394) (xy 79.652454 -348.66706) (xy 79.644692 -348.613072) (xy 78.161865 -348.613072)
			(xy 78.154105 -348.667045) (xy 78.138743 -348.71937) (xy 78.11609 -348.768976) (xy 78.086609 -348.814854)
			(xy 78.050899 -348.856069) (xy 78.009687 -348.891784) (xy 77.963813 -348.92127) (xy 77.914209 -348.943928)
			(xy 77.861886 -348.959296) (xy 77.807909 -348.967063) (xy 77.780642 -348.967552) (xy 76.917042 -348.967552)
			(xy 76.889768 -348.967111) (xy 76.835776 -348.959354) (xy 76.783436 -348.943991) (xy 76.733817 -348.921335)
			(xy 76.687927 -348.891848) (xy 76.6467 -348.856129) (xy 76.610977 -348.814907) (xy 76.581485 -348.76902)
			(xy 76.558824 -348.719403) (xy 76.543455 -348.667066) (xy 76.535692 -348.613074) (xy 75.052988 -348.613074)
			(xy 75.045226 -348.667058) (xy 75.029859 -348.719391) (xy 75.007201 -348.769004) (xy 74.977712 -348.814887)
			(xy 74.941994 -348.856107) (xy 74.900773 -348.891823) (xy 74.854888 -348.92131) (xy 74.805274 -348.943966)
			(xy 74.752941 -348.95933) (xy 74.698953 -348.96709) (xy 74.671682 -348.967552) (xy 73.808082 -348.967552)
			(xy 73.780813 -348.967084) (xy 73.72683 -348.95932) (xy 73.674501 -348.943953) (xy 73.624892 -348.921295)
			(xy 73.579012 -348.891808) (xy 73.537795 -348.856092) (xy 73.502081 -348.814874) (xy 73.472596 -348.768992)
			(xy 73.449941 -348.719382) (xy 73.434576 -348.667053) (xy 73.426814 -348.613069) (xy 71.943966 -348.613069)
			(xy 71.936205 -348.667048) (xy 71.920841 -348.719374) (xy 71.898187 -348.768982) (xy 71.868704 -348.81486)
			(xy 71.832992 -348.856076) (xy 71.791778 -348.891791) (xy 71.745901 -348.921276) (xy 71.696295 -348.943933)
			(xy 71.643969 -348.9593) (xy 71.58999 -348.967064) (xy 71.562722 -348.967552) (xy 70.699122 -348.967552)
			(xy 70.671849 -348.96711) (xy 70.617859 -348.95935) (xy 70.565522 -348.943985) (xy 70.515905 -348.921329)
			(xy 70.470017 -348.891841) (xy 70.428793 -348.856122) (xy 70.393072 -348.814901) (xy 70.363582 -348.769015)
			(xy 70.340922 -348.719399) (xy 70.325554 -348.667063) (xy 70.317792 -348.613073) (xy 68.835088 -348.613073)
			(xy 68.827326 -348.667061) (xy 68.811958 -348.719395) (xy 68.789298 -348.76901) (xy 68.759808 -348.814894)
			(xy 68.724087 -348.856114) (xy 68.682863 -348.89183) (xy 68.636976 -348.921316) (xy 68.58736 -348.943971)
			(xy 68.535024 -348.959334) (xy 68.481034 -348.967091) (xy 68.453762 -348.967552) (xy 67.590162 -348.967552)
			(xy 67.562894 -348.967083) (xy 67.508913 -348.959317) (xy 67.456586 -348.943948) (xy 67.40698 -348.921289)
			(xy 67.361102 -348.891801) (xy 67.319888 -348.856085) (xy 67.284176 -348.814867) (xy 67.254693 -348.768987)
			(xy 67.232039 -348.719378) (xy 67.216675 -348.66705) (xy 67.208914 -348.613068) (xy 65.726066 -348.613068)
			(xy 65.726066 -348.613069) (xy 65.718304 -348.667051) (xy 65.702939 -348.719379) (xy 65.680284 -348.768987)
			(xy 65.650799 -348.814867) (xy 65.615085 -348.856083) (xy 65.573869 -348.891798) (xy 65.527989 -348.921283)
			(xy 65.47838 -348.943939) (xy 65.426053 -348.959304) (xy 65.372071 -348.967065) (xy 65.344802 -348.967552)
			(xy 64.481202 -348.967552) (xy 64.45393 -348.967109) (xy 64.399942 -348.959347) (xy 64.347607 -348.94398)
			(xy 64.297993 -348.921322) (xy 64.252108 -348.891834) (xy 64.210886 -348.856115) (xy 64.175168 -348.814894)
			(xy 64.145679 -348.769009) (xy 64.123021 -348.719394) (xy 64.107654 -348.66706) (xy 64.099892 -348.613072)
			(xy 62.617065 -348.613072) (xy 62.609305 -348.667045) (xy 62.593943 -348.71937) (xy 62.57129 -348.768976)
			(xy 62.541809 -348.814854) (xy 62.506099 -348.856069) (xy 62.464887 -348.891784) (xy 62.419013 -348.92127)
			(xy 62.369409 -348.943928) (xy 62.317086 -348.959296) (xy 62.263109 -348.967063) (xy 62.235842 -348.967552)
			(xy 61.372242 -348.967552) (xy 61.344968 -348.967111) (xy 61.290976 -348.959354) (xy 61.238636 -348.943991)
			(xy 61.189017 -348.921335) (xy 61.143127 -348.891848) (xy 61.1019 -348.856129) (xy 61.066177 -348.814907)
			(xy 61.036685 -348.76902) (xy 61.014024 -348.719403) (xy 60.998655 -348.667066) (xy 60.990892 -348.613074)
			(xy 51.666865 -348.613074) (xy 51.659106 -348.667044) (xy 51.643743 -348.719369) (xy 51.621091 -348.768974)
			(xy 51.59161 -348.814852) (xy 51.555901 -348.856067) (xy 51.51469 -348.891781) (xy 51.468817 -348.921268)
			(xy 51.419214 -348.943926) (xy 51.366891 -348.959295) (xy 51.312914 -348.967062) (xy 51.285648 -348.967552)
			(xy 50.422048 -348.967552) (xy 50.394774 -348.967112) (xy 50.340781 -348.959355) (xy 50.288441 -348.943992)
			(xy 50.23882 -348.921337) (xy 50.192929 -348.89185) (xy 50.151702 -348.856132) (xy 50.115979 -348.814909)
			(xy 50.086486 -348.769022) (xy 50.063824 -348.719404) (xy 50.048455 -348.667066) (xy 50.040692 -348.613074)
			(xy 48.557989 -348.613074) (xy 48.550226 -348.667057) (xy 48.53486 -348.71939) (xy 48.512202 -348.769002)
			(xy 48.482714 -348.814885) (xy 48.446996 -348.856105) (xy 48.405776 -348.891821) (xy 48.359892 -348.921308)
			(xy 48.310278 -348.943964) (xy 48.257946 -348.959329) (xy 48.203959 -348.967089) (xy 48.176688 -348.967552)
			(xy 47.313088 -348.967552) (xy 47.285818 -348.967085) (xy 47.231835 -348.959321) (xy 47.179505 -348.943955)
			(xy 47.129895 -348.921297) (xy 47.084015 -348.89181) (xy 47.042797 -348.856094) (xy 47.007083 -348.814876)
			(xy 46.977597 -348.768994) (xy 46.954941 -348.719383) (xy 46.939576 -348.667053) (xy 46.931814 -348.61307)
			(xy 45.448966 -348.61307) (xy 45.441205 -348.667047) (xy 45.425841 -348.719373) (xy 45.403188 -348.76898)
			(xy 45.373705 -348.814858) (xy 45.337994 -348.856074) (xy 45.296781 -348.891789) (xy 45.250905 -348.921274)
			(xy 45.201299 -348.943932) (xy 45.148975 -348.959299) (xy 45.094995 -348.967064) (xy 45.067728 -348.967552)
			(xy 44.204128 -348.967552) (xy 44.176855 -348.96711) (xy 44.122864 -348.959351) (xy 44.070526 -348.943987)
			(xy 44.020908 -348.92133) (xy 43.97502 -348.891843) (xy 43.933795 -348.856124) (xy 43.898074 -348.814903)
			(xy 43.868583 -348.769016) (xy 43.845923 -348.7194) (xy 43.830555 -348.667064) (xy 43.822792 -348.613073)
			(xy 42.340088 -348.613073) (xy 42.332326 -348.66706) (xy 42.316958 -348.719394) (xy 42.294299 -348.769008)
			(xy 42.264809 -348.814892) (xy 42.229089 -348.856112) (xy 42.187866 -348.891828) (xy 42.14198 -348.921314)
			(xy 42.092364 -348.943969) (xy 42.040029 -348.959332) (xy 41.98604 -348.967091) (xy 41.958768 -348.967552)
			(xy 41.095168 -348.967552) (xy 41.067899 -348.967083) (xy 41.013918 -348.959318) (xy 40.961591 -348.943949)
			(xy 40.911983 -348.921291) (xy 40.866105 -348.891803) (xy 40.82489 -348.856087) (xy 40.789178 -348.814869)
			(xy 40.759694 -348.768989) (xy 40.73704 -348.719379) (xy 40.721675 -348.667051) (xy 40.713914 -348.613069)
			(xy 39.231066 -348.613069) (xy 39.223304 -348.66705) (xy 39.20794 -348.719377) (xy 39.185285 -348.768986)
			(xy 39.1558 -348.814865) (xy 39.120087 -348.856081) (xy 39.078871 -348.891796) (xy 39.032993 -348.921281)
			(xy 38.983385 -348.943937) (xy 38.931058 -348.959303) (xy 38.877076 -348.967065) (xy 38.849808 -348.967552)
			(xy 37.986208 -348.967552) (xy 37.958936 -348.967109) (xy 37.904947 -348.959348) (xy 37.852612 -348.943982)
			(xy 37.802996 -348.921324) (xy 37.75711 -348.891836) (xy 37.715888 -348.856117) (xy 37.680169 -348.814896)
			(xy 37.65068 -348.769011) (xy 37.628021 -348.719396) (xy 37.612654 -348.667061) (xy 37.604892 -348.613072)
			(xy 36.122065 -348.613072) (xy 36.114306 -348.667044) (xy 36.098943 -348.719369) (xy 36.076291 -348.768974)
			(xy 36.04681 -348.814852) (xy 36.011101 -348.856067) (xy 35.96989 -348.891781) (xy 35.924017 -348.921268)
			(xy 35.874414 -348.943926) (xy 35.822091 -348.959295) (xy 35.768114 -348.967062) (xy 35.740848 -348.967552)
			(xy 34.877248 -348.967552) (xy 34.849974 -348.967112) (xy 34.795981 -348.959355) (xy 34.743641 -348.943992)
			(xy 34.69402 -348.921337) (xy 34.648129 -348.89185) (xy 34.606902 -348.856132) (xy 34.571179 -348.814909)
			(xy 34.541686 -348.769022) (xy 34.519024 -348.719404) (xy 34.503655 -348.667066) (xy 34.495892 -348.613074)
			(xy 33.013189 -348.613074) (xy 33.005426 -348.667057) (xy 32.99006 -348.71939) (xy 32.967402 -348.769002)
			(xy 32.937914 -348.814885) (xy 32.902196 -348.856105) (xy 32.860976 -348.891821) (xy 32.815092 -348.921308)
			(xy 32.765478 -348.943964) (xy 32.713146 -348.959329) (xy 32.659159 -348.967089) (xy 32.631888 -348.967552)
			(xy 31.768288 -348.967552) (xy 31.741018 -348.967085) (xy 31.687035 -348.959321) (xy 31.634705 -348.943955)
			(xy 31.585095 -348.921297) (xy 31.539215 -348.89181) (xy 31.497997 -348.856094) (xy 31.462283 -348.814876)
			(xy 31.432797 -348.768994) (xy 31.410141 -348.719383) (xy 31.394776 -348.667053) (xy 31.387014 -348.61307)
			(xy 29.904166 -348.61307) (xy 29.896405 -348.667047) (xy 29.881041 -348.719373) (xy 29.858388 -348.76898)
			(xy 29.828905 -348.814858) (xy 29.793194 -348.856074) (xy 29.751981 -348.891789) (xy 29.706105 -348.921274)
			(xy 29.656499 -348.943932) (xy 29.604175 -348.959299) (xy 29.550195 -348.967064) (xy 29.522928 -348.967552)
			(xy 28.659328 -348.967552) (xy 28.632055 -348.96711) (xy 28.578064 -348.959351) (xy 28.525726 -348.943987)
			(xy 28.476108 -348.92133) (xy 28.43022 -348.891843) (xy 28.388995 -348.856124) (xy 28.353274 -348.814903)
			(xy 28.323783 -348.769016) (xy 28.301123 -348.7194) (xy 28.285755 -348.667064) (xy 28.277992 -348.613073)
			(xy 26.795288 -348.613073) (xy 26.787526 -348.66706) (xy 26.772158 -348.719394) (xy 26.749499 -348.769008)
			(xy 26.720009 -348.814892) (xy 26.684289 -348.856112) (xy 26.643066 -348.891828) (xy 26.59718 -348.921314)
			(xy 26.547564 -348.943969) (xy 26.495229 -348.959332) (xy 26.44124 -348.967091) (xy 26.413968 -348.967552)
			(xy 25.550368 -348.967552) (xy 25.523099 -348.967083) (xy 25.469118 -348.959318) (xy 25.416791 -348.943949)
			(xy 25.367183 -348.921291) (xy 25.321305 -348.891803) (xy 25.28009 -348.856087) (xy 25.244378 -348.814869)
			(xy 25.214894 -348.768989) (xy 25.19224 -348.719379) (xy 25.176875 -348.667051) (xy 25.169114 -348.613069)
			(xy 23.686266 -348.613069) (xy 23.678504 -348.66705) (xy 23.66314 -348.719377) (xy 23.640485 -348.768986)
			(xy 23.611 -348.814865) (xy 23.575287 -348.856081) (xy 23.534071 -348.891796) (xy 23.488193 -348.921281)
			(xy 23.438585 -348.943937) (xy 23.386258 -348.959303) (xy 23.332276 -348.967065) (xy 23.305008 -348.967552)
			(xy 22.441408 -348.967552) (xy 22.414136 -348.967109) (xy 22.360147 -348.959348) (xy 22.307812 -348.943982)
			(xy 22.258196 -348.921324) (xy 22.21231 -348.891836) (xy 22.171088 -348.856117) (xy 22.135369 -348.814896)
			(xy 22.10588 -348.769011) (xy 22.083221 -348.719396) (xy 22.067854 -348.667061) (xy 22.060092 -348.613072)
			(xy 20.577347 -348.613072) (xy 20.569586 -348.667048) (xy 20.55422 -348.719381) (xy 20.531562 -348.768994)
			(xy 20.502074 -348.814878) (xy 20.466357 -348.856098) (xy 20.425136 -348.891816) (xy 20.379253 -348.921303)
			(xy 20.329639 -348.943961) (xy 20.277306 -348.959327) (xy 20.223319 -348.967089) (xy 20.196048 -348.967552)
			(xy 19.332448 -348.967552) (xy 19.305179 -348.967065) (xy 19.251195 -348.959304) (xy 19.198866 -348.943938)
			(xy 19.149256 -348.921282) (xy 19.103375 -348.891796) (xy 19.062158 -348.856081) (xy 19.026443 -348.814863)
			(xy 18.996957 -348.768982) (xy 18.974301 -348.719372) (xy 18.958936 -348.667043) (xy 18.951174 -348.613059)
			(xy 8.879169 -348.613059) (xy 8.892221 -348.718461) (xy 8.900171 -348.847356) (xy 8.900668 -348.911926)
			(xy 8.900171 -348.976496) (xy 8.892221 -349.105391) (xy 8.876351 -349.233551) (xy 8.852622 -349.360492)
			(xy 8.821123 -349.485731) (xy 8.781974 -349.608794) (xy 8.735323 -349.729213) (xy 8.681348 -349.846532)
			(xy 8.620253 -349.960306) (xy 8.55227 -350.070103) (xy 8.477656 -350.175506) (xy 8.396695 -350.276116)
			(xy 8.309695 -350.371551) (xy 8.216984 -350.46145) (xy 8.118914 -350.545471) (xy 8.015859 -350.623295)
			(xy 7.908208 -350.694627) (xy 7.796369 -350.759197) (xy 7.680768 -350.816759) (xy 7.561843 -350.867096)
			(xy 7.440044 -350.910016) (xy 7.315834 -350.945357) (xy 7.189685 -350.972984) (xy 7.062073 -350.992793)
			(xy 6.933484 -351.004709) (xy 6.804406 -351.008686) (xy 6.675328 -351.004709) (xy 6.546739 -350.992793)
			(xy 6.419127 -350.972984) (xy 6.292978 -350.945357) (xy 6.168768 -350.910016) (xy 6.046969 -350.867096)
			(xy 5.928044 -350.816759) (xy 5.812443 -350.759197) (xy 5.700604 -350.694627) (xy 5.592953 -350.623295)
			(xy 5.489898 -350.545471) (xy 5.391828 -350.46145) (xy 5.299117 -350.371551) (xy 5.212117 -350.276116)
			(xy 5.131156 -350.175506) (xy 5.056542 -350.070103) (xy 4.988559 -349.960306) (xy 4.927464 -349.846532)
			(xy 4.873489 -349.729213) (xy 4.826838 -349.608794) (xy 4.787689 -349.485731) (xy 4.75619 -349.360492)
			(xy 4.732461 -349.233551) (xy 4.716591 -349.105391) (xy 4.708641 -348.976496) (xy 0.509016 -348.976496)
			(xy 0.509016 -351.638709) (xy 18.951172 -351.638709) (xy 18.951172 -351.584171) (xy 18.958934 -351.530187)
			(xy 18.974299 -351.477857) (xy 18.996956 -351.428247) (xy 19.026441 -351.382366) (xy 19.062157 -351.341148)
			(xy 19.103374 -351.305433) (xy 19.149255 -351.275947) (xy 19.198865 -351.25329) (xy 19.251195 -351.237925)
			(xy 19.305179 -351.230163) (xy 19.332448 -351.229676) (xy 20.196048 -351.229676) (xy 20.223319 -351.230143)
			(xy 20.277306 -351.237905) (xy 20.329638 -351.253271) (xy 20.379252 -351.275929) (xy 20.425135 -351.305416)
			(xy 20.466355 -351.341133) (xy 20.502073 -351.382353) (xy 20.53156 -351.428237) (xy 20.554218 -351.47785)
			(xy 20.569584 -351.530182) (xy 20.577347 -351.584169) (xy 20.577347 -351.638669) (xy 22.060139 -351.638669)
			(xy 22.060139 -351.584131) (xy 22.067901 -351.530149) (xy 22.083266 -351.477821) (xy 22.105922 -351.428212)
			(xy 22.135407 -351.382333) (xy 22.171122 -351.341117) (xy 22.212339 -351.305403) (xy 22.258219 -351.275918)
			(xy 22.307829 -351.253263) (xy 22.360157 -351.237899) (xy 22.414139 -351.230139) (xy 22.441408 -351.229676)
			(xy 23.305008 -351.229676) (xy 23.33228 -351.230087) (xy 23.386268 -351.23785) (xy 23.438602 -351.253218)
			(xy 23.488216 -351.275877) (xy 23.5341 -351.305366) (xy 23.575321 -351.341085) (xy 23.611039 -351.382306)
			(xy 23.640527 -351.428191) (xy 23.663185 -351.477806) (xy 23.678551 -351.53014) (xy 23.686314 -351.584128)
			(xy 23.686314 -351.638665) (xy 25.169162 -351.638665) (xy 25.169162 -351.584135) (xy 25.176922 -351.530159)
			(xy 25.192284 -351.477838) (xy 25.214936 -351.428234) (xy 25.244416 -351.38236) (xy 25.280124 -351.341147)
			(xy 25.321334 -351.305435) (xy 25.367206 -351.275951) (xy 25.416808 -351.253296) (xy 25.469128 -351.237929)
			(xy 25.523103 -351.230165) (xy 25.550368 -351.229676) (xy 26.413968 -351.229676) (xy 26.441243 -351.230061)
			(xy 26.495239 -351.237821) (xy 26.547581 -351.253186) (xy 26.597203 -351.275844) (xy 26.643095 -351.305333)
			(xy 26.684323 -351.341054) (xy 26.720047 -351.382279) (xy 26.749541 -351.428169) (xy 26.772203 -351.477789)
			(xy 26.787573 -351.53013) (xy 26.795336 -351.584125) (xy 26.795336 -351.63867) (xy 28.278039 -351.63867)
			(xy 28.278039 -351.58413) (xy 28.285802 -351.530146) (xy 28.301168 -351.477817) (xy 28.323825 -351.428207)
			(xy 28.353312 -351.382326) (xy 28.389029 -351.341109) (xy 28.430249 -351.305396) (xy 28.476131 -351.275912)
			(xy 28.525743 -351.253258) (xy 28.578074 -351.237896) (xy 28.632058 -351.230137) (xy 28.659328 -351.229676)
			(xy 29.522928 -351.229676) (xy 29.550199 -351.230088) (xy 29.604185 -351.237854) (xy 29.656516 -351.253223)
			(xy 29.706128 -351.275883) (xy 29.75201 -351.305373) (xy 29.793228 -351.341092) (xy 29.828944 -351.382313)
			(xy 29.85843 -351.428197) (xy 29.881086 -351.47781) (xy 29.896452 -351.530143) (xy 29.904214 -351.584129)
			(xy 29.904214 -351.638666) (xy 31.387062 -351.638666) (xy 31.387062 -351.584134) (xy 31.394823 -351.530157)
			(xy 31.410186 -351.477833) (xy 31.432839 -351.428229) (xy 31.462321 -351.382353) (xy 31.498031 -351.34114)
			(xy 31.539243 -351.305428) (xy 31.585118 -351.275945) (xy 31.634722 -351.25329) (xy 31.687045 -351.237925)
			(xy 31.741022 -351.230163) (xy 31.768288 -351.229676) (xy 32.631888 -351.229676) (xy 32.659162 -351.230063)
			(xy 32.713156 -351.237824) (xy 32.765495 -351.253191) (xy 32.815115 -351.27585) (xy 32.861004 -351.30534)
			(xy 32.90223 -351.341061) (xy 32.937952 -351.382286) (xy 32.967444 -351.428175) (xy 32.990105 -351.477794)
			(xy 33.005473 -351.530132) (xy 33.013236 -351.584126) (xy 33.013236 -351.63867) (xy 34.49594 -351.63867)
			(xy 34.49594 -351.58413) (xy 34.503702 -351.530144) (xy 34.519069 -351.477812) (xy 34.541728 -351.428201)
			(xy 34.571217 -351.38232) (xy 34.606936 -351.341102) (xy 34.648158 -351.305388) (xy 34.694043 -351.275905)
			(xy 34.743658 -351.253253) (xy 34.795991 -351.237892) (xy 34.849977 -351.230136) (xy 34.877248 -351.229676)
			(xy 35.740848 -351.229676) (xy 35.768118 -351.23009) (xy 35.822102 -351.237858) (xy 35.874431 -351.253229)
			(xy 35.92404 -351.27589) (xy 35.969919 -351.30538) (xy 36.011135 -351.341099) (xy 36.046849 -351.382319)
			(xy 36.076333 -351.428203) (xy 36.098988 -351.477814) (xy 36.114352 -351.530145) (xy 36.122114 -351.58413)
			(xy 36.122114 -351.638669) (xy 37.604939 -351.638669) (xy 37.604939 -351.584131) (xy 37.612701 -351.530149)
			(xy 37.628066 -351.477821) (xy 37.650722 -351.428212) (xy 37.680207 -351.382333) (xy 37.715922 -351.341117)
			(xy 37.757139 -351.305403) (xy 37.803019 -351.275918) (xy 37.852629 -351.253263) (xy 37.904957 -351.237899)
			(xy 37.958939 -351.230139) (xy 37.986208 -351.229676) (xy 38.849808 -351.229676) (xy 38.87708 -351.230087)
			(xy 38.931068 -351.23785) (xy 38.983402 -351.253218) (xy 39.033016 -351.275877) (xy 39.0789 -351.305366)
			(xy 39.120121 -351.341085) (xy 39.155839 -351.382306) (xy 39.185327 -351.428191) (xy 39.207985 -351.477806)
			(xy 39.223351 -351.53014) (xy 39.231114 -351.584128) (xy 39.231114 -351.638665) (xy 40.713962 -351.638665)
			(xy 40.713962 -351.584135) (xy 40.721722 -351.530159) (xy 40.737084 -351.477838) (xy 40.759736 -351.428234)
			(xy 40.789216 -351.38236) (xy 40.824924 -351.341147) (xy 40.866134 -351.305435) (xy 40.912006 -351.275951)
			(xy 40.961608 -351.253296) (xy 41.013928 -351.237929) (xy 41.067903 -351.230165) (xy 41.095168 -351.229676)
			(xy 41.958768 -351.229676) (xy 41.986043 -351.230061) (xy 42.040039 -351.237821) (xy 42.092381 -351.253186)
			(xy 42.142003 -351.275844) (xy 42.187895 -351.305333) (xy 42.229123 -351.341054) (xy 42.264847 -351.382279)
			(xy 42.294341 -351.428169) (xy 42.317003 -351.477789) (xy 42.332373 -351.53013) (xy 42.340136 -351.584125)
			(xy 42.340136 -351.63867) (xy 43.822839 -351.63867) (xy 43.822839 -351.58413) (xy 43.830602 -351.530146)
			(xy 43.845968 -351.477817) (xy 43.868625 -351.428207) (xy 43.898112 -351.382326) (xy 43.933829 -351.341109)
			(xy 43.975049 -351.305396) (xy 44.020931 -351.275912) (xy 44.070543 -351.253258) (xy 44.122874 -351.237896)
			(xy 44.176858 -351.230137) (xy 44.204128 -351.229676) (xy 45.067728 -351.229676) (xy 45.094999 -351.230088)
			(xy 45.148985 -351.237854) (xy 45.201316 -351.253223) (xy 45.250928 -351.275883) (xy 45.29681 -351.305373)
			(xy 45.338028 -351.341092) (xy 45.373744 -351.382313) (xy 45.40323 -351.428197) (xy 45.425886 -351.47781)
			(xy 45.441252 -351.530143) (xy 45.449014 -351.584129) (xy 45.449014 -351.638666) (xy 46.931862 -351.638666)
			(xy 46.931862 -351.584134) (xy 46.939623 -351.530157) (xy 46.954986 -351.477833) (xy 46.977639 -351.428229)
			(xy 47.007121 -351.382353) (xy 47.042831 -351.34114) (xy 47.084043 -351.305428) (xy 47.129918 -351.275945)
			(xy 47.179522 -351.25329) (xy 47.231845 -351.237925) (xy 47.285822 -351.230163) (xy 47.313088 -351.229676)
			(xy 48.176688 -351.229676) (xy 48.203962 -351.230063) (xy 48.257956 -351.237824) (xy 48.310295 -351.253191)
			(xy 48.359915 -351.27585) (xy 48.405804 -351.30534) (xy 48.44703 -351.341061) (xy 48.482752 -351.382286)
			(xy 48.512244 -351.428175) (xy 48.534905 -351.477794) (xy 48.550273 -351.530132) (xy 48.558036 -351.584126)
			(xy 48.558036 -351.63867) (xy 50.04074 -351.63867) (xy 50.04074 -351.58413) (xy 50.048502 -351.530144)
			(xy 50.063869 -351.477812) (xy 50.086528 -351.428201) (xy 50.116017 -351.38232) (xy 50.151736 -351.341102)
			(xy 50.192958 -351.305388) (xy 50.238843 -351.275905) (xy 50.288458 -351.253253) (xy 50.340791 -351.237892)
			(xy 50.394777 -351.230136) (xy 50.422048 -351.229676) (xy 51.285648 -351.229676) (xy 51.312918 -351.23009)
			(xy 51.366902 -351.237858) (xy 51.419231 -351.253229) (xy 51.46884 -351.27589) (xy 51.514719 -351.30538)
			(xy 51.555935 -351.341099) (xy 51.591649 -351.382319) (xy 51.621133 -351.428203) (xy 51.643788 -351.477814)
			(xy 51.659152 -351.530145) (xy 51.666914 -351.58413) (xy 51.666914 -351.63867) (xy 60.99094 -351.63867)
			(xy 60.99094 -351.58413) (xy 60.998702 -351.530145) (xy 61.014069 -351.477814) (xy 61.036727 -351.428203)
			(xy 61.066216 -351.382322) (xy 61.101934 -351.341105) (xy 61.143155 -351.305391) (xy 61.18904 -351.275907)
			(xy 61.238653 -351.253254) (xy 61.290986 -351.237893) (xy 61.344972 -351.230137) (xy 61.372242 -351.229676)
			(xy 62.235842 -351.229676) (xy 62.263112 -351.230089) (xy 62.317097 -351.237857) (xy 62.369426 -351.253227)
			(xy 62.419036 -351.275888) (xy 62.464916 -351.305378) (xy 62.506133 -351.341097) (xy 62.541847 -351.382317)
			(xy 62.571332 -351.428201) (xy 62.593988 -351.477813) (xy 62.609352 -351.530145) (xy 62.617114 -351.58413)
			(xy 62.617114 -351.638668) (xy 64.099939 -351.638668) (xy 64.099939 -351.584132) (xy 64.107701 -351.53015)
			(xy 64.123066 -351.477822) (xy 64.145721 -351.428214) (xy 64.175206 -351.382335) (xy 64.21092 -351.341119)
			(xy 64.252136 -351.305405) (xy 64.298016 -351.27592) (xy 64.347624 -351.253265) (xy 64.399952 -351.2379)
			(xy 64.453934 -351.230139) (xy 64.481202 -351.229676) (xy 65.344802 -351.229676) (xy 65.372074 -351.230087)
			(xy 65.426063 -351.237849) (xy 65.478397 -351.253216) (xy 65.528012 -351.275875) (xy 65.573897 -351.305364)
			(xy 65.615119 -351.341083) (xy 65.650837 -351.382304) (xy 65.680326 -351.42819) (xy 65.702984 -351.477805)
			(xy 65.718351 -351.530139) (xy 65.726113 -351.584128) (xy 65.726113 -351.638665) (xy 67.208962 -351.638665)
			(xy 67.208962 -351.584135) (xy 67.216722 -351.53016) (xy 67.232084 -351.477839) (xy 67.254735 -351.428236)
			(xy 67.284215 -351.382362) (xy 67.319922 -351.341149) (xy 67.361131 -351.305437) (xy 67.407003 -351.275953)
			(xy 67.456603 -351.253297) (xy 67.508923 -351.23793) (xy 67.562897 -351.230165) (xy 67.590162 -351.229676)
			(xy 68.453762 -351.229676) (xy 68.481037 -351.230061) (xy 68.535034 -351.23782) (xy 68.587376 -351.253184)
			(xy 68.636999 -351.275842) (xy 68.682892 -351.305331) (xy 68.724121 -351.341052) (xy 68.759846 -351.382277)
			(xy 68.78934 -351.428167) (xy 68.812003 -351.477788) (xy 68.827372 -351.530129) (xy 68.835136 -351.584125)
			(xy 68.835136 -351.638669) (xy 70.317839 -351.638669) (xy 70.317839 -351.584131) (xy 70.325601 -351.530147)
			(xy 70.340967 -351.477818) (xy 70.363624 -351.428208) (xy 70.393111 -351.382328) (xy 70.428827 -351.341112)
			(xy 70.470046 -351.305398) (xy 70.515928 -351.275914) (xy 70.565539 -351.25326) (xy 70.617869 -351.237897)
			(xy 70.671853 -351.230138) (xy 70.699122 -351.229676) (xy 71.562722 -351.229676) (xy 71.589993 -351.230088)
			(xy 71.64398 -351.237853) (xy 71.696312 -351.253222) (xy 71.745924 -351.275881) (xy 71.791807 -351.305371)
			(xy 71.833026 -351.34109) (xy 71.868742 -351.382311) (xy 71.898229 -351.428195) (xy 71.920886 -351.477809)
			(xy 71.936252 -351.530142) (xy 71.944014 -351.584129) (xy 71.944014 -351.638666) (xy 73.426862 -351.638666)
			(xy 73.426862 -351.584134) (xy 73.434623 -351.530158) (xy 73.449986 -351.477835) (xy 73.472638 -351.428231)
			(xy 73.50212 -351.382355) (xy 73.537829 -351.341142) (xy 73.579041 -351.30543) (xy 73.624915 -351.275947)
			(xy 73.674518 -351.253292) (xy 73.72684 -351.237927) (xy 73.780816 -351.230164) (xy 73.808082 -351.229676)
			(xy 74.671682 -351.229676) (xy 74.698957 -351.230062) (xy 74.752951 -351.237823) (xy 74.805291 -351.253189)
			(xy 74.854911 -351.275848) (xy 74.900802 -351.305338) (xy 74.942028 -351.341059) (xy 74.977751 -351.382284)
			(xy 75.007243 -351.428173) (xy 75.029904 -351.477792) (xy 75.045273 -351.530132) (xy 75.053036 -351.584125)
			(xy 75.053036 -351.63867) (xy 76.53574 -351.63867) (xy 76.53574 -351.58413) (xy 76.543502 -351.530145)
			(xy 76.558869 -351.477814) (xy 76.581527 -351.428203) (xy 76.611016 -351.382322) (xy 76.646734 -351.341105)
			(xy 76.687955 -351.305391) (xy 76.73384 -351.275907) (xy 76.783453 -351.253254) (xy 76.835786 -351.237893)
			(xy 76.889772 -351.230137) (xy 76.917042 -351.229676) (xy 77.780642 -351.229676) (xy 77.807912 -351.230089)
			(xy 77.861897 -351.237857) (xy 77.914226 -351.253227) (xy 77.963836 -351.275888) (xy 78.009716 -351.305378)
			(xy 78.050933 -351.341097) (xy 78.086647 -351.382317) (xy 78.116132 -351.428201) (xy 78.138788 -351.477813)
			(xy 78.154152 -351.530145) (xy 78.161914 -351.58413) (xy 78.161914 -351.638668) (xy 79.644739 -351.638668)
			(xy 79.644739 -351.584132) (xy 79.652501 -351.53015) (xy 79.667866 -351.477822) (xy 79.690521 -351.428214)
			(xy 79.720006 -351.382335) (xy 79.75572 -351.341119) (xy 79.796936 -351.305405) (xy 79.842816 -351.27592)
			(xy 79.892424 -351.253265) (xy 79.944752 -351.2379) (xy 79.998734 -351.230139) (xy 80.026002 -351.229676)
			(xy 80.889602 -351.229676) (xy 80.916874 -351.230087) (xy 80.970863 -351.237849) (xy 81.023197 -351.253216)
			(xy 81.072812 -351.275875) (xy 81.118697 -351.305364) (xy 81.159919 -351.341083) (xy 81.195637 -351.382304)
			(xy 81.225126 -351.42819) (xy 81.247784 -351.477805) (xy 81.263151 -351.530139) (xy 81.270913 -351.584128)
			(xy 81.270913 -351.638665) (xy 82.753762 -351.638665) (xy 82.753762 -351.584135) (xy 82.761522 -351.53016)
			(xy 82.776884 -351.477839) (xy 82.799535 -351.428236) (xy 82.829015 -351.382362) (xy 82.864722 -351.341149)
			(xy 82.905931 -351.305437) (xy 82.951803 -351.275953) (xy 83.001403 -351.253297) (xy 83.053723 -351.23793)
			(xy 83.107697 -351.230165) (xy 83.134962 -351.229676) (xy 83.998562 -351.229676) (xy 84.025837 -351.230061)
			(xy 84.079834 -351.23782) (xy 84.132176 -351.253184) (xy 84.181799 -351.275842) (xy 84.227692 -351.305331)
			(xy 84.268921 -351.341052) (xy 84.304646 -351.382277) (xy 84.33414 -351.428167) (xy 84.356803 -351.477788)
			(xy 84.372172 -351.530129) (xy 84.379936 -351.584125) (xy 84.379936 -351.638669) (xy 85.862639 -351.638669)
			(xy 85.862639 -351.584131) (xy 85.870401 -351.530147) (xy 85.885767 -351.477818) (xy 85.908424 -351.428208)
			(xy 85.937911 -351.382328) (xy 85.973627 -351.341112) (xy 86.014846 -351.305398) (xy 86.060728 -351.275914)
			(xy 86.110339 -351.25326) (xy 86.162669 -351.237897) (xy 86.216653 -351.230138) (xy 86.243922 -351.229676)
			(xy 87.107522 -351.229676) (xy 87.134793 -351.230088) (xy 87.18878 -351.237853) (xy 87.241112 -351.253222)
			(xy 87.290724 -351.275881) (xy 87.336607 -351.305371) (xy 87.377826 -351.34109) (xy 87.413542 -351.382311)
			(xy 87.443029 -351.428195) (xy 87.465686 -351.477809) (xy 87.481052 -351.530142) (xy 87.488814 -351.584129)
			(xy 87.488814 -351.638666) (xy 88.971662 -351.638666) (xy 88.971662 -351.584134) (xy 88.979423 -351.530158)
			(xy 88.994786 -351.477835) (xy 89.017438 -351.428231) (xy 89.04692 -351.382355) (xy 89.082629 -351.341142)
			(xy 89.123841 -351.30543) (xy 89.169715 -351.275947) (xy 89.219318 -351.253292) (xy 89.27164 -351.237927)
			(xy 89.325616 -351.230164) (xy 89.352882 -351.229676) (xy 90.216482 -351.229676) (xy 90.243757 -351.230062)
			(xy 90.297751 -351.237823) (xy 90.350091 -351.253189) (xy 90.399711 -351.275848) (xy 90.445602 -351.305338)
			(xy 90.486828 -351.341059) (xy 90.522551 -351.382284) (xy 90.552043 -351.428173) (xy 90.574704 -351.477792)
			(xy 90.590073 -351.530132) (xy 90.597836 -351.584125) (xy 90.597836 -351.63867) (xy 92.08054 -351.63867)
			(xy 92.08054 -351.58413) (xy 92.088302 -351.530145) (xy 92.103669 -351.477814) (xy 92.126327 -351.428203)
			(xy 92.155816 -351.382322) (xy 92.191534 -351.341105) (xy 92.232755 -351.305391) (xy 92.27864 -351.275907)
			(xy 92.328253 -351.253254) (xy 92.380586 -351.237893) (xy 92.434572 -351.230137) (xy 92.461842 -351.229676)
			(xy 93.325442 -351.229676) (xy 93.352712 -351.230089) (xy 93.406697 -351.237857) (xy 93.459026 -351.253227)
			(xy 93.508636 -351.275888) (xy 93.554516 -351.305378) (xy 93.595733 -351.341097) (xy 93.631447 -351.382317)
			(xy 93.660932 -351.428201) (xy 93.683588 -351.477813) (xy 93.698952 -351.530145) (xy 93.706714 -351.58413)
			(xy 93.706714 -351.638669) (xy 111.480839 -351.638669) (xy 111.480839 -351.584131) (xy 111.488601 -351.530149)
			(xy 111.503966 -351.477821) (xy 111.526622 -351.428212) (xy 111.556107 -351.382333) (xy 111.591822 -351.341117)
			(xy 111.633039 -351.305403) (xy 111.678919 -351.275918) (xy 111.728529 -351.253263) (xy 111.780857 -351.237899)
			(xy 111.834839 -351.230139) (xy 111.862108 -351.229676) (xy 112.725708 -351.229676) (xy 112.75298 -351.230087)
			(xy 112.806968 -351.23785) (xy 112.859302 -351.253218) (xy 112.908916 -351.275877) (xy 112.9548 -351.305366)
			(xy 112.996021 -351.341085) (xy 113.031739 -351.382306) (xy 113.061227 -351.428191) (xy 113.083885 -351.477806)
			(xy 113.099251 -351.53014) (xy 113.107014 -351.584128) (xy 113.107014 -351.638665) (xy 114.589862 -351.638665)
			(xy 114.589862 -351.584135) (xy 114.597622 -351.530159) (xy 114.612984 -351.477838) (xy 114.635636 -351.428234)
			(xy 114.665116 -351.38236) (xy 114.700824 -351.341147) (xy 114.742034 -351.305435) (xy 114.787906 -351.275951)
			(xy 114.837508 -351.253296) (xy 114.889828 -351.237929) (xy 114.943803 -351.230165) (xy 114.971068 -351.229676)
			(xy 115.834668 -351.229676) (xy 115.861943 -351.230061) (xy 115.915939 -351.237821) (xy 115.968281 -351.253186)
			(xy 116.017903 -351.275844) (xy 116.063795 -351.305333) (xy 116.105023 -351.341054) (xy 116.140747 -351.382279)
			(xy 116.170241 -351.428169) (xy 116.192903 -351.477789) (xy 116.208273 -351.53013) (xy 116.216036 -351.584125)
			(xy 116.216036 -351.63867) (xy 117.698739 -351.63867) (xy 117.698739 -351.58413) (xy 117.706502 -351.530146)
			(xy 117.721868 -351.477817) (xy 117.744525 -351.428207) (xy 117.774012 -351.382326) (xy 117.809729 -351.341109)
			(xy 117.850949 -351.305396) (xy 117.896831 -351.275912) (xy 117.946443 -351.253258) (xy 117.998774 -351.237896)
			(xy 118.052758 -351.230137) (xy 118.080028 -351.229676) (xy 118.943628 -351.229676) (xy 118.970899 -351.230088)
			(xy 119.024885 -351.237854) (xy 119.077216 -351.253223) (xy 119.126828 -351.275883) (xy 119.17271 -351.305373)
			(xy 119.213928 -351.341092) (xy 119.249644 -351.382313) (xy 119.27913 -351.428197) (xy 119.301786 -351.47781)
			(xy 119.317152 -351.530143) (xy 119.324914 -351.584129) (xy 119.324914 -351.638666) (xy 120.807762 -351.638666)
			(xy 120.807762 -351.584134) (xy 120.815523 -351.530157) (xy 120.830886 -351.477833) (xy 120.853539 -351.428229)
			(xy 120.883021 -351.382353) (xy 120.918731 -351.34114) (xy 120.959943 -351.305428) (xy 121.005818 -351.275945)
			(xy 121.055422 -351.25329) (xy 121.107745 -351.237925) (xy 121.161722 -351.230163) (xy 121.188988 -351.229676)
			(xy 122.052588 -351.229676) (xy 122.079862 -351.230063) (xy 122.133856 -351.237824) (xy 122.186195 -351.253191)
			(xy 122.235815 -351.27585) (xy 122.281704 -351.30534) (xy 122.32293 -351.341061) (xy 122.358652 -351.382286)
			(xy 122.388144 -351.428175) (xy 122.410805 -351.477794) (xy 122.426173 -351.530132) (xy 122.433936 -351.584126)
			(xy 122.433936 -351.63867) (xy 123.91664 -351.63867) (xy 123.91664 -351.58413) (xy 123.924402 -351.530144)
			(xy 123.939769 -351.477812) (xy 123.962428 -351.428201) (xy 123.991917 -351.38232) (xy 124.027636 -351.341102)
			(xy 124.068858 -351.305388) (xy 124.114743 -351.275905) (xy 124.164358 -351.253253) (xy 124.216691 -351.237892)
			(xy 124.270677 -351.230136) (xy 124.297948 -351.229676) (xy 125.161548 -351.229676) (xy 125.188818 -351.23009)
			(xy 125.242802 -351.237858) (xy 125.295131 -351.253229) (xy 125.34474 -351.27589) (xy 125.390619 -351.30538)
			(xy 125.431835 -351.341099) (xy 125.467549 -351.382319) (xy 125.497033 -351.428203) (xy 125.519688 -351.477814)
			(xy 125.535052 -351.530145) (xy 125.542814 -351.58413) (xy 125.542814 -351.638669) (xy 127.025639 -351.638669)
			(xy 127.025639 -351.584131) (xy 127.033401 -351.530149) (xy 127.048766 -351.477821) (xy 127.071422 -351.428212)
			(xy 127.100907 -351.382333) (xy 127.136622 -351.341117) (xy 127.177839 -351.305403) (xy 127.223719 -351.275918)
			(xy 127.273329 -351.253263) (xy 127.325657 -351.237899) (xy 127.379639 -351.230139) (xy 127.406908 -351.229676)
			(xy 128.270508 -351.229676) (xy 128.29778 -351.230087) (xy 128.351768 -351.23785) (xy 128.404102 -351.253218)
			(xy 128.453716 -351.275877) (xy 128.4996 -351.305366) (xy 128.540821 -351.341085) (xy 128.576539 -351.382306)
			(xy 128.606027 -351.428191) (xy 128.628685 -351.477806) (xy 128.644051 -351.53014) (xy 128.651814 -351.584128)
			(xy 128.651814 -351.638665) (xy 130.134662 -351.638665) (xy 130.134662 -351.584135) (xy 130.142422 -351.530159)
			(xy 130.157784 -351.477838) (xy 130.180436 -351.428234) (xy 130.209916 -351.38236) (xy 130.245624 -351.341147)
			(xy 130.286834 -351.305435) (xy 130.332706 -351.275951) (xy 130.382308 -351.253296) (xy 130.434628 -351.237929)
			(xy 130.488603 -351.230165) (xy 130.515868 -351.229676) (xy 131.379468 -351.229676) (xy 131.406743 -351.230061)
			(xy 131.460739 -351.237821) (xy 131.513081 -351.253186) (xy 131.562703 -351.275844) (xy 131.608595 -351.305333)
			(xy 131.649823 -351.341054) (xy 131.685547 -351.382279) (xy 131.715041 -351.428169) (xy 131.737703 -351.477789)
			(xy 131.753073 -351.53013) (xy 131.760836 -351.584125) (xy 131.760836 -351.63867) (xy 133.243539 -351.63867)
			(xy 133.243539 -351.58413) (xy 133.251302 -351.530146) (xy 133.266668 -351.477817) (xy 133.289325 -351.428207)
			(xy 133.318812 -351.382326) (xy 133.354529 -351.341109) (xy 133.395749 -351.305396) (xy 133.441631 -351.275912)
			(xy 133.491243 -351.253258) (xy 133.543574 -351.237896) (xy 133.597558 -351.230137) (xy 133.624828 -351.229676)
			(xy 134.488428 -351.229676) (xy 134.515699 -351.230088) (xy 134.569685 -351.237854) (xy 134.622016 -351.253223)
			(xy 134.671628 -351.275883) (xy 134.71751 -351.305373) (xy 134.758728 -351.341092) (xy 134.794444 -351.382313)
			(xy 134.82393 -351.428197) (xy 134.846586 -351.47781) (xy 134.861952 -351.530143) (xy 134.869714 -351.584129)
			(xy 134.869714 -351.638666) (xy 136.352562 -351.638666) (xy 136.352562 -351.584134) (xy 136.360323 -351.530157)
			(xy 136.375686 -351.477833) (xy 136.398339 -351.428229) (xy 136.427821 -351.382353) (xy 136.463531 -351.34114)
			(xy 136.504743 -351.305428) (xy 136.550618 -351.275945) (xy 136.600222 -351.25329) (xy 136.652545 -351.237925)
			(xy 136.706522 -351.230163) (xy 136.733788 -351.229676) (xy 137.597388 -351.229676) (xy 137.624662 -351.230063)
			(xy 137.678656 -351.237824) (xy 137.730995 -351.253191) (xy 137.780615 -351.27585) (xy 137.826504 -351.30534)
			(xy 137.86773 -351.341061) (xy 137.903452 -351.382286) (xy 137.932944 -351.428175) (xy 137.955605 -351.477794)
			(xy 137.970973 -351.530132) (xy 137.978736 -351.584126) (xy 137.978736 -351.63867) (xy 139.46144 -351.63867)
			(xy 139.46144 -351.58413) (xy 139.469202 -351.530144) (xy 139.484569 -351.477812) (xy 139.507228 -351.428201)
			(xy 139.536717 -351.38232) (xy 139.572436 -351.341102) (xy 139.613658 -351.305388) (xy 139.659543 -351.275905)
			(xy 139.709158 -351.253253) (xy 139.761491 -351.237892) (xy 139.815477 -351.230136) (xy 139.842748 -351.229676)
			(xy 140.706348 -351.229676) (xy 140.733618 -351.23009) (xy 140.787602 -351.237858) (xy 140.839931 -351.253229)
			(xy 140.88954 -351.27589) (xy 140.935419 -351.30538) (xy 140.976635 -351.341099) (xy 141.012349 -351.382319)
			(xy 141.041833 -351.428203) (xy 141.064488 -351.477814) (xy 141.079852 -351.530145) (xy 141.087614 -351.58413)
			(xy 141.087614 -351.638669) (xy 142.570439 -351.638669) (xy 142.570439 -351.584131) (xy 142.578201 -351.530149)
			(xy 142.593566 -351.477821) (xy 142.616222 -351.428212) (xy 142.645707 -351.382333) (xy 142.681422 -351.341117)
			(xy 142.722639 -351.305403) (xy 142.768519 -351.275918) (xy 142.818129 -351.253263) (xy 142.870457 -351.237899)
			(xy 142.924439 -351.230139) (xy 142.951708 -351.229676) (xy 143.815308 -351.229676) (xy 143.84258 -351.230087)
			(xy 143.896568 -351.23785) (xy 143.948902 -351.253218) (xy 143.998516 -351.275877) (xy 144.0444 -351.305366)
			(xy 144.085621 -351.341085) (xy 144.121339 -351.382306) (xy 144.150827 -351.428191) (xy 144.173485 -351.477806)
			(xy 144.188851 -351.53014) (xy 144.196614 -351.584128) (xy 144.196614 -351.638669) (xy 161.804839 -351.638669)
			(xy 161.804839 -351.584131) (xy 161.812601 -351.530149) (xy 161.827966 -351.47782) (xy 161.850623 -351.428211)
			(xy 161.880108 -351.382331) (xy 161.915824 -351.341115) (xy 161.957041 -351.305401) (xy 162.002922 -351.275917)
			(xy 162.052531 -351.253262) (xy 162.10486 -351.237899) (xy 162.158843 -351.230139) (xy 162.186112 -351.229676)
			(xy 163.049712 -351.229676) (xy 163.076984 -351.230087) (xy 163.130971 -351.237851) (xy 163.183304 -351.253219)
			(xy 163.232918 -351.275878) (xy 163.278802 -351.305367) (xy 163.320022 -351.341086) (xy 163.35574 -351.382308)
			(xy 163.385228 -351.428192) (xy 163.407885 -351.477807) (xy 163.423251 -351.530141) (xy 163.431014 -351.584128)
			(xy 163.431014 -351.638665) (xy 164.913862 -351.638665) (xy 164.913862 -351.584135) (xy 164.921622 -351.530159)
			(xy 164.936985 -351.477837) (xy 164.959637 -351.428233) (xy 164.989117 -351.382358) (xy 165.024826 -351.341146)
			(xy 165.066036 -351.305434) (xy 165.111909 -351.27595) (xy 165.16151 -351.253295) (xy 165.213831 -351.237928)
			(xy 165.267807 -351.230164) (xy 165.295072 -351.229676) (xy 166.158672 -351.229676) (xy 166.185947 -351.230062)
			(xy 166.239942 -351.237821) (xy 166.292284 -351.253187) (xy 166.341905 -351.275845) (xy 166.387797 -351.305335)
			(xy 166.429024 -351.341056) (xy 166.464748 -351.382281) (xy 166.494242 -351.42817) (xy 166.516903 -351.47779)
			(xy 166.532273 -351.53013) (xy 166.540036 -351.584125) (xy 166.540036 -351.63867) (xy 168.022739 -351.63867)
			(xy 168.022739 -351.58413) (xy 168.030502 -351.530146) (xy 168.045868 -351.477816) (xy 168.068526 -351.428206)
			(xy 168.098013 -351.382325) (xy 168.133731 -351.341108) (xy 168.174951 -351.305394) (xy 168.220834 -351.27591)
			(xy 168.270446 -351.253257) (xy 168.322777 -351.237895) (xy 168.376762 -351.230137) (xy 168.404032 -351.229676)
			(xy 169.267632 -351.229676) (xy 169.294903 -351.230089) (xy 169.348888 -351.237855) (xy 169.401219 -351.253224)
			(xy 169.45083 -351.275885) (xy 169.496712 -351.305374) (xy 169.537929 -351.341093) (xy 169.573645 -351.382314)
			(xy 169.603131 -351.428198) (xy 169.625787 -351.477811) (xy 169.641152 -351.530143) (xy 169.648914 -351.584129)
			(xy 169.648914 -351.638666) (xy 171.131762 -351.638666) (xy 171.131762 -351.584134) (xy 171.139523 -351.530156)
			(xy 171.154886 -351.477832) (xy 171.17754 -351.428228) (xy 171.207022 -351.382352) (xy 171.242733 -351.341138)
			(xy 171.283945 -351.305427) (xy 171.329821 -351.275944) (xy 171.379425 -351.253289) (xy 171.431748 -351.237925)
			(xy 171.485726 -351.230163) (xy 171.512992 -351.229676) (xy 172.376592 -351.229676) (xy 172.403866 -351.230063)
			(xy 172.457859 -351.237825) (xy 172.510198 -351.253192) (xy 172.559817 -351.275851) (xy 172.605706 -351.305342)
			(xy 172.646932 -351.341063) (xy 172.682653 -351.382287) (xy 172.712145 -351.428176) (xy 172.734805 -351.477794)
			(xy 172.750173 -351.530133) (xy 172.757936 -351.584126) (xy 172.757936 -351.638664) (xy 174.240762 -351.638664)
			(xy 174.240762 -351.584136) (xy 174.248522 -351.530162) (xy 174.263883 -351.477841) (xy 174.286534 -351.428239)
			(xy 174.316012 -351.382365) (xy 174.351719 -351.341153) (xy 174.392926 -351.305441) (xy 174.438797 -351.275957)
			(xy 174.488396 -351.2533) (xy 174.540715 -351.237932) (xy 174.594688 -351.230166) (xy 174.621952 -351.229676)
			(xy 175.485552 -351.229676) (xy 175.512828 -351.23006) (xy 175.566825 -351.237818) (xy 175.619169 -351.253181)
			(xy 175.668793 -351.275838) (xy 175.714687 -351.305328) (xy 175.755917 -351.341049) (xy 175.791644 -351.382274)
			(xy 175.821139 -351.428165) (xy 175.843802 -351.477786) (xy 175.859172 -351.530128) (xy 175.866936 -351.584124)
			(xy 175.866936 -351.638669) (xy 177.349639 -351.638669) (xy 177.349639 -351.584131) (xy 177.357401 -351.530149)
			(xy 177.372766 -351.47782) (xy 177.395423 -351.428211) (xy 177.424908 -351.382331) (xy 177.460624 -351.341115)
			(xy 177.501841 -351.305401) (xy 177.547722 -351.275917) (xy 177.597331 -351.253262) (xy 177.64966 -351.237899)
			(xy 177.703643 -351.230139) (xy 177.730912 -351.229676) (xy 178.594512 -351.229676) (xy 178.621784 -351.230087)
			(xy 178.675771 -351.237851) (xy 178.728104 -351.253219) (xy 178.777718 -351.275878) (xy 178.823602 -351.305367)
			(xy 178.864822 -351.341086) (xy 178.90054 -351.382308) (xy 178.930028 -351.428192) (xy 178.952685 -351.477807)
			(xy 178.968051 -351.530141) (xy 178.975814 -351.584128) (xy 178.975814 -351.638665) (xy 180.458662 -351.638665)
			(xy 180.458662 -351.584135) (xy 180.466422 -351.530159) (xy 180.481785 -351.477837) (xy 180.504437 -351.428233)
			(xy 180.533917 -351.382358) (xy 180.569626 -351.341146) (xy 180.610836 -351.305434) (xy 180.656709 -351.27595)
			(xy 180.70631 -351.253295) (xy 180.758631 -351.237928) (xy 180.812607 -351.230164) (xy 180.839872 -351.229676)
			(xy 181.703472 -351.229676) (xy 181.730747 -351.230062) (xy 181.784742 -351.237821) (xy 181.837084 -351.253187)
			(xy 181.886705 -351.275845) (xy 181.932597 -351.305335) (xy 181.973824 -351.341056) (xy 182.009548 -351.382281)
			(xy 182.039042 -351.42817) (xy 182.061703 -351.47779) (xy 182.077073 -351.53013) (xy 182.084836 -351.584125)
			(xy 182.084836 -351.63867) (xy 183.567539 -351.63867) (xy 183.567539 -351.58413) (xy 183.575302 -351.530146)
			(xy 183.590668 -351.477816) (xy 183.613326 -351.428206) (xy 183.642813 -351.382325) (xy 183.678531 -351.341108)
			(xy 183.719751 -351.305394) (xy 183.765634 -351.27591) (xy 183.815246 -351.253257) (xy 183.867577 -351.237895)
			(xy 183.921562 -351.230137) (xy 183.948832 -351.229676) (xy 184.812432 -351.229676) (xy 184.839703 -351.230089)
			(xy 184.893688 -351.237855) (xy 184.946019 -351.253224) (xy 184.99563 -351.275885) (xy 185.041512 -351.305374)
			(xy 185.082729 -351.341093) (xy 185.118445 -351.382314) (xy 185.147931 -351.428198) (xy 185.170587 -351.477811)
			(xy 185.185952 -351.530143) (xy 185.193714 -351.584129) (xy 185.193714 -351.638666) (xy 186.676562 -351.638666)
			(xy 186.676562 -351.584134) (xy 186.684323 -351.530156) (xy 186.699686 -351.477832) (xy 186.72234 -351.428228)
			(xy 186.751822 -351.382352) (xy 186.787533 -351.341138) (xy 186.828745 -351.305427) (xy 186.874621 -351.275944)
			(xy 186.924225 -351.253289) (xy 186.976548 -351.237925) (xy 187.030526 -351.230163) (xy 187.057792 -351.229676)
			(xy 187.921392 -351.229676) (xy 187.948666 -351.230063) (xy 188.002659 -351.237825) (xy 188.054998 -351.253192)
			(xy 188.104617 -351.275851) (xy 188.150506 -351.305342) (xy 188.191732 -351.341063) (xy 188.227453 -351.382287)
			(xy 188.256945 -351.428176) (xy 188.279605 -351.477794) (xy 188.294973 -351.530133) (xy 188.302736 -351.584126)
			(xy 188.302736 -351.638664) (xy 189.785562 -351.638664) (xy 189.785562 -351.584136) (xy 189.793322 -351.530162)
			(xy 189.808683 -351.477841) (xy 189.831334 -351.428239) (xy 189.860812 -351.382365) (xy 189.896519 -351.341153)
			(xy 189.937726 -351.305441) (xy 189.983597 -351.275957) (xy 190.033196 -351.2533) (xy 190.085515 -351.237932)
			(xy 190.139488 -351.230166) (xy 190.166752 -351.229676) (xy 191.030352 -351.229676) (xy 191.057628 -351.23006)
			(xy 191.111625 -351.237818) (xy 191.163969 -351.253181) (xy 191.213593 -351.275838) (xy 191.259487 -351.305328)
			(xy 191.300717 -351.341049) (xy 191.336444 -351.382274) (xy 191.365939 -351.428165) (xy 191.388602 -351.477786)
			(xy 191.403972 -351.530128) (xy 191.411736 -351.584124) (xy 191.411736 -351.638669) (xy 192.894439 -351.638669)
			(xy 192.894439 -351.584131) (xy 192.902201 -351.530149) (xy 192.917566 -351.47782) (xy 192.940223 -351.428211)
			(xy 192.969708 -351.382331) (xy 193.005424 -351.341115) (xy 193.046641 -351.305401) (xy 193.092522 -351.275917)
			(xy 193.142131 -351.253262) (xy 193.19446 -351.237899) (xy 193.248443 -351.230139) (xy 193.275712 -351.229676)
			(xy 194.139312 -351.229676) (xy 194.166584 -351.230087) (xy 194.220571 -351.237851) (xy 194.272904 -351.253219)
			(xy 194.322518 -351.275878) (xy 194.368402 -351.305367) (xy 194.409622 -351.341086) (xy 194.44534 -351.382308)
			(xy 194.474828 -351.428192) (xy 194.497485 -351.477807) (xy 194.512851 -351.530141) (xy 194.520614 -351.584128)
			(xy 194.520614 -351.638668) (xy 267.515839 -351.638668) (xy 267.515839 -351.584132) (xy 267.523601 -351.53015)
			(xy 267.538966 -351.477822) (xy 267.561621 -351.428214) (xy 267.591106 -351.382335) (xy 267.62682 -351.341119)
			(xy 267.668036 -351.305405) (xy 267.713916 -351.27592) (xy 267.763524 -351.253265) (xy 267.815852 -351.2379)
			(xy 267.869834 -351.230139) (xy 267.897102 -351.229676) (xy 268.760702 -351.229676) (xy 268.787974 -351.230087)
			(xy 268.841963 -351.237849) (xy 268.894297 -351.253216) (xy 268.943912 -351.275875) (xy 268.989797 -351.305364)
			(xy 269.031019 -351.341083) (xy 269.066737 -351.382304) (xy 269.096226 -351.42819) (xy 269.118884 -351.477805)
			(xy 269.134251 -351.530139) (xy 269.142013 -351.584128) (xy 269.142013 -351.638665) (xy 270.624862 -351.638665)
			(xy 270.624862 -351.584135) (xy 270.632622 -351.53016) (xy 270.647984 -351.477839) (xy 270.670635 -351.428236)
			(xy 270.700115 -351.382362) (xy 270.735822 -351.341149) (xy 270.777031 -351.305437) (xy 270.822903 -351.275953)
			(xy 270.872503 -351.253297) (xy 270.924823 -351.23793) (xy 270.978797 -351.230165) (xy 271.006062 -351.229676)
			(xy 271.869662 -351.229676) (xy 271.896937 -351.230061) (xy 271.950934 -351.23782) (xy 272.003276 -351.253184)
			(xy 272.052899 -351.275842) (xy 272.098792 -351.305331) (xy 272.140021 -351.341052) (xy 272.175746 -351.382277)
			(xy 272.20524 -351.428167) (xy 272.227903 -351.477788) (xy 272.243272 -351.530129) (xy 272.251036 -351.584125)
			(xy 272.251036 -351.638669) (xy 273.733739 -351.638669) (xy 273.733739 -351.584131) (xy 273.741501 -351.530147)
			(xy 273.756867 -351.477818) (xy 273.779524 -351.428208) (xy 273.809011 -351.382328) (xy 273.844727 -351.341112)
			(xy 273.885946 -351.305398) (xy 273.931828 -351.275914) (xy 273.981439 -351.25326) (xy 274.033769 -351.237897)
			(xy 274.087753 -351.230138) (xy 274.115022 -351.229676) (xy 274.978622 -351.229676) (xy 275.005893 -351.230088)
			(xy 275.05988 -351.237853) (xy 275.112212 -351.253222) (xy 275.161824 -351.275881) (xy 275.207707 -351.305371)
			(xy 275.248926 -351.34109) (xy 275.284642 -351.382311) (xy 275.314129 -351.428195) (xy 275.336786 -351.477809)
			(xy 275.352152 -351.530142) (xy 275.359914 -351.584129) (xy 275.359914 -351.638666) (xy 276.842762 -351.638666)
			(xy 276.842762 -351.584134) (xy 276.850523 -351.530158) (xy 276.865886 -351.477835) (xy 276.888538 -351.428231)
			(xy 276.91802 -351.382355) (xy 276.953729 -351.341142) (xy 276.994941 -351.30543) (xy 277.040815 -351.275947)
			(xy 277.090418 -351.253292) (xy 277.14274 -351.237927) (xy 277.196716 -351.230164) (xy 277.223982 -351.229676)
			(xy 278.087582 -351.229676) (xy 278.114857 -351.230062) (xy 278.168851 -351.237823) (xy 278.221191 -351.253189)
			(xy 278.270811 -351.275848) (xy 278.316702 -351.305338) (xy 278.357928 -351.341059) (xy 278.393651 -351.382284)
			(xy 278.423143 -351.428173) (xy 278.445804 -351.477792) (xy 278.461173 -351.530132) (xy 278.468936 -351.584125)
			(xy 278.468936 -351.63867) (xy 279.95164 -351.63867) (xy 279.95164 -351.58413) (xy 279.959402 -351.530145)
			(xy 279.974769 -351.477814) (xy 279.997427 -351.428203) (xy 280.026916 -351.382322) (xy 280.062634 -351.341105)
			(xy 280.103855 -351.305391) (xy 280.14974 -351.275907) (xy 280.199353 -351.253254) (xy 280.251686 -351.237893)
			(xy 280.305672 -351.230137) (xy 280.332942 -351.229676) (xy 281.196542 -351.229676) (xy 281.223812 -351.230089)
			(xy 281.277797 -351.237857) (xy 281.330126 -351.253227) (xy 281.379736 -351.275888) (xy 281.425616 -351.305378)
			(xy 281.466833 -351.341097) (xy 281.502547 -351.382317) (xy 281.532032 -351.428201) (xy 281.554688 -351.477813)
			(xy 281.570052 -351.530145) (xy 281.577814 -351.58413) (xy 281.577814 -351.638668) (xy 283.060639 -351.638668)
			(xy 283.060639 -351.584132) (xy 283.068401 -351.53015) (xy 283.083766 -351.477822) (xy 283.106421 -351.428214)
			(xy 283.135906 -351.382335) (xy 283.17162 -351.341119) (xy 283.212836 -351.305405) (xy 283.258716 -351.27592)
			(xy 283.308324 -351.253265) (xy 283.360652 -351.2379) (xy 283.414634 -351.230139) (xy 283.441902 -351.229676)
			(xy 284.305502 -351.229676) (xy 284.332774 -351.230087) (xy 284.386763 -351.237849) (xy 284.439097 -351.253216)
			(xy 284.488712 -351.275875) (xy 284.534597 -351.305364) (xy 284.575819 -351.341083) (xy 284.611537 -351.382304)
			(xy 284.641026 -351.42819) (xy 284.663684 -351.477805) (xy 284.679051 -351.530139) (xy 284.686813 -351.584128)
			(xy 284.686813 -351.638665) (xy 286.169662 -351.638665) (xy 286.169662 -351.584135) (xy 286.177422 -351.53016)
			(xy 286.192784 -351.477839) (xy 286.215435 -351.428236) (xy 286.244915 -351.382362) (xy 286.280622 -351.341149)
			(xy 286.321831 -351.305437) (xy 286.367703 -351.275953) (xy 286.417303 -351.253297) (xy 286.469623 -351.23793)
			(xy 286.523597 -351.230165) (xy 286.550862 -351.229676) (xy 287.414462 -351.229676) (xy 287.441737 -351.230061)
			(xy 287.495734 -351.23782) (xy 287.548076 -351.253184) (xy 287.597699 -351.275842) (xy 287.643592 -351.305331)
			(xy 287.684821 -351.341052) (xy 287.720546 -351.382277) (xy 287.75004 -351.428167) (xy 287.772703 -351.477788)
			(xy 287.788072 -351.530129) (xy 287.795836 -351.584125) (xy 287.795836 -351.638669) (xy 289.278539 -351.638669)
			(xy 289.278539 -351.584131) (xy 289.286301 -351.530147) (xy 289.301667 -351.477818) (xy 289.324324 -351.428208)
			(xy 289.353811 -351.382328) (xy 289.389527 -351.341112) (xy 289.430746 -351.305398) (xy 289.476628 -351.275914)
			(xy 289.526239 -351.25326) (xy 289.578569 -351.237897) (xy 289.632553 -351.230138) (xy 289.659822 -351.229676)
			(xy 290.523422 -351.229676) (xy 290.550693 -351.230088) (xy 290.60468 -351.237853) (xy 290.657012 -351.253222)
			(xy 290.706624 -351.275881) (xy 290.752507 -351.305371) (xy 290.793726 -351.34109) (xy 290.829442 -351.382311)
			(xy 290.858929 -351.428195) (xy 290.881586 -351.477809) (xy 290.896952 -351.530142) (xy 290.904714 -351.584129)
			(xy 290.904714 -351.638666) (xy 292.387562 -351.638666) (xy 292.387562 -351.584134) (xy 292.395323 -351.530158)
			(xy 292.410686 -351.477835) (xy 292.433338 -351.428231) (xy 292.46282 -351.382355) (xy 292.498529 -351.341142)
			(xy 292.539741 -351.30543) (xy 292.585615 -351.275947) (xy 292.635218 -351.253292) (xy 292.68754 -351.237927)
			(xy 292.741516 -351.230164) (xy 292.768782 -351.229676) (xy 293.632382 -351.229676) (xy 293.659657 -351.230062)
			(xy 293.713651 -351.237823) (xy 293.765991 -351.253189) (xy 293.815611 -351.275848) (xy 293.861502 -351.305338)
			(xy 293.902728 -351.341059) (xy 293.938451 -351.382284) (xy 293.967943 -351.428173) (xy 293.990604 -351.477792)
			(xy 294.005973 -351.530132) (xy 294.013736 -351.584125) (xy 294.013736 -351.63867) (xy 295.49644 -351.63867)
			(xy 295.49644 -351.58413) (xy 295.504202 -351.530145) (xy 295.519569 -351.477814) (xy 295.542227 -351.428203)
			(xy 295.571716 -351.382322) (xy 295.607434 -351.341105) (xy 295.648655 -351.305391) (xy 295.69454 -351.275907)
			(xy 295.744153 -351.253254) (xy 295.796486 -351.237893) (xy 295.850472 -351.230137) (xy 295.877742 -351.229676)
			(xy 296.741342 -351.229676) (xy 296.768612 -351.230089) (xy 296.822597 -351.237857) (xy 296.874926 -351.253227)
			(xy 296.924536 -351.275888) (xy 296.970416 -351.305378) (xy 297.011633 -351.341097) (xy 297.047347 -351.382317)
			(xy 297.076832 -351.428201) (xy 297.099488 -351.477813) (xy 297.114852 -351.530145) (xy 297.122614 -351.58413)
			(xy 297.122614 -351.638668) (xy 298.605439 -351.638668) (xy 298.605439 -351.584132) (xy 298.613201 -351.53015)
			(xy 298.628566 -351.477822) (xy 298.651221 -351.428214) (xy 298.680706 -351.382335) (xy 298.71642 -351.341119)
			(xy 298.757636 -351.305405) (xy 298.803516 -351.27592) (xy 298.853124 -351.253265) (xy 298.905452 -351.2379)
			(xy 298.959434 -351.230139) (xy 298.986702 -351.229676) (xy 299.850302 -351.229676) (xy 299.877574 -351.230087)
			(xy 299.931563 -351.237849) (xy 299.983897 -351.253216) (xy 300.033512 -351.275875) (xy 300.079397 -351.305364)
			(xy 300.120619 -351.341083) (xy 300.156337 -351.382304) (xy 300.185826 -351.42819) (xy 300.208484 -351.477805)
			(xy 300.223851 -351.530139) (xy 300.231613 -351.584128) (xy 300.231613 -351.638668) (xy 312.121539 -351.638668)
			(xy 312.121539 -351.584132) (xy 312.129301 -351.53015) (xy 312.144666 -351.477822) (xy 312.167321 -351.428213)
			(xy 312.196807 -351.382334) (xy 312.232521 -351.341118) (xy 312.273737 -351.305404) (xy 312.319617 -351.27592)
			(xy 312.369226 -351.253264) (xy 312.421554 -351.2379) (xy 312.475536 -351.230139) (xy 312.502804 -351.229676)
			(xy 313.366404 -351.229676) (xy 313.393676 -351.230087) (xy 313.447664 -351.23785) (xy 313.499999 -351.253217)
			(xy 313.549613 -351.275876) (xy 313.595498 -351.305365) (xy 313.63672 -351.341083) (xy 313.672438 -351.382305)
			(xy 313.701926 -351.42819) (xy 313.724584 -351.477805) (xy 313.739951 -351.530139) (xy 313.747713 -351.584128)
			(xy 313.747713 -351.638665) (xy 315.230562 -351.638665) (xy 315.230562 -351.584135) (xy 315.238322 -351.53016)
			(xy 315.253684 -351.477838) (xy 315.276335 -351.428236) (xy 315.305815 -351.382361) (xy 315.341523 -351.341148)
			(xy 315.382732 -351.305437) (xy 315.428604 -351.275953) (xy 315.478205 -351.253297) (xy 315.530525 -351.23793)
			(xy 315.584499 -351.230165) (xy 315.611764 -351.229676) (xy 316.475364 -351.229676) (xy 316.502639 -351.230061)
			(xy 316.556636 -351.23782) (xy 316.608978 -351.253185) (xy 316.6586 -351.275842) (xy 316.704493 -351.305332)
			(xy 316.745722 -351.341053) (xy 316.781446 -351.382278) (xy 316.81094 -351.428168) (xy 316.833603 -351.477788)
			(xy 316.848972 -351.530129) (xy 316.856736 -351.584125) (xy 316.856736 -351.638669) (xy 318.339439 -351.638669)
			(xy 318.339439 -351.584131) (xy 318.347201 -351.530147) (xy 318.362567 -351.477818) (xy 318.385224 -351.428208)
			(xy 318.414711 -351.382328) (xy 318.450428 -351.341111) (xy 318.491647 -351.305397) (xy 318.537529 -351.275913)
			(xy 318.58714 -351.253259) (xy 318.63947 -351.237896) (xy 318.693455 -351.230138) (xy 318.720724 -351.229676)
			(xy 319.584324 -351.229676) (xy 319.611595 -351.230088) (xy 319.665581 -351.237853) (xy 319.717913 -351.253222)
			(xy 319.767525 -351.275882) (xy 319.813408 -351.305372) (xy 319.854627 -351.34109) (xy 319.890343 -351.382312)
			(xy 319.919829 -351.428196) (xy 319.942486 -351.477809) (xy 319.957852 -351.530142) (xy 319.965614 -351.584129)
			(xy 319.965614 -351.638666) (xy 321.448462 -351.638666) (xy 321.448462 -351.584134) (xy 321.456223 -351.530157)
			(xy 321.471586 -351.477834) (xy 321.494239 -351.42823) (xy 321.52372 -351.382354) (xy 321.55943 -351.341141)
			(xy 321.600642 -351.30543) (xy 321.646516 -351.275946) (xy 321.696119 -351.253291) (xy 321.748442 -351.237926)
			(xy 321.802418 -351.230163) (xy 321.829684 -351.229676) (xy 322.693284 -351.229676) (xy 322.720558 -351.230062)
			(xy 322.774552 -351.237824) (xy 322.826892 -351.25319) (xy 322.876512 -351.275849) (xy 322.922403 -351.305339)
			(xy 322.963629 -351.34106) (xy 322.999351 -351.382285) (xy 323.028843 -351.428174) (xy 323.051504 -351.477793)
			(xy 323.066873 -351.530132) (xy 323.074636 -351.584126) (xy 323.074636 -351.63867) (xy 324.55734 -351.63867)
			(xy 324.55734 -351.58413) (xy 324.565102 -351.530144) (xy 324.580469 -351.477813) (xy 324.603128 -351.428202)
			(xy 324.632616 -351.382321) (xy 324.668335 -351.341104) (xy 324.709556 -351.30539) (xy 324.755441 -351.275906)
			(xy 324.805055 -351.253254) (xy 324.857387 -351.237893) (xy 324.911374 -351.230136) (xy 324.938644 -351.229676)
			(xy 325.802244 -351.229676) (xy 325.829514 -351.23009) (xy 325.883498 -351.237857) (xy 325.935828 -351.253228)
			(xy 325.985437 -351.275889) (xy 326.031317 -351.305379) (xy 326.072534 -351.341097) (xy 326.108248 -351.382318)
			(xy 326.137732 -351.428201) (xy 326.160388 -351.477814) (xy 326.175752 -351.530145) (xy 326.183514 -351.58413)
			(xy 326.183514 -351.638668) (xy 327.666339 -351.638668) (xy 327.666339 -351.584132) (xy 327.674101 -351.53015)
			(xy 327.689466 -351.477822) (xy 327.712121 -351.428213) (xy 327.741607 -351.382334) (xy 327.777321 -351.341118)
			(xy 327.818537 -351.305404) (xy 327.864417 -351.27592) (xy 327.914026 -351.253264) (xy 327.966354 -351.2379)
			(xy 328.020336 -351.230139) (xy 328.047604 -351.229676) (xy 328.911204 -351.229676) (xy 328.938476 -351.230087)
			(xy 328.992464 -351.23785) (xy 329.044799 -351.253217) (xy 329.094413 -351.275876) (xy 329.140298 -351.305365)
			(xy 329.18152 -351.341083) (xy 329.217238 -351.382305) (xy 329.246726 -351.42819) (xy 329.269384 -351.477805)
			(xy 329.284751 -351.530139) (xy 329.292513 -351.584128) (xy 329.292513 -351.638665) (xy 330.775362 -351.638665)
			(xy 330.775362 -351.584135) (xy 330.783122 -351.53016) (xy 330.798484 -351.477838) (xy 330.821135 -351.428236)
			(xy 330.850615 -351.382361) (xy 330.886323 -351.341148) (xy 330.927532 -351.305437) (xy 330.973404 -351.275953)
			(xy 331.023005 -351.253297) (xy 331.075325 -351.23793) (xy 331.129299 -351.230165) (xy 331.156564 -351.229676)
			(xy 332.020164 -351.229676) (xy 332.047439 -351.230061) (xy 332.101436 -351.23782) (xy 332.153778 -351.253185)
			(xy 332.2034 -351.275842) (xy 332.249293 -351.305332) (xy 332.290522 -351.341053) (xy 332.326246 -351.382278)
			(xy 332.35574 -351.428168) (xy 332.378403 -351.477788) (xy 332.393772 -351.530129) (xy 332.401536 -351.584125)
			(xy 332.401536 -351.638669) (xy 333.884239 -351.638669) (xy 333.884239 -351.584131) (xy 333.892001 -351.530147)
			(xy 333.907367 -351.477818) (xy 333.930024 -351.428208) (xy 333.959511 -351.382328) (xy 333.995228 -351.341111)
			(xy 334.036447 -351.305397) (xy 334.082329 -351.275913) (xy 334.13194 -351.253259) (xy 334.18427 -351.237896)
			(xy 334.238255 -351.230138) (xy 334.265524 -351.229676) (xy 335.129124 -351.229676) (xy 335.156395 -351.230088)
			(xy 335.210381 -351.237853) (xy 335.262713 -351.253222) (xy 335.312325 -351.275882) (xy 335.358208 -351.305372)
			(xy 335.399427 -351.34109) (xy 335.435143 -351.382312) (xy 335.464629 -351.428196) (xy 335.487286 -351.477809)
			(xy 335.502652 -351.530142) (xy 335.510414 -351.584129) (xy 335.510414 -351.638666) (xy 336.993262 -351.638666)
			(xy 336.993262 -351.584134) (xy 337.001023 -351.530157) (xy 337.016386 -351.477834) (xy 337.039039 -351.42823)
			(xy 337.06852 -351.382354) (xy 337.10423 -351.341141) (xy 337.145442 -351.30543) (xy 337.191316 -351.275946)
			(xy 337.240919 -351.253291) (xy 337.293242 -351.237926) (xy 337.347218 -351.230163) (xy 337.374484 -351.229676)
			(xy 338.238084 -351.229676) (xy 338.265358 -351.230062) (xy 338.319352 -351.237824) (xy 338.371692 -351.25319)
			(xy 338.421312 -351.275849) (xy 338.467203 -351.305339) (xy 338.508429 -351.34106) (xy 338.544151 -351.382285)
			(xy 338.573643 -351.428174) (xy 338.596304 -351.477793) (xy 338.611673 -351.530132) (xy 338.619436 -351.584126)
			(xy 338.619436 -351.63867) (xy 340.10214 -351.63867) (xy 340.10214 -351.58413) (xy 340.109902 -351.530144)
			(xy 340.125269 -351.477813) (xy 340.147928 -351.428202) (xy 340.177416 -351.382321) (xy 340.213135 -351.341104)
			(xy 340.254356 -351.30539) (xy 340.300241 -351.275906) (xy 340.349855 -351.253254) (xy 340.402187 -351.237893)
			(xy 340.456174 -351.230136) (xy 340.483444 -351.229676) (xy 341.347044 -351.229676) (xy 341.374314 -351.23009)
			(xy 341.428298 -351.237857) (xy 341.480628 -351.253228) (xy 341.530237 -351.275889) (xy 341.576117 -351.305379)
			(xy 341.617334 -351.341097) (xy 341.653048 -351.382318) (xy 341.682532 -351.428201) (xy 341.705188 -351.477814)
			(xy 341.720552 -351.530145) (xy 341.728314 -351.58413) (xy 341.728314 -351.638668) (xy 343.211139 -351.638668)
			(xy 343.211139 -351.584132) (xy 343.218901 -351.53015) (xy 343.234266 -351.477822) (xy 343.256921 -351.428213)
			(xy 343.286407 -351.382334) (xy 343.322121 -351.341118) (xy 343.363337 -351.305404) (xy 343.409217 -351.27592)
			(xy 343.458826 -351.253264) (xy 343.511154 -351.2379) (xy 343.565136 -351.230139) (xy 343.592404 -351.229676)
			(xy 344.456004 -351.229676) (xy 344.483276 -351.230087) (xy 344.537264 -351.23785) (xy 344.589599 -351.253217)
			(xy 344.639213 -351.275876) (xy 344.685098 -351.305365) (xy 344.72632 -351.341083) (xy 344.762038 -351.382305)
			(xy 344.791526 -351.42819) (xy 344.814184 -351.477805) (xy 344.829551 -351.530139) (xy 344.837313 -351.584128)
			(xy 344.837313 -351.638666) (xy 370.806762 -351.638666) (xy 370.806762 -351.584134) (xy 370.814523 -351.530158)
			(xy 370.829885 -351.477835) (xy 370.852538 -351.428231) (xy 370.882019 -351.382356) (xy 370.917729 -351.341143)
			(xy 370.95894 -351.305431) (xy 371.004814 -351.275948) (xy 371.054416 -351.253292) (xy 371.106738 -351.237927)
			(xy 371.160714 -351.230164) (xy 371.18798 -351.229676) (xy 372.05158 -351.229676) (xy 372.078855 -351.230062)
			(xy 372.132849 -351.237823) (xy 372.185189 -351.253189) (xy 372.23481 -351.275848) (xy 372.280701 -351.305338)
			(xy 372.321927 -351.341059) (xy 372.35765 -351.382283) (xy 372.387143 -351.428172) (xy 372.409804 -351.477792)
			(xy 372.425173 -351.530131) (xy 372.432936 -351.584125) (xy 372.432936 -351.63867) (xy 373.91564 -351.63867)
			(xy 373.91564 -351.58413) (xy 373.923402 -351.530145) (xy 373.938769 -351.477814) (xy 373.961427 -351.428203)
			(xy 373.990915 -351.382322) (xy 374.026634 -351.341105) (xy 374.067854 -351.305391) (xy 374.113738 -351.275908)
			(xy 374.163352 -351.253255) (xy 374.215684 -351.237893) (xy 374.26967 -351.230137) (xy 374.29694 -351.229676)
			(xy 375.16054 -351.229676) (xy 375.18781 -351.230089) (xy 375.241795 -351.237856) (xy 375.294125 -351.253227)
			(xy 375.343735 -351.275887) (xy 375.389615 -351.305377) (xy 375.430832 -351.341096) (xy 375.466547 -351.382317)
			(xy 375.496032 -351.4282) (xy 375.518687 -351.477813) (xy 375.534052 -351.530144) (xy 375.541814 -351.58413)
			(xy 375.541814 -351.638667) (xy 377.024662 -351.638667) (xy 377.024662 -351.584133) (xy 377.032423 -351.530155)
			(xy 377.047787 -351.477831) (xy 377.070441 -351.428226) (xy 377.099924 -351.382349) (xy 377.135636 -351.341136)
			(xy 377.176849 -351.305424) (xy 377.222726 -351.275941) (xy 377.272331 -351.253287) (xy 377.324655 -351.237923)
			(xy 377.378633 -351.230162) (xy 377.4059 -351.229676) (xy 378.2695 -351.229676) (xy 378.296772 -351.230087)
			(xy 378.350761 -351.237849) (xy 378.403096 -351.253216) (xy 378.452711 -351.275874) (xy 378.498596 -351.305363)
			(xy 378.539818 -351.341082) (xy 378.575537 -351.382304) (xy 378.605026 -351.428189) (xy 378.627684 -351.477804)
			(xy 378.643051 -351.530139) (xy 378.650813 -351.584128) (xy 378.650813 -351.638665) (xy 380.133662 -351.638665)
			(xy 380.133662 -351.584135) (xy 380.141422 -351.53016) (xy 380.156784 -351.477839) (xy 380.179435 -351.428237)
			(xy 380.208914 -351.382362) (xy 380.244621 -351.34115) (xy 380.28583 -351.305438) (xy 380.331702 -351.275954)
			(xy 380.381302 -351.253298) (xy 380.433621 -351.237931) (xy 380.487595 -351.230165) (xy 380.51486 -351.229676)
			(xy 381.37846 -351.229676) (xy 381.405736 -351.230061) (xy 381.459732 -351.237819) (xy 381.512075 -351.253183)
			(xy 381.561698 -351.275841) (xy 381.607591 -351.30533) (xy 381.64882 -351.341051) (xy 381.684546 -351.382277)
			(xy 381.71404 -351.428167) (xy 381.736703 -351.477788) (xy 381.752072 -351.530129) (xy 381.759836 -351.584124)
			(xy 381.759836 -351.638669) (xy 383.242539 -351.638669) (xy 383.242539 -351.584131) (xy 383.250301 -351.530148)
			(xy 383.265667 -351.477818) (xy 383.288324 -351.428209) (xy 383.31781 -351.382329) (xy 383.353526 -351.341112)
			(xy 383.394745 -351.305398) (xy 383.440626 -351.275914) (xy 383.490237 -351.25326) (xy 383.542567 -351.237897)
			(xy 383.596551 -351.230138) (xy 383.62382 -351.229676) (xy 384.48742 -351.229676) (xy 384.514691 -351.230088)
			(xy 384.568678 -351.237853) (xy 384.62101 -351.253221) (xy 384.670623 -351.275881) (xy 384.716506 -351.30537)
			(xy 384.757725 -351.341089) (xy 384.793442 -351.38231) (xy 384.822929 -351.428195) (xy 384.845586 -351.477808)
			(xy 384.860952 -351.530142) (xy 384.868714 -351.584129) (xy 384.868714 -351.638666) (xy 386.351562 -351.638666)
			(xy 386.351562 -351.584134) (xy 386.359323 -351.530158) (xy 386.374685 -351.477835) (xy 386.397338 -351.428231)
			(xy 386.426819 -351.382356) (xy 386.462529 -351.341143) (xy 386.50374 -351.305431) (xy 386.549614 -351.275948)
			(xy 386.599216 -351.253292) (xy 386.651538 -351.237927) (xy 386.705514 -351.230164) (xy 386.73278 -351.229676)
			(xy 387.59638 -351.229676) (xy 387.623655 -351.230062) (xy 387.677649 -351.237823) (xy 387.729989 -351.253189)
			(xy 387.77961 -351.275848) (xy 387.825501 -351.305338) (xy 387.866727 -351.341059) (xy 387.90245 -351.382283)
			(xy 387.931943 -351.428172) (xy 387.954604 -351.477792) (xy 387.969973 -351.530131) (xy 387.977736 -351.584125)
			(xy 387.977736 -351.63867) (xy 389.46044 -351.63867) (xy 389.46044 -351.58413) (xy 389.468202 -351.530145)
			(xy 389.483569 -351.477814) (xy 389.506227 -351.428203) (xy 389.535715 -351.382322) (xy 389.571434 -351.341105)
			(xy 389.612654 -351.305391) (xy 389.658538 -351.275908) (xy 389.708152 -351.253255) (xy 389.760484 -351.237893)
			(xy 389.81447 -351.230137) (xy 389.84174 -351.229676) (xy 390.70534 -351.229676) (xy 390.73261 -351.230089)
			(xy 390.786595 -351.237856) (xy 390.838925 -351.253227) (xy 390.888535 -351.275887) (xy 390.934415 -351.305377)
			(xy 390.975632 -351.341096) (xy 391.011347 -351.382317) (xy 391.040832 -351.4282) (xy 391.063487 -351.477813)
			(xy 391.078852 -351.530144) (xy 391.086614 -351.58413) (xy 391.086614 -351.638667) (xy 392.569462 -351.638667)
			(xy 392.569462 -351.584133) (xy 392.577223 -351.530155) (xy 392.592587 -351.477831) (xy 392.615241 -351.428226)
			(xy 392.644724 -351.382349) (xy 392.680436 -351.341136) (xy 392.721649 -351.305424) (xy 392.767526 -351.275941)
			(xy 392.817131 -351.253287) (xy 392.869455 -351.237923) (xy 392.923433 -351.230162) (xy 392.9507 -351.229676)
			(xy 393.8143 -351.229676) (xy 393.841572 -351.230087) (xy 393.895561 -351.237849) (xy 393.947896 -351.253216)
			(xy 393.997511 -351.275874) (xy 394.043396 -351.305363) (xy 394.084618 -351.341082) (xy 394.120337 -351.382304)
			(xy 394.149826 -351.428189) (xy 394.172484 -351.477804) (xy 394.187851 -351.530139) (xy 394.195613 -351.584128)
			(xy 394.195613 -351.638665) (xy 395.678462 -351.638665) (xy 395.678462 -351.584135) (xy 395.686222 -351.53016)
			(xy 395.701584 -351.477839) (xy 395.724235 -351.428237) (xy 395.753714 -351.382362) (xy 395.789421 -351.34115)
			(xy 395.83063 -351.305438) (xy 395.876502 -351.275954) (xy 395.926102 -351.253298) (xy 395.978421 -351.237931)
			(xy 396.032395 -351.230165) (xy 396.05966 -351.229676) (xy 396.92326 -351.229676) (xy 396.950536 -351.230061)
			(xy 397.004532 -351.237819) (xy 397.056875 -351.253183) (xy 397.106498 -351.275841) (xy 397.152391 -351.30533)
			(xy 397.19362 -351.341051) (xy 397.229346 -351.382277) (xy 397.25884 -351.428167) (xy 397.281503 -351.477788)
			(xy 397.296872 -351.530129) (xy 397.304636 -351.584124) (xy 397.304636 -351.638669) (xy 398.787339 -351.638669)
			(xy 398.787339 -351.584131) (xy 398.795101 -351.530148) (xy 398.810467 -351.477818) (xy 398.833124 -351.428209)
			(xy 398.86261 -351.382329) (xy 398.898326 -351.341112) (xy 398.939545 -351.305398) (xy 398.985426 -351.275914)
			(xy 399.035037 -351.25326) (xy 399.087367 -351.237897) (xy 399.141351 -351.230138) (xy 399.16862 -351.229676)
			(xy 400.03222 -351.229676) (xy 400.059491 -351.230088) (xy 400.113478 -351.237853) (xy 400.16581 -351.253221)
			(xy 400.215423 -351.275881) (xy 400.261306 -351.30537) (xy 400.302525 -351.341089) (xy 400.338242 -351.38231)
			(xy 400.367729 -351.428195) (xy 400.390386 -351.477808) (xy 400.405752 -351.530142) (xy 400.413514 -351.584129)
			(xy 400.413514 -351.638666) (xy 401.896362 -351.638666) (xy 401.896362 -351.584134) (xy 401.904123 -351.530158)
			(xy 401.919485 -351.477835) (xy 401.942138 -351.428231) (xy 401.971619 -351.382356) (xy 402.007329 -351.341143)
			(xy 402.04854 -351.305431) (xy 402.094414 -351.275948) (xy 402.144016 -351.253292) (xy 402.196338 -351.237927)
			(xy 402.250314 -351.230164) (xy 402.27758 -351.229676) (xy 403.14118 -351.229676) (xy 403.168455 -351.230062)
			(xy 403.222449 -351.237823) (xy 403.274789 -351.253189) (xy 403.32441 -351.275848) (xy 403.370301 -351.305338)
			(xy 403.411527 -351.341059) (xy 403.44725 -351.382283) (xy 403.476743 -351.428172) (xy 403.499404 -351.477792)
			(xy 403.514773 -351.530131) (xy 403.522536 -351.584125) (xy 403.522536 -351.638666) (xy 408.913862 -351.638666)
			(xy 408.913862 -351.584134) (xy 408.921623 -351.530156) (xy 408.936986 -351.477832) (xy 408.95964 -351.428228)
			(xy 408.989122 -351.382352) (xy 409.024833 -351.341138) (xy 409.066045 -351.305427) (xy 409.111921 -351.275944)
			(xy 409.161525 -351.253289) (xy 409.213848 -351.237925) (xy 409.267826 -351.230163) (xy 409.295092 -351.229676)
			(xy 410.158692 -351.229676) (xy 410.185966 -351.230063) (xy 410.239959 -351.237825) (xy 410.292298 -351.253192)
			(xy 410.341917 -351.275851) (xy 410.387806 -351.305342) (xy 410.429032 -351.341063) (xy 410.464753 -351.382287)
			(xy 410.494245 -351.428176) (xy 410.516905 -351.477794) (xy 410.532273 -351.530133) (xy 410.540036 -351.584126)
			(xy 410.540036 -351.638664) (xy 412.022862 -351.638664) (xy 412.022862 -351.584136) (xy 412.030622 -351.530162)
			(xy 412.045983 -351.477841) (xy 412.068634 -351.428239) (xy 412.098112 -351.382365) (xy 412.133819 -351.341153)
			(xy 412.175026 -351.305441) (xy 412.220897 -351.275957) (xy 412.270496 -351.2533) (xy 412.322815 -351.237932)
			(xy 412.376788 -351.230166) (xy 412.404052 -351.229676) (xy 413.267652 -351.229676) (xy 413.294928 -351.23006)
			(xy 413.348925 -351.237818) (xy 413.401269 -351.253181) (xy 413.450893 -351.275838) (xy 413.496787 -351.305328)
			(xy 413.538017 -351.341049) (xy 413.573744 -351.382274) (xy 413.603239 -351.428165) (xy 413.625902 -351.477786)
			(xy 413.641272 -351.530128) (xy 413.649036 -351.584124) (xy 413.649036 -351.638669) (xy 415.131739 -351.638669)
			(xy 415.131739 -351.584131) (xy 415.139501 -351.530149) (xy 415.154866 -351.47782) (xy 415.177523 -351.428211)
			(xy 415.207008 -351.382331) (xy 415.242724 -351.341115) (xy 415.283941 -351.305401) (xy 415.329822 -351.275917)
			(xy 415.379431 -351.253262) (xy 415.43176 -351.237899) (xy 415.485743 -351.230139) (xy 415.513012 -351.229676)
			(xy 416.376612 -351.229676) (xy 416.403884 -351.230087) (xy 416.457871 -351.237851) (xy 416.510204 -351.253219)
			(xy 416.559818 -351.275878) (xy 416.605702 -351.305367) (xy 416.646922 -351.341086) (xy 416.68264 -351.382308)
			(xy 416.712128 -351.428192) (xy 416.734785 -351.477807) (xy 416.750151 -351.530141) (xy 416.757914 -351.584128)
			(xy 416.757914 -351.638665) (xy 418.240762 -351.638665) (xy 418.240762 -351.584135) (xy 418.248522 -351.530159)
			(xy 418.263885 -351.477837) (xy 418.286537 -351.428233) (xy 418.316017 -351.382358) (xy 418.351726 -351.341146)
			(xy 418.392936 -351.305434) (xy 418.438809 -351.27595) (xy 418.48841 -351.253295) (xy 418.540731 -351.237928)
			(xy 418.594707 -351.230164) (xy 418.621972 -351.229676) (xy 419.485572 -351.229676) (xy 419.512847 -351.230062)
			(xy 419.566842 -351.237821) (xy 419.619184 -351.253187) (xy 419.668805 -351.275845) (xy 419.714697 -351.305335)
			(xy 419.755924 -351.341056) (xy 419.791648 -351.382281) (xy 419.821142 -351.42817) (xy 419.843803 -351.47779)
			(xy 419.859173 -351.53013) (xy 419.866936 -351.584125) (xy 419.866936 -351.63867) (xy 421.349639 -351.63867)
			(xy 421.349639 -351.58413) (xy 421.357402 -351.530146) (xy 421.372768 -351.477816) (xy 421.395426 -351.428206)
			(xy 421.424913 -351.382325) (xy 421.460631 -351.341108) (xy 421.501851 -351.305394) (xy 421.547734 -351.27591)
			(xy 421.597346 -351.253257) (xy 421.649677 -351.237895) (xy 421.703662 -351.230137) (xy 421.730932 -351.229676)
			(xy 422.594532 -351.229676) (xy 422.621803 -351.230089) (xy 422.675788 -351.237855) (xy 422.728119 -351.253224)
			(xy 422.77773 -351.275885) (xy 422.823612 -351.305374) (xy 422.864829 -351.341093) (xy 422.900545 -351.382314)
			(xy 422.930031 -351.428198) (xy 422.952687 -351.477811) (xy 422.968052 -351.530143) (xy 422.975814 -351.584129)
			(xy 422.975814 -351.638666) (xy 424.458662 -351.638666) (xy 424.458662 -351.584134) (xy 424.466423 -351.530156)
			(xy 424.481786 -351.477832) (xy 424.50444 -351.428228) (xy 424.533922 -351.382352) (xy 424.569633 -351.341138)
			(xy 424.610845 -351.305427) (xy 424.656721 -351.275944) (xy 424.706325 -351.253289) (xy 424.758648 -351.237925)
			(xy 424.812626 -351.230163) (xy 424.839892 -351.229676) (xy 425.703492 -351.229676) (xy 425.730766 -351.230063)
			(xy 425.784759 -351.237825) (xy 425.837098 -351.253192) (xy 425.886717 -351.275851) (xy 425.932606 -351.305342)
			(xy 425.973832 -351.341063) (xy 426.009553 -351.382287) (xy 426.039045 -351.428176) (xy 426.061705 -351.477794)
			(xy 426.077073 -351.530133) (xy 426.084836 -351.584126) (xy 426.084836 -351.638664) (xy 427.567662 -351.638664)
			(xy 427.567662 -351.584136) (xy 427.575422 -351.530162) (xy 427.590783 -351.477841) (xy 427.613434 -351.428239)
			(xy 427.642912 -351.382365) (xy 427.678619 -351.341153) (xy 427.719826 -351.305441) (xy 427.765697 -351.275957)
			(xy 427.815296 -351.2533) (xy 427.867615 -351.237932) (xy 427.921588 -351.230166) (xy 427.948852 -351.229676)
			(xy 428.812452 -351.229676) (xy 428.839728 -351.23006) (xy 428.893725 -351.237818) (xy 428.946069 -351.253181)
			(xy 428.995693 -351.275838) (xy 429.041587 -351.305328) (xy 429.082817 -351.341049) (xy 429.118544 -351.382274)
			(xy 429.148039 -351.428165) (xy 429.170702 -351.477786) (xy 429.186072 -351.530128) (xy 429.193836 -351.584124)
			(xy 429.193836 -351.638669) (xy 430.676539 -351.638669) (xy 430.676539 -351.584131) (xy 430.684301 -351.530149)
			(xy 430.699666 -351.47782) (xy 430.722323 -351.428211) (xy 430.751808 -351.382331) (xy 430.787524 -351.341115)
			(xy 430.828741 -351.305401) (xy 430.874622 -351.275917) (xy 430.924231 -351.253262) (xy 430.97656 -351.237899)
			(xy 431.030543 -351.230139) (xy 431.057812 -351.229676) (xy 431.921412 -351.229676) (xy 431.948684 -351.230087)
			(xy 432.002671 -351.237851) (xy 432.055004 -351.253219) (xy 432.104618 -351.275878) (xy 432.150502 -351.305367)
			(xy 432.191722 -351.341086) (xy 432.22744 -351.382308) (xy 432.256928 -351.428192) (xy 432.279585 -351.477807)
			(xy 432.294951 -351.530141) (xy 432.302714 -351.584128) (xy 432.302714 -351.638665) (xy 433.785562 -351.638665)
			(xy 433.785562 -351.584135) (xy 433.793322 -351.530159) (xy 433.808685 -351.477837) (xy 433.831337 -351.428233)
			(xy 433.860817 -351.382358) (xy 433.896526 -351.341146) (xy 433.937736 -351.305434) (xy 433.983609 -351.27595)
			(xy 434.03321 -351.253295) (xy 434.085531 -351.237928) (xy 434.139507 -351.230164) (xy 434.166772 -351.229676)
			(xy 435.030372 -351.229676) (xy 435.057647 -351.230062) (xy 435.111642 -351.237821) (xy 435.163984 -351.253187)
			(xy 435.213605 -351.275845) (xy 435.259497 -351.305335) (xy 435.300724 -351.341056) (xy 435.336448 -351.382281)
			(xy 435.365942 -351.42817) (xy 435.388603 -351.47779) (xy 435.403973 -351.53013) (xy 435.411736 -351.584125)
			(xy 435.411736 -351.63867) (xy 436.894439 -351.63867) (xy 436.894439 -351.58413) (xy 436.902202 -351.530146)
			(xy 436.917568 -351.477816) (xy 436.940226 -351.428206) (xy 436.969713 -351.382325) (xy 437.005431 -351.341108)
			(xy 437.046651 -351.305394) (xy 437.092534 -351.27591) (xy 437.142146 -351.253257) (xy 437.194477 -351.237895)
			(xy 437.248462 -351.230137) (xy 437.275732 -351.229676) (xy 438.139332 -351.229676) (xy 438.166603 -351.230089)
			(xy 438.220588 -351.237855) (xy 438.272919 -351.253224) (xy 438.32253 -351.275885) (xy 438.368412 -351.305374)
			(xy 438.409629 -351.341093) (xy 438.445345 -351.382314) (xy 438.474831 -351.428198) (xy 438.497487 -351.477811)
			(xy 438.512852 -351.530143) (xy 438.520614 -351.584129) (xy 438.520614 -351.638666) (xy 440.003462 -351.638666)
			(xy 440.003462 -351.584134) (xy 440.011223 -351.530156) (xy 440.026586 -351.477832) (xy 440.04924 -351.428228)
			(xy 440.078722 -351.382352) (xy 440.114433 -351.341138) (xy 440.155645 -351.305427) (xy 440.201521 -351.275944)
			(xy 440.251125 -351.253289) (xy 440.303448 -351.237925) (xy 440.357426 -351.230163) (xy 440.384692 -351.229676)
			(xy 441.248292 -351.229676) (xy 441.275566 -351.230063) (xy 441.329559 -351.237825) (xy 441.381898 -351.253192)
			(xy 441.431517 -351.275851) (xy 441.477406 -351.305342) (xy 441.518632 -351.341063) (xy 441.554353 -351.382287)
			(xy 441.583845 -351.428176) (xy 441.606505 -351.477794) (xy 441.621873 -351.530133) (xy 441.629636 -351.584126)
			(xy 441.629636 -351.638674) (xy 441.621873 -351.692667) (xy 441.606505 -351.745006) (xy 441.583845 -351.794624)
			(xy 441.554353 -351.840513) (xy 441.518632 -351.881737) (xy 441.477406 -351.917458) (xy 441.431517 -351.946949)
			(xy 441.381898 -351.969608) (xy 441.329559 -351.984975) (xy 441.275566 -351.992737) (xy 441.248292 -351.9932)
			(xy 440.384692 -351.9932) (xy 440.357426 -351.992637) (xy 440.303448 -351.984875) (xy 440.251125 -351.969511)
			(xy 440.201521 -351.946856) (xy 440.155645 -351.917373) (xy 440.114433 -351.881662) (xy 440.078722 -351.840448)
			(xy 440.04924 -351.794572) (xy 440.026586 -351.744968) (xy 440.011223 -351.692644) (xy 440.003462 -351.638666)
			(xy 438.520614 -351.638666) (xy 438.520614 -351.638671) (xy 438.512852 -351.692657) (xy 438.497487 -351.744989)
			(xy 438.474831 -351.794602) (xy 438.445345 -351.840486) (xy 438.409629 -351.881707) (xy 438.368412 -351.917426)
			(xy 438.32253 -351.946915) (xy 438.272919 -351.969576) (xy 438.220588 -351.984945) (xy 438.166603 -351.992711)
			(xy 438.139332 -351.9932) (xy 437.275732 -351.9932) (xy 437.248462 -351.992663) (xy 437.194477 -351.984905)
			(xy 437.142146 -351.969543) (xy 437.092534 -351.94689) (xy 437.046651 -351.917406) (xy 437.005431 -351.881692)
			(xy 436.969713 -351.840475) (xy 436.940226 -351.794594) (xy 436.917568 -351.744984) (xy 436.902202 -351.692654)
			(xy 436.894439 -351.63867) (xy 435.411736 -351.63867) (xy 435.411736 -351.638675) (xy 435.403973 -351.69267)
			(xy 435.388603 -351.74501) (xy 435.365942 -351.79463) (xy 435.336448 -351.840519) (xy 435.300724 -351.881744)
			(xy 435.259497 -351.917465) (xy 435.213605 -351.946955) (xy 435.163984 -351.969613) (xy 435.111642 -351.984979)
			(xy 435.057647 -351.992738) (xy 435.030372 -351.9932) (xy 434.166772 -351.9932) (xy 434.139507 -351.992636)
			(xy 434.085531 -351.984872) (xy 434.03321 -351.969505) (xy 433.983609 -351.94685) (xy 433.937736 -351.917366)
			(xy 433.896526 -351.881654) (xy 433.860817 -351.840442) (xy 433.831337 -351.794567) (xy 433.808685 -351.744963)
			(xy 433.793322 -351.692641) (xy 433.785562 -351.638665) (xy 432.302714 -351.638665) (xy 432.302714 -351.638672)
			(xy 432.294951 -351.692659) (xy 432.279585 -351.744993) (xy 432.256928 -351.794608) (xy 432.22744 -351.840492)
			(xy 432.191722 -351.881714) (xy 432.150502 -351.917433) (xy 432.104618 -351.946922) (xy 432.055004 -351.969581)
			(xy 432.002671 -351.984949) (xy 431.948684 -351.992713) (xy 431.921412 -351.9932) (xy 431.057812 -351.9932)
			(xy 431.030543 -351.992661) (xy 430.97656 -351.984901) (xy 430.924231 -351.969538) (xy 430.874622 -351.946883)
			(xy 430.828741 -351.917399) (xy 430.787524 -351.881685) (xy 430.751808 -351.840469) (xy 430.722323 -351.794589)
			(xy 430.699666 -351.74498) (xy 430.684301 -351.692651) (xy 430.676539 -351.638669) (xy 429.193836 -351.638669)
			(xy 429.193836 -351.638676) (xy 429.186072 -351.692672) (xy 429.170702 -351.745014) (xy 429.148039 -351.794635)
			(xy 429.118544 -351.840526) (xy 429.082817 -351.881751) (xy 429.041587 -351.917472) (xy 428.995693 -351.946962)
			(xy 428.946069 -351.969619) (xy 428.893725 -351.984982) (xy 428.839728 -351.99274) (xy 428.812452 -351.9932)
			(xy 427.948852 -351.9932) (xy 427.921588 -351.992634) (xy 427.867615 -351.984868) (xy 427.815296 -351.9695)
			(xy 427.765697 -351.946843) (xy 427.719826 -351.917359) (xy 427.678619 -351.881647) (xy 427.642912 -351.840435)
			(xy 427.613434 -351.794561) (xy 427.590783 -351.744959) (xy 427.575422 -351.692639) (xy 427.567662 -351.638664)
			(xy 426.084836 -351.638664) (xy 426.084836 -351.638674) (xy 426.077073 -351.692667) (xy 426.061705 -351.745006)
			(xy 426.039045 -351.794624) (xy 426.009553 -351.840513) (xy 425.973832 -351.881737) (xy 425.932606 -351.917458)
			(xy 425.886717 -351.946949) (xy 425.837098 -351.969608) (xy 425.784759 -351.984975) (xy 425.730766 -351.992737)
			(xy 425.703492 -351.9932) (xy 424.839892 -351.9932) (xy 424.812626 -351.992637) (xy 424.758648 -351.984875)
			(xy 424.706325 -351.969511) (xy 424.656721 -351.946856) (xy 424.610845 -351.917373) (xy 424.569633 -351.881662)
			(xy 424.533922 -351.840448) (xy 424.50444 -351.794572) (xy 424.481786 -351.744968) (xy 424.466423 -351.692644)
			(xy 424.458662 -351.638666) (xy 422.975814 -351.638666) (xy 422.975814 -351.638671) (xy 422.968052 -351.692657)
			(xy 422.952687 -351.744989) (xy 422.930031 -351.794602) (xy 422.900545 -351.840486) (xy 422.864829 -351.881707)
			(xy 422.823612 -351.917426) (xy 422.77773 -351.946915) (xy 422.728119 -351.969576) (xy 422.675788 -351.984945)
			(xy 422.621803 -351.992711) (xy 422.594532 -351.9932) (xy 421.730932 -351.9932) (xy 421.703662 -351.992663)
			(xy 421.649677 -351.984905) (xy 421.597346 -351.969543) (xy 421.547734 -351.94689) (xy 421.501851 -351.917406)
			(xy 421.460631 -351.881692) (xy 421.424913 -351.840475) (xy 421.395426 -351.794594) (xy 421.372768 -351.744984)
			(xy 421.357402 -351.692654) (xy 421.349639 -351.63867) (xy 419.866936 -351.63867) (xy 419.866936 -351.638675)
			(xy 419.859173 -351.69267) (xy 419.843803 -351.74501) (xy 419.821142 -351.79463) (xy 419.791648 -351.840519)
			(xy 419.755924 -351.881744) (xy 419.714697 -351.917465) (xy 419.668805 -351.946955) (xy 419.619184 -351.969613)
			(xy 419.566842 -351.984979) (xy 419.512847 -351.992738) (xy 419.485572 -351.9932) (xy 418.621972 -351.9932)
			(xy 418.594707 -351.992636) (xy 418.540731 -351.984872) (xy 418.48841 -351.969505) (xy 418.438809 -351.94685)
			(xy 418.392936 -351.917366) (xy 418.351726 -351.881654) (xy 418.316017 -351.840442) (xy 418.286537 -351.794567)
			(xy 418.263885 -351.744963) (xy 418.248522 -351.692641) (xy 418.240762 -351.638665) (xy 416.757914 -351.638665)
			(xy 416.757914 -351.638672) (xy 416.750151 -351.692659) (xy 416.734785 -351.744993) (xy 416.712128 -351.794608)
			(xy 416.68264 -351.840492) (xy 416.646922 -351.881714) (xy 416.605702 -351.917433) (xy 416.559818 -351.946922)
			(xy 416.510204 -351.969581) (xy 416.457871 -351.984949) (xy 416.403884 -351.992713) (xy 416.376612 -351.9932)
			(xy 415.513012 -351.9932) (xy 415.485743 -351.992661) (xy 415.43176 -351.984901) (xy 415.379431 -351.969538)
			(xy 415.329822 -351.946883) (xy 415.283941 -351.917399) (xy 415.242724 -351.881685) (xy 415.207008 -351.840469)
			(xy 415.177523 -351.794589) (xy 415.154866 -351.74498) (xy 415.139501 -351.692651) (xy 415.131739 -351.638669)
			(xy 413.649036 -351.638669) (xy 413.649036 -351.638676) (xy 413.641272 -351.692672) (xy 413.625902 -351.745014)
			(xy 413.603239 -351.794635) (xy 413.573744 -351.840526) (xy 413.538017 -351.881751) (xy 413.496787 -351.917472)
			(xy 413.450893 -351.946962) (xy 413.401269 -351.969619) (xy 413.348925 -351.984982) (xy 413.294928 -351.99274)
			(xy 413.267652 -351.9932) (xy 412.404052 -351.9932) (xy 412.376788 -351.992634) (xy 412.322815 -351.984868)
			(xy 412.270496 -351.9695) (xy 412.220897 -351.946843) (xy 412.175026 -351.917359) (xy 412.133819 -351.881647)
			(xy 412.098112 -351.840435) (xy 412.068634 -351.794561) (xy 412.045983 -351.744959) (xy 412.030622 -351.692639)
			(xy 412.022862 -351.638664) (xy 410.540036 -351.638664) (xy 410.540036 -351.638674) (xy 410.532273 -351.692667)
			(xy 410.516905 -351.745006) (xy 410.494245 -351.794624) (xy 410.464753 -351.840513) (xy 410.429032 -351.881737)
			(xy 410.387806 -351.917458) (xy 410.341917 -351.946949) (xy 410.292298 -351.969608) (xy 410.239959 -351.984975)
			(xy 410.185966 -351.992737) (xy 410.158692 -351.9932) (xy 409.295092 -351.9932) (xy 409.267826 -351.992637)
			(xy 409.213848 -351.984875) (xy 409.161525 -351.969511) (xy 409.111921 -351.946856) (xy 409.066045 -351.917373)
			(xy 409.024833 -351.881662) (xy 408.989122 -351.840448) (xy 408.95964 -351.794572) (xy 408.936986 -351.744968)
			(xy 408.921623 -351.692644) (xy 408.913862 -351.638666) (xy 403.522536 -351.638666) (xy 403.522536 -351.638675)
			(xy 403.514773 -351.692669) (xy 403.499404 -351.745008) (xy 403.476743 -351.794628) (xy 403.44725 -351.840517)
			(xy 403.411527 -351.881741) (xy 403.370301 -351.917462) (xy 403.32441 -351.946952) (xy 403.274789 -351.969611)
			(xy 403.222449 -351.984977) (xy 403.168455 -351.992738) (xy 403.14118 -351.9932) (xy 402.27758 -351.9932)
			(xy 402.250314 -351.992636) (xy 402.196338 -351.984873) (xy 402.144016 -351.969508) (xy 402.094414 -351.946852)
			(xy 402.04854 -351.917369) (xy 402.007329 -351.881657) (xy 401.971619 -351.840444) (xy 401.942138 -351.794569)
			(xy 401.919485 -351.744965) (xy 401.904123 -351.692642) (xy 401.896362 -351.638666) (xy 400.413514 -351.638666)
			(xy 400.413514 -351.638671) (xy 400.405752 -351.692658) (xy 400.390386 -351.744992) (xy 400.367729 -351.794605)
			(xy 400.338242 -351.84049) (xy 400.302525 -351.881711) (xy 400.261306 -351.91743) (xy 400.215423 -351.946919)
			(xy 400.16581 -351.969579) (xy 400.113478 -351.984947) (xy 400.059491 -351.992712) (xy 400.03222 -351.9932)
			(xy 399.16862 -351.9932) (xy 399.141351 -351.992662) (xy 399.087367 -351.984903) (xy 399.035037 -351.96954)
			(xy 398.985426 -351.946886) (xy 398.939545 -351.917402) (xy 398.898326 -351.881688) (xy 398.86261 -351.840471)
			(xy 398.833124 -351.794591) (xy 398.810467 -351.744982) (xy 398.795101 -351.692652) (xy 398.787339 -351.638669)
			(xy 397.304636 -351.638669) (xy 397.304636 -351.638676) (xy 397.296872 -351.692671) (xy 397.281503 -351.745012)
			(xy 397.25884 -351.794633) (xy 397.229346 -351.840523) (xy 397.19362 -351.881749) (xy 397.152391 -351.91747)
			(xy 397.106498 -351.946959) (xy 397.056875 -351.969617) (xy 397.004532 -351.984981) (xy 396.950536 -351.992739)
			(xy 396.92326 -351.9932) (xy 396.05966 -351.9932) (xy 396.032395 -351.992635) (xy 395.978421 -351.984869)
			(xy 395.926102 -351.969502) (xy 395.876502 -351.946846) (xy 395.83063 -351.917362) (xy 395.789421 -351.88165)
			(xy 395.753714 -351.840438) (xy 395.724235 -351.794563) (xy 395.701584 -351.744961) (xy 395.686222 -351.69264)
			(xy 395.678462 -351.638665) (xy 394.195613 -351.638665) (xy 394.195613 -351.638672) (xy 394.187851 -351.692661)
			(xy 394.172484 -351.744996) (xy 394.149826 -351.794611) (xy 394.120337 -351.840496) (xy 394.084618 -351.881718)
			(xy 394.043396 -351.917437) (xy 393.997511 -351.946926) (xy 393.947896 -351.969584) (xy 393.895561 -351.984951)
			(xy 393.841572 -351.992713) (xy 393.8143 -351.9932) (xy 392.9507 -351.9932) (xy 392.923433 -351.992638)
			(xy 392.869455 -351.984877) (xy 392.817131 -351.969513) (xy 392.767526 -351.946859) (xy 392.721649 -351.917376)
			(xy 392.680436 -351.881664) (xy 392.644724 -351.840451) (xy 392.615241 -351.794574) (xy 392.592587 -351.744969)
			(xy 392.577223 -351.692645) (xy 392.569462 -351.638667) (xy 391.086614 -351.638667) (xy 391.086614 -351.63867)
			(xy 391.078852 -351.692656) (xy 391.063487 -351.744987) (xy 391.040832 -351.7946) (xy 391.011347 -351.840483)
			(xy 390.975632 -351.881704) (xy 390.934415 -351.917423) (xy 390.888535 -351.946913) (xy 390.838925 -351.969573)
			(xy 390.786595 -351.984944) (xy 390.73261 -351.992711) (xy 390.70534 -351.9932) (xy 389.84174 -351.9932)
			(xy 389.81447 -351.992663) (xy 389.760484 -351.984907) (xy 389.708152 -351.969545) (xy 389.658538 -351.946892)
			(xy 389.612654 -351.917409) (xy 389.571434 -351.881695) (xy 389.535715 -351.840478) (xy 389.506227 -351.794597)
			(xy 389.483569 -351.744986) (xy 389.468202 -351.692655) (xy 389.46044 -351.63867) (xy 387.977736 -351.63867)
			(xy 387.977736 -351.638675) (xy 387.969973 -351.692669) (xy 387.954604 -351.745008) (xy 387.931943 -351.794628)
			(xy 387.90245 -351.840517) (xy 387.866727 -351.881741) (xy 387.825501 -351.917462) (xy 387.77961 -351.946952)
			(xy 387.729989 -351.969611) (xy 387.677649 -351.984977) (xy 387.623655 -351.992738) (xy 387.59638 -351.9932)
			(xy 386.73278 -351.9932) (xy 386.705514 -351.992636) (xy 386.651538 -351.984873) (xy 386.599216 -351.969508)
			(xy 386.549614 -351.946852) (xy 386.50374 -351.917369) (xy 386.462529 -351.881657) (xy 386.426819 -351.840444)
			(xy 386.397338 -351.794569) (xy 386.374685 -351.744965) (xy 386.359323 -351.692642) (xy 386.351562 -351.638666)
			(xy 384.868714 -351.638666) (xy 384.868714 -351.638671) (xy 384.860952 -351.692658) (xy 384.845586 -351.744992)
			(xy 384.822929 -351.794605) (xy 384.793442 -351.84049) (xy 384.757725 -351.881711) (xy 384.716506 -351.91743)
			(xy 384.670623 -351.946919) (xy 384.62101 -351.969579) (xy 384.568678 -351.984947) (xy 384.514691 -351.992712)
			(xy 384.48742 -351.9932) (xy 383.62382 -351.9932) (xy 383.596551 -351.992662) (xy 383.542567 -351.984903)
			(xy 383.490237 -351.96954) (xy 383.440626 -351.946886) (xy 383.394745 -351.917402) (xy 383.353526 -351.881688)
			(xy 383.31781 -351.840471) (xy 383.288324 -351.794591) (xy 383.265667 -351.744982) (xy 383.250301 -351.692652)
			(xy 383.242539 -351.638669) (xy 381.759836 -351.638669) (xy 381.759836 -351.638676) (xy 381.752072 -351.692671)
			(xy 381.736703 -351.745012) (xy 381.71404 -351.794633) (xy 381.684546 -351.840523) (xy 381.64882 -351.881749)
			(xy 381.607591 -351.91747) (xy 381.561698 -351.946959) (xy 381.512075 -351.969617) (xy 381.459732 -351.984981)
			(xy 381.405736 -351.992739) (xy 381.37846 -351.9932) (xy 380.51486 -351.9932) (xy 380.487595 -351.992635)
			(xy 380.433621 -351.984869) (xy 380.381302 -351.969502) (xy 380.331702 -351.946846) (xy 380.28583 -351.917362)
			(xy 380.244621 -351.88165) (xy 380.208914 -351.840438) (xy 380.179435 -351.794563) (xy 380.156784 -351.744961)
			(xy 380.141422 -351.69264) (xy 380.133662 -351.638665) (xy 378.650813 -351.638665) (xy 378.650813 -351.638672)
			(xy 378.643051 -351.692661) (xy 378.627684 -351.744996) (xy 378.605026 -351.794611) (xy 378.575537 -351.840496)
			(xy 378.539818 -351.881718) (xy 378.498596 -351.917437) (xy 378.452711 -351.946926) (xy 378.403096 -351.969584)
			(xy 378.350761 -351.984951) (xy 378.296772 -351.992713) (xy 378.2695 -351.9932) (xy 377.4059 -351.9932)
			(xy 377.378633 -351.992638) (xy 377.324655 -351.984877) (xy 377.272331 -351.969513) (xy 377.222726 -351.946859)
			(xy 377.176849 -351.917376) (xy 377.135636 -351.881664) (xy 377.099924 -351.840451) (xy 377.070441 -351.794574)
			(xy 377.047787 -351.744969) (xy 377.032423 -351.692645) (xy 377.024662 -351.638667) (xy 375.541814 -351.638667)
			(xy 375.541814 -351.63867) (xy 375.534052 -351.692656) (xy 375.518687 -351.744987) (xy 375.496032 -351.7946)
			(xy 375.466547 -351.840483) (xy 375.430832 -351.881704) (xy 375.389615 -351.917423) (xy 375.343735 -351.946913)
			(xy 375.294125 -351.969573) (xy 375.241795 -351.984944) (xy 375.18781 -351.992711) (xy 375.16054 -351.9932)
			(xy 374.29694 -351.9932) (xy 374.26967 -351.992663) (xy 374.215684 -351.984907) (xy 374.163352 -351.969545)
			(xy 374.113738 -351.946892) (xy 374.067854 -351.917409) (xy 374.026634 -351.881695) (xy 373.990915 -351.840478)
			(xy 373.961427 -351.794597) (xy 373.938769 -351.744986) (xy 373.923402 -351.692655) (xy 373.91564 -351.63867)
			(xy 372.432936 -351.63867) (xy 372.432936 -351.638675) (xy 372.425173 -351.692669) (xy 372.409804 -351.745008)
			(xy 372.387143 -351.794628) (xy 372.35765 -351.840517) (xy 372.321927 -351.881741) (xy 372.280701 -351.917462)
			(xy 372.23481 -351.946952) (xy 372.185189 -351.969611) (xy 372.132849 -351.984977) (xy 372.078855 -351.992738)
			(xy 372.05158 -351.9932) (xy 371.18798 -351.9932) (xy 371.160714 -351.992636) (xy 371.106738 -351.984873)
			(xy 371.054416 -351.969508) (xy 371.004814 -351.946852) (xy 370.95894 -351.917369) (xy 370.917729 -351.881657)
			(xy 370.882019 -351.840444) (xy 370.852538 -351.794569) (xy 370.829885 -351.744965) (xy 370.814523 -351.692642)
			(xy 370.806762 -351.638666) (xy 344.837313 -351.638666) (xy 344.837313 -351.638672) (xy 344.829551 -351.692661)
			(xy 344.814184 -351.744995) (xy 344.791526 -351.79461) (xy 344.762038 -351.840495) (xy 344.726319 -351.881717)
			(xy 344.685098 -351.917435) (xy 344.639213 -351.946924) (xy 344.589599 -351.969583) (xy 344.537264 -351.98495)
			(xy 344.483276 -351.992713) (xy 344.456004 -351.9932) (xy 343.592404 -351.9932) (xy 343.565136 -351.992661)
			(xy 343.511154 -351.9849) (xy 343.458826 -351.969536) (xy 343.409217 -351.94688) (xy 343.363337 -351.917396)
			(xy 343.322121 -351.881682) (xy 343.286407 -351.840466) (xy 343.256921 -351.794587) (xy 343.234266 -351.744978)
			(xy 343.218901 -351.69265) (xy 343.211139 -351.638668) (xy 341.728314 -351.638668) (xy 341.728314 -351.63867)
			(xy 341.720552 -351.692655) (xy 341.705188 -351.744986) (xy 341.682532 -351.794599) (xy 341.653048 -351.840482)
			(xy 341.617334 -351.881703) (xy 341.576117 -351.917421) (xy 341.530237 -351.946911) (xy 341.480628 -351.969572)
			(xy 341.428298 -351.984943) (xy 341.374314 -351.99271) (xy 341.347044 -351.9932) (xy 340.483444 -351.9932)
			(xy 340.456174 -351.992664) (xy 340.402187 -351.984907) (xy 340.349855 -351.969546) (xy 340.300241 -351.946894)
			(xy 340.254356 -351.91741) (xy 340.213135 -351.881696) (xy 340.177416 -351.840479) (xy 340.147928 -351.794598)
			(xy 340.125269 -351.744987) (xy 340.109902 -351.692656) (xy 340.10214 -351.63867) (xy 338.619436 -351.63867)
			(xy 338.619436 -351.638674) (xy 338.611673 -351.692668) (xy 338.596304 -351.745007) (xy 338.573643 -351.794626)
			(xy 338.544151 -351.840515) (xy 338.508429 -351.88174) (xy 338.467203 -351.917461) (xy 338.421312 -351.946951)
			(xy 338.371692 -351.96961) (xy 338.319352 -351.984976) (xy 338.265358 -351.992738) (xy 338.238084 -351.9932)
			(xy 337.374484 -351.9932) (xy 337.347218 -351.992637) (xy 337.293242 -351.984874) (xy 337.240919 -351.969509)
			(xy 337.191316 -351.946854) (xy 337.145442 -351.91737) (xy 337.10423 -351.881659) (xy 337.06852 -351.840446)
			(xy 337.039039 -351.79457) (xy 337.016386 -351.744966) (xy 337.001023 -351.692643) (xy 336.993262 -351.638666)
			(xy 335.510414 -351.638666) (xy 335.510414 -351.638671) (xy 335.502652 -351.692658) (xy 335.487286 -351.744991)
			(xy 335.464629 -351.794604) (xy 335.435143 -351.840488) (xy 335.399427 -351.88171) (xy 335.358208 -351.917428)
			(xy 335.312325 -351.946918) (xy 335.262713 -351.969578) (xy 335.210381 -351.984947) (xy 335.156395 -351.992712)
			(xy 335.129124 -351.9932) (xy 334.265524 -351.9932) (xy 334.238255 -351.992662) (xy 334.18427 -351.984904)
			(xy 334.13194 -351.969541) (xy 334.082329 -351.946887) (xy 334.036447 -351.917403) (xy 333.995228 -351.881689)
			(xy 333.959511 -351.840472) (xy 333.930024 -351.794592) (xy 333.907367 -351.744982) (xy 333.892001 -351.692653)
			(xy 333.884239 -351.638669) (xy 332.401536 -351.638669) (xy 332.401536 -351.638675) (xy 332.393772 -351.692671)
			(xy 332.378403 -351.745011) (xy 332.35574 -351.794632) (xy 332.326246 -351.840522) (xy 332.290522 -351.881747)
			(xy 332.249293 -351.917468) (xy 332.2034 -351.946958) (xy 332.153778 -351.969615) (xy 332.101436 -351.98498)
			(xy 332.047439 -351.992739) (xy 332.020164 -351.9932) (xy 331.156564 -351.9932) (xy 331.129299 -351.992635)
			(xy 331.075325 -351.98487) (xy 331.023005 -351.969503) (xy 330.973404 -351.946847) (xy 330.927532 -351.917363)
			(xy 330.886323 -351.881652) (xy 330.850615 -351.840439) (xy 330.821136 -351.794564) (xy 330.798484 -351.744962)
			(xy 330.783122 -351.69264) (xy 330.775362 -351.638665) (xy 329.292513 -351.638665) (xy 329.292513 -351.638672)
			(xy 329.284751 -351.692661) (xy 329.269384 -351.744995) (xy 329.246726 -351.79461) (xy 329.217238 -351.840495)
			(xy 329.181519 -351.881717) (xy 329.140298 -351.917435) (xy 329.094413 -351.946924) (xy 329.044799 -351.969583)
			(xy 328.992464 -351.98495) (xy 328.938476 -351.992713) (xy 328.911204 -351.9932) (xy 328.047604 -351.9932)
			(xy 328.020336 -351.992661) (xy 327.966354 -351.9849) (xy 327.914026 -351.969536) (xy 327.864417 -351.94688)
			(xy 327.818537 -351.917396) (xy 327.777321 -351.881682) (xy 327.741607 -351.840466) (xy 327.712121 -351.794587)
			(xy 327.689466 -351.744978) (xy 327.674101 -351.69265) (xy 327.666339 -351.638668) (xy 326.183514 -351.638668)
			(xy 326.183514 -351.63867) (xy 326.175752 -351.692655) (xy 326.160388 -351.744986) (xy 326.137732 -351.794599)
			(xy 326.108248 -351.840482) (xy 326.072534 -351.881703) (xy 326.031317 -351.917421) (xy 325.985437 -351.946911)
			(xy 325.935828 -351.969572) (xy 325.883498 -351.984943) (xy 325.829514 -351.99271) (xy 325.802244 -351.9932)
			(xy 324.938644 -351.9932) (xy 324.911374 -351.992664) (xy 324.857387 -351.984907) (xy 324.805055 -351.969546)
			(xy 324.755441 -351.946894) (xy 324.709556 -351.91741) (xy 324.668335 -351.881696) (xy 324.632616 -351.840479)
			(xy 324.603128 -351.794598) (xy 324.580469 -351.744987) (xy 324.565102 -351.692656) (xy 324.55734 -351.63867)
			(xy 323.074636 -351.63867) (xy 323.074636 -351.638674) (xy 323.066873 -351.692668) (xy 323.051504 -351.745007)
			(xy 323.028843 -351.794626) (xy 322.999351 -351.840515) (xy 322.963629 -351.88174) (xy 322.922403 -351.917461)
			(xy 322.876512 -351.946951) (xy 322.826892 -351.96961) (xy 322.774552 -351.984976) (xy 322.720558 -351.992738)
			(xy 322.693284 -351.9932) (xy 321.829684 -351.9932) (xy 321.802418 -351.992637) (xy 321.748442 -351.984874)
			(xy 321.696119 -351.969509) (xy 321.646516 -351.946854) (xy 321.600642 -351.91737) (xy 321.55943 -351.881659)
			(xy 321.52372 -351.840446) (xy 321.494239 -351.79457) (xy 321.471586 -351.744966) (xy 321.456223 -351.692643)
			(xy 321.448462 -351.638666) (xy 319.965614 -351.638666) (xy 319.965614 -351.638671) (xy 319.957852 -351.692658)
			(xy 319.942486 -351.744991) (xy 319.919829 -351.794604) (xy 319.890343 -351.840488) (xy 319.854627 -351.88171)
			(xy 319.813408 -351.917428) (xy 319.767525 -351.946918) (xy 319.717913 -351.969578) (xy 319.665581 -351.984947)
			(xy 319.611595 -351.992712) (xy 319.584324 -351.9932) (xy 318.720724 -351.9932) (xy 318.693455 -351.992662)
			(xy 318.63947 -351.984904) (xy 318.58714 -351.969541) (xy 318.537529 -351.946887) (xy 318.491647 -351.917403)
			(xy 318.450428 -351.881689) (xy 318.414711 -351.840472) (xy 318.385224 -351.794592) (xy 318.362567 -351.744982)
			(xy 318.347201 -351.692653) (xy 318.339439 -351.638669) (xy 316.856736 -351.638669) (xy 316.856736 -351.638675)
			(xy 316.848972 -351.692671) (xy 316.833603 -351.745011) (xy 316.81094 -351.794632) (xy 316.781446 -351.840522)
			(xy 316.745722 -351.881747) (xy 316.704493 -351.917468) (xy 316.6586 -351.946958) (xy 316.608978 -351.969615)
			(xy 316.556636 -351.98498) (xy 316.502639 -351.992739) (xy 316.475364 -351.9932) (xy 315.611764 -351.9932)
			(xy 315.584499 -351.992635) (xy 315.530525 -351.98487) (xy 315.478205 -351.969503) (xy 315.428604 -351.946847)
			(xy 315.382732 -351.917363) (xy 315.341523 -351.881652) (xy 315.305815 -351.840439) (xy 315.276336 -351.794564)
			(xy 315.253684 -351.744962) (xy 315.238322 -351.69264) (xy 315.230562 -351.638665) (xy 313.747713 -351.638665)
			(xy 313.747713 -351.638672) (xy 313.739951 -351.692661) (xy 313.724584 -351.744995) (xy 313.701926 -351.79461)
			(xy 313.672438 -351.840495) (xy 313.636719 -351.881717) (xy 313.595498 -351.917435) (xy 313.549613 -351.946924)
			(xy 313.499999 -351.969583) (xy 313.447664 -351.98495) (xy 313.393676 -351.992713) (xy 313.366404 -351.9932)
			(xy 312.502804 -351.9932) (xy 312.475536 -351.992661) (xy 312.421554 -351.9849) (xy 312.369226 -351.969536)
			(xy 312.319617 -351.94688) (xy 312.273737 -351.917396) (xy 312.232521 -351.881682) (xy 312.196807 -351.840466)
			(xy 312.167321 -351.794587) (xy 312.144666 -351.744978) (xy 312.129301 -351.69265) (xy 312.121539 -351.638668)
			(xy 300.231613 -351.638668) (xy 300.231613 -351.638672) (xy 300.223851 -351.692661) (xy 300.208484 -351.744995)
			(xy 300.185826 -351.79461) (xy 300.156337 -351.840496) (xy 300.120619 -351.881717) (xy 300.079397 -351.917436)
			(xy 300.033512 -351.946925) (xy 299.983897 -351.969584) (xy 299.931563 -351.984951) (xy 299.877574 -351.992713)
			(xy 299.850302 -351.9932) (xy 298.986702 -351.9932) (xy 298.959434 -351.992661) (xy 298.905452 -351.9849)
			(xy 298.853124 -351.969535) (xy 298.803516 -351.94688) (xy 298.757636 -351.917395) (xy 298.71642 -351.881681)
			(xy 298.680706 -351.840465) (xy 298.651221 -351.794586) (xy 298.628566 -351.744978) (xy 298.613201 -351.69265)
			(xy 298.605439 -351.638668) (xy 297.122614 -351.638668) (xy 297.122614 -351.63867) (xy 297.114852 -351.692655)
			(xy 297.099488 -351.744987) (xy 297.076832 -351.794599) (xy 297.047347 -351.840483) (xy 297.011633 -351.881703)
			(xy 296.970416 -351.917422) (xy 296.924536 -351.946912) (xy 296.874926 -351.969573) (xy 296.822597 -351.984943)
			(xy 296.768612 -351.992711) (xy 296.741342 -351.9932) (xy 295.877742 -351.9932) (xy 295.850472 -351.992663)
			(xy 295.796486 -351.984907) (xy 295.744153 -351.969546) (xy 295.69454 -351.946893) (xy 295.648655 -351.917409)
			(xy 295.607434 -351.881695) (xy 295.571716 -351.840478) (xy 295.542227 -351.794597) (xy 295.519569 -351.744986)
			(xy 295.504202 -351.692655) (xy 295.49644 -351.63867) (xy 294.013736 -351.63867) (xy 294.013736 -351.638675)
			(xy 294.005973 -351.692668) (xy 293.990604 -351.745008) (xy 293.967943 -351.794627) (xy 293.938451 -351.840516)
			(xy 293.902728 -351.881741) (xy 293.861502 -351.917462) (xy 293.815611 -351.946952) (xy 293.765991 -351.969611)
			(xy 293.713651 -351.984977) (xy 293.659657 -351.992738) (xy 293.632382 -351.9932) (xy 292.768782 -351.9932)
			(xy 292.741516 -351.992636) (xy 292.68754 -351.984873) (xy 292.635218 -351.969508) (xy 292.585615 -351.946853)
			(xy 292.539741 -351.91737) (xy 292.498529 -351.881658) (xy 292.46282 -351.840445) (xy 292.433338 -351.794569)
			(xy 292.410686 -351.744965) (xy 292.395323 -351.692642) (xy 292.387562 -351.638666) (xy 290.904714 -351.638666)
			(xy 290.904714 -351.638671) (xy 290.896952 -351.692658) (xy 290.881586 -351.744991) (xy 290.858929 -351.794605)
			(xy 290.829442 -351.840489) (xy 290.793726 -351.88171) (xy 290.752507 -351.917429) (xy 290.706624 -351.946919)
			(xy 290.657012 -351.969578) (xy 290.60468 -351.984947) (xy 290.550693 -351.992712) (xy 290.523422 -351.9932)
			(xy 289.659822 -351.9932) (xy 289.632553 -351.992662) (xy 289.578569 -351.984903) (xy 289.526239 -351.96954)
			(xy 289.476628 -351.946886) (xy 289.430746 -351.917402) (xy 289.389527 -351.881688) (xy 289.353811 -351.840472)
			(xy 289.324324 -351.794592) (xy 289.301667 -351.744982) (xy 289.286301 -351.692653) (xy 289.278539 -351.638669)
			(xy 287.795836 -351.638669) (xy 287.795836 -351.638675) (xy 287.788072 -351.692671) (xy 287.772703 -351.745012)
			(xy 287.75004 -351.794633) (xy 287.720546 -351.840523) (xy 287.684821 -351.881748) (xy 287.643592 -351.917469)
			(xy 287.597699 -351.946958) (xy 287.548076 -351.969616) (xy 287.495734 -351.98498) (xy 287.441737 -351.992739)
			(xy 287.414462 -351.9932) (xy 286.550862 -351.9932) (xy 286.523597 -351.992635) (xy 286.469623 -351.98487)
			(xy 286.417303 -351.969503) (xy 286.367703 -351.946847) (xy 286.321831 -351.917363) (xy 286.280622 -351.881651)
			(xy 286.244915 -351.840438) (xy 286.215435 -351.794564) (xy 286.192784 -351.744961) (xy 286.177422 -351.69264)
			(xy 286.169662 -351.638665) (xy 284.686813 -351.638665) (xy 284.686813 -351.638672) (xy 284.679051 -351.692661)
			(xy 284.663684 -351.744995) (xy 284.641026 -351.79461) (xy 284.611537 -351.840496) (xy 284.575819 -351.881717)
			(xy 284.534597 -351.917436) (xy 284.488712 -351.946925) (xy 284.439097 -351.969584) (xy 284.386763 -351.984951)
			(xy 284.332774 -351.992713) (xy 284.305502 -351.9932) (xy 283.441902 -351.9932) (xy 283.414634 -351.992661)
			(xy 283.360652 -351.9849) (xy 283.308324 -351.969535) (xy 283.258716 -351.94688) (xy 283.212836 -351.917395)
			(xy 283.17162 -351.881681) (xy 283.135906 -351.840465) (xy 283.106421 -351.794586) (xy 283.083766 -351.744978)
			(xy 283.068401 -351.69265) (xy 283.060639 -351.638668) (xy 281.577814 -351.638668) (xy 281.577814 -351.63867)
			(xy 281.570052 -351.692655) (xy 281.554688 -351.744987) (xy 281.532032 -351.794599) (xy 281.502547 -351.840483)
			(xy 281.466833 -351.881703) (xy 281.425616 -351.917422) (xy 281.379736 -351.946912) (xy 281.330126 -351.969573)
			(xy 281.277797 -351.984943) (xy 281.223812 -351.992711) (xy 281.196542 -351.9932) (xy 280.332942 -351.9932)
			(xy 280.305672 -351.992663) (xy 280.251686 -351.984907) (xy 280.199353 -351.969546) (xy 280.14974 -351.946893)
			(xy 280.103855 -351.917409) (xy 280.062634 -351.881695) (xy 280.026916 -351.840478) (xy 279.997427 -351.794597)
			(xy 279.974769 -351.744986) (xy 279.959402 -351.692655) (xy 279.95164 -351.63867) (xy 278.468936 -351.63867)
			(xy 278.468936 -351.638675) (xy 278.461173 -351.692668) (xy 278.445804 -351.745008) (xy 278.423143 -351.794627)
			(xy 278.393651 -351.840516) (xy 278.357928 -351.881741) (xy 278.316702 -351.917462) (xy 278.270811 -351.946952)
			(xy 278.221191 -351.969611) (xy 278.168851 -351.984977) (xy 278.114857 -351.992738) (xy 278.087582 -351.9932)
			(xy 277.223982 -351.9932) (xy 277.196716 -351.992636) (xy 277.14274 -351.984873) (xy 277.090418 -351.969508)
			(xy 277.040815 -351.946853) (xy 276.994941 -351.91737) (xy 276.953729 -351.881658) (xy 276.91802 -351.840445)
			(xy 276.888538 -351.794569) (xy 276.865886 -351.744965) (xy 276.850523 -351.692642) (xy 276.842762 -351.638666)
			(xy 275.359914 -351.638666) (xy 275.359914 -351.638671) (xy 275.352152 -351.692658) (xy 275.336786 -351.744991)
			(xy 275.314129 -351.794605) (xy 275.284642 -351.840489) (xy 275.248926 -351.88171) (xy 275.207707 -351.917429)
			(xy 275.161824 -351.946919) (xy 275.112212 -351.969578) (xy 275.05988 -351.984947) (xy 275.005893 -351.992712)
			(xy 274.978622 -351.9932) (xy 274.115022 -351.9932) (xy 274.087753 -351.992662) (xy 274.033769 -351.984903)
			(xy 273.981439 -351.96954) (xy 273.931828 -351.946886) (xy 273.885946 -351.917402) (xy 273.844727 -351.881688)
			(xy 273.809011 -351.840472) (xy 273.779524 -351.794592) (xy 273.756867 -351.744982) (xy 273.741501 -351.692653)
			(xy 273.733739 -351.638669) (xy 272.251036 -351.638669) (xy 272.251036 -351.638675) (xy 272.243272 -351.692671)
			(xy 272.227903 -351.745012) (xy 272.20524 -351.794633) (xy 272.175746 -351.840523) (xy 272.140021 -351.881748)
			(xy 272.098792 -351.917469) (xy 272.052899 -351.946958) (xy 272.003276 -351.969616) (xy 271.950934 -351.98498)
			(xy 271.896937 -351.992739) (xy 271.869662 -351.9932) (xy 271.006062 -351.9932) (xy 270.978797 -351.992635)
			(xy 270.924823 -351.98487) (xy 270.872503 -351.969503) (xy 270.822903 -351.946847) (xy 270.777031 -351.917363)
			(xy 270.735822 -351.881651) (xy 270.700115 -351.840438) (xy 270.670635 -351.794564) (xy 270.647984 -351.744961)
			(xy 270.632622 -351.69264) (xy 270.624862 -351.638665) (xy 269.142013 -351.638665) (xy 269.142013 -351.638672)
			(xy 269.134251 -351.692661) (xy 269.118884 -351.744995) (xy 269.096226 -351.79461) (xy 269.066737 -351.840496)
			(xy 269.031019 -351.881717) (xy 268.989797 -351.917436) (xy 268.943912 -351.946925) (xy 268.894297 -351.969584)
			(xy 268.841963 -351.984951) (xy 268.787974 -351.992713) (xy 268.760702 -351.9932) (xy 267.897102 -351.9932)
			(xy 267.869834 -351.992661) (xy 267.815852 -351.9849) (xy 267.763524 -351.969535) (xy 267.713916 -351.94688)
			(xy 267.668036 -351.917395) (xy 267.62682 -351.881681) (xy 267.591106 -351.840465) (xy 267.561621 -351.794586)
			(xy 267.538966 -351.744978) (xy 267.523601 -351.69265) (xy 267.515839 -351.638668) (xy 194.520614 -351.638668)
			(xy 194.520614 -351.638672) (xy 194.512851 -351.692659) (xy 194.497485 -351.744993) (xy 194.474828 -351.794608)
			(xy 194.44534 -351.840492) (xy 194.409622 -351.881714) (xy 194.368402 -351.917433) (xy 194.322518 -351.946922)
			(xy 194.272904 -351.969581) (xy 194.220571 -351.984949) (xy 194.166584 -351.992713) (xy 194.139312 -351.9932)
			(xy 193.275712 -351.9932) (xy 193.248443 -351.992661) (xy 193.19446 -351.984901) (xy 193.142131 -351.969538)
			(xy 193.092522 -351.946883) (xy 193.046641 -351.917399) (xy 193.005424 -351.881685) (xy 192.969708 -351.840469)
			(xy 192.940223 -351.794589) (xy 192.917566 -351.74498) (xy 192.902201 -351.692651) (xy 192.894439 -351.638669)
			(xy 191.411736 -351.638669) (xy 191.411736 -351.638676) (xy 191.403972 -351.692672) (xy 191.388602 -351.745014)
			(xy 191.365939 -351.794635) (xy 191.336444 -351.840526) (xy 191.300717 -351.881751) (xy 191.259487 -351.917472)
			(xy 191.213593 -351.946962) (xy 191.163969 -351.969619) (xy 191.111625 -351.984982) (xy 191.057628 -351.99274)
			(xy 191.030352 -351.9932) (xy 190.166752 -351.9932) (xy 190.139488 -351.992634) (xy 190.085515 -351.984868)
			(xy 190.033196 -351.9695) (xy 189.983597 -351.946843) (xy 189.937726 -351.917359) (xy 189.896519 -351.881647)
			(xy 189.860812 -351.840435) (xy 189.831334 -351.794561) (xy 189.808683 -351.744959) (xy 189.793322 -351.692639)
			(xy 189.785562 -351.638664) (xy 188.302736 -351.638664) (xy 188.302736 -351.638674) (xy 188.294973 -351.692667)
			(xy 188.279605 -351.745006) (xy 188.256945 -351.794624) (xy 188.227453 -351.840513) (xy 188.191732 -351.881737)
			(xy 188.150506 -351.917458) (xy 188.104617 -351.946949) (xy 188.054998 -351.969608) (xy 188.002659 -351.984975)
			(xy 187.948666 -351.992737) (xy 187.921392 -351.9932) (xy 187.057792 -351.9932) (xy 187.030526 -351.992637)
			(xy 186.976548 -351.984875) (xy 186.924225 -351.969511) (xy 186.874621 -351.946856) (xy 186.828745 -351.917373)
			(xy 186.787533 -351.881662) (xy 186.751822 -351.840448) (xy 186.72234 -351.794572) (xy 186.699686 -351.744968)
			(xy 186.684323 -351.692644) (xy 186.676562 -351.638666) (xy 185.193714 -351.638666) (xy 185.193714 -351.638671)
			(xy 185.185952 -351.692657) (xy 185.170587 -351.744989) (xy 185.147931 -351.794602) (xy 185.118445 -351.840486)
			(xy 185.082729 -351.881707) (xy 185.041512 -351.917426) (xy 184.99563 -351.946915) (xy 184.946019 -351.969576)
			(xy 184.893688 -351.984945) (xy 184.839703 -351.992711) (xy 184.812432 -351.9932) (xy 183.948832 -351.9932)
			(xy 183.921562 -351.992663) (xy 183.867577 -351.984905) (xy 183.815246 -351.969543) (xy 183.765634 -351.94689)
			(xy 183.719751 -351.917406) (xy 183.678531 -351.881692) (xy 183.642813 -351.840475) (xy 183.613326 -351.794594)
			(xy 183.590668 -351.744984) (xy 183.575302 -351.692654) (xy 183.567539 -351.63867) (xy 182.084836 -351.63867)
			(xy 182.084836 -351.638675) (xy 182.077073 -351.69267) (xy 182.061703 -351.74501) (xy 182.039042 -351.79463)
			(xy 182.009548 -351.840519) (xy 181.973824 -351.881744) (xy 181.932597 -351.917465) (xy 181.886705 -351.946955)
			(xy 181.837084 -351.969613) (xy 181.784742 -351.984979) (xy 181.730747 -351.992738) (xy 181.703472 -351.9932)
			(xy 180.839872 -351.9932) (xy 180.812607 -351.992636) (xy 180.758631 -351.984872) (xy 180.70631 -351.969505)
			(xy 180.656709 -351.94685) (xy 180.610836 -351.917366) (xy 180.569626 -351.881654) (xy 180.533917 -351.840442)
			(xy 180.504437 -351.794567) (xy 180.481785 -351.744963) (xy 180.466422 -351.692641) (xy 180.458662 -351.638665)
			(xy 178.975814 -351.638665) (xy 178.975814 -351.638672) (xy 178.968051 -351.692659) (xy 178.952685 -351.744993)
			(xy 178.930028 -351.794608) (xy 178.90054 -351.840492) (xy 178.864822 -351.881714) (xy 178.823602 -351.917433)
			(xy 178.777718 -351.946922) (xy 178.728104 -351.969581) (xy 178.675771 -351.984949) (xy 178.621784 -351.992713)
			(xy 178.594512 -351.9932) (xy 177.730912 -351.9932) (xy 177.703643 -351.992661) (xy 177.64966 -351.984901)
			(xy 177.597331 -351.969538) (xy 177.547722 -351.946883) (xy 177.501841 -351.917399) (xy 177.460624 -351.881685)
			(xy 177.424908 -351.840469) (xy 177.395423 -351.794589) (xy 177.372766 -351.74498) (xy 177.357401 -351.692651)
			(xy 177.349639 -351.638669) (xy 175.866936 -351.638669) (xy 175.866936 -351.638676) (xy 175.859172 -351.692672)
			(xy 175.843802 -351.745014) (xy 175.821139 -351.794635) (xy 175.791644 -351.840526) (xy 175.755917 -351.881751)
			(xy 175.714687 -351.917472) (xy 175.668793 -351.946962) (xy 175.619169 -351.969619) (xy 175.566825 -351.984982)
			(xy 175.512828 -351.99274) (xy 175.485552 -351.9932) (xy 174.621952 -351.9932) (xy 174.594688 -351.992634)
			(xy 174.540715 -351.984868) (xy 174.488396 -351.9695) (xy 174.438797 -351.946843) (xy 174.392926 -351.917359)
			(xy 174.351719 -351.881647) (xy 174.316012 -351.840435) (xy 174.286534 -351.794561) (xy 174.263883 -351.744959)
			(xy 174.248522 -351.692639) (xy 174.240762 -351.638664) (xy 172.757936 -351.638664) (xy 172.757936 -351.638674)
			(xy 172.750173 -351.692667) (xy 172.734805 -351.745006) (xy 172.712145 -351.794624) (xy 172.682653 -351.840513)
			(xy 172.646932 -351.881737) (xy 172.605706 -351.917458) (xy 172.559817 -351.946949) (xy 172.510198 -351.969608)
			(xy 172.457859 -351.984975) (xy 172.403866 -351.992737) (xy 172.376592 -351.9932) (xy 171.512992 -351.9932)
			(xy 171.485726 -351.992637) (xy 171.431748 -351.984875) (xy 171.379425 -351.969511) (xy 171.329821 -351.946856)
			(xy 171.283945 -351.917373) (xy 171.242733 -351.881662) (xy 171.207022 -351.840448) (xy 171.17754 -351.794572)
			(xy 171.154886 -351.744968) (xy 171.139523 -351.692644) (xy 171.131762 -351.638666) (xy 169.648914 -351.638666)
			(xy 169.648914 -351.638671) (xy 169.641152 -351.692657) (xy 169.625787 -351.744989) (xy 169.603131 -351.794602)
			(xy 169.573645 -351.840486) (xy 169.537929 -351.881707) (xy 169.496712 -351.917426) (xy 169.45083 -351.946915)
			(xy 169.401219 -351.969576) (xy 169.348888 -351.984945) (xy 169.294903 -351.992711) (xy 169.267632 -351.9932)
			(xy 168.404032 -351.9932) (xy 168.376762 -351.992663) (xy 168.322777 -351.984905) (xy 168.270446 -351.969543)
			(xy 168.220834 -351.94689) (xy 168.174951 -351.917406) (xy 168.133731 -351.881692) (xy 168.098013 -351.840475)
			(xy 168.068526 -351.794594) (xy 168.045868 -351.744984) (xy 168.030502 -351.692654) (xy 168.022739 -351.63867)
			(xy 166.540036 -351.63867) (xy 166.540036 -351.638675) (xy 166.532273 -351.69267) (xy 166.516903 -351.74501)
			(xy 166.494242 -351.79463) (xy 166.464748 -351.840519) (xy 166.429024 -351.881744) (xy 166.387797 -351.917465)
			(xy 166.341905 -351.946955) (xy 166.292284 -351.969613) (xy 166.239942 -351.984979) (xy 166.185947 -351.992738)
			(xy 166.158672 -351.9932) (xy 165.295072 -351.9932) (xy 165.267807 -351.992636) (xy 165.213831 -351.984872)
			(xy 165.16151 -351.969505) (xy 165.111909 -351.94685) (xy 165.066036 -351.917366) (xy 165.024826 -351.881654)
			(xy 164.989117 -351.840442) (xy 164.959637 -351.794567) (xy 164.936985 -351.744963) (xy 164.921622 -351.692641)
			(xy 164.913862 -351.638665) (xy 163.431014 -351.638665) (xy 163.431014 -351.638672) (xy 163.423251 -351.692659)
			(xy 163.407885 -351.744993) (xy 163.385228 -351.794608) (xy 163.35574 -351.840492) (xy 163.320022 -351.881714)
			(xy 163.278802 -351.917433) (xy 163.232918 -351.946922) (xy 163.183304 -351.969581) (xy 163.130971 -351.984949)
			(xy 163.076984 -351.992713) (xy 163.049712 -351.9932) (xy 162.186112 -351.9932) (xy 162.158843 -351.992661)
			(xy 162.10486 -351.984901) (xy 162.052531 -351.969538) (xy 162.002922 -351.946883) (xy 161.957041 -351.917399)
			(xy 161.915824 -351.881685) (xy 161.880108 -351.840469) (xy 161.850623 -351.794589) (xy 161.827966 -351.74498)
			(xy 161.812601 -351.692651) (xy 161.804839 -351.638669) (xy 144.196614 -351.638669) (xy 144.196614 -351.638672)
			(xy 144.188851 -351.69266) (xy 144.173485 -351.744994) (xy 144.150827 -351.794609) (xy 144.121339 -351.840494)
			(xy 144.085621 -351.881715) (xy 144.0444 -351.917434) (xy 143.998516 -351.946923) (xy 143.948902 -351.969582)
			(xy 143.896568 -351.98495) (xy 143.84258 -351.992713) (xy 143.815308 -351.9932) (xy 142.951708 -351.9932)
			(xy 142.924439 -351.992661) (xy 142.870457 -351.984901) (xy 142.818129 -351.969537) (xy 142.768519 -351.946882)
			(xy 142.722639 -351.917397) (xy 142.681422 -351.881683) (xy 142.645707 -351.840467) (xy 142.616222 -351.794588)
			(xy 142.593566 -351.744979) (xy 142.578201 -351.692651) (xy 142.570439 -351.638669) (xy 141.087614 -351.638669)
			(xy 141.087614 -351.63867) (xy 141.079852 -351.692655) (xy 141.064488 -351.744986) (xy 141.041833 -351.794597)
			(xy 141.012349 -351.840481) (xy 140.976635 -351.881701) (xy 140.935419 -351.91742) (xy 140.88954 -351.94691)
			(xy 140.839931 -351.969571) (xy 140.787602 -351.984942) (xy 140.733618 -351.99271) (xy 140.706348 -351.9932)
			(xy 139.842748 -351.9932) (xy 139.815477 -351.992664) (xy 139.761491 -351.984908) (xy 139.709158 -351.969547)
			(xy 139.659543 -351.946895) (xy 139.613658 -351.917411) (xy 139.572436 -351.881698) (xy 139.536717 -351.84048)
			(xy 139.507228 -351.794599) (xy 139.484569 -351.744987) (xy 139.469202 -351.692656) (xy 139.46144 -351.63867)
			(xy 137.978736 -351.63867) (xy 137.978736 -351.638674) (xy 137.970973 -351.692668) (xy 137.955605 -351.745006)
			(xy 137.932944 -351.794625) (xy 137.903452 -351.840514) (xy 137.86773 -351.881739) (xy 137.826504 -351.91746)
			(xy 137.780615 -351.94695) (xy 137.730995 -351.969609) (xy 137.678656 -351.984976) (xy 137.624662 -351.992737)
			(xy 137.597388 -351.9932) (xy 136.733788 -351.9932) (xy 136.706522 -351.992637) (xy 136.652545 -351.984875)
			(xy 136.600222 -351.96951) (xy 136.550618 -351.946855) (xy 136.504744 -351.917372) (xy 136.463531 -351.88166)
			(xy 136.427821 -351.840447) (xy 136.398339 -351.794571) (xy 136.375686 -351.744967) (xy 136.360323 -351.692643)
			(xy 136.352562 -351.638666) (xy 134.869714 -351.638666) (xy 134.869714 -351.638671) (xy 134.861952 -351.692657)
			(xy 134.846586 -351.74499) (xy 134.82393 -351.794603) (xy 134.794444 -351.840487) (xy 134.758728 -351.881708)
			(xy 134.71751 -351.917427) (xy 134.671628 -351.946917) (xy 134.622016 -351.969577) (xy 134.569685 -351.984946)
			(xy 134.515699 -351.992712) (xy 134.488428 -351.9932) (xy 133.624828 -351.9932) (xy 133.597558 -351.992663)
			(xy 133.543574 -351.984904) (xy 133.491243 -351.969542) (xy 133.441631 -351.946888) (xy 133.395749 -351.917404)
			(xy 133.354529 -351.881691) (xy 133.318812 -351.840474) (xy 133.289325 -351.794593) (xy 133.266668 -351.744983)
			(xy 133.251302 -351.692654) (xy 133.243539 -351.63867) (xy 131.760836 -351.63867) (xy 131.760836 -351.638675)
			(xy 131.753073 -351.69267) (xy 131.737703 -351.745011) (xy 131.715041 -351.794631) (xy 131.685547 -351.840521)
			(xy 131.649823 -351.881746) (xy 131.608595 -351.917467) (xy 131.562703 -351.946956) (xy 131.513081 -351.969614)
			(xy 131.460739 -351.984979) (xy 131.406743 -351.992739) (xy 131.379468 -351.9932) (xy 130.515868 -351.9932)
			(xy 130.488603 -351.992635) (xy 130.434628 -351.984871) (xy 130.382308 -351.969504) (xy 130.332706 -351.946849)
			(xy 130.286834 -351.917365) (xy 130.245624 -351.881653) (xy 130.209916 -351.84044) (xy 130.180436 -351.794566)
			(xy 130.157784 -351.744962) (xy 130.142422 -351.692641) (xy 130.134662 -351.638665) (xy 128.651814 -351.638665)
			(xy 128.651814 -351.638672) (xy 128.644051 -351.69266) (xy 128.628685 -351.744994) (xy 128.606027 -351.794609)
			(xy 128.576539 -351.840494) (xy 128.540821 -351.881715) (xy 128.4996 -351.917434) (xy 128.453716 -351.946923)
			(xy 128.404102 -351.969582) (xy 128.351768 -351.98495) (xy 128.29778 -351.992713) (xy 128.270508 -351.9932)
			(xy 127.406908 -351.9932) (xy 127.379639 -351.992661) (xy 127.325657 -351.984901) (xy 127.273329 -351.969537)
			(xy 127.223719 -351.946882) (xy 127.177839 -351.917397) (xy 127.136622 -351.881683) (xy 127.100907 -351.840467)
			(xy 127.071422 -351.794588) (xy 127.048766 -351.744979) (xy 127.033401 -351.692651) (xy 127.025639 -351.638669)
			(xy 125.542814 -351.638669) (xy 125.542814 -351.63867) (xy 125.535052 -351.692655) (xy 125.519688 -351.744986)
			(xy 125.497033 -351.794597) (xy 125.467549 -351.840481) (xy 125.431835 -351.881701) (xy 125.390619 -351.91742)
			(xy 125.34474 -351.94691) (xy 125.295131 -351.969571) (xy 125.242802 -351.984942) (xy 125.188818 -351.99271)
			(xy 125.161548 -351.9932) (xy 124.297948 -351.9932) (xy 124.270677 -351.992664) (xy 124.216691 -351.984908)
			(xy 124.164358 -351.969547) (xy 124.114743 -351.946895) (xy 124.068858 -351.917411) (xy 124.027636 -351.881698)
			(xy 123.991917 -351.84048) (xy 123.962428 -351.794599) (xy 123.939769 -351.744987) (xy 123.924402 -351.692656)
			(xy 123.91664 -351.63867) (xy 122.433936 -351.63867) (xy 122.433936 -351.638674) (xy 122.426173 -351.692668)
			(xy 122.410805 -351.745006) (xy 122.388144 -351.794625) (xy 122.358652 -351.840514) (xy 122.32293 -351.881739)
			(xy 122.281704 -351.91746) (xy 122.235815 -351.94695) (xy 122.186195 -351.969609) (xy 122.133856 -351.984976)
			(xy 122.079862 -351.992737) (xy 122.052588 -351.9932) (xy 121.188988 -351.9932) (xy 121.161722 -351.992637)
			(xy 121.107745 -351.984875) (xy 121.055422 -351.96951) (xy 121.005818 -351.946855) (xy 120.959944 -351.917372)
			(xy 120.918731 -351.88166) (xy 120.883021 -351.840447) (xy 120.853539 -351.794571) (xy 120.830886 -351.744967)
			(xy 120.815523 -351.692643) (xy 120.807762 -351.638666) (xy 119.324914 -351.638666) (xy 119.324914 -351.638671)
			(xy 119.317152 -351.692657) (xy 119.301786 -351.74499) (xy 119.27913 -351.794603) (xy 119.249644 -351.840487)
			(xy 119.213928 -351.881708) (xy 119.17271 -351.917427) (xy 119.126828 -351.946917) (xy 119.077216 -351.969577)
			(xy 119.024885 -351.984946) (xy 118.970899 -351.992712) (xy 118.943628 -351.9932) (xy 118.080028 -351.9932)
			(xy 118.052758 -351.992663) (xy 117.998774 -351.984904) (xy 117.946443 -351.969542) (xy 117.896831 -351.946888)
			(xy 117.850949 -351.917404) (xy 117.809729 -351.881691) (xy 117.774012 -351.840474) (xy 117.744525 -351.794593)
			(xy 117.721868 -351.744983) (xy 117.706502 -351.692654) (xy 117.698739 -351.63867) (xy 116.216036 -351.63867)
			(xy 116.216036 -351.638675) (xy 116.208273 -351.69267) (xy 116.192903 -351.745011) (xy 116.170241 -351.794631)
			(xy 116.140747 -351.840521) (xy 116.105023 -351.881746) (xy 116.063795 -351.917467) (xy 116.017903 -351.946956)
			(xy 115.968281 -351.969614) (xy 115.915939 -351.984979) (xy 115.861943 -351.992739) (xy 115.834668 -351.9932)
			(xy 114.971068 -351.9932) (xy 114.943803 -351.992635) (xy 114.889828 -351.984871) (xy 114.837508 -351.969504)
			(xy 114.787906 -351.946849) (xy 114.742034 -351.917365) (xy 114.700824 -351.881653) (xy 114.665116 -351.84044)
			(xy 114.635636 -351.794566) (xy 114.612984 -351.744962) (xy 114.597622 -351.692641) (xy 114.589862 -351.638665)
			(xy 113.107014 -351.638665) (xy 113.107014 -351.638672) (xy 113.099251 -351.69266) (xy 113.083885 -351.744994)
			(xy 113.061227 -351.794609) (xy 113.031739 -351.840494) (xy 112.996021 -351.881715) (xy 112.9548 -351.917434)
			(xy 112.908916 -351.946923) (xy 112.859302 -351.969582) (xy 112.806968 -351.98495) (xy 112.75298 -351.992713)
			(xy 112.725708 -351.9932) (xy 111.862108 -351.9932) (xy 111.834839 -351.992661) (xy 111.780857 -351.984901)
			(xy 111.728529 -351.969537) (xy 111.678919 -351.946882) (xy 111.633039 -351.917397) (xy 111.591822 -351.881683)
			(xy 111.556107 -351.840467) (xy 111.526622 -351.794588) (xy 111.503966 -351.744979) (xy 111.488601 -351.692651)
			(xy 111.480839 -351.638669) (xy 93.706714 -351.638669) (xy 93.706714 -351.63867) (xy 93.698952 -351.692655)
			(xy 93.683588 -351.744987) (xy 93.660932 -351.794599) (xy 93.631447 -351.840483) (xy 93.595733 -351.881703)
			(xy 93.554516 -351.917422) (xy 93.508636 -351.946912) (xy 93.459026 -351.969573) (xy 93.406697 -351.984943)
			(xy 93.352712 -351.992711) (xy 93.325442 -351.9932) (xy 92.461842 -351.9932) (xy 92.434572 -351.992663)
			(xy 92.380586 -351.984907) (xy 92.328253 -351.969546) (xy 92.27864 -351.946893) (xy 92.232755 -351.917409)
			(xy 92.191534 -351.881695) (xy 92.155816 -351.840478) (xy 92.126327 -351.794597) (xy 92.103669 -351.744986)
			(xy 92.088302 -351.692655) (xy 92.08054 -351.63867) (xy 90.597836 -351.63867) (xy 90.597836 -351.638675)
			(xy 90.590073 -351.692668) (xy 90.574704 -351.745008) (xy 90.552043 -351.794627) (xy 90.522551 -351.840516)
			(xy 90.486828 -351.881741) (xy 90.445602 -351.917462) (xy 90.399711 -351.946952) (xy 90.350091 -351.969611)
			(xy 90.297751 -351.984977) (xy 90.243757 -351.992738) (xy 90.216482 -351.9932) (xy 89.352882 -351.9932)
			(xy 89.325616 -351.992636) (xy 89.27164 -351.984873) (xy 89.219318 -351.969508) (xy 89.169715 -351.946853)
			(xy 89.123841 -351.91737) (xy 89.082629 -351.881658) (xy 89.04692 -351.840445) (xy 89.017438 -351.794569)
			(xy 88.994786 -351.744965) (xy 88.979423 -351.692642) (xy 88.971662 -351.638666) (xy 87.488814 -351.638666)
			(xy 87.488814 -351.638671) (xy 87.481052 -351.692658) (xy 87.465686 -351.744991) (xy 87.443029 -351.794605)
			(xy 87.413542 -351.840489) (xy 87.377826 -351.88171) (xy 87.336607 -351.917429) (xy 87.290724 -351.946919)
			(xy 87.241112 -351.969578) (xy 87.18878 -351.984947) (xy 87.134793 -351.992712) (xy 87.107522 -351.9932)
			(xy 86.243922 -351.9932) (xy 86.216653 -351.992662) (xy 86.162669 -351.984903) (xy 86.110339 -351.96954)
			(xy 86.060728 -351.946886) (xy 86.014846 -351.917402) (xy 85.973627 -351.881688) (xy 85.937911 -351.840472)
			(xy 85.908424 -351.794592) (xy 85.885767 -351.744982) (xy 85.870401 -351.692653) (xy 85.862639 -351.638669)
			(xy 84.379936 -351.638669) (xy 84.379936 -351.638675) (xy 84.372172 -351.692671) (xy 84.356803 -351.745012)
			(xy 84.33414 -351.794633) (xy 84.304646 -351.840523) (xy 84.268921 -351.881748) (xy 84.227692 -351.917469)
			(xy 84.181799 -351.946958) (xy 84.132176 -351.969616) (xy 84.079834 -351.98498) (xy 84.025837 -351.992739)
			(xy 83.998562 -351.9932) (xy 83.134962 -351.9932) (xy 83.107697 -351.992635) (xy 83.053723 -351.98487)
			(xy 83.001403 -351.969503) (xy 82.951803 -351.946847) (xy 82.905931 -351.917363) (xy 82.864722 -351.881651)
			(xy 82.829015 -351.840438) (xy 82.799535 -351.794564) (xy 82.776884 -351.744961) (xy 82.761522 -351.69264)
			(xy 82.753762 -351.638665) (xy 81.270913 -351.638665) (xy 81.270913 -351.638672) (xy 81.263151 -351.692661)
			(xy 81.247784 -351.744995) (xy 81.225126 -351.79461) (xy 81.195637 -351.840496) (xy 81.159919 -351.881717)
			(xy 81.118697 -351.917436) (xy 81.072812 -351.946925) (xy 81.023197 -351.969584) (xy 80.970863 -351.984951)
			(xy 80.916874 -351.992713) (xy 80.889602 -351.9932) (xy 80.026002 -351.9932) (xy 79.998734 -351.992661)
			(xy 79.944752 -351.9849) (xy 79.892424 -351.969535) (xy 79.842816 -351.94688) (xy 79.796936 -351.917395)
			(xy 79.75572 -351.881681) (xy 79.720006 -351.840465) (xy 79.690521 -351.794586) (xy 79.667866 -351.744978)
			(xy 79.652501 -351.69265) (xy 79.644739 -351.638668) (xy 78.161914 -351.638668) (xy 78.161914 -351.63867)
			(xy 78.154152 -351.692655) (xy 78.138788 -351.744987) (xy 78.116132 -351.794599) (xy 78.086647 -351.840483)
			(xy 78.050933 -351.881703) (xy 78.009716 -351.917422) (xy 77.963836 -351.946912) (xy 77.914226 -351.969573)
			(xy 77.861897 -351.984943) (xy 77.807912 -351.992711) (xy 77.780642 -351.9932) (xy 76.917042 -351.9932)
			(xy 76.889772 -351.992663) (xy 76.835786 -351.984907) (xy 76.783453 -351.969546) (xy 76.73384 -351.946893)
			(xy 76.687955 -351.917409) (xy 76.646734 -351.881695) (xy 76.611016 -351.840478) (xy 76.581527 -351.794597)
			(xy 76.558869 -351.744986) (xy 76.543502 -351.692655) (xy 76.53574 -351.63867) (xy 75.053036 -351.63867)
			(xy 75.053036 -351.638675) (xy 75.045273 -351.692668) (xy 75.029904 -351.745008) (xy 75.007243 -351.794627)
			(xy 74.977751 -351.840516) (xy 74.942028 -351.881741) (xy 74.900802 -351.917462) (xy 74.854911 -351.946952)
			(xy 74.805291 -351.969611) (xy 74.752951 -351.984977) (xy 74.698957 -351.992738) (xy 74.671682 -351.9932)
			(xy 73.808082 -351.9932) (xy 73.780816 -351.992636) (xy 73.72684 -351.984873) (xy 73.674518 -351.969508)
			(xy 73.624915 -351.946853) (xy 73.579041 -351.91737) (xy 73.537829 -351.881658) (xy 73.50212 -351.840445)
			(xy 73.472638 -351.794569) (xy 73.449986 -351.744965) (xy 73.434623 -351.692642) (xy 73.426862 -351.638666)
			(xy 71.944014 -351.638666) (xy 71.944014 -351.638671) (xy 71.936252 -351.692658) (xy 71.920886 -351.744991)
			(xy 71.898229 -351.794605) (xy 71.868742 -351.840489) (xy 71.833026 -351.88171) (xy 71.791807 -351.917429)
			(xy 71.745924 -351.946919) (xy 71.696312 -351.969578) (xy 71.64398 -351.984947) (xy 71.589993 -351.992712)
			(xy 71.562722 -351.9932) (xy 70.699122 -351.9932) (xy 70.671853 -351.992662) (xy 70.617869 -351.984903)
			(xy 70.565539 -351.96954) (xy 70.515928 -351.946886) (xy 70.470046 -351.917402) (xy 70.428827 -351.881688)
			(xy 70.393111 -351.840472) (xy 70.363624 -351.794592) (xy 70.340967 -351.744982) (xy 70.325601 -351.692653)
			(xy 70.317839 -351.638669) (xy 68.835136 -351.638669) (xy 68.835136 -351.638675) (xy 68.827372 -351.692671)
			(xy 68.812003 -351.745012) (xy 68.78934 -351.794633) (xy 68.759846 -351.840523) (xy 68.724121 -351.881748)
			(xy 68.682892 -351.917469) (xy 68.636999 -351.946958) (xy 68.587376 -351.969616) (xy 68.535034 -351.98498)
			(xy 68.481037 -351.992739) (xy 68.453762 -351.9932) (xy 67.590162 -351.9932) (xy 67.562897 -351.992635)
			(xy 67.508923 -351.98487) (xy 67.456603 -351.969503) (xy 67.407003 -351.946847) (xy 67.361131 -351.917363)
			(xy 67.319922 -351.881651) (xy 67.284215 -351.840438) (xy 67.254735 -351.794564) (xy 67.232084 -351.744961)
			(xy 67.216722 -351.69264) (xy 67.208962 -351.638665) (xy 65.726113 -351.638665) (xy 65.726113 -351.638672)
			(xy 65.718351 -351.692661) (xy 65.702984 -351.744995) (xy 65.680326 -351.79461) (xy 65.650837 -351.840496)
			(xy 65.615119 -351.881717) (xy 65.573897 -351.917436) (xy 65.528012 -351.946925) (xy 65.478397 -351.969584)
			(xy 65.426063 -351.984951) (xy 65.372074 -351.992713) (xy 65.344802 -351.9932) (xy 64.481202 -351.9932)
			(xy 64.453934 -351.992661) (xy 64.399952 -351.9849) (xy 64.347624 -351.969535) (xy 64.298016 -351.94688)
			(xy 64.252136 -351.917395) (xy 64.21092 -351.881681) (xy 64.175206 -351.840465) (xy 64.145721 -351.794586)
			(xy 64.123066 -351.744978) (xy 64.107701 -351.69265) (xy 64.099939 -351.638668) (xy 62.617114 -351.638668)
			(xy 62.617114 -351.63867) (xy 62.609352 -351.692655) (xy 62.593988 -351.744987) (xy 62.571332 -351.794599)
			(xy 62.541847 -351.840483) (xy 62.506133 -351.881703) (xy 62.464916 -351.917422) (xy 62.419036 -351.946912)
			(xy 62.369426 -351.969573) (xy 62.317097 -351.984943) (xy 62.263112 -351.992711) (xy 62.235842 -351.9932)
			(xy 61.372242 -351.9932) (xy 61.344972 -351.992663) (xy 61.290986 -351.984907) (xy 61.238653 -351.969546)
			(xy 61.18904 -351.946893) (xy 61.143155 -351.917409) (xy 61.101934 -351.881695) (xy 61.066216 -351.840478)
			(xy 61.036727 -351.794597) (xy 61.014069 -351.744986) (xy 60.998702 -351.692655) (xy 60.99094 -351.63867)
			(xy 51.666914 -351.63867) (xy 51.659152 -351.692655) (xy 51.643788 -351.744986) (xy 51.621133 -351.794597)
			(xy 51.591649 -351.840481) (xy 51.555935 -351.881701) (xy 51.514719 -351.91742) (xy 51.46884 -351.94691)
			(xy 51.419231 -351.969571) (xy 51.366902 -351.984942) (xy 51.312918 -351.99271) (xy 51.285648 -351.9932)
			(xy 50.422048 -351.9932) (xy 50.394777 -351.992664) (xy 50.340791 -351.984908) (xy 50.288458 -351.969547)
			(xy 50.238843 -351.946895) (xy 50.192958 -351.917411) (xy 50.151736 -351.881698) (xy 50.116017 -351.84048)
			(xy 50.086528 -351.794599) (xy 50.063869 -351.744987) (xy 50.048502 -351.692656) (xy 50.04074 -351.63867)
			(xy 48.558036 -351.63867) (xy 48.558036 -351.638674) (xy 48.550273 -351.692668) (xy 48.534905 -351.745006)
			(xy 48.512244 -351.794625) (xy 48.482752 -351.840514) (xy 48.44703 -351.881739) (xy 48.405804 -351.91746)
			(xy 48.359915 -351.94695) (xy 48.310295 -351.969609) (xy 48.257956 -351.984976) (xy 48.203962 -351.992737)
			(xy 48.176688 -351.9932) (xy 47.313088 -351.9932) (xy 47.285822 -351.992637) (xy 47.231845 -351.984875)
			(xy 47.179522 -351.96951) (xy 47.129918 -351.946855) (xy 47.084044 -351.917372) (xy 47.042831 -351.88166)
			(xy 47.007121 -351.840447) (xy 46.977639 -351.794571) (xy 46.954986 -351.744967) (xy 46.939623 -351.692643)
			(xy 46.931862 -351.638666) (xy 45.449014 -351.638666) (xy 45.449014 -351.638671) (xy 45.441252 -351.692657)
			(xy 45.425886 -351.74499) (xy 45.40323 -351.794603) (xy 45.373744 -351.840487) (xy 45.338028 -351.881708)
			(xy 45.29681 -351.917427) (xy 45.250928 -351.946917) (xy 45.201316 -351.969577) (xy 45.148985 -351.984946)
			(xy 45.094999 -351.992712) (xy 45.067728 -351.9932) (xy 44.204128 -351.9932) (xy 44.176858 -351.992663)
			(xy 44.122874 -351.984904) (xy 44.070543 -351.969542) (xy 44.020931 -351.946888) (xy 43.975049 -351.917404)
			(xy 43.933829 -351.881691) (xy 43.898112 -351.840474) (xy 43.868625 -351.794593) (xy 43.845968 -351.744983)
			(xy 43.830602 -351.692654) (xy 43.822839 -351.63867) (xy 42.340136 -351.63867) (xy 42.340136 -351.638675)
			(xy 42.332373 -351.69267) (xy 42.317003 -351.745011) (xy 42.294341 -351.794631) (xy 42.264847 -351.840521)
			(xy 42.229123 -351.881746) (xy 42.187895 -351.917467) (xy 42.142003 -351.946956) (xy 42.092381 -351.969614)
			(xy 42.040039 -351.984979) (xy 41.986043 -351.992739) (xy 41.958768 -351.9932) (xy 41.095168 -351.9932)
			(xy 41.067903 -351.992635) (xy 41.013928 -351.984871) (xy 40.961608 -351.969504) (xy 40.912006 -351.946849)
			(xy 40.866134 -351.917365) (xy 40.824924 -351.881653) (xy 40.789216 -351.84044) (xy 40.759736 -351.794566)
			(xy 40.737084 -351.744962) (xy 40.721722 -351.692641) (xy 40.713962 -351.638665) (xy 39.231114 -351.638665)
			(xy 39.231114 -351.638672) (xy 39.223351 -351.69266) (xy 39.207985 -351.744994) (xy 39.185327 -351.794609)
			(xy 39.155839 -351.840494) (xy 39.120121 -351.881715) (xy 39.0789 -351.917434) (xy 39.033016 -351.946923)
			(xy 38.983402 -351.969582) (xy 38.931068 -351.98495) (xy 38.87708 -351.992713) (xy 38.849808 -351.9932)
			(xy 37.986208 -351.9932) (xy 37.958939 -351.992661) (xy 37.904957 -351.984901) (xy 37.852629 -351.969537)
			(xy 37.803019 -351.946882) (xy 37.757139 -351.917397) (xy 37.715922 -351.881683) (xy 37.680207 -351.840467)
			(xy 37.650722 -351.794588) (xy 37.628066 -351.744979) (xy 37.612701 -351.692651) (xy 37.604939 -351.638669)
			(xy 36.122114 -351.638669) (xy 36.122114 -351.63867) (xy 36.114352 -351.692655) (xy 36.098988 -351.744986)
			(xy 36.076333 -351.794597) (xy 36.046849 -351.840481) (xy 36.011135 -351.881701) (xy 35.969919 -351.91742)
			(xy 35.92404 -351.94691) (xy 35.874431 -351.969571) (xy 35.822102 -351.984942) (xy 35.768118 -351.99271)
			(xy 35.740848 -351.9932) (xy 34.877248 -351.9932) (xy 34.849977 -351.992664) (xy 34.795991 -351.984908)
			(xy 34.743658 -351.969547) (xy 34.694043 -351.946895) (xy 34.648158 -351.917411) (xy 34.606936 -351.881698)
			(xy 34.571217 -351.84048) (xy 34.541728 -351.794599) (xy 34.519069 -351.744987) (xy 34.503702 -351.692656)
			(xy 34.49594 -351.63867) (xy 33.013236 -351.63867) (xy 33.013236 -351.638674) (xy 33.005473 -351.692668)
			(xy 32.990105 -351.745006) (xy 32.967444 -351.794625) (xy 32.937952 -351.840514) (xy 32.90223 -351.881739)
			(xy 32.861004 -351.91746) (xy 32.815115 -351.94695) (xy 32.765495 -351.969609) (xy 32.713156 -351.984976)
			(xy 32.659162 -351.992737) (xy 32.631888 -351.9932) (xy 31.768288 -351.9932) (xy 31.741022 -351.992637)
			(xy 31.687045 -351.984875) (xy 31.634722 -351.96951) (xy 31.585118 -351.946855) (xy 31.539244 -351.917372)
			(xy 31.498031 -351.88166) (xy 31.462321 -351.840447) (xy 31.432839 -351.794571) (xy 31.410186 -351.744967)
			(xy 31.394823 -351.692643) (xy 31.387062 -351.638666) (xy 29.904214 -351.638666) (xy 29.904214 -351.638671)
			(xy 29.896452 -351.692657) (xy 29.881086 -351.74499) (xy 29.85843 -351.794603) (xy 29.828944 -351.840487)
			(xy 29.793228 -351.881708) (xy 29.75201 -351.917427) (xy 29.706128 -351.946917) (xy 29.656516 -351.969577)
			(xy 29.604185 -351.984946) (xy 29.550199 -351.992712) (xy 29.522928 -351.9932) (xy 28.659328 -351.9932)
			(xy 28.632058 -351.992663) (xy 28.578074 -351.984904) (xy 28.525743 -351.969542) (xy 28.476131 -351.946888)
			(xy 28.430249 -351.917404) (xy 28.389029 -351.881691) (xy 28.353312 -351.840474) (xy 28.323825 -351.794593)
			(xy 28.301168 -351.744983) (xy 28.285802 -351.692654) (xy 28.278039 -351.63867) (xy 26.795336 -351.63867)
			(xy 26.795336 -351.638675) (xy 26.787573 -351.69267) (xy 26.772203 -351.745011) (xy 26.749541 -351.794631)
			(xy 26.720047 -351.840521) (xy 26.684323 -351.881746) (xy 26.643095 -351.917467) (xy 26.597203 -351.946956)
			(xy 26.547581 -351.969614) (xy 26.495239 -351.984979) (xy 26.441243 -351.992739) (xy 26.413968 -351.9932)
			(xy 25.550368 -351.9932) (xy 25.523103 -351.992635) (xy 25.469128 -351.984871) (xy 25.416808 -351.969504)
			(xy 25.367206 -351.946849) (xy 25.321334 -351.917365) (xy 25.280124 -351.881653) (xy 25.244416 -351.84044)
			(xy 25.214936 -351.794566) (xy 25.192284 -351.744962) (xy 25.176922 -351.692641) (xy 25.169162 -351.638665)
			(xy 23.686314 -351.638665) (xy 23.686314 -351.638672) (xy 23.678551 -351.69266) (xy 23.663185 -351.744994)
			(xy 23.640527 -351.794609) (xy 23.611039 -351.840494) (xy 23.575321 -351.881715) (xy 23.5341 -351.917434)
			(xy 23.488216 -351.946923) (xy 23.438602 -351.969582) (xy 23.386268 -351.98495) (xy 23.33228 -351.992713)
			(xy 23.305008 -351.9932) (xy 22.441408 -351.9932) (xy 22.414139 -351.992661) (xy 22.360157 -351.984901)
			(xy 22.307829 -351.969537) (xy 22.258219 -351.946882) (xy 22.212339 -351.917397) (xy 22.171122 -351.881683)
			(xy 22.135407 -351.840467) (xy 22.105922 -351.794588) (xy 22.083266 -351.744979) (xy 22.067901 -351.692651)
			(xy 22.060139 -351.638669) (xy 20.577347 -351.638669) (xy 20.577347 -351.638711) (xy 20.569584 -351.692698)
			(xy 20.554218 -351.74503) (xy 20.53156 -351.794643) (xy 20.502073 -351.840527) (xy 20.466355 -351.881747)
			(xy 20.425135 -351.917464) (xy 20.379252 -351.946951) (xy 20.329638 -351.969609) (xy 20.277306 -351.984975)
			(xy 20.223319 -351.992737) (xy 20.196048 -351.9932) (xy 19.332448 -351.9932) (xy 19.305179 -351.992717)
			(xy 19.251195 -351.984955) (xy 19.198865 -351.96959) (xy 19.149255 -351.946933) (xy 19.103374 -351.917447)
			(xy 19.062157 -351.881732) (xy 19.026441 -351.840514) (xy 18.996956 -351.794633) (xy 18.974299 -351.745023)
			(xy 18.958934 -351.692693) (xy 18.951172 -351.638709) (xy 0.509016 -351.638709) (xy 0.509016 -354.759373)
			(xy 22.060084 -354.759373) (xy 22.060084 -354.704827) (xy 22.067846 -354.650837) (xy 22.083214 -354.598501)
			(xy 22.105873 -354.548885) (xy 22.135363 -354.502999) (xy 22.171083 -354.461777) (xy 22.212306 -354.426058)
			(xy 22.258192 -354.396569) (xy 22.307809 -354.373911) (xy 22.360145 -354.358545) (xy 22.414135 -354.350783)
			(xy 22.441408 -354.35032) (xy 23.305008 -354.35032) (xy 23.332276 -354.350843) (xy 23.386256 -354.358605)
			(xy 23.438582 -354.37397) (xy 23.488189 -354.396626) (xy 23.534067 -354.426111) (xy 23.575281 -354.461824)
			(xy 23.610994 -354.50304) (xy 23.640478 -354.548918) (xy 23.663132 -354.598525) (xy 23.678497 -354.650852)
			(xy 23.686258 -354.704832) (xy 23.686258 -354.759368) (xy 23.686258 -354.759369) (xy 25.169106 -354.759369)
			(xy 25.169106 -354.704831) (xy 25.176868 -354.650847) (xy 25.192232 -354.598518) (xy 25.214887 -354.548908)
			(xy 25.244371 -354.503026) (xy 25.280085 -354.461807) (xy 25.3213 -354.42609) (xy 25.36718 -354.396602)
			(xy 25.416788 -354.373943) (xy 25.469116 -354.358574) (xy 25.523099 -354.350809) (xy 25.550368 -354.35032)
			(xy 26.413968 -354.35032) (xy 26.441239 -354.350817) (xy 26.495227 -354.358575) (xy 26.547561 -354.373938)
			(xy 26.597176 -354.396593) (xy 26.643061 -354.426078) (xy 26.684283 -354.461794) (xy 26.720003 -354.503013)
			(xy 26.749492 -354.548896) (xy 26.772151 -354.598509) (xy 26.787518 -354.650842) (xy 26.79528 -354.704829)
			(xy 26.79528 -354.759371) (xy 26.79528 -354.759374) (xy 28.277984 -354.759374) (xy 28.277984 -354.704826)
			(xy 28.285747 -354.650835) (xy 28.301115 -354.598497) (xy 28.323776 -354.54888) (xy 28.353268 -354.502993)
			(xy 28.38899 -354.46177) (xy 28.430215 -354.426051) (xy 28.476104 -354.396562) (xy 28.525723 -354.373905)
			(xy 28.578062 -354.358541) (xy 28.632054 -354.350782) (xy 28.659328 -354.35032) (xy 29.522928 -354.35032)
			(xy 29.550195 -354.350844) (xy 29.604173 -354.358609) (xy 29.656497 -354.373976) (xy 29.706101 -354.396633)
			(xy 29.751976 -354.426118) (xy 29.793188 -354.461831) (xy 29.828899 -354.503046) (xy 29.858381 -354.548924)
			(xy 29.881034 -354.59853) (xy 29.896397 -354.650855) (xy 29.904158 -354.704833) (xy 29.904158 -354.759367)
			(xy 29.904158 -354.75937) (xy 31.387006 -354.75937) (xy 31.387006 -354.70483) (xy 31.394768 -354.650845)
			(xy 31.410134 -354.598514) (xy 31.43279 -354.548902) (xy 31.462276 -354.50302) (xy 31.497992 -354.4618)
			(xy 31.53921 -354.426083) (xy 31.585091 -354.396596) (xy 31.634703 -354.373938) (xy 31.687033 -354.358571)
			(xy 31.741018 -354.350807) (xy 31.768288 -354.35032) (xy 32.631888 -354.35032) (xy 32.659158 -354.350819)
			(xy 32.713144 -354.358579) (xy 32.765476 -354.373944) (xy 32.815088 -354.396599) (xy 32.860971 -354.426085)
			(xy 32.902191 -354.461801) (xy 32.937908 -354.503019) (xy 32.967395 -354.548902) (xy 32.990052 -354.598513)
			(xy 33.005418 -354.650844) (xy 33.013181 -354.70483) (xy 33.013181 -354.75937) (xy 33.01318 -354.759374)
			(xy 34.495884 -354.759374) (xy 34.495884 -354.704826) (xy 34.503647 -354.650832) (xy 34.519017 -354.598493)
			(xy 34.541679 -354.548874) (xy 34.571172 -354.502986) (xy 34.606897 -354.461763) (xy 34.648125 -354.426044)
			(xy 34.694016 -354.396556) (xy 34.743638 -354.3739) (xy 34.795979 -354.358537) (xy 34.849973 -354.35078)
			(xy 34.877248 -354.35032) (xy 35.740848 -354.35032) (xy 35.768114 -354.350846) (xy 35.82209 -354.358613)
			(xy 35.874411 -354.373981) (xy 35.924013 -354.396639) (xy 35.969886 -354.426125) (xy 36.011095 -354.461839)
			(xy 36.046804 -354.503053) (xy 36.076284 -354.548929) (xy 36.098936 -354.598534) (xy 36.114298 -354.650857)
			(xy 36.122058 -354.704834) (xy 36.122058 -354.759366) (xy 36.122057 -354.759373) (xy 37.604884 -354.759373)
			(xy 37.604884 -354.704827) (xy 37.612646 -354.650837) (xy 37.628014 -354.598501) (xy 37.650673 -354.548885)
			(xy 37.680163 -354.502999) (xy 37.715883 -354.461777) (xy 37.757106 -354.426058) (xy 37.802992 -354.396569)
			(xy 37.852609 -354.373911) (xy 37.904945 -354.358545) (xy 37.958935 -354.350783) (xy 37.986208 -354.35032)
			(xy 38.849808 -354.35032) (xy 38.877076 -354.350843) (xy 38.931056 -354.358605) (xy 38.983382 -354.37397)
			(xy 39.032989 -354.396626) (xy 39.078867 -354.426111) (xy 39.120081 -354.461824) (xy 39.155794 -354.50304)
			(xy 39.185278 -354.548918) (xy 39.207932 -354.598525) (xy 39.223297 -354.650852) (xy 39.231058 -354.704832)
			(xy 39.231058 -354.759368) (xy 39.231058 -354.759369) (xy 40.713906 -354.759369) (xy 40.713906 -354.704831)
			(xy 40.721668 -354.650847) (xy 40.737032 -354.598518) (xy 40.759687 -354.548908) (xy 40.789171 -354.503026)
			(xy 40.824885 -354.461807) (xy 40.8661 -354.42609) (xy 40.91198 -354.396602) (xy 40.961588 -354.373943)
			(xy 41.013916 -354.358574) (xy 41.067899 -354.350809) (xy 41.095168 -354.35032) (xy 41.958768 -354.35032)
			(xy 41.986039 -354.350817) (xy 42.040027 -354.358575) (xy 42.092361 -354.373938) (xy 42.141976 -354.396593)
			(xy 42.187861 -354.426078) (xy 42.229083 -354.461794) (xy 42.264803 -354.503013) (xy 42.294292 -354.548896)
			(xy 42.316951 -354.598509) (xy 42.332318 -354.650842) (xy 42.34008 -354.704829) (xy 42.34008 -354.759371)
			(xy 42.34008 -354.759374) (xy 43.822784 -354.759374) (xy 43.822784 -354.704826) (xy 43.830547 -354.650835)
			(xy 43.845915 -354.598497) (xy 43.868576 -354.54888) (xy 43.898068 -354.502993) (xy 43.93379 -354.46177)
			(xy 43.975015 -354.426051) (xy 44.020904 -354.396562) (xy 44.070523 -354.373905) (xy 44.122862 -354.358541)
			(xy 44.176854 -354.350782) (xy 44.204128 -354.35032) (xy 45.067728 -354.35032) (xy 45.094995 -354.350844)
			(xy 45.148973 -354.358609) (xy 45.201297 -354.373976) (xy 45.250901 -354.396633) (xy 45.296776 -354.426118)
			(xy 45.337988 -354.461831) (xy 45.373699 -354.503046) (xy 45.403181 -354.548924) (xy 45.425834 -354.59853)
			(xy 45.441197 -354.650855) (xy 45.448958 -354.704833) (xy 45.448958 -354.759367) (xy 45.448958 -354.75937)
			(xy 46.931806 -354.75937) (xy 46.931806 -354.70483) (xy 46.939568 -354.650845) (xy 46.954934 -354.598514)
			(xy 46.97759 -354.548902) (xy 47.007076 -354.50302) (xy 47.042792 -354.4618) (xy 47.08401 -354.426083)
			(xy 47.129891 -354.396596) (xy 47.179503 -354.373938) (xy 47.231833 -354.358571) (xy 47.285818 -354.350807)
			(xy 47.313088 -354.35032) (xy 48.176688 -354.35032) (xy 48.203958 -354.350819) (xy 48.257944 -354.358579)
			(xy 48.310276 -354.373944) (xy 48.359888 -354.396599) (xy 48.405771 -354.426085) (xy 48.446991 -354.461801)
			(xy 48.482708 -354.503019) (xy 48.512195 -354.548902) (xy 48.534852 -354.598513) (xy 48.550218 -354.650844)
			(xy 48.557981 -354.70483) (xy 48.557981 -354.75937) (xy 48.55798 -354.759374) (xy 50.040684 -354.759374)
			(xy 50.040684 -354.704826) (xy 50.048447 -354.650832) (xy 50.063817 -354.598493) (xy 50.086479 -354.548874)
			(xy 50.115972 -354.502986) (xy 50.151697 -354.461763) (xy 50.192925 -354.426044) (xy 50.238816 -354.396556)
			(xy 50.288438 -354.3739) (xy 50.340779 -354.358537) (xy 50.394773 -354.35078) (xy 50.422048 -354.35032)
			(xy 51.285648 -354.35032) (xy 51.312914 -354.350846) (xy 51.36689 -354.358613) (xy 51.419211 -354.373981)
			(xy 51.468813 -354.396639) (xy 51.514686 -354.426125) (xy 51.555895 -354.461839) (xy 51.591604 -354.503053)
			(xy 51.621084 -354.548929) (xy 51.643736 -354.598534) (xy 51.659098 -354.650857) (xy 51.666858 -354.704834)
			(xy 51.666858 -354.759366) (xy 51.666857 -354.759372) (xy 64.099884 -354.759372) (xy 64.099884 -354.704828)
			(xy 64.107646 -354.650838) (xy 64.123013 -354.598503) (xy 64.145672 -354.548887) (xy 64.175161 -354.503001)
			(xy 64.210881 -354.461779) (xy 64.252103 -354.42606) (xy 64.297989 -354.396571) (xy 64.347605 -354.373912)
			(xy 64.39994 -354.358546) (xy 64.45393 -354.350783) (xy 64.481202 -354.35032) (xy 65.344802 -354.35032)
			(xy 65.37207 -354.350843) (xy 65.426051 -354.358604) (xy 65.478378 -354.373969) (xy 65.527985 -354.396624)
			(xy 65.573864 -354.426109) (xy 65.615079 -354.461822) (xy 65.650793 -354.503038) (xy 65.680277 -354.548917)
			(xy 65.702932 -354.598524) (xy 65.718296 -354.650851) (xy 65.726058 -354.704832) (xy 65.726058 -354.759368)
			(xy 65.726058 -354.759369) (xy 67.208906 -354.759369) (xy 67.208906 -354.704831) (xy 67.216667 -354.650848)
			(xy 67.232032 -354.598519) (xy 67.254686 -354.548909) (xy 67.28417 -354.503028) (xy 67.319883 -354.46181)
			(xy 67.361098 -354.426093) (xy 67.406976 -354.396604) (xy 67.456584 -354.373945) (xy 67.508911 -354.358575)
			(xy 67.562893 -354.350809) (xy 67.590162 -354.35032) (xy 68.453762 -354.35032) (xy 68.481033 -354.350817)
			(xy 68.535022 -354.358574) (xy 68.587357 -354.373936) (xy 68.636972 -354.396591) (xy 68.682859 -354.426076)
			(xy 68.724081 -354.461792) (xy 68.759801 -354.503011) (xy 68.789291 -354.548894) (xy 68.81195 -354.598508)
			(xy 68.827318 -354.650841) (xy 68.83508 -354.704829) (xy 68.83508 -354.759371) (xy 68.83508 -354.759373)
			(xy 70.317784 -354.759373) (xy 70.317784 -354.704827) (xy 70.325547 -354.650835) (xy 70.340915 -354.598498)
			(xy 70.363575 -354.548882) (xy 70.393066 -354.502995) (xy 70.428788 -354.461772) (xy 70.470012 -354.426053)
			(xy 70.515901 -354.396564) (xy 70.565519 -354.373907) (xy 70.617857 -354.358542) (xy 70.671849 -354.350782)
			(xy 70.699122 -354.35032) (xy 71.562722 -354.35032) (xy 71.589989 -354.350844) (xy 71.643968 -354.358608)
			(xy 71.696292 -354.373974) (xy 71.745897 -354.396631) (xy 71.791773 -354.426116) (xy 71.832986 -354.461829)
			(xy 71.868697 -354.503044) (xy 71.89818 -354.548922) (xy 71.920833 -354.598528) (xy 71.936197 -354.650854)
			(xy 71.943958 -354.704833) (xy 71.943958 -354.759367) (xy 71.943958 -354.75937) (xy 73.426806 -354.75937)
			(xy 73.426806 -354.70483) (xy 73.434568 -354.650846) (xy 73.449933 -354.598515) (xy 73.472589 -354.548904)
			(xy 73.502075 -354.503022) (xy 73.53779 -354.461802) (xy 73.579007 -354.426085) (xy 73.624888 -354.396598)
			(xy 73.674498 -354.373939) (xy 73.726828 -354.358572) (xy 73.780812 -354.350808) (xy 73.808082 -354.35032)
			(xy 74.671682 -354.35032) (xy 74.698953 -354.350818) (xy 74.752939 -354.358578) (xy 74.805271 -354.373942)
			(xy 74.854884 -354.396597) (xy 74.900768 -354.426083) (xy 74.941988 -354.461799) (xy 74.977706 -354.503018)
			(xy 75.007194 -354.5489) (xy 75.029852 -354.598512) (xy 75.045218 -354.650844) (xy 75.052981 -354.704829)
			(xy 75.052981 -354.759371) (xy 75.052981 -354.759374) (xy 76.535684 -354.759374) (xy 76.535684 -354.704826)
			(xy 76.543447 -354.650833) (xy 76.558816 -354.598494) (xy 76.581478 -354.548876) (xy 76.610971 -354.502988)
			(xy 76.646695 -354.461765) (xy 76.687922 -354.426046) (xy 76.733813 -354.396558) (xy 76.783434 -354.373902)
			(xy 76.835774 -354.358538) (xy 76.889768 -354.350781) (xy 76.917042 -354.35032) (xy 77.780642 -354.35032)
			(xy 77.807908 -354.350845) (xy 77.861885 -354.358611) (xy 77.914207 -354.37398) (xy 77.963809 -354.396637)
			(xy 78.009683 -354.426123) (xy 78.050893 -354.461836) (xy 78.086602 -354.503051) (xy 78.116083 -354.548928)
			(xy 78.138735 -354.598533) (xy 78.154098 -354.650856) (xy 78.161858 -354.704834) (xy 78.161858 -354.759366)
			(xy 78.161857 -354.759372) (xy 79.644684 -354.759372) (xy 79.644684 -354.704828) (xy 79.652446 -354.650838)
			(xy 79.667813 -354.598503) (xy 79.690472 -354.548887) (xy 79.719961 -354.503001) (xy 79.755681 -354.461779)
			(xy 79.796903 -354.42606) (xy 79.842789 -354.396571) (xy 79.892405 -354.373912) (xy 79.94474 -354.358546)
			(xy 79.99873 -354.350783) (xy 80.026002 -354.35032) (xy 80.889602 -354.35032) (xy 80.91687 -354.350843)
			(xy 80.970851 -354.358604) (xy 81.023178 -354.373969) (xy 81.072785 -354.396624) (xy 81.118664 -354.426109)
			(xy 81.159879 -354.461822) (xy 81.195593 -354.503038) (xy 81.225077 -354.548917) (xy 81.247732 -354.598524)
			(xy 81.263096 -354.650851) (xy 81.270858 -354.704832) (xy 81.270858 -354.759368) (xy 81.270858 -354.759369)
			(xy 82.753706 -354.759369) (xy 82.753706 -354.704831) (xy 82.761467 -354.650848) (xy 82.776832 -354.598519)
			(xy 82.799486 -354.548909) (xy 82.82897 -354.503028) (xy 82.864683 -354.46181) (xy 82.905898 -354.426093)
			(xy 82.951776 -354.396604) (xy 83.001384 -354.373945) (xy 83.053711 -354.358575) (xy 83.107693 -354.350809)
			(xy 83.134962 -354.35032) (xy 83.998562 -354.35032) (xy 84.025833 -354.350817) (xy 84.079822 -354.358574)
			(xy 84.132157 -354.373936) (xy 84.181772 -354.396591) (xy 84.227659 -354.426076) (xy 84.268881 -354.461792)
			(xy 84.304601 -354.503011) (xy 84.334091 -354.548894) (xy 84.35675 -354.598508) (xy 84.372118 -354.650841)
			(xy 84.37988 -354.704829) (xy 84.37988 -354.759371) (xy 84.37988 -354.759373) (xy 85.862584 -354.759373)
			(xy 85.862584 -354.704827) (xy 85.870347 -354.650835) (xy 85.885715 -354.598498) (xy 85.908375 -354.548882)
			(xy 85.937866 -354.502995) (xy 85.973588 -354.461772) (xy 86.014812 -354.426053) (xy 86.060701 -354.396564)
			(xy 86.110319 -354.373907) (xy 86.162657 -354.358542) (xy 86.216649 -354.350782) (xy 86.243922 -354.35032)
			(xy 87.107522 -354.35032) (xy 87.134789 -354.350844) (xy 87.188768 -354.358608) (xy 87.241092 -354.373974)
			(xy 87.290697 -354.396631) (xy 87.336573 -354.426116) (xy 87.377786 -354.461829) (xy 87.413497 -354.503044)
			(xy 87.44298 -354.548922) (xy 87.465633 -354.598528) (xy 87.480997 -354.650854) (xy 87.488758 -354.704833)
			(xy 87.488758 -354.759367) (xy 87.488758 -354.75937) (xy 88.971606 -354.75937) (xy 88.971606 -354.70483)
			(xy 88.979368 -354.650846) (xy 88.994733 -354.598515) (xy 89.017389 -354.548904) (xy 89.046875 -354.503022)
			(xy 89.08259 -354.461802) (xy 89.123807 -354.426085) (xy 89.169688 -354.396598) (xy 89.219298 -354.373939)
			(xy 89.271628 -354.358572) (xy 89.325612 -354.350808) (xy 89.352882 -354.35032) (xy 90.216482 -354.35032)
			(xy 90.243753 -354.350818) (xy 90.297739 -354.358578) (xy 90.350071 -354.373942) (xy 90.399684 -354.396597)
			(xy 90.445568 -354.426083) (xy 90.486788 -354.461799) (xy 90.522506 -354.503018) (xy 90.551994 -354.5489)
			(xy 90.574652 -354.598512) (xy 90.590018 -354.650844) (xy 90.597781 -354.704829) (xy 90.597781 -354.759371)
			(xy 90.597781 -354.759374) (xy 92.080484 -354.759374) (xy 92.080484 -354.704826) (xy 92.088247 -354.650833)
			(xy 92.103616 -354.598494) (xy 92.126278 -354.548876) (xy 92.155771 -354.502988) (xy 92.191495 -354.461765)
			(xy 92.232722 -354.426046) (xy 92.278613 -354.396558) (xy 92.328234 -354.373902) (xy 92.380574 -354.358538)
			(xy 92.434568 -354.350781) (xy 92.461842 -354.35032) (xy 93.325442 -354.35032) (xy 93.352708 -354.350845)
			(xy 93.406685 -354.358611) (xy 93.459007 -354.37398) (xy 93.508609 -354.396637) (xy 93.554483 -354.426123)
			(xy 93.595693 -354.461836) (xy 93.631402 -354.503051) (xy 93.660883 -354.548928) (xy 93.683535 -354.598533)
			(xy 93.698898 -354.650856) (xy 93.706658 -354.704834) (xy 93.706658 -354.759366) (xy 93.706658 -354.759369)
			(xy 114.589806 -354.759369) (xy 114.589806 -354.704831) (xy 114.597568 -354.650847) (xy 114.612932 -354.598518)
			(xy 114.635587 -354.548908) (xy 114.665071 -354.503026) (xy 114.700785 -354.461807) (xy 114.742 -354.42609)
			(xy 114.78788 -354.396602) (xy 114.837488 -354.373943) (xy 114.889816 -354.358574) (xy 114.943799 -354.350809)
			(xy 114.971068 -354.35032) (xy 115.834668 -354.35032) (xy 115.861939 -354.350817) (xy 115.915927 -354.358575)
			(xy 115.968261 -354.373938) (xy 116.017876 -354.396593) (xy 116.063761 -354.426078) (xy 116.104983 -354.461794)
			(xy 116.140703 -354.503013) (xy 116.170192 -354.548896) (xy 116.192851 -354.598509) (xy 116.208218 -354.650842)
			(xy 116.21598 -354.704829) (xy 116.21598 -354.759371) (xy 116.21598 -354.759374) (xy 117.698684 -354.759374)
			(xy 117.698684 -354.704826) (xy 117.706447 -354.650835) (xy 117.721815 -354.598497) (xy 117.744476 -354.54888)
			(xy 117.773968 -354.502993) (xy 117.80969 -354.46177) (xy 117.850915 -354.426051) (xy 117.896804 -354.396562)
			(xy 117.946423 -354.373905) (xy 117.998762 -354.358541) (xy 118.052754 -354.350782) (xy 118.080028 -354.35032)
			(xy 118.943628 -354.35032) (xy 118.970895 -354.350844) (xy 119.024873 -354.358609) (xy 119.077197 -354.373976)
			(xy 119.126801 -354.396633) (xy 119.172676 -354.426118) (xy 119.213888 -354.461831) (xy 119.249599 -354.503046)
			(xy 119.279081 -354.548924) (xy 119.301734 -354.59853) (xy 119.317097 -354.650855) (xy 119.324858 -354.704833)
			(xy 119.324858 -354.759367) (xy 119.324858 -354.75937) (xy 120.807706 -354.75937) (xy 120.807706 -354.70483)
			(xy 120.815468 -354.650845) (xy 120.830834 -354.598514) (xy 120.85349 -354.548902) (xy 120.882976 -354.50302)
			(xy 120.918692 -354.4618) (xy 120.95991 -354.426083) (xy 121.005791 -354.396596) (xy 121.055403 -354.373938)
			(xy 121.107733 -354.358571) (xy 121.161718 -354.350807) (xy 121.188988 -354.35032) (xy 122.052588 -354.35032)
			(xy 122.079858 -354.350819) (xy 122.133844 -354.358579) (xy 122.186176 -354.373944) (xy 122.235788 -354.396599)
			(xy 122.281671 -354.426085) (xy 122.322891 -354.461801) (xy 122.358608 -354.503019) (xy 122.388095 -354.548902)
			(xy 122.410752 -354.598513) (xy 122.426118 -354.650844) (xy 122.433881 -354.70483) (xy 122.433881 -354.75937)
			(xy 122.43388 -354.759374) (xy 123.916584 -354.759374) (xy 123.916584 -354.704826) (xy 123.924347 -354.650832)
			(xy 123.939717 -354.598493) (xy 123.962379 -354.548874) (xy 123.991872 -354.502986) (xy 124.027597 -354.461763)
			(xy 124.068825 -354.426044) (xy 124.114716 -354.396556) (xy 124.164338 -354.3739) (xy 124.216679 -354.358537)
			(xy 124.270673 -354.35078) (xy 124.297948 -354.35032) (xy 125.161548 -354.35032) (xy 125.188814 -354.350846)
			(xy 125.24279 -354.358613) (xy 125.295111 -354.373981) (xy 125.344713 -354.396639) (xy 125.390586 -354.426125)
			(xy 125.431795 -354.461839) (xy 125.467504 -354.503053) (xy 125.496984 -354.548929) (xy 125.519636 -354.598534)
			(xy 125.534998 -354.650857) (xy 125.542758 -354.704834) (xy 125.542758 -354.759366) (xy 125.542757 -354.759373)
			(xy 127.025584 -354.759373) (xy 127.025584 -354.704827) (xy 127.033346 -354.650837) (xy 127.048714 -354.598501)
			(xy 127.071373 -354.548885) (xy 127.100863 -354.502999) (xy 127.136583 -354.461777) (xy 127.177806 -354.426058)
			(xy 127.223692 -354.396569) (xy 127.273309 -354.373911) (xy 127.325645 -354.358545) (xy 127.379635 -354.350783)
			(xy 127.406908 -354.35032) (xy 128.270508 -354.35032) (xy 128.297776 -354.350843) (xy 128.351756 -354.358605)
			(xy 128.404082 -354.37397) (xy 128.453689 -354.396626) (xy 128.499567 -354.426111) (xy 128.540781 -354.461824)
			(xy 128.576494 -354.50304) (xy 128.605978 -354.548918) (xy 128.628632 -354.598525) (xy 128.643997 -354.650852)
			(xy 128.651758 -354.704832) (xy 128.651758 -354.759368) (xy 128.651758 -354.759369) (xy 130.134606 -354.759369)
			(xy 130.134606 -354.704831) (xy 130.142368 -354.650847) (xy 130.157732 -354.598518) (xy 130.180387 -354.548908)
			(xy 130.209871 -354.503026) (xy 130.245585 -354.461807) (xy 130.2868 -354.42609) (xy 130.33268 -354.396602)
			(xy 130.382288 -354.373943) (xy 130.434616 -354.358574) (xy 130.488599 -354.350809) (xy 130.515868 -354.35032)
			(xy 131.379468 -354.35032) (xy 131.406739 -354.350817) (xy 131.460727 -354.358575) (xy 131.513061 -354.373938)
			(xy 131.562676 -354.396593) (xy 131.608561 -354.426078) (xy 131.649783 -354.461794) (xy 131.685503 -354.503013)
			(xy 131.714992 -354.548896) (xy 131.737651 -354.598509) (xy 131.753018 -354.650842) (xy 131.76078 -354.704829)
			(xy 131.76078 -354.759371) (xy 131.76078 -354.759374) (xy 133.243484 -354.759374) (xy 133.243484 -354.704826)
			(xy 133.251247 -354.650835) (xy 133.266615 -354.598497) (xy 133.289276 -354.54888) (xy 133.318768 -354.502993)
			(xy 133.35449 -354.46177) (xy 133.395715 -354.426051) (xy 133.441604 -354.396562) (xy 133.491223 -354.373905)
			(xy 133.543562 -354.358541) (xy 133.597554 -354.350782) (xy 133.624828 -354.35032) (xy 134.488428 -354.35032)
			(xy 134.515695 -354.350844) (xy 134.569673 -354.358609) (xy 134.621997 -354.373976) (xy 134.671601 -354.396633)
			(xy 134.717476 -354.426118) (xy 134.758688 -354.461831) (xy 134.794399 -354.503046) (xy 134.823881 -354.548924)
			(xy 134.846534 -354.59853) (xy 134.861897 -354.650855) (xy 134.869658 -354.704833) (xy 134.869658 -354.759367)
			(xy 134.869658 -354.75937) (xy 136.352506 -354.75937) (xy 136.352506 -354.70483) (xy 136.360268 -354.650845)
			(xy 136.375634 -354.598514) (xy 136.39829 -354.548902) (xy 136.427776 -354.50302) (xy 136.463492 -354.4618)
			(xy 136.50471 -354.426083) (xy 136.550591 -354.396596) (xy 136.600203 -354.373938) (xy 136.652533 -354.358571)
			(xy 136.706518 -354.350807) (xy 136.733788 -354.35032) (xy 137.597388 -354.35032) (xy 137.624658 -354.350819)
			(xy 137.678644 -354.358579) (xy 137.730976 -354.373944) (xy 137.780588 -354.396599) (xy 137.826471 -354.426085)
			(xy 137.867691 -354.461801) (xy 137.903408 -354.503019) (xy 137.932895 -354.548902) (xy 137.955552 -354.598513)
			(xy 137.970918 -354.650844) (xy 137.978681 -354.70483) (xy 137.978681 -354.75937) (xy 137.97868 -354.759374)
			(xy 139.461384 -354.759374) (xy 139.461384 -354.704826) (xy 139.469147 -354.650832) (xy 139.484517 -354.598493)
			(xy 139.507179 -354.548874) (xy 139.536672 -354.502986) (xy 139.572397 -354.461763) (xy 139.613625 -354.426044)
			(xy 139.659516 -354.396556) (xy 139.709138 -354.3739) (xy 139.761479 -354.358537) (xy 139.815473 -354.35078)
			(xy 139.842748 -354.35032) (xy 140.706348 -354.35032) (xy 140.733614 -354.350846) (xy 140.78759 -354.358613)
			(xy 140.839911 -354.373981) (xy 140.889513 -354.396639) (xy 140.935386 -354.426125) (xy 140.976595 -354.461839)
			(xy 141.012304 -354.503053) (xy 141.041784 -354.548929) (xy 141.064436 -354.598534) (xy 141.079798 -354.650857)
			(xy 141.087558 -354.704834) (xy 141.087558 -354.759366) (xy 141.087557 -354.759373) (xy 142.570384 -354.759373)
			(xy 142.570384 -354.704827) (xy 142.578146 -354.650837) (xy 142.593514 -354.598501) (xy 142.616173 -354.548885)
			(xy 142.645663 -354.502999) (xy 142.681383 -354.461777) (xy 142.722606 -354.426058) (xy 142.768492 -354.396569)
			(xy 142.818109 -354.373911) (xy 142.870445 -354.358545) (xy 142.924435 -354.350783) (xy 142.951708 -354.35032)
			(xy 143.815308 -354.35032) (xy 143.842576 -354.350843) (xy 143.896556 -354.358605) (xy 143.948882 -354.37397)
			(xy 143.998489 -354.396626) (xy 144.044367 -354.426111) (xy 144.085581 -354.461824) (xy 144.121294 -354.50304)
			(xy 144.150778 -354.548918) (xy 144.173432 -354.598525) (xy 144.188797 -354.650852) (xy 144.196558 -354.704832)
			(xy 144.196558 -354.759368) (xy 158.695906 -354.759368) (xy 158.695906 -354.704832) (xy 158.703667 -354.65085)
			(xy 158.719031 -354.598521) (xy 158.741685 -354.548912) (xy 158.771167 -354.503031) (xy 158.806879 -354.461813)
			(xy 158.848093 -354.426096) (xy 158.89397 -354.396608) (xy 158.943576 -354.373948) (xy 158.995903 -354.358577)
			(xy 159.049884 -354.35081) (xy 159.077152 -354.35032) (xy 159.940752 -354.35032) (xy 159.968024 -354.350816)
			(xy 160.022013 -354.358572) (xy 160.074349 -354.373934) (xy 160.123966 -354.396588) (xy 160.169854 -354.426072)
			(xy 160.211078 -354.461788) (xy 160.246799 -354.503008) (xy 160.276289 -354.548891) (xy 160.298949 -354.598506)
			(xy 160.314317 -354.65084) (xy 160.32208 -354.704828) (xy 160.32208 -354.759372) (xy 160.32208 -354.759373)
			(xy 161.804784 -354.759373) (xy 161.804784 -354.704827) (xy 161.812546 -354.650837) (xy 161.827914 -354.598501)
			(xy 161.850573 -354.548884) (xy 161.880064 -354.502998) (xy 161.915784 -354.461776) (xy 161.957008 -354.426056)
			(xy 162.002895 -354.396568) (xy 162.052512 -354.37391) (xy 162.104848 -354.358544) (xy 162.158839 -354.350783)
			(xy 162.186112 -354.35032) (xy 163.049712 -354.35032) (xy 163.07698 -354.350843) (xy 163.130959 -354.358606)
			(xy 163.183285 -354.373972) (xy 163.232891 -354.396627) (xy 163.278768 -354.426112) (xy 163.319983 -354.461826)
			(xy 163.355695 -354.503041) (xy 163.385178 -354.548919) (xy 163.407833 -354.598526) (xy 163.423197 -354.650852)
			(xy 163.430958 -354.704832) (xy 163.430958 -354.759368) (xy 163.430958 -354.759369) (xy 164.913806 -354.759369)
			(xy 164.913806 -354.704831) (xy 164.921568 -354.650847) (xy 164.936932 -354.598517) (xy 164.959588 -354.548907)
			(xy 164.989072 -354.503025) (xy 165.024786 -354.461806) (xy 165.066002 -354.426089) (xy 165.111882 -354.396601)
			(xy 165.161491 -354.373942) (xy 165.21382 -354.358574) (xy 165.267803 -354.350808) (xy 165.295072 -354.35032)
			(xy 166.158672 -354.35032) (xy 166.185943 -354.350818) (xy 166.23993 -354.358576) (xy 166.292264 -354.373939)
			(xy 166.341878 -354.396594) (xy 166.387763 -354.42608) (xy 166.428985 -354.461795) (xy 166.464704 -354.503014)
			(xy 166.494192 -354.548897) (xy 166.516851 -354.59851) (xy 166.532218 -354.650842) (xy 166.53998 -354.704829)
			(xy 166.53998 -354.759371) (xy 166.53998 -354.759374) (xy 168.022684 -354.759374) (xy 168.022684 -354.704826)
			(xy 168.030447 -354.650834) (xy 168.045816 -354.598496) (xy 168.068477 -354.548879) (xy 168.097969 -354.502991)
			(xy 168.133691 -354.461768) (xy 168.174917 -354.426049) (xy 168.220807 -354.396561) (xy 168.270426 -354.373904)
			(xy 168.322765 -354.35854) (xy 168.376758 -354.350781) (xy 168.404032 -354.35032) (xy 169.267632 -354.35032)
			(xy 169.294899 -354.350845) (xy 169.348876 -354.35861) (xy 169.401199 -354.373977) (xy 169.450803 -354.396634)
			(xy 169.496678 -354.426119) (xy 169.53789 -354.461833) (xy 169.5736 -354.503048) (xy 169.603081 -354.548925)
			(xy 169.625734 -354.598531) (xy 169.641097 -354.650855) (xy 169.648858 -354.704833) (xy 169.648858 -354.759367)
			(xy 169.648858 -354.75937) (xy 171.131706 -354.75937) (xy 171.131706 -354.70483) (xy 171.139468 -354.650844)
			(xy 171.154834 -354.598513) (xy 171.177491 -354.548901) (xy 171.206977 -354.503018) (xy 171.242693 -354.461799)
			(xy 171.283912 -354.426082) (xy 171.329794 -354.396594) (xy 171.379405 -354.373937) (xy 171.431736 -354.35857)
			(xy 171.485722 -354.350807) (xy 171.512992 -354.35032) (xy 172.376592 -354.35032) (xy 172.403862 -354.350819)
			(xy 172.457847 -354.35858) (xy 172.510178 -354.373945) (xy 172.55979 -354.396601) (xy 172.605673 -354.426087)
			(xy 172.646892 -354.461802) (xy 172.682609 -354.503021) (xy 172.712096 -354.548903) (xy 172.734753 -354.598514)
			(xy 172.750119 -354.650845) (xy 172.757881 -354.70483) (xy 172.757881 -354.759368) (xy 174.240706 -354.759368)
			(xy 174.240706 -354.704832) (xy 174.248467 -354.65085) (xy 174.263831 -354.598521) (xy 174.286485 -354.548912)
			(xy 174.315967 -354.503031) (xy 174.351679 -354.461813) (xy 174.392893 -354.426096) (xy 174.43877 -354.396608)
			(xy 174.488376 -354.373948) (xy 174.540703 -354.358577) (xy 174.594684 -354.35081) (xy 174.621952 -354.35032)
			(xy 175.485552 -354.35032) (xy 175.512824 -354.350816) (xy 175.566813 -354.358572) (xy 175.619149 -354.373934)
			(xy 175.668766 -354.396588) (xy 175.714654 -354.426072) (xy 175.755878 -354.461788) (xy 175.791599 -354.503008)
			(xy 175.821089 -354.548891) (xy 175.843749 -354.598506) (xy 175.859117 -354.65084) (xy 175.86688 -354.704828)
			(xy 175.86688 -354.759372) (xy 175.86688 -354.759373) (xy 177.349584 -354.759373) (xy 177.349584 -354.704827)
			(xy 177.357346 -354.650837) (xy 177.372714 -354.598501) (xy 177.395373 -354.548884) (xy 177.424864 -354.502998)
			(xy 177.460584 -354.461776) (xy 177.501808 -354.426056) (xy 177.547695 -354.396568) (xy 177.597312 -354.37391)
			(xy 177.649648 -354.358544) (xy 177.703639 -354.350783) (xy 177.730912 -354.35032) (xy 178.594512 -354.35032)
			(xy 178.62178 -354.350843) (xy 178.675759 -354.358606) (xy 178.728085 -354.373972) (xy 178.777691 -354.396627)
			(xy 178.823568 -354.426112) (xy 178.864783 -354.461826) (xy 178.900495 -354.503041) (xy 178.929978 -354.548919)
			(xy 178.952633 -354.598526) (xy 178.967997 -354.650852) (xy 178.975758 -354.704832) (xy 178.975758 -354.759368)
			(xy 178.975758 -354.759369) (xy 180.458606 -354.759369) (xy 180.458606 -354.704831) (xy 180.466368 -354.650847)
			(xy 180.481732 -354.598517) (xy 180.504388 -354.548907) (xy 180.533872 -354.503025) (xy 180.569586 -354.461806)
			(xy 180.610802 -354.426089) (xy 180.656682 -354.396601) (xy 180.706291 -354.373942) (xy 180.75862 -354.358574)
			(xy 180.812603 -354.350808) (xy 180.839872 -354.35032) (xy 181.703472 -354.35032) (xy 181.730743 -354.350818)
			(xy 181.78473 -354.358576) (xy 181.837064 -354.373939) (xy 181.886678 -354.396594) (xy 181.932563 -354.42608)
			(xy 181.973785 -354.461795) (xy 182.009504 -354.503014) (xy 182.038992 -354.548897) (xy 182.061651 -354.59851)
			(xy 182.077018 -354.650842) (xy 182.08478 -354.704829) (xy 182.08478 -354.735472) (xy 183.567508 -354.735472)
			(xy 183.567508 -354.680928) (xy 183.57527 -354.626939) (xy 183.590638 -354.574605) (xy 183.613298 -354.52499)
			(xy 183.642788 -354.479106) (xy 183.678508 -354.437885) (xy 183.719731 -354.402169) (xy 183.765618 -354.372682)
			(xy 183.815235 -354.350027) (xy 183.86757 -354.334664) (xy 183.92156 -354.326905) (xy 183.948832 -354.326444)
			(xy 184.812432 -354.326444) (xy 184.8397 -354.326921) (xy 184.893681 -354.334686) (xy 184.946008 -354.350054)
			(xy 184.995615 -354.372713) (xy 185.041492 -354.4022) (xy 185.082707 -354.437916) (xy 185.118419 -354.479133)
			(xy 185.147903 -354.525013) (xy 185.170557 -354.574622) (xy 185.185921 -354.62695) (xy 185.193682 -354.680932)
			(xy 185.193682 -354.735468) (xy 185.193682 -354.735469) (xy 186.67653 -354.735469) (xy 186.67653 -354.680931)
			(xy 186.684292 -354.626949) (xy 186.699656 -354.574621) (xy 186.722312 -354.525012) (xy 186.751796 -354.479133)
			(xy 186.78751 -354.437916) (xy 186.828726 -354.402201) (xy 186.874605 -354.372716) (xy 186.924214 -354.350059)
			(xy 186.976542 -354.334693) (xy 187.030523 -354.326931) (xy 187.057792 -354.326444) (xy 187.921392 -354.326444)
			(xy 187.948664 -354.326895) (xy 188.002652 -354.334656) (xy 188.054987 -354.350022) (xy 188.104602 -354.37268)
			(xy 188.150487 -354.402167) (xy 188.191709 -354.437885) (xy 188.227428 -354.479106) (xy 188.256917 -354.524991)
			(xy 188.279575 -354.574606) (xy 188.294942 -354.62694) (xy 188.302704 -354.680928) (xy 188.302704 -354.735472)
			(xy 188.299268 -354.759369) (xy 270.624806 -354.759369) (xy 270.624806 -354.704831) (xy 270.632567 -354.650848)
			(xy 270.647932 -354.598519) (xy 270.670586 -354.548909) (xy 270.70007 -354.503028) (xy 270.735783 -354.46181)
			(xy 270.776998 -354.426093) (xy 270.822876 -354.396604) (xy 270.872484 -354.373945) (xy 270.924811 -354.358575)
			(xy 270.978793 -354.350809) (xy 271.006062 -354.35032) (xy 271.869662 -354.35032) (xy 271.896933 -354.350817)
			(xy 271.950922 -354.358574) (xy 272.003257 -354.373936) (xy 272.052872 -354.396591) (xy 272.098759 -354.426076)
			(xy 272.139981 -354.461792) (xy 272.175701 -354.503011) (xy 272.205191 -354.548894) (xy 272.22785 -354.598508)
			(xy 272.243218 -354.650841) (xy 272.25098 -354.704829) (xy 272.25098 -354.759371) (xy 272.25098 -354.759373)
			(xy 273.733684 -354.759373) (xy 273.733684 -354.704827) (xy 273.741447 -354.650835) (xy 273.756815 -354.598498)
			(xy 273.779475 -354.548882) (xy 273.808966 -354.502995) (xy 273.844688 -354.461772) (xy 273.885912 -354.426053)
			(xy 273.931801 -354.396564) (xy 273.981419 -354.373907) (xy 274.033757 -354.358542) (xy 274.087749 -354.350782)
			(xy 274.115022 -354.35032) (xy 274.978622 -354.35032) (xy 275.005889 -354.350844) (xy 275.059868 -354.358608)
			(xy 275.112192 -354.373974) (xy 275.161797 -354.396631) (xy 275.207673 -354.426116) (xy 275.248886 -354.461829)
			(xy 275.284597 -354.503044) (xy 275.31408 -354.548922) (xy 275.336733 -354.598528) (xy 275.352097 -354.650854)
			(xy 275.359858 -354.704833) (xy 275.359858 -354.759367) (xy 275.359858 -354.75937) (xy 276.842706 -354.75937)
			(xy 276.842706 -354.70483) (xy 276.850468 -354.650846) (xy 276.865833 -354.598515) (xy 276.888489 -354.548904)
			(xy 276.917975 -354.503022) (xy 276.95369 -354.461802) (xy 276.994907 -354.426085) (xy 277.040788 -354.396598)
			(xy 277.090398 -354.373939) (xy 277.142728 -354.358572) (xy 277.196712 -354.350808) (xy 277.223982 -354.35032)
			(xy 278.087582 -354.35032) (xy 278.114853 -354.350818) (xy 278.168839 -354.358578) (xy 278.221171 -354.373942)
			(xy 278.270784 -354.396597) (xy 278.316668 -354.426083) (xy 278.357888 -354.461799) (xy 278.393606 -354.503018)
			(xy 278.423094 -354.5489) (xy 278.445752 -354.598512) (xy 278.461118 -354.650844) (xy 278.468881 -354.704829)
			(xy 278.468881 -354.759371) (xy 278.468881 -354.759374) (xy 279.951584 -354.759374) (xy 279.951584 -354.704826)
			(xy 279.959347 -354.650833) (xy 279.974716 -354.598494) (xy 279.997378 -354.548876) (xy 280.026871 -354.502988)
			(xy 280.062595 -354.461765) (xy 280.103822 -354.426046) (xy 280.149713 -354.396558) (xy 280.199334 -354.373902)
			(xy 280.251674 -354.358538) (xy 280.305668 -354.350781) (xy 280.332942 -354.35032) (xy 281.196542 -354.35032)
			(xy 281.223808 -354.350845) (xy 281.277785 -354.358611) (xy 281.330107 -354.37398) (xy 281.379709 -354.396637)
			(xy 281.425583 -354.426123) (xy 281.466793 -354.461836) (xy 281.502502 -354.503051) (xy 281.531983 -354.548928)
			(xy 281.554635 -354.598533) (xy 281.569998 -354.650856) (xy 281.577758 -354.704834) (xy 281.577758 -354.759366)
			(xy 281.577757 -354.759372) (xy 283.060584 -354.759372) (xy 283.060584 -354.704828) (xy 283.068346 -354.650838)
			(xy 283.083713 -354.598503) (xy 283.106372 -354.548887) (xy 283.135861 -354.503001) (xy 283.171581 -354.461779)
			(xy 283.212803 -354.42606) (xy 283.258689 -354.396571) (xy 283.308305 -354.373912) (xy 283.36064 -354.358546)
			(xy 283.41463 -354.350783) (xy 283.441902 -354.35032) (xy 284.305502 -354.35032) (xy 284.33277 -354.350843)
			(xy 284.386751 -354.358604) (xy 284.439078 -354.373969) (xy 284.488685 -354.396624) (xy 284.534564 -354.426109)
			(xy 284.575779 -354.461822) (xy 284.611493 -354.503038) (xy 284.640977 -354.548917) (xy 284.663632 -354.598524)
			(xy 284.678996 -354.650851) (xy 284.686758 -354.704832) (xy 284.686758 -354.759368) (xy 284.686758 -354.759369)
			(xy 286.169606 -354.759369) (xy 286.169606 -354.704831) (xy 286.177367 -354.650848) (xy 286.192732 -354.598519)
			(xy 286.215386 -354.548909) (xy 286.24487 -354.503028) (xy 286.280583 -354.46181) (xy 286.321798 -354.426093)
			(xy 286.367676 -354.396604) (xy 286.417284 -354.373945) (xy 286.469611 -354.358575) (xy 286.523593 -354.350809)
			(xy 286.550862 -354.35032) (xy 287.414462 -354.35032) (xy 287.441733 -354.350817) (xy 287.495722 -354.358574)
			(xy 287.548057 -354.373936) (xy 287.597672 -354.396591) (xy 287.643559 -354.426076) (xy 287.684781 -354.461792)
			(xy 287.720501 -354.503011) (xy 287.749991 -354.548894) (xy 287.77265 -354.598508) (xy 287.788018 -354.650841)
			(xy 287.79578 -354.704829) (xy 287.79578 -354.759371) (xy 287.79578 -354.759373) (xy 289.278484 -354.759373)
			(xy 289.278484 -354.704827) (xy 289.286247 -354.650835) (xy 289.301615 -354.598498) (xy 289.324275 -354.548882)
			(xy 289.353766 -354.502995) (xy 289.389488 -354.461772) (xy 289.430712 -354.426053) (xy 289.476601 -354.396564)
			(xy 289.526219 -354.373907) (xy 289.578557 -354.358542) (xy 289.632549 -354.350782) (xy 289.659822 -354.35032)
			(xy 290.523422 -354.35032) (xy 290.550689 -354.350844) (xy 290.604668 -354.358608) (xy 290.656992 -354.373974)
			(xy 290.706597 -354.396631) (xy 290.752473 -354.426116) (xy 290.793686 -354.461829) (xy 290.829397 -354.503044)
			(xy 290.85888 -354.548922) (xy 290.881533 -354.598528) (xy 290.896897 -354.650854) (xy 290.904658 -354.704833)
			(xy 290.904658 -354.759367) (xy 290.904658 -354.75937) (xy 292.387506 -354.75937) (xy 292.387506 -354.70483)
			(xy 292.395268 -354.650846) (xy 292.410633 -354.598515) (xy 292.433289 -354.548904) (xy 292.462775 -354.503022)
			(xy 292.49849 -354.461802) (xy 292.539707 -354.426085) (xy 292.585588 -354.396598) (xy 292.635198 -354.373939)
			(xy 292.687528 -354.358572) (xy 292.741512 -354.350808) (xy 292.768782 -354.35032) (xy 293.632382 -354.35032)
			(xy 293.659653 -354.350818) (xy 293.713639 -354.358578) (xy 293.765971 -354.373942) (xy 293.815584 -354.396597)
			(xy 293.861468 -354.426083) (xy 293.902688 -354.461799) (xy 293.938406 -354.503018) (xy 293.967894 -354.5489)
			(xy 293.990552 -354.598512) (xy 294.005918 -354.650844) (xy 294.013681 -354.704829) (xy 294.013681 -354.759371)
			(xy 294.013681 -354.759374) (xy 295.496384 -354.759374) (xy 295.496384 -354.704826) (xy 295.504147 -354.650833)
			(xy 295.519516 -354.598494) (xy 295.542178 -354.548876) (xy 295.571671 -354.502988) (xy 295.607395 -354.461765)
			(xy 295.648622 -354.426046) (xy 295.694513 -354.396558) (xy 295.744134 -354.373902) (xy 295.796474 -354.358538)
			(xy 295.850468 -354.350781) (xy 295.877742 -354.35032) (xy 296.741342 -354.35032) (xy 296.768608 -354.350845)
			(xy 296.822585 -354.358611) (xy 296.874907 -354.37398) (xy 296.924509 -354.396637) (xy 296.970383 -354.426123)
			(xy 297.011593 -354.461836) (xy 297.047302 -354.503051) (xy 297.076783 -354.548928) (xy 297.099435 -354.598533)
			(xy 297.114798 -354.650856) (xy 297.122558 -354.704834) (xy 297.122558 -354.759366) (xy 297.122557 -354.759372)
			(xy 298.605384 -354.759372) (xy 298.605384 -354.704828) (xy 298.613146 -354.650838) (xy 298.628513 -354.598503)
			(xy 298.651172 -354.548887) (xy 298.680661 -354.503001) (xy 298.716381 -354.461779) (xy 298.757603 -354.42606)
			(xy 298.803489 -354.396571) (xy 298.853105 -354.373912) (xy 298.90544 -354.358546) (xy 298.95943 -354.350783)
			(xy 298.986702 -354.35032) (xy 299.850302 -354.35032) (xy 299.87757 -354.350843) (xy 299.931551 -354.358604)
			(xy 299.983878 -354.373969) (xy 300.033485 -354.396624) (xy 300.079364 -354.426109) (xy 300.120579 -354.461822)
			(xy 300.156293 -354.503038) (xy 300.185777 -354.548917) (xy 300.208432 -354.598524) (xy 300.223796 -354.650851)
			(xy 300.231558 -354.704832) (xy 300.231558 -354.759368) (xy 300.231558 -354.759369) (xy 315.230506 -354.759369)
			(xy 315.230506 -354.704831) (xy 315.238267 -354.650848) (xy 315.253632 -354.598519) (xy 315.276286 -354.548909)
			(xy 315.30577 -354.503027) (xy 315.341483 -354.461809) (xy 315.382699 -354.426092) (xy 315.428577 -354.396604)
			(xy 315.478185 -354.373944) (xy 315.530513 -354.358575) (xy 315.584495 -354.350809) (xy 315.611764 -354.35032)
			(xy 316.475364 -354.35032) (xy 316.502635 -354.350817) (xy 316.556624 -354.358575) (xy 316.608958 -354.373937)
			(xy 316.658574 -354.396591) (xy 316.70446 -354.426077) (xy 316.745682 -354.461793) (xy 316.781402 -354.503012)
			(xy 316.810891 -354.548895) (xy 316.83355 -354.598508) (xy 316.848918 -354.650841) (xy 316.85668 -354.704829)
			(xy 316.85668 -354.759371) (xy 316.85668 -354.759373) (xy 318.339384 -354.759373) (xy 318.339384 -354.704827)
			(xy 318.347147 -354.650835) (xy 318.362515 -354.598498) (xy 318.385175 -354.548881) (xy 318.414667 -354.502994)
			(xy 318.450388 -354.461771) (xy 318.491613 -354.426052) (xy 318.537502 -354.396564) (xy 318.587121 -354.373907)
			(xy 318.639459 -354.358542) (xy 318.693451 -354.350782) (xy 318.720724 -354.35032) (xy 319.584324 -354.35032)
			(xy 319.611591 -354.350844) (xy 319.665569 -354.358608) (xy 319.717894 -354.373975) (xy 319.767498 -354.396631)
			(xy 319.813374 -354.426116) (xy 319.854587 -354.46183) (xy 319.890298 -354.503045) (xy 319.91978 -354.548923)
			(xy 319.942434 -354.598529) (xy 319.957797 -354.650854) (xy 319.965558 -354.704833) (xy 319.965558 -354.759367)
			(xy 319.965558 -354.75937) (xy 321.448406 -354.75937) (xy 321.448406 -354.70483) (xy 321.456168 -354.650845)
			(xy 321.471533 -354.598515) (xy 321.494189 -354.548903) (xy 321.523675 -354.503021) (xy 321.55939 -354.461802)
			(xy 321.600608 -354.426085) (xy 321.646489 -354.396597) (xy 321.6961 -354.373939) (xy 321.74843 -354.358571)
			(xy 321.802414 -354.350808) (xy 321.829684 -354.35032) (xy 322.693284 -354.35032) (xy 322.720554 -354.350818)
			(xy 322.774541 -354.358578) (xy 322.826873 -354.373942) (xy 322.876485 -354.396598) (xy 322.922369 -354.426084)
			(xy 322.963589 -354.4618) (xy 322.999307 -354.503018) (xy 323.028794 -354.5489) (xy 323.051452 -354.598512)
			(xy 323.066818 -354.650844) (xy 323.074581 -354.70483) (xy 323.074581 -354.75937) (xy 323.07458 -354.759374)
			(xy 324.557284 -354.759374) (xy 324.557284 -354.704826) (xy 324.565047 -354.650832) (xy 324.580417 -354.598494)
			(xy 324.603078 -354.548875) (xy 324.632571 -354.502987) (xy 324.668295 -354.461764) (xy 324.709523 -354.426045)
			(xy 324.755414 -354.396557) (xy 324.805035 -354.373901) (xy 324.857375 -354.358538) (xy 324.91137 -354.350781)
			(xy 324.938644 -354.35032) (xy 325.802244 -354.35032) (xy 325.82951 -354.350845) (xy 325.883486 -354.358612)
			(xy 325.935808 -354.37398) (xy 325.98541 -354.396638) (xy 326.031284 -354.426124) (xy 326.072494 -354.461837)
			(xy 326.108203 -354.503052) (xy 326.137683 -354.548928) (xy 326.160335 -354.598533) (xy 326.175698 -354.650857)
			(xy 326.183458 -354.704834) (xy 326.183458 -354.759366) (xy 326.183457 -354.759372) (xy 327.666284 -354.759372)
			(xy 327.666284 -354.704828) (xy 327.674046 -354.650838) (xy 327.689413 -354.598502) (xy 327.712072 -354.548887)
			(xy 327.741562 -354.503001) (xy 327.777281 -354.461778) (xy 327.818504 -354.426059) (xy 327.86439 -354.39657)
			(xy 327.914006 -354.373912) (xy 327.966342 -354.358545) (xy 328.020332 -354.350783) (xy 328.047604 -354.35032)
			(xy 328.911204 -354.35032) (xy 328.938472 -354.350843) (xy 328.992453 -354.358604) (xy 329.044779 -354.373969)
			(xy 329.094386 -354.396625) (xy 329.140265 -354.426109) (xy 329.18148 -354.461823) (xy 329.217193 -354.503039)
			(xy 329.246677 -354.548917) (xy 329.269332 -354.598525) (xy 329.284696 -354.650851) (xy 329.292458 -354.704832)
			(xy 329.292458 -354.759368) (xy 329.292458 -354.759369) (xy 330.775306 -354.759369) (xy 330.775306 -354.704831)
			(xy 330.783067 -354.650848) (xy 330.798432 -354.598519) (xy 330.821086 -354.548909) (xy 330.85057 -354.503027)
			(xy 330.886283 -354.461809) (xy 330.927499 -354.426092) (xy 330.973377 -354.396604) (xy 331.022985 -354.373944)
			(xy 331.075313 -354.358575) (xy 331.129295 -354.350809) (xy 331.156564 -354.35032) (xy 332.020164 -354.35032)
			(xy 332.047435 -354.350817) (xy 332.101424 -354.358575) (xy 332.153758 -354.373937) (xy 332.203374 -354.396591)
			(xy 332.24926 -354.426077) (xy 332.290482 -354.461793) (xy 332.326202 -354.503012) (xy 332.355691 -354.548895)
			(xy 332.37835 -354.598508) (xy 332.393718 -354.650841) (xy 332.40148 -354.704829) (xy 332.40148 -354.759371)
			(xy 332.40148 -354.759373) (xy 333.884184 -354.759373) (xy 333.884184 -354.704827) (xy 333.891947 -354.650835)
			(xy 333.907315 -354.598498) (xy 333.929975 -354.548881) (xy 333.959467 -354.502994) (xy 333.995188 -354.461771)
			(xy 334.036413 -354.426052) (xy 334.082302 -354.396564) (xy 334.131921 -354.373907) (xy 334.184259 -354.358542)
			(xy 334.238251 -354.350782) (xy 334.265524 -354.35032) (xy 335.129124 -354.35032) (xy 335.156391 -354.350844)
			(xy 335.210369 -354.358608) (xy 335.262694 -354.373975) (xy 335.312298 -354.396631) (xy 335.358174 -354.426116)
			(xy 335.399387 -354.46183) (xy 335.435098 -354.503045) (xy 335.46458 -354.548923) (xy 335.487234 -354.598529)
			(xy 335.502597 -354.650854) (xy 335.510358 -354.704833) (xy 335.510358 -354.759367) (xy 335.510358 -354.75937)
			(xy 336.993206 -354.75937) (xy 336.993206 -354.70483) (xy 337.000968 -354.650845) (xy 337.016333 -354.598515)
			(xy 337.038989 -354.548903) (xy 337.068475 -354.503021) (xy 337.10419 -354.461802) (xy 337.145408 -354.426085)
			(xy 337.191289 -354.396597) (xy 337.2409 -354.373939) (xy 337.29323 -354.358571) (xy 337.347214 -354.350808)
			(xy 337.374484 -354.35032) (xy 338.238084 -354.35032) (xy 338.265354 -354.350818) (xy 338.319341 -354.358578)
			(xy 338.371673 -354.373942) (xy 338.421285 -354.396598) (xy 338.467169 -354.426084) (xy 338.508389 -354.4618)
			(xy 338.544107 -354.503018) (xy 338.573594 -354.5489) (xy 338.596252 -354.598512) (xy 338.611618 -354.650844)
			(xy 338.619381 -354.70483) (xy 338.619381 -354.75937) (xy 338.61938 -354.759374) (xy 340.102084 -354.759374)
			(xy 340.102084 -354.704826) (xy 340.109847 -354.650832) (xy 340.125217 -354.598494) (xy 340.147878 -354.548875)
			(xy 340.177371 -354.502987) (xy 340.213095 -354.461764) (xy 340.254323 -354.426045) (xy 340.300214 -354.396557)
			(xy 340.349835 -354.373901) (xy 340.402175 -354.358538) (xy 340.45617 -354.350781) (xy 340.483444 -354.35032)
			(xy 341.347044 -354.35032) (xy 341.37431 -354.350845) (xy 341.428286 -354.358612) (xy 341.480608 -354.37398)
			(xy 341.53021 -354.396638) (xy 341.576084 -354.426124) (xy 341.617294 -354.461837) (xy 341.653003 -354.503052)
			(xy 341.682483 -354.548928) (xy 341.705135 -354.598533) (xy 341.720498 -354.650857) (xy 341.728258 -354.704834)
			(xy 341.728258 -354.759366) (xy 341.728257 -354.759372) (xy 343.211084 -354.759372) (xy 343.211084 -354.704828)
			(xy 343.218846 -354.650838) (xy 343.234213 -354.598502) (xy 343.256872 -354.548887) (xy 343.286362 -354.503001)
			(xy 343.322081 -354.461778) (xy 343.363304 -354.426059) (xy 343.40919 -354.39657) (xy 343.458806 -354.373912)
			(xy 343.511142 -354.358545) (xy 343.565132 -354.350783) (xy 343.592404 -354.35032) (xy 344.456004 -354.35032)
			(xy 344.483272 -354.350843) (xy 344.537253 -354.358604) (xy 344.589579 -354.373969) (xy 344.639186 -354.396625)
			(xy 344.685065 -354.426109) (xy 344.72628 -354.461823) (xy 344.761993 -354.503039) (xy 344.791477 -354.548917)
			(xy 344.814132 -354.598525) (xy 344.829496 -354.650851) (xy 344.837258 -354.704832) (xy 344.837258 -354.759368)
			(xy 344.837257 -354.759374) (xy 373.915584 -354.759374) (xy 373.915584 -354.704826) (xy 373.923347 -354.650833)
			(xy 373.938716 -354.598495) (xy 373.961378 -354.548876) (xy 373.990871 -354.502989) (xy 374.026594 -354.461766)
			(xy 374.067821 -354.426047) (xy 374.113712 -354.396559) (xy 374.163332 -354.373902) (xy 374.215672 -354.358539)
			(xy 374.269666 -354.350781) (xy 374.29694 -354.35032) (xy 375.16054 -354.35032) (xy 375.187806 -354.350845)
			(xy 375.241783 -354.358611) (xy 375.294105 -354.373979) (xy 375.343708 -354.396637) (xy 375.389582 -354.426122)
			(xy 375.430793 -354.461836) (xy 375.466502 -354.50305) (xy 375.495983 -354.548927) (xy 375.518635 -354.598532)
			(xy 375.533997 -354.650856) (xy 375.541758 -354.704834) (xy 375.541758 -354.759366) (xy 375.541757 -354.759371)
			(xy 377.024606 -354.759371) (xy 377.024606 -354.704829) (xy 377.032369 -354.650843) (xy 377.047735 -354.598511)
			(xy 377.070392 -354.548899) (xy 377.099879 -354.503016) (xy 377.135596 -354.461796) (xy 377.176816 -354.426079)
			(xy 377.222699 -354.396592) (xy 377.272311 -354.373935) (xy 377.324643 -354.358569) (xy 377.378629 -354.350806)
			(xy 377.4059 -354.35032) (xy 378.2695 -354.35032) (xy 378.296768 -354.350842) (xy 378.350749 -354.358604)
			(xy 378.403076 -354.373968) (xy 378.452684 -354.396623) (xy 378.498563 -354.426108) (xy 378.539778 -354.461822)
			(xy 378.575492 -354.503037) (xy 378.604977 -354.548916) (xy 378.627632 -354.598524) (xy 378.642996 -354.650851)
			(xy 378.650758 -354.704832) (xy 378.650758 -354.759368) (xy 378.650758 -354.759369) (xy 380.133606 -354.759369)
			(xy 380.133606 -354.704831) (xy 380.141367 -354.650849) (xy 380.156731 -354.59852) (xy 380.179386 -354.54891)
			(xy 380.208869 -354.503029) (xy 380.244582 -354.46181) (xy 380.285797 -354.426093) (xy 380.331675 -354.396605)
			(xy 380.381282 -354.373945) (xy 380.433609 -354.358576) (xy 380.487591 -354.350809) (xy 380.51486 -354.35032)
			(xy 381.37846 -354.35032) (xy 381.405732 -354.350817) (xy 381.45972 -354.358574) (xy 381.512055 -354.373936)
			(xy 381.561671 -354.39659) (xy 381.607558 -354.426075) (xy 381.648781 -354.461791) (xy 381.684501 -354.50301)
			(xy 381.713991 -354.548894) (xy 381.73665 -354.598507) (xy 381.752018 -354.650841) (xy 381.75978 -354.704828)
			(xy 381.75978 -354.759372) (xy 381.75978 -354.759373) (xy 383.242484 -354.759373) (xy 383.242484 -354.704827)
			(xy 383.250247 -354.650836) (xy 383.265615 -354.598499) (xy 383.288275 -354.548882) (xy 383.317766 -354.502995)
			(xy 383.353487 -354.461773) (xy 383.394711 -354.426054) (xy 383.4406 -354.396565) (xy 383.490218 -354.373908)
			(xy 383.542555 -354.358542) (xy 383.596547 -354.350782) (xy 383.62382 -354.35032) (xy 384.48742 -354.35032)
			(xy 384.514687 -354.350844) (xy 384.568666 -354.358607) (xy 384.620991 -354.373974) (xy 384.670596 -354.39663)
			(xy 384.716472 -354.426115) (xy 384.757686 -354.461829) (xy 384.793397 -354.503044) (xy 384.82288 -354.548922)
			(xy 384.845533 -354.598528) (xy 384.860897 -354.650854) (xy 384.868658 -354.704833) (xy 384.868658 -354.759367)
			(xy 384.868658 -354.75937) (xy 386.351506 -354.75937) (xy 386.351506 -354.70483) (xy 386.359268 -354.650846)
			(xy 386.374633 -354.598515) (xy 386.397289 -354.548904) (xy 386.426774 -354.503022) (xy 386.462489 -354.461803)
			(xy 386.503706 -354.426086) (xy 386.549587 -354.396598) (xy 386.599197 -354.37394) (xy 386.651526 -354.358572)
			(xy 386.70551 -354.350808) (xy 386.73278 -354.35032) (xy 387.59638 -354.35032) (xy 387.623651 -354.350818)
			(xy 387.677637 -354.358578) (xy 387.72997 -354.373941) (xy 387.779583 -354.396597) (xy 387.825467 -354.426082)
			(xy 387.866688 -354.461798) (xy 387.902406 -354.503017) (xy 387.931894 -354.548899) (xy 387.954552 -354.598511)
			(xy 387.969918 -354.650843) (xy 387.97768 -354.704829) (xy 387.97768 -354.759371) (xy 387.97768 -354.759374)
			(xy 389.460384 -354.759374) (xy 389.460384 -354.704826) (xy 389.468147 -354.650833) (xy 389.483516 -354.598495)
			(xy 389.506178 -354.548876) (xy 389.535671 -354.502989) (xy 389.571394 -354.461766) (xy 389.612621 -354.426047)
			(xy 389.658512 -354.396559) (xy 389.708132 -354.373902) (xy 389.760472 -354.358539) (xy 389.814466 -354.350781)
			(xy 389.84174 -354.35032) (xy 390.70534 -354.35032) (xy 390.732606 -354.350845) (xy 390.786583 -354.358611)
			(xy 390.838905 -354.373979) (xy 390.888508 -354.396637) (xy 390.934382 -354.426122) (xy 390.975593 -354.461836)
			(xy 391.011302 -354.50305) (xy 391.040783 -354.548927) (xy 391.063435 -354.598532) (xy 391.078797 -354.650856)
			(xy 391.086558 -354.704834) (xy 391.086558 -354.759366) (xy 391.086557 -354.759371) (xy 392.569406 -354.759371)
			(xy 392.569406 -354.704829) (xy 392.577169 -354.650843) (xy 392.592535 -354.598511) (xy 392.615192 -354.548899)
			(xy 392.644679 -354.503016) (xy 392.680396 -354.461796) (xy 392.721616 -354.426079) (xy 392.767499 -354.396592)
			(xy 392.817111 -354.373935) (xy 392.869443 -354.358569) (xy 392.923429 -354.350806) (xy 392.9507 -354.35032)
			(xy 393.8143 -354.35032) (xy 393.841568 -354.350842) (xy 393.895549 -354.358604) (xy 393.947876 -354.373968)
			(xy 393.997484 -354.396623) (xy 394.043363 -354.426108) (xy 394.084578 -354.461822) (xy 394.120292 -354.503037)
			(xy 394.149777 -354.548916) (xy 394.172432 -354.598524) (xy 394.187796 -354.650851) (xy 394.195558 -354.704832)
			(xy 394.195558 -354.759368) (xy 394.195558 -354.759369) (xy 395.678406 -354.759369) (xy 395.678406 -354.704831)
			(xy 395.686167 -354.650849) (xy 395.701531 -354.59852) (xy 395.724186 -354.54891) (xy 395.753669 -354.503029)
			(xy 395.789382 -354.46181) (xy 395.830597 -354.426093) (xy 395.876475 -354.396605) (xy 395.926082 -354.373945)
			(xy 395.978409 -354.358576) (xy 396.032391 -354.350809) (xy 396.05966 -354.35032) (xy 396.92326 -354.35032)
			(xy 396.950532 -354.350817) (xy 397.00452 -354.358574) (xy 397.056855 -354.373936) (xy 397.106471 -354.39659)
			(xy 397.152358 -354.426075) (xy 397.193581 -354.461791) (xy 397.229301 -354.50301) (xy 397.258791 -354.548894)
			(xy 397.28145 -354.598507) (xy 397.296818 -354.650841) (xy 397.30458 -354.704828) (xy 397.30458 -354.759372)
			(xy 397.30458 -354.759373) (xy 398.787284 -354.759373) (xy 398.787284 -354.704827) (xy 398.795047 -354.650836)
			(xy 398.810415 -354.598499) (xy 398.833075 -354.548882) (xy 398.862566 -354.502995) (xy 398.898287 -354.461773)
			(xy 398.939511 -354.426054) (xy 398.9854 -354.396565) (xy 399.035018 -354.373908) (xy 399.087355 -354.358542)
			(xy 399.141347 -354.350782) (xy 399.16862 -354.35032) (xy 400.03222 -354.35032) (xy 400.059487 -354.350844)
			(xy 400.113466 -354.358607) (xy 400.165791 -354.373974) (xy 400.215396 -354.39663) (xy 400.261272 -354.426115)
			(xy 400.302486 -354.461829) (xy 400.338197 -354.503044) (xy 400.36768 -354.548922) (xy 400.390333 -354.598528)
			(xy 400.405697 -354.650854) (xy 400.413458 -354.704833) (xy 400.413458 -354.759367) (xy 400.413458 -354.75937)
			(xy 401.896306 -354.75937) (xy 401.896306 -354.70483) (xy 401.904068 -354.650846) (xy 401.919433 -354.598515)
			(xy 401.942089 -354.548904) (xy 401.971574 -354.503022) (xy 402.007289 -354.461803) (xy 402.048506 -354.426086)
			(xy 402.094387 -354.396598) (xy 402.143997 -354.37394) (xy 402.196326 -354.358572) (xy 402.25031 -354.350808)
			(xy 402.27758 -354.35032) (xy 403.14118 -354.35032) (xy 403.168451 -354.350818) (xy 403.222437 -354.358578)
			(xy 403.27477 -354.373941) (xy 403.324383 -354.396597) (xy 403.370267 -354.426082) (xy 403.411488 -354.461798)
			(xy 403.447206 -354.503017) (xy 403.476694 -354.548899) (xy 403.499352 -354.598511) (xy 403.514718 -354.650843)
			(xy 403.52248 -354.704829) (xy 403.52248 -354.759368) (xy 412.022806 -354.759368) (xy 412.022806 -354.704832)
			(xy 412.030567 -354.65085) (xy 412.045931 -354.598521) (xy 412.068585 -354.548912) (xy 412.098067 -354.503031)
			(xy 412.133779 -354.461813) (xy 412.174993 -354.426096) (xy 412.22087 -354.396608) (xy 412.270476 -354.373948)
			(xy 412.322803 -354.358577) (xy 412.376784 -354.35081) (xy 412.404052 -354.35032) (xy 413.267652 -354.35032)
			(xy 413.294924 -354.350816) (xy 413.348913 -354.358572) (xy 413.401249 -354.373934) (xy 413.450866 -354.396588)
			(xy 413.496754 -354.426072) (xy 413.537978 -354.461788) (xy 413.573699 -354.503008) (xy 413.603189 -354.548891)
			(xy 413.625849 -354.598506) (xy 413.641217 -354.65084) (xy 413.64898 -354.704828) (xy 413.64898 -354.759372)
			(xy 413.64898 -354.759373) (xy 415.131684 -354.759373) (xy 415.131684 -354.704827) (xy 415.139446 -354.650837)
			(xy 415.154814 -354.598501) (xy 415.177473 -354.548884) (xy 415.206964 -354.502998) (xy 415.242684 -354.461776)
			(xy 415.283908 -354.426056) (xy 415.329795 -354.396568) (xy 415.379412 -354.37391) (xy 415.431748 -354.358544)
			(xy 415.485739 -354.350783) (xy 415.513012 -354.35032) (xy 416.376612 -354.35032) (xy 416.40388 -354.350843)
			(xy 416.457859 -354.358606) (xy 416.510185 -354.373972) (xy 416.559791 -354.396627) (xy 416.605668 -354.426112)
			(xy 416.646883 -354.461826) (xy 416.682595 -354.503041) (xy 416.712078 -354.548919) (xy 416.734733 -354.598526)
			(xy 416.750097 -354.650852) (xy 416.757858 -354.704832) (xy 416.757858 -354.759368) (xy 416.757858 -354.759369)
			(xy 418.240706 -354.759369) (xy 418.240706 -354.704831) (xy 418.248468 -354.650847) (xy 418.263832 -354.598517)
			(xy 418.286488 -354.548907) (xy 418.315972 -354.503025) (xy 418.351686 -354.461806) (xy 418.392902 -354.426089)
			(xy 418.438782 -354.396601) (xy 418.488391 -354.373942) (xy 418.54072 -354.358574) (xy 418.594703 -354.350808)
			(xy 418.621972 -354.35032) (xy 419.485572 -354.35032) (xy 419.512843 -354.350818) (xy 419.56683 -354.358576)
			(xy 419.619164 -354.373939) (xy 419.668778 -354.396594) (xy 419.714663 -354.42608) (xy 419.755885 -354.461795)
			(xy 419.791604 -354.503014) (xy 419.821092 -354.548897) (xy 419.843751 -354.59851) (xy 419.859118 -354.650842)
			(xy 419.86688 -354.704829) (xy 419.86688 -354.759371) (xy 419.86688 -354.759374) (xy 421.349584 -354.759374)
			(xy 421.349584 -354.704826) (xy 421.357347 -354.650834) (xy 421.372716 -354.598496) (xy 421.395377 -354.548879)
			(xy 421.424869 -354.502991) (xy 421.460591 -354.461768) (xy 421.501817 -354.426049) (xy 421.547707 -354.396561)
			(xy 421.597326 -354.373904) (xy 421.649665 -354.35854) (xy 421.703658 -354.350781) (xy 421.730932 -354.35032)
			(xy 422.594532 -354.35032) (xy 422.621799 -354.350845) (xy 422.675776 -354.35861) (xy 422.728099 -354.373977)
			(xy 422.777703 -354.396634) (xy 422.823578 -354.426119) (xy 422.86479 -354.461833) (xy 422.9005 -354.503048)
			(xy 422.929981 -354.548925) (xy 422.952634 -354.598531) (xy 422.967997 -354.650855) (xy 422.975758 -354.704833)
			(xy 422.975758 -354.759367) (xy 422.975758 -354.75937) (xy 424.458606 -354.75937) (xy 424.458606 -354.70483)
			(xy 424.466368 -354.650844) (xy 424.481734 -354.598513) (xy 424.504391 -354.548901) (xy 424.533877 -354.503018)
			(xy 424.569593 -354.461799) (xy 424.610812 -354.426082) (xy 424.656694 -354.396594) (xy 424.706305 -354.373937)
			(xy 424.758636 -354.35857) (xy 424.812622 -354.350807) (xy 424.839892 -354.35032) (xy 425.703492 -354.35032)
			(xy 425.730762 -354.350819) (xy 425.784747 -354.35858) (xy 425.837078 -354.373945) (xy 425.88669 -354.396601)
			(xy 425.932573 -354.426087) (xy 425.973792 -354.461802) (xy 426.009509 -354.503021) (xy 426.038996 -354.548903)
			(xy 426.061653 -354.598514) (xy 426.077019 -354.650845) (xy 426.084781 -354.70483) (xy 426.084781 -354.759368)
			(xy 427.567606 -354.759368) (xy 427.567606 -354.704832) (xy 427.575367 -354.65085) (xy 427.590731 -354.598521)
			(xy 427.613385 -354.548912) (xy 427.642867 -354.503031) (xy 427.678579 -354.461813) (xy 427.719793 -354.426096)
			(xy 427.76567 -354.396608) (xy 427.815276 -354.373948) (xy 427.867603 -354.358577) (xy 427.921584 -354.35081)
			(xy 427.948852 -354.35032) (xy 428.812452 -354.35032) (xy 428.839724 -354.350816) (xy 428.893713 -354.358572)
			(xy 428.946049 -354.373934) (xy 428.995666 -354.396588) (xy 429.041554 -354.426072) (xy 429.082778 -354.461788)
			(xy 429.118499 -354.503008) (xy 429.147989 -354.548891) (xy 429.170649 -354.598506) (xy 429.186017 -354.65084)
			(xy 429.19378 -354.704828) (xy 429.19378 -354.759372) (xy 429.19378 -354.759373) (xy 430.676484 -354.759373)
			(xy 430.676484 -354.704827) (xy 430.684246 -354.650837) (xy 430.699614 -354.598501) (xy 430.722273 -354.548884)
			(xy 430.751764 -354.502998) (xy 430.787484 -354.461776) (xy 430.828708 -354.426056) (xy 430.874595 -354.396568)
			(xy 430.924212 -354.37391) (xy 430.976548 -354.358544) (xy 431.030539 -354.350783) (xy 431.057812 -354.35032)
			(xy 431.921412 -354.35032) (xy 431.94868 -354.350843) (xy 432.002659 -354.358606) (xy 432.054985 -354.373972)
			(xy 432.104591 -354.396627) (xy 432.150468 -354.426112) (xy 432.191683 -354.461826) (xy 432.227395 -354.503041)
			(xy 432.256878 -354.548919) (xy 432.279533 -354.598526) (xy 432.294897 -354.650852) (xy 432.302658 -354.704832)
			(xy 432.302658 -354.759368) (xy 432.302658 -354.759369) (xy 433.785506 -354.759369) (xy 433.785506 -354.704831)
			(xy 433.793268 -354.650847) (xy 433.808632 -354.598517) (xy 433.831288 -354.548907) (xy 433.860772 -354.503025)
			(xy 433.896486 -354.461806) (xy 433.937702 -354.426089) (xy 433.983582 -354.396601) (xy 434.033191 -354.373942)
			(xy 434.08552 -354.358574) (xy 434.139503 -354.350808) (xy 434.166772 -354.35032) (xy 435.030372 -354.35032)
			(xy 435.057643 -354.350818) (xy 435.11163 -354.358576) (xy 435.163964 -354.373939) (xy 435.213578 -354.396594)
			(xy 435.259463 -354.42608) (xy 435.300685 -354.461795) (xy 435.336404 -354.503014) (xy 435.365892 -354.548897)
			(xy 435.388551 -354.59851) (xy 435.403918 -354.650842) (xy 435.41168 -354.704829) (xy 435.41168 -354.759371)
			(xy 435.41168 -354.759374) (xy 436.894384 -354.759374) (xy 436.894384 -354.704826) (xy 436.902147 -354.650834)
			(xy 436.917516 -354.598496) (xy 436.940177 -354.548879) (xy 436.969669 -354.502991) (xy 437.005391 -354.461768)
			(xy 437.046617 -354.426049) (xy 437.092507 -354.396561) (xy 437.142126 -354.373904) (xy 437.194465 -354.35854)
			(xy 437.248458 -354.350781) (xy 437.275732 -354.35032) (xy 438.139332 -354.35032) (xy 438.166599 -354.350845)
			(xy 438.220576 -354.35861) (xy 438.272899 -354.373977) (xy 438.322503 -354.396634) (xy 438.368378 -354.426119)
			(xy 438.40959 -354.461833) (xy 438.4453 -354.503048) (xy 438.474781 -354.548925) (xy 438.497434 -354.598531)
			(xy 438.512797 -354.650855) (xy 438.520558 -354.704833) (xy 438.520558 -354.759367) (xy 438.520558 -354.75937)
			(xy 440.003406 -354.75937) (xy 440.003406 -354.70483) (xy 440.011168 -354.650844) (xy 440.026534 -354.598513)
			(xy 440.049191 -354.548901) (xy 440.078677 -354.503018) (xy 440.114393 -354.461799) (xy 440.155612 -354.426082)
			(xy 440.201494 -354.396594) (xy 440.251105 -354.373937) (xy 440.303436 -354.35857) (xy 440.357422 -354.350807)
			(xy 440.384692 -354.35032) (xy 441.248292 -354.35032) (xy 441.275562 -354.350819) (xy 441.329547 -354.35858)
			(xy 441.381878 -354.373945) (xy 441.43149 -354.396601) (xy 441.477373 -354.426087) (xy 441.518592 -354.461802)
			(xy 441.554309 -354.503021) (xy 441.583796 -354.548903) (xy 441.606453 -354.598514) (xy 441.621819 -354.650845)
			(xy 441.629581 -354.70483) (xy 441.629581 -354.75937) (xy 441.621819 -354.813355) (xy 441.606453 -354.865686)
			(xy 441.583796 -354.915297) (xy 441.554309 -354.961179) (xy 441.518592 -355.002398) (xy 441.477373 -355.038113)
			(xy 441.43149 -355.067599) (xy 441.381878 -355.090255) (xy 441.329547 -355.10562) (xy 441.275562 -355.113381)
			(xy 441.248292 -355.113844) (xy 440.384692 -355.113844) (xy 440.357422 -355.113393) (xy 440.303436 -355.10563)
			(xy 440.251105 -355.090263) (xy 440.201494 -355.067606) (xy 440.155612 -355.038118) (xy 440.114393 -355.002401)
			(xy 440.078677 -354.961182) (xy 440.049191 -354.915299) (xy 440.026534 -354.865687) (xy 440.011168 -354.813356)
			(xy 440.003406 -354.75937) (xy 438.520558 -354.75937) (xy 438.512797 -354.813345) (xy 438.497434 -354.865669)
			(xy 438.474781 -354.915275) (xy 438.4453 -354.961152) (xy 438.40959 -355.002367) (xy 438.368378 -355.038081)
			(xy 438.322503 -355.067566) (xy 438.272899 -355.090223) (xy 438.220576 -355.10559) (xy 438.166599 -355.113355)
			(xy 438.139332 -355.113844) (xy 437.275732 -355.113844) (xy 437.248458 -355.113419) (xy 437.194465 -355.10566)
			(xy 437.142126 -355.090296) (xy 437.092507 -355.067639) (xy 437.046617 -355.038151) (xy 437.005391 -355.002432)
			(xy 436.969669 -354.961209) (xy 436.940177 -354.915321) (xy 436.917516 -354.865704) (xy 436.902147 -354.813366)
			(xy 436.894384 -354.759374) (xy 435.41168 -354.759374) (xy 435.403918 -354.813358) (xy 435.388551 -354.86569)
			(xy 435.365892 -354.915303) (xy 435.336404 -354.961186) (xy 435.300685 -355.002405) (xy 435.259463 -355.03812)
			(xy 435.213578 -355.067606) (xy 435.163964 -355.090261) (xy 435.11163 -355.105624) (xy 435.057643 -355.113382)
			(xy 435.030372 -355.113844) (xy 434.166772 -355.113844) (xy 434.139503 -355.113392) (xy 434.08552 -355.105626)
			(xy 434.033191 -355.090258) (xy 433.983582 -355.067599) (xy 433.937702 -355.038111) (xy 433.896486 -355.002394)
			(xy 433.860772 -354.961175) (xy 433.831288 -354.915293) (xy 433.808632 -354.865683) (xy 433.793268 -354.813353)
			(xy 433.785506 -354.759369) (xy 432.302658 -354.759369) (xy 432.294897 -354.813348) (xy 432.279533 -354.865674)
			(xy 432.256878 -354.915281) (xy 432.227395 -354.961159) (xy 432.191683 -355.002374) (xy 432.150468 -355.038088)
			(xy 432.104591 -355.067573) (xy 432.054985 -355.090228) (xy 432.002659 -355.105594) (xy 431.94868 -355.113357)
			(xy 431.921412 -355.113844) (xy 431.057812 -355.113844) (xy 431.030539 -355.113417) (xy 430.976548 -355.105656)
			(xy 430.924212 -355.09029) (xy 430.874595 -355.067632) (xy 430.828708 -355.038144) (xy 430.787484 -355.002424)
			(xy 430.751764 -354.961202) (xy 430.722273 -354.915316) (xy 430.699614 -354.865699) (xy 430.684246 -354.813363)
			(xy 430.676484 -354.759373) (xy 429.19378 -354.759373) (xy 429.186017 -354.81336) (xy 429.170649 -354.865694)
			(xy 429.147989 -354.915309) (xy 429.118499 -354.961192) (xy 429.082778 -355.002412) (xy 429.041554 -355.038128)
			(xy 428.995666 -355.067612) (xy 428.946049 -355.090266) (xy 428.893713 -355.105628) (xy 428.839724 -355.113384)
			(xy 428.812452 -355.113844) (xy 427.948852 -355.113844) (xy 427.921584 -355.11339) (xy 427.867603 -355.105623)
			(xy 427.815276 -355.090252) (xy 427.76567 -355.067592) (xy 427.719793 -355.038104) (xy 427.678579 -355.002387)
			(xy 427.642867 -354.961169) (xy 427.613385 -354.915288) (xy 427.590731 -354.865679) (xy 427.575367 -354.81335)
			(xy 427.567606 -354.759368) (xy 426.084781 -354.759368) (xy 426.084781 -354.75937) (xy 426.077019 -354.813355)
			(xy 426.061653 -354.865686) (xy 426.038996 -354.915297) (xy 426.009509 -354.961179) (xy 425.973792 -355.002398)
			(xy 425.932573 -355.038113) (xy 425.88669 -355.067599) (xy 425.837078 -355.090255) (xy 425.784747 -355.10562)
			(xy 425.730762 -355.113381) (xy 425.703492 -355.113844) (xy 424.839892 -355.113844) (xy 424.812622 -355.113393)
			(xy 424.758636 -355.10563) (xy 424.706305 -355.090263) (xy 424.656694 -355.067606) (xy 424.610812 -355.038118)
			(xy 424.569593 -355.002401) (xy 424.533877 -354.961182) (xy 424.504391 -354.915299) (xy 424.481734 -354.865687)
			(xy 424.466368 -354.813356) (xy 424.458606 -354.75937) (xy 422.975758 -354.75937) (xy 422.967997 -354.813345)
			(xy 422.952634 -354.865669) (xy 422.929981 -354.915275) (xy 422.9005 -354.961152) (xy 422.86479 -355.002367)
			(xy 422.823578 -355.038081) (xy 422.777703 -355.067566) (xy 422.728099 -355.090223) (xy 422.675776 -355.10559)
			(xy 422.621799 -355.113355) (xy 422.594532 -355.113844) (xy 421.730932 -355.113844) (xy 421.703658 -355.113419)
			(xy 421.649665 -355.10566) (xy 421.597326 -355.090296) (xy 421.547707 -355.067639) (xy 421.501817 -355.038151)
			(xy 421.460591 -355.002432) (xy 421.424869 -354.961209) (xy 421.395377 -354.915321) (xy 421.372716 -354.865704)
			(xy 421.357347 -354.813366) (xy 421.349584 -354.759374) (xy 419.86688 -354.759374) (xy 419.859118 -354.813358)
			(xy 419.843751 -354.86569) (xy 419.821092 -354.915303) (xy 419.791604 -354.961186) (xy 419.755885 -355.002405)
			(xy 419.714663 -355.03812) (xy 419.668778 -355.067606) (xy 419.619164 -355.090261) (xy 419.56683 -355.105624)
			(xy 419.512843 -355.113382) (xy 419.485572 -355.113844) (xy 418.621972 -355.113844) (xy 418.594703 -355.113392)
			(xy 418.54072 -355.105626) (xy 418.488391 -355.090258) (xy 418.438782 -355.067599) (xy 418.392902 -355.038111)
			(xy 418.351686 -355.002394) (xy 418.315972 -354.961175) (xy 418.286488 -354.915293) (xy 418.263832 -354.865683)
			(xy 418.248468 -354.813353) (xy 418.240706 -354.759369) (xy 416.757858 -354.759369) (xy 416.750097 -354.813348)
			(xy 416.734733 -354.865674) (xy 416.712078 -354.915281) (xy 416.682595 -354.961159) (xy 416.646883 -355.002374)
			(xy 416.605668 -355.038088) (xy 416.559791 -355.067573) (xy 416.510185 -355.090228) (xy 416.457859 -355.105594)
			(xy 416.40388 -355.113357) (xy 416.376612 -355.113844) (xy 415.513012 -355.113844) (xy 415.485739 -355.113417)
			(xy 415.431748 -355.105656) (xy 415.379412 -355.09029) (xy 415.329795 -355.067632) (xy 415.283908 -355.038144)
			(xy 415.242684 -355.002424) (xy 415.206964 -354.961202) (xy 415.177473 -354.915316) (xy 415.154814 -354.865699)
			(xy 415.139446 -354.813363) (xy 415.131684 -354.759373) (xy 413.64898 -354.759373) (xy 413.641217 -354.81336)
			(xy 413.625849 -354.865694) (xy 413.603189 -354.915309) (xy 413.573699 -354.961192) (xy 413.537978 -355.002412)
			(xy 413.496754 -355.038128) (xy 413.450866 -355.067612) (xy 413.401249 -355.090266) (xy 413.348913 -355.105628)
			(xy 413.294924 -355.113384) (xy 413.267652 -355.113844) (xy 412.404052 -355.113844) (xy 412.376784 -355.11339)
			(xy 412.322803 -355.105623) (xy 412.270476 -355.090252) (xy 412.22087 -355.067592) (xy 412.174993 -355.038104)
			(xy 412.133779 -355.002387) (xy 412.098067 -354.961169) (xy 412.068585 -354.915288) (xy 412.045931 -354.865679)
			(xy 412.030567 -354.81335) (xy 412.022806 -354.759368) (xy 403.52248 -354.759368) (xy 403.52248 -354.759371)
			(xy 403.514718 -354.813357) (xy 403.499352 -354.865689) (xy 403.476694 -354.915301) (xy 403.447206 -354.961183)
			(xy 403.411488 -355.002402) (xy 403.370267 -355.038118) (xy 403.324383 -355.067603) (xy 403.27477 -355.090259)
			(xy 403.222437 -355.105622) (xy 403.168451 -355.113382) (xy 403.14118 -355.113844) (xy 402.27758 -355.113844)
			(xy 402.25031 -355.113392) (xy 402.196326 -355.105628) (xy 402.143997 -355.09026) (xy 402.094387 -355.067602)
			(xy 402.048506 -355.038114) (xy 402.007289 -355.002397) (xy 401.971574 -354.961178) (xy 401.942089 -354.915296)
			(xy 401.919433 -354.865685) (xy 401.904068 -354.813354) (xy 401.896306 -354.75937) (xy 400.413458 -354.75937)
			(xy 400.405697 -354.813346) (xy 400.390333 -354.865672) (xy 400.36768 -354.915278) (xy 400.338197 -354.961156)
			(xy 400.302486 -355.002371) (xy 400.261272 -355.038085) (xy 400.215396 -355.06757) (xy 400.165791 -355.090226)
			(xy 400.113466 -355.105593) (xy 400.059487 -355.113356) (xy 400.03222 -355.113844) (xy 399.16862 -355.113844)
			(xy 399.141347 -355.113418) (xy 399.087355 -355.105658) (xy 399.035018 -355.090292) (xy 398.9854 -355.067635)
			(xy 398.939511 -355.038146) (xy 398.898287 -355.002427) (xy 398.862566 -354.961205) (xy 398.833075 -354.915318)
			(xy 398.810415 -354.865701) (xy 398.795047 -354.813364) (xy 398.787284 -354.759373) (xy 397.30458 -354.759373)
			(xy 397.296818 -354.813359) (xy 397.28145 -354.865693) (xy 397.258791 -354.915306) (xy 397.229301 -354.96119)
			(xy 397.193581 -355.002409) (xy 397.152358 -355.038125) (xy 397.106471 -355.06761) (xy 397.056855 -355.090264)
			(xy 397.00452 -355.105626) (xy 396.950532 -355.113383) (xy 396.92326 -355.113844) (xy 396.05966 -355.113844)
			(xy 396.032391 -355.113391) (xy 395.978409 -355.105624) (xy 395.926082 -355.090255) (xy 395.876475 -355.067595)
			(xy 395.830597 -355.038107) (xy 395.789382 -355.00239) (xy 395.753669 -354.961171) (xy 395.724186 -354.91529)
			(xy 395.701531 -354.86568) (xy 395.686167 -354.813351) (xy 395.678406 -354.759369) (xy 394.195558 -354.759369)
			(xy 394.187796 -354.813349) (xy 394.172432 -354.865676) (xy 394.149777 -354.915284) (xy 394.120292 -354.961163)
			(xy 394.084578 -355.002378) (xy 394.043363 -355.038092) (xy 393.997484 -355.067577) (xy 393.947876 -355.090232)
			(xy 393.895549 -355.105596) (xy 393.841568 -355.113358) (xy 393.8143 -355.113844) (xy 392.9507 -355.113844)
			(xy 392.923429 -355.113394) (xy 392.869443 -355.105631) (xy 392.817111 -355.090265) (xy 392.767499 -355.067608)
			(xy 392.721616 -355.038121) (xy 392.680396 -355.002404) (xy 392.644679 -354.961184) (xy 392.615192 -354.915301)
			(xy 392.592535 -354.865689) (xy 392.577169 -354.813357) (xy 392.569406 -354.759371) (xy 391.086557 -354.759371)
			(xy 391.078797 -354.813344) (xy 391.063435 -354.865668) (xy 391.040783 -354.915273) (xy 391.011302 -354.96115)
			(xy 390.975593 -355.002364) (xy 390.934382 -355.038078) (xy 390.888508 -355.067563) (xy 390.838905 -355.090221)
			(xy 390.786583 -355.105589) (xy 390.732606 -355.113355) (xy 390.70534 -355.113844) (xy 389.84174 -355.113844)
			(xy 389.814466 -355.113419) (xy 389.760472 -355.105661) (xy 389.708132 -355.090298) (xy 389.658512 -355.067641)
			(xy 389.612621 -355.038153) (xy 389.571394 -355.002434) (xy 389.535671 -354.961211) (xy 389.506178 -354.915324)
			(xy 389.483516 -354.865705) (xy 389.468147 -354.813367) (xy 389.460384 -354.759374) (xy 387.97768 -354.759374)
			(xy 387.969918 -354.813357) (xy 387.954552 -354.865689) (xy 387.931894 -354.915301) (xy 387.902406 -354.961183)
			(xy 387.866688 -355.002402) (xy 387.825467 -355.038118) (xy 387.779583 -355.067603) (xy 387.72997 -355.090259)
			(xy 387.677637 -355.105622) (xy 387.623651 -355.113382) (xy 387.59638 -355.113844) (xy 386.73278 -355.113844)
			(xy 386.70551 -355.113392) (xy 386.651526 -355.105628) (xy 386.599197 -355.09026) (xy 386.549587 -355.067602)
			(xy 386.503706 -355.038114) (xy 386.462489 -355.002397) (xy 386.426774 -354.961178) (xy 386.397289 -354.915296)
			(xy 386.374633 -354.865685) (xy 386.359268 -354.813354) (xy 386.351506 -354.75937) (xy 384.868658 -354.75937)
			(xy 384.860897 -354.813346) (xy 384.845533 -354.865672) (xy 384.82288 -354.915278) (xy 384.793397 -354.961156)
			(xy 384.757686 -355.002371) (xy 384.716472 -355.038085) (xy 384.670596 -355.06757) (xy 384.620991 -355.090226)
			(xy 384.568666 -355.105593) (xy 384.514687 -355.113356) (xy 384.48742 -355.113844) (xy 383.62382 -355.113844)
			(xy 383.596547 -355.113418) (xy 383.542555 -355.105658) (xy 383.490218 -355.090292) (xy 383.4406 -355.067635)
			(xy 383.394711 -355.038146) (xy 383.353487 -355.002427) (xy 383.317766 -354.961205) (xy 383.288275 -354.915318)
			(xy 383.265615 -354.865701) (xy 383.250247 -354.813364) (xy 383.242484 -354.759373) (xy 381.75978 -354.759373)
			(xy 381.752018 -354.813359) (xy 381.73665 -354.865693) (xy 381.713991 -354.915306) (xy 381.684501 -354.96119)
			(xy 381.648781 -355.002409) (xy 381.607558 -355.038125) (xy 381.561671 -355.06761) (xy 381.512055 -355.090264)
			(xy 381.45972 -355.105626) (xy 381.405732 -355.113383) (xy 381.37846 -355.113844) (xy 380.51486 -355.113844)
			(xy 380.487591 -355.113391) (xy 380.433609 -355.105624) (xy 380.381282 -355.090255) (xy 380.331675 -355.067595)
			(xy 380.285797 -355.038107) (xy 380.244582 -355.00239) (xy 380.208869 -354.961171) (xy 380.179386 -354.91529)
			(xy 380.156731 -354.86568) (xy 380.141367 -354.813351) (xy 380.133606 -354.759369) (xy 378.650758 -354.759369)
			(xy 378.642996 -354.813349) (xy 378.627632 -354.865676) (xy 378.604977 -354.915284) (xy 378.575492 -354.961163)
			(xy 378.539778 -355.002378) (xy 378.498563 -355.038092) (xy 378.452684 -355.067577) (xy 378.403076 -355.090232)
			(xy 378.350749 -355.105596) (xy 378.296768 -355.113358) (xy 378.2695 -355.113844) (xy 377.4059 -355.113844)
			(xy 377.378629 -355.113394) (xy 377.324643 -355.105631) (xy 377.272311 -355.090265) (xy 377.222699 -355.067608)
			(xy 377.176816 -355.038121) (xy 377.135596 -355.002404) (xy 377.099879 -354.961184) (xy 377.070392 -354.915301)
			(xy 377.047735 -354.865689) (xy 377.032369 -354.813357) (xy 377.024606 -354.759371) (xy 375.541757 -354.759371)
			(xy 375.533997 -354.813344) (xy 375.518635 -354.865668) (xy 375.495983 -354.915273) (xy 375.466502 -354.96115)
			(xy 375.430793 -355.002364) (xy 375.389582 -355.038078) (xy 375.343708 -355.067563) (xy 375.294105 -355.090221)
			(xy 375.241783 -355.105589) (xy 375.187806 -355.113355) (xy 375.16054 -355.113844) (xy 374.29694 -355.113844)
			(xy 374.269666 -355.113419) (xy 374.215672 -355.105661) (xy 374.163332 -355.090298) (xy 374.113712 -355.067641)
			(xy 374.067821 -355.038153) (xy 374.026594 -355.002434) (xy 373.990871 -354.961211) (xy 373.961378 -354.915324)
			(xy 373.938716 -354.865705) (xy 373.923347 -354.813367) (xy 373.915584 -354.759374) (xy 344.837257 -354.759374)
			(xy 344.829496 -354.813349) (xy 344.814132 -354.865675) (xy 344.791477 -354.915283) (xy 344.761993 -354.961161)
			(xy 344.72628 -355.002377) (xy 344.685065 -355.038091) (xy 344.639186 -355.067575) (xy 344.589579 -355.090231)
			(xy 344.537253 -355.105596) (xy 344.483272 -355.113357) (xy 344.456004 -355.113844) (xy 343.592404 -355.113844)
			(xy 343.565132 -355.113417) (xy 343.511142 -355.105655) (xy 343.458806 -355.090288) (xy 343.40919 -355.06763)
			(xy 343.363304 -355.038141) (xy 343.322081 -355.002422) (xy 343.286362 -354.961199) (xy 343.256872 -354.915313)
			(xy 343.234213 -354.865698) (xy 343.218846 -354.813362) (xy 343.211084 -354.759372) (xy 341.728257 -354.759372)
			(xy 341.720498 -354.813343) (xy 341.705135 -354.865667) (xy 341.682483 -354.915272) (xy 341.653003 -354.961148)
			(xy 341.617294 -355.002363) (xy 341.576084 -355.038076) (xy 341.53021 -355.067562) (xy 341.480608 -355.09022)
			(xy 341.428286 -355.105588) (xy 341.37431 -355.113355) (xy 341.347044 -355.113844) (xy 340.483444 -355.113844)
			(xy 340.45617 -355.113419) (xy 340.402175 -355.105662) (xy 340.349835 -355.090299) (xy 340.300214 -355.067643)
			(xy 340.254323 -355.038155) (xy 340.213095 -355.002436) (xy 340.177371 -354.961213) (xy 340.147878 -354.915325)
			(xy 340.125217 -354.865706) (xy 340.109847 -354.813368) (xy 340.102084 -354.759374) (xy 338.61938 -354.759374)
			(xy 338.611618 -354.813356) (xy 338.596252 -354.865688) (xy 338.573594 -354.9153) (xy 338.544107 -354.961182)
			(xy 338.508389 -355.0024) (xy 338.467169 -355.038116) (xy 338.421285 -355.067602) (xy 338.371673 -355.090258)
			(xy 338.319341 -355.105622) (xy 338.265354 -355.113382) (xy 338.238084 -355.113844) (xy 337.374484 -355.113844)
			(xy 337.347214 -355.113392) (xy 337.29323 -355.105629) (xy 337.2409 -355.090261) (xy 337.191289 -355.067603)
			(xy 337.145408 -355.038115) (xy 337.10419 -355.002398) (xy 337.068475 -354.961179) (xy 337.038989 -354.915297)
			(xy 337.016333 -354.865685) (xy 337.000968 -354.813355) (xy 336.993206 -354.75937) (xy 335.510358 -354.75937)
			(xy 335.502597 -354.813346) (xy 335.487234 -354.865671) (xy 335.46458 -354.915277) (xy 335.435098 -354.961155)
			(xy 335.399387 -355.00237) (xy 335.358174 -355.038084) (xy 335.312298 -355.067569) (xy 335.262694 -355.090225)
			(xy 335.210369 -355.105592) (xy 335.156391 -355.113356) (xy 335.129124 -355.113844) (xy 334.265524 -355.113844)
			(xy 334.238251 -355.113418) (xy 334.184259 -355.105658) (xy 334.131921 -355.090293) (xy 334.082302 -355.067636)
			(xy 334.036413 -355.038148) (xy 333.995188 -355.002429) (xy 333.959467 -354.961206) (xy 333.929975 -354.915319)
			(xy 333.907315 -354.865702) (xy 333.891947 -354.813365) (xy 333.884184 -354.759373) (xy 332.40148 -354.759373)
			(xy 332.393718 -354.813359) (xy 332.37835 -354.865692) (xy 332.355691 -354.915305) (xy 332.326202 -354.961188)
			(xy 332.290482 -355.002407) (xy 332.24926 -355.038123) (xy 332.203374 -355.067609) (xy 332.153758 -355.090263)
			(xy 332.101424 -355.105625) (xy 332.047435 -355.113383) (xy 332.020164 -355.113844) (xy 331.156564 -355.113844)
			(xy 331.129295 -355.113391) (xy 331.075313 -355.105625) (xy 331.022985 -355.090256) (xy 330.973377 -355.067596)
			(xy 330.927499 -355.038108) (xy 330.886283 -355.002391) (xy 330.85057 -354.961173) (xy 330.821086 -354.915291)
			(xy 330.798432 -354.865681) (xy 330.783067 -354.813352) (xy 330.775306 -354.759369) (xy 329.292458 -354.759369)
			(xy 329.284696 -354.813349) (xy 329.269332 -354.865675) (xy 329.246677 -354.915283) (xy 329.217193 -354.961161)
			(xy 329.18148 -355.002377) (xy 329.140265 -355.038091) (xy 329.094386 -355.067575) (xy 329.044779 -355.090231)
			(xy 328.992453 -355.105596) (xy 328.938472 -355.113357) (xy 328.911204 -355.113844) (xy 328.047604 -355.113844)
			(xy 328.020332 -355.113417) (xy 327.966342 -355.105655) (xy 327.914006 -355.090288) (xy 327.86439 -355.06763)
			(xy 327.818504 -355.038141) (xy 327.777281 -355.002422) (xy 327.741562 -354.961199) (xy 327.712072 -354.915313)
			(xy 327.689413 -354.865698) (xy 327.674046 -354.813362) (xy 327.666284 -354.759372) (xy 326.183457 -354.759372)
			(xy 326.175698 -354.813343) (xy 326.160335 -354.865667) (xy 326.137683 -354.915272) (xy 326.108203 -354.961148)
			(xy 326.072494 -355.002363) (xy 326.031284 -355.038076) (xy 325.98541 -355.067562) (xy 325.935808 -355.09022)
			(xy 325.883486 -355.105588) (xy 325.82951 -355.113355) (xy 325.802244 -355.113844) (xy 324.938644 -355.113844)
			(xy 324.91137 -355.113419) (xy 324.857375 -355.105662) (xy 324.805035 -355.090299) (xy 324.755414 -355.067643)
			(xy 324.709523 -355.038155) (xy 324.668295 -355.002436) (xy 324.632571 -354.961213) (xy 324.603078 -354.915325)
			(xy 324.580417 -354.865706) (xy 324.565047 -354.813368) (xy 324.557284 -354.759374) (xy 323.07458 -354.759374)
			(xy 323.066818 -354.813356) (xy 323.051452 -354.865688) (xy 323.028794 -354.9153) (xy 322.999307 -354.961182)
			(xy 322.963589 -355.0024) (xy 322.922369 -355.038116) (xy 322.876485 -355.067602) (xy 322.826873 -355.090258)
			(xy 322.774541 -355.105622) (xy 322.720554 -355.113382) (xy 322.693284 -355.113844) (xy 321.829684 -355.113844)
			(xy 321.802414 -355.113392) (xy 321.74843 -355.105629) (xy 321.6961 -355.090261) (xy 321.646489 -355.067603)
			(xy 321.600608 -355.038115) (xy 321.55939 -355.002398) (xy 321.523675 -354.961179) (xy 321.494189 -354.915297)
			(xy 321.471533 -354.865685) (xy 321.456168 -354.813355) (xy 321.448406 -354.75937) (xy 319.965558 -354.75937)
			(xy 319.957797 -354.813346) (xy 319.942434 -354.865671) (xy 319.91978 -354.915277) (xy 319.890298 -354.961155)
			(xy 319.854587 -355.00237) (xy 319.813374 -355.038084) (xy 319.767498 -355.067569) (xy 319.717894 -355.090225)
			(xy 319.665569 -355.105592) (xy 319.611591 -355.113356) (xy 319.584324 -355.113844) (xy 318.720724 -355.113844)
			(xy 318.693451 -355.113418) (xy 318.639459 -355.105658) (xy 318.587121 -355.090293) (xy 318.537502 -355.067636)
			(xy 318.491613 -355.038148) (xy 318.450388 -355.002429) (xy 318.414667 -354.961206) (xy 318.385175 -354.915319)
			(xy 318.362515 -354.865702) (xy 318.347147 -354.813365) (xy 318.339384 -354.759373) (xy 316.85668 -354.759373)
			(xy 316.848918 -354.813359) (xy 316.83355 -354.865692) (xy 316.810891 -354.915305) (xy 316.781402 -354.961188)
			(xy 316.745682 -355.002407) (xy 316.70446 -355.038123) (xy 316.658574 -355.067609) (xy 316.608958 -355.090263)
			(xy 316.556624 -355.105625) (xy 316.502635 -355.113383) (xy 316.475364 -355.113844) (xy 315.611764 -355.113844)
			(xy 315.584495 -355.113391) (xy 315.530513 -355.105625) (xy 315.478185 -355.090256) (xy 315.428577 -355.067596)
			(xy 315.382699 -355.038108) (xy 315.341483 -355.002391) (xy 315.30577 -354.961173) (xy 315.276286 -354.915291)
			(xy 315.253632 -354.865681) (xy 315.238267 -354.813352) (xy 315.230506 -354.759369) (xy 300.231558 -354.759369)
			(xy 300.223796 -354.813349) (xy 300.208432 -354.865676) (xy 300.185777 -354.915283) (xy 300.156293 -354.961162)
			(xy 300.120579 -355.002378) (xy 300.079364 -355.038091) (xy 300.033485 -355.067576) (xy 299.983878 -355.090231)
			(xy 299.931551 -355.105596) (xy 299.87757 -355.113357) (xy 299.850302 -355.113844) (xy 298.986702 -355.113844)
			(xy 298.95943 -355.113417) (xy 298.90544 -355.105654) (xy 298.853105 -355.090288) (xy 298.803489 -355.067629)
			(xy 298.757603 -355.03814) (xy 298.716381 -355.002421) (xy 298.680661 -354.961199) (xy 298.651172 -354.915313)
			(xy 298.628513 -354.865697) (xy 298.613146 -354.813362) (xy 298.605384 -354.759372) (xy 297.122557 -354.759372)
			(xy 297.114798 -354.813344) (xy 297.099435 -354.865667) (xy 297.076783 -354.915272) (xy 297.047302 -354.961149)
			(xy 297.011593 -355.002364) (xy 296.970383 -355.038077) (xy 296.924509 -355.067563) (xy 296.874907 -355.09022)
			(xy 296.822585 -355.105589) (xy 296.768608 -355.113355) (xy 296.741342 -355.113844) (xy 295.877742 -355.113844)
			(xy 295.850468 -355.113419) (xy 295.796474 -355.105662) (xy 295.744134 -355.090298) (xy 295.694513 -355.067642)
			(xy 295.648622 -355.038154) (xy 295.607395 -355.002435) (xy 295.571671 -354.961212) (xy 295.542178 -354.915324)
			(xy 295.519516 -354.865706) (xy 295.504147 -354.813367) (xy 295.496384 -354.759374) (xy 294.013681 -354.759374)
			(xy 294.005918 -354.813356) (xy 293.990552 -354.865688) (xy 293.967894 -354.9153) (xy 293.938406 -354.961182)
			(xy 293.902688 -355.002401) (xy 293.861468 -355.038117) (xy 293.815584 -355.067603) (xy 293.765971 -355.090258)
			(xy 293.713639 -355.105622) (xy 293.659653 -355.113382) (xy 293.632382 -355.113844) (xy 292.768782 -355.113844)
			(xy 292.741512 -355.113392) (xy 292.687528 -355.105628) (xy 292.635198 -355.090261) (xy 292.585588 -355.067602)
			(xy 292.539707 -355.038115) (xy 292.49849 -355.002398) (xy 292.462775 -354.961178) (xy 292.433289 -354.915296)
			(xy 292.410633 -354.865685) (xy 292.395268 -354.813354) (xy 292.387506 -354.75937) (xy 290.904658 -354.75937)
			(xy 290.896897 -354.813346) (xy 290.881533 -354.865672) (xy 290.85888 -354.915278) (xy 290.829397 -354.961156)
			(xy 290.793686 -355.002371) (xy 290.752473 -355.038084) (xy 290.706597 -355.067569) (xy 290.656992 -355.090226)
			(xy 290.604668 -355.105592) (xy 290.550689 -355.113356) (xy 290.523422 -355.113844) (xy 289.659822 -355.113844)
			(xy 289.632549 -355.113418) (xy 289.578557 -355.105658) (xy 289.526219 -355.090293) (xy 289.476601 -355.067636)
			(xy 289.430712 -355.038147) (xy 289.389488 -355.002428) (xy 289.353766 -354.961205) (xy 289.324275 -354.915318)
			(xy 289.301615 -354.865702) (xy 289.286247 -354.813365) (xy 289.278484 -354.759373) (xy 287.79578 -354.759373)
			(xy 287.788018 -354.813359) (xy 287.77265 -354.865692) (xy 287.749991 -354.915306) (xy 287.720501 -354.961189)
			(xy 287.684781 -355.002408) (xy 287.643559 -355.038124) (xy 287.597672 -355.067609) (xy 287.548057 -355.090264)
			(xy 287.495722 -355.105626) (xy 287.441733 -355.113383) (xy 287.414462 -355.113844) (xy 286.550862 -355.113844)
			(xy 286.523593 -355.113391) (xy 286.469611 -355.105625) (xy 286.417284 -355.090255) (xy 286.367676 -355.067596)
			(xy 286.321798 -355.038107) (xy 286.280583 -355.00239) (xy 286.24487 -354.961172) (xy 286.215386 -354.915291)
			(xy 286.192732 -354.865681) (xy 286.177367 -354.813352) (xy 286.169606 -354.759369) (xy 284.686758 -354.759369)
			(xy 284.678996 -354.813349) (xy 284.663632 -354.865676) (xy 284.640977 -354.915283) (xy 284.611493 -354.961162)
			(xy 284.575779 -355.002378) (xy 284.534564 -355.038091) (xy 284.488685 -355.067576) (xy 284.439078 -355.090231)
			(xy 284.386751 -355.105596) (xy 284.33277 -355.113357) (xy 284.305502 -355.113844) (xy 283.441902 -355.113844)
			(xy 283.41463 -355.113417) (xy 283.36064 -355.105654) (xy 283.308305 -355.090288) (xy 283.258689 -355.067629)
			(xy 283.212803 -355.03814) (xy 283.171581 -355.002421) (xy 283.135861 -354.961199) (xy 283.106372 -354.915313)
			(xy 283.083713 -354.865697) (xy 283.068346 -354.813362) (xy 283.060584 -354.759372) (xy 281.577757 -354.759372)
			(xy 281.569998 -354.813344) (xy 281.554635 -354.865667) (xy 281.531983 -354.915272) (xy 281.502502 -354.961149)
			(xy 281.466793 -355.002364) (xy 281.425583 -355.038077) (xy 281.379709 -355.067563) (xy 281.330107 -355.09022)
			(xy 281.277785 -355.105589) (xy 281.223808 -355.113355) (xy 281.196542 -355.113844) (xy 280.332942 -355.113844)
			(xy 280.305668 -355.113419) (xy 280.251674 -355.105662) (xy 280.199334 -355.090298) (xy 280.149713 -355.067642)
			(xy 280.103822 -355.038154) (xy 280.062595 -355.002435) (xy 280.026871 -354.961212) (xy 279.997378 -354.915324)
			(xy 279.974716 -354.865706) (xy 279.959347 -354.813367) (xy 279.951584 -354.759374) (xy 278.468881 -354.759374)
			(xy 278.461118 -354.813356) (xy 278.445752 -354.865688) (xy 278.423094 -354.9153) (xy 278.393606 -354.961182)
			(xy 278.357888 -355.002401) (xy 278.316668 -355.038117) (xy 278.270784 -355.067603) (xy 278.221171 -355.090258)
			(xy 278.168839 -355.105622) (xy 278.114853 -355.113382) (xy 278.087582 -355.113844) (xy 277.223982 -355.113844)
			(xy 277.196712 -355.113392) (xy 277.142728 -355.105628) (xy 277.090398 -355.090261) (xy 277.040788 -355.067602)
			(xy 276.994907 -355.038115) (xy 276.95369 -355.002398) (xy 276.917975 -354.961178) (xy 276.888489 -354.915296)
			(xy 276.865833 -354.865685) (xy 276.850468 -354.813354) (xy 276.842706 -354.75937) (xy 275.359858 -354.75937)
			(xy 275.352097 -354.813346) (xy 275.336733 -354.865672) (xy 275.31408 -354.915278) (xy 275.284597 -354.961156)
			(xy 275.248886 -355.002371) (xy 275.207673 -355.038084) (xy 275.161797 -355.067569) (xy 275.112192 -355.090226)
			(xy 275.059868 -355.105592) (xy 275.005889 -355.113356) (xy 274.978622 -355.113844) (xy 274.115022 -355.113844)
			(xy 274.087749 -355.113418) (xy 274.033757 -355.105658) (xy 273.981419 -355.090293) (xy 273.931801 -355.067636)
			(xy 273.885912 -355.038147) (xy 273.844688 -355.002428) (xy 273.808966 -354.961205) (xy 273.779475 -354.915318)
			(xy 273.756815 -354.865702) (xy 273.741447 -354.813365) (xy 273.733684 -354.759373) (xy 272.25098 -354.759373)
			(xy 272.243218 -354.813359) (xy 272.22785 -354.865692) (xy 272.205191 -354.915306) (xy 272.175701 -354.961189)
			(xy 272.139981 -355.002408) (xy 272.098759 -355.038124) (xy 272.052872 -355.067609) (xy 272.003257 -355.090264)
			(xy 271.950922 -355.105626) (xy 271.896933 -355.113383) (xy 271.869662 -355.113844) (xy 271.006062 -355.113844)
			(xy 270.978793 -355.113391) (xy 270.924811 -355.105625) (xy 270.872484 -355.090255) (xy 270.822876 -355.067596)
			(xy 270.776998 -355.038107) (xy 270.735783 -355.00239) (xy 270.70007 -354.961172) (xy 270.670586 -354.915291)
			(xy 270.647932 -354.865681) (xy 270.632567 -354.813352) (xy 270.624806 -354.759369) (xy 188.299268 -354.759369)
			(xy 188.294942 -354.78946) (xy 188.279575 -354.841794) (xy 188.256917 -354.891409) (xy 188.227428 -354.937294)
			(xy 188.191709 -354.978515) (xy 188.150487 -355.014233) (xy 188.104602 -355.04372) (xy 188.054987 -355.066378)
			(xy 188.002652 -355.081744) (xy 187.948664 -355.089505) (xy 187.921392 -355.089968) (xy 187.057792 -355.089968)
			(xy 187.030523 -355.089469) (xy 186.976542 -355.081707) (xy 186.924214 -355.066341) (xy 186.874605 -355.043684)
			(xy 186.828726 -355.014199) (xy 186.78751 -354.978484) (xy 186.751796 -354.937267) (xy 186.722312 -354.891388)
			(xy 186.699656 -354.841779) (xy 186.684292 -354.789451) (xy 186.67653 -354.735469) (xy 185.193682 -354.735469)
			(xy 185.185921 -354.78945) (xy 185.170557 -354.841778) (xy 185.147903 -354.891387) (xy 185.118419 -354.937267)
			(xy 185.082707 -354.978484) (xy 185.041492 -355.0142) (xy 184.995615 -355.043687) (xy 184.946008 -355.066346)
			(xy 184.893681 -355.081714) (xy 184.8397 -355.089479) (xy 184.812432 -355.089968) (xy 183.948832 -355.089968)
			(xy 183.92156 -355.089495) (xy 183.86757 -355.081736) (xy 183.815235 -355.066373) (xy 183.765618 -355.043718)
			(xy 183.719731 -355.014231) (xy 183.678508 -354.978515) (xy 183.642788 -354.937294) (xy 183.613298 -354.89141)
			(xy 183.590638 -354.841795) (xy 183.57527 -354.789461) (xy 183.567508 -354.735472) (xy 182.08478 -354.735472)
			(xy 182.08478 -354.759371) (xy 182.077018 -354.813358) (xy 182.061651 -354.86569) (xy 182.038992 -354.915303)
			(xy 182.009504 -354.961186) (xy 181.973785 -355.002405) (xy 181.932563 -355.03812) (xy 181.886678 -355.067606)
			(xy 181.837064 -355.090261) (xy 181.78473 -355.105624) (xy 181.730743 -355.113382) (xy 181.703472 -355.113844)
			(xy 180.839872 -355.113844) (xy 180.812603 -355.113392) (xy 180.75862 -355.105626) (xy 180.706291 -355.090258)
			(xy 180.656682 -355.067599) (xy 180.610802 -355.038111) (xy 180.569586 -355.002394) (xy 180.533872 -354.961175)
			(xy 180.504388 -354.915293) (xy 180.481732 -354.865683) (xy 180.466368 -354.813353) (xy 180.458606 -354.759369)
			(xy 178.975758 -354.759369) (xy 178.967997 -354.813348) (xy 178.952633 -354.865674) (xy 178.929978 -354.915281)
			(xy 178.900495 -354.961159) (xy 178.864783 -355.002374) (xy 178.823568 -355.038088) (xy 178.777691 -355.067573)
			(xy 178.728085 -355.090228) (xy 178.675759 -355.105594) (xy 178.62178 -355.113357) (xy 178.594512 -355.113844)
			(xy 177.730912 -355.113844) (xy 177.703639 -355.113417) (xy 177.649648 -355.105656) (xy 177.597312 -355.09029)
			(xy 177.547695 -355.067632) (xy 177.501808 -355.038144) (xy 177.460584 -355.002424) (xy 177.424864 -354.961202)
			(xy 177.395373 -354.915316) (xy 177.372714 -354.865699) (xy 177.357346 -354.813363) (xy 177.349584 -354.759373)
			(xy 175.86688 -354.759373) (xy 175.859117 -354.81336) (xy 175.843749 -354.865694) (xy 175.821089 -354.915309)
			(xy 175.791599 -354.961192) (xy 175.755878 -355.002412) (xy 175.714654 -355.038128) (xy 175.668766 -355.067612)
			(xy 175.619149 -355.090266) (xy 175.566813 -355.105628) (xy 175.512824 -355.113384) (xy 175.485552 -355.113844)
			(xy 174.621952 -355.113844) (xy 174.594684 -355.11339) (xy 174.540703 -355.105623) (xy 174.488376 -355.090252)
			(xy 174.43877 -355.067592) (xy 174.392893 -355.038104) (xy 174.351679 -355.002387) (xy 174.315967 -354.961169)
			(xy 174.286485 -354.915288) (xy 174.263831 -354.865679) (xy 174.248467 -354.81335) (xy 174.240706 -354.759368)
			(xy 172.757881 -354.759368) (xy 172.757881 -354.75937) (xy 172.750119 -354.813355) (xy 172.734753 -354.865686)
			(xy 172.712096 -354.915297) (xy 172.682609 -354.961179) (xy 172.646892 -355.002398) (xy 172.605673 -355.038113)
			(xy 172.55979 -355.067599) (xy 172.510178 -355.090255) (xy 172.457847 -355.10562) (xy 172.403862 -355.113381)
			(xy 172.376592 -355.113844) (xy 171.512992 -355.113844) (xy 171.485722 -355.113393) (xy 171.431736 -355.10563)
			(xy 171.379405 -355.090263) (xy 171.329794 -355.067606) (xy 171.283912 -355.038118) (xy 171.242693 -355.002401)
			(xy 171.206977 -354.961182) (xy 171.177491 -354.915299) (xy 171.154834 -354.865687) (xy 171.139468 -354.813356)
			(xy 171.131706 -354.75937) (xy 169.648858 -354.75937) (xy 169.641097 -354.813345) (xy 169.625734 -354.865669)
			(xy 169.603081 -354.915275) (xy 169.5736 -354.961152) (xy 169.53789 -355.002367) (xy 169.496678 -355.038081)
			(xy 169.450803 -355.067566) (xy 169.401199 -355.090223) (xy 169.348876 -355.10559) (xy 169.294899 -355.113355)
			(xy 169.267632 -355.113844) (xy 168.404032 -355.113844) (xy 168.376758 -355.113419) (xy 168.322765 -355.10566)
			(xy 168.270426 -355.090296) (xy 168.220807 -355.067639) (xy 168.174917 -355.038151) (xy 168.133691 -355.002432)
			(xy 168.097969 -354.961209) (xy 168.068477 -354.915321) (xy 168.045816 -354.865704) (xy 168.030447 -354.813366)
			(xy 168.022684 -354.759374) (xy 166.53998 -354.759374) (xy 166.532218 -354.813358) (xy 166.516851 -354.86569)
			(xy 166.494192 -354.915303) (xy 166.464704 -354.961186) (xy 166.428985 -355.002405) (xy 166.387763 -355.03812)
			(xy 166.341878 -355.067606) (xy 166.292264 -355.090261) (xy 166.23993 -355.105624) (xy 166.185943 -355.113382)
			(xy 166.158672 -355.113844) (xy 165.295072 -355.113844) (xy 165.267803 -355.113392) (xy 165.21382 -355.105626)
			(xy 165.161491 -355.090258) (xy 165.111882 -355.067599) (xy 165.066002 -355.038111) (xy 165.024786 -355.002394)
			(xy 164.989072 -354.961175) (xy 164.959588 -354.915293) (xy 164.936932 -354.865683) (xy 164.921568 -354.813353)
			(xy 164.913806 -354.759369) (xy 163.430958 -354.759369) (xy 163.423197 -354.813348) (xy 163.407833 -354.865674)
			(xy 163.385178 -354.915281) (xy 163.355695 -354.961159) (xy 163.319983 -355.002374) (xy 163.278768 -355.038088)
			(xy 163.232891 -355.067573) (xy 163.183285 -355.090228) (xy 163.130959 -355.105594) (xy 163.07698 -355.113357)
			(xy 163.049712 -355.113844) (xy 162.186112 -355.113844) (xy 162.158839 -355.113417) (xy 162.104848 -355.105656)
			(xy 162.052512 -355.09029) (xy 162.002895 -355.067632) (xy 161.957008 -355.038144) (xy 161.915784 -355.002424)
			(xy 161.880064 -354.961202) (xy 161.850573 -354.915316) (xy 161.827914 -354.865699) (xy 161.812546 -354.813363)
			(xy 161.804784 -354.759373) (xy 160.32208 -354.759373) (xy 160.314317 -354.81336) (xy 160.298949 -354.865694)
			(xy 160.276289 -354.915309) (xy 160.246799 -354.961192) (xy 160.211078 -355.002412) (xy 160.169854 -355.038128)
			(xy 160.123966 -355.067612) (xy 160.074349 -355.090266) (xy 160.022013 -355.105628) (xy 159.968024 -355.113384)
			(xy 159.940752 -355.113844) (xy 159.077152 -355.113844) (xy 159.049884 -355.11339) (xy 158.995903 -355.105623)
			(xy 158.943576 -355.090252) (xy 158.89397 -355.067592) (xy 158.848093 -355.038104) (xy 158.806879 -355.002387)
			(xy 158.771167 -354.961169) (xy 158.741685 -354.915288) (xy 158.719031 -354.865679) (xy 158.703667 -354.81335)
			(xy 158.695906 -354.759368) (xy 144.196558 -354.759368) (xy 144.188797 -354.813348) (xy 144.173432 -354.865675)
			(xy 144.150778 -354.915282) (xy 144.121294 -354.96116) (xy 144.085581 -355.002376) (xy 144.044367 -355.038089)
			(xy 143.998489 -355.067574) (xy 143.948882 -355.09023) (xy 143.896556 -355.105595) (xy 143.842576 -355.113357)
			(xy 143.815308 -355.113844) (xy 142.951708 -355.113844) (xy 142.924435 -355.113417) (xy 142.870445 -355.105655)
			(xy 142.818109 -355.090289) (xy 142.768492 -355.067631) (xy 142.722606 -355.038142) (xy 142.681383 -355.002423)
			(xy 142.645663 -354.961201) (xy 142.616173 -354.915315) (xy 142.593514 -354.865699) (xy 142.578146 -354.813363)
			(xy 142.570384 -354.759373) (xy 141.087557 -354.759373) (xy 141.079798 -354.813343) (xy 141.064436 -354.865666)
			(xy 141.041784 -354.915271) (xy 141.012304 -354.961147) (xy 140.976595 -355.002361) (xy 140.935386 -355.038075)
			(xy 140.889513 -355.067561) (xy 140.839911 -355.090219) (xy 140.78759 -355.105587) (xy 140.733614 -355.113354)
			(xy 140.706348 -355.113844) (xy 139.842748 -355.113844) (xy 139.815473 -355.11342) (xy 139.761479 -355.105663)
			(xy 139.709138 -355.0903) (xy 139.659516 -355.067644) (xy 139.613625 -355.038156) (xy 139.572397 -355.002437)
			(xy 139.536672 -354.961214) (xy 139.507179 -354.915326) (xy 139.484517 -354.865707) (xy 139.469147 -354.813368)
			(xy 139.461384 -354.759374) (xy 137.97868 -354.759374) (xy 137.970918 -354.813356) (xy 137.955552 -354.865687)
			(xy 137.932895 -354.915298) (xy 137.903408 -354.961181) (xy 137.867691 -355.002399) (xy 137.826471 -355.038115)
			(xy 137.780588 -355.067601) (xy 137.730976 -355.090256) (xy 137.678644 -355.105621) (xy 137.624658 -355.113381)
			(xy 137.597388 -355.113844) (xy 136.733788 -355.113844) (xy 136.706518 -355.113393) (xy 136.652533 -355.105629)
			(xy 136.600203 -355.090262) (xy 136.550591 -355.067604) (xy 136.50471 -355.038117) (xy 136.463492 -355.0024)
			(xy 136.427776 -354.96118) (xy 136.39829 -354.915298) (xy 136.375634 -354.865686) (xy 136.360268 -354.813355)
			(xy 136.352506 -354.75937) (xy 134.869658 -354.75937) (xy 134.861897 -354.813345) (xy 134.846534 -354.86567)
			(xy 134.823881 -354.915276) (xy 134.794399 -354.961154) (xy 134.758688 -355.002369) (xy 134.717476 -355.038082)
			(xy 134.671601 -355.067567) (xy 134.621997 -355.090224) (xy 134.569673 -355.105591) (xy 134.515695 -355.113356)
			(xy 134.488428 -355.113844) (xy 133.624828 -355.113844) (xy 133.597554 -355.113418) (xy 133.543562 -355.105659)
			(xy 133.491223 -355.090295) (xy 133.441604 -355.067638) (xy 133.395715 -355.038149) (xy 133.35449 -355.00243)
			(xy 133.318768 -354.961207) (xy 133.289276 -354.91532) (xy 133.266615 -354.865703) (xy 133.251247 -354.813365)
			(xy 133.243484 -354.759374) (xy 131.76078 -354.759374) (xy 131.753018 -354.813358) (xy 131.737651 -354.865691)
			(xy 131.714992 -354.915304) (xy 131.685503 -354.961187) (xy 131.649783 -355.002406) (xy 131.608561 -355.038122)
			(xy 131.562676 -355.067607) (xy 131.513061 -355.090262) (xy 131.460727 -355.105625) (xy 131.406739 -355.113383)
			(xy 131.379468 -355.113844) (xy 130.515868 -355.113844) (xy 130.488599 -355.113391) (xy 130.434616 -355.105626)
			(xy 130.382288 -355.090257) (xy 130.33268 -355.067598) (xy 130.2868 -355.03811) (xy 130.245585 -355.002393)
			(xy 130.209871 -354.961174) (xy 130.180387 -354.915292) (xy 130.157732 -354.865682) (xy 130.142368 -354.813353)
			(xy 130.134606 -354.759369) (xy 128.651758 -354.759369) (xy 128.643997 -354.813348) (xy 128.628632 -354.865675)
			(xy 128.605978 -354.915282) (xy 128.576494 -354.96116) (xy 128.540781 -355.002376) (xy 128.499567 -355.038089)
			(xy 128.453689 -355.067574) (xy 128.404082 -355.09023) (xy 128.351756 -355.105595) (xy 128.297776 -355.113357)
			(xy 128.270508 -355.113844) (xy 127.406908 -355.113844) (xy 127.379635 -355.113417) (xy 127.325645 -355.105655)
			(xy 127.273309 -355.090289) (xy 127.223692 -355.067631) (xy 127.177806 -355.038142) (xy 127.136583 -355.002423)
			(xy 127.100863 -354.961201) (xy 127.071373 -354.915315) (xy 127.048714 -354.865699) (xy 127.033346 -354.813363)
			(xy 127.025584 -354.759373) (xy 125.542757 -354.759373) (xy 125.534998 -354.813343) (xy 125.519636 -354.865666)
			(xy 125.496984 -354.915271) (xy 125.467504 -354.961147) (xy 125.431795 -355.002361) (xy 125.390586 -355.038075)
			(xy 125.344713 -355.067561) (xy 125.295111 -355.090219) (xy 125.24279 -355.105587) (xy 125.188814 -355.113354)
			(xy 125.161548 -355.113844) (xy 124.297948 -355.113844) (xy 124.270673 -355.11342) (xy 124.216679 -355.105663)
			(xy 124.164338 -355.0903) (xy 124.114716 -355.067644) (xy 124.068825 -355.038156) (xy 124.027597 -355.002437)
			(xy 123.991872 -354.961214) (xy 123.962379 -354.915326) (xy 123.939717 -354.865707) (xy 123.924347 -354.813368)
			(xy 123.916584 -354.759374) (xy 122.43388 -354.759374) (xy 122.426118 -354.813356) (xy 122.410752 -354.865687)
			(xy 122.388095 -354.915298) (xy 122.358608 -354.961181) (xy 122.322891 -355.002399) (xy 122.281671 -355.038115)
			(xy 122.235788 -355.067601) (xy 122.186176 -355.090256) (xy 122.133844 -355.105621) (xy 122.079858 -355.113381)
			(xy 122.052588 -355.113844) (xy 121.188988 -355.113844) (xy 121.161718 -355.113393) (xy 121.107733 -355.105629)
			(xy 121.055403 -355.090262) (xy 121.005791 -355.067604) (xy 120.95991 -355.038117) (xy 120.918692 -355.0024)
			(xy 120.882976 -354.96118) (xy 120.85349 -354.915298) (xy 120.830834 -354.865686) (xy 120.815468 -354.813355)
			(xy 120.807706 -354.75937) (xy 119.324858 -354.75937) (xy 119.317097 -354.813345) (xy 119.301734 -354.86567)
			(xy 119.279081 -354.915276) (xy 119.249599 -354.961154) (xy 119.213888 -355.002369) (xy 119.172676 -355.038082)
			(xy 119.126801 -355.067567) (xy 119.077197 -355.090224) (xy 119.024873 -355.105591) (xy 118.970895 -355.113356)
			(xy 118.943628 -355.113844) (xy 118.080028 -355.113844) (xy 118.052754 -355.113418) (xy 117.998762 -355.105659)
			(xy 117.946423 -355.090295) (xy 117.896804 -355.067638) (xy 117.850915 -355.038149) (xy 117.80969 -355.00243)
			(xy 117.773968 -354.961207) (xy 117.744476 -354.91532) (xy 117.721815 -354.865703) (xy 117.706447 -354.813365)
			(xy 117.698684 -354.759374) (xy 116.21598 -354.759374) (xy 116.208218 -354.813358) (xy 116.192851 -354.865691)
			(xy 116.170192 -354.915304) (xy 116.140703 -354.961187) (xy 116.104983 -355.002406) (xy 116.063761 -355.038122)
			(xy 116.017876 -355.067607) (xy 115.968261 -355.090262) (xy 115.915927 -355.105625) (xy 115.861939 -355.113383)
			(xy 115.834668 -355.113844) (xy 114.971068 -355.113844) (xy 114.943799 -355.113391) (xy 114.889816 -355.105626)
			(xy 114.837488 -355.090257) (xy 114.78788 -355.067598) (xy 114.742 -355.03811) (xy 114.700785 -355.002393)
			(xy 114.665071 -354.961174) (xy 114.635587 -354.915292) (xy 114.612932 -354.865682) (xy 114.597568 -354.813353)
			(xy 114.589806 -354.759369) (xy 93.706658 -354.759369) (xy 93.698898 -354.813344) (xy 93.683535 -354.865667)
			(xy 93.660883 -354.915272) (xy 93.631402 -354.961149) (xy 93.595693 -355.002364) (xy 93.554483 -355.038077)
			(xy 93.508609 -355.067563) (xy 93.459007 -355.09022) (xy 93.406685 -355.105589) (xy 93.352708 -355.113355)
			(xy 93.325442 -355.113844) (xy 92.461842 -355.113844) (xy 92.434568 -355.113419) (xy 92.380574 -355.105662)
			(xy 92.328234 -355.090298) (xy 92.278613 -355.067642) (xy 92.232722 -355.038154) (xy 92.191495 -355.002435)
			(xy 92.155771 -354.961212) (xy 92.126278 -354.915324) (xy 92.103616 -354.865706) (xy 92.088247 -354.813367)
			(xy 92.080484 -354.759374) (xy 90.597781 -354.759374) (xy 90.590018 -354.813356) (xy 90.574652 -354.865688)
			(xy 90.551994 -354.9153) (xy 90.522506 -354.961182) (xy 90.486788 -355.002401) (xy 90.445568 -355.038117)
			(xy 90.399684 -355.067603) (xy 90.350071 -355.090258) (xy 90.297739 -355.105622) (xy 90.243753 -355.113382)
			(xy 90.216482 -355.113844) (xy 89.352882 -355.113844) (xy 89.325612 -355.113392) (xy 89.271628 -355.105628)
			(xy 89.219298 -355.090261) (xy 89.169688 -355.067602) (xy 89.123807 -355.038115) (xy 89.08259 -355.002398)
			(xy 89.046875 -354.961178) (xy 89.017389 -354.915296) (xy 88.994733 -354.865685) (xy 88.979368 -354.813354)
			(xy 88.971606 -354.75937) (xy 87.488758 -354.75937) (xy 87.480997 -354.813346) (xy 87.465633 -354.865672)
			(xy 87.44298 -354.915278) (xy 87.413497 -354.961156) (xy 87.377786 -355.002371) (xy 87.336573 -355.038084)
			(xy 87.290697 -355.067569) (xy 87.241092 -355.090226) (xy 87.188768 -355.105592) (xy 87.134789 -355.113356)
			(xy 87.107522 -355.113844) (xy 86.243922 -355.113844) (xy 86.216649 -355.113418) (xy 86.162657 -355.105658)
			(xy 86.110319 -355.090293) (xy 86.060701 -355.067636) (xy 86.014812 -355.038147) (xy 85.973588 -355.002428)
			(xy 85.937866 -354.961205) (xy 85.908375 -354.915318) (xy 85.885715 -354.865702) (xy 85.870347 -354.813365)
			(xy 85.862584 -354.759373) (xy 84.37988 -354.759373) (xy 84.372118 -354.813359) (xy 84.35675 -354.865692)
			(xy 84.334091 -354.915306) (xy 84.304601 -354.961189) (xy 84.268881 -355.002408) (xy 84.227659 -355.038124)
			(xy 84.181772 -355.067609) (xy 84.132157 -355.090264) (xy 84.079822 -355.105626) (xy 84.025833 -355.113383)
			(xy 83.998562 -355.113844) (xy 83.134962 -355.113844) (xy 83.107693 -355.113391) (xy 83.053711 -355.105625)
			(xy 83.001384 -355.090255) (xy 82.951776 -355.067596) (xy 82.905898 -355.038107) (xy 82.864683 -355.00239)
			(xy 82.82897 -354.961172) (xy 82.799486 -354.915291) (xy 82.776832 -354.865681) (xy 82.761467 -354.813352)
			(xy 82.753706 -354.759369) (xy 81.270858 -354.759369) (xy 81.263096 -354.813349) (xy 81.247732 -354.865676)
			(xy 81.225077 -354.915283) (xy 81.195593 -354.961162) (xy 81.159879 -355.002378) (xy 81.118664 -355.038091)
			(xy 81.072785 -355.067576) (xy 81.023178 -355.090231) (xy 80.970851 -355.105596) (xy 80.91687 -355.113357)
			(xy 80.889602 -355.113844) (xy 80.026002 -355.113844) (xy 79.99873 -355.113417) (xy 79.94474 -355.105654)
			(xy 79.892405 -355.090288) (xy 79.842789 -355.067629) (xy 79.796903 -355.03814) (xy 79.755681 -355.002421)
			(xy 79.719961 -354.961199) (xy 79.690472 -354.915313) (xy 79.667813 -354.865697) (xy 79.652446 -354.813362)
			(xy 79.644684 -354.759372) (xy 78.161857 -354.759372) (xy 78.154098 -354.813344) (xy 78.138735 -354.865667)
			(xy 78.116083 -354.915272) (xy 78.086602 -354.961149) (xy 78.050893 -355.002364) (xy 78.009683 -355.038077)
			(xy 77.963809 -355.067563) (xy 77.914207 -355.09022) (xy 77.861885 -355.105589) (xy 77.807908 -355.113355)
			(xy 77.780642 -355.113844) (xy 76.917042 -355.113844) (xy 76.889768 -355.113419) (xy 76.835774 -355.105662)
			(xy 76.783434 -355.090298) (xy 76.733813 -355.067642) (xy 76.687922 -355.038154) (xy 76.646695 -355.002435)
			(xy 76.610971 -354.961212) (xy 76.581478 -354.915324) (xy 76.558816 -354.865706) (xy 76.543447 -354.813367)
			(xy 76.535684 -354.759374) (xy 75.052981 -354.759374) (xy 75.045218 -354.813356) (xy 75.029852 -354.865688)
			(xy 75.007194 -354.9153) (xy 74.977706 -354.961182) (xy 74.941988 -355.002401) (xy 74.900768 -355.038117)
			(xy 74.854884 -355.067603) (xy 74.805271 -355.090258) (xy 74.752939 -355.105622) (xy 74.698953 -355.113382)
			(xy 74.671682 -355.113844) (xy 73.808082 -355.113844) (xy 73.780812 -355.113392) (xy 73.726828 -355.105628)
			(xy 73.674498 -355.090261) (xy 73.624888 -355.067602) (xy 73.579007 -355.038115) (xy 73.53779 -355.002398)
			(xy 73.502075 -354.961178) (xy 73.472589 -354.915296) (xy 73.449933 -354.865685) (xy 73.434568 -354.813354)
			(xy 73.426806 -354.75937) (xy 71.943958 -354.75937) (xy 71.936197 -354.813346) (xy 71.920833 -354.865672)
			(xy 71.89818 -354.915278) (xy 71.868697 -354.961156) (xy 71.832986 -355.002371) (xy 71.791773 -355.038084)
			(xy 71.745897 -355.067569) (xy 71.696292 -355.090226) (xy 71.643968 -355.105592) (xy 71.589989 -355.113356)
			(xy 71.562722 -355.113844) (xy 70.699122 -355.113844) (xy 70.671849 -355.113418) (xy 70.617857 -355.105658)
			(xy 70.565519 -355.090293) (xy 70.515901 -355.067636) (xy 70.470012 -355.038147) (xy 70.428788 -355.002428)
			(xy 70.393066 -354.961205) (xy 70.363575 -354.915318) (xy 70.340915 -354.865702) (xy 70.325547 -354.813365)
			(xy 70.317784 -354.759373) (xy 68.83508 -354.759373) (xy 68.827318 -354.813359) (xy 68.81195 -354.865692)
			(xy 68.789291 -354.915306) (xy 68.759801 -354.961189) (xy 68.724081 -355.002408) (xy 68.682859 -355.038124)
			(xy 68.636972 -355.067609) (xy 68.587357 -355.090264) (xy 68.535022 -355.105626) (xy 68.481033 -355.113383)
			(xy 68.453762 -355.113844) (xy 67.590162 -355.113844) (xy 67.562893 -355.113391) (xy 67.508911 -355.105625)
			(xy 67.456584 -355.090255) (xy 67.406976 -355.067596) (xy 67.361098 -355.038107) (xy 67.319883 -355.00239)
			(xy 67.28417 -354.961172) (xy 67.254686 -354.915291) (xy 67.232032 -354.865681) (xy 67.216667 -354.813352)
			(xy 67.208906 -354.759369) (xy 65.726058 -354.759369) (xy 65.718296 -354.813349) (xy 65.702932 -354.865676)
			(xy 65.680277 -354.915283) (xy 65.650793 -354.961162) (xy 65.615079 -355.002378) (xy 65.573864 -355.038091)
			(xy 65.527985 -355.067576) (xy 65.478378 -355.090231) (xy 65.426051 -355.105596) (xy 65.37207 -355.113357)
			(xy 65.344802 -355.113844) (xy 64.481202 -355.113844) (xy 64.45393 -355.113417) (xy 64.39994 -355.105654)
			(xy 64.347605 -355.090288) (xy 64.297989 -355.067629) (xy 64.252103 -355.03814) (xy 64.210881 -355.002421)
			(xy 64.175161 -354.961199) (xy 64.145672 -354.915313) (xy 64.123013 -354.865697) (xy 64.107646 -354.813362)
			(xy 64.099884 -354.759372) (xy 51.666857 -354.759372) (xy 51.659098 -354.813343) (xy 51.643736 -354.865666)
			(xy 51.621084 -354.915271) (xy 51.591604 -354.961147) (xy 51.555895 -355.002361) (xy 51.514686 -355.038075)
			(xy 51.468813 -355.067561) (xy 51.419211 -355.090219) (xy 51.36689 -355.105587) (xy 51.312914 -355.113354)
			(xy 51.285648 -355.113844) (xy 50.422048 -355.113844) (xy 50.394773 -355.11342) (xy 50.340779 -355.105663)
			(xy 50.288438 -355.0903) (xy 50.238816 -355.067644) (xy 50.192925 -355.038156) (xy 50.151697 -355.002437)
			(xy 50.115972 -354.961214) (xy 50.086479 -354.915326) (xy 50.063817 -354.865707) (xy 50.048447 -354.813368)
			(xy 50.040684 -354.759374) (xy 48.55798 -354.759374) (xy 48.550218 -354.813356) (xy 48.534852 -354.865687)
			(xy 48.512195 -354.915298) (xy 48.482708 -354.961181) (xy 48.446991 -355.002399) (xy 48.405771 -355.038115)
			(xy 48.359888 -355.067601) (xy 48.310276 -355.090256) (xy 48.257944 -355.105621) (xy 48.203958 -355.113381)
			(xy 48.176688 -355.113844) (xy 47.313088 -355.113844) (xy 47.285818 -355.113393) (xy 47.231833 -355.105629)
			(xy 47.179503 -355.090262) (xy 47.129891 -355.067604) (xy 47.08401 -355.038117) (xy 47.042792 -355.0024)
			(xy 47.007076 -354.96118) (xy 46.97759 -354.915298) (xy 46.954934 -354.865686) (xy 46.939568 -354.813355)
			(xy 46.931806 -354.75937) (xy 45.448958 -354.75937) (xy 45.441197 -354.813345) (xy 45.425834 -354.86567)
			(xy 45.403181 -354.915276) (xy 45.373699 -354.961154) (xy 45.337988 -355.002369) (xy 45.296776 -355.038082)
			(xy 45.250901 -355.067567) (xy 45.201297 -355.090224) (xy 45.148973 -355.105591) (xy 45.094995 -355.113356)
			(xy 45.067728 -355.113844) (xy 44.204128 -355.113844) (xy 44.176854 -355.113418) (xy 44.122862 -355.105659)
			(xy 44.070523 -355.090295) (xy 44.020904 -355.067638) (xy 43.975015 -355.038149) (xy 43.93379 -355.00243)
			(xy 43.898068 -354.961207) (xy 43.868576 -354.91532) (xy 43.845915 -354.865703) (xy 43.830547 -354.813365)
			(xy 43.822784 -354.759374) (xy 42.34008 -354.759374) (xy 42.332318 -354.813358) (xy 42.316951 -354.865691)
			(xy 42.294292 -354.915304) (xy 42.264803 -354.961187) (xy 42.229083 -355.002406) (xy 42.187861 -355.038122)
			(xy 42.141976 -355.067607) (xy 42.092361 -355.090262) (xy 42.040027 -355.105625) (xy 41.986039 -355.113383)
			(xy 41.958768 -355.113844) (xy 41.095168 -355.113844) (xy 41.067899 -355.113391) (xy 41.013916 -355.105626)
			(xy 40.961588 -355.090257) (xy 40.91198 -355.067598) (xy 40.8661 -355.03811) (xy 40.824885 -355.002393)
			(xy 40.789171 -354.961174) (xy 40.759687 -354.915292) (xy 40.737032 -354.865682) (xy 40.721668 -354.813353)
			(xy 40.713906 -354.759369) (xy 39.231058 -354.759369) (xy 39.223297 -354.813348) (xy 39.207932 -354.865675)
			(xy 39.185278 -354.915282) (xy 39.155794 -354.96116) (xy 39.120081 -355.002376) (xy 39.078867 -355.038089)
			(xy 39.032989 -355.067574) (xy 38.983382 -355.09023) (xy 38.931056 -355.105595) (xy 38.877076 -355.113357)
			(xy 38.849808 -355.113844) (xy 37.986208 -355.113844) (xy 37.958935 -355.113417) (xy 37.904945 -355.105655)
			(xy 37.852609 -355.090289) (xy 37.802992 -355.067631) (xy 37.757106 -355.038142) (xy 37.715883 -355.002423)
			(xy 37.680163 -354.961201) (xy 37.650673 -354.915315) (xy 37.628014 -354.865699) (xy 37.612646 -354.813363)
			(xy 37.604884 -354.759373) (xy 36.122057 -354.759373) (xy 36.114298 -354.813343) (xy 36.098936 -354.865666)
			(xy 36.076284 -354.915271) (xy 36.046804 -354.961147) (xy 36.011095 -355.002361) (xy 35.969886 -355.038075)
			(xy 35.924013 -355.067561) (xy 35.874411 -355.090219) (xy 35.82209 -355.105587) (xy 35.768114 -355.113354)
			(xy 35.740848 -355.113844) (xy 34.877248 -355.113844) (xy 34.849973 -355.11342) (xy 34.795979 -355.105663)
			(xy 34.743638 -355.0903) (xy 34.694016 -355.067644) (xy 34.648125 -355.038156) (xy 34.606897 -355.002437)
			(xy 34.571172 -354.961214) (xy 34.541679 -354.915326) (xy 34.519017 -354.865707) (xy 34.503647 -354.813368)
			(xy 34.495884 -354.759374) (xy 33.01318 -354.759374) (xy 33.005418 -354.813356) (xy 32.990052 -354.865687)
			(xy 32.967395 -354.915298) (xy 32.937908 -354.961181) (xy 32.902191 -355.002399) (xy 32.860971 -355.038115)
			(xy 32.815088 -355.067601) (xy 32.765476 -355.090256) (xy 32.713144 -355.105621) (xy 32.659158 -355.113381)
			(xy 32.631888 -355.113844) (xy 31.768288 -355.113844) (xy 31.741018 -355.113393) (xy 31.687033 -355.105629)
			(xy 31.634703 -355.090262) (xy 31.585091 -355.067604) (xy 31.53921 -355.038117) (xy 31.497992 -355.0024)
			(xy 31.462276 -354.96118) (xy 31.43279 -354.915298) (xy 31.410134 -354.865686) (xy 31.394768 -354.813355)
			(xy 31.387006 -354.75937) (xy 29.904158 -354.75937) (xy 29.896397 -354.813345) (xy 29.881034 -354.86567)
			(xy 29.858381 -354.915276) (xy 29.828899 -354.961154) (xy 29.793188 -355.002369) (xy 29.751976 -355.038082)
			(xy 29.706101 -355.067567) (xy 29.656497 -355.090224) (xy 29.604173 -355.105591) (xy 29.550195 -355.113356)
			(xy 29.522928 -355.113844) (xy 28.659328 -355.113844) (xy 28.632054 -355.113418) (xy 28.578062 -355.105659)
			(xy 28.525723 -355.090295) (xy 28.476104 -355.067638) (xy 28.430215 -355.038149) (xy 28.38899 -355.00243)
			(xy 28.353268 -354.961207) (xy 28.323776 -354.91532) (xy 28.301115 -354.865703) (xy 28.285747 -354.813365)
			(xy 28.277984 -354.759374) (xy 26.79528 -354.759374) (xy 26.787518 -354.813358) (xy 26.772151 -354.865691)
			(xy 26.749492 -354.915304) (xy 26.720003 -354.961187) (xy 26.684283 -355.002406) (xy 26.643061 -355.038122)
			(xy 26.597176 -355.067607) (xy 26.547561 -355.090262) (xy 26.495227 -355.105625) (xy 26.441239 -355.113383)
			(xy 26.413968 -355.113844) (xy 25.550368 -355.113844) (xy 25.523099 -355.113391) (xy 25.469116 -355.105626)
			(xy 25.416788 -355.090257) (xy 25.36718 -355.067598) (xy 25.3213 -355.03811) (xy 25.280085 -355.002393)
			(xy 25.244371 -354.961174) (xy 25.214887 -354.915292) (xy 25.192232 -354.865682) (xy 25.176868 -354.813353)
			(xy 25.169106 -354.759369) (xy 23.686258 -354.759369) (xy 23.678497 -354.813348) (xy 23.663132 -354.865675)
			(xy 23.640478 -354.915282) (xy 23.610994 -354.96116) (xy 23.575281 -355.002376) (xy 23.534067 -355.038089)
			(xy 23.488189 -355.067574) (xy 23.438582 -355.09023) (xy 23.386256 -355.105595) (xy 23.332276 -355.113357)
			(xy 23.305008 -355.113844) (xy 22.441408 -355.113844) (xy 22.414135 -355.113417) (xy 22.360145 -355.105655)
			(xy 22.307809 -355.090289) (xy 22.258192 -355.067631) (xy 22.212306 -355.038142) (xy 22.171083 -355.002423)
			(xy 22.135363 -354.961201) (xy 22.105873 -354.915315) (xy 22.083214 -354.865699) (xy 22.067846 -354.813363)
			(xy 22.060084 -354.759373) (xy 0.509016 -354.759373) (xy 0.509016 -357.784969) (xy 22.060131 -357.784969)
			(xy 22.060131 -357.730431) (xy 22.067893 -357.676447) (xy 22.083259 -357.624118) (xy 22.105915 -357.574508)
			(xy 22.135401 -357.528628) (xy 22.171117 -357.487411) (xy 22.212334 -357.451696) (xy 22.258215 -357.422211)
			(xy 22.307826 -357.399556) (xy 22.360155 -357.384191) (xy 22.414139 -357.376431) (xy 22.441408 -357.375968)
			(xy 23.305008 -357.375968) (xy 23.332279 -357.376395) (xy 23.386266 -357.384158) (xy 23.438599 -357.399525)
			(xy 23.488212 -357.422184) (xy 23.534095 -357.451672) (xy 23.575315 -357.48739) (xy 23.611032 -357.528611)
			(xy 23.64052 -357.574495) (xy 23.663177 -357.624109) (xy 23.678543 -357.676442) (xy 23.686306 -357.730429)
			(xy 23.686306 -357.784966) (xy 25.169154 -357.784966) (xy 25.169154 -357.730434) (xy 25.176914 -357.676458)
			(xy 25.192277 -357.624135) (xy 25.214929 -357.574531) (xy 25.24441 -357.528655) (xy 25.280119 -357.487441)
			(xy 25.321329 -357.451729) (xy 25.367203 -357.422244) (xy 25.416805 -357.399588) (xy 25.469126 -357.384221)
			(xy 25.523102 -357.376457) (xy 25.550368 -357.375968) (xy 26.413968 -357.375968) (xy 26.441243 -357.376369)
			(xy 26.495237 -357.384128) (xy 26.547578 -357.399493) (xy 26.597199 -357.422151) (xy 26.64309 -357.45164)
			(xy 26.684317 -357.48736) (xy 26.720041 -357.528584) (xy 26.749534 -357.574473) (xy 26.772196 -357.624092)
			(xy 26.787565 -357.676431) (xy 26.795328 -357.730425) (xy 26.795328 -357.78497) (xy 28.278031 -357.78497)
			(xy 28.278032 -357.73043) (xy 28.285794 -357.676445) (xy 28.30116 -357.624114) (xy 28.323818 -357.574503)
			(xy 28.353306 -357.528621) (xy 28.389024 -357.487404) (xy 28.430244 -357.451689) (xy 28.476127 -357.422205)
			(xy 28.52574 -357.39955) (xy 28.578072 -357.384188) (xy 28.632058 -357.37643) (xy 28.659328 -357.375968)
			(xy 29.522928 -357.375968) (xy 29.550198 -357.376396) (xy 29.604183 -357.384162) (xy 29.656513 -357.399531)
			(xy 29.706124 -357.42219) (xy 29.752005 -357.451679) (xy 29.793222 -357.487397) (xy 29.828937 -357.528618)
			(xy 29.858423 -357.574501) (xy 29.881079 -357.624113) (xy 29.896444 -357.676444) (xy 29.904206 -357.73043)
			(xy 29.904206 -357.784967) (xy 31.387054 -357.784967) (xy 31.387054 -357.730433) (xy 31.394815 -357.676455)
			(xy 31.410179 -357.624131) (xy 31.432832 -357.574525) (xy 31.462315 -357.528648) (xy 31.498026 -357.487434)
			(xy 31.539239 -357.451722) (xy 31.585115 -357.422238) (xy 31.634719 -357.399583) (xy 31.687043 -357.384218)
			(xy 31.741021 -357.376455) (xy 31.768288 -357.375968) (xy 32.631888 -357.375968) (xy 32.659162 -357.376371)
			(xy 32.713154 -357.384132) (xy 32.765492 -357.399499) (xy 32.815111 -357.422157) (xy 32.861 -357.451647)
			(xy 32.902224 -357.487367) (xy 32.937946 -357.528591) (xy 32.967437 -357.574479) (xy 32.990097 -357.624096)
			(xy 33.005465 -357.676434) (xy 33.013228 -357.730426) (xy 33.013228 -357.784971) (xy 34.495932 -357.784971)
			(xy 34.495932 -357.730429) (xy 34.503694 -357.676442) (xy 34.519062 -357.62411) (xy 34.541721 -357.574497)
			(xy 34.571211 -357.528615) (xy 34.606931 -357.487397) (xy 34.648153 -357.451682) (xy 34.694039 -357.422198)
			(xy 34.743655 -357.399545) (xy 34.795989 -357.384184) (xy 34.849977 -357.376428) (xy 34.877248 -357.375968)
			(xy 35.740848 -357.375968) (xy 35.768117 -357.376398) (xy 35.8221 -357.384166) (xy 35.874428 -357.399536)
			(xy 35.924036 -357.422197) (xy 35.969914 -357.451687) (xy 36.011129 -357.487405) (xy 36.046842 -357.528624)
			(xy 36.076326 -357.574506) (xy 36.09898 -357.624117) (xy 36.114345 -357.676447) (xy 36.122106 -357.730431)
			(xy 36.122106 -357.784969) (xy 37.604931 -357.784969) (xy 37.604931 -357.730431) (xy 37.612693 -357.676447)
			(xy 37.628059 -357.624118) (xy 37.650715 -357.574508) (xy 37.680201 -357.528628) (xy 37.715917 -357.487411)
			(xy 37.757134 -357.451696) (xy 37.803015 -357.422211) (xy 37.852626 -357.399556) (xy 37.904955 -357.384191)
			(xy 37.958939 -357.376431) (xy 37.986208 -357.375968) (xy 38.849808 -357.375968) (xy 38.877079 -357.376395)
			(xy 38.931066 -357.384158) (xy 38.983399 -357.399525) (xy 39.033012 -357.422184) (xy 39.078895 -357.451672)
			(xy 39.120115 -357.48739) (xy 39.155832 -357.528611) (xy 39.18532 -357.574495) (xy 39.207977 -357.624109)
			(xy 39.223343 -357.676442) (xy 39.231106 -357.730429) (xy 39.231106 -357.784966) (xy 40.713954 -357.784966)
			(xy 40.713954 -357.730434) (xy 40.721714 -357.676458) (xy 40.737077 -357.624135) (xy 40.759729 -357.574531)
			(xy 40.78921 -357.528655) (xy 40.824919 -357.487441) (xy 40.866129 -357.451729) (xy 40.912003 -357.422244)
			(xy 40.961605 -357.399588) (xy 41.013926 -357.384221) (xy 41.067902 -357.376457) (xy 41.095168 -357.375968)
			(xy 41.958768 -357.375968) (xy 41.986043 -357.376369) (xy 42.040037 -357.384128) (xy 42.092378 -357.399493)
			(xy 42.141999 -357.422151) (xy 42.18789 -357.45164) (xy 42.229117 -357.48736) (xy 42.264841 -357.528584)
			(xy 42.294334 -357.574473) (xy 42.316996 -357.624092) (xy 42.332365 -357.676431) (xy 42.340128 -357.730425)
			(xy 42.340128 -357.78497) (xy 43.822831 -357.78497) (xy 43.822832 -357.73043) (xy 43.830594 -357.676445)
			(xy 43.84596 -357.624114) (xy 43.868618 -357.574503) (xy 43.898106 -357.528621) (xy 43.933824 -357.487404)
			(xy 43.975044 -357.451689) (xy 44.020927 -357.422205) (xy 44.07054 -357.39955) (xy 44.122872 -357.384188)
			(xy 44.176858 -357.37643) (xy 44.204128 -357.375968) (xy 45.067728 -357.375968) (xy 45.094998 -357.376396)
			(xy 45.148983 -357.384162) (xy 45.201313 -357.399531) (xy 45.250924 -357.42219) (xy 45.296805 -357.451679)
			(xy 45.338022 -357.487397) (xy 45.373737 -357.528618) (xy 45.403223 -357.574501) (xy 45.425879 -357.624113)
			(xy 45.441244 -357.676444) (xy 45.449006 -357.73043) (xy 45.449006 -357.784967) (xy 46.931854 -357.784967)
			(xy 46.931854 -357.730433) (xy 46.939615 -357.676455) (xy 46.954979 -357.624131) (xy 46.977632 -357.574525)
			(xy 47.007115 -357.528648) (xy 47.042826 -357.487434) (xy 47.084039 -357.451722) (xy 47.129915 -357.422238)
			(xy 47.179519 -357.399583) (xy 47.231843 -357.384218) (xy 47.285821 -357.376455) (xy 47.313088 -357.375968)
			(xy 48.176688 -357.375968) (xy 48.203962 -357.376371) (xy 48.257954 -357.384132) (xy 48.310292 -357.399499)
			(xy 48.359911 -357.422157) (xy 48.4058 -357.451647) (xy 48.447024 -357.487367) (xy 48.482746 -357.528591)
			(xy 48.512237 -357.574479) (xy 48.534897 -357.624096) (xy 48.550265 -357.676434) (xy 48.558028 -357.730426)
			(xy 48.558028 -357.784971) (xy 50.040732 -357.784971) (xy 50.040732 -357.730429) (xy 50.048494 -357.676442)
			(xy 50.063862 -357.62411) (xy 50.086521 -357.574497) (xy 50.116011 -357.528615) (xy 50.151731 -357.487397)
			(xy 50.192953 -357.451682) (xy 50.238839 -357.422198) (xy 50.288455 -357.399545) (xy 50.340789 -357.384184)
			(xy 50.394777 -357.376428) (xy 50.422048 -357.375968) (xy 51.285648 -357.375968) (xy 51.312917 -357.376398)
			(xy 51.3669 -357.384166) (xy 51.419228 -357.399536) (xy 51.468836 -357.422197) (xy 51.514714 -357.451687)
			(xy 51.555929 -357.487405) (xy 51.591642 -357.528624) (xy 51.621126 -357.574506) (xy 51.64378 -357.624117)
			(xy 51.659145 -357.676447) (xy 51.666906 -357.730431) (xy 51.666906 -357.784969) (xy 64.099931 -357.784969)
			(xy 64.099931 -357.730431) (xy 64.107693 -357.676448) (xy 64.123058 -357.62412) (xy 64.145714 -357.57451)
			(xy 64.1752 -357.52863) (xy 64.210914 -357.487413) (xy 64.252132 -357.451698) (xy 64.298012 -357.422213)
			(xy 64.347621 -357.399557) (xy 64.39995 -357.384193) (xy 64.453933 -357.376431) (xy 64.481202 -357.375968)
			(xy 65.344802 -357.375968) (xy 65.372073 -357.376395) (xy 65.426061 -357.384157) (xy 65.478394 -357.399524)
			(xy 65.528008 -357.422182) (xy 65.573893 -357.45167) (xy 65.615113 -357.487388) (xy 65.650831 -357.528609)
			(xy 65.680319 -357.574493) (xy 65.702977 -357.624107) (xy 65.718343 -357.676441) (xy 65.726106 -357.730429)
			(xy 65.726106 -357.784966) (xy 67.208954 -357.784966) (xy 67.208954 -357.730435) (xy 67.216714 -357.676458)
			(xy 67.232077 -357.624136) (xy 67.254728 -357.574532) (xy 67.284208 -357.528657) (xy 67.319917 -357.487443)
			(xy 67.361126 -357.451731) (xy 67.406999 -357.422246) (xy 67.4566 -357.39959) (xy 67.508921 -357.384222)
			(xy 67.562897 -357.376457) (xy 67.590162 -357.375968) (xy 68.453762 -357.375968) (xy 68.481037 -357.376369)
			(xy 68.535032 -357.384127) (xy 68.587373 -357.399491) (xy 68.636995 -357.422149) (xy 68.682887 -357.451638)
			(xy 68.724115 -357.487358) (xy 68.75984 -357.528582) (xy 68.789333 -357.574471) (xy 68.811995 -357.624091)
			(xy 68.827365 -357.676431) (xy 68.835128 -357.730425) (xy 68.835128 -357.78497) (xy 70.317831 -357.78497)
			(xy 70.317831 -357.73043) (xy 70.325594 -357.676446) (xy 70.34096 -357.624115) (xy 70.363617 -357.574505)
			(xy 70.393105 -357.528623) (xy 70.428822 -357.487406) (xy 70.470041 -357.451691) (xy 70.515924 -357.422207)
			(xy 70.565536 -357.399552) (xy 70.617867 -357.384189) (xy 70.671852 -357.37643) (xy 70.699122 -357.375968)
			(xy 71.562722 -357.375968) (xy 71.589992 -357.376396) (xy 71.643978 -357.384161) (xy 71.696309 -357.399529)
			(xy 71.74592 -357.422189) (xy 71.791802 -357.451677) (xy 71.83302 -357.487395) (xy 71.868736 -357.528616)
			(xy 71.898222 -357.574499) (xy 71.920878 -357.624112) (xy 71.936244 -357.676444) (xy 71.944006 -357.730429)
			(xy 71.944006 -357.784966) (xy 73.426854 -357.784966) (xy 73.426854 -357.730434) (xy 73.434615 -357.676456)
			(xy 73.449978 -357.624132) (xy 73.472631 -357.574527) (xy 73.502113 -357.52865) (xy 73.537824 -357.487436)
			(xy 73.579036 -357.451724) (xy 73.624911 -357.42224) (xy 73.674515 -357.399584) (xy 73.726838 -357.384219)
			(xy 73.780816 -357.376456) (xy 73.808082 -357.375968) (xy 74.671682 -357.375968) (xy 74.698956 -357.37637)
			(xy 74.752949 -357.384131) (xy 74.805288 -357.399497) (xy 74.854907 -357.422155) (xy 74.900797 -357.451645)
			(xy 74.942022 -357.487365) (xy 74.977744 -357.528589) (xy 75.007236 -357.574477) (xy 75.029897 -357.624095)
			(xy 75.045265 -357.676433) (xy 75.053028 -357.730426) (xy 75.053028 -357.784971) (xy 76.535732 -357.784971)
			(xy 76.535732 -357.730429) (xy 76.543494 -357.676443) (xy 76.558861 -357.624111) (xy 76.58152 -357.574499)
			(xy 76.611009 -357.528617) (xy 76.646729 -357.487399) (xy 76.687951 -357.451684) (xy 76.733836 -357.4222)
			(xy 76.78345 -357.399547) (xy 76.835784 -357.384185) (xy 76.889771 -357.376429) (xy 76.917042 -357.375968)
			(xy 77.780642 -357.375968) (xy 77.807912 -357.376397) (xy 77.861895 -357.384165) (xy 77.914223 -357.399535)
			(xy 77.963832 -357.422195) (xy 78.009711 -357.451684) (xy 78.050927 -357.487402) (xy 78.086641 -357.528622)
			(xy 78.116125 -357.574505) (xy 78.13878 -357.624116) (xy 78.154144 -357.676446) (xy 78.161906 -357.73043)
			(xy 78.161906 -357.784969) (xy 79.644731 -357.784969) (xy 79.644731 -357.730431) (xy 79.652493 -357.676448)
			(xy 79.667858 -357.62412) (xy 79.690514 -357.57451) (xy 79.72 -357.52863) (xy 79.755714 -357.487413)
			(xy 79.796932 -357.451698) (xy 79.842812 -357.422213) (xy 79.892421 -357.399557) (xy 79.94475 -357.384193)
			(xy 79.998733 -357.376431) (xy 80.026002 -357.375968) (xy 80.889602 -357.375968) (xy 80.916873 -357.376395)
			(xy 80.970861 -357.384157) (xy 81.023194 -357.399524) (xy 81.072808 -357.422182) (xy 81.118693 -357.45167)
			(xy 81.159913 -357.487388) (xy 81.195631 -357.528609) (xy 81.225119 -357.574493) (xy 81.247777 -357.624107)
			(xy 81.263143 -357.676441) (xy 81.270906 -357.730429) (xy 81.270906 -357.784966) (xy 82.753754 -357.784966)
			(xy 82.753754 -357.730435) (xy 82.761514 -357.676458) (xy 82.776877 -357.624136) (xy 82.799528 -357.574532)
			(xy 82.829008 -357.528657) (xy 82.864717 -357.487443) (xy 82.905926 -357.451731) (xy 82.951799 -357.422246)
			(xy 83.0014 -357.39959) (xy 83.053721 -357.384222) (xy 83.107697 -357.376457) (xy 83.134962 -357.375968)
			(xy 83.998562 -357.375968) (xy 84.025837 -357.376369) (xy 84.079832 -357.384127) (xy 84.132173 -357.399491)
			(xy 84.181795 -357.422149) (xy 84.227687 -357.451638) (xy 84.268915 -357.487358) (xy 84.30464 -357.528582)
			(xy 84.334133 -357.574471) (xy 84.356795 -357.624091) (xy 84.372165 -357.676431) (xy 84.379928 -357.730425)
			(xy 84.379928 -357.78497) (xy 85.862631 -357.78497) (xy 85.862631 -357.73043) (xy 85.870394 -357.676446)
			(xy 85.88576 -357.624115) (xy 85.908417 -357.574505) (xy 85.937905 -357.528623) (xy 85.973622 -357.487406)
			(xy 86.014841 -357.451691) (xy 86.060724 -357.422207) (xy 86.110336 -357.399552) (xy 86.162667 -357.384189)
			(xy 86.216652 -357.37643) (xy 86.243922 -357.375968) (xy 87.107522 -357.375968) (xy 87.134792 -357.376396)
			(xy 87.188778 -357.384161) (xy 87.241109 -357.399529) (xy 87.29072 -357.422189) (xy 87.336602 -357.451677)
			(xy 87.37782 -357.487395) (xy 87.413536 -357.528616) (xy 87.443022 -357.574499) (xy 87.465678 -357.624112)
			(xy 87.481044 -357.676444) (xy 87.488806 -357.730429) (xy 87.488806 -357.784966) (xy 88.971654 -357.784966)
			(xy 88.971654 -357.730434) (xy 88.979415 -357.676456) (xy 88.994778 -357.624132) (xy 89.017431 -357.574527)
			(xy 89.046913 -357.52865) (xy 89.082624 -357.487436) (xy 89.123836 -357.451724) (xy 89.169711 -357.42224)
			(xy 89.219315 -357.399584) (xy 89.271638 -357.384219) (xy 89.325616 -357.376456) (xy 89.352882 -357.375968)
			(xy 90.216482 -357.375968) (xy 90.243756 -357.37637) (xy 90.297749 -357.384131) (xy 90.350088 -357.399497)
			(xy 90.399707 -357.422155) (xy 90.445597 -357.451645) (xy 90.486822 -357.487365) (xy 90.522544 -357.528589)
			(xy 90.552036 -357.574477) (xy 90.574697 -357.624095) (xy 90.590065 -357.676433) (xy 90.597828 -357.730426)
			(xy 90.597828 -357.784971) (xy 92.080532 -357.784971) (xy 92.080532 -357.730429) (xy 92.088294 -357.676443)
			(xy 92.103661 -357.624111) (xy 92.12632 -357.574499) (xy 92.155809 -357.528617) (xy 92.191529 -357.487399)
			(xy 92.232751 -357.451684) (xy 92.278636 -357.4222) (xy 92.32825 -357.399547) (xy 92.380584 -357.384185)
			(xy 92.434571 -357.376429) (xy 92.461842 -357.375968) (xy 93.325442 -357.375968) (xy 93.352712 -357.376397)
			(xy 93.406695 -357.384165) (xy 93.459023 -357.399535) (xy 93.508632 -357.422195) (xy 93.554511 -357.451684)
			(xy 93.595727 -357.487402) (xy 93.631441 -357.528622) (xy 93.660925 -357.574505) (xy 93.68358 -357.624116)
			(xy 93.698944 -357.676446) (xy 93.706706 -357.73043) (xy 93.706706 -357.784966) (xy 114.589854 -357.784966)
			(xy 114.589854 -357.730434) (xy 114.597614 -357.676458) (xy 114.612977 -357.624135) (xy 114.635629 -357.574531)
			(xy 114.66511 -357.528655) (xy 114.700819 -357.487441) (xy 114.742029 -357.451729) (xy 114.787903 -357.422244)
			(xy 114.837505 -357.399588) (xy 114.889826 -357.384221) (xy 114.943802 -357.376457) (xy 114.971068 -357.375968)
			(xy 115.834668 -357.375968) (xy 115.861943 -357.376369) (xy 115.915937 -357.384128) (xy 115.968278 -357.399493)
			(xy 116.017899 -357.422151) (xy 116.06379 -357.45164) (xy 116.105017 -357.48736) (xy 116.140741 -357.528584)
			(xy 116.170234 -357.574473) (xy 116.192896 -357.624092) (xy 116.208265 -357.676431) (xy 116.216028 -357.730425)
			(xy 116.216028 -357.78497) (xy 117.698731 -357.78497) (xy 117.698732 -357.73043) (xy 117.706494 -357.676445)
			(xy 117.72186 -357.624114) (xy 117.744518 -357.574503) (xy 117.774006 -357.528621) (xy 117.809724 -357.487404)
			(xy 117.850944 -357.451689) (xy 117.896827 -357.422205) (xy 117.94644 -357.39955) (xy 117.998772 -357.384188)
			(xy 118.052758 -357.37643) (xy 118.080028 -357.375968) (xy 118.943628 -357.375968) (xy 118.970898 -357.376396)
			(xy 119.024883 -357.384162) (xy 119.077213 -357.399531) (xy 119.126824 -357.42219) (xy 119.172705 -357.451679)
			(xy 119.213922 -357.487397) (xy 119.249637 -357.528618) (xy 119.279123 -357.574501) (xy 119.301779 -357.624113)
			(xy 119.317144 -357.676444) (xy 119.324906 -357.73043) (xy 119.324906 -357.784967) (xy 120.807754 -357.784967)
			(xy 120.807754 -357.730433) (xy 120.815515 -357.676455) (xy 120.830879 -357.624131) (xy 120.853532 -357.574525)
			(xy 120.883015 -357.528648) (xy 120.918726 -357.487434) (xy 120.959939 -357.451722) (xy 121.005815 -357.422238)
			(xy 121.055419 -357.399583) (xy 121.107743 -357.384218) (xy 121.161721 -357.376455) (xy 121.188988 -357.375968)
			(xy 122.052588 -357.375968) (xy 122.079862 -357.376371) (xy 122.133854 -357.384132) (xy 122.186192 -357.399499)
			(xy 122.235811 -357.422157) (xy 122.2817 -357.451647) (xy 122.322924 -357.487367) (xy 122.358646 -357.528591)
			(xy 122.388137 -357.574479) (xy 122.410797 -357.624096) (xy 122.426165 -357.676434) (xy 122.433928 -357.730426)
			(xy 122.433928 -357.784971) (xy 123.916632 -357.784971) (xy 123.916632 -357.730429) (xy 123.924394 -357.676442)
			(xy 123.939762 -357.62411) (xy 123.962421 -357.574497) (xy 123.991911 -357.528615) (xy 124.027631 -357.487397)
			(xy 124.068853 -357.451682) (xy 124.114739 -357.422198) (xy 124.164355 -357.399545) (xy 124.216689 -357.384184)
			(xy 124.270677 -357.376428) (xy 124.297948 -357.375968) (xy 125.161548 -357.375968) (xy 125.188817 -357.376398)
			(xy 125.2428 -357.384166) (xy 125.295128 -357.399536) (xy 125.344736 -357.422197) (xy 125.390614 -357.451687)
			(xy 125.431829 -357.487405) (xy 125.467542 -357.528624) (xy 125.497026 -357.574506) (xy 125.51968 -357.624117)
			(xy 125.535045 -357.676447) (xy 125.542806 -357.730431) (xy 125.542806 -357.784969) (xy 127.025631 -357.784969)
			(xy 127.025631 -357.730431) (xy 127.033393 -357.676447) (xy 127.048759 -357.624118) (xy 127.071415 -357.574508)
			(xy 127.100901 -357.528628) (xy 127.136617 -357.487411) (xy 127.177834 -357.451696) (xy 127.223715 -357.422211)
			(xy 127.273326 -357.399556) (xy 127.325655 -357.384191) (xy 127.379639 -357.376431) (xy 127.406908 -357.375968)
			(xy 128.270508 -357.375968) (xy 128.297779 -357.376395) (xy 128.351766 -357.384158) (xy 128.404099 -357.399525)
			(xy 128.453712 -357.422184) (xy 128.499595 -357.451672) (xy 128.540815 -357.48739) (xy 128.576532 -357.528611)
			(xy 128.60602 -357.574495) (xy 128.628677 -357.624109) (xy 128.644043 -357.676442) (xy 128.651806 -357.730429)
			(xy 128.651806 -357.784966) (xy 130.134654 -357.784966) (xy 130.134654 -357.730434) (xy 130.142414 -357.676458)
			(xy 130.157777 -357.624135) (xy 130.180429 -357.574531) (xy 130.20991 -357.528655) (xy 130.245619 -357.487441)
			(xy 130.286829 -357.451729) (xy 130.332703 -357.422244) (xy 130.382305 -357.399588) (xy 130.434626 -357.384221)
			(xy 130.488602 -357.376457) (xy 130.515868 -357.375968) (xy 131.379468 -357.375968) (xy 131.406743 -357.376369)
			(xy 131.460737 -357.384128) (xy 131.513078 -357.399493) (xy 131.562699 -357.422151) (xy 131.60859 -357.45164)
			(xy 131.649817 -357.48736) (xy 131.685541 -357.528584) (xy 131.715034 -357.574473) (xy 131.737696 -357.624092)
			(xy 131.753065 -357.676431) (xy 131.760828 -357.730425) (xy 131.760828 -357.78497) (xy 133.243531 -357.78497)
			(xy 133.243532 -357.73043) (xy 133.251294 -357.676445) (xy 133.26666 -357.624114) (xy 133.289318 -357.574503)
			(xy 133.318806 -357.528621) (xy 133.354524 -357.487404) (xy 133.395744 -357.451689) (xy 133.441627 -357.422205)
			(xy 133.49124 -357.39955) (xy 133.543572 -357.384188) (xy 133.597558 -357.37643) (xy 133.624828 -357.375968)
			(xy 134.488428 -357.375968) (xy 134.515698 -357.376396) (xy 134.569683 -357.384162) (xy 134.622013 -357.399531)
			(xy 134.671624 -357.42219) (xy 134.717505 -357.451679) (xy 134.758722 -357.487397) (xy 134.794437 -357.528618)
			(xy 134.823923 -357.574501) (xy 134.846579 -357.624113) (xy 134.861944 -357.676444) (xy 134.869706 -357.73043)
			(xy 134.869706 -357.784967) (xy 136.352554 -357.784967) (xy 136.352554 -357.730433) (xy 136.360315 -357.676455)
			(xy 136.375679 -357.624131) (xy 136.398332 -357.574525) (xy 136.427815 -357.528648) (xy 136.463526 -357.487434)
			(xy 136.504739 -357.451722) (xy 136.550615 -357.422238) (xy 136.600219 -357.399583) (xy 136.652543 -357.384218)
			(xy 136.706521 -357.376455) (xy 136.733788 -357.375968) (xy 137.597388 -357.375968) (xy 137.624662 -357.376371)
			(xy 137.678654 -357.384132) (xy 137.730992 -357.399499) (xy 137.780611 -357.422157) (xy 137.8265 -357.451647)
			(xy 137.867724 -357.487367) (xy 137.903446 -357.528591) (xy 137.932937 -357.574479) (xy 137.955597 -357.624096)
			(xy 137.970965 -357.676434) (xy 137.978728 -357.730426) (xy 137.978728 -357.784971) (xy 139.461432 -357.784971)
			(xy 139.461432 -357.730429) (xy 139.469194 -357.676442) (xy 139.484562 -357.62411) (xy 139.507221 -357.574497)
			(xy 139.536711 -357.528615) (xy 139.572431 -357.487397) (xy 139.613653 -357.451682) (xy 139.659539 -357.422198)
			(xy 139.709155 -357.399545) (xy 139.761489 -357.384184) (xy 139.815477 -357.376428) (xy 139.842748 -357.375968)
			(xy 140.706348 -357.375968) (xy 140.733617 -357.376398) (xy 140.7876 -357.384166) (xy 140.839928 -357.399536)
			(xy 140.889536 -357.422197) (xy 140.935414 -357.451687) (xy 140.976629 -357.487405) (xy 141.012342 -357.528624)
			(xy 141.041826 -357.574506) (xy 141.06448 -357.624117) (xy 141.079845 -357.676447) (xy 141.087606 -357.730431)
			(xy 141.087606 -357.784969) (xy 142.570431 -357.784969) (xy 142.570431 -357.730431) (xy 142.578193 -357.676447)
			(xy 142.593559 -357.624118) (xy 142.616215 -357.574508) (xy 142.645701 -357.528628) (xy 142.681417 -357.487411)
			(xy 142.722634 -357.451696) (xy 142.768515 -357.422211) (xy 142.818126 -357.399556) (xy 142.870455 -357.384191)
			(xy 142.924439 -357.376431) (xy 142.951708 -357.375968) (xy 143.815308 -357.375968) (xy 143.842579 -357.376395)
			(xy 143.896566 -357.384158) (xy 143.948899 -357.399525) (xy 143.998512 -357.422184) (xy 144.044395 -357.451672)
			(xy 144.085615 -357.48739) (xy 144.121332 -357.528611) (xy 144.15082 -357.574495) (xy 144.173477 -357.624109)
			(xy 144.188843 -357.676442) (xy 144.196606 -357.730429) (xy 144.196606 -357.784965) (xy 158.695954 -357.784965)
			(xy 158.695954 -357.730435) (xy 158.703714 -357.67646) (xy 158.719076 -357.624138) (xy 158.741727 -357.574535)
			(xy 158.771206 -357.52866) (xy 158.806913 -357.487447) (xy 158.848122 -357.451735) (xy 158.893993 -357.42225)
			(xy 158.943593 -357.399593) (xy 158.995913 -357.384224) (xy 159.049887 -357.376458) (xy 159.077152 -357.375968)
			(xy 159.940752 -357.375968) (xy 159.968027 -357.376368) (xy 160.022024 -357.384125) (xy 160.074366 -357.399489)
			(xy 160.123989 -357.422145) (xy 160.169883 -357.451634) (xy 160.211112 -357.487354) (xy 160.246837 -357.528579)
			(xy 160.276332 -357.574468) (xy 160.298994 -357.624089) (xy 160.314364 -357.676429) (xy 160.322128 -357.730425)
			(xy 160.322128 -357.784969) (xy 161.804831 -357.784969) (xy 161.804831 -357.730431) (xy 161.812593 -357.676447)
			(xy 161.827959 -357.624117) (xy 161.850616 -357.574507) (xy 161.880102 -357.528627) (xy 161.915818 -357.487409)
			(xy 161.957036 -357.451695) (xy 162.002918 -357.42221) (xy 162.052529 -357.399555) (xy 162.104859 -357.384191)
			(xy 162.158843 -357.376431) (xy 162.186112 -357.375968) (xy 163.049712 -357.375968) (xy 163.076983 -357.376395)
			(xy 163.130969 -357.384159) (xy 163.183302 -357.399527) (xy 163.232914 -357.422185) (xy 163.278797 -357.451674)
			(xy 163.320017 -357.487392) (xy 163.355733 -357.528612) (xy 163.385221 -357.574496) (xy 163.407878 -357.62411)
			(xy 163.423244 -357.676442) (xy 163.431006 -357.730429) (xy 163.431006 -357.784966) (xy 164.913854 -357.784966)
			(xy 164.913854 -357.730434) (xy 164.921615 -357.676457) (xy 164.936977 -357.624134) (xy 164.95963 -357.57453)
			(xy 164.989111 -357.528654) (xy 165.02482 -357.48744) (xy 165.066031 -357.451727) (xy 165.111905 -357.422243)
			(xy 165.161508 -357.399587) (xy 165.21383 -357.384221) (xy 165.267806 -357.376456) (xy 165.295072 -357.375968)
			(xy 166.158672 -357.375968) (xy 166.185946 -357.37637) (xy 166.239941 -357.384129) (xy 166.292281 -357.399494)
			(xy 166.341901 -357.422152) (xy 166.387792 -357.451641) (xy 166.429019 -357.487361) (xy 166.464742 -357.528585)
			(xy 166.494235 -357.574474) (xy 166.516896 -357.624093) (xy 166.532265 -357.676432) (xy 166.540028 -357.730426)
			(xy 166.540028 -357.78497) (xy 168.022732 -357.78497) (xy 168.022732 -357.73043) (xy 168.030494 -357.676444)
			(xy 168.045861 -357.624113) (xy 168.068519 -357.574502) (xy 168.098007 -357.52862) (xy 168.133725 -357.487402)
			(xy 168.174946 -357.451688) (xy 168.22083 -357.422203) (xy 168.270443 -357.399549) (xy 168.322776 -357.384187)
			(xy 168.376762 -357.376429) (xy 168.404032 -357.375968) (xy 169.267632 -357.375968) (xy 169.294902 -357.376397)
			(xy 169.348886 -357.384163) (xy 169.401216 -357.399532) (xy 169.450826 -357.422192) (xy 169.496707 -357.451681)
			(xy 169.537924 -357.487399) (xy 169.573638 -357.528619) (xy 169.603124 -357.574502) (xy 169.625779 -357.624114)
			(xy 169.641144 -357.676445) (xy 169.648906 -357.73043) (xy 169.648906 -357.784967) (xy 171.131754 -357.784967)
			(xy 171.131754 -357.730433) (xy 171.139515 -357.676454) (xy 171.154879 -357.62413) (xy 171.177533 -357.574524)
			(xy 171.207016 -357.528647) (xy 171.242727 -357.487433) (xy 171.283941 -357.45172) (xy 171.329817 -357.422237)
			(xy 171.379422 -357.399582) (xy 171.431747 -357.384217) (xy 171.485725 -357.376455) (xy 171.512992 -357.375968)
			(xy 172.376592 -357.375968) (xy 172.403866 -357.376371) (xy 172.457857 -357.384133) (xy 172.510195 -357.3995)
			(xy 172.559813 -357.422159) (xy 172.605702 -357.451648) (xy 172.646926 -357.487368) (xy 172.682647 -357.528592)
			(xy 172.712138 -357.57448) (xy 172.734798 -357.624097) (xy 172.750165 -357.676435) (xy 172.757928 -357.730426)
			(xy 172.757928 -357.784965) (xy 174.240754 -357.784965) (xy 174.240754 -357.730435) (xy 174.248514 -357.67646)
			(xy 174.263876 -357.624138) (xy 174.286527 -357.574535) (xy 174.316006 -357.52866) (xy 174.351713 -357.487447)
			(xy 174.392922 -357.451735) (xy 174.438793 -357.42225) (xy 174.488393 -357.399593) (xy 174.540713 -357.384224)
			(xy 174.594687 -357.376458) (xy 174.621952 -357.375968) (xy 175.485552 -357.375968) (xy 175.512827 -357.376368)
			(xy 175.566824 -357.384125) (xy 175.619166 -357.399489) (xy 175.668789 -357.422145) (xy 175.714683 -357.451634)
			(xy 175.755912 -357.487354) (xy 175.791637 -357.528579) (xy 175.821132 -357.574468) (xy 175.843794 -357.624089)
			(xy 175.859164 -357.676429) (xy 175.866928 -357.730425) (xy 175.866928 -357.784969) (xy 177.349631 -357.784969)
			(xy 177.349631 -357.730431) (xy 177.357393 -357.676447) (xy 177.372759 -357.624117) (xy 177.395416 -357.574507)
			(xy 177.424902 -357.528627) (xy 177.460618 -357.487409) (xy 177.501836 -357.451695) (xy 177.547718 -357.42221)
			(xy 177.597329 -357.399555) (xy 177.649659 -357.384191) (xy 177.703643 -357.376431) (xy 177.730912 -357.375968)
			(xy 178.594512 -357.375968) (xy 178.621783 -357.376395) (xy 178.675769 -357.384159) (xy 178.728102 -357.399527)
			(xy 178.777714 -357.422185) (xy 178.823597 -357.451674) (xy 178.864817 -357.487392) (xy 178.900533 -357.528612)
			(xy 178.930021 -357.574496) (xy 178.952678 -357.62411) (xy 178.968044 -357.676442) (xy 178.975806 -357.730429)
			(xy 178.975806 -357.784966) (xy 180.458654 -357.784966) (xy 180.458654 -357.730434) (xy 180.466415 -357.676457)
			(xy 180.481777 -357.624134) (xy 180.50443 -357.57453) (xy 180.533911 -357.528654) (xy 180.56962 -357.48744)
			(xy 180.610831 -357.451727) (xy 180.656705 -357.422243) (xy 180.706308 -357.399587) (xy 180.75863 -357.384221)
			(xy 180.812606 -357.376456) (xy 180.839872 -357.375968) (xy 181.703472 -357.375968) (xy 181.730746 -357.37637)
			(xy 181.784741 -357.384129) (xy 181.837081 -357.399494) (xy 181.886701 -357.422152) (xy 181.932592 -357.451641)
			(xy 181.973819 -357.487361) (xy 182.009542 -357.528585) (xy 182.039035 -357.574474) (xy 182.061696 -357.624093)
			(xy 182.077065 -357.676432) (xy 182.084828 -357.730426) (xy 182.084828 -357.761176) (xy 183.567456 -357.761176)
			(xy 183.567456 -357.706624) (xy 183.57522 -357.652628) (xy 183.590589 -357.600287) (xy 183.613252 -357.550665)
			(xy 183.642746 -357.504775) (xy 183.678471 -357.463549) (xy 183.7197 -357.427827) (xy 183.765593 -357.398337)
			(xy 183.815217 -357.375678) (xy 183.867559 -357.360313) (xy 183.921556 -357.352553) (xy 183.948832 -357.352092)
			(xy 184.812432 -357.352092) (xy 184.839697 -357.352672) (xy 184.89367 -357.360437) (xy 184.94599 -357.375803)
			(xy 184.99559 -357.398458) (xy 185.041461 -357.427942) (xy 185.08267 -357.463653) (xy 185.118378 -357.504864)
			(xy 185.147857 -357.550738) (xy 185.170508 -357.60034) (xy 185.18587 -357.652661) (xy 185.19363 -357.706635)
			(xy 185.19363 -357.761165) (xy 185.193629 -357.761172) (xy 186.676479 -357.761172) (xy 186.676479 -357.706628)
			(xy 186.684241 -357.652638) (xy 186.699608 -357.600303) (xy 186.722266 -357.550688) (xy 186.751755 -357.504801)
			(xy 186.787473 -357.463579) (xy 186.828695 -357.42786) (xy 186.87458 -357.39837) (xy 186.924196 -357.37571)
			(xy 186.97653 -357.360343) (xy 187.03052 -357.352579) (xy 187.057792 -357.352092) (xy 187.921392 -357.352092)
			(xy 187.94866 -357.352647) (xy 188.002641 -357.360407) (xy 188.054969 -357.375771) (xy 188.104577 -357.398425)
			(xy 188.150456 -357.427909) (xy 188.191672 -357.463622) (xy 188.227386 -357.504838) (xy 188.256871 -357.550716)
			(xy 188.279526 -357.600324) (xy 188.294891 -357.652651) (xy 188.302653 -357.706632) (xy 188.302653 -357.761168)
			(xy 188.294891 -357.815149) (xy 188.279526 -357.867476) (xy 188.256871 -357.917084) (xy 188.227386 -357.962962)
			(xy 188.223925 -357.966956) (xy 245.50903 -357.966956) (xy 245.50903 -357.88226) (xy 245.517081 -357.797946)
			(xy 245.53311 -357.71478) (xy 245.556971 -357.633513) (xy 245.58845 -357.554883) (xy 245.627261 -357.479602)
			(xy 245.673051 -357.40835) (xy 245.725407 -357.341774) (xy 245.783855 -357.280476) (xy 245.847865 -357.225011)
			(xy 245.916857 -357.175882) (xy 245.990207 -357.133533) (xy 246.06725 -357.098349) (xy 246.147289 -357.070647)
			(xy 246.229598 -357.050679) (xy 246.313433 -357.038626) (xy 246.398034 -357.034596) (xy 246.482635 -357.038626)
			(xy 246.56647 -357.050679) (xy 246.648779 -357.070647) (xy 246.728818 -357.098349) (xy 246.805861 -357.133533)
			(xy 246.879211 -357.175882) (xy 246.948203 -357.225011) (xy 247.012213 -357.280476) (xy 247.070661 -357.341774)
			(xy 247.123017 -357.40835) (xy 247.168807 -357.479602) (xy 247.207618 -357.554883) (xy 247.239097 -357.633513)
			(xy 247.262958 -357.71478) (xy 247.276485 -357.784966) (xy 270.624854 -357.784966) (xy 270.624854 -357.730435)
			(xy 270.632614 -357.676458) (xy 270.647977 -357.624136) (xy 270.670628 -357.574532) (xy 270.700108 -357.528657)
			(xy 270.735817 -357.487443) (xy 270.777026 -357.451731) (xy 270.822899 -357.422246) (xy 270.8725 -357.39959)
			(xy 270.924821 -357.384222) (xy 270.978797 -357.376457) (xy 271.006062 -357.375968) (xy 271.869662 -357.375968)
			(xy 271.896937 -357.376369) (xy 271.950932 -357.384127) (xy 272.003273 -357.399491) (xy 272.052895 -357.422149)
			(xy 272.098787 -357.451638) (xy 272.140015 -357.487358) (xy 272.17574 -357.528582) (xy 272.205233 -357.574471)
			(xy 272.227895 -357.624091) (xy 272.243265 -357.676431) (xy 272.251028 -357.730425) (xy 272.251028 -357.78497)
			(xy 273.733731 -357.78497) (xy 273.733731 -357.73043) (xy 273.741494 -357.676446) (xy 273.75686 -357.624115)
			(xy 273.779517 -357.574505) (xy 273.809005 -357.528623) (xy 273.844722 -357.487406) (xy 273.885941 -357.451691)
			(xy 273.931824 -357.422207) (xy 273.981436 -357.399552) (xy 274.033767 -357.384189) (xy 274.087752 -357.37643)
			(xy 274.115022 -357.375968) (xy 274.978622 -357.375968) (xy 275.005892 -357.376396) (xy 275.059878 -357.384161)
			(xy 275.112209 -357.399529) (xy 275.16182 -357.422189) (xy 275.207702 -357.451677) (xy 275.24892 -357.487395)
			(xy 275.284636 -357.528616) (xy 275.314122 -357.574499) (xy 275.336778 -357.624112) (xy 275.352144 -357.676444)
			(xy 275.359906 -357.730429) (xy 275.359906 -357.784966) (xy 276.842754 -357.784966) (xy 276.842754 -357.730434)
			(xy 276.850515 -357.676456) (xy 276.865878 -357.624132) (xy 276.888531 -357.574527) (xy 276.918013 -357.52865)
			(xy 276.953724 -357.487436) (xy 276.994936 -357.451724) (xy 277.040811 -357.42224) (xy 277.090415 -357.399584)
			(xy 277.142738 -357.384219) (xy 277.196716 -357.376456) (xy 277.223982 -357.375968) (xy 278.087582 -357.375968)
			(xy 278.114856 -357.37637) (xy 278.168849 -357.384131) (xy 278.221188 -357.399497) (xy 278.270807 -357.422155)
			(xy 278.316697 -357.451645) (xy 278.357922 -357.487365) (xy 278.393644 -357.528589) (xy 278.423136 -357.574477)
			(xy 278.445797 -357.624095) (xy 278.461165 -357.676433) (xy 278.468928 -357.730426) (xy 278.468928 -357.784971)
			(xy 279.951632 -357.784971) (xy 279.951632 -357.730429) (xy 279.959394 -357.676443) (xy 279.974761 -357.624111)
			(xy 279.99742 -357.574499) (xy 280.026909 -357.528617) (xy 280.062629 -357.487399) (xy 280.103851 -357.451684)
			(xy 280.149736 -357.4222) (xy 280.19935 -357.399547) (xy 280.251684 -357.384185) (xy 280.305671 -357.376429)
			(xy 280.332942 -357.375968) (xy 281.196542 -357.375968) (xy 281.223812 -357.376397) (xy 281.277795 -357.384165)
			(xy 281.330123 -357.399535) (xy 281.379732 -357.422195) (xy 281.425611 -357.451684) (xy 281.466827 -357.487402)
			(xy 281.502541 -357.528622) (xy 281.532025 -357.574505) (xy 281.55468 -357.624116) (xy 281.570044 -357.676446)
			(xy 281.577806 -357.73043) (xy 281.577806 -357.784969) (xy 283.060631 -357.784969) (xy 283.060631 -357.730431)
			(xy 283.068393 -357.676448) (xy 283.083758 -357.62412) (xy 283.106414 -357.57451) (xy 283.1359 -357.52863)
			(xy 283.171614 -357.487413) (xy 283.212832 -357.451698) (xy 283.258712 -357.422213) (xy 283.308321 -357.399557)
			(xy 283.36065 -357.384193) (xy 283.414633 -357.376431) (xy 283.441902 -357.375968) (xy 284.305502 -357.375968)
			(xy 284.332773 -357.376395) (xy 284.386761 -357.384157) (xy 284.439094 -357.399524) (xy 284.488708 -357.422182)
			(xy 284.534593 -357.45167) (xy 284.575813 -357.487388) (xy 284.611531 -357.528609) (xy 284.641019 -357.574493)
			(xy 284.663677 -357.624107) (xy 284.679043 -357.676441) (xy 284.686806 -357.730429) (xy 284.686806 -357.784966)
			(xy 286.169654 -357.784966) (xy 286.169654 -357.730435) (xy 286.177414 -357.676458) (xy 286.192777 -357.624136)
			(xy 286.215428 -357.574532) (xy 286.244908 -357.528657) (xy 286.280617 -357.487443) (xy 286.321826 -357.451731)
			(xy 286.367699 -357.422246) (xy 286.4173 -357.39959) (xy 286.469621 -357.384222) (xy 286.523597 -357.376457)
			(xy 286.550862 -357.375968) (xy 287.414462 -357.375968) (xy 287.441737 -357.376369) (xy 287.495732 -357.384127)
			(xy 287.548073 -357.399491) (xy 287.597695 -357.422149) (xy 287.643587 -357.451638) (xy 287.684815 -357.487358)
			(xy 287.72054 -357.528582) (xy 287.750033 -357.574471) (xy 287.772695 -357.624091) (xy 287.788065 -357.676431)
			(xy 287.795828 -357.730425) (xy 287.795828 -357.78497) (xy 289.278531 -357.78497) (xy 289.278531 -357.73043)
			(xy 289.286294 -357.676446) (xy 289.30166 -357.624115) (xy 289.324317 -357.574505) (xy 289.353805 -357.528623)
			(xy 289.389522 -357.487406) (xy 289.430741 -357.451691) (xy 289.476624 -357.422207) (xy 289.526236 -357.399552)
			(xy 289.578567 -357.384189) (xy 289.632552 -357.37643) (xy 289.659822 -357.375968) (xy 290.523422 -357.375968)
			(xy 290.550692 -357.376396) (xy 290.604678 -357.384161) (xy 290.657009 -357.399529) (xy 290.70662 -357.422189)
			(xy 290.752502 -357.451677) (xy 290.79372 -357.487395) (xy 290.829436 -357.528616) (xy 290.858922 -357.574499)
			(xy 290.881578 -357.624112) (xy 290.896944 -357.676444) (xy 290.904706 -357.730429) (xy 290.904706 -357.784966)
			(xy 292.387554 -357.784966) (xy 292.387554 -357.730434) (xy 292.395315 -357.676456) (xy 292.410678 -357.624132)
			(xy 292.433331 -357.574527) (xy 292.462813 -357.52865) (xy 292.498524 -357.487436) (xy 292.539736 -357.451724)
			(xy 292.585611 -357.42224) (xy 292.635215 -357.399584) (xy 292.687538 -357.384219) (xy 292.741516 -357.376456)
			(xy 292.768782 -357.375968) (xy 293.632382 -357.375968) (xy 293.659656 -357.37637) (xy 293.713649 -357.384131)
			(xy 293.765988 -357.399497) (xy 293.815607 -357.422155) (xy 293.861497 -357.451645) (xy 293.902722 -357.487365)
			(xy 293.938444 -357.528589) (xy 293.967936 -357.574477) (xy 293.990597 -357.624095) (xy 294.005965 -357.676433)
			(xy 294.013728 -357.730426) (xy 294.013728 -357.784971) (xy 295.496432 -357.784971) (xy 295.496432 -357.730429)
			(xy 295.504194 -357.676443) (xy 295.519561 -357.624111) (xy 295.54222 -357.574499) (xy 295.571709 -357.528617)
			(xy 295.607429 -357.487399) (xy 295.648651 -357.451684) (xy 295.694536 -357.4222) (xy 295.74415 -357.399547)
			(xy 295.796484 -357.384185) (xy 295.850471 -357.376429) (xy 295.877742 -357.375968) (xy 296.741342 -357.375968)
			(xy 296.768612 -357.376397) (xy 296.822595 -357.384165) (xy 296.874923 -357.399535) (xy 296.924532 -357.422195)
			(xy 296.970411 -357.451684) (xy 297.011627 -357.487402) (xy 297.047341 -357.528622) (xy 297.076825 -357.574505)
			(xy 297.09948 -357.624116) (xy 297.114844 -357.676446) (xy 297.122606 -357.73043) (xy 297.122606 -357.784969)
			(xy 298.605431 -357.784969) (xy 298.605431 -357.730431) (xy 298.613193 -357.676448) (xy 298.628558 -357.62412)
			(xy 298.651214 -357.57451) (xy 298.6807 -357.52863) (xy 298.716414 -357.487413) (xy 298.757632 -357.451698)
			(xy 298.803512 -357.422213) (xy 298.853121 -357.399557) (xy 298.90545 -357.384193) (xy 298.959433 -357.376431)
			(xy 298.986702 -357.375968) (xy 299.850302 -357.375968) (xy 299.877573 -357.376395) (xy 299.931561 -357.384157)
			(xy 299.983894 -357.399524) (xy 300.033508 -357.422182) (xy 300.079393 -357.45167) (xy 300.120613 -357.487388)
			(xy 300.156331 -357.528609) (xy 300.185819 -357.574493) (xy 300.208477 -357.624107) (xy 300.223843 -357.676441)
			(xy 300.231606 -357.730429) (xy 300.231606 -357.784966) (xy 315.230554 -357.784966) (xy 315.230554 -357.730434)
			(xy 315.238314 -357.676458) (xy 315.253677 -357.624136) (xy 315.276328 -357.574532) (xy 315.305809 -357.528656)
			(xy 315.341517 -357.487443) (xy 315.382727 -357.45173) (xy 315.4286 -357.422246) (xy 315.478202 -357.399589)
			(xy 315.530523 -357.384222) (xy 315.584498 -357.376457) (xy 315.611764 -357.375968) (xy 316.475364 -357.375968)
			(xy 316.502639 -357.376369) (xy 316.556634 -357.384128) (xy 316.608975 -357.399492) (xy 316.658597 -357.422149)
			(xy 316.704488 -357.451638) (xy 316.745716 -357.487359) (xy 316.78144 -357.528583) (xy 316.810933 -357.574472)
			(xy 316.833595 -357.624091) (xy 316.848965 -357.676431) (xy 316.856728 -357.730425) (xy 316.856728 -357.78497)
			(xy 318.339431 -357.78497) (xy 318.339431 -357.73043) (xy 318.347194 -357.676445) (xy 318.36256 -357.624115)
			(xy 318.385217 -357.574504) (xy 318.414705 -357.528623) (xy 318.450422 -357.487405) (xy 318.491642 -357.451691)
			(xy 318.537525 -357.422206) (xy 318.587137 -357.399552) (xy 318.639469 -357.384189) (xy 318.693454 -357.37643)
			(xy 318.720724 -357.375968) (xy 319.584324 -357.375968) (xy 319.611594 -357.376396) (xy 319.66558 -357.384161)
			(xy 319.71791 -357.39953) (xy 319.767521 -357.422189) (xy 319.813403 -357.451678) (xy 319.854621 -357.487396)
			(xy 319.890336 -357.528616) (xy 319.919822 -357.5745) (xy 319.942479 -357.624112) (xy 319.957844 -357.676444)
			(xy 319.965606 -357.73043) (xy 319.965606 -357.784967) (xy 321.448454 -357.784967) (xy 321.448454 -357.730434)
			(xy 321.456215 -357.676456) (xy 321.471578 -357.624131) (xy 321.494232 -357.574526) (xy 321.523714 -357.52865)
			(xy 321.559424 -357.487436) (xy 321.600637 -357.451723) (xy 321.646512 -357.422239) (xy 321.696116 -357.399584)
			(xy 321.74844 -357.384218) (xy 321.802418 -357.376455) (xy 321.829684 -357.375968) (xy 322.693284 -357.375968)
			(xy 322.720558 -357.37637) (xy 322.774551 -357.384131) (xy 322.826889 -357.399497) (xy 322.876508 -357.422156)
			(xy 322.922398 -357.451645) (xy 322.963623 -357.487366) (xy 322.999345 -357.528589) (xy 323.028836 -357.574477)
			(xy 323.051497 -357.624096) (xy 323.066865 -357.676434) (xy 323.074628 -357.730426) (xy 323.074628 -357.784971)
			(xy 324.557332 -357.784971) (xy 324.557332 -357.730429) (xy 324.565094 -357.676443) (xy 324.580461 -357.624111)
			(xy 324.603121 -357.574498) (xy 324.63261 -357.528616) (xy 324.668329 -357.487398) (xy 324.709551 -357.451684)
			(xy 324.755437 -357.422199) (xy 324.805052 -357.399546) (xy 324.857386 -357.384185) (xy 324.911373 -357.376428)
			(xy 324.938644 -357.375968) (xy 325.802244 -357.375968) (xy 325.829513 -357.376398) (xy 325.883497 -357.384165)
			(xy 325.935825 -357.399535) (xy 325.985433 -357.422196) (xy 326.031312 -357.451685) (xy 326.072528 -357.487403)
			(xy 326.108241 -357.528623) (xy 326.137725 -357.574505) (xy 326.16038 -357.624116) (xy 326.175744 -357.676447)
			(xy 326.183506 -357.73043) (xy 326.183506 -357.784969) (xy 327.666331 -357.784969) (xy 327.666331 -357.730431)
			(xy 327.674093 -357.676448) (xy 327.689458 -357.624119) (xy 327.712114 -357.57451) (xy 327.7416 -357.528629)
			(xy 327.777315 -357.487412) (xy 327.818533 -357.451698) (xy 327.864413 -357.422212) (xy 327.914023 -357.399557)
			(xy 327.966352 -357.384192) (xy 328.020335 -357.376431) (xy 328.047604 -357.375968) (xy 328.911204 -357.375968)
			(xy 328.938475 -357.376395) (xy 328.992463 -357.384158) (xy 329.044796 -357.399524) (xy 329.094409 -357.422183)
			(xy 329.140293 -357.451671) (xy 329.181514 -357.487389) (xy 329.217231 -357.52861) (xy 329.246719 -357.574494)
			(xy 329.269377 -357.624108) (xy 329.284743 -357.676441) (xy 329.292506 -357.730429) (xy 329.292506 -357.784966)
			(xy 330.775354 -357.784966) (xy 330.775354 -357.730434) (xy 330.783114 -357.676458) (xy 330.798477 -357.624136)
			(xy 330.821128 -357.574532) (xy 330.850609 -357.528656) (xy 330.886317 -357.487443) (xy 330.927527 -357.45173)
			(xy 330.9734 -357.422246) (xy 331.023002 -357.399589) (xy 331.075323 -357.384222) (xy 331.129298 -357.376457)
			(xy 331.156564 -357.375968) (xy 332.020164 -357.375968) (xy 332.047439 -357.376369) (xy 332.101434 -357.384128)
			(xy 332.153775 -357.399492) (xy 332.203397 -357.422149) (xy 332.249288 -357.451638) (xy 332.290516 -357.487359)
			(xy 332.32624 -357.528583) (xy 332.355733 -357.574472) (xy 332.378395 -357.624091) (xy 332.393765 -357.676431)
			(xy 332.401528 -357.730425) (xy 332.401528 -357.78497) (xy 333.884231 -357.78497) (xy 333.884231 -357.73043)
			(xy 333.891994 -357.676445) (xy 333.90736 -357.624115) (xy 333.930017 -357.574504) (xy 333.959505 -357.528623)
			(xy 333.995222 -357.487405) (xy 334.036442 -357.451691) (xy 334.082325 -357.422206) (xy 334.131937 -357.399552)
			(xy 334.184269 -357.384189) (xy 334.238254 -357.37643) (xy 334.265524 -357.375968) (xy 335.129124 -357.375968)
			(xy 335.156394 -357.376396) (xy 335.21038 -357.384161) (xy 335.26271 -357.39953) (xy 335.312321 -357.422189)
			(xy 335.358203 -357.451678) (xy 335.399421 -357.487396) (xy 335.435136 -357.528616) (xy 335.464622 -357.5745)
			(xy 335.487279 -357.624112) (xy 335.502644 -357.676444) (xy 335.510406 -357.73043) (xy 335.510406 -357.784967)
			(xy 336.993254 -357.784967) (xy 336.993254 -357.730434) (xy 337.001015 -357.676456) (xy 337.016378 -357.624131)
			(xy 337.039032 -357.574526) (xy 337.068514 -357.52865) (xy 337.104224 -357.487436) (xy 337.145437 -357.451723)
			(xy 337.191312 -357.422239) (xy 337.240916 -357.399584) (xy 337.29324 -357.384218) (xy 337.347218 -357.376455)
			(xy 337.374484 -357.375968) (xy 338.238084 -357.375968) (xy 338.265358 -357.37637) (xy 338.319351 -357.384131)
			(xy 338.371689 -357.399497) (xy 338.421308 -357.422156) (xy 338.467198 -357.451645) (xy 338.508423 -357.487366)
			(xy 338.544145 -357.528589) (xy 338.573636 -357.574477) (xy 338.596297 -357.624096) (xy 338.611665 -357.676434)
			(xy 338.619428 -357.730426) (xy 338.619428 -357.784971) (xy 340.102132 -357.784971) (xy 340.102132 -357.730429)
			(xy 340.109894 -357.676443) (xy 340.125261 -357.624111) (xy 340.147921 -357.574498) (xy 340.17741 -357.528616)
			(xy 340.213129 -357.487398) (xy 340.254351 -357.451684) (xy 340.300237 -357.422199) (xy 340.349852 -357.399546)
			(xy 340.402186 -357.384185) (xy 340.456173 -357.376428) (xy 340.483444 -357.375968) (xy 341.347044 -357.375968)
			(xy 341.374313 -357.376398) (xy 341.428297 -357.384165) (xy 341.480625 -357.399535) (xy 341.530233 -357.422196)
			(xy 341.576112 -357.451685) (xy 341.617328 -357.487403) (xy 341.653041 -357.528623) (xy 341.682525 -357.574505)
			(xy 341.70518 -357.624116) (xy 341.720544 -357.676447) (xy 341.728306 -357.73043) (xy 341.728306 -357.784969)
			(xy 343.211131 -357.784969) (xy 343.211131 -357.730431) (xy 343.218893 -357.676448) (xy 343.234258 -357.624119)
			(xy 343.256914 -357.57451) (xy 343.2864 -357.528629) (xy 343.322115 -357.487412) (xy 343.363333 -357.451698)
			(xy 343.409213 -357.422212) (xy 343.458823 -357.399557) (xy 343.511152 -357.384192) (xy 343.565135 -357.376431)
			(xy 343.592404 -357.375968) (xy 344.456004 -357.375968) (xy 344.483275 -357.376395) (xy 344.537263 -357.384158)
			(xy 344.589596 -357.399524) (xy 344.639209 -357.422183) (xy 344.685093 -357.451671) (xy 344.726314 -357.487389)
			(xy 344.762031 -357.52861) (xy 344.791519 -357.574494) (xy 344.814177 -357.624108) (xy 344.829543 -357.676441)
			(xy 344.837306 -357.730429) (xy 344.837306 -357.784971) (xy 373.915632 -357.784971) (xy 373.915632 -357.730429)
			(xy 373.923394 -357.676443) (xy 373.938761 -357.624111) (xy 373.96142 -357.574499) (xy 373.990909 -357.528617)
			(xy 374.026628 -357.4874) (xy 374.06785 -357.451685) (xy 374.113735 -357.422201) (xy 374.163349 -357.399547)
			(xy 374.215682 -357.384186) (xy 374.269669 -357.376429) (xy 374.29694 -357.375968) (xy 375.16054 -357.375968)
			(xy 375.18781 -357.376397) (xy 375.241793 -357.384164) (xy 375.294122 -357.399534) (xy 375.343731 -357.422194)
			(xy 375.389611 -357.451684) (xy 375.430827 -357.487402) (xy 375.46654 -357.528622) (xy 375.496025 -357.574504)
			(xy 375.51868 -357.624116) (xy 375.534044 -357.676446) (xy 375.541806 -357.73043) (xy 375.541806 -357.784967)
			(xy 377.024654 -357.784967) (xy 377.024654 -357.730433) (xy 377.032415 -357.676453) (xy 377.04778 -357.624128)
			(xy 377.070434 -357.574522) (xy 377.099918 -357.528644) (xy 377.13563 -357.48743) (xy 377.176844 -357.451718)
			(xy 377.222722 -357.422234) (xy 377.272328 -357.39958) (xy 377.324653 -357.384215) (xy 377.378633 -357.376454)
			(xy 377.4059 -357.375968) (xy 378.2695 -357.375968) (xy 378.296772 -357.376395) (xy 378.350759 -357.384157)
			(xy 378.403093 -357.399523) (xy 378.452707 -357.422181) (xy 378.498592 -357.451669) (xy 378.539812 -357.487388)
			(xy 378.575531 -357.528608) (xy 378.605019 -357.574493) (xy 378.627677 -357.624107) (xy 378.643043 -357.676441)
			(xy 378.650805 -357.730428) (xy 378.650805 -357.784965) (xy 380.133654 -357.784965) (xy 380.133654 -357.730435)
			(xy 380.141414 -357.676459) (xy 380.156776 -357.624137) (xy 380.179428 -357.574533) (xy 380.208908 -357.528658)
			(xy 380.244616 -357.487444) (xy 380.285825 -357.451732) (xy 380.331698 -357.422247) (xy 380.381299 -357.39959)
			(xy 380.43362 -357.384223) (xy 380.487595 -357.376457) (xy 380.51486 -357.375968) (xy 381.37846 -357.375968)
			(xy 381.405735 -357.376369) (xy 381.45973 -357.384127) (xy 381.512072 -357.399491) (xy 381.561694 -357.422148)
			(xy 381.607586 -357.451637) (xy 381.648815 -357.487357) (xy 381.684539 -357.528582) (xy 381.714033 -357.574471)
			(xy 381.736695 -357.62409) (xy 381.752065 -357.67643) (xy 381.759828 -357.730425) (xy 381.759828 -357.78497)
			(xy 383.242531 -357.78497) (xy 383.242531 -357.73043) (xy 383.250294 -357.676446) (xy 383.26566 -357.624116)
			(xy 383.288317 -357.574505) (xy 383.317804 -357.528624) (xy 383.353521 -357.487407) (xy 383.39474 -357.451692)
			(xy 383.440623 -357.422207) (xy 383.490234 -357.399553) (xy 383.542565 -357.384189) (xy 383.59655 -357.37643)
			(xy 383.62382 -357.375968) (xy 384.48742 -357.375968) (xy 384.514691 -357.376396) (xy 384.568676 -357.38416)
			(xy 384.621007 -357.399529) (xy 384.670619 -357.422188) (xy 384.716501 -357.451677) (xy 384.75772 -357.487395)
			(xy 384.793435 -357.528615) (xy 384.822922 -357.574499) (xy 384.845578 -357.624111) (xy 384.860944 -357.676443)
			(xy 384.868706 -357.730429) (xy 384.868706 -357.784966) (xy 386.351554 -357.784966) (xy 386.351554 -357.730434)
			(xy 386.359315 -357.676456) (xy 386.374678 -357.624132) (xy 386.397331 -357.574527) (xy 386.426813 -357.528651)
			(xy 386.462523 -357.487437) (xy 386.503735 -357.451725) (xy 386.54961 -357.422241) (xy 386.599213 -357.399585)
			(xy 386.651537 -357.384219) (xy 386.705514 -357.376456) (xy 386.73278 -357.375968) (xy 387.59638 -357.375968)
			(xy 387.623654 -357.37637) (xy 387.677647 -357.384131) (xy 387.729987 -357.399496) (xy 387.779606 -357.422155)
			(xy 387.825496 -357.451644) (xy 387.866722 -357.487364) (xy 387.902444 -357.528588) (xy 387.931936 -357.574476)
			(xy 387.954597 -357.624095) (xy 387.969965 -357.676433) (xy 387.977728 -357.730426) (xy 387.977728 -357.784971)
			(xy 389.460432 -357.784971) (xy 389.460432 -357.730429) (xy 389.468194 -357.676443) (xy 389.483561 -357.624111)
			(xy 389.50622 -357.574499) (xy 389.535709 -357.528617) (xy 389.571428 -357.4874) (xy 389.61265 -357.451685)
			(xy 389.658535 -357.422201) (xy 389.708149 -357.399547) (xy 389.760482 -357.384186) (xy 389.814469 -357.376429)
			(xy 389.84174 -357.375968) (xy 390.70534 -357.375968) (xy 390.73261 -357.376397) (xy 390.786593 -357.384164)
			(xy 390.838922 -357.399534) (xy 390.888531 -357.422194) (xy 390.934411 -357.451684) (xy 390.975627 -357.487402)
			(xy 391.01134 -357.528622) (xy 391.040825 -357.574504) (xy 391.06348 -357.624116) (xy 391.078844 -357.676446)
			(xy 391.086606 -357.73043) (xy 391.086606 -357.784967) (xy 392.569454 -357.784967) (xy 392.569454 -357.730433)
			(xy 392.577215 -357.676453) (xy 392.59258 -357.624128) (xy 392.615234 -357.574522) (xy 392.644718 -357.528644)
			(xy 392.68043 -357.48743) (xy 392.721644 -357.451718) (xy 392.767522 -357.422234) (xy 392.817128 -357.39958)
			(xy 392.869453 -357.384215) (xy 392.923433 -357.376454) (xy 392.9507 -357.375968) (xy 393.8143 -357.375968)
			(xy 393.841572 -357.376395) (xy 393.895559 -357.384157) (xy 393.947893 -357.399523) (xy 393.997507 -357.422181)
			(xy 394.043392 -357.451669) (xy 394.084612 -357.487388) (xy 394.120331 -357.528608) (xy 394.149819 -357.574493)
			(xy 394.172477 -357.624107) (xy 394.187843 -357.676441) (xy 394.195605 -357.730428) (xy 394.195605 -357.784965)
			(xy 395.678454 -357.784965) (xy 395.678454 -357.730435) (xy 395.686214 -357.676459) (xy 395.701576 -357.624137)
			(xy 395.724228 -357.574533) (xy 395.753708 -357.528658) (xy 395.789416 -357.487444) (xy 395.830625 -357.451732)
			(xy 395.876498 -357.422247) (xy 395.926099 -357.39959) (xy 395.97842 -357.384223) (xy 396.032395 -357.376457)
			(xy 396.05966 -357.375968) (xy 396.92326 -357.375968) (xy 396.950535 -357.376369) (xy 397.00453 -357.384127)
			(xy 397.056872 -357.399491) (xy 397.106494 -357.422148) (xy 397.152386 -357.451637) (xy 397.193615 -357.487357)
			(xy 397.229339 -357.528582) (xy 397.258833 -357.574471) (xy 397.281495 -357.62409) (xy 397.296865 -357.67643)
			(xy 397.304628 -357.730425) (xy 397.304628 -357.78497) (xy 398.787331 -357.78497) (xy 398.787331 -357.73043)
			(xy 398.795094 -357.676446) (xy 398.81046 -357.624116) (xy 398.833117 -357.574505) (xy 398.862604 -357.528624)
			(xy 398.898321 -357.487407) (xy 398.93954 -357.451692) (xy 398.985423 -357.422207) (xy 399.035034 -357.399553)
			(xy 399.087365 -357.384189) (xy 399.14135 -357.37643) (xy 399.16862 -357.375968) (xy 400.03222 -357.375968)
			(xy 400.059491 -357.376396) (xy 400.113476 -357.38416) (xy 400.165807 -357.399529) (xy 400.215419 -357.422188)
			(xy 400.261301 -357.451677) (xy 400.30252 -357.487395) (xy 400.338235 -357.528615) (xy 400.367722 -357.574499)
			(xy 400.390378 -357.624111) (xy 400.405744 -357.676443) (xy 400.413506 -357.730429) (xy 400.413506 -357.784966)
			(xy 401.896354 -357.784966) (xy 401.896354 -357.730434) (xy 401.904115 -357.676456) (xy 401.919478 -357.624132)
			(xy 401.942131 -357.574527) (xy 401.971613 -357.528651) (xy 402.007323 -357.487437) (xy 402.048535 -357.451725)
			(xy 402.09441 -357.422241) (xy 402.144013 -357.399585) (xy 402.196337 -357.384219) (xy 402.250314 -357.376456)
			(xy 402.27758 -357.375968) (xy 403.14118 -357.375968) (xy 403.168454 -357.37637) (xy 403.222447 -357.384131)
			(xy 403.274787 -357.399496) (xy 403.324406 -357.422155) (xy 403.370296 -357.451644) (xy 403.411522 -357.487364)
			(xy 403.447244 -357.528588) (xy 403.476736 -357.574476) (xy 403.499397 -357.624095) (xy 403.514765 -357.676433)
			(xy 403.522528 -357.730426) (xy 403.522528 -357.784965) (xy 412.022854 -357.784965) (xy 412.022854 -357.730435)
			(xy 412.030614 -357.67646) (xy 412.045976 -357.624138) (xy 412.068627 -357.574535) (xy 412.098106 -357.52866)
			(xy 412.133813 -357.487447) (xy 412.175022 -357.451735) (xy 412.220893 -357.42225) (xy 412.270493 -357.399593)
			(xy 412.322813 -357.384224) (xy 412.376787 -357.376458) (xy 412.404052 -357.375968) (xy 413.267652 -357.375968)
			(xy 413.294927 -357.376368) (xy 413.348924 -357.384125) (xy 413.401266 -357.399489) (xy 413.450889 -357.422145)
			(xy 413.496783 -357.451634) (xy 413.538012 -357.487354) (xy 413.573737 -357.528579) (xy 413.603232 -357.574468)
			(xy 413.625894 -357.624089) (xy 413.641264 -357.676429) (xy 413.649028 -357.730425) (xy 413.649028 -357.784969)
			(xy 415.131731 -357.784969) (xy 415.131731 -357.730431) (xy 415.139493 -357.676447) (xy 415.154859 -357.624117)
			(xy 415.177516 -357.574507) (xy 415.207002 -357.528627) (xy 415.242718 -357.487409) (xy 415.283936 -357.451695)
			(xy 415.329818 -357.42221) (xy 415.379429 -357.399555) (xy 415.431759 -357.384191) (xy 415.485743 -357.376431)
			(xy 415.513012 -357.375968) (xy 416.376612 -357.375968) (xy 416.403883 -357.376395) (xy 416.457869 -357.384159)
			(xy 416.510202 -357.399527) (xy 416.559814 -357.422185) (xy 416.605697 -357.451674) (xy 416.646917 -357.487392)
			(xy 416.682633 -357.528612) (xy 416.712121 -357.574496) (xy 416.734778 -357.62411) (xy 416.750144 -357.676442)
			(xy 416.757906 -357.730429) (xy 416.757906 -357.784966) (xy 418.240754 -357.784966) (xy 418.240754 -357.730434)
			(xy 418.248515 -357.676457) (xy 418.263877 -357.624134) (xy 418.28653 -357.57453) (xy 418.316011 -357.528654)
			(xy 418.35172 -357.48744) (xy 418.392931 -357.451727) (xy 418.438805 -357.422243) (xy 418.488408 -357.399587)
			(xy 418.54073 -357.384221) (xy 418.594706 -357.376456) (xy 418.621972 -357.375968) (xy 419.485572 -357.375968)
			(xy 419.512846 -357.37637) (xy 419.566841 -357.384129) (xy 419.619181 -357.399494) (xy 419.668801 -357.422152)
			(xy 419.714692 -357.451641) (xy 419.755919 -357.487361) (xy 419.791642 -357.528585) (xy 419.821135 -357.574474)
			(xy 419.843796 -357.624093) (xy 419.859165 -357.676432) (xy 419.866928 -357.730426) (xy 419.866928 -357.78497)
			(xy 421.349632 -357.78497) (xy 421.349632 -357.73043) (xy 421.357394 -357.676444) (xy 421.372761 -357.624113)
			(xy 421.395419 -357.574502) (xy 421.424907 -357.52862) (xy 421.460625 -357.487402) (xy 421.501846 -357.451688)
			(xy 421.54773 -357.422203) (xy 421.597343 -357.399549) (xy 421.649676 -357.384187) (xy 421.703662 -357.376429)
			(xy 421.730932 -357.375968) (xy 422.594532 -357.375968) (xy 422.621802 -357.376397) (xy 422.675786 -357.384163)
			(xy 422.728116 -357.399532) (xy 422.777726 -357.422192) (xy 422.823607 -357.451681) (xy 422.864824 -357.487399)
			(xy 422.900538 -357.528619) (xy 422.930024 -357.574502) (xy 422.952679 -357.624114) (xy 422.968044 -357.676445)
			(xy 422.975806 -357.73043) (xy 422.975806 -357.784967) (xy 424.458654 -357.784967) (xy 424.458654 -357.730433)
			(xy 424.466415 -357.676454) (xy 424.481779 -357.62413) (xy 424.504433 -357.574524) (xy 424.533916 -357.528647)
			(xy 424.569627 -357.487433) (xy 424.610841 -357.45172) (xy 424.656717 -357.422237) (xy 424.706322 -357.399582)
			(xy 424.758647 -357.384217) (xy 424.812625 -357.376455) (xy 424.839892 -357.375968) (xy 425.703492 -357.375968)
			(xy 425.730766 -357.376371) (xy 425.784757 -357.384133) (xy 425.837095 -357.3995) (xy 425.886713 -357.422159)
			(xy 425.932602 -357.451648) (xy 425.973826 -357.487368) (xy 426.009547 -357.528592) (xy 426.039038 -357.57448)
			(xy 426.061698 -357.624097) (xy 426.077065 -357.676435) (xy 426.084828 -357.730426) (xy 426.084828 -357.784965)
			(xy 427.567654 -357.784965) (xy 427.567654 -357.730435) (xy 427.575414 -357.67646) (xy 427.590776 -357.624138)
			(xy 427.613427 -357.574535) (xy 427.642906 -357.52866) (xy 427.678613 -357.487447) (xy 427.719822 -357.451735)
			(xy 427.765693 -357.42225) (xy 427.815293 -357.399593) (xy 427.867613 -357.384224) (xy 427.921587 -357.376458)
			(xy 427.948852 -357.375968) (xy 428.812452 -357.375968) (xy 428.839727 -357.376368) (xy 428.893724 -357.384125)
			(xy 428.946066 -357.399489) (xy 428.995689 -357.422145) (xy 429.041583 -357.451634) (xy 429.082812 -357.487354)
			(xy 429.118537 -357.528579) (xy 429.148032 -357.574468) (xy 429.170694 -357.624089) (xy 429.186064 -357.676429)
			(xy 429.193828 -357.730425) (xy 429.193828 -357.784969) (xy 430.676531 -357.784969) (xy 430.676531 -357.730431)
			(xy 430.684293 -357.676447) (xy 430.699659 -357.624117) (xy 430.722316 -357.574507) (xy 430.751802 -357.528627)
			(xy 430.787518 -357.487409) (xy 430.828736 -357.451695) (xy 430.874618 -357.42221) (xy 430.924229 -357.399555)
			(xy 430.976559 -357.384191) (xy 431.030543 -357.376431) (xy 431.057812 -357.375968) (xy 431.921412 -357.375968)
			(xy 431.948683 -357.376395) (xy 432.002669 -357.384159) (xy 432.055002 -357.399527) (xy 432.104614 -357.422185)
			(xy 432.150497 -357.451674) (xy 432.191717 -357.487392) (xy 432.227433 -357.528612) (xy 432.256921 -357.574496)
			(xy 432.279578 -357.62411) (xy 432.294944 -357.676442) (xy 432.302706 -357.730429) (xy 432.302706 -357.784966)
			(xy 433.785554 -357.784966) (xy 433.785554 -357.730434) (xy 433.793315 -357.676457) (xy 433.808677 -357.624134)
			(xy 433.83133 -357.57453) (xy 433.860811 -357.528654) (xy 433.89652 -357.48744) (xy 433.937731 -357.451727)
			(xy 433.983605 -357.422243) (xy 434.033208 -357.399587) (xy 434.08553 -357.384221) (xy 434.139506 -357.376456)
			(xy 434.166772 -357.375968) (xy 435.030372 -357.375968) (xy 435.057646 -357.37637) (xy 435.111641 -357.384129)
			(xy 435.163981 -357.399494) (xy 435.213601 -357.422152) (xy 435.259492 -357.451641) (xy 435.300719 -357.487361)
			(xy 435.336442 -357.528585) (xy 435.365935 -357.574474) (xy 435.388596 -357.624093) (xy 435.403965 -357.676432)
			(xy 435.411728 -357.730426) (xy 435.411728 -357.78497) (xy 436.894432 -357.78497) (xy 436.894432 -357.73043)
			(xy 436.902194 -357.676444) (xy 436.917561 -357.624113) (xy 436.940219 -357.574502) (xy 436.969707 -357.52862)
			(xy 437.005425 -357.487402) (xy 437.046646 -357.451688) (xy 437.09253 -357.422203) (xy 437.142143 -357.399549)
			(xy 437.194476 -357.384187) (xy 437.248462 -357.376429) (xy 437.275732 -357.375968) (xy 438.139332 -357.375968)
			(xy 438.166602 -357.376397) (xy 438.220586 -357.384163) (xy 438.272916 -357.399532) (xy 438.322526 -357.422192)
			(xy 438.368407 -357.451681) (xy 438.409624 -357.487399) (xy 438.445338 -357.528619) (xy 438.474824 -357.574502)
			(xy 438.497479 -357.624114) (xy 438.512844 -357.676445) (xy 438.520606 -357.73043) (xy 438.520606 -357.784967)
			(xy 440.003454 -357.784967) (xy 440.003454 -357.730433) (xy 440.011215 -357.676454) (xy 440.026579 -357.62413)
			(xy 440.049233 -357.574524) (xy 440.078716 -357.528647) (xy 440.114427 -357.487433) (xy 440.155641 -357.45172)
			(xy 440.201517 -357.422237) (xy 440.251122 -357.399582) (xy 440.303447 -357.384217) (xy 440.357425 -357.376455)
			(xy 440.384692 -357.375968) (xy 441.248292 -357.375968) (xy 441.275566 -357.376371) (xy 441.329557 -357.384133)
			(xy 441.381895 -357.3995) (xy 441.431513 -357.422159) (xy 441.477402 -357.451648) (xy 441.518626 -357.487368)
			(xy 441.554347 -357.528592) (xy 441.583838 -357.57448) (xy 441.606498 -357.624097) (xy 441.621865 -357.676435)
			(xy 441.629628 -357.730426) (xy 441.629628 -357.784974) (xy 441.621865 -357.838965) (xy 441.606498 -357.891303)
			(xy 441.583838 -357.94092) (xy 441.554347 -357.986808) (xy 441.518626 -358.028032) (xy 441.477402 -358.063752)
			(xy 441.431513 -358.093241) (xy 441.381895 -358.1159) (xy 441.329557 -358.131267) (xy 441.275566 -358.139029)
			(xy 441.248292 -358.139492) (xy 440.384692 -358.139492) (xy 440.357425 -358.138945) (xy 440.303447 -358.131183)
			(xy 440.251122 -358.115818) (xy 440.201517 -358.093163) (xy 440.155641 -358.06368) (xy 440.114427 -358.027967)
			(xy 440.078716 -357.986753) (xy 440.049233 -357.940876) (xy 440.026579 -357.89127) (xy 440.011215 -357.838946)
			(xy 440.003454 -357.784967) (xy 438.520606 -357.784967) (xy 438.520606 -357.78497) (xy 438.512844 -357.838955)
			(xy 438.497479 -357.891286) (xy 438.474824 -357.940898) (xy 438.445338 -357.986781) (xy 438.409624 -358.028001)
			(xy 438.368407 -358.063719) (xy 438.322526 -358.093208) (xy 438.272916 -358.115868) (xy 438.220586 -358.131237)
			(xy 438.166602 -358.139003) (xy 438.139332 -358.139492) (xy 437.275732 -358.139492) (xy 437.248462 -358.138971)
			(xy 437.194476 -358.131213) (xy 437.142143 -358.115851) (xy 437.09253 -358.093197) (xy 437.046646 -358.063712)
			(xy 437.005425 -358.027998) (xy 436.969707 -357.98678) (xy 436.940219 -357.940898) (xy 436.917561 -357.891287)
			(xy 436.902194 -357.838956) (xy 436.894432 -357.78497) (xy 435.411728 -357.78497) (xy 435.411728 -357.784974)
			(xy 435.403965 -357.838968) (xy 435.388596 -357.891307) (xy 435.365935 -357.940926) (xy 435.336442 -357.986815)
			(xy 435.300719 -358.028039) (xy 435.259492 -358.063759) (xy 435.213601 -358.093248) (xy 435.163981 -358.115906)
			(xy 435.111641 -358.131271) (xy 435.057646 -358.13903) (xy 435.030372 -358.139492) (xy 434.166772 -358.139492)
			(xy 434.139506 -358.138944) (xy 434.08553 -358.131179) (xy 434.033208 -358.115813) (xy 433.983605 -358.093157)
			(xy 433.937731 -358.063673) (xy 433.89652 -358.02796) (xy 433.860811 -357.986746) (xy 433.83133 -357.94087)
			(xy 433.808677 -357.891266) (xy 433.793315 -357.838943) (xy 433.785554 -357.784966) (xy 432.302706 -357.784966)
			(xy 432.302706 -357.784971) (xy 432.294944 -357.838958) (xy 432.279578 -357.89129) (xy 432.256921 -357.940904)
			(xy 432.227433 -357.986788) (xy 432.191717 -358.028008) (xy 432.150497 -358.063726) (xy 432.104614 -358.093215)
			(xy 432.055002 -358.115873) (xy 432.002669 -358.131241) (xy 431.948683 -358.139005) (xy 431.921412 -358.139492)
			(xy 431.057812 -358.139492) (xy 431.030543 -358.138969) (xy 430.976559 -358.131209) (xy 430.924229 -358.115845)
			(xy 430.874618 -358.09319) (xy 430.828736 -358.063705) (xy 430.787518 -358.027991) (xy 430.751802 -357.986773)
			(xy 430.722316 -357.940893) (xy 430.699659 -357.891283) (xy 430.684293 -357.838953) (xy 430.676531 -357.784969)
			(xy 429.193828 -357.784969) (xy 429.193828 -357.784975) (xy 429.186064 -357.838971) (xy 429.170694 -357.891311)
			(xy 429.148032 -357.940932) (xy 429.118537 -357.986821) (xy 429.082812 -358.028046) (xy 429.041583 -358.063766)
			(xy 428.995689 -358.093255) (xy 428.946066 -358.115911) (xy 428.893724 -358.131275) (xy 428.839727 -358.139032)
			(xy 428.812452 -358.139492) (xy 427.948852 -358.139492) (xy 427.921587 -358.138942) (xy 427.867613 -358.131176)
			(xy 427.815293 -358.115807) (xy 427.765693 -358.09315) (xy 427.719822 -358.063665) (xy 427.678613 -358.027953)
			(xy 427.642906 -357.98674) (xy 427.613427 -357.940865) (xy 427.590776 -357.891262) (xy 427.575414 -357.83894)
			(xy 427.567654 -357.784965) (xy 426.084828 -357.784965) (xy 426.084828 -357.784974) (xy 426.077065 -357.838965)
			(xy 426.061698 -357.891303) (xy 426.039038 -357.94092) (xy 426.009547 -357.986808) (xy 425.973826 -358.028032)
			(xy 425.932602 -358.063752) (xy 425.886713 -358.093241) (xy 425.837095 -358.1159) (xy 425.784757 -358.131267)
			(xy 425.730766 -358.139029) (xy 425.703492 -358.139492) (xy 424.839892 -358.139492) (xy 424.812625 -358.138945)
			(xy 424.758647 -358.131183) (xy 424.706322 -358.115818) (xy 424.656717 -358.093163) (xy 424.610841 -358.06368)
			(xy 424.569627 -358.027967) (xy 424.533916 -357.986753) (xy 424.504433 -357.940876) (xy 424.481779 -357.89127)
			(xy 424.466415 -357.838946) (xy 424.458654 -357.784967) (xy 422.975806 -357.784967) (xy 422.975806 -357.78497)
			(xy 422.968044 -357.838955) (xy 422.952679 -357.891286) (xy 422.930024 -357.940898) (xy 422.900538 -357.986781)
			(xy 422.864824 -358.028001) (xy 422.823607 -358.063719) (xy 422.777726 -358.093208) (xy 422.728116 -358.115868)
			(xy 422.675786 -358.131237) (xy 422.621802 -358.139003) (xy 422.594532 -358.139492) (xy 421.730932 -358.139492)
			(xy 421.703662 -358.138971) (xy 421.649676 -358.131213) (xy 421.597343 -358.115851) (xy 421.54773 -358.093197)
			(xy 421.501846 -358.063712) (xy 421.460625 -358.027998) (xy 421.424907 -357.98678) (xy 421.395419 -357.940898)
			(xy 421.372761 -357.891287) (xy 421.357394 -357.838956) (xy 421.349632 -357.78497) (xy 419.866928 -357.78497)
			(xy 419.866928 -357.784974) (xy 419.859165 -357.838968) (xy 419.843796 -357.891307) (xy 419.821135 -357.940926)
			(xy 419.791642 -357.986815) (xy 419.755919 -358.028039) (xy 419.714692 -358.063759) (xy 419.668801 -358.093248)
			(xy 419.619181 -358.115906) (xy 419.566841 -358.131271) (xy 419.512846 -358.13903) (xy 419.485572 -358.139492)
			(xy 418.621972 -358.139492) (xy 418.594706 -358.138944) (xy 418.54073 -358.131179) (xy 418.488408 -358.115813)
			(xy 418.438805 -358.093157) (xy 418.392931 -358.063673) (xy 418.35172 -358.02796) (xy 418.316011 -357.986746)
			(xy 418.28653 -357.94087) (xy 418.263877 -357.891266) (xy 418.248515 -357.838943) (xy 418.240754 -357.784966)
			(xy 416.757906 -357.784966) (xy 416.757906 -357.784971) (xy 416.750144 -357.838958) (xy 416.734778 -357.89129)
			(xy 416.712121 -357.940904) (xy 416.682633 -357.986788) (xy 416.646917 -358.028008) (xy 416.605697 -358.063726)
			(xy 416.559814 -358.093215) (xy 416.510202 -358.115873) (xy 416.457869 -358.131241) (xy 416.403883 -358.139005)
			(xy 416.376612 -358.139492) (xy 415.513012 -358.139492) (xy 415.485743 -358.138969) (xy 415.431759 -358.131209)
			(xy 415.379429 -358.115845) (xy 415.329818 -358.09319) (xy 415.283936 -358.063705) (xy 415.242718 -358.027991)
			(xy 415.207002 -357.986773) (xy 415.177516 -357.940893) (xy 415.154859 -357.891283) (xy 415.139493 -357.838953)
			(xy 415.131731 -357.784969) (xy 413.649028 -357.784969) (xy 413.649028 -357.784975) (xy 413.641264 -357.838971)
			(xy 413.625894 -357.891311) (xy 413.603232 -357.940932) (xy 413.573737 -357.986821) (xy 413.538012 -358.028046)
			(xy 413.496783 -358.063766) (xy 413.450889 -358.093255) (xy 413.401266 -358.115911) (xy 413.348924 -358.131275)
			(xy 413.294927 -358.139032) (xy 413.267652 -358.139492) (xy 412.404052 -358.139492) (xy 412.376787 -358.138942)
			(xy 412.322813 -358.131176) (xy 412.270493 -358.115807) (xy 412.220893 -358.09315) (xy 412.175022 -358.063665)
			(xy 412.133813 -358.027953) (xy 412.098106 -357.98674) (xy 412.068627 -357.940865) (xy 412.045976 -357.891262)
			(xy 412.030614 -357.83894) (xy 412.022854 -357.784965) (xy 403.522528 -357.784965) (xy 403.522528 -357.784974)
			(xy 403.514765 -357.838967) (xy 403.499397 -357.891305) (xy 403.476736 -357.940924) (xy 403.447244 -357.986812)
			(xy 403.411522 -358.028036) (xy 403.370296 -358.063756) (xy 403.324406 -358.093245) (xy 403.274787 -358.115904)
			(xy 403.222447 -358.131269) (xy 403.168454 -358.13903) (xy 403.14118 -358.139492) (xy 402.27758 -358.139492)
			(xy 402.250314 -358.138944) (xy 402.196337 -358.131181) (xy 402.144013 -358.115815) (xy 402.09441 -358.093159)
			(xy 402.048535 -358.063675) (xy 402.007323 -358.027963) (xy 401.971613 -357.986749) (xy 401.942131 -357.940873)
			(xy 401.919478 -357.891268) (xy 401.904115 -357.838944) (xy 401.896354 -357.784966) (xy 400.413506 -357.784966)
			(xy 400.413506 -357.784971) (xy 400.405744 -357.838957) (xy 400.390378 -357.891289) (xy 400.367722 -357.940901)
			(xy 400.338235 -357.986785) (xy 400.30252 -358.028005) (xy 400.261301 -358.063723) (xy 400.215419 -358.093212)
			(xy 400.165807 -358.115871) (xy 400.113476 -358.13124) (xy 400.059491 -358.139004) (xy 400.03222 -358.139492)
			(xy 399.16862 -358.139492) (xy 399.14135 -358.13897) (xy 399.087365 -358.131211) (xy 399.035034 -358.115847)
			(xy 398.985423 -358.093193) (xy 398.93954 -358.063708) (xy 398.898321 -358.027993) (xy 398.862604 -357.986776)
			(xy 398.833117 -357.940895) (xy 398.81046 -357.891284) (xy 398.795094 -357.838954) (xy 398.787331 -357.78497)
			(xy 397.304628 -357.78497) (xy 397.304628 -357.784975) (xy 397.296865 -357.83897) (xy 397.281495 -357.89131)
			(xy 397.258833 -357.940929) (xy 397.229339 -357.986818) (xy 397.193615 -358.028043) (xy 397.152386 -358.063763)
			(xy 397.106494 -358.093252) (xy 397.056872 -358.115909) (xy 397.00453 -358.131273) (xy 396.950535 -358.139031)
			(xy 396.92326 -358.139492) (xy 396.05966 -358.139492) (xy 396.032395 -358.138943) (xy 395.97842 -358.131177)
			(xy 395.926099 -358.11581) (xy 395.876498 -358.093153) (xy 395.830625 -358.063668) (xy 395.789416 -358.027956)
			(xy 395.753708 -357.986742) (xy 395.724228 -357.940867) (xy 395.701576 -357.891263) (xy 395.686214 -357.838941)
			(xy 395.678454 -357.784965) (xy 394.195605 -357.784965) (xy 394.195605 -357.784972) (xy 394.187843 -357.838959)
			(xy 394.172477 -357.891293) (xy 394.149819 -357.940907) (xy 394.120331 -357.986792) (xy 394.084612 -358.028012)
			(xy 394.043392 -358.063731) (xy 393.997507 -358.093219) (xy 393.947893 -358.115877) (xy 393.895559 -358.131243)
			(xy 393.841572 -358.139005) (xy 393.8143 -358.139492) (xy 392.9507 -358.139492) (xy 392.923433 -358.138946)
			(xy 392.869453 -358.131185) (xy 392.817128 -358.11582) (xy 392.767522 -358.093166) (xy 392.721644 -358.063682)
			(xy 392.68043 -358.02797) (xy 392.644718 -357.986756) (xy 392.615234 -357.940878) (xy 392.59258 -357.891272)
			(xy 392.577215 -357.838947) (xy 392.569454 -357.784967) (xy 391.086606 -357.784967) (xy 391.086606 -357.78497)
			(xy 391.078844 -357.838954) (xy 391.06348 -357.891284) (xy 391.040825 -357.940896) (xy 391.01134 -357.986778)
			(xy 390.975627 -358.027998) (xy 390.934411 -358.063716) (xy 390.888531 -358.093206) (xy 390.838922 -358.115866)
			(xy 390.786593 -358.131236) (xy 390.73261 -358.139003) (xy 390.70534 -358.139492) (xy 389.84174 -358.139492)
			(xy 389.814469 -358.138971) (xy 389.760482 -358.131214) (xy 389.708149 -358.115853) (xy 389.658535 -358.093199)
			(xy 389.61265 -358.063715) (xy 389.571428 -358.028) (xy 389.535709 -357.986783) (xy 389.50622 -357.940901)
			(xy 389.483561 -357.891289) (xy 389.468194 -357.838957) (xy 389.460432 -357.784971) (xy 387.977728 -357.784971)
			(xy 387.977728 -357.784974) (xy 387.969965 -357.838967) (xy 387.954597 -357.891305) (xy 387.931936 -357.940924)
			(xy 387.902444 -357.986812) (xy 387.866722 -358.028036) (xy 387.825496 -358.063756) (xy 387.779606 -358.093245)
			(xy 387.729987 -358.115904) (xy 387.677647 -358.131269) (xy 387.623654 -358.13903) (xy 387.59638 -358.139492)
			(xy 386.73278 -358.139492) (xy 386.705514 -358.138944) (xy 386.651537 -358.131181) (xy 386.599213 -358.115815)
			(xy 386.54961 -358.093159) (xy 386.503735 -358.063675) (xy 386.462523 -358.027963) (xy 386.426813 -357.986749)
			(xy 386.397331 -357.940873) (xy 386.374678 -357.891268) (xy 386.359315 -357.838944) (xy 386.351554 -357.784966)
			(xy 384.868706 -357.784966) (xy 384.868706 -357.784971) (xy 384.860944 -357.838957) (xy 384.845578 -357.891289)
			(xy 384.822922 -357.940901) (xy 384.793435 -357.986785) (xy 384.75772 -358.028005) (xy 384.716501 -358.063723)
			(xy 384.670619 -358.093212) (xy 384.621007 -358.115871) (xy 384.568676 -358.13124) (xy 384.514691 -358.139004)
			(xy 384.48742 -358.139492) (xy 383.62382 -358.139492) (xy 383.59655 -358.13897) (xy 383.542565 -358.131211)
			(xy 383.490234 -358.115847) (xy 383.440623 -358.093193) (xy 383.39474 -358.063708) (xy 383.353521 -358.027993)
			(xy 383.317804 -357.986776) (xy 383.288317 -357.940895) (xy 383.26566 -357.891284) (xy 383.250294 -357.838954)
			(xy 383.242531 -357.78497) (xy 381.759828 -357.78497) (xy 381.759828 -357.784975) (xy 381.752065 -357.83897)
			(xy 381.736695 -357.89131) (xy 381.714033 -357.940929) (xy 381.684539 -357.986818) (xy 381.648815 -358.028043)
			(xy 381.607586 -358.063763) (xy 381.561694 -358.093252) (xy 381.512072 -358.115909) (xy 381.45973 -358.131273)
			(xy 381.405735 -358.139031) (xy 381.37846 -358.139492) (xy 380.51486 -358.139492) (xy 380.487595 -358.138943)
			(xy 380.43362 -358.131177) (xy 380.381299 -358.11581) (xy 380.331698 -358.093153) (xy 380.285825 -358.063668)
			(xy 380.244616 -358.027956) (xy 380.208908 -357.986742) (xy 380.179428 -357.940867) (xy 380.156776 -357.891263)
			(xy 380.141414 -357.838941) (xy 380.133654 -357.784965) (xy 378.650805 -357.784965) (xy 378.650805 -357.784972)
			(xy 378.643043 -357.838959) (xy 378.627677 -357.891293) (xy 378.605019 -357.940907) (xy 378.575531 -357.986792)
			(xy 378.539812 -358.028012) (xy 378.498592 -358.063731) (xy 378.452707 -358.093219) (xy 378.403093 -358.115877)
			(xy 378.350759 -358.131243) (xy 378.296772 -358.139005) (xy 378.2695 -358.139492) (xy 377.4059 -358.139492)
			(xy 377.378633 -358.138946) (xy 377.324653 -358.131185) (xy 377.272328 -358.11582) (xy 377.222722 -358.093166)
			(xy 377.176844 -358.063682) (xy 377.13563 -358.02797) (xy 377.099918 -357.986756) (xy 377.070434 -357.940878)
			(xy 377.04778 -357.891272) (xy 377.032415 -357.838947) (xy 377.024654 -357.784967) (xy 375.541806 -357.784967)
			(xy 375.541806 -357.78497) (xy 375.534044 -357.838954) (xy 375.51868 -357.891284) (xy 375.496025 -357.940896)
			(xy 375.46654 -357.986778) (xy 375.430827 -358.027998) (xy 375.389611 -358.063716) (xy 375.343731 -358.093206)
			(xy 375.294122 -358.115866) (xy 375.241793 -358.131236) (xy 375.18781 -358.139003) (xy 375.16054 -358.139492)
			(xy 374.29694 -358.139492) (xy 374.269669 -358.138971) (xy 374.215682 -358.131214) (xy 374.163349 -358.115853)
			(xy 374.113735 -358.093199) (xy 374.06785 -358.063715) (xy 374.026628 -358.028) (xy 373.990909 -357.986783)
			(xy 373.96142 -357.940901) (xy 373.938761 -357.891289) (xy 373.923394 -357.838957) (xy 373.915632 -357.784971)
			(xy 344.837306 -357.784971) (xy 344.829543 -357.838959) (xy 344.814177 -357.891292) (xy 344.791519 -357.940906)
			(xy 344.762031 -357.98679) (xy 344.726314 -358.028011) (xy 344.685093 -358.063729) (xy 344.639209 -358.093217)
			(xy 344.589596 -358.115876) (xy 344.537263 -358.131242) (xy 344.483275 -358.139005) (xy 344.456004 -358.139492)
			(xy 343.592404 -358.139492) (xy 343.565135 -358.138969) (xy 343.511152 -358.131208) (xy 343.458823 -358.115843)
			(xy 343.409213 -358.093188) (xy 343.363333 -358.063702) (xy 343.322115 -358.027988) (xy 343.2864 -357.986771)
			(xy 343.256914 -357.94089) (xy 343.234258 -357.891281) (xy 343.218893 -357.838952) (xy 343.211131 -357.784969)
			(xy 341.728306 -357.784969) (xy 341.728306 -357.78497) (xy 341.720544 -357.838953) (xy 341.70518 -357.891284)
			(xy 341.682525 -357.940895) (xy 341.653041 -357.986777) (xy 341.617328 -358.027997) (xy 341.576112 -358.063715)
			(xy 341.530233 -358.093204) (xy 341.480625 -358.115865) (xy 341.428297 -358.131235) (xy 341.374313 -358.139002)
			(xy 341.347044 -358.139492) (xy 340.483444 -358.139492) (xy 340.456173 -358.138972) (xy 340.402186 -358.131215)
			(xy 340.349852 -358.115854) (xy 340.300237 -358.093201) (xy 340.254351 -358.063716) (xy 340.213129 -358.028002)
			(xy 340.17741 -357.986784) (xy 340.147921 -357.940902) (xy 340.125261 -357.891289) (xy 340.109894 -357.838957)
			(xy 340.102132 -357.784971) (xy 338.619428 -357.784971) (xy 338.619428 -357.784974) (xy 338.611665 -357.838966)
			(xy 338.596297 -357.891304) (xy 338.573636 -357.940923) (xy 338.544145 -357.986811) (xy 338.508423 -358.028034)
			(xy 338.467198 -358.063755) (xy 338.421308 -358.093244) (xy 338.371689 -358.115903) (xy 338.319351 -358.131269)
			(xy 338.265358 -358.13903) (xy 338.238084 -358.139492) (xy 337.374484 -358.139492) (xy 337.347218 -358.138945)
			(xy 337.29324 -358.131182) (xy 337.240916 -358.115816) (xy 337.191312 -358.093161) (xy 337.145437 -358.063677)
			(xy 337.104224 -358.027964) (xy 337.068514 -357.98675) (xy 337.039032 -357.940874) (xy 337.016378 -357.891269)
			(xy 337.001015 -357.838944) (xy 336.993254 -357.784967) (xy 335.510406 -357.784967) (xy 335.510406 -357.78497)
			(xy 335.502644 -357.838956) (xy 335.487279 -357.891288) (xy 335.464622 -357.9409) (xy 335.435136 -357.986784)
			(xy 335.399421 -358.028004) (xy 335.358203 -358.063722) (xy 335.312321 -358.093211) (xy 335.26271 -358.11587)
			(xy 335.21038 -358.131239) (xy 335.156394 -358.139004) (xy 335.129124 -358.139492) (xy 334.265524 -358.139492)
			(xy 334.238254 -358.13897) (xy 334.184269 -358.131211) (xy 334.131937 -358.115848) (xy 334.082325 -358.093194)
			(xy 334.036442 -358.063709) (xy 333.995222 -358.027995) (xy 333.959505 -357.986777) (xy 333.930017 -357.940896)
			(xy 333.90736 -357.891285) (xy 333.891994 -357.838955) (xy 333.884231 -357.78497) (xy 332.401528 -357.78497)
			(xy 332.401528 -357.784975) (xy 332.393765 -357.838969) (xy 332.378395 -357.891309) (xy 332.355733 -357.940928)
			(xy 332.32624 -357.986817) (xy 332.290516 -358.028041) (xy 332.249288 -358.063762) (xy 332.203397 -358.093251)
			(xy 332.153775 -358.115908) (xy 332.101434 -358.131272) (xy 332.047439 -358.139031) (xy 332.020164 -358.139492)
			(xy 331.156564 -358.139492) (xy 331.129298 -358.138943) (xy 331.075323 -358.131178) (xy 331.023002 -358.115811)
			(xy 330.9734 -358.093154) (xy 330.927527 -358.06367) (xy 330.886317 -358.027957) (xy 330.850609 -357.986744)
			(xy 330.821128 -357.940868) (xy 330.798477 -357.891264) (xy 330.783114 -357.838942) (xy 330.775354 -357.784966)
			(xy 329.292506 -357.784966) (xy 329.292506 -357.784971) (xy 329.284743 -357.838959) (xy 329.269377 -357.891292)
			(xy 329.246719 -357.940906) (xy 329.217231 -357.98679) (xy 329.181514 -358.028011) (xy 329.140293 -358.063729)
			(xy 329.094409 -358.093217) (xy 329.044796 -358.115876) (xy 328.992463 -358.131242) (xy 328.938475 -358.139005)
			(xy 328.911204 -358.139492) (xy 328.047604 -358.139492) (xy 328.020335 -358.138969) (xy 327.966352 -358.131208)
			(xy 327.914023 -358.115843) (xy 327.864413 -358.093188) (xy 327.818533 -358.063702) (xy 327.777315 -358.027988)
			(xy 327.7416 -357.986771) (xy 327.712114 -357.94089) (xy 327.689458 -357.891281) (xy 327.674093 -357.838952)
			(xy 327.666331 -357.784969) (xy 326.183506 -357.784969) (xy 326.183506 -357.78497) (xy 326.175744 -357.838953)
			(xy 326.16038 -357.891284) (xy 326.137725 -357.940895) (xy 326.108241 -357.986777) (xy 326.072528 -358.027997)
			(xy 326.031312 -358.063715) (xy 325.985433 -358.093204) (xy 325.935825 -358.115865) (xy 325.883497 -358.131235)
			(xy 325.829513 -358.139002) (xy 325.802244 -358.139492) (xy 324.938644 -358.139492) (xy 324.911373 -358.138972)
			(xy 324.857386 -358.131215) (xy 324.805052 -358.115854) (xy 324.755437 -358.093201) (xy 324.709551 -358.063716)
			(xy 324.668329 -358.028002) (xy 324.63261 -357.986784) (xy 324.603121 -357.940902) (xy 324.580461 -357.891289)
			(xy 324.565094 -357.838957) (xy 324.557332 -357.784971) (xy 323.074628 -357.784971) (xy 323.074628 -357.784974)
			(xy 323.066865 -357.838966) (xy 323.051497 -357.891304) (xy 323.028836 -357.940923) (xy 322.999345 -357.986811)
			(xy 322.963623 -358.028034) (xy 322.922398 -358.063755) (xy 322.876508 -358.093244) (xy 322.826889 -358.115903)
			(xy 322.774551 -358.131269) (xy 322.720558 -358.13903) (xy 322.693284 -358.139492) (xy 321.829684 -358.139492)
			(xy 321.802418 -358.138945) (xy 321.74844 -358.131182) (xy 321.696116 -358.115816) (xy 321.646512 -358.093161)
			(xy 321.600637 -358.063677) (xy 321.559424 -358.027964) (xy 321.523714 -357.98675) (xy 321.494232 -357.940874)
			(xy 321.471578 -357.891269) (xy 321.456215 -357.838944) (xy 321.448454 -357.784967) (xy 319.965606 -357.784967)
			(xy 319.965606 -357.78497) (xy 319.957844 -357.838956) (xy 319.942479 -357.891288) (xy 319.919822 -357.9409)
			(xy 319.890336 -357.986784) (xy 319.854621 -358.028004) (xy 319.813403 -358.063722) (xy 319.767521 -358.093211)
			(xy 319.71791 -358.11587) (xy 319.66558 -358.131239) (xy 319.611594 -358.139004) (xy 319.584324 -358.139492)
			(xy 318.720724 -358.139492) (xy 318.693454 -358.13897) (xy 318.639469 -358.131211) (xy 318.587137 -358.115848)
			(xy 318.537525 -358.093194) (xy 318.491642 -358.063709) (xy 318.450422 -358.027995) (xy 318.414705 -357.986777)
			(xy 318.385217 -357.940896) (xy 318.36256 -357.891285) (xy 318.347194 -357.838955) (xy 318.339431 -357.78497)
			(xy 316.856728 -357.78497) (xy 316.856728 -357.784975) (xy 316.848965 -357.838969) (xy 316.833595 -357.891309)
			(xy 316.810933 -357.940928) (xy 316.78144 -357.986817) (xy 316.745716 -358.028041) (xy 316.704488 -358.063762)
			(xy 316.658597 -358.093251) (xy 316.608975 -358.115908) (xy 316.556634 -358.131272) (xy 316.502639 -358.139031)
			(xy 316.475364 -358.139492) (xy 315.611764 -358.139492) (xy 315.584498 -358.138943) (xy 315.530523 -358.131178)
			(xy 315.478202 -358.115811) (xy 315.4286 -358.093154) (xy 315.382727 -358.06367) (xy 315.341517 -358.027957)
			(xy 315.305809 -357.986744) (xy 315.276328 -357.940868) (xy 315.253677 -357.891264) (xy 315.238314 -357.838942)
			(xy 315.230554 -357.784966) (xy 300.231606 -357.784966) (xy 300.231606 -357.784971) (xy 300.223843 -357.838959)
			(xy 300.208477 -357.891293) (xy 300.185819 -357.940907) (xy 300.156331 -357.986791) (xy 300.120613 -358.028012)
			(xy 300.079393 -358.06373) (xy 300.033508 -358.093218) (xy 299.983894 -358.115876) (xy 299.931561 -358.131243)
			(xy 299.877573 -358.139005) (xy 299.850302 -358.139492) (xy 298.986702 -358.139492) (xy 298.959433 -358.138969)
			(xy 298.90545 -358.131207) (xy 298.853121 -358.115843) (xy 298.803512 -358.093187) (xy 298.757632 -358.063702)
			(xy 298.716414 -358.027987) (xy 298.6807 -357.98677) (xy 298.651214 -357.94089) (xy 298.628558 -357.89128)
			(xy 298.613193 -357.838952) (xy 298.605431 -357.784969) (xy 297.122606 -357.784969) (xy 297.122606 -357.78497)
			(xy 297.114844 -357.838954) (xy 297.09948 -357.891284) (xy 297.076825 -357.940895) (xy 297.047341 -357.986778)
			(xy 297.011627 -358.027998) (xy 296.970411 -358.063716) (xy 296.924532 -358.093205) (xy 296.874923 -358.115865)
			(xy 296.822595 -358.131235) (xy 296.768612 -358.139003) (xy 296.741342 -358.139492) (xy 295.877742 -358.139492)
			(xy 295.850471 -358.138971) (xy 295.796484 -358.131215) (xy 295.74415 -358.115853) (xy 295.694536 -358.0932)
			(xy 295.64865 -358.063716) (xy 295.607429 -358.028001) (xy 295.571709 -357.986783) (xy 295.54222 -357.940901)
			(xy 295.519561 -357.891289) (xy 295.504194 -357.838957) (xy 295.496432 -357.784971) (xy 294.013728 -357.784971)
			(xy 294.013728 -357.784974) (xy 294.005965 -357.838967) (xy 293.990597 -357.891305) (xy 293.967936 -357.940923)
			(xy 293.938444 -357.986811) (xy 293.902722 -358.028035) (xy 293.861497 -358.063755) (xy 293.815607 -358.093245)
			(xy 293.765988 -358.115903) (xy 293.713649 -358.131269) (xy 293.659656 -358.13903) (xy 293.632382 -358.139492)
			(xy 292.768782 -358.139492) (xy 292.741516 -358.138944) (xy 292.687538 -358.131181) (xy 292.635215 -358.115816)
			(xy 292.585611 -358.09316) (xy 292.539736 -358.063676) (xy 292.498524 -358.027964) (xy 292.462813 -357.98675)
			(xy 292.433331 -357.940873) (xy 292.410678 -357.891268) (xy 292.395315 -357.838944) (xy 292.387554 -357.784966)
			(xy 290.904706 -357.784966) (xy 290.904706 -357.784971) (xy 290.896944 -357.838956) (xy 290.881578 -357.891288)
			(xy 290.858922 -357.940901) (xy 290.829436 -357.986784) (xy 290.79372 -358.028005) (xy 290.752502 -358.063723)
			(xy 290.70662 -358.093211) (xy 290.657009 -358.115871) (xy 290.604678 -358.131239) (xy 290.550692 -358.139004)
			(xy 290.523422 -358.139492) (xy 289.659822 -358.139492) (xy 289.632552 -358.13897) (xy 289.578567 -358.131211)
			(xy 289.526236 -358.115848) (xy 289.476624 -358.093193) (xy 289.430741 -358.063709) (xy 289.389522 -358.027994)
			(xy 289.353805 -357.986777) (xy 289.324317 -357.940895) (xy 289.30166 -357.891285) (xy 289.286294 -357.838954)
			(xy 289.278531 -357.78497) (xy 287.795828 -357.78497) (xy 287.795828 -357.784975) (xy 287.788065 -357.838969)
			(xy 287.772695 -357.891309) (xy 287.750033 -357.940929) (xy 287.72054 -357.986818) (xy 287.684815 -358.028042)
			(xy 287.643587 -358.063762) (xy 287.597695 -358.093251) (xy 287.548073 -358.115908) (xy 287.495732 -358.131273)
			(xy 287.441737 -358.139031) (xy 287.414462 -358.139492) (xy 286.550862 -358.139492) (xy 286.523597 -358.138943)
			(xy 286.469621 -358.131178) (xy 286.4173 -358.11581) (xy 286.367699 -358.093154) (xy 286.321826 -358.063669)
			(xy 286.280617 -358.027957) (xy 286.244908 -357.986743) (xy 286.215428 -357.940868) (xy 286.192777 -357.891264)
			(xy 286.177414 -357.838942) (xy 286.169654 -357.784966) (xy 284.686806 -357.784966) (xy 284.686806 -357.784971)
			(xy 284.679043 -357.838959) (xy 284.663677 -357.891293) (xy 284.641019 -357.940907) (xy 284.611531 -357.986791)
			(xy 284.575813 -358.028012) (xy 284.534593 -358.06373) (xy 284.488708 -358.093218) (xy 284.439094 -358.115876)
			(xy 284.386761 -358.131243) (xy 284.332773 -358.139005) (xy 284.305502 -358.139492) (xy 283.441902 -358.139492)
			(xy 283.414633 -358.138969) (xy 283.36065 -358.131207) (xy 283.308321 -358.115843) (xy 283.258712 -358.093187)
			(xy 283.212832 -358.063702) (xy 283.171614 -358.027987) (xy 283.1359 -357.98677) (xy 283.106414 -357.94089)
			(xy 283.083758 -357.89128) (xy 283.068393 -357.838952) (xy 283.060631 -357.784969) (xy 281.577806 -357.784969)
			(xy 281.577806 -357.78497) (xy 281.570044 -357.838954) (xy 281.55468 -357.891284) (xy 281.532025 -357.940895)
			(xy 281.502541 -357.986778) (xy 281.466827 -358.027998) (xy 281.425611 -358.063716) (xy 281.379732 -358.093205)
			(xy 281.330123 -358.115865) (xy 281.277795 -358.131235) (xy 281.223812 -358.139003) (xy 281.196542 -358.139492)
			(xy 280.332942 -358.139492) (xy 280.305671 -358.138971) (xy 280.251684 -358.131215) (xy 280.19935 -358.115853)
			(xy 280.149736 -358.0932) (xy 280.10385 -358.063716) (xy 280.062629 -358.028001) (xy 280.026909 -357.986783)
			(xy 279.99742 -357.940901) (xy 279.974761 -357.891289) (xy 279.959394 -357.838957) (xy 279.951632 -357.784971)
			(xy 278.468928 -357.784971) (xy 278.468928 -357.784974) (xy 278.461165 -357.838967) (xy 278.445797 -357.891305)
			(xy 278.423136 -357.940923) (xy 278.393644 -357.986811) (xy 278.357922 -358.028035) (xy 278.316697 -358.063755)
			(xy 278.270807 -358.093245) (xy 278.221188 -358.115903) (xy 278.168849 -358.131269) (xy 278.114856 -358.13903)
			(xy 278.087582 -358.139492) (xy 277.223982 -358.139492) (xy 277.196716 -358.138944) (xy 277.142738 -358.131181)
			(xy 277.090415 -358.115816) (xy 277.040811 -358.09316) (xy 276.994936 -358.063676) (xy 276.953724 -358.027964)
			(xy 276.918013 -357.98675) (xy 276.888531 -357.940873) (xy 276.865878 -357.891268) (xy 276.850515 -357.838944)
			(xy 276.842754 -357.784966) (xy 275.359906 -357.784966) (xy 275.359906 -357.784971) (xy 275.352144 -357.838956)
			(xy 275.336778 -357.891288) (xy 275.314122 -357.940901) (xy 275.284636 -357.986784) (xy 275.24892 -358.028005)
			(xy 275.207702 -358.063723) (xy 275.16182 -358.093211) (xy 275.112209 -358.115871) (xy 275.059878 -358.131239)
			(xy 275.005892 -358.139004) (xy 274.978622 -358.139492) (xy 274.115022 -358.139492) (xy 274.087752 -358.13897)
			(xy 274.033767 -358.131211) (xy 273.981436 -358.115848) (xy 273.931824 -358.093193) (xy 273.885941 -358.063709)
			(xy 273.844722 -358.027994) (xy 273.809005 -357.986777) (xy 273.779517 -357.940895) (xy 273.75686 -357.891285)
			(xy 273.741494 -357.838954) (xy 273.733731 -357.78497) (xy 272.251028 -357.78497) (xy 272.251028 -357.784975)
			(xy 272.243265 -357.838969) (xy 272.227895 -357.891309) (xy 272.205233 -357.940929) (xy 272.17574 -357.986818)
			(xy 272.140015 -358.028042) (xy 272.098787 -358.063762) (xy 272.052895 -358.093251) (xy 272.003273 -358.115908)
			(xy 271.950932 -358.131273) (xy 271.896937 -358.139031) (xy 271.869662 -358.139492) (xy 271.006062 -358.139492)
			(xy 270.978797 -358.138943) (xy 270.924821 -358.131178) (xy 270.8725 -358.11581) (xy 270.822899 -358.093154)
			(xy 270.777026 -358.063669) (xy 270.735817 -358.027957) (xy 270.700108 -357.986743) (xy 270.670628 -357.940868)
			(xy 270.647977 -357.891264) (xy 270.632614 -357.838942) (xy 270.624854 -357.784966) (xy 247.276485 -357.784966)
			(xy 247.278987 -357.797946) (xy 247.287038 -357.88226) (xy 247.287542 -357.924608) (xy 247.287038 -357.966956)
			(xy 247.278987 -358.05127) (xy 247.262958 -358.134436) (xy 247.239097 -358.215703) (xy 247.207618 -358.294333)
			(xy 247.168807 -358.369614) (xy 247.123017 -358.440866) (xy 247.070661 -358.507442) (xy 247.012213 -358.56874)
			(xy 246.948203 -358.624205) (xy 246.879211 -358.673334) (xy 246.805861 -358.715683) (xy 246.728818 -358.750867)
			(xy 246.648779 -358.778569) (xy 246.56647 -358.798537) (xy 246.482635 -358.81059) (xy 246.398034 -358.814621)
			(xy 246.313433 -358.81059) (xy 246.229598 -358.798537) (xy 246.147289 -358.778569) (xy 246.06725 -358.750867)
			(xy 245.990207 -358.715683) (xy 245.916857 -358.673334) (xy 245.847865 -358.624205) (xy 245.783855 -358.56874)
			(xy 245.725407 -358.507442) (xy 245.673051 -358.440866) (xy 245.627261 -358.369614) (xy 245.58845 -358.294333)
			(xy 245.556971 -358.215703) (xy 245.53311 -358.134436) (xy 245.517081 -358.05127) (xy 245.50903 -357.966956)
			(xy 188.223925 -357.966956) (xy 188.191672 -358.004178) (xy 188.150456 -358.039891) (xy 188.104577 -358.069375)
			(xy 188.054969 -358.092029) (xy 188.002641 -358.107393) (xy 187.94866 -358.115153) (xy 187.921392 -358.115616)
			(xy 187.057792 -358.115616) (xy 187.03052 -358.115221) (xy 186.97653 -358.107457) (xy 186.924196 -358.092089)
			(xy 186.87458 -358.06943) (xy 186.828695 -358.03994) (xy 186.787473 -358.004221) (xy 186.751755 -357.962999)
			(xy 186.722266 -357.917112) (xy 186.699608 -357.867497) (xy 186.684241 -357.815162) (xy 186.676479 -357.761172)
			(xy 185.193629 -357.761172) (xy 185.18587 -357.815139) (xy 185.170508 -357.86746) (xy 185.147857 -357.917062)
			(xy 185.118378 -357.962936) (xy 185.08267 -358.004147) (xy 185.041461 -358.039858) (xy 184.99559 -358.069342)
			(xy 184.94599 -358.091997) (xy 184.89367 -358.107363) (xy 184.839697 -358.115128) (xy 184.812432 -358.115616)
			(xy 183.948832 -358.115616) (xy 183.921556 -358.115247) (xy 183.867559 -358.107487) (xy 183.815217 -358.092122)
			(xy 183.765593 -358.069463) (xy 183.7197 -358.039973) (xy 183.678471 -358.004251) (xy 183.642746 -357.963025)
			(xy 183.613252 -357.917135) (xy 183.590589 -357.867513) (xy 183.57522 -357.815172) (xy 183.567456 -357.761176)
			(xy 182.084828 -357.761176) (xy 182.084828 -357.784974) (xy 182.077065 -357.838968) (xy 182.061696 -357.891307)
			(xy 182.039035 -357.940926) (xy 182.009542 -357.986815) (xy 181.973819 -358.028039) (xy 181.932592 -358.063759)
			(xy 181.886701 -358.093248) (xy 181.837081 -358.115906) (xy 181.784741 -358.131271) (xy 181.730746 -358.13903)
			(xy 181.703472 -358.139492) (xy 180.839872 -358.139492) (xy 180.812606 -358.138944) (xy 180.75863 -358.131179)
			(xy 180.706308 -358.115813) (xy 180.656705 -358.093157) (xy 180.610831 -358.063673) (xy 180.56962 -358.02796)
			(xy 180.533911 -357.986746) (xy 180.50443 -357.94087) (xy 180.481777 -357.891266) (xy 180.466415 -357.838943)
			(xy 180.458654 -357.784966) (xy 178.975806 -357.784966) (xy 178.975806 -357.784971) (xy 178.968044 -357.838958)
			(xy 178.952678 -357.89129) (xy 178.930021 -357.940904) (xy 178.900533 -357.986788) (xy 178.864817 -358.028008)
			(xy 178.823597 -358.063726) (xy 178.777714 -358.093215) (xy 178.728102 -358.115873) (xy 178.675769 -358.131241)
			(xy 178.621783 -358.139005) (xy 178.594512 -358.139492) (xy 177.730912 -358.139492) (xy 177.703643 -358.138969)
			(xy 177.649659 -358.131209) (xy 177.597329 -358.115845) (xy 177.547718 -358.09319) (xy 177.501836 -358.063705)
			(xy 177.460618 -358.027991) (xy 177.424902 -357.986773) (xy 177.395416 -357.940893) (xy 177.372759 -357.891283)
			(xy 177.357393 -357.838953) (xy 177.349631 -357.784969) (xy 175.866928 -357.784969) (xy 175.866928 -357.784975)
			(xy 175.859164 -357.838971) (xy 175.843794 -357.891311) (xy 175.821132 -357.940932) (xy 175.791637 -357.986821)
			(xy 175.755912 -358.028046) (xy 175.714683 -358.063766) (xy 175.668789 -358.093255) (xy 175.619166 -358.115911)
			(xy 175.566824 -358.131275) (xy 175.512827 -358.139032) (xy 175.485552 -358.139492) (xy 174.621952 -358.139492)
			(xy 174.594687 -358.138942) (xy 174.540713 -358.131176) (xy 174.488393 -358.115807) (xy 174.438793 -358.09315)
			(xy 174.392922 -358.063665) (xy 174.351713 -358.027953) (xy 174.316006 -357.98674) (xy 174.286527 -357.940865)
			(xy 174.263876 -357.891262) (xy 174.248514 -357.83894) (xy 174.240754 -357.784965) (xy 172.757928 -357.784965)
			(xy 172.757928 -357.784974) (xy 172.750165 -357.838965) (xy 172.734798 -357.891303) (xy 172.712138 -357.94092)
			(xy 172.682647 -357.986808) (xy 172.646926 -358.028032) (xy 172.605702 -358.063752) (xy 172.559813 -358.093241)
			(xy 172.510195 -358.1159) (xy 172.457857 -358.131267) (xy 172.403866 -358.139029) (xy 172.376592 -358.139492)
			(xy 171.512992 -358.139492) (xy 171.485725 -358.138945) (xy 171.431747 -358.131183) (xy 171.379422 -358.115818)
			(xy 171.329817 -358.093163) (xy 171.283941 -358.06368) (xy 171.242727 -358.027967) (xy 171.207016 -357.986753)
			(xy 171.177533 -357.940876) (xy 171.154879 -357.89127) (xy 171.139515 -357.838946) (xy 171.131754 -357.784967)
			(xy 169.648906 -357.784967) (xy 169.648906 -357.78497) (xy 169.641144 -357.838955) (xy 169.625779 -357.891286)
			(xy 169.603124 -357.940898) (xy 169.573638 -357.986781) (xy 169.537924 -358.028001) (xy 169.496707 -358.063719)
			(xy 169.450826 -358.093208) (xy 169.401216 -358.115868) (xy 169.348886 -358.131237) (xy 169.294902 -358.139003)
			(xy 169.267632 -358.139492) (xy 168.404032 -358.139492) (xy 168.376762 -358.138971) (xy 168.322776 -358.131213)
			(xy 168.270443 -358.115851) (xy 168.22083 -358.093197) (xy 168.174946 -358.063712) (xy 168.133725 -358.027998)
			(xy 168.098007 -357.98678) (xy 168.068519 -357.940898) (xy 168.045861 -357.891287) (xy 168.030494 -357.838956)
			(xy 168.022732 -357.78497) (xy 166.540028 -357.78497) (xy 166.540028 -357.784974) (xy 166.532265 -357.838968)
			(xy 166.516896 -357.891307) (xy 166.494235 -357.940926) (xy 166.464742 -357.986815) (xy 166.429019 -358.028039)
			(xy 166.387792 -358.063759) (xy 166.341901 -358.093248) (xy 166.292281 -358.115906) (xy 166.239941 -358.131271)
			(xy 166.185946 -358.13903) (xy 166.158672 -358.139492) (xy 165.295072 -358.139492) (xy 165.267806 -358.138944)
			(xy 165.21383 -358.131179) (xy 165.161508 -358.115813) (xy 165.111905 -358.093157) (xy 165.066031 -358.063673)
			(xy 165.02482 -358.02796) (xy 164.989111 -357.986746) (xy 164.95963 -357.94087) (xy 164.936977 -357.891266)
			(xy 164.921615 -357.838943) (xy 164.913854 -357.784966) (xy 163.431006 -357.784966) (xy 163.431006 -357.784971)
			(xy 163.423244 -357.838958) (xy 163.407878 -357.89129) (xy 163.385221 -357.940904) (xy 163.355733 -357.986788)
			(xy 163.320017 -358.028008) (xy 163.278797 -358.063726) (xy 163.232914 -358.093215) (xy 163.183302 -358.115873)
			(xy 163.130969 -358.131241) (xy 163.076983 -358.139005) (xy 163.049712 -358.139492) (xy 162.186112 -358.139492)
			(xy 162.158843 -358.138969) (xy 162.104859 -358.131209) (xy 162.052529 -358.115845) (xy 162.002918 -358.09319)
			(xy 161.957036 -358.063705) (xy 161.915818 -358.027991) (xy 161.880102 -357.986773) (xy 161.850616 -357.940893)
			(xy 161.827959 -357.891283) (xy 161.812593 -357.838953) (xy 161.804831 -357.784969) (xy 160.322128 -357.784969)
			(xy 160.322128 -357.784975) (xy 160.314364 -357.838971) (xy 160.298994 -357.891311) (xy 160.276332 -357.940932)
			(xy 160.246837 -357.986821) (xy 160.211112 -358.028046) (xy 160.169883 -358.063766) (xy 160.123989 -358.093255)
			(xy 160.074366 -358.115911) (xy 160.022024 -358.131275) (xy 159.968027 -358.139032) (xy 159.940752 -358.139492)
			(xy 159.077152 -358.139492) (xy 159.049887 -358.138942) (xy 158.995913 -358.131176) (xy 158.943593 -358.115807)
			(xy 158.893993 -358.09315) (xy 158.848122 -358.063665) (xy 158.806913 -358.027953) (xy 158.771206 -357.98674)
			(xy 158.741727 -357.940865) (xy 158.719076 -357.891262) (xy 158.703714 -357.83894) (xy 158.695954 -357.784965)
			(xy 144.196606 -357.784965) (xy 144.196606 -357.784971) (xy 144.188843 -357.838958) (xy 144.173477 -357.891291)
			(xy 144.15082 -357.940905) (xy 144.121332 -357.986789) (xy 144.085615 -358.02801) (xy 144.044395 -358.063728)
			(xy 143.998512 -358.093216) (xy 143.948899 -358.115875) (xy 143.896566 -358.131242) (xy 143.842579 -358.139005)
			(xy 143.815308 -358.139492) (xy 142.951708 -358.139492) (xy 142.924439 -358.138969) (xy 142.870455 -358.131209)
			(xy 142.818126 -358.115844) (xy 142.768515 -358.093189) (xy 142.722634 -358.063704) (xy 142.681417 -358.027989)
			(xy 142.645701 -357.986772) (xy 142.616215 -357.940892) (xy 142.593559 -357.891282) (xy 142.578193 -357.838953)
			(xy 142.570431 -357.784969) (xy 141.087606 -357.784969) (xy 141.079845 -357.838953) (xy 141.06448 -357.891283)
			(xy 141.041826 -357.940894) (xy 141.012342 -357.986776) (xy 140.976629 -358.027995) (xy 140.935414 -358.063713)
			(xy 140.889536 -358.093203) (xy 140.839928 -358.115864) (xy 140.7876 -358.131234) (xy 140.733617 -358.139002)
			(xy 140.706348 -358.139492) (xy 139.842748 -358.139492) (xy 139.815477 -358.138972) (xy 139.761489 -358.131216)
			(xy 139.709155 -358.115855) (xy 139.659539 -358.093202) (xy 139.613653 -358.063718) (xy 139.572431 -358.028003)
			(xy 139.536711 -357.986785) (xy 139.507221 -357.940903) (xy 139.484562 -357.89129) (xy 139.469194 -357.838958)
			(xy 139.461432 -357.784971) (xy 137.978728 -357.784971) (xy 137.978728 -357.784974) (xy 137.970965 -357.838966)
			(xy 137.955597 -357.891304) (xy 137.932937 -357.940921) (xy 137.903446 -357.986809) (xy 137.867724 -358.028033)
			(xy 137.8265 -358.063753) (xy 137.780611 -358.093243) (xy 137.730992 -358.115901) (xy 137.678654 -358.131268)
			(xy 137.624662 -358.139029) (xy 137.597388 -358.139492) (xy 136.733788 -358.139492) (xy 136.706521 -358.138945)
			(xy 136.652543 -358.131182) (xy 136.600219 -358.115817) (xy 136.550615 -358.093162) (xy 136.504739 -358.063678)
			(xy 136.463526 -358.027966) (xy 136.427815 -357.986752) (xy 136.398332 -357.940875) (xy 136.375679 -357.891269)
			(xy 136.360315 -357.838945) (xy 136.352554 -357.784967) (xy 134.869706 -357.784967) (xy 134.869706 -357.78497)
			(xy 134.861944 -357.838956) (xy 134.846579 -357.891287) (xy 134.823923 -357.940899) (xy 134.794437 -357.986782)
			(xy 134.758722 -358.028003) (xy 134.717505 -358.063721) (xy 134.671624 -358.09321) (xy 134.622013 -358.115869)
			(xy 134.569683 -358.131238) (xy 134.515698 -358.139004) (xy 134.488428 -358.139492) (xy 133.624828 -358.139492)
			(xy 133.597558 -358.13897) (xy 133.543572 -358.131212) (xy 133.49124 -358.11585) (xy 133.441627 -358.093195)
			(xy 133.395744 -358.063711) (xy 133.354524 -358.027996) (xy 133.318806 -357.986779) (xy 133.289318 -357.940897)
			(xy 133.26666 -357.891286) (xy 133.251294 -357.838955) (xy 133.243531 -357.78497) (xy 131.760828 -357.78497)
			(xy 131.760828 -357.784975) (xy 131.753065 -357.838969) (xy 131.737696 -357.891308) (xy 131.715034 -357.940927)
			(xy 131.685541 -357.986816) (xy 131.649817 -358.02804) (xy 131.60859 -358.06376) (xy 131.562699 -358.093249)
			(xy 131.513078 -358.115907) (xy 131.460737 -358.131272) (xy 131.406743 -358.139031) (xy 131.379468 -358.139492)
			(xy 130.515868 -358.139492) (xy 130.488602 -358.138943) (xy 130.434626 -358.131179) (xy 130.382305 -358.115812)
			(xy 130.332703 -358.093156) (xy 130.286829 -358.063671) (xy 130.245619 -358.027959) (xy 130.20991 -357.986745)
			(xy 130.180429 -357.940869) (xy 130.157777 -357.891265) (xy 130.142414 -357.838942) (xy 130.134654 -357.784966)
			(xy 128.651806 -357.784966) (xy 128.651806 -357.784971) (xy 128.644043 -357.838958) (xy 128.628677 -357.891291)
			(xy 128.60602 -357.940905) (xy 128.576532 -357.986789) (xy 128.540815 -358.02801) (xy 128.499595 -358.063728)
			(xy 128.453712 -358.093216) (xy 128.404099 -358.115875) (xy 128.351766 -358.131242) (xy 128.297779 -358.139005)
			(xy 128.270508 -358.139492) (xy 127.406908 -358.139492) (xy 127.379639 -358.138969) (xy 127.325655 -358.131209)
			(xy 127.273326 -358.115844) (xy 127.223715 -358.093189) (xy 127.177834 -358.063704) (xy 127.136617 -358.027989)
			(xy 127.100901 -357.986772) (xy 127.071415 -357.940892) (xy 127.048759 -357.891282) (xy 127.033393 -357.838953)
			(xy 127.025631 -357.784969) (xy 125.542806 -357.784969) (xy 125.535045 -357.838953) (xy 125.51968 -357.891283)
			(xy 125.497026 -357.940894) (xy 125.467542 -357.986776) (xy 125.431829 -358.027995) (xy 125.390614 -358.063713)
			(xy 125.344736 -358.093203) (xy 125.295128 -358.115864) (xy 125.2428 -358.131234) (xy 125.188817 -358.139002)
			(xy 125.161548 -358.139492) (xy 124.297948 -358.139492) (xy 124.270677 -358.138972) (xy 124.216689 -358.131216)
			(xy 124.164355 -358.115855) (xy 124.114739 -358.093202) (xy 124.068853 -358.063718) (xy 124.027631 -358.028003)
			(xy 123.991911 -357.986785) (xy 123.962421 -357.940903) (xy 123.939762 -357.89129) (xy 123.924394 -357.838958)
			(xy 123.916632 -357.784971) (xy 122.433928 -357.784971) (xy 122.433928 -357.784974) (xy 122.426165 -357.838966)
			(xy 122.410797 -357.891304) (xy 122.388137 -357.940921) (xy 122.358646 -357.986809) (xy 122.322924 -358.028033)
			(xy 122.2817 -358.063753) (xy 122.235811 -358.093243) (xy 122.186192 -358.115901) (xy 122.133854 -358.131268)
			(xy 122.079862 -358.139029) (xy 122.052588 -358.139492) (xy 121.188988 -358.139492) (xy 121.161721 -358.138945)
			(xy 121.107743 -358.131182) (xy 121.055419 -358.115817) (xy 121.005815 -358.093162) (xy 120.959939 -358.063678)
			(xy 120.918726 -358.027966) (xy 120.883015 -357.986752) (xy 120.853532 -357.940875) (xy 120.830879 -357.891269)
			(xy 120.815515 -357.838945) (xy 120.807754 -357.784967) (xy 119.324906 -357.784967) (xy 119.324906 -357.78497)
			(xy 119.317144 -357.838956) (xy 119.301779 -357.891287) (xy 119.279123 -357.940899) (xy 119.249637 -357.986782)
			(xy 119.213922 -358.028003) (xy 119.172705 -358.063721) (xy 119.126824 -358.09321) (xy 119.077213 -358.115869)
			(xy 119.024883 -358.131238) (xy 118.970898 -358.139004) (xy 118.943628 -358.139492) (xy 118.080028 -358.139492)
			(xy 118.052758 -358.13897) (xy 117.998772 -358.131212) (xy 117.94644 -358.11585) (xy 117.896827 -358.093195)
			(xy 117.850944 -358.063711) (xy 117.809724 -358.027996) (xy 117.774006 -357.986779) (xy 117.744518 -357.940897)
			(xy 117.72186 -357.891286) (xy 117.706494 -357.838955) (xy 117.698731 -357.78497) (xy 116.216028 -357.78497)
			(xy 116.216028 -357.784975) (xy 116.208265 -357.838969) (xy 116.192896 -357.891308) (xy 116.170234 -357.940927)
			(xy 116.140741 -357.986816) (xy 116.105017 -358.02804) (xy 116.06379 -358.06376) (xy 116.017899 -358.093249)
			(xy 115.968278 -358.115907) (xy 115.915937 -358.131272) (xy 115.861943 -358.139031) (xy 115.834668 -358.139492)
			(xy 114.971068 -358.139492) (xy 114.943802 -358.138943) (xy 114.889826 -358.131179) (xy 114.837505 -358.115812)
			(xy 114.787903 -358.093156) (xy 114.742029 -358.063671) (xy 114.700819 -358.027959) (xy 114.66511 -357.986745)
			(xy 114.635629 -357.940869) (xy 114.612977 -357.891265) (xy 114.597614 -357.838942) (xy 114.589854 -357.784966)
			(xy 93.706706 -357.784966) (xy 93.706706 -357.78497) (xy 93.698944 -357.838954) (xy 93.68358 -357.891284)
			(xy 93.660925 -357.940895) (xy 93.631441 -357.986778) (xy 93.595727 -358.027998) (xy 93.554511 -358.063716)
			(xy 93.508632 -358.093205) (xy 93.459023 -358.115865) (xy 93.406695 -358.131235) (xy 93.352712 -358.139003)
			(xy 93.325442 -358.139492) (xy 92.461842 -358.139492) (xy 92.434571 -358.138971) (xy 92.380584 -358.131215)
			(xy 92.32825 -358.115853) (xy 92.278636 -358.0932) (xy 92.23275 -358.063716) (xy 92.191529 -358.028001)
			(xy 92.155809 -357.986783) (xy 92.12632 -357.940901) (xy 92.103661 -357.891289) (xy 92.088294 -357.838957)
			(xy 92.080532 -357.784971) (xy 90.597828 -357.784971) (xy 90.597828 -357.784974) (xy 90.590065 -357.838967)
			(xy 90.574697 -357.891305) (xy 90.552036 -357.940923) (xy 90.522544 -357.986811) (xy 90.486822 -358.028035)
			(xy 90.445597 -358.063755) (xy 90.399707 -358.093245) (xy 90.350088 -358.115903) (xy 90.297749 -358.131269)
			(xy 90.243756 -358.13903) (xy 90.216482 -358.139492) (xy 89.352882 -358.139492) (xy 89.325616 -358.138944)
			(xy 89.271638 -358.131181) (xy 89.219315 -358.115816) (xy 89.169711 -358.09316) (xy 89.123836 -358.063676)
			(xy 89.082624 -358.027964) (xy 89.046913 -357.98675) (xy 89.017431 -357.940873) (xy 88.994778 -357.891268)
			(xy 88.979415 -357.838944) (xy 88.971654 -357.784966) (xy 87.488806 -357.784966) (xy 87.488806 -357.784971)
			(xy 87.481044 -357.838956) (xy 87.465678 -357.891288) (xy 87.443022 -357.940901) (xy 87.413536 -357.986784)
			(xy 87.37782 -358.028005) (xy 87.336602 -358.063723) (xy 87.29072 -358.093211) (xy 87.241109 -358.115871)
			(xy 87.188778 -358.131239) (xy 87.134792 -358.139004) (xy 87.107522 -358.139492) (xy 86.243922 -358.139492)
			(xy 86.216652 -358.13897) (xy 86.162667 -358.131211) (xy 86.110336 -358.115848) (xy 86.060724 -358.093193)
			(xy 86.014841 -358.063709) (xy 85.973622 -358.027994) (xy 85.937905 -357.986777) (xy 85.908417 -357.940895)
			(xy 85.88576 -357.891285) (xy 85.870394 -357.838954) (xy 85.862631 -357.78497) (xy 84.379928 -357.78497)
			(xy 84.379928 -357.784975) (xy 84.372165 -357.838969) (xy 84.356795 -357.891309) (xy 84.334133 -357.940929)
			(xy 84.30464 -357.986818) (xy 84.268915 -358.028042) (xy 84.227687 -358.063762) (xy 84.181795 -358.093251)
			(xy 84.132173 -358.115908) (xy 84.079832 -358.131273) (xy 84.025837 -358.139031) (xy 83.998562 -358.139492)
			(xy 83.134962 -358.139492) (xy 83.107697 -358.138943) (xy 83.053721 -358.131178) (xy 83.0014 -358.11581)
			(xy 82.951799 -358.093154) (xy 82.905926 -358.063669) (xy 82.864717 -358.027957) (xy 82.829008 -357.986743)
			(xy 82.799528 -357.940868) (xy 82.776877 -357.891264) (xy 82.761514 -357.838942) (xy 82.753754 -357.784966)
			(xy 81.270906 -357.784966) (xy 81.270906 -357.784971) (xy 81.263143 -357.838959) (xy 81.247777 -357.891293)
			(xy 81.225119 -357.940907) (xy 81.195631 -357.986791) (xy 81.159913 -358.028012) (xy 81.118693 -358.06373)
			(xy 81.072808 -358.093218) (xy 81.023194 -358.115876) (xy 80.970861 -358.131243) (xy 80.916873 -358.139005)
			(xy 80.889602 -358.139492) (xy 80.026002 -358.139492) (xy 79.998733 -358.138969) (xy 79.94475 -358.131207)
			(xy 79.892421 -358.115843) (xy 79.842812 -358.093187) (xy 79.796932 -358.063702) (xy 79.755714 -358.027987)
			(xy 79.72 -357.98677) (xy 79.690514 -357.94089) (xy 79.667858 -357.89128) (xy 79.652493 -357.838952)
			(xy 79.644731 -357.784969) (xy 78.161906 -357.784969) (xy 78.161906 -357.78497) (xy 78.154144 -357.838954)
			(xy 78.13878 -357.891284) (xy 78.116125 -357.940895) (xy 78.086641 -357.986778) (xy 78.050927 -358.027998)
			(xy 78.009711 -358.063716) (xy 77.963832 -358.093205) (xy 77.914223 -358.115865) (xy 77.861895 -358.131235)
			(xy 77.807912 -358.139003) (xy 77.780642 -358.139492) (xy 76.917042 -358.139492) (xy 76.889771 -358.138971)
			(xy 76.835784 -358.131215) (xy 76.78345 -358.115853) (xy 76.733836 -358.0932) (xy 76.68795 -358.063716)
			(xy 76.646729 -358.028001) (xy 76.611009 -357.986783) (xy 76.58152 -357.940901) (xy 76.558861 -357.891289)
			(xy 76.543494 -357.838957) (xy 76.535732 -357.784971) (xy 75.053028 -357.784971) (xy 75.053028 -357.784974)
			(xy 75.045265 -357.838967) (xy 75.029897 -357.891305) (xy 75.007236 -357.940923) (xy 74.977744 -357.986811)
			(xy 74.942022 -358.028035) (xy 74.900797 -358.063755) (xy 74.854907 -358.093245) (xy 74.805288 -358.115903)
			(xy 74.752949 -358.131269) (xy 74.698956 -358.13903) (xy 74.671682 -358.139492) (xy 73.808082 -358.139492)
			(xy 73.780816 -358.138944) (xy 73.726838 -358.131181) (xy 73.674515 -358.115816) (xy 73.624911 -358.09316)
			(xy 73.579036 -358.063676) (xy 73.537824 -358.027964) (xy 73.502113 -357.98675) (xy 73.472631 -357.940873)
			(xy 73.449978 -357.891268) (xy 73.434615 -357.838944) (xy 73.426854 -357.784966) (xy 71.944006 -357.784966)
			(xy 71.944006 -357.784971) (xy 71.936244 -357.838956) (xy 71.920878 -357.891288) (xy 71.898222 -357.940901)
			(xy 71.868736 -357.986784) (xy 71.83302 -358.028005) (xy 71.791802 -358.063723) (xy 71.74592 -358.093211)
			(xy 71.696309 -358.115871) (xy 71.643978 -358.131239) (xy 71.589992 -358.139004) (xy 71.562722 -358.139492)
			(xy 70.699122 -358.139492) (xy 70.671852 -358.13897) (xy 70.617867 -358.131211) (xy 70.565536 -358.115848)
			(xy 70.515924 -358.093193) (xy 70.470041 -358.063709) (xy 70.428822 -358.027994) (xy 70.393105 -357.986777)
			(xy 70.363617 -357.940895) (xy 70.34096 -357.891285) (xy 70.325594 -357.838954) (xy 70.317831 -357.78497)
			(xy 68.835128 -357.78497) (xy 68.835128 -357.784975) (xy 68.827365 -357.838969) (xy 68.811995 -357.891309)
			(xy 68.789333 -357.940929) (xy 68.75984 -357.986818) (xy 68.724115 -358.028042) (xy 68.682887 -358.063762)
			(xy 68.636995 -358.093251) (xy 68.587373 -358.115908) (xy 68.535032 -358.131273) (xy 68.481037 -358.139031)
			(xy 68.453762 -358.139492) (xy 67.590162 -358.139492) (xy 67.562897 -358.138943) (xy 67.508921 -358.131178)
			(xy 67.4566 -358.11581) (xy 67.406999 -358.093154) (xy 67.361126 -358.063669) (xy 67.319917 -358.027957)
			(xy 67.284208 -357.986743) (xy 67.254728 -357.940868) (xy 67.232077 -357.891264) (xy 67.216714 -357.838942)
			(xy 67.208954 -357.784966) (xy 65.726106 -357.784966) (xy 65.726106 -357.784971) (xy 65.718343 -357.838959)
			(xy 65.702977 -357.891293) (xy 65.680319 -357.940907) (xy 65.650831 -357.986791) (xy 65.615113 -358.028012)
			(xy 65.573893 -358.06373) (xy 65.528008 -358.093218) (xy 65.478394 -358.115876) (xy 65.426061 -358.131243)
			(xy 65.372073 -358.139005) (xy 65.344802 -358.139492) (xy 64.481202 -358.139492) (xy 64.453933 -358.138969)
			(xy 64.39995 -358.131207) (xy 64.347621 -358.115843) (xy 64.298012 -358.093187) (xy 64.252132 -358.063702)
			(xy 64.210914 -358.027987) (xy 64.1752 -357.98677) (xy 64.145714 -357.94089) (xy 64.123058 -357.89128)
			(xy 64.107693 -357.838952) (xy 64.099931 -357.784969) (xy 51.666906 -357.784969) (xy 51.659145 -357.838953)
			(xy 51.64378 -357.891283) (xy 51.621126 -357.940894) (xy 51.591642 -357.986776) (xy 51.555929 -358.027995)
			(xy 51.514714 -358.063713) (xy 51.468836 -358.093203) (xy 51.419228 -358.115864) (xy 51.3669 -358.131234)
			(xy 51.312917 -358.139002) (xy 51.285648 -358.139492) (xy 50.422048 -358.139492) (xy 50.394777 -358.138972)
			(xy 50.340789 -358.131216) (xy 50.288455 -358.115855) (xy 50.238839 -358.093202) (xy 50.192953 -358.063718)
			(xy 50.151731 -358.028003) (xy 50.116011 -357.986785) (xy 50.086521 -357.940903) (xy 50.063862 -357.89129)
			(xy 50.048494 -357.838958) (xy 50.040732 -357.784971) (xy 48.558028 -357.784971) (xy 48.558028 -357.784974)
			(xy 48.550265 -357.838966) (xy 48.534897 -357.891304) (xy 48.512237 -357.940921) (xy 48.482746 -357.986809)
			(xy 48.447024 -358.028033) (xy 48.4058 -358.063753) (xy 48.359911 -358.093243) (xy 48.310292 -358.115901)
			(xy 48.257954 -358.131268) (xy 48.203962 -358.139029) (xy 48.176688 -358.139492) (xy 47.313088 -358.139492)
			(xy 47.285821 -358.138945) (xy 47.231843 -358.131182) (xy 47.179519 -358.115817) (xy 47.129915 -358.093162)
			(xy 47.084039 -358.063678) (xy 47.042826 -358.027966) (xy 47.007115 -357.986752) (xy 46.977632 -357.940875)
			(xy 46.954979 -357.891269) (xy 46.939615 -357.838945) (xy 46.931854 -357.784967) (xy 45.449006 -357.784967)
			(xy 45.449006 -357.78497) (xy 45.441244 -357.838956) (xy 45.425879 -357.891287) (xy 45.403223 -357.940899)
			(xy 45.373737 -357.986782) (xy 45.338022 -358.028003) (xy 45.296805 -358.063721) (xy 45.250924 -358.09321)
			(xy 45.201313 -358.115869) (xy 45.148983 -358.131238) (xy 45.094998 -358.139004) (xy 45.067728 -358.139492)
			(xy 44.204128 -358.139492) (xy 44.176858 -358.13897) (xy 44.122872 -358.131212) (xy 44.07054 -358.11585)
			(xy 44.020927 -358.093195) (xy 43.975044 -358.063711) (xy 43.933824 -358.027996) (xy 43.898106 -357.986779)
			(xy 43.868618 -357.940897) (xy 43.84596 -357.891286) (xy 43.830594 -357.838955) (xy 43.822831 -357.78497)
			(xy 42.340128 -357.78497) (xy 42.340128 -357.784975) (xy 42.332365 -357.838969) (xy 42.316996 -357.891308)
			(xy 42.294334 -357.940927) (xy 42.264841 -357.986816) (xy 42.229117 -358.02804) (xy 42.18789 -358.06376)
			(xy 42.141999 -358.093249) (xy 42.092378 -358.115907) (xy 42.040037 -358.131272) (xy 41.986043 -358.139031)
			(xy 41.958768 -358.139492) (xy 41.095168 -358.139492) (xy 41.067902 -358.138943) (xy 41.013926 -358.131179)
			(xy 40.961605 -358.115812) (xy 40.912003 -358.093156) (xy 40.866129 -358.063671) (xy 40.824919 -358.027959)
			(xy 40.78921 -357.986745) (xy 40.759729 -357.940869) (xy 40.737077 -357.891265) (xy 40.721714 -357.838942)
			(xy 40.713954 -357.784966) (xy 39.231106 -357.784966) (xy 39.231106 -357.784971) (xy 39.223343 -357.838958)
			(xy 39.207977 -357.891291) (xy 39.18532 -357.940905) (xy 39.155832 -357.986789) (xy 39.120115 -358.02801)
			(xy 39.078895 -358.063728) (xy 39.033012 -358.093216) (xy 38.983399 -358.115875) (xy 38.931066 -358.131242)
			(xy 38.877079 -358.139005) (xy 38.849808 -358.139492) (xy 37.986208 -358.139492) (xy 37.958939 -358.138969)
			(xy 37.904955 -358.131209) (xy 37.852626 -358.115844) (xy 37.803015 -358.093189) (xy 37.757134 -358.063704)
			(xy 37.715917 -358.027989) (xy 37.680201 -357.986772) (xy 37.650715 -357.940892) (xy 37.628059 -357.891282)
			(xy 37.612693 -357.838953) (xy 37.604931 -357.784969) (xy 36.122106 -357.784969) (xy 36.114345 -357.838953)
			(xy 36.09898 -357.891283) (xy 36.076326 -357.940894) (xy 36.046842 -357.986776) (xy 36.011129 -358.027995)
			(xy 35.969914 -358.063713) (xy 35.924036 -358.093203) (xy 35.874428 -358.115864) (xy 35.8221 -358.131234)
			(xy 35.768117 -358.139002) (xy 35.740848 -358.139492) (xy 34.877248 -358.139492) (xy 34.849977 -358.138972)
			(xy 34.795989 -358.131216) (xy 34.743655 -358.115855) (xy 34.694039 -358.093202) (xy 34.648153 -358.063718)
			(xy 34.606931 -358.028003) (xy 34.571211 -357.986785) (xy 34.541721 -357.940903) (xy 34.519062 -357.89129)
			(xy 34.503694 -357.838958) (xy 34.495932 -357.784971) (xy 33.013228 -357.784971) (xy 33.013228 -357.784974)
			(xy 33.005465 -357.838966) (xy 32.990097 -357.891304) (xy 32.967437 -357.940921) (xy 32.937946 -357.986809)
			(xy 32.902224 -358.028033) (xy 32.861 -358.063753) (xy 32.815111 -358.093243) (xy 32.765492 -358.115901)
			(xy 32.713154 -358.131268) (xy 32.659162 -358.139029) (xy 32.631888 -358.139492) (xy 31.768288 -358.139492)
			(xy 31.741021 -358.138945) (xy 31.687043 -358.131182) (xy 31.634719 -358.115817) (xy 31.585115 -358.093162)
			(xy 31.539239 -358.063678) (xy 31.498026 -358.027966) (xy 31.462315 -357.986752) (xy 31.432832 -357.940875)
			(xy 31.410179 -357.891269) (xy 31.394815 -357.838945) (xy 31.387054 -357.784967) (xy 29.904206 -357.784967)
			(xy 29.904206 -357.78497) (xy 29.896444 -357.838956) (xy 29.881079 -357.891287) (xy 29.858423 -357.940899)
			(xy 29.828937 -357.986782) (xy 29.793222 -358.028003) (xy 29.752005 -358.063721) (xy 29.706124 -358.09321)
			(xy 29.656513 -358.115869) (xy 29.604183 -358.131238) (xy 29.550198 -358.139004) (xy 29.522928 -358.139492)
			(xy 28.659328 -358.139492) (xy 28.632058 -358.13897) (xy 28.578072 -358.131212) (xy 28.52574 -358.11585)
			(xy 28.476127 -358.093195) (xy 28.430244 -358.063711) (xy 28.389024 -358.027996) (xy 28.353306 -357.986779)
			(xy 28.323818 -357.940897) (xy 28.30116 -357.891286) (xy 28.285794 -357.838955) (xy 28.278031 -357.78497)
			(xy 26.795328 -357.78497) (xy 26.795328 -357.784975) (xy 26.787565 -357.838969) (xy 26.772196 -357.891308)
			(xy 26.749534 -357.940927) (xy 26.720041 -357.986816) (xy 26.684317 -358.02804) (xy 26.64309 -358.06376)
			(xy 26.597199 -358.093249) (xy 26.547578 -358.115907) (xy 26.495237 -358.131272) (xy 26.441243 -358.139031)
			(xy 26.413968 -358.139492) (xy 25.550368 -358.139492) (xy 25.523102 -358.138943) (xy 25.469126 -358.131179)
			(xy 25.416805 -358.115812) (xy 25.367203 -358.093156) (xy 25.321329 -358.063671) (xy 25.280119 -358.027959)
			(xy 25.24441 -357.986745) (xy 25.214929 -357.940869) (xy 25.192277 -357.891265) (xy 25.176914 -357.838942)
			(xy 25.169154 -357.784966) (xy 23.686306 -357.784966) (xy 23.686306 -357.784971) (xy 23.678543 -357.838958)
			(xy 23.663177 -357.891291) (xy 23.64052 -357.940905) (xy 23.611032 -357.986789) (xy 23.575315 -358.02801)
			(xy 23.534095 -358.063728) (xy 23.488212 -358.093216) (xy 23.438599 -358.115875) (xy 23.386266 -358.131242)
			(xy 23.332279 -358.139005) (xy 23.305008 -358.139492) (xy 22.441408 -358.139492) (xy 22.414139 -358.138969)
			(xy 22.360155 -358.131209) (xy 22.307826 -358.115844) (xy 22.258215 -358.093189) (xy 22.212334 -358.063704)
			(xy 22.171117 -358.027989) (xy 22.135401 -357.986772) (xy 22.105915 -357.940892) (xy 22.083259 -357.891282)
			(xy 22.067893 -357.838953) (xy 22.060131 -357.784969) (xy 0.509016 -357.784969) (xy 0.509016 -360.017783)
			(xy 101.774757 -360.017783) (xy 101.774757 -359.957817) (xy 101.782584 -359.898365) (xy 101.798104 -359.840443)
			(xy 101.821052 -359.785042) (xy 101.851035 -359.733111) (xy 101.88754 -359.685538) (xy 101.929942 -359.643136)
			(xy 101.977516 -359.606632) (xy 102.029448 -359.57665) (xy 102.084849 -359.553703) (xy 102.142771 -359.538183)
			(xy 102.202223 -359.530357) (xy 102.232206 -359.529888) (xy 103.095806 -359.529888) (xy 103.125793 -359.530279)
			(xy 103.185255 -359.538108) (xy 103.243186 -359.553631) (xy 103.298595 -359.576583) (xy 103.350534 -359.60657)
			(xy 103.398115 -359.643081) (xy 103.440523 -359.68549) (xy 103.477033 -359.733071) (xy 103.50702 -359.785011)
			(xy 103.529971 -359.84042) (xy 103.545494 -359.898351) (xy 103.553322 -359.957813) (xy 103.553322 -360.017787)
			(xy 103.545494 -360.077249) (xy 103.529971 -360.13518) (xy 103.50702 -360.190589) (xy 103.477033 -360.242529)
			(xy 103.440523 -360.29011) (xy 103.398115 -360.332519) (xy 103.350534 -360.36903) (xy 103.298595 -360.399017)
			(xy 103.243186 -360.421969) (xy 103.185255 -360.437492) (xy 103.125793 -360.445321) (xy 103.095806 -360.445812)
			(xy 102.232206 -360.445812) (xy 102.202223 -360.445243) (xy 102.142771 -360.437417) (xy 102.084849 -360.421897)
			(xy 102.029448 -360.39895) (xy 101.977516 -360.368968) (xy 101.929942 -360.332464) (xy 101.88754 -360.290062)
			(xy 101.851035 -360.242489) (xy 101.821052 -360.190558) (xy 101.798104 -360.135157) (xy 101.782584 -360.077235)
			(xy 101.774757 -360.017783) (xy 0.509016 -360.017783) (xy 0.509016 -363.334808) (xy 54.890416 -363.334808)
			(xy 54.890416 -362.471208) (xy 54.890906 -362.441224) (xy 54.898734 -362.381768) (xy 54.914255 -362.323843)
			(xy 54.937204 -362.268439) (xy 54.967188 -362.216505) (xy 55.003694 -362.168929) (xy 55.046099 -362.126524)
			(xy 55.093675 -362.090018) (xy 55.145609 -362.060034) (xy 55.201013 -362.037085) (xy 55.258938 -362.021564)
			(xy 55.318394 -362.013736) (xy 55.378362 -362.013736) (xy 55.437818 -362.021564) (xy 55.495743 -362.037085)
			(xy 55.551147 -362.060034) (xy 55.603081 -362.090018) (xy 55.650657 -362.126524) (xy 55.693062 -362.168929)
			(xy 55.729568 -362.216505) (xy 55.759552 -362.268439) (xy 55.782501 -362.323843) (xy 55.798022 -362.381768)
			(xy 55.80585 -362.441224) (xy 55.80634 -362.471208) (xy 55.80634 -363.334808) (xy 55.80585 -363.364792)
			(xy 55.798022 -363.424248) (xy 55.782501 -363.482173) (xy 55.759552 -363.537577) (xy 55.729568 -363.589511)
			(xy 55.693062 -363.637087) (xy 55.650657 -363.679492) (xy 55.603081 -363.715998) (xy 55.551147 -363.745982)
			(xy 55.495743 -363.768931) (xy 55.437818 -363.784452) (xy 55.378362 -363.79228) (xy 55.318394 -363.79228)
			(xy 55.258938 -363.784452) (xy 55.201013 -363.768931) (xy 55.145609 -363.745982) (xy 55.093675 -363.715998)
			(xy 55.046099 -363.679492) (xy 55.003694 -363.637087) (xy 54.967188 -363.589511) (xy 54.937204 -363.537577)
			(xy 54.914255 -363.482173) (xy 54.898734 -363.424248) (xy 54.890906 -363.364792) (xy 54.890416 -363.334808)
			(xy 0.509016 -363.334808) (xy 0.509016 -365.797384) (xy 54.438294 -365.797384) (xy 54.438294 -365.737416)
			(xy 54.446121 -365.67796) (xy 54.461641 -365.620034) (xy 54.484589 -365.564629) (xy 54.514571 -365.512694)
			(xy 54.551076 -365.465115) (xy 54.593478 -365.422709) (xy 54.641052 -365.386199) (xy 54.692984 -365.356211)
			(xy 54.748387 -365.333257) (xy 54.806311 -365.317731) (xy 54.865766 -365.309897) (xy 54.89575 -365.309404)
			(xy 55.75935 -365.309404) (xy 55.789336 -365.309938) (xy 55.848794 -365.31776) (xy 55.906723 -365.333276)
			(xy 55.962131 -365.356222) (xy 56.01407 -365.386203) (xy 56.06165 -365.422708) (xy 56.104059 -365.465112)
			(xy 56.140569 -365.512689) (xy 56.170556 -365.564624) (xy 56.193508 -365.620029) (xy 56.20903 -365.677957)
			(xy 56.216859 -365.737414) (xy 56.216859 -365.797386) (xy 56.20903 -365.856843) (xy 56.193508 -365.914771)
			(xy 56.170556 -365.970176) (xy 56.140569 -366.022112) (xy 56.104059 -366.069688) (xy 56.06165 -366.112092)
			(xy 56.01407 -366.148597) (xy 55.962131 -366.178578) (xy 55.906723 -366.201524) (xy 55.848794 -366.21704)
			(xy 55.789336 -366.224862) (xy 55.75935 -366.225328) (xy 54.89575 -366.225328) (xy 54.865766 -366.224903)
			(xy 54.806311 -366.217069) (xy 54.748386 -366.201543) (xy 54.692984 -366.178589) (xy 54.641052 -366.148601)
			(xy 54.593478 -366.112091) (xy 54.551076 -366.069685) (xy 54.514571 -366.022106) (xy 54.484589 -365.970171)
			(xy 54.461641 -365.914766) (xy 54.446121 -365.85684) (xy 54.438294 -365.797384) (xy 0.509016 -365.797384)
			(xy 0.509016 -368.516662) (xy 53.966364 -368.516662) (xy 53.966364 -367.653062) (xy 53.96685 -367.625793)
			(xy 53.974612 -367.571809) (xy 53.989977 -367.519479) (xy 54.012634 -367.469869) (xy 54.04212 -367.423988)
			(xy 54.077835 -367.382771) (xy 54.119052 -367.347056) (xy 54.164933 -367.31757) (xy 54.214543 -367.294913)
			(xy 54.266873 -367.279548) (xy 54.320857 -367.271786) (xy 54.375395 -367.271786) (xy 54.429379 -367.279548)
			(xy 54.481709 -367.294913) (xy 54.531319 -367.31757) (xy 54.5772 -367.347056) (xy 54.618417 -367.382771)
			(xy 54.654132 -367.423988) (xy 54.683618 -367.469869) (xy 54.706275 -367.519479) (xy 54.72164 -367.571809)
			(xy 54.729402 -367.625793) (xy 54.729888 -367.653062) (xy 54.729888 -368.516662) (xy 57.339484 -368.516662)
			(xy 57.339484 -367.653062) (xy 57.33997 -367.625793) (xy 57.347732 -367.571809) (xy 57.363097 -367.519479)
			(xy 57.385754 -367.469869) (xy 57.41524 -367.423988) (xy 57.450955 -367.382771) (xy 57.492172 -367.347056)
			(xy 57.538053 -367.31757) (xy 57.587663 -367.294913) (xy 57.639993 -367.279548) (xy 57.693977 -367.271786)
			(xy 57.748515 -367.271786) (xy 57.802499 -367.279548) (xy 57.854829 -367.294913) (xy 57.904439 -367.31757)
			(xy 57.95032 -367.347056) (xy 57.991537 -367.382771) (xy 58.027252 -367.423988) (xy 58.056738 -367.469869)
			(xy 58.079395 -367.519479) (xy 58.09476 -367.571809) (xy 58.102522 -367.625793) (xy 58.103008 -367.653062)
			(xy 58.103008 -368.516662) (xy 58.102522 -368.543931) (xy 58.09476 -368.597915) (xy 58.079395 -368.650245)
			(xy 58.056738 -368.699855) (xy 58.027252 -368.745736) (xy 57.991537 -368.786953) (xy 57.95032 -368.822668)
			(xy 57.904439 -368.852154) (xy 57.854829 -368.874811) (xy 57.802499 -368.890176) (xy 57.748515 -368.897938)
			(xy 57.693977 -368.897938) (xy 57.639993 -368.890176) (xy 57.587663 -368.874811) (xy 57.538053 -368.852154)
			(xy 57.492172 -368.822668) (xy 57.450955 -368.786953) (xy 57.41524 -368.745736) (xy 57.385754 -368.699855)
			(xy 57.363097 -368.650245) (xy 57.347732 -368.597915) (xy 57.33997 -368.543931) (xy 57.339484 -368.516662)
			(xy 54.729888 -368.516662) (xy 54.729402 -368.543931) (xy 54.72164 -368.597915) (xy 54.706275 -368.650245)
			(xy 54.683618 -368.699855) (xy 54.654132 -368.745736) (xy 54.618417 -368.786953) (xy 54.5772 -368.822668)
			(xy 54.531319 -368.852154) (xy 54.481709 -368.874811) (xy 54.429379 -368.890176) (xy 54.375395 -368.897938)
			(xy 54.320857 -368.897938) (xy 54.266873 -368.890176) (xy 54.214543 -368.874811) (xy 54.164933 -368.852154)
			(xy 54.119052 -368.822668) (xy 54.077835 -368.786953) (xy 54.04212 -368.745736) (xy 54.012634 -368.699855)
			(xy 53.989977 -368.650245) (xy 53.974612 -368.597915) (xy 53.96685 -368.543931) (xy 53.966364 -368.516662)
			(xy 0.509016 -368.516662) (xy 0.509016 -370.523703) (xy 27.348898 -370.523703) (xy 27.348899 -370.456279)
			(xy 27.356975 -370.38934) (xy 27.373012 -370.323851) (xy 27.396776 -370.260753) (xy 27.427927 -370.200957)
			(xy 27.466016 -370.145322) (xy 27.48788 -370.119656) (xy 27.493675 -370.11251) (xy 27.500191 -370.09532)
			(xy 27.50058 -370.086128) (xy 27.50058 -369.928902) (xy 27.501029 -369.918771) (xy 27.508764 -369.900042)
			(xy 27.523062 -369.885684) (xy 27.541759 -369.877872) (xy 27.551888 -369.87734) (xy 28.268168 -369.87734)
			(xy 28.278293 -369.877743) (xy 28.297004 -369.885488) (xy 28.311321 -369.899809) (xy 28.31906 -369.918522)
			(xy 28.319476 -369.928648) (xy 28.319476 -370.086128) (xy 28.319878 -370.095316) (xy 28.326398 -370.1125)
			(xy 28.332176 -370.119656) (xy 28.354029 -370.145331) (xy 28.39212 -370.200963) (xy 28.423272 -370.260758)
			(xy 28.447038 -370.323854) (xy 28.463075 -370.389342) (xy 28.471152 -370.456279) (xy 28.471153 -370.523644)
			(xy 31.749193 -370.523644) (xy 31.749194 -370.456338) (xy 31.75724 -370.389514) (xy 31.773215 -370.324131)
			(xy 31.79689 -370.261126) (xy 31.827927 -370.201402) (xy 31.865879 -370.145816) (xy 31.887668 -370.120164)
			(xy 31.893471 -370.113023) (xy 31.89998 -370.095829) (xy 31.900368 -370.086636) (xy 31.900368 -369.928902)
			(xy 31.900766 -369.918727) (xy 31.908556 -369.899926) (xy 31.92295 -369.88554) (xy 31.941755 -369.877761)
			(xy 31.95193 -369.87734) (xy 32.66821 -369.87734) (xy 32.678369 -369.877825) (xy 32.697138 -369.885603)
			(xy 32.711503 -369.899972) (xy 32.719277 -369.918743) (xy 32.719772 -369.928902) (xy 32.719772 -370.086636)
			(xy 32.720171 -370.095824) (xy 32.726693 -370.113008) (xy 32.732472 -370.120164) (xy 32.754248 -370.145826)
			(xy 32.792196 -370.201411) (xy 32.823229 -370.261134) (xy 32.846902 -370.324137) (xy 32.862876 -370.389518)
			(xy 32.870921 -370.456339) (xy 32.870922 -370.523643) (xy 32.870915 -370.523703) (xy 36.148986 -370.523703)
			(xy 36.148987 -370.456279) (xy 36.157063 -370.389341) (xy 36.173099 -370.323851) (xy 36.196863 -370.260754)
			(xy 36.228013 -370.200957) (xy 36.266101 -370.145322) (xy 36.287964 -370.119656) (xy 36.29377 -370.112518)
			(xy 36.300277 -370.095322) (xy 36.300664 -370.086128) (xy 36.300664 -369.928902) (xy 36.301129 -369.918772)
			(xy 36.308861 -369.900047) (xy 36.323154 -369.88569) (xy 36.341845 -369.877875) (xy 36.351972 -369.87734)
			(xy 37.068252 -369.87734) (xy 37.078408 -369.877762) (xy 37.097167 -369.885549) (xy 37.111494 -369.899947)
			(xy 37.119188 -369.918744) (xy 37.11956 -369.928902) (xy 37.11956 -370.086128) (xy 37.119966 -370.095315)
			(xy 37.126483 -370.112499) (xy 37.13226 -370.119656) (xy 37.154114 -370.14533) (xy 37.192205 -370.200963)
			(xy 37.223359 -370.260757) (xy 37.247125 -370.323853) (xy 37.263163 -370.389341) (xy 37.27124 -370.456279)
			(xy 37.271241 -370.523703) (xy 37.271241 -370.523704) (xy 40.548752 -370.523704) (xy 40.548753 -370.456278)
			(xy 40.556831 -370.389338) (xy 40.572869 -370.323848) (xy 40.596637 -370.26075) (xy 40.627792 -370.200954)
			(xy 40.665885 -370.14532) (xy 40.687752 -370.119656) (xy 40.693556 -370.112516) (xy 40.700065 -370.095321)
			(xy 40.700452 -370.086128) (xy 40.700452 -369.928902) (xy 40.700929 -369.918774) (xy 40.708658 -369.900051)
			(xy 40.722947 -369.885694) (xy 40.741634 -369.877877) (xy 40.75176 -369.87734) (xy 41.46804 -369.87734)
			(xy 41.478202 -369.87769) (xy 41.496963 -369.885506) (xy 41.511286 -369.899925) (xy 41.518977 -369.918738)
			(xy 41.519348 -369.928902) (xy 41.519348 -370.086128) (xy 41.519756 -370.095315) (xy 41.526273 -370.112499)
			(xy 41.532048 -370.119656) (xy 41.553902 -370.14533) (xy 41.591994 -370.200962) (xy 41.623149 -370.260757)
			(xy 41.646916 -370.323852) (xy 41.662954 -370.389341) (xy 41.671031 -370.456279) (xy 41.671032 -370.523644)
			(xy 44.949071 -370.523644) (xy 44.949073 -370.456338) (xy 44.957118 -370.389515) (xy 44.973092 -370.324132)
			(xy 44.996766 -370.261127) (xy 45.027801 -370.201403) (xy 45.065751 -370.145816) (xy 45.08754 -370.120164)
			(xy 45.093339 -370.113021) (xy 45.099851 -370.095829) (xy 45.10024 -370.086636) (xy 45.10024 -369.928902)
			(xy 45.100665 -369.91873) (xy 45.10845 -369.899935) (xy 45.122835 -369.88555) (xy 45.14163 -369.877765)
			(xy 45.151802 -369.87734) (xy 45.868082 -369.87734) (xy 45.878253 -369.877778) (xy 45.897047 -369.885558)
			(xy 45.911433 -369.899939) (xy 45.919218 -369.918731) (xy 45.919644 -369.928902) (xy 45.919644 -370.086636)
			(xy 45.92005 -370.095823) (xy 45.926568 -370.113007) (xy 45.932344 -370.120164) (xy 45.95412 -370.145826)
			(xy 45.992071 -370.20141) (xy 46.023105 -370.261132) (xy 46.046779 -370.324136) (xy 46.062754 -370.389517)
			(xy 46.070799 -370.456339) (xy 46.0708 -370.523643) (xy 46.062757 -370.590465) (xy 46.046785 -370.655847)
			(xy 46.023113 -370.718851) (xy 45.99208 -370.778574) (xy 45.954131 -370.83416) (xy 45.932344 -370.859812)
			(xy 45.926553 -370.866961) (xy 45.920036 -370.884149) (xy 45.919644 -370.89334) (xy 45.919644 -371.386862)
			(xy 45.920085 -371.396046) (xy 45.926578 -371.41323) (xy 45.932344 -371.42039) (xy 45.954146 -371.44603)
			(xy 45.992096 -371.501618) (xy 46.023129 -371.561343) (xy 46.046568 -371.623726) (xy 47.14919 -371.623726)
			(xy 47.149193 -371.556417) (xy 47.157242 -371.489591) (xy 47.17322 -371.424206) (xy 47.1969 -371.3612)
			(xy 47.22794 -371.301475) (xy 47.265897 -371.24589) (xy 47.287688 -371.220238) (xy 47.293492 -371.213098)
			(xy 47.300003 -371.195904) (xy 47.300388 -371.18671) (xy 47.300388 -371.028722) (xy 47.300783 -371.018546)
			(xy 47.30857 -370.999742) (xy 47.322966 -370.985355) (xy 47.341773 -370.977578) (xy 47.35195 -370.97716)
			(xy 48.06823 -370.97716) (xy 48.078392 -370.977609) (xy 48.097167 -370.985398) (xy 48.111532 -370.999777)
			(xy 48.119301 -371.018559) (xy 48.119792 -371.028722) (xy 48.119792 -371.18671) (xy 48.120199 -371.195898)
			(xy 48.126715 -371.213082) (xy 48.132492 -371.220238) (xy 48.154241 -371.245921) (xy 48.192189 -371.301504)
			(xy 48.196948 -371.310662) (xy 53.966364 -371.310662) (xy 53.966364 -370.447062) (xy 53.96685 -370.419793)
			(xy 53.974612 -370.365809) (xy 53.989977 -370.313479) (xy 54.012634 -370.263869) (xy 54.04212 -370.217988)
			(xy 54.077835 -370.176771) (xy 54.119052 -370.141056) (xy 54.164933 -370.11157) (xy 54.214543 -370.088913)
			(xy 54.266873 -370.073548) (xy 54.320857 -370.065786) (xy 54.375395 -370.065786) (xy 54.429379 -370.073548)
			(xy 54.481709 -370.088913) (xy 54.531319 -370.11157) (xy 54.5772 -370.141056) (xy 54.618417 -370.176771)
			(xy 54.654132 -370.217988) (xy 54.683618 -370.263869) (xy 54.706275 -370.313479) (xy 54.72164 -370.365809)
			(xy 54.729402 -370.419793) (xy 54.729888 -370.447062) (xy 54.729888 -371.310662) (xy 57.339484 -371.310662)
			(xy 57.339484 -370.447062) (xy 57.33997 -370.419793) (xy 57.347732 -370.365809) (xy 57.363097 -370.313479)
			(xy 57.385754 -370.263869) (xy 57.41524 -370.217988) (xy 57.450955 -370.176771) (xy 57.492172 -370.141056)
			(xy 57.538053 -370.11157) (xy 57.587663 -370.088913) (xy 57.639993 -370.073548) (xy 57.693977 -370.065786)
			(xy 57.748515 -370.065786) (xy 57.802499 -370.073548) (xy 57.854829 -370.088913) (xy 57.904439 -370.11157)
			(xy 57.95032 -370.141056) (xy 57.991537 -370.176771) (xy 58.027252 -370.217988) (xy 58.056738 -370.263869)
			(xy 58.079395 -370.313479) (xy 58.09476 -370.365809) (xy 58.102522 -370.419793) (xy 58.103008 -370.447062)
			(xy 58.103008 -370.523703) (xy 71.348807 -370.523703) (xy 71.348808 -370.456279) (xy 71.356885 -370.38934)
			(xy 71.372921 -370.32385) (xy 71.396686 -370.260753) (xy 71.427838 -370.200956) (xy 71.465928 -370.145321)
			(xy 71.487792 -370.119656) (xy 71.493589 -370.112511) (xy 71.500104 -370.09532) (xy 71.500492 -370.086128)
			(xy 71.500492 -369.928902) (xy 71.501027 -369.918781) (xy 71.508745 -369.900069) (xy 71.523016 -369.885715)
			(xy 71.541682 -369.877887) (xy 71.5518 -369.87734) (xy 72.26808 -369.87734) (xy 72.278238 -369.877739)
			(xy 72.296998 -369.885535) (xy 72.311323 -369.89994) (xy 72.319016 -369.918742) (xy 72.319388 -369.928902)
			(xy 72.319388 -370.086128) (xy 72.319787 -370.095316) (xy 72.326309 -370.1125) (xy 72.332088 -370.119656)
			(xy 72.353941 -370.145331) (xy 72.39203 -370.200964) (xy 72.423182 -370.260758) (xy 72.446948 -370.323854)
			(xy 72.462984 -370.389342) (xy 72.471061 -370.45628) (xy 72.471063 -370.523644) (xy 75.749102 -370.523644)
			(xy 75.749103 -370.456338) (xy 75.757149 -370.389513) (xy 75.773125 -370.32413) (xy 75.796801 -370.261125)
			(xy 75.827837 -370.201401) (xy 75.86579 -370.145816) (xy 75.88758 -370.120164) (xy 75.893372 -370.113015)
			(xy 75.89989 -370.095828) (xy 75.90028 -370.086636) (xy 75.90028 -369.928902) (xy 75.900666 -369.918725)
			(xy 75.908459 -369.899923) (xy 75.922856 -369.885536) (xy 75.941665 -369.877759) (xy 75.951842 -369.87734)
			(xy 76.668122 -369.87734) (xy 76.678281 -369.877815) (xy 76.697052 -369.885597) (xy 76.711416 -369.899969)
			(xy 76.71919 -369.918742) (xy 76.719684 -369.928902) (xy 76.719684 -370.086636) (xy 76.72008 -370.095825)
			(xy 76.726604 -370.113009) (xy 76.732384 -370.120164) (xy 76.754159 -370.145826) (xy 76.792107 -370.201412)
			(xy 76.82314 -370.261134) (xy 76.846812 -370.324137) (xy 76.862785 -370.389518) (xy 76.87083 -370.456339)
			(xy 76.870831 -370.523643) (xy 76.870824 -370.523703) (xy 80.148895 -370.523703) (xy 80.148896 -370.456279)
			(xy 80.156972 -370.38934) (xy 80.173008 -370.323851) (xy 80.196773 -370.260754) (xy 80.227924 -370.200957)
			(xy 80.266012 -370.145322) (xy 80.287876 -370.119656) (xy 80.293671 -370.112509) (xy 80.300187 -370.09532)
			(xy 80.300576 -370.086128) (xy 80.300576 -369.928902) (xy 80.301029 -369.918771) (xy 80.308763 -369.900043)
			(xy 80.32306 -369.885685) (xy 80.341755 -369.877873) (xy 80.351884 -369.87734) (xy 81.068164 -369.87734)
			(xy 81.078289 -369.877747) (xy 81.096999 -369.88549) (xy 81.111316 -369.899811) (xy 81.119056 -369.918523)
			(xy 81.119472 -369.928648) (xy 81.119472 -370.086128) (xy 81.119875 -370.095316) (xy 81.126394 -370.1125)
			(xy 81.132172 -370.119656) (xy 81.154025 -370.14533) (xy 81.192116 -370.200963) (xy 81.223269 -370.260758)
			(xy 81.247035 -370.323853) (xy 81.263072 -370.389342) (xy 81.271149 -370.456279) (xy 81.27115 -370.523703)
			(xy 84.548686 -370.523703) (xy 84.548687 -370.456279) (xy 84.556763 -370.389341) (xy 84.572799 -370.323851)
			(xy 84.596563 -370.260754) (xy 84.627713 -370.200957) (xy 84.665801 -370.145322) (xy 84.687664 -370.119656)
			(xy 84.69347 -370.112518) (xy 84.699977 -370.095322) (xy 84.700364 -370.086128) (xy 84.700364 -369.928902)
			(xy 84.700829 -369.918772) (xy 84.708561 -369.900047) (xy 84.722854 -369.88569) (xy 84.741545 -369.877875)
			(xy 84.751672 -369.87734) (xy 85.467952 -369.87734) (xy 85.478076 -369.877756) (xy 85.496787 -369.885496)
			(xy 85.511104 -369.899813) (xy 85.518844 -369.918524) (xy 85.51926 -369.928648) (xy 85.51926 -370.086128)
			(xy 85.519666 -370.095315) (xy 85.526183 -370.112499) (xy 85.53196 -370.119656) (xy 85.553814 -370.14533)
			(xy 85.591905 -370.200963) (xy 85.623059 -370.260757) (xy 85.646825 -370.323853) (xy 85.662863 -370.389341)
			(xy 85.67094 -370.456279) (xy 85.670941 -370.523644) (xy 115.349244 -370.523644) (xy 115.349245 -370.456338)
			(xy 115.35729 -370.389516) (xy 115.373263 -370.324133) (xy 115.396936 -370.261128) (xy 115.427969 -370.201404)
			(xy 115.465917 -370.145817) (xy 115.487704 -370.120164) (xy 115.493499 -370.113018) (xy 115.500014 -370.095828)
			(xy 115.500404 -370.086636) (xy 115.500404 -369.928902) (xy 115.500934 -369.918749) (xy 115.508702 -369.899986)
			(xy 115.523056 -369.885622) (xy 115.541813 -369.877841) (xy 115.551966 -369.87734) (xy 116.268246 -369.87734)
			(xy 116.278407 -369.877796) (xy 116.297177 -369.885586) (xy 116.311541 -369.899963) (xy 116.319314 -369.918741)
			(xy 116.319808 -369.928902) (xy 116.319808 -370.086636) (xy 116.320199 -370.095825) (xy 116.326726 -370.11301)
			(xy 116.332508 -370.120164) (xy 116.354286 -370.145825) (xy 116.392238 -370.201409) (xy 116.423275 -370.261131)
			(xy 116.446951 -370.324134) (xy 116.462926 -370.389516) (xy 116.470972 -370.456338) (xy 116.470973 -370.523644)
			(xy 116.470966 -370.523703) (xy 119.749013 -370.523703) (xy 119.749014 -370.456279) (xy 119.757091 -370.38934)
			(xy 119.773128 -370.32385) (xy 119.796893 -370.260752) (xy 119.828045 -370.200956) (xy 119.866135 -370.145321)
			(xy 119.888 -370.119656) (xy 119.893798 -370.112512) (xy 119.900312 -370.09532) (xy 119.9007 -370.086128)
			(xy 119.9007 -369.928902) (xy 119.901227 -369.91878) (xy 119.908947 -369.900067) (xy 119.92322 -369.885712)
			(xy 119.941889 -369.877886) (xy 119.952008 -369.87734) (xy 120.668288 -369.87734) (xy 120.678446 -369.877732)
			(xy 120.697206 -369.885531) (xy 120.711531 -369.899938) (xy 120.719224 -369.918741) (xy 120.719596 -369.928902)
			(xy 120.719596 -370.086128) (xy 120.719993 -370.095317) (xy 120.726516 -370.112501) (xy 120.732296 -370.119656)
			(xy 120.754148 -370.145331) (xy 120.792238 -370.200964) (xy 120.823389 -370.260759) (xy 120.847154 -370.323854)
			(xy 120.863191 -370.389342) (xy 120.871267 -370.45628) (xy 120.871269 -370.523644) (xy 124.149308 -370.523644)
			(xy 124.149309 -370.456338) (xy 124.157355 -370.389513) (xy 124.173331 -370.32413) (xy 124.197007 -370.261125)
			(xy 124.228045 -370.201401) (xy 124.265998 -370.145816) (xy 124.287788 -370.120164) (xy 124.293581 -370.113016)
			(xy 124.300098 -370.095828) (xy 124.300488 -370.086636) (xy 124.300488 -369.928902) (xy 124.300867 -369.918724)
			(xy 124.30866 -369.89992) (xy 124.32306 -369.885533) (xy 124.341872 -369.877757) (xy 124.35205 -369.87734)
			(xy 125.06833 -369.87734) (xy 125.07849 -369.877809) (xy 125.09726 -369.885593) (xy 125.111625 -369.899967)
			(xy 125.119398 -369.918742) (xy 125.119892 -369.928902) (xy 125.119892 -370.086636) (xy 125.120286 -370.095825)
			(xy 125.126811 -370.113009) (xy 125.132592 -370.120164) (xy 125.154367 -370.145826) (xy 125.192314 -370.201412)
			(xy 125.223346 -370.261134) (xy 125.247018 -370.324138) (xy 125.262991 -370.389518) (xy 125.271036 -370.456339)
			(xy 125.271037 -370.523643) (xy 125.271037 -370.523644) (xy 128.549099 -370.523644) (xy 128.5491 -370.456338)
			(xy 128.557146 -370.389514) (xy 128.573121 -370.32413) (xy 128.596797 -370.261125) (xy 128.627834 -370.201402)
			(xy 128.665787 -370.145816) (xy 128.687576 -370.120164) (xy 128.693368 -370.113015) (xy 128.699886 -370.095828)
			(xy 128.700276 -370.086636) (xy 128.700276 -369.928902) (xy 128.700666 -369.918726) (xy 128.708458 -369.899924)
			(xy 128.722854 -369.885538) (xy 128.741661 -369.877759) (xy 128.751838 -369.87734) (xy 129.468118 -369.87734)
			(xy 129.478277 -369.877818) (xy 129.497047 -369.885599) (xy 129.511412 -369.89997) (xy 129.519185 -369.918743)
			(xy 129.51968 -369.928902) (xy 129.51968 -370.086636) (xy 129.520077 -370.095824) (xy 129.5266 -370.113008)
			(xy 129.53238 -370.120164) (xy 129.554155 -370.145826) (xy 129.592103 -370.201412) (xy 129.623136 -370.261134)
			(xy 129.646809 -370.324137) (xy 129.662782 -370.389518) (xy 129.670827 -370.456339) (xy 129.670828 -370.523643)
			(xy 129.670828 -370.523644) (xy 159.349153 -370.523644) (xy 159.349154 -370.456338) (xy 159.357199 -370.389515)
			(xy 159.373173 -370.324133) (xy 159.396846 -370.261128) (xy 159.427879 -370.201404) (xy 159.465828 -370.145816)
			(xy 159.487616 -370.120164) (xy 159.493412 -370.113019) (xy 159.499927 -370.095828) (xy 159.500316 -370.086636)
			(xy 159.500316 -369.928902) (xy 159.500835 -369.918747) (xy 159.508604 -369.899982) (xy 159.522962 -369.885618)
			(xy 159.541723 -369.877839) (xy 159.551878 -369.87734) (xy 160.268158 -369.87734) (xy 160.278327 -369.877798)
			(xy 160.297121 -369.88557) (xy 160.311508 -369.899945) (xy 160.319294 -369.918733) (xy 160.31972 -369.928902)
			(xy 160.31972 -370.086636) (xy 160.320109 -370.095826) (xy 160.326637 -370.11301) (xy 160.33242 -370.120164)
			(xy 160.354197 -370.145825) (xy 160.392149 -370.20141) (xy 160.423185 -370.261131) (xy 160.44686 -370.324135)
			(xy 160.462835 -370.389516) (xy 160.470881 -370.456339) (xy 160.470882 -370.523643) (xy 160.470875 -370.523703)
			(xy 163.748922 -370.523703) (xy 163.748923 -370.456279) (xy 163.757 -370.389339) (xy 163.773037 -370.323849)
			(xy 163.796803 -370.260752) (xy 163.827956 -370.200955) (xy 163.866047 -370.145321) (xy 163.887912 -370.119656)
			(xy 163.893711 -370.112513) (xy 163.900224 -370.095321) (xy 163.900612 -370.086128) (xy 163.900612 -369.928902)
			(xy 163.901127 -369.918779) (xy 163.908849 -369.900063) (xy 163.923126 -369.885708) (xy 163.9418 -369.877884)
			(xy 163.95192 -369.87734) (xy 164.6682 -369.87734) (xy 164.678359 -369.877722) (xy 164.697119 -369.885526)
			(xy 164.711444 -369.899935) (xy 164.719136 -369.918741) (xy 164.719508 -369.928902) (xy 164.719508 -370.086128)
			(xy 164.719903 -370.095317) (xy 164.726427 -370.112501) (xy 164.732208 -370.119656) (xy 164.75406 -370.145331)
			(xy 164.792148 -370.200964) (xy 164.823299 -370.260759) (xy 164.847064 -370.323855) (xy 164.8631 -370.389343)
			(xy 164.871176 -370.45628) (xy 164.871178 -370.523644) (xy 168.149241 -370.523644) (xy 168.149242 -370.456338)
			(xy 168.157287 -370.389516) (xy 168.17326 -370.324133) (xy 168.196933 -370.261128) (xy 168.227965 -370.201404)
			(xy 168.265913 -370.145817) (xy 168.2877 -370.120164) (xy 168.293494 -370.113017) (xy 168.30001 -370.095828)
			(xy 168.3004 -370.086636) (xy 168.3004 -369.928902) (xy 168.300934 -369.918749) (xy 168.308701 -369.899987)
			(xy 168.323054 -369.885623) (xy 168.341809 -369.877842) (xy 168.351962 -369.87734) (xy 169.068242 -369.87734)
			(xy 169.078403 -369.877799) (xy 169.097173 -369.885588) (xy 169.111537 -369.899964) (xy 169.11931 -369.918741)
			(xy 169.119804 -369.928902) (xy 169.119804 -370.086636) (xy 169.120196 -370.095825) (xy 169.126722 -370.113009)
			(xy 169.132504 -370.120164) (xy 169.154279 -370.145826) (xy 169.192225 -370.201412) (xy 169.223256 -370.261135)
			(xy 169.246928 -370.324138) (xy 169.2629 -370.389519) (xy 169.270945 -370.456339) (xy 169.270946 -370.523643)
			(xy 169.270946 -370.523644) (xy 172.549008 -370.523644) (xy 172.549009 -370.456338) (xy 172.557055 -370.389513)
			(xy 172.573031 -370.32413) (xy 172.596707 -370.261125) (xy 172.627745 -370.201401) (xy 172.665698 -370.145816)
			(xy 172.687488 -370.120164) (xy 172.693281 -370.113016) (xy 172.699798 -370.095828) (xy 172.700188 -370.086636)
			(xy 172.700188 -369.928902) (xy 172.700567 -369.918724) (xy 172.70836 -369.89992) (xy 172.72276 -369.885533)
			(xy 172.741572 -369.877757) (xy 172.75175 -369.87734) (xy 173.46803 -369.87734) (xy 173.47819 -369.877809)
			(xy 173.49696 -369.885593) (xy 173.511325 -369.899967) (xy 173.519098 -369.918742) (xy 173.519592 -369.928902)
			(xy 173.519592 -370.086636) (xy 173.519986 -370.095825) (xy 173.526511 -370.113009) (xy 173.532292 -370.120164)
			(xy 173.554067 -370.145826) (xy 173.592014 -370.201412) (xy 173.623046 -370.261134) (xy 173.646718 -370.324138)
			(xy 173.662691 -370.389518) (xy 173.670736 -370.456339) (xy 173.670737 -370.523643) (xy 173.662694 -370.590464)
			(xy 173.646724 -370.655845) (xy 173.623054 -370.718849) (xy 173.592023 -370.778573) (xy 173.554078 -370.834159)
			(xy 173.532292 -370.859812) (xy 173.526507 -370.866965) (xy 173.519986 -370.88415) (xy 173.519592 -370.89334)
			(xy 173.519592 -371.386862) (xy 173.520022 -371.396047) (xy 173.526522 -371.413231) (xy 173.532292 -371.42039)
			(xy 173.554093 -371.446031) (xy 173.592039 -371.50162) (xy 173.62307 -371.561345) (xy 173.646506 -371.623725)
			(xy 174.74915 -371.623725) (xy 174.749154 -371.556417) (xy 174.757201 -371.489592) (xy 174.773178 -371.424208)
			(xy 174.796855 -371.361202) (xy 174.827893 -371.301477) (xy 174.865846 -371.24589) (xy 174.887636 -371.220238)
			(xy 174.893446 -371.213102) (xy 174.899952 -371.195904) (xy 174.900336 -371.18671) (xy 174.900336 -371.028722)
			(xy 174.900782 -371.018552) (xy 174.908559 -370.999758) (xy 174.922938 -370.985373) (xy 174.941728 -370.977587)
			(xy 174.951898 -370.97716) (xy 175.668178 -370.97716) (xy 175.678351 -370.977583) (xy 175.697149 -370.985364)
			(xy 175.711536 -370.999751) (xy 175.719317 -371.018549) (xy 175.71974 -371.028722) (xy 175.71974 -371.18671)
			(xy 175.720159 -371.195896) (xy 175.726668 -371.21308) (xy 175.73244 -371.220238) (xy 175.754191 -371.245921)
			(xy 175.792142 -371.301502) (xy 175.823178 -371.361221) (xy 175.846854 -371.424222) (xy 175.86283 -371.489601)
			(xy 175.870878 -371.55642) (xy 175.870881 -371.623723) (xy 175.862841 -371.690543) (xy 175.846871 -371.755923)
			(xy 175.823202 -371.818926) (xy 175.792172 -371.878649) (xy 175.754226 -371.934234) (xy 175.73244 -371.959886)
			(xy 175.726617 -371.967012) (xy 175.72012 -371.984218) (xy 175.71974 -371.993414) (xy 175.71974 -372.486682)
			(xy 175.720172 -372.495867) (xy 175.726672 -372.51305) (xy 175.73244 -372.52021) (xy 175.754262 -372.545834)
			(xy 175.792211 -372.601424) (xy 175.823244 -372.661151) (xy 175.846916 -372.72416) (xy 175.862887 -372.789545)
			(xy 175.870929 -372.856371) (xy 175.870926 -372.92368) (xy 175.862878 -372.990505) (xy 175.846901 -373.055889)
			(xy 175.823223 -373.118895) (xy 175.792185 -373.17862) (xy 175.754231 -373.234206) (xy 175.73244 -373.259858)
			(xy 175.726629 -373.266993) (xy 175.720125 -373.284191) (xy 175.71974 -373.293386) (xy 175.71974 -373.451374)
			(xy 175.719314 -373.461547) (xy 175.711534 -373.480345) (xy 175.697148 -373.494731) (xy 175.678351 -373.502513)
			(xy 175.668178 -373.502936) (xy 174.951898 -373.502936) (xy 174.941723 -373.502537) (xy 174.922923 -373.494747)
			(xy 174.908538 -373.480353) (xy 174.900757 -373.461549) (xy 174.900336 -373.451374) (xy 174.900336 -373.293386)
			(xy 174.899925 -373.284199) (xy 174.893411 -373.267015) (xy 174.887636 -373.259858) (xy 174.865882 -373.234178)
			(xy 174.827932 -373.178596) (xy 174.796898 -373.118876) (xy 174.773223 -373.055875) (xy 174.757248 -372.990496)
			(xy 174.749201 -372.923677) (xy 174.749198 -372.856374) (xy 174.757239 -372.789554) (xy 174.773208 -372.724174)
			(xy 174.796877 -372.661171) (xy 174.827906 -372.601448) (xy 174.865851 -372.545862) (xy 174.887636 -372.52021)
			(xy 174.893458 -372.513083) (xy 174.899957 -372.495878) (xy 174.900336 -372.486682) (xy 174.900336 -371.993414)
			(xy 174.899911 -371.984229) (xy 174.893407 -371.967044) (xy 174.887636 -371.959886) (xy 174.865811 -371.934265)
			(xy 174.827863 -371.878674) (xy 174.796832 -371.818946) (xy 174.773161 -371.755937) (xy 174.757191 -371.690551)
			(xy 174.74915 -371.623725) (xy 173.646506 -371.623725) (xy 173.646741 -371.624351) (xy 173.662712 -371.689734)
			(xy 173.670754 -371.756558) (xy 173.670753 -371.823863) (xy 173.662708 -371.890686) (xy 173.646734 -371.956069)
			(xy 173.623061 -372.019074) (xy 173.592028 -372.078798) (xy 173.55408 -372.134385) (xy 173.532292 -372.160038)
			(xy 173.526496 -372.167183) (xy 173.519981 -372.184374) (xy 173.519592 -372.193566) (xy 173.519592 -372.351554)
			(xy 173.519099 -372.361719) (xy 173.511335 -372.380507) (xy 173.496971 -372.394892) (xy 173.478194 -372.402684)
			(xy 173.46803 -372.403116) (xy 172.75175 -372.403116) (xy 172.741576 -372.402694) (xy 172.722773 -372.394917)
			(xy 172.708385 -372.38053) (xy 172.700607 -372.361728) (xy 172.700188 -372.351554) (xy 172.700188 -372.193566)
			(xy 172.699797 -372.184377) (xy 172.69327 -372.167192) (xy 172.687488 -372.160038) (xy 172.665713 -372.134375)
			(xy 172.62776 -372.078791) (xy 172.596724 -372.01907) (xy 172.573048 -371.956067) (xy 172.557072 -371.890685)
			(xy 172.549026 -371.823863) (xy 172.549025 -371.756558) (xy 172.557069 -371.689736) (xy 172.573042 -371.624354)
			(xy 172.596715 -371.561349) (xy 172.627749 -371.501627) (xy 172.6657 -371.446041) (xy 172.687488 -371.42039)
			(xy 172.69327 -371.413234) (xy 172.699794 -371.396052) (xy 172.700188 -371.386862) (xy 172.700188 -370.89334)
			(xy 172.699761 -370.884154) (xy 172.69326 -370.86697) (xy 172.687488 -370.859812) (xy 172.665687 -370.83417)
			(xy 172.627735 -370.778583) (xy 172.5967 -370.718859) (xy 172.573026 -370.655853) (xy 172.557052 -370.590469)
			(xy 172.549008 -370.523644) (xy 169.270946 -370.523644) (xy 169.262904 -370.590464) (xy 169.246933 -370.655845)
			(xy 169.223264 -370.718849) (xy 169.192234 -370.778572) (xy 169.15429 -370.834159) (xy 169.132504 -370.859812)
			(xy 169.12672 -370.866966) (xy 169.120198 -370.88415) (xy 169.119804 -370.89334) (xy 169.119804 -371.386862)
			(xy 169.120231 -371.396047) (xy 169.126733 -371.413232) (xy 169.132504 -371.42039) (xy 169.154304 -371.446031)
			(xy 169.19225 -371.50162) (xy 169.22328 -371.561346) (xy 169.246737 -371.623785) (xy 170.348831 -371.623785)
			(xy 170.348834 -371.556358) (xy 170.356914 -371.489416) (xy 170.372955 -371.423924) (xy 170.396726 -371.360825)
			(xy 170.427884 -371.301029) (xy 170.46598 -371.245394) (xy 170.487848 -371.21973) (xy 170.493663 -371.212598)
			(xy 170.500165 -371.195397) (xy 170.500548 -371.186202) (xy 170.500548 -371.028722) (xy 170.501045 -371.018596)
			(xy 170.508767 -370.999873) (xy 170.52305 -370.985516) (xy 170.541732 -370.977698) (xy 170.551856 -370.97716)
			(xy 171.268136 -370.97716) (xy 171.278287 -370.977591) (xy 171.297033 -370.985391) (xy 171.311354 -370.999784)
			(xy 171.319059 -371.018568) (xy 171.319444 -371.028722) (xy 171.319444 -371.186202) (xy 171.319866 -371.195388)
			(xy 171.326373 -371.212571) (xy 171.332144 -371.21973) (xy 171.353973 -371.245425) (xy 171.392066 -371.301054)
			(xy 171.423222 -371.360846) (xy 171.44699 -371.423939) (xy 171.46303 -371.489425) (xy 171.47111 -371.556361)
			(xy 171.471113 -371.623782) (xy 171.46304 -371.690719) (xy 171.447007 -371.756207) (xy 171.423245 -371.819302)
			(xy 171.392096 -371.879097) (xy 171.354008 -371.93473) (xy 171.332144 -371.960394) (xy 171.326361 -371.967548)
			(xy 171.31984 -371.984732) (xy 171.319444 -371.993922) (xy 171.319444 -372.486174) (xy 171.319879 -372.495358)
			(xy 171.326377 -372.512542) (xy 171.332144 -372.519702) (xy 171.354043 -372.545339) (xy 171.392135 -372.600976)
			(xy 171.423287 -372.660776) (xy 171.447052 -372.723876) (xy 171.463087 -372.789369) (xy 171.471161 -372.856312)
			(xy 171.471158 -372.923739) (xy 171.463077 -372.990681) (xy 171.447037 -373.056172) (xy 171.423266 -373.119271)
			(xy 171.392108 -373.179068) (xy 171.354012 -373.234702) (xy 171.332144 -373.260366) (xy 171.32633 -373.267499)
			(xy 171.319827 -373.284699) (xy 171.319444 -373.293894) (xy 171.319444 -373.451374) (xy 171.318952 -373.461501)
			(xy 171.31123 -373.480225) (xy 171.296945 -373.494583) (xy 171.27826 -373.5024) (xy 171.268136 -373.502936)
			(xy 170.551856 -373.502936) (xy 170.541704 -373.502515) (xy 170.522957 -373.494712) (xy 170.508637 -373.480316)
			(xy 170.500932 -373.461529) (xy 170.500548 -373.451374) (xy 170.500548 -373.293894) (xy 170.50013 -373.284708)
			(xy 170.493621 -373.267524) (xy 170.487848 -373.260366) (xy 170.466016 -373.234674) (xy 170.427923 -373.179044)
			(xy 170.396768 -373.119252) (xy 170.373 -373.056159) (xy 170.356961 -372.990673) (xy 170.348881 -372.923736)
			(xy 170.348878 -372.856315) (xy 170.356951 -372.789378) (xy 170.372985 -372.72389) (xy 170.396747 -372.660794)
			(xy 170.427897 -372.600999) (xy 170.465984 -372.545366) (xy 170.487848 -372.519702) (xy 170.493632 -372.512548)
			(xy 170.500153 -372.495364) (xy 170.500548 -372.486174) (xy 170.500548 -371.993922) (xy 170.500117 -371.984737)
			(xy 170.493617 -371.967553) (xy 170.487848 -371.960394) (xy 170.465945 -371.93476) (xy 170.427854 -371.879122)
			(xy 170.396703 -371.819322) (xy 170.372938 -371.756221) (xy 170.356904 -371.690728) (xy 170.348831 -371.623785)
			(xy 169.246737 -371.623785) (xy 169.24695 -371.624352) (xy 169.262921 -371.689735) (xy 169.270963 -371.756558)
			(xy 169.270962 -371.823863) (xy 169.262917 -371.890686) (xy 169.246944 -371.956068) (xy 169.223271 -372.019073)
			(xy 169.192239 -372.078798) (xy 169.154291 -372.134385) (xy 169.132504 -372.160038) (xy 169.126709 -372.167185)
			(xy 169.120193 -372.184374) (xy 169.119804 -372.193566) (xy 169.119804 -372.351554) (xy 169.1193 -372.361717)
			(xy 169.111537 -372.380503) (xy 169.097177 -372.394888) (xy 169.078405 -372.402682) (xy 169.068242 -372.403116)
			(xy 168.351962 -372.403116) (xy 168.341782 -372.402766) (xy 168.322978 -372.39496) (xy 168.308593 -372.380552)
			(xy 168.300817 -372.361734) (xy 168.3004 -372.351554) (xy 168.3004 -372.193566) (xy 168.300006 -372.184377)
			(xy 168.293481 -372.167193) (xy 168.2877 -372.160038) (xy 168.265927 -372.134374) (xy 168.227981 -372.078788)
			(xy 168.196949 -372.019066) (xy 168.173277 -371.956063) (xy 168.157304 -371.890683) (xy 168.14926 -371.823862)
			(xy 168.149258 -371.756559) (xy 168.1573 -371.689738) (xy 168.173271 -371.624357) (xy 168.19694 -371.561353)
			(xy 168.22797 -371.50163) (xy 168.265914 -371.446043) (xy 168.2877 -371.42039) (xy 168.293483 -371.413235)
			(xy 168.300006 -371.396052) (xy 168.3004 -371.386862) (xy 168.3004 -370.89334) (xy 168.299971 -370.884155)
			(xy 168.29347 -370.86697) (xy 168.2877 -370.859812) (xy 168.265902 -370.834169) (xy 168.227956 -370.77858)
			(xy 168.196925 -370.718855) (xy 168.173255 -370.65585) (xy 168.157284 -370.590467) (xy 168.149241 -370.523644)
			(xy 164.871178 -370.523644) (xy 164.871178 -370.523702) (xy 164.863103 -370.59064) (xy 164.847069 -370.656128)
			(xy 164.823307 -370.719224) (xy 164.792158 -370.77902) (xy 164.754071 -370.834655) (xy 164.732208 -370.86032)
			(xy 164.726421 -370.867472) (xy 164.7199 -370.884657) (xy 164.719508 -370.893848) (xy 164.719508 -371.386354)
			(xy 164.719938 -371.395539) (xy 164.726438 -371.412724) (xy 164.732208 -371.419882) (xy 164.754085 -371.445536)
			(xy 164.792173 -371.501172) (xy 164.823323 -371.56097) (xy 164.846957 -371.623726) (xy 165.949062 -371.623726)
			(xy 165.949066 -371.556417) (xy 165.957114 -371.489592) (xy 165.973091 -371.424207) (xy 165.996769 -371.361201)
			(xy 166.027807 -371.301477) (xy 166.065761 -371.24589) (xy 166.087552 -371.220238) (xy 166.093364 -371.213104)
			(xy 166.099868 -371.195905) (xy 166.100252 -371.18671) (xy 166.100252 -371.028722) (xy 166.100682 -371.01855)
			(xy 166.108463 -370.999753) (xy 166.122847 -370.985367) (xy 166.141642 -370.977584) (xy 166.151814 -370.97716)
			(xy 166.868094 -370.97716) (xy 166.878268 -370.977569) (xy 166.897067 -370.985356) (xy 166.911453 -370.999747)
			(xy 166.919234 -371.018548) (xy 166.919656 -371.028722) (xy 166.919656 -371.18671) (xy 166.920071 -371.195896)
			(xy 166.926582 -371.21308) (xy 166.932356 -371.220238) (xy 166.954106 -371.245921) (xy 166.992057 -371.301503)
			(xy 167.023092 -371.361222) (xy 167.046767 -371.424223) (xy 167.062743 -371.489601) (xy 167.07079 -371.55642)
			(xy 167.070793 -371.623722) (xy 167.062753 -371.690543) (xy 167.046784 -371.755923) (xy 167.023115 -371.818926)
			(xy 166.992086 -371.878648) (xy 166.954141 -371.934234) (xy 166.932356 -371.959886) (xy 166.926535 -371.967014)
			(xy 166.920036 -371.984218) (xy 166.919656 -371.993414) (xy 166.919656 -372.486682) (xy 166.920085 -372.495867)
			(xy 166.926586 -372.513051) (xy 166.932356 -372.52021) (xy 166.954177 -372.545834) (xy 166.992126 -372.601425)
			(xy 167.023158 -372.661152) (xy 167.046829 -372.72416) (xy 167.0628 -372.789546) (xy 167.070841 -372.856372)
			(xy 167.070838 -372.923679) (xy 167.06279 -372.990504) (xy 167.046814 -373.055889) (xy 167.023137 -373.118895)
			(xy 166.992099 -373.178619) (xy 166.954146 -373.234206) (xy 166.932356 -373.259858) (xy 166.926547 -373.266994)
			(xy 166.920041 -373.284192) (xy 166.919656 -373.293386) (xy 166.919656 -373.451374) (xy 166.919215 -373.461545)
			(xy 166.911437 -373.48034) (xy 166.897057 -373.494726) (xy 166.878264 -373.502511) (xy 166.868094 -373.502936)
			(xy 166.151814 -373.502936) (xy 166.14164 -373.502524) (xy 166.122841 -373.494739) (xy 166.108454 -373.480349)
			(xy 166.100673 -373.461548) (xy 166.100252 -373.451374) (xy 166.100252 -373.293386) (xy 166.099837 -373.2842)
			(xy 166.093325 -373.267016) (xy 166.087552 -373.259858) (xy 166.065797 -373.234178) (xy 166.027847 -373.178596)
			(xy 165.996811 -373.118877) (xy 165.973136 -373.055876) (xy 165.95716 -372.990497) (xy 165.949113 -372.923677)
			(xy 165.94911 -372.856374) (xy 165.957151 -372.789554) (xy 165.973121 -372.724173) (xy 165.99679 -372.66117)
			(xy 166.02782 -372.601448) (xy 166.065766 -372.545862) (xy 166.087552 -372.52021) (xy 166.093376 -372.513084)
			(xy 166.099873 -372.495879) (xy 166.100252 -372.486682) (xy 166.100252 -371.993414) (xy 166.099824 -371.984229)
			(xy 166.093321 -371.967045) (xy 166.087552 -371.959886) (xy 166.065726 -371.934265) (xy 166.027778 -371.878674)
			(xy 165.996745 -371.818947) (xy 165.973074 -371.755938) (xy 165.957104 -371.690552) (xy 165.949062 -371.623726)
			(xy 164.846957 -371.623726) (xy 164.847086 -371.624068) (xy 164.86312 -371.689559) (xy 164.871195 -371.756498)
			(xy 164.871194 -371.823923) (xy 164.863116 -371.890862) (xy 164.84708 -371.956352) (xy 164.823314 -372.019449)
			(xy 164.792162 -372.079246) (xy 164.754073 -372.134881) (xy 164.732208 -372.160546) (xy 164.72641 -372.16769)
			(xy 164.719896 -372.184881) (xy 164.719508 -372.194074) (xy 164.719508 -372.351554) (xy 164.718937 -372.361672)
			(xy 164.711233 -372.380383) (xy 164.696973 -372.394739) (xy 164.678314 -372.402568) (xy 164.6682 -372.403116)
			(xy 163.95192 -372.403116) (xy 163.941769 -372.402662) (xy 163.92302 -372.394876) (xy 163.908697 -372.38049)
			(xy 163.900993 -372.361707) (xy 163.900612 -372.351554) (xy 163.900612 -372.194074) (xy 163.900212 -372.184886)
			(xy 163.893691 -372.167702) (xy 163.887912 -372.160546) (xy 163.866061 -372.13487) (xy 163.827971 -372.079237)
			(xy 163.796819 -372.019442) (xy 163.773054 -371.956347) (xy 163.757017 -371.890859) (xy 163.74894 -371.823922)
			(xy 163.748939 -371.756499) (xy 163.757013 -371.689562) (xy 163.773048 -371.624073) (xy 163.796811 -371.560977)
			(xy 163.827961 -371.501181) (xy 163.866048 -371.445547) (xy 163.887912 -371.419882) (xy 163.8937 -371.412731)
			(xy 163.900219 -371.395545) (xy 163.900612 -371.386354) (xy 163.900612 -370.893848) (xy 163.900176 -370.884664)
			(xy 163.89368 -370.867479) (xy 163.887912 -370.86032) (xy 163.866036 -370.834665) (xy 163.827947 -370.779029)
			(xy 163.796796 -370.719232) (xy 163.773032 -370.656133) (xy 163.756997 -370.590643) (xy 163.748922 -370.523703)
			(xy 160.470875 -370.523703) (xy 160.462839 -370.590466) (xy 160.446866 -370.655848) (xy 160.423192 -370.718852)
			(xy 160.392158 -370.778575) (xy 160.354208 -370.83416) (xy 160.33242 -370.859812) (xy 160.326638 -370.866968)
			(xy 160.320114 -370.88415) (xy 160.31972 -370.89334) (xy 160.31972 -371.386862) (xy 160.320144 -371.396048)
			(xy 160.326647 -371.413233) (xy 160.33242 -371.42039) (xy 160.354223 -371.44603) (xy 160.392174 -371.501618)
			(xy 160.423209 -371.561342) (xy 160.44667 -371.623784) (xy 161.548767 -371.623784) (xy 161.548771 -371.556358)
			(xy 161.55685 -371.489418) (xy 161.572888 -371.423928) (xy 161.596655 -371.360829) (xy 161.627808 -371.301032)
			(xy 161.665899 -371.245396) (xy 161.687764 -371.21973) (xy 161.693581 -371.212599) (xy 161.700082 -371.195397)
			(xy 161.700464 -371.186202) (xy 161.700464 -371.028722) (xy 161.700945 -371.018594) (xy 161.70867 -370.999868)
			(xy 161.722959 -370.985511) (xy 161.741646 -370.977695) (xy 161.751772 -370.97716) (xy 162.468052 -370.97716)
			(xy 162.478166 -370.977654) (xy 162.496861 -370.985379) (xy 162.511176 -370.999671) (xy 162.51893 -371.018354)
			(xy 162.51936 -371.028468) (xy 162.51936 -371.186202) (xy 162.519778 -371.195388) (xy 162.526287 -371.212572)
			(xy 162.53206 -371.21973) (xy 162.553888 -371.245425) (xy 162.591981 -371.301055) (xy 162.623135 -371.360846)
			(xy 162.646903 -371.423939) (xy 162.662942 -371.489425) (xy 162.671022 -371.556361) (xy 162.671025 -371.623782)
			(xy 162.662953 -371.690719) (xy 162.64692 -371.756206) (xy 162.623158 -371.819302) (xy 162.59201 -371.879096)
			(xy 162.553923 -371.934729) (xy 162.53206 -371.960394) (xy 162.526278 -371.96755) (xy 162.519756 -371.984732)
			(xy 162.51936 -371.993922) (xy 162.51936 -372.486174) (xy 162.519791 -372.495359) (xy 162.526291 -372.512543)
			(xy 162.53206 -372.519702) (xy 162.553959 -372.545339) (xy 162.592049 -372.600977) (xy 162.623201 -372.660776)
			(xy 162.646965 -372.723877) (xy 162.662999 -372.78937) (xy 162.671073 -372.856312) (xy 162.67107 -372.923739)
			(xy 162.66299 -372.99068) (xy 162.646949 -373.056172) (xy 162.62318 -373.11927) (xy 162.592023 -373.179067)
			(xy 162.553927 -373.234701) (xy 162.53206 -373.260366) (xy 162.526248 -373.2675) (xy 162.519743 -373.284699)
			(xy 162.51936 -373.293894) (xy 162.51936 -373.451374) (xy 162.518852 -373.461499) (xy 162.511133 -373.48022)
			(xy 162.496853 -373.494577) (xy 162.478174 -373.502397) (xy 162.468052 -373.502936) (xy 161.751772 -373.502936)
			(xy 161.741666 -373.502439) (xy 161.722994 -373.494699) (xy 161.708701 -373.480406) (xy 161.700961 -373.461734)
			(xy 161.700464 -373.451628) (xy 161.700464 -373.293894) (xy 161.700042 -373.284708) (xy 161.693535 -373.267525)
			(xy 161.687764 -373.260366) (xy 161.665935 -373.234673) (xy 161.627847 -373.179041) (xy 161.596697 -373.119249)
			(xy 161.572933 -373.056155) (xy 161.556896 -372.99067) (xy 161.548818 -372.923736) (xy 161.548815 -372.856315)
			(xy 161.556887 -372.78938) (xy 161.572918 -372.723893) (xy 161.596676 -372.660798) (xy 161.627821 -372.601003)
			(xy 161.665903 -372.545368) (xy 161.687764 -372.519702) (xy 161.69355 -372.51255) (xy 161.700069 -372.495364)
			(xy 161.700464 -372.486174) (xy 161.700464 -371.993922) (xy 161.700029 -371.984738) (xy 161.693531 -371.967554)
			(xy 161.687764 -371.960394) (xy 161.665864 -371.934759) (xy 161.627779 -371.879119) (xy 161.596632 -371.819319)
			(xy 161.572871 -371.756218) (xy 161.55684 -371.690725) (xy 161.548767 -371.623784) (xy 160.44667 -371.623784)
			(xy 160.446882 -371.624348) (xy 160.462856 -371.689733) (xy 160.470899 -371.756557) (xy 160.470898 -371.823864)
			(xy 160.462852 -371.890688) (xy 160.446876 -371.956072) (xy 160.4232 -372.019077) (xy 160.392163 -372.078801)
			(xy 160.35421 -372.134386) (xy 160.33242 -372.160038) (xy 160.326627 -372.167186) (xy 160.32011 -372.184374)
			(xy 160.31972 -372.193566) (xy 160.31972 -372.351554) (xy 160.319297 -372.361728) (xy 160.31152 -372.38053)
			(xy 160.297133 -372.394918) (xy 160.278332 -372.402697) (xy 160.268158 -372.403116) (xy 159.551878 -372.403116)
			(xy 159.541699 -372.402753) (xy 159.522895 -372.394952) (xy 159.50851 -372.380547) (xy 159.500734 -372.361733)
			(xy 159.500316 -372.351554) (xy 159.500316 -372.193566) (xy 159.499919 -372.184378) (xy 159.493396 -372.167193)
			(xy 159.487616 -372.160038) (xy 159.465843 -372.134374) (xy 159.427895 -372.078789) (xy 159.396862 -372.019067)
			(xy 159.37319 -371.956064) (xy 159.357216 -371.890683) (xy 159.349172 -371.823862) (xy 159.34917 -371.756559)
			(xy 159.357213 -371.689738) (xy 159.373184 -371.624356) (xy 159.396854 -371.561353) (xy 159.427884 -371.501629)
			(xy 159.46583 -371.446042) (xy 159.487616 -371.42039) (xy 159.493401 -371.413237) (xy 159.499922 -371.396052)
			(xy 159.500316 -371.386862) (xy 159.500316 -370.89334) (xy 159.499883 -370.884155) (xy 159.493385 -370.866971)
			(xy 159.487616 -370.859812) (xy 159.465817 -370.834169) (xy 159.42787 -370.778581) (xy 159.396839 -370.718856)
			(xy 159.373168 -370.65585) (xy 159.357196 -370.590467) (xy 159.349153 -370.523644) (xy 129.670828 -370.523644)
			(xy 129.662785 -370.590464) (xy 129.646814 -370.655846) (xy 129.623143 -370.71885) (xy 129.592113 -370.778573)
			(xy 129.554166 -370.83416) (xy 129.53238 -370.859812) (xy 129.526594 -370.866964) (xy 129.520073 -370.884149)
			(xy 129.51968 -370.89334) (xy 129.51968 -371.386862) (xy 129.520113 -371.396047) (xy 129.526611 -371.413231)
			(xy 129.53238 -371.42039) (xy 129.554181 -371.446031) (xy 129.592128 -371.50162) (xy 129.62316 -371.561345)
			(xy 129.646596 -371.623725) (xy 130.749241 -371.623725) (xy 130.749245 -371.556418) (xy 130.757292 -371.489593)
			(xy 130.773269 -371.424208) (xy 130.796945 -371.361202) (xy 130.827982 -371.301478) (xy 130.865934 -371.24589)
			(xy 130.887724 -371.220238) (xy 130.893532 -371.213101) (xy 130.900039 -371.195904) (xy 130.900424 -371.18671)
			(xy 130.900424 -371.028722) (xy 130.900882 -371.018554) (xy 130.908657 -370.999762) (xy 130.923032 -370.985377)
			(xy 130.941818 -370.977589) (xy 130.951986 -370.97716) (xy 131.668266 -370.97716) (xy 131.678438 -370.977592)
			(xy 131.697236 -370.98537) (xy 131.711623 -370.999754) (xy 131.719405 -371.01855) (xy 131.719828 -371.028722)
			(xy 131.719828 -371.18671) (xy 131.720227 -371.195898) (xy 131.726748 -371.213083) (xy 131.732528 -371.220238)
			(xy 131.754279 -371.24592) (xy 131.792231 -371.301502) (xy 131.823268 -371.361221) (xy 131.846945 -371.424221)
			(xy 131.862921 -371.4896) (xy 131.870969 -371.55642) (xy 131.870972 -371.623723) (xy 131.862931 -371.690543)
			(xy 131.846961 -371.755924) (xy 131.823291 -371.818927) (xy 131.792261 -371.878649) (xy 131.754314 -371.934234)
			(xy 131.732528 -371.959886) (xy 131.726704 -371.967011) (xy 131.720208 -371.984217) (xy 131.719828 -371.993414)
			(xy 131.719828 -372.486682) (xy 131.72024 -372.495869) (xy 131.726752 -372.513054) (xy 131.732528 -372.52021)
			(xy 131.75435 -372.545834) (xy 131.7923 -372.601424) (xy 131.823334 -372.661151) (xy 131.847006 -372.724159)
			(xy 131.862978 -372.789545) (xy 131.87102 -372.856371) (xy 131.871017 -372.92368) (xy 131.862969 -372.990505)
			(xy 131.846991 -373.05589) (xy 131.823313 -373.118896) (xy 131.792274 -373.17862) (xy 131.754319 -373.234206)
			(xy 131.732528 -373.259858) (xy 131.726716 -373.266992) (xy 131.720212 -373.284191) (xy 131.719828 -373.293386)
			(xy 131.719828 -373.451374) (xy 131.719414 -373.461548) (xy 131.711631 -373.480349) (xy 131.697242 -373.494736)
			(xy 131.67844 -373.502515) (xy 131.668266 -373.502936) (xy 130.951986 -373.502936) (xy 130.94181 -373.502547)
			(xy 130.92301 -373.494752) (xy 130.908625 -373.480356) (xy 130.900845 -373.46155) (xy 130.900424 -373.451374)
			(xy 130.900424 -373.293386) (xy 130.900015 -373.284199) (xy 130.8935 -373.267015) (xy 130.887724 -373.259858)
			(xy 130.86597 -373.234178) (xy 130.828022 -373.178595) (xy 130.796988 -373.118875) (xy 130.773314 -373.055874)
			(xy 130.757339 -372.990496) (xy 130.749292 -372.923677) (xy 130.749289 -372.856375) (xy 130.75733 -372.789555)
			(xy 130.773299 -372.724174) (xy 130.796967 -372.661171) (xy 130.827995 -372.601449) (xy 130.865939 -372.545863)
			(xy 130.887724 -372.52021) (xy 130.893544 -372.513082) (xy 130.900044 -372.495878) (xy 130.900424 -372.486682)
			(xy 130.900424 -371.993414) (xy 130.900002 -371.984228) (xy 130.893496 -371.967044) (xy 130.887724 -371.959886)
			(xy 130.865899 -371.934264) (xy 130.827953 -371.878673) (xy 130.796922 -371.818945) (xy 130.773252 -371.755937)
			(xy 130.757282 -371.690551) (xy 130.749241 -371.623725) (xy 129.646596 -371.623725) (xy 129.646831 -371.624351)
			(xy 129.662802 -371.689734) (xy 129.670845 -371.756558) (xy 129.670844 -371.823863) (xy 129.662799 -371.890687)
			(xy 129.646825 -371.956069) (xy 129.623151 -372.019074) (xy 129.592117 -372.078799) (xy 129.554168 -372.134386)
			(xy 129.53238 -372.160038) (xy 129.526582 -372.167182) (xy 129.520069 -372.184374) (xy 129.51968 -372.193566)
			(xy 129.51968 -372.351554) (xy 129.519199 -372.36172) (xy 129.511432 -372.380511) (xy 129.497064 -372.394896)
			(xy 129.478284 -372.402686) (xy 129.468118 -372.403116) (xy 128.751838 -372.403116) (xy 128.741663 -372.402704)
			(xy 128.722861 -372.394923) (xy 128.708473 -372.380533) (xy 128.700695 -372.361729) (xy 128.700276 -372.351554)
			(xy 128.700276 -372.193566) (xy 128.699887 -372.184376) (xy 128.693359 -372.167192) (xy 128.687576 -372.160038)
			(xy 128.665801 -372.134375) (xy 128.627849 -372.078791) (xy 128.596813 -372.019069) (xy 128.573138 -371.956066)
			(xy 128.557163 -371.890685) (xy 128.549117 -371.823863) (xy 128.549116 -371.756558) (xy 128.557159 -371.689736)
			(xy 128.573132 -371.624354) (xy 128.596805 -371.56135) (xy 128.627838 -371.501627) (xy 128.665788 -371.446042)
			(xy 128.687576 -371.42039) (xy 128.693357 -371.413233) (xy 128.699882 -371.396052) (xy 128.700276 -371.386862)
			(xy 128.700276 -370.89334) (xy 128.699852 -370.884154) (xy 128.693349 -370.866969) (xy 128.687576 -370.859812)
			(xy 128.665775 -370.83417) (xy 128.627825 -370.778583) (xy 128.59679 -370.718858) (xy 128.573116 -370.655852)
			(xy 128.557143 -370.590469) (xy 128.549099 -370.523644) (xy 125.271037 -370.523644) (xy 125.262994 -370.590464)
			(xy 125.247024 -370.655845) (xy 125.223354 -370.718849) (xy 125.192323 -370.778573) (xy 125.154378 -370.834159)
			(xy 125.132592 -370.859812) (xy 125.126807 -370.866965) (xy 125.120286 -370.88415) (xy 125.119892 -370.89334)
			(xy 125.119892 -371.386862) (xy 125.120322 -371.396047) (xy 125.126822 -371.413231) (xy 125.132592 -371.42039)
			(xy 125.154393 -371.446031) (xy 125.192339 -371.50162) (xy 125.22337 -371.561345) (xy 125.246828 -371.623785)
			(xy 126.348921 -371.623785) (xy 126.348925 -371.556358) (xy 126.357005 -371.489416) (xy 126.373046 -371.423925)
			(xy 126.396816 -371.360826) (xy 126.427973 -371.301029) (xy 126.466069 -371.245395) (xy 126.487936 -371.21973)
			(xy 126.493749 -371.212597) (xy 126.500253 -371.195397) (xy 126.500636 -371.186202) (xy 126.500636 -371.028722)
			(xy 126.501144 -371.018597) (xy 126.508864 -370.999877) (xy 126.523144 -370.98552) (xy 126.541822 -370.9777)
			(xy 126.551944 -370.97716) (xy 127.268224 -370.97716) (xy 127.278375 -370.977601) (xy 127.29712 -370.985397)
			(xy 127.311441 -370.999787) (xy 127.319147 -371.018569) (xy 127.319532 -371.028722) (xy 127.319532 -371.186202)
			(xy 127.319956 -371.195387) (xy 127.326462 -371.212571) (xy 127.332232 -371.21973) (xy 127.354058 -371.245427)
			(xy 127.392145 -371.301057) (xy 127.423296 -371.36085) (xy 127.447061 -371.423942) (xy 127.463098 -371.489427)
			(xy 127.471176 -371.556361) (xy 127.47118 -371.623781) (xy 127.463108 -371.690717) (xy 127.447078 -371.756203)
			(xy 127.423319 -371.819298) (xy 127.392175 -371.879094) (xy 127.354093 -371.934728) (xy 127.332232 -371.960394)
			(xy 127.326447 -371.967547) (xy 127.319927 -371.984732) (xy 127.319532 -371.993922) (xy 127.319532 -372.486174)
			(xy 127.31997 -372.495358) (xy 127.326466 -372.512542) (xy 127.332232 -372.519702) (xy 127.354128 -372.54534)
			(xy 127.392214 -372.600979) (xy 127.423361 -372.66078) (xy 127.447122 -372.72388) (xy 127.463154 -372.789372)
			(xy 127.471227 -372.856313) (xy 127.471224 -372.923738) (xy 127.463145 -372.990678) (xy 127.447107 -373.056169)
			(xy 127.42334 -373.119267) (xy 127.392188 -373.179064) (xy 127.354097 -373.2347) (xy 127.332232 -373.260366)
			(xy 127.326417 -373.267498) (xy 127.319915 -373.284699) (xy 127.319532 -373.293894) (xy 127.319532 -373.451374)
			(xy 127.319051 -373.461503) (xy 127.311327 -373.480228) (xy 127.297038 -373.494587) (xy 127.27835 -373.502402)
			(xy 127.268224 -373.502936) (xy 126.551944 -373.502936) (xy 126.541797 -373.502443) (xy 126.523053 -373.494669)
			(xy 126.508729 -373.480294) (xy 126.501021 -373.461522) (xy 126.500636 -373.451374) (xy 126.500636 -373.293894)
			(xy 126.500221 -373.284708) (xy 126.49371 -373.267524) (xy 126.487936 -373.260366) (xy 126.466104 -373.234674)
			(xy 126.428012 -373.179044) (xy 126.396858 -373.119252) (xy 126.37309 -373.056158) (xy 126.357051 -372.990672)
			(xy 126.348972 -372.923736) (xy 126.348969 -372.856315) (xy 126.357042 -372.789378) (xy 126.373075 -372.72389)
			(xy 126.396837 -372.660795) (xy 126.427986 -372.601) (xy 126.466073 -372.545367) (xy 126.487936 -372.519702)
			(xy 126.493719 -372.512547) (xy 126.500241 -372.495364) (xy 126.500636 -372.486174) (xy 126.500636 -371.993922)
			(xy 126.500207 -371.984737) (xy 126.493706 -371.967553) (xy 126.487936 -371.960394) (xy 126.466033 -371.93476)
			(xy 126.427943 -371.879122) (xy 126.396792 -371.819322) (xy 126.373029 -371.756221) (xy 126.356995 -371.690727)
			(xy 126.348921 -371.623785) (xy 125.246828 -371.623785) (xy 125.247041 -371.624351) (xy 125.263012 -371.689734)
			(xy 125.271054 -371.756558) (xy 125.271053 -371.823863) (xy 125.263008 -371.890686) (xy 125.247034 -371.956069)
			(xy 125.223361 -372.019074) (xy 125.192328 -372.078798) (xy 125.15438 -372.134385) (xy 125.132592 -372.160038)
			(xy 125.126796 -372.167183) (xy 125.120281 -372.184374) (xy 125.119892 -372.193566) (xy 125.119892 -372.351554)
			(xy 125.119399 -372.361719) (xy 125.111635 -372.380507) (xy 125.097271 -372.394892) (xy 125.078494 -372.402684)
			(xy 125.06833 -372.403116) (xy 124.35205 -372.403116) (xy 124.341876 -372.402694) (xy 124.323073 -372.394917)
			(xy 124.308685 -372.38053) (xy 124.300907 -372.361728) (xy 124.300488 -372.351554) (xy 124.300488 -372.193566)
			(xy 124.300097 -372.184377) (xy 124.29357 -372.167192) (xy 124.287788 -372.160038) (xy 124.266013 -372.134375)
			(xy 124.22806 -372.078791) (xy 124.197024 -372.01907) (xy 124.173348 -371.956067) (xy 124.157372 -371.890685)
			(xy 124.149326 -371.823863) (xy 124.149325 -371.756558) (xy 124.157369 -371.689736) (xy 124.173342 -371.624354)
			(xy 124.197015 -371.561349) (xy 124.228049 -371.501627) (xy 124.266 -371.446041) (xy 124.287788 -371.42039)
			(xy 124.29357 -371.413234) (xy 124.300094 -371.396052) (xy 124.300488 -371.386862) (xy 124.300488 -370.89334)
			(xy 124.300061 -370.884154) (xy 124.29356 -370.86697) (xy 124.287788 -370.859812) (xy 124.265987 -370.83417)
			(xy 124.228035 -370.778583) (xy 124.197 -370.718859) (xy 124.173326 -370.655853) (xy 124.157352 -370.590469)
			(xy 124.149308 -370.523644) (xy 120.871269 -370.523644) (xy 120.871269 -370.523702) (xy 120.863194 -370.59064)
			(xy 120.847159 -370.656128) (xy 120.823396 -370.719225) (xy 120.792247 -370.779021) (xy 120.754159 -370.834655)
			(xy 120.732296 -370.86032) (xy 120.726508 -370.867471) (xy 120.719988 -370.884657) (xy 120.719596 -370.893848)
			(xy 120.719596 -371.386354) (xy 120.720029 -371.395539) (xy 120.726527 -371.412723) (xy 120.732296 -371.419882)
			(xy 120.754174 -371.445536) (xy 120.792262 -371.501172) (xy 120.823413 -371.56097) (xy 120.847047 -371.623725)
			(xy 121.949153 -371.623725) (xy 121.949157 -371.556417) (xy 121.957205 -371.489592) (xy 121.973182 -371.424208)
			(xy 121.996859 -371.361202) (xy 122.027896 -371.301477) (xy 122.06585 -371.24589) (xy 122.08764 -371.220238)
			(xy 122.09345 -371.213103) (xy 122.099956 -371.195904) (xy 122.10034 -371.18671) (xy 122.10034 -371.028722)
			(xy 122.100782 -371.018552) (xy 122.10856 -370.999757) (xy 122.12294 -370.985371) (xy 122.141732 -370.977586)
			(xy 122.151902 -370.97716) (xy 122.868182 -370.97716) (xy 122.878355 -370.977579) (xy 122.897154 -370.985362)
			(xy 122.91154 -370.99975) (xy 122.919322 -371.018549) (xy 122.919744 -371.028722) (xy 122.919744 -371.18671)
			(xy 122.920162 -371.195896) (xy 122.926672 -371.21308) (xy 122.932444 -371.220238) (xy 122.954195 -371.245921)
			(xy 122.992146 -371.301502) (xy 123.023182 -371.361222) (xy 123.046857 -371.424222) (xy 123.062833 -371.489601)
			(xy 123.070881 -371.55642) (xy 123.070884 -371.623723) (xy 123.062844 -371.690543) (xy 123.046874 -371.755923)
			(xy 123.023205 -371.818926) (xy 122.992175 -371.878648) (xy 122.95423 -371.934234) (xy 122.932444 -371.959886)
			(xy 122.926622 -371.967013) (xy 122.920124 -371.984218) (xy 122.919744 -371.993414) (xy 122.919744 -372.486682)
			(xy 122.920175 -372.495867) (xy 122.926676 -372.513051) (xy 122.932444 -372.52021) (xy 122.954266 -372.545834)
			(xy 122.992215 -372.601424) (xy 123.023248 -372.661152) (xy 123.046919 -372.72416) (xy 123.06289 -372.789546)
			(xy 123.070932 -372.856372) (xy 123.070929 -372.92368) (xy 123.062881 -372.990505) (xy 123.046904 -373.055889)
			(xy 123.023227 -373.118895) (xy 122.992188 -373.17862) (xy 122.954234 -373.234206) (xy 122.932444 -373.259858)
			(xy 122.926633 -373.266993) (xy 122.920129 -373.284192) (xy 122.919744 -373.293386) (xy 122.919744 -373.451374)
			(xy 122.919314 -373.461546) (xy 122.911534 -373.480344) (xy 122.89715 -373.49473) (xy 122.878354 -373.502513)
			(xy 122.868182 -373.502936) (xy 122.151902 -373.502936) (xy 122.141727 -373.502534) (xy 122.122928 -373.494745)
			(xy 122.108542 -373.480352) (xy 122.100761 -373.461549) (xy 122.10034 -373.451374) (xy 122.10034 -373.293386)
			(xy 122.099928 -373.284199) (xy 122.093415 -373.267015) (xy 122.08764 -373.259858) (xy 122.065886 -373.234178)
			(xy 122.027936 -373.178596) (xy 121.996901 -373.118876) (xy 121.973226 -373.055875) (xy 121.957251 -372.990496)
			(xy 121.949204 -372.923677) (xy 121.949201 -372.856374) (xy 121.957242 -372.789554) (xy 121.973211 -372.724174)
			(xy 121.99688 -372.661171) (xy 122.02791 -372.601448) (xy 122.065855 -372.545862) (xy 122.08764 -372.52021)
			(xy 122.093462 -372.513083) (xy 122.099961 -372.495878) (xy 122.10034 -372.486682) (xy 122.10034 -371.993414)
			(xy 122.099914 -371.984229) (xy 122.093411 -371.967045) (xy 122.08764 -371.959886) (xy 122.065815 -371.934265)
			(xy 122.027867 -371.878674) (xy 121.996835 -371.818946) (xy 121.973165 -371.755937) (xy 121.957194 -371.690551)
			(xy 121.949153 -371.623725) (xy 120.847047 -371.623725) (xy 120.847176 -371.624068) (xy 120.863211 -371.689558)
			(xy 120.871286 -371.756498) (xy 120.871284 -371.823923) (xy 120.863207 -371.890862) (xy 120.84717 -371.956352)
			(xy 120.823404 -372.01945) (xy 120.792252 -372.079246) (xy 120.754161 -372.134881) (xy 120.732296 -372.160546)
			(xy 120.726497 -372.167689) (xy 120.719984 -372.184881) (xy 120.719596 -372.194074) (xy 120.719596 -372.351554)
			(xy 120.719037 -372.361673) (xy 120.711331 -372.380387) (xy 120.697067 -372.394743) (xy 120.678404 -372.40257)
			(xy 120.668288 -372.403116) (xy 119.952008 -372.403116) (xy 119.941856 -372.402672) (xy 119.923107 -372.394882)
			(xy 119.908784 -372.380493) (xy 119.901081 -372.361707) (xy 119.9007 -372.351554) (xy 119.9007 -372.194074)
			(xy 119.900303 -372.184885) (xy 119.89378 -372.167701) (xy 119.888 -372.160546) (xy 119.86615 -372.134869)
			(xy 119.828061 -372.079237) (xy 119.796909 -372.019442) (xy 119.773144 -371.956346) (xy 119.757108 -371.890859)
			(xy 119.749031 -371.823922) (xy 119.74903 -371.756499) (xy 119.757104 -371.689562) (xy 119.773138 -371.624074)
			(xy 119.796901 -371.560977) (xy 119.82805 -371.501182) (xy 119.866137 -371.445547) (xy 119.888 -371.419882)
			(xy 119.893787 -371.41273) (xy 119.900307 -371.395545) (xy 119.9007 -371.386354) (xy 119.9007 -370.893848)
			(xy 119.900267 -370.884663) (xy 119.893769 -370.867479) (xy 119.888 -370.86032) (xy 119.866124 -370.834664)
			(xy 119.828036 -370.779029) (xy 119.796886 -370.719231) (xy 119.773122 -370.656133) (xy 119.757088 -370.590643)
			(xy 119.749013 -370.523703) (xy 116.470966 -370.523703) (xy 116.462929 -370.590466) (xy 116.446956 -370.655848)
			(xy 116.423282 -370.718853) (xy 116.392247 -370.778575) (xy 116.354297 -370.834161) (xy 116.332508 -370.859812)
			(xy 116.326725 -370.866967) (xy 116.320202 -370.88415) (xy 116.319808 -370.89334) (xy 116.319808 -371.386862)
			(xy 116.320235 -371.396047) (xy 116.326737 -371.413232) (xy 116.332508 -371.42039) (xy 116.354311 -371.44603)
			(xy 116.392263 -371.501617) (xy 116.423299 -371.561342) (xy 116.446761 -371.623785) (xy 117.548834 -371.623785)
			(xy 117.548837 -371.556358) (xy 117.556917 -371.489416) (xy 117.572959 -371.423924) (xy 117.596729 -371.360825)
			(xy 117.627887 -371.301028) (xy 117.665984 -371.245394) (xy 117.687852 -371.21973) (xy 117.693667 -371.212598)
			(xy 117.700169 -371.195397) (xy 117.700552 -371.186202) (xy 117.700552 -371.028722) (xy 117.701045 -371.018595)
			(xy 117.708768 -370.999872) (xy 117.723052 -370.985515) (xy 117.741736 -370.977697) (xy 117.75186 -370.97716)
			(xy 118.46814 -370.97716) (xy 118.478292 -370.977588) (xy 118.497037 -370.985389) (xy 118.511358 -370.999783)
			(xy 118.519063 -371.018568) (xy 118.519448 -371.028722) (xy 118.519448 -371.186202) (xy 118.519869 -371.195388)
			(xy 118.526376 -371.212572) (xy 118.532148 -371.21973) (xy 118.553976 -371.245425) (xy 118.59207 -371.301054)
			(xy 118.623225 -371.360846) (xy 118.646994 -371.423939) (xy 118.663033 -371.489425) (xy 118.671113 -371.556361)
			(xy 118.671116 -371.623782) (xy 118.663044 -371.690719) (xy 118.647011 -371.756207) (xy 118.623248 -371.819302)
			(xy 118.592099 -371.879097) (xy 118.554012 -371.93473) (xy 118.532148 -371.960394) (xy 118.526365 -371.967549)
			(xy 118.519844 -371.984732) (xy 118.519448 -371.993922) (xy 118.519448 -372.486174) (xy 118.519882 -372.495358)
			(xy 118.52638 -372.512542) (xy 118.532148 -372.519702) (xy 118.554047 -372.545339) (xy 118.592138 -372.600976)
			(xy 118.62329 -372.660776) (xy 118.647055 -372.723877) (xy 118.66309 -372.78937) (xy 118.671164 -372.856312)
			(xy 118.671161 -372.923739) (xy 118.663081 -372.990681) (xy 118.64704 -373.056172) (xy 118.62327 -373.119271)
			(xy 118.592112 -373.179068) (xy 118.554016 -373.234702) (xy 118.532148 -373.260366) (xy 118.526334 -373.267499)
			(xy 118.519831 -373.284699) (xy 118.519448 -373.293894) (xy 118.519448 -373.451374) (xy 118.518952 -373.461501)
			(xy 118.51123 -373.480223) (xy 118.496947 -373.494581) (xy 118.478264 -373.502399) (xy 118.46814 -373.502936)
			(xy 117.75186 -373.502936) (xy 117.741708 -373.502512) (xy 117.722961 -373.49471) (xy 117.708641 -373.480315)
			(xy 117.700936 -373.461528) (xy 117.700552 -373.451374) (xy 117.700552 -373.293894) (xy 117.700133 -373.284708)
			(xy 117.693624 -373.267524) (xy 117.687852 -373.260366) (xy 117.66602 -373.234674) (xy 117.627926 -373.179045)
			(xy 117.596771 -373.119253) (xy 117.573003 -373.056159) (xy 117.556964 -372.990673) (xy 117.548884 -372.923737)
			(xy 117.548881 -372.856315) (xy 117.556954 -372.789378) (xy 117.572988 -372.72389) (xy 117.596751 -372.660794)
			(xy 117.6279 -372.600999) (xy 117.665988 -372.545366) (xy 117.687852 -372.519702) (xy 117.693637 -372.512549)
			(xy 117.700157 -372.495364) (xy 117.700552 -372.486174) (xy 117.700552 -371.993922) (xy 117.70012 -371.984737)
			(xy 117.69362 -371.967553) (xy 117.687852 -371.960394) (xy 117.665949 -371.93476) (xy 117.627858 -371.879123)
			(xy 117.596706 -371.819323) (xy 117.572942 -371.756221) (xy 117.556907 -371.690728) (xy 117.548834 -371.623785)
			(xy 116.446761 -371.623785) (xy 116.446973 -371.624348) (xy 116.462946 -371.689732) (xy 116.47099 -371.756557)
			(xy 116.470989 -371.823864) (xy 116.462943 -371.890689) (xy 116.446967 -371.956072) (xy 116.42329 -372.019077)
			(xy 116.392252 -372.078801) (xy 116.354298 -372.134387) (xy 116.332508 -372.160038) (xy 116.326714 -372.167185)
			(xy 116.320197 -372.184374) (xy 116.319808 -372.193566) (xy 116.319808 -372.351554) (xy 116.31923 -372.361703)
			(xy 116.311479 -372.380462) (xy 116.29714 -372.394828) (xy 116.278394 -372.402612) (xy 116.268246 -372.403116)
			(xy 115.551966 -372.403116) (xy 115.541786 -372.402763) (xy 115.522982 -372.394958) (xy 115.508597 -372.380551)
			(xy 115.500821 -372.361734) (xy 115.500404 -372.351554) (xy 115.500404 -372.193566) (xy 115.500009 -372.184377)
			(xy 115.493485 -372.167193) (xy 115.487704 -372.160038) (xy 115.465931 -372.134374) (xy 115.427984 -372.078788)
			(xy 115.396952 -372.019066) (xy 115.37328 -371.956063) (xy 115.357307 -371.890683) (xy 115.349263 -371.823862)
			(xy 115.349261 -371.756559) (xy 115.357303 -371.689738) (xy 115.373274 -371.624357) (xy 115.396944 -371.561353)
			(xy 115.427973 -371.50163) (xy 115.465918 -371.446043) (xy 115.487704 -371.42039) (xy 115.493488 -371.413236)
			(xy 115.50001 -371.396052) (xy 115.500404 -371.386862) (xy 115.500404 -370.89334) (xy 115.499974 -370.884155)
			(xy 115.493474 -370.86697) (xy 115.487704 -370.859812) (xy 115.465906 -370.834169) (xy 115.427959 -370.77858)
			(xy 115.396929 -370.718855) (xy 115.373258 -370.65585) (xy 115.357287 -370.590467) (xy 115.349244 -370.523644)
			(xy 85.670941 -370.523644) (xy 85.670941 -370.523703) (xy 85.662866 -370.590641) (xy 85.646831 -370.65613)
			(xy 85.623066 -370.719226) (xy 85.591915 -370.779022) (xy 85.553825 -370.834655) (xy 85.53196 -370.86032)
			(xy 85.526167 -370.867468) (xy 85.519651 -370.884656) (xy 85.51926 -370.893848) (xy 85.51926 -371.386354)
			(xy 85.519701 -371.395538) (xy 85.526194 -371.412722) (xy 85.53196 -371.419882) (xy 85.553839 -371.445535)
			(xy 85.59193 -371.501171) (xy 85.623082 -371.560968) (xy 85.646742 -371.623785) (xy 86.748803 -371.623785)
			(xy 86.748807 -371.556358) (xy 86.756887 -371.489417) (xy 86.772927 -371.423926) (xy 86.796696 -371.360827)
			(xy 86.827851 -371.30103) (xy 86.865945 -371.245395) (xy 86.887812 -371.21973) (xy 86.893622 -371.212594)
			(xy 86.900128 -371.195397) (xy 86.900512 -371.186202) (xy 86.900512 -371.028722) (xy 86.901044 -371.0186)
			(xy 86.908759 -370.999885) (xy 86.923031 -370.985529) (xy 86.941701 -370.977704) (xy 86.95182 -370.97716)
			(xy 87.6681 -370.97716) (xy 87.678204 -370.977684) (xy 87.696874 -370.985414) (xy 87.711168 -370.999699)
			(xy 87.718909 -371.018365) (xy 87.719408 -371.028468) (xy 87.719408 -371.186202) (xy 87.719815 -371.195389)
			(xy 87.726331 -371.212574) (xy 87.732108 -371.21973) (xy 87.753934 -371.245426) (xy 87.792024 -371.301056)
			(xy 87.823176 -371.360848) (xy 87.846942 -371.423941) (xy 87.862979 -371.489426) (xy 87.871058 -371.556361)
			(xy 87.871062 -371.623782) (xy 87.86299 -371.690717) (xy 87.846958 -371.756204) (xy 87.823199 -371.819299)
			(xy 87.792053 -371.879095) (xy 87.753969 -371.934729) (xy 87.732108 -371.960394) (xy 87.726332 -371.967554)
			(xy 87.719805 -371.984733) (xy 87.719408 -371.993922) (xy 87.719408 -372.486174) (xy 87.719829 -372.49536)
			(xy 87.726335 -372.512545) (xy 87.732108 -372.519702) (xy 87.754005 -372.54534) (xy 87.792092 -372.600978)
			(xy 87.823241 -372.660779) (xy 87.847003 -372.723879) (xy 87.863036 -372.789371) (xy 87.871109 -372.856312)
			(xy 87.871106 -372.923739) (xy 87.863027 -372.990679) (xy 87.846988 -373.05617) (xy 87.82322 -373.119268)
			(xy 87.792066 -373.179065) (xy 87.753974 -373.234701) (xy 87.732108 -373.260366) (xy 87.726302 -373.267504)
			(xy 87.719793 -373.2847) (xy 87.719408 -373.293894) (xy 87.719408 -373.451374) (xy 87.718854 -373.461493)
			(xy 87.711143 -373.480205) (xy 87.696878 -373.49456) (xy 87.678216 -373.502389) (xy 87.6681 -373.502936)
			(xy 86.95182 -373.502936) (xy 86.941717 -373.502399) (xy 86.923046 -373.494675) (xy 86.908752 -373.480394)
			(xy 86.90101 -373.461731) (xy 86.900512 -373.451628) (xy 86.900512 -373.293894) (xy 86.900102 -373.284707)
			(xy 86.893588 -373.267523) (xy 86.887812 -373.260366) (xy 86.865981 -373.234673) (xy 86.82789 -373.179043)
			(xy 86.796738 -373.119251) (xy 86.772971 -373.056157) (xy 86.756933 -372.990672) (xy 86.748854 -372.923736)
			(xy 86.748851 -372.856315) (xy 86.756924 -372.789379) (xy 86.772956 -372.723891) (xy 86.796717 -372.660796)
			(xy 86.827864 -372.601001) (xy 86.86595 -372.545367) (xy 86.887812 -372.519702) (xy 86.893592 -372.512545)
			(xy 86.900116 -372.495363) (xy 86.900512 -372.486174) (xy 86.900512 -371.993922) (xy 86.900088 -371.984736)
			(xy 86.893584 -371.967552) (xy 86.887812 -371.960394) (xy 86.86591 -371.93476) (xy 86.827822 -371.879121)
			(xy 86.796672 -371.819321) (xy 86.77291 -371.75622) (xy 86.756876 -371.690727) (xy 86.748803 -371.623785)
			(xy 85.646742 -371.623785) (xy 85.646848 -371.624067) (xy 85.662883 -371.689557) (xy 85.670959 -371.756498)
			(xy 85.670957 -371.823923) (xy 85.662879 -371.890863) (xy 85.646841 -371.956354) (xy 85.623074 -372.019451)
			(xy 85.591919 -372.079248) (xy 85.553826 -372.134881) (xy 85.53196 -372.160546) (xy 85.526156 -372.167686)
			(xy 85.519647 -372.184881) (xy 85.51926 -372.194074) (xy 85.51926 -372.351554) (xy 85.518736 -372.361678)
			(xy 85.511023 -372.380398) (xy 85.496748 -372.394756) (xy 85.478073 -372.402576) (xy 85.467952 -372.403116)
			(xy 84.751672 -372.403116) (xy 84.741563 -372.402638) (xy 84.722888 -372.394894) (xy 84.708594 -372.380596)
			(xy 84.700858 -372.361917) (xy 84.700364 -372.351808) (xy 84.700364 -372.194074) (xy 84.699952 -372.184887)
			(xy 84.693438 -372.167704) (xy 84.687664 -372.160546) (xy 84.665815 -372.134869) (xy 84.627728 -372.079235)
			(xy 84.596579 -372.01944) (xy 84.572816 -371.956345) (xy 84.55678 -371.890858) (xy 84.548704 -371.823921)
			(xy 84.548703 -371.7565) (xy 84.556776 -371.689563) (xy 84.572809 -371.624075) (xy 84.59657 -371.560979)
			(xy 84.627717 -371.501183) (xy 84.665802 -371.445548) (xy 84.687664 -371.419882) (xy 84.693459 -371.412736)
			(xy 84.699973 -371.395546) (xy 84.700364 -371.386354) (xy 84.700364 -370.893848) (xy 84.699917 -370.884665)
			(xy 84.693427 -370.867481) (xy 84.687664 -370.86032) (xy 84.66579 -370.834664) (xy 84.627704 -370.779027)
			(xy 84.596555 -370.719229) (xy 84.572793 -370.656131) (xy 84.55676 -370.590642) (xy 84.548686 -370.523703)
			(xy 81.27115 -370.523703) (xy 81.263075 -370.590641) (xy 81.24704 -370.656129) (xy 81.223276 -370.719226)
			(xy 81.192125 -370.779021) (xy 81.154036 -370.834655) (xy 81.132172 -370.86032) (xy 81.126381 -370.867469)
			(xy 81.119864 -370.884657) (xy 81.119472 -370.893848) (xy 81.119472 -371.386354) (xy 81.119911 -371.395538)
			(xy 81.126405 -371.412722) (xy 81.132172 -371.419882) (xy 81.154051 -371.445535) (xy 81.192141 -371.501171)
			(xy 81.223293 -371.560969) (xy 81.246928 -371.623725) (xy 82.349035 -371.623725) (xy 82.349038 -371.556418)
			(xy 82.357086 -371.489593) (xy 82.373062 -371.424209) (xy 82.396738 -371.361203) (xy 82.427775 -371.301478)
			(xy 82.465727 -371.24589) (xy 82.487516 -371.220238) (xy 82.493323 -371.2131) (xy 82.499831 -371.195904)
			(xy 82.500216 -371.18671) (xy 82.500216 -371.028722) (xy 82.500751 -371.018568) (xy 82.508514 -370.999804)
			(xy 82.522867 -370.985439) (xy 82.541625 -370.977659) (xy 82.551778 -370.97716) (xy 83.268058 -370.97716)
			(xy 83.27823 -370.977599) (xy 83.297028 -370.985374) (xy 83.311415 -370.999756) (xy 83.319197 -371.018551)
			(xy 83.31962 -371.028722) (xy 83.31962 -371.18671) (xy 83.320021 -371.195898) (xy 83.326541 -371.213083)
			(xy 83.33232 -371.220238) (xy 83.354072 -371.24592) (xy 83.392024 -371.301501) (xy 83.423061 -371.361221)
			(xy 83.446738 -371.424221) (xy 83.462715 -371.4896) (xy 83.470763 -371.55642) (xy 83.470766 -371.623723)
			(xy 83.462725 -371.690544) (xy 83.446755 -371.755924) (xy 83.423085 -371.818927) (xy 83.392054 -371.878649)
			(xy 83.354107 -371.934234) (xy 83.33232 -371.959886) (xy 83.326507 -371.96702) (xy 83.320001 -371.984219)
			(xy 83.31962 -371.993414) (xy 83.31962 -372.486682) (xy 83.320034 -372.495869) (xy 83.326545 -372.513054)
			(xy 83.33232 -372.52021) (xy 83.354142 -372.545834) (xy 83.392093 -372.601424) (xy 83.423127 -372.661151)
			(xy 83.446799 -372.724159) (xy 83.462771 -372.789545) (xy 83.470813 -372.856371) (xy 83.47081 -372.92368)
			(xy 83.462762 -372.990505) (xy 83.446784 -373.05589) (xy 83.423106 -373.118896) (xy 83.392066 -373.17862)
			(xy 83.354111 -373.234206) (xy 83.33232 -373.259858) (xy 83.326519 -373.267) (xy 83.320006 -373.284193)
			(xy 83.31962 -373.293386) (xy 83.31962 -373.451374) (xy 83.319214 -373.461549) (xy 83.311429 -373.480351)
			(xy 83.297038 -373.494738) (xy 83.278233 -373.502517) (xy 83.268058 -373.502936) (xy 82.551778 -373.502936)
			(xy 82.541602 -373.502553) (xy 82.522802 -373.494756) (xy 82.508417 -373.480358) (xy 82.500637 -373.461551)
			(xy 82.500216 -373.451374) (xy 82.500216 -373.293386) (xy 82.499809 -373.284199) (xy 82.493293 -373.267014)
			(xy 82.487516 -373.259858) (xy 82.465763 -373.234178) (xy 82.427814 -373.178595) (xy 82.396781 -373.118875)
			(xy 82.373107 -373.055874) (xy 82.357133 -372.990496) (xy 82.349086 -372.923677) (xy 82.349083 -372.856375)
			(xy 82.357123 -372.789555) (xy 82.373092 -372.724175) (xy 82.39676 -372.661172) (xy 82.427788 -372.601449)
			(xy 82.465731 -372.545863) (xy 82.487516 -372.52021) (xy 82.493335 -372.513081) (xy 82.499836 -372.495878)
			(xy 82.500216 -372.486682) (xy 82.500216 -371.993414) (xy 82.499795 -371.984228) (xy 82.493288 -371.967044)
			(xy 82.487516 -371.959886) (xy 82.465692 -371.934264) (xy 82.427745 -371.878673) (xy 82.396715 -371.818945)
			(xy 82.373045 -371.755936) (xy 82.357076 -371.690551) (xy 82.349035 -371.623725) (xy 81.246928 -371.623725)
			(xy 81.247057 -371.624067) (xy 81.263092 -371.689558) (xy 81.271168 -371.756498) (xy 81.271166 -371.823923)
			(xy 81.263089 -371.890863) (xy 81.247051 -371.956353) (xy 81.223284 -372.019451) (xy 81.19213 -372.079247)
			(xy 81.154038 -372.134881) (xy 81.132172 -372.160546) (xy 81.12637 -372.167687) (xy 81.119859 -372.184881)
			(xy 81.119472 -372.194074) (xy 81.119472 -372.351554) (xy 81.118936 -372.361676) (xy 81.111226 -372.380394)
			(xy 81.096954 -372.394752) (xy 81.078283 -372.402574) (xy 81.068164 -372.403116) (xy 80.351884 -372.403116)
			(xy 80.341776 -372.402628) (xy 80.323101 -372.394888) (xy 80.308807 -372.380592) (xy 80.30107 -372.361916)
			(xy 80.300576 -372.351808) (xy 80.300576 -372.194074) (xy 80.300184 -372.184885) (xy 80.293658 -372.1677)
			(xy 80.287876 -372.160546) (xy 80.266027 -372.134869) (xy 80.227939 -372.079236) (xy 80.196789 -372.019441)
			(xy 80.173025 -371.956346) (xy 80.156989 -371.890858) (xy 80.148913 -371.823922) (xy 80.148912 -371.756499)
			(xy 80.156986 -371.689563) (xy 80.173019 -371.624075) (xy 80.196781 -371.560978) (xy 80.227928 -371.501182)
			(xy 80.266014 -371.445548) (xy 80.287876 -371.419882) (xy 80.29366 -371.412728) (xy 80.300183 -371.395544)
			(xy 80.300576 -371.386354) (xy 80.300576 -370.893848) (xy 80.300148 -370.884663) (xy 80.293647 -370.867478)
			(xy 80.287876 -370.86032) (xy 80.266001 -370.834664) (xy 80.227914 -370.779028) (xy 80.196765 -370.71923)
			(xy 80.173003 -370.656132) (xy 80.156969 -370.590642) (xy 80.148895 -370.523703) (xy 76.870824 -370.523703)
			(xy 76.862788 -370.590464) (xy 76.846817 -370.655845) (xy 76.823147 -370.718849) (xy 76.792116 -370.778573)
			(xy 76.75417 -370.83416) (xy 76.732384 -370.859812) (xy 76.726598 -370.866965) (xy 76.720078 -370.88415)
			(xy 76.719684 -370.89334) (xy 76.719684 -371.386862) (xy 76.720116 -371.396047) (xy 76.726615 -371.413231)
			(xy 76.732384 -371.42039) (xy 76.754185 -371.446031) (xy 76.792132 -371.50162) (xy 76.823163 -371.561345)
			(xy 76.846621 -371.623785) (xy 77.948715 -371.623785) (xy 77.948719 -371.556358) (xy 77.956799 -371.489417)
			(xy 77.972839 -371.423925) (xy 77.996609 -371.360826) (xy 78.027766 -371.301029) (xy 78.065861 -371.245395)
			(xy 78.087728 -371.21973) (xy 78.09354 -371.212596) (xy 78.100045 -371.195397) (xy 78.100428 -371.186202)
			(xy 78.100428 -371.028722) (xy 78.100944 -371.018598) (xy 78.108662 -370.99988) (xy 78.12294 -370.985523)
			(xy 78.141615 -370.977701) (xy 78.151736 -370.97716) (xy 78.868016 -370.97716) (xy 78.878121 -370.977671)
			(xy 78.896792 -370.985407) (xy 78.911084 -370.999695) (xy 78.918826 -371.018363) (xy 78.919324 -371.028468)
			(xy 78.919324 -371.186202) (xy 78.919728 -371.19539) (xy 78.926245 -371.212575) (xy 78.932024 -371.21973)
			(xy 78.95385 -371.245426) (xy 78.991938 -371.301057) (xy 79.023089 -371.360849) (xy 79.046854 -371.423942)
			(xy 79.062892 -371.489427) (xy 79.07097 -371.556361) (xy 79.070974 -371.623782) (xy 79.062902 -371.690717)
			(xy 79.046871 -371.756203) (xy 79.023112 -371.819299) (xy 78.991967 -371.879094) (xy 78.953885 -371.934728)
			(xy 78.932024 -371.960394) (xy 78.92625 -371.967556) (xy 78.919721 -371.984733) (xy 78.919324 -371.993922)
			(xy 78.919324 -372.486174) (xy 78.919741 -372.495361) (xy 78.926249 -372.512545) (xy 78.932024 -372.519702)
			(xy 78.953921 -372.54534) (xy 78.992007 -372.600979) (xy 79.023155 -372.660779) (xy 79.046916 -372.72388)
			(xy 79.062948 -372.789372) (xy 79.071021 -372.856313) (xy 79.071018 -372.923738) (xy 79.062939 -372.990679)
			(xy 79.046901 -373.056169) (xy 79.023134 -373.119267) (xy 78.99198 -373.179065) (xy 78.953889 -373.2347)
			(xy 78.932024 -373.260366) (xy 78.92622 -373.267506) (xy 78.919709 -373.2847) (xy 78.919324 -373.293894)
			(xy 78.919324 -373.451374) (xy 78.918851 -373.461504) (xy 78.911125 -373.480231) (xy 78.896834 -373.49459)
			(xy 78.878143 -373.502403) (xy 78.868016 -373.502936) (xy 78.151736 -373.502936) (xy 78.14162 -373.502455)
			(xy 78.122924 -373.494726) (xy 78.10861 -373.480429) (xy 78.100857 -373.461743) (xy 78.100428 -373.451628)
			(xy 78.100428 -373.293894) (xy 78.100015 -373.284707) (xy 78.093503 -373.267523) (xy 78.087728 -373.260366)
			(xy 78.065896 -373.234674) (xy 78.027805 -373.179044) (xy 77.996651 -373.119251) (xy 77.972884 -373.056158)
			(xy 77.956845 -372.990672) (xy 77.948766 -372.923736) (xy 77.948763 -372.856315) (xy 77.956836 -372.789378)
			(xy 77.972869 -372.723891) (xy 77.99663 -372.660795) (xy 78.027779 -372.601) (xy 78.065865 -372.545367)
			(xy 78.087728 -372.519702) (xy 78.09351 -372.512547) (xy 78.100033 -372.495364) (xy 78.100428 -372.486174)
			(xy 78.100428 -371.993922) (xy 78.100001 -371.984737) (xy 78.093498 -371.967553) (xy 78.087728 -371.960394)
			(xy 78.065826 -371.93476) (xy 78.027736 -371.879122) (xy 77.996586 -371.819321) (xy 77.972822 -371.75622)
			(xy 77.956789 -371.690727) (xy 77.948715 -371.623785) (xy 76.846621 -371.623785) (xy 76.846834 -371.624351)
			(xy 76.862805 -371.689734) (xy 76.870848 -371.756558) (xy 76.870847 -371.823863) (xy 76.862802 -371.890687)
			(xy 76.846828 -371.956069) (xy 76.823155 -372.019074) (xy 76.792121 -372.078798) (xy 76.754172 -372.134386)
			(xy 76.732384 -372.160038) (xy 76.726587 -372.167183) (xy 76.720073 -372.184374) (xy 76.719684 -372.193566)
			(xy 76.719684 -372.351554) (xy 76.719199 -372.36172) (xy 76.711433 -372.380509) (xy 76.697067 -372.394895)
			(xy 76.678287 -372.402686) (xy 76.668122 -372.403116) (xy 75.951842 -372.403116) (xy 75.941667 -372.402701)
			(xy 75.922865 -372.394921) (xy 75.908477 -372.380532) (xy 75.900699 -372.361729) (xy 75.90028 -372.351554)
			(xy 75.90028 -372.193566) (xy 75.899891 -372.184377) (xy 75.893363 -372.167192) (xy 75.88758 -372.160038)
			(xy 75.865805 -372.134375) (xy 75.827853 -372.078791) (xy 75.796817 -372.019069) (xy 75.773141 -371.956066)
			(xy 75.757166 -371.890685) (xy 75.74912 -371.823863) (xy 75.749119 -371.756558) (xy 75.757162 -371.689736)
			(xy 75.773135 -371.624354) (xy 75.796808 -371.56135) (xy 75.827842 -371.501627) (xy 75.865792 -371.446042)
			(xy 75.88758 -371.42039) (xy 75.893361 -371.413234) (xy 75.899886 -371.396052) (xy 75.90028 -371.386862)
			(xy 75.90028 -370.89334) (xy 75.899855 -370.884154) (xy 75.893352 -370.866969) (xy 75.88758 -370.859812)
			(xy 75.865779 -370.83417) (xy 75.827828 -370.778583) (xy 75.796793 -370.718859) (xy 75.773119 -370.655853)
			(xy 75.757146 -370.590469) (xy 75.749102 -370.523644) (xy 72.471063 -370.523644) (xy 72.471063 -370.523702)
			(xy 72.462988 -370.59064) (xy 72.446953 -370.656129) (xy 72.42319 -370.719225) (xy 72.39204 -370.779021)
			(xy 72.353952 -370.834655) (xy 72.332088 -370.86032) (xy 72.326299 -370.867471) (xy 72.31978 -370.884657)
			(xy 72.319388 -370.893848) (xy 72.319388 -371.386354) (xy 72.319823 -371.395539) (xy 72.32632 -371.412723)
			(xy 72.332088 -371.419882) (xy 72.353966 -371.445536) (xy 72.392055 -371.501172) (xy 72.423206 -371.560969)
			(xy 72.446841 -371.623725) (xy 73.548947 -371.623725) (xy 73.548951 -371.556417) (xy 73.556998 -371.489592)
			(xy 73.572975 -371.424208) (xy 73.596652 -371.361202) (xy 73.627689 -371.301477) (xy 73.665642 -371.24589)
			(xy 73.687432 -371.220238) (xy 73.693242 -371.213102) (xy 73.699748 -371.195904) (xy 73.700132 -371.18671)
			(xy 73.700132 -371.028722) (xy 73.700582 -371.018553) (xy 73.708359 -370.99976) (xy 73.722736 -370.985374)
			(xy 73.741525 -370.977587) (xy 73.751694 -370.97716) (xy 74.467974 -370.97716) (xy 74.478147 -370.977586)
			(xy 74.496945 -370.985366) (xy 74.511331 -370.999752) (xy 74.519113 -371.018549) (xy 74.519536 -371.028722)
			(xy 74.519536 -371.18671) (xy 74.519956 -371.195896) (xy 74.526464 -371.21308) (xy 74.532236 -371.220238)
			(xy 74.553987 -371.245921) (xy 74.591939 -371.301502) (xy 74.622975 -371.361221) (xy 74.646651 -371.424222)
			(xy 74.662627 -371.489601) (xy 74.670675 -371.55642) (xy 74.670678 -371.623723) (xy 74.662638 -371.690543)
			(xy 74.646668 -371.755924) (xy 74.622998 -371.818926) (xy 74.591968 -371.878649) (xy 74.554022 -371.934234)
			(xy 74.532236 -371.959886) (xy 74.526413 -371.967012) (xy 74.519916 -371.984217) (xy 74.519536 -371.993414)
			(xy 74.519536 -372.486682) (xy 74.519969 -372.495866) (xy 74.526468 -372.51305) (xy 74.532236 -372.52021)
			(xy 74.554058 -372.545834) (xy 74.592008 -372.601424) (xy 74.623041 -372.661151) (xy 74.646713 -372.724159)
			(xy 74.662684 -372.789545) (xy 74.670726 -372.856371) (xy 74.670723 -372.92368) (xy 74.662675 -372.990505)
			(xy 74.646698 -373.055889) (xy 74.62302 -373.118896) (xy 74.591981 -373.17862) (xy 74.554027 -373.234206)
			(xy 74.532236 -373.259858) (xy 74.526425 -373.266992) (xy 74.519921 -373.284191) (xy 74.519536 -373.293386)
			(xy 74.519536 -373.451374) (xy 74.519114 -373.461547) (xy 74.511333 -373.480346) (xy 74.496946 -373.494733)
			(xy 74.478147 -373.502514) (xy 74.467974 -373.502936) (xy 73.751694 -373.502936) (xy 73.741519 -373.50254)
			(xy 73.722719 -373.494749) (xy 73.708333 -373.480354) (xy 73.700553 -373.461549) (xy 73.700132 -373.451374)
			(xy 73.700132 -373.293386) (xy 73.699722 -373.284199) (xy 73.693207 -373.267015) (xy 73.687432 -373.259858)
			(xy 73.665678 -373.234178) (xy 73.627729 -373.178595) (xy 73.596694 -373.118876) (xy 73.57302 -373.055875)
			(xy 73.557045 -372.990496) (xy 73.548998 -372.923677) (xy 73.548995 -372.856374) (xy 73.557036 -372.789554)
			(xy 73.573005 -372.724174) (xy 73.596674 -372.661171) (xy 73.627702 -372.601448) (xy 73.665647 -372.545862)
			(xy 73.687432 -372.52021) (xy 73.693253 -372.513083) (xy 73.699753 -372.495878) (xy 73.700132 -372.486682)
			(xy 73.700132 -371.993414) (xy 73.699708 -371.984228) (xy 73.693203 -371.967044) (xy 73.687432 -371.959886)
			(xy 73.665607 -371.934265) (xy 73.62766 -371.878674) (xy 73.596629 -371.818946) (xy 73.572958 -371.755937)
			(xy 73.556988 -371.690551) (xy 73.548947 -371.623725) (xy 72.446841 -371.623725) (xy 72.44697 -371.624068)
			(xy 72.463005 -371.689558) (xy 72.47108 -371.756498) (xy 72.471078 -371.823923) (xy 72.463001 -371.890862)
			(xy 72.446964 -371.956352) (xy 72.423197 -372.01945) (xy 72.392044 -372.079246) (xy 72.353953 -372.134881)
			(xy 72.332088 -372.160546) (xy 72.326288 -372.167689) (xy 72.319776 -372.184881) (xy 72.319388 -372.194074)
			(xy 72.319388 -372.351554) (xy 72.318836 -372.361674) (xy 72.311129 -372.380389) (xy 72.296863 -372.394746)
			(xy 72.278197 -372.402572) (xy 72.26808 -372.403116) (xy 71.5518 -372.403116) (xy 71.541648 -372.402679)
			(xy 71.522899 -372.394886) (xy 71.508576 -372.380494) (xy 71.500873 -372.361708) (xy 71.500492 -372.351554)
			(xy 71.500492 -372.194074) (xy 71.500096 -372.184885) (xy 71.493573 -372.167701) (xy 71.487792 -372.160546)
			(xy 71.465942 -372.134869) (xy 71.427853 -372.079236) (xy 71.396703 -372.019442) (xy 71.372938 -371.956346)
			(xy 71.356902 -371.890859) (xy 71.348825 -371.823922) (xy 71.348824 -371.756499) (xy 71.356898 -371.689562)
			(xy 71.372932 -371.624074) (xy 71.396694 -371.560978) (xy 71.427843 -371.501182) (xy 71.465929 -371.445547)
			(xy 71.487792 -371.419882) (xy 71.493578 -371.412729) (xy 71.500099 -371.395545) (xy 71.500492 -371.386354)
			(xy 71.500492 -370.893848) (xy 71.500061 -370.884663) (xy 71.493562 -370.867478) (xy 71.487792 -370.86032)
			(xy 71.465917 -370.834664) (xy 71.427829 -370.779028) (xy 71.396679 -370.719231) (xy 71.372916 -370.656133)
			(xy 71.356881 -370.590642) (xy 71.348807 -370.523703) (xy 58.103008 -370.523703) (xy 58.103008 -371.310662)
			(xy 58.102522 -371.337931) (xy 58.09476 -371.391915) (xy 58.079395 -371.444245) (xy 58.056738 -371.493855)
			(xy 58.027252 -371.539736) (xy 57.991537 -371.580953) (xy 57.95032 -371.616668) (xy 57.904439 -371.646154)
			(xy 57.854829 -371.668811) (xy 57.802499 -371.684176) (xy 57.748515 -371.691938) (xy 57.693977 -371.691938)
			(xy 57.639993 -371.684176) (xy 57.587663 -371.668811) (xy 57.538053 -371.646154) (xy 57.492172 -371.616668)
			(xy 57.450955 -371.580953) (xy 57.41524 -371.539736) (xy 57.385754 -371.493855) (xy 57.363097 -371.444245)
			(xy 57.347732 -371.391915) (xy 57.33997 -371.337931) (xy 57.339484 -371.310662) (xy 54.729888 -371.310662)
			(xy 54.729402 -371.337931) (xy 54.72164 -371.391915) (xy 54.706275 -371.444245) (xy 54.683618 -371.493855)
			(xy 54.654132 -371.539736) (xy 54.618417 -371.580953) (xy 54.5772 -371.616668) (xy 54.531319 -371.646154)
			(xy 54.481709 -371.668811) (xy 54.429379 -371.684176) (xy 54.375395 -371.691938) (xy 54.320857 -371.691938)
			(xy 54.266873 -371.684176) (xy 54.214543 -371.668811) (xy 54.164933 -371.646154) (xy 54.119052 -371.616668)
			(xy 54.077835 -371.580953) (xy 54.04212 -371.539736) (xy 54.012634 -371.493855) (xy 53.989977 -371.444245)
			(xy 53.974612 -371.391915) (xy 53.96685 -371.337931) (xy 53.966364 -371.310662) (xy 48.196948 -371.310662)
			(xy 48.223223 -371.361224) (xy 48.246896 -371.424224) (xy 48.262871 -371.489602) (xy 48.270918 -371.556421)
			(xy 48.270921 -371.623722) (xy 48.262881 -371.690542) (xy 48.246913 -371.755921) (xy 48.223246 -371.818924)
			(xy 48.192219 -371.878647) (xy 48.154277 -371.934234) (xy 48.132492 -371.959886) (xy 48.126675 -371.967017)
			(xy 48.120173 -371.984218) (xy 48.119792 -371.993414) (xy 48.119792 -372.486682) (xy 48.120213 -372.495868)
			(xy 48.126719 -372.513052) (xy 48.132492 -372.52021) (xy 48.154312 -372.545835) (xy 48.192258 -372.601426)
			(xy 48.223288 -372.661154) (xy 48.246958 -372.724162) (xy 48.262927 -372.789547) (xy 48.270968 -372.856372)
			(xy 48.270965 -372.923679) (xy 48.262918 -372.990504) (xy 48.246942 -373.055887) (xy 48.223267 -373.118893)
			(xy 48.192232 -373.178618) (xy 48.154281 -373.234205) (xy 48.132492 -373.259858) (xy 48.126687 -373.266997)
			(xy 48.120178 -373.284192) (xy 48.119792 -373.293386) (xy 48.119792 -373.451374) (xy 48.119246 -373.461526)
			(xy 48.111486 -373.480289) (xy 48.097136 -373.494655) (xy 48.078382 -373.502435) (xy 48.06823 -373.502936)
			(xy 47.35195 -373.502936) (xy 47.341778 -373.502495) (xy 47.32298 -373.494721) (xy 47.308592 -373.48034)
			(xy 47.30081 -373.461545) (xy 47.300388 -373.451374) (xy 47.300388 -373.293386) (xy 47.299987 -373.284198)
			(xy 47.293467 -373.267013) (xy 47.287688 -373.259858) (xy 47.265932 -373.234179) (xy 47.227979 -373.178598)
			(xy 47.196942 -373.118878) (xy 47.173265 -373.055877) (xy 47.157288 -372.990498) (xy 47.14924 -372.923677)
			(xy 47.149237 -372.856374) (xy 47.157279 -372.789553) (xy 47.17325 -372.724172) (xy 47.196921 -372.661169)
			(xy 47.227953 -372.601446) (xy 47.265901 -372.545861) (xy 47.287688 -372.52021) (xy 47.293504 -372.513078)
			(xy 47.300007 -372.495878) (xy 47.300388 -372.486682) (xy 47.300388 -371.993414) (xy 47.299974 -371.984227)
			(xy 47.293463 -371.967043) (xy 47.287688 -371.959886) (xy 47.265861 -371.934265) (xy 47.227911 -371.878675)
			(xy 47.196876 -371.818948) (xy 47.173204 -371.755939) (xy 47.157232 -371.690553) (xy 47.14919 -371.623726)
			(xy 46.046568 -371.623726) (xy 46.046802 -371.624349) (xy 46.062775 -371.689733) (xy 46.070818 -371.756557)
			(xy 46.070817 -371.823864) (xy 46.062771 -371.890688) (xy 46.046796 -371.956071) (xy 46.023121 -372.019076)
			(xy 45.992085 -372.0788) (xy 45.954133 -372.134386) (xy 45.932344 -372.160038) (xy 45.926542 -372.167179)
			(xy 45.920032 -372.184373) (xy 45.919644 -372.193566) (xy 45.919644 -372.351554) (xy 45.919198 -372.361725)
			(xy 45.911425 -372.380522) (xy 45.897046 -372.394909) (xy 45.878253 -372.402693) (xy 45.868082 -372.403116)
			(xy 45.151802 -372.403116) (xy 45.141625 -372.402733) (xy 45.122821 -372.394941) (xy 45.108435 -372.380542)
			(xy 45.100658 -372.361732) (xy 45.10024 -372.351554) (xy 45.10024 -372.193566) (xy 45.099837 -372.184378)
			(xy 45.093317 -372.167194) (xy 45.08754 -372.160038) (xy 45.065766 -372.134374) (xy 45.027817 -372.07879)
			(xy 44.996783 -372.019068) (xy 44.973109 -371.956065) (xy 44.957135 -371.890684) (xy 44.94909 -371.823862)
			(xy 44.949089 -371.756559) (xy 44.957132 -371.689737) (xy 44.973103 -371.624356) (xy 44.996774 -371.561352)
			(xy 45.027806 -371.501628) (xy 45.065753 -371.446042) (xy 45.08754 -371.42039) (xy 45.093328 -371.413239)
			(xy 45.099847 -371.396053) (xy 45.10024 -371.386862) (xy 45.10024 -370.89334) (xy 45.099801 -370.884156)
			(xy 45.093306 -370.866972) (xy 45.08754 -370.859812) (xy 45.06574 -370.83417) (xy 45.027792 -370.778582)
			(xy 44.996759 -370.718857) (xy 44.973087 -370.655851) (xy 44.957115 -370.590468) (xy 44.949071 -370.523644)
			(xy 41.671032 -370.523644) (xy 41.671032 -370.523703) (xy 41.662957 -370.590641) (xy 41.646921 -370.65613)
			(xy 41.623156 -370.719227) (xy 41.592004 -370.779022) (xy 41.553913 -370.834656) (xy 41.532048 -370.86032)
			(xy 41.526254 -370.867467) (xy 41.519739 -370.884656) (xy 41.519348 -370.893848) (xy 41.519348 -371.386354)
			(xy 41.519792 -371.395537) (xy 41.526284 -371.412721) (xy 41.532048 -371.419882) (xy 41.553928 -371.445535)
			(xy 41.592019 -371.50117) (xy 41.623172 -371.560967) (xy 41.646832 -371.623785) (xy 42.748894 -371.623785)
			(xy 42.748898 -371.556358) (xy 42.756977 -371.489417) (xy 42.773017 -371.423926) (xy 42.796785 -371.360828)
			(xy 42.827941 -371.30103) (xy 42.866034 -371.245395) (xy 42.8879 -371.21973) (xy 42.893709 -371.212593)
			(xy 42.900216 -371.195396) (xy 42.9006 -371.186202) (xy 42.9006 -371.028722) (xy 42.901143 -371.018602)
			(xy 42.908856 -370.999888) (xy 42.923125 -370.985533) (xy 42.941791 -370.977706) (xy 42.951908 -370.97716)
			(xy 43.668188 -370.97716) (xy 43.678336 -370.977631) (xy 43.697081 -370.985415) (xy 43.711403 -370.999796)
			(xy 43.71911 -371.018572) (xy 43.719496 -371.028722) (xy 43.719496 -371.186202) (xy 43.719906 -371.195389)
			(xy 43.72642 -371.212573) (xy 43.732196 -371.21973) (xy 43.754023 -371.245426) (xy 43.792113 -371.301056)
			(xy 43.823265 -371.360848) (xy 43.847032 -371.423941) (xy 43.86307 -371.489426) (xy 43.871149 -371.556361)
			(xy 43.871153 -371.623782) (xy 43.86308 -371.690718) (xy 43.847049 -371.756205) (xy 43.823289 -371.8193)
			(xy 43.792142 -371.879095) (xy 43.754058 -371.934729) (xy 43.732196 -371.960394) (xy 43.726419 -371.967553)
			(xy 43.719893 -371.984733) (xy 43.719496 -371.993922) (xy 43.719496 -372.486174) (xy 43.71992 -372.49536)
			(xy 43.726424 -372.512544) (xy 43.732196 -372.519702) (xy 43.754094 -372.54534) (xy 43.792181 -372.600978)
			(xy 43.823331 -372.660778) (xy 43.847093 -372.723878) (xy 43.863127 -372.789371) (xy 43.8712 -372.856312)
			(xy 43.871197 -372.923739) (xy 43.863117 -372.990679) (xy 43.847078 -373.05617) (xy 43.82331 -373.119269)
			(xy 43.792155 -373.179066) (xy 43.754062 -373.234701) (xy 43.732196 -373.260366) (xy 43.726388 -373.267503)
			(xy 43.71988 -373.2847) (xy 43.719496 -373.293894) (xy 43.719496 -373.451374) (xy 43.718953 -373.461495)
			(xy 43.711241 -373.480208) (xy 43.696972 -373.494564) (xy 43.678306 -373.502391) (xy 43.668188 -373.502936)
			(xy 42.951908 -373.502936) (xy 42.941759 -373.502473) (xy 42.923014 -373.494686) (xy 42.908691 -373.480303)
			(xy 42.900985 -373.461525) (xy 42.9006 -373.451374) (xy 42.9006 -373.293894) (xy 42.900193 -373.284707)
			(xy 42.893677 -373.267522) (xy 42.8879 -373.260366) (xy 42.866069 -373.234673) (xy 42.82798 -373.179043)
			(xy 42.796828 -373.11925) (xy 42.773061 -373.056157) (xy 42.757024 -372.990671) (xy 42.748945 -372.923736)
			(xy 42.748942 -372.856315) (xy 42.757014 -372.789379) (xy 42.773046 -372.723892) (xy 42.796807 -372.660796)
			(xy 42.827953 -372.601001) (xy 42.866038 -372.545367) (xy 42.8879 -372.519702) (xy 42.893678 -372.512544)
			(xy 42.900204 -372.495363) (xy 42.9006 -372.486174) (xy 42.9006 -371.993922) (xy 42.900179 -371.984736)
			(xy 42.893673 -371.967551) (xy 42.8879 -371.960394) (xy 42.865999 -371.93476) (xy 42.827911 -371.879121)
			(xy 42.796762 -371.81932) (xy 42.773 -371.756219) (xy 42.756967 -371.690726) (xy 42.748894 -371.623785)
			(xy 41.646832 -371.623785) (xy 41.646938 -371.624066) (xy 41.662974 -371.689557) (xy 41.67105 -371.756498)
			(xy 41.671048 -371.823923) (xy 41.66297 -371.890864) (xy 41.646932 -371.956354) (xy 41.623164 -372.019452)
			(xy 41.592008 -372.079248) (xy 41.553915 -372.134882) (xy 41.532048 -372.160546) (xy 41.526243 -372.167685)
			(xy 41.519735 -372.18488) (xy 41.519348 -372.194074) (xy 41.519348 -372.351554) (xy 41.518835 -372.361679)
			(xy 41.51112 -372.380402) (xy 41.496842 -372.39476) (xy 41.478162 -372.402579) (xy 41.46804 -372.403116)
			(xy 40.75176 -372.403116) (xy 40.741605 -372.402711) (xy 40.722855 -372.394906) (xy 40.708534 -372.380504)
			(xy 40.700833 -372.361711) (xy 40.700452 -372.351554) (xy 40.700452 -372.194074) (xy 40.700043 -372.184887)
			(xy 40.693527 -372.167703) (xy 40.687752 -372.160546) (xy 40.6659 -372.13487) (xy 40.627807 -372.079238)
			(xy 40.596653 -372.019444) (xy 40.572886 -371.956349) (xy 40.556848 -371.89086) (xy 40.54877 -371.823922)
			(xy 40.548769 -371.756499) (xy 40.556844 -371.68956) (xy 40.57288 -371.624072) (xy 40.596645 -371.560975)
			(xy 40.627797 -371.50118) (xy 40.665887 -371.445546) (xy 40.687752 -371.419882) (xy 40.693545 -371.412735)
			(xy 40.70006 -371.395546) (xy 40.700452 -371.386354) (xy 40.700452 -370.893848) (xy 40.700007 -370.884665)
			(xy 40.693516 -370.867481) (xy 40.687752 -370.86032) (xy 40.665874 -370.834665) (xy 40.627783 -370.779031)
			(xy 40.59663 -370.719233) (xy 40.572864 -370.656135) (xy 40.556828 -370.590644) (xy 40.548752 -370.523704)
			(xy 37.271241 -370.523704) (xy 37.263166 -370.590641) (xy 37.247131 -370.65613) (xy 37.223366 -370.719226)
			(xy 37.192215 -370.779022) (xy 37.154125 -370.834655) (xy 37.13226 -370.86032) (xy 37.126467 -370.867468)
			(xy 37.119951 -370.884656) (xy 37.11956 -370.893848) (xy 37.11956 -371.386354) (xy 37.120001 -371.395538)
			(xy 37.126494 -371.412722) (xy 37.13226 -371.419882) (xy 37.154139 -371.445535) (xy 37.19223 -371.501171)
			(xy 37.223382 -371.560968) (xy 37.247019 -371.623725) (xy 38.349126 -371.623725) (xy 38.349129 -371.556418)
			(xy 38.357177 -371.489593) (xy 38.373153 -371.424209) (xy 38.396828 -371.361203) (xy 38.427864 -371.301478)
			(xy 38.465815 -371.245891) (xy 38.487604 -371.220238) (xy 38.49341 -371.213099) (xy 38.499919 -371.195904)
			(xy 38.500304 -371.18671) (xy 38.500304 -371.028722) (xy 38.50085 -371.01857) (xy 38.508611 -370.999808)
			(xy 38.522961 -370.985443) (xy 38.541714 -370.977661) (xy 38.551866 -370.97716) (xy 39.268146 -370.97716)
			(xy 39.278309 -370.977596) (xy 39.297084 -370.98539) (xy 39.311448 -370.999773) (xy 39.319217 -371.018558)
			(xy 39.319708 -371.028722) (xy 39.319708 -371.18671) (xy 39.320112 -371.195898) (xy 39.32663 -371.213082)
			(xy 39.332408 -371.220238) (xy 39.35416 -371.24592) (xy 39.392113 -371.301501) (xy 39.423151 -371.36122)
			(xy 39.446829 -371.424221) (xy 39.462806 -371.4896) (xy 39.470854 -371.55642) (xy 39.470857 -371.623723)
			(xy 39.462816 -371.690544) (xy 39.446845 -371.755925) (xy 39.423175 -371.818928) (xy 39.392143 -371.87865)
			(xy 39.354195 -371.934235) (xy 39.332408 -371.959886) (xy 39.326593 -371.967018) (xy 39.320089 -371.984219)
			(xy 39.319708 -371.993414) (xy 39.319708 -372.486682) (xy 39.320125 -372.495868) (xy 39.326634 -372.513053)
			(xy 39.332408 -372.52021) (xy 39.354231 -372.545834) (xy 39.392182 -372.601423) (xy 39.423217 -372.66115)
			(xy 39.44689 -372.724158) (xy 39.462862 -372.789545) (xy 39.470904 -372.856371) (xy 39.470901 -372.92368)
			(xy 39.462853 -372.990506) (xy 39.446875 -373.05589) (xy 39.423196 -373.118897) (xy 39.392156 -373.178621)
			(xy 39.354199 -373.234207) (xy 39.332408 -373.259858) (xy 39.326605 -373.266999) (xy 39.320094 -373.284193)
			(xy 39.319708 -373.293386) (xy 39.319708 -373.451374) (xy 39.319147 -373.461525) (xy 39.311389 -373.480284)
			(xy 39.297045 -373.494649) (xy 39.278296 -373.502432) (xy 39.268146 -373.502936) (xy 38.551866 -373.502936)
			(xy 38.541703 -373.502494) (xy 38.522928 -373.494703) (xy 38.508563 -373.480322) (xy 38.500794 -373.461538)
			(xy 38.500304 -373.451374) (xy 38.500304 -373.293386) (xy 38.4999 -373.284198) (xy 38.493382 -373.267014)
			(xy 38.487604 -373.259858) (xy 38.465851 -373.234178) (xy 38.427903 -373.178595) (xy 38.39687 -373.118875)
			(xy 38.373197 -373.055874) (xy 38.357223 -372.990495) (xy 38.349177 -372.923676) (xy 38.349174 -372.856375)
			(xy 38.357214 -372.789555) (xy 38.373182 -372.724175) (xy 38.396849 -372.661172) (xy 38.427877 -372.601449)
			(xy 38.465819 -372.545863) (xy 38.487604 -372.52021) (xy 38.493422 -372.51308) (xy 38.499924 -372.495878)
			(xy 38.500304 -372.486682) (xy 38.500304 -371.993414) (xy 38.499886 -371.984228) (xy 38.493378 -371.967043)
			(xy 38.487604 -371.959886) (xy 38.46578 -371.934264) (xy 38.427835 -371.878672) (xy 38.396805 -371.818944)
			(xy 38.373136 -371.755936) (xy 38.357167 -371.69055) (xy 38.349126 -371.623725) (xy 37.247019 -371.623725)
			(xy 37.247148 -371.624067) (xy 37.263183 -371.689557) (xy 37.271259 -371.756498) (xy 37.271257 -371.823923)
			(xy 37.263179 -371.890863) (xy 37.247141 -371.956354) (xy 37.223374 -372.019451) (xy 37.192219 -372.079248)
			(xy 37.154126 -372.134881) (xy 37.13226 -372.160546) (xy 37.126456 -372.167686) (xy 37.119947 -372.184881)
			(xy 37.11956 -372.194074) (xy 37.11956 -372.351554) (xy 37.119036 -372.361678) (xy 37.111323 -372.380398)
			(xy 37.097048 -372.394756) (xy 37.078373 -372.402576) (xy 37.068252 -372.403116) (xy 36.351972 -372.403116)
			(xy 36.341818 -372.402702) (xy 36.323068 -372.3949) (xy 36.308746 -372.380501) (xy 36.301045 -372.36171)
			(xy 36.300664 -372.351554) (xy 36.300664 -372.194074) (xy 36.300252 -372.184887) (xy 36.293738 -372.167704)
			(xy 36.287964 -372.160546) (xy 36.266115 -372.134869) (xy 36.228028 -372.079235) (xy 36.196879 -372.01944)
			(xy 36.173116 -371.956345) (xy 36.15708 -371.890858) (xy 36.149004 -371.823921) (xy 36.149003 -371.7565)
			(xy 36.157076 -371.689563) (xy 36.173109 -371.624075) (xy 36.19687 -371.560979) (xy 36.228017 -371.501183)
			(xy 36.266102 -371.445548) (xy 36.287964 -371.419882) (xy 36.293759 -371.412736) (xy 36.300273 -371.395546)
			(xy 36.300664 -371.386354) (xy 36.300664 -370.893848) (xy 36.300217 -370.884665) (xy 36.293727 -370.867481)
			(xy 36.287964 -370.86032) (xy 36.26609 -370.834664) (xy 36.228004 -370.779027) (xy 36.196855 -370.719229)
			(xy 36.173093 -370.656131) (xy 36.15706 -370.590642) (xy 36.148986 -370.523703) (xy 32.870915 -370.523703)
			(xy 32.862879 -370.590465) (xy 32.846908 -370.655846) (xy 32.823237 -370.71885) (xy 32.792205 -370.778573)
			(xy 32.754259 -370.83416) (xy 32.732472 -370.859812) (xy 32.726684 -370.866963) (xy 32.720165 -370.884149)
			(xy 32.719772 -370.89334) (xy 32.719772 -371.386862) (xy 32.720207 -371.396046) (xy 32.726704 -371.413231)
			(xy 32.732472 -371.42039) (xy 32.754273 -371.446031) (xy 32.792221 -371.501619) (xy 32.823253 -371.561344)
			(xy 32.846713 -371.623785) (xy 33.948806 -371.623785) (xy 33.94881 -371.556358) (xy 33.95689 -371.489417)
			(xy 33.97293 -371.423925) (xy 33.996699 -371.360827) (xy 34.027855 -371.30103) (xy 34.065949 -371.245395)
			(xy 34.087816 -371.21973) (xy 34.093627 -371.212595) (xy 34.100132 -371.195397) (xy 34.100516 -371.186202)
			(xy 34.100516 -371.028722) (xy 34.101044 -371.0186) (xy 34.10876 -370.999883) (xy 34.123033 -370.985527)
			(xy 34.141705 -370.977703) (xy 34.151824 -370.97716) (xy 34.868104 -370.97716) (xy 34.878253 -370.977618)
			(xy 34.896998 -370.985407) (xy 34.91132 -370.999792) (xy 34.919027 -371.018571) (xy 34.919412 -371.028722)
			(xy 34.919412 -371.186202) (xy 34.919819 -371.19539) (xy 34.926334 -371.212574) (xy 34.932112 -371.21973)
			(xy 34.953938 -371.245426) (xy 34.992027 -371.301057) (xy 35.023179 -371.360849) (xy 35.046945 -371.423941)
			(xy 35.062982 -371.489427) (xy 35.071061 -371.556361) (xy 35.071065 -371.623782) (xy 35.062993 -371.690717)
			(xy 35.046962 -371.756204) (xy 35.023202 -371.819299) (xy 34.992057 -371.879094) (xy 34.953973 -371.934729)
			(xy 34.932112 -371.960394) (xy 34.926337 -371.967555) (xy 34.919809 -371.984733) (xy 34.919412 -371.993922)
			(xy 34.919412 -372.486174) (xy 34.919832 -372.49536) (xy 34.926338 -372.512545) (xy 34.932112 -372.519702)
			(xy 34.954009 -372.54534) (xy 34.992096 -372.600979) (xy 35.023244 -372.660779) (xy 35.047006 -372.723879)
			(xy 35.063039 -372.789371) (xy 35.071112 -372.856312) (xy 35.071109 -372.923739) (xy 35.06303 -372.990679)
			(xy 35.046991 -373.05617) (xy 35.023224 -373.119268) (xy 34.99207 -373.179065) (xy 34.953978 -373.234701)
			(xy 34.932112 -373.260366) (xy 34.926306 -373.267505) (xy 34.919797 -373.2847) (xy 34.919412 -373.293894)
			(xy 34.919412 -373.451374) (xy 34.918854 -373.461493) (xy 34.911144 -373.480203) (xy 34.89688 -373.494559)
			(xy 34.878219 -373.502388) (xy 34.868104 -373.502936) (xy 34.151824 -373.502936) (xy 34.141676 -373.50246)
			(xy 34.122931 -373.494679) (xy 34.108608 -373.480299) (xy 34.100901 -373.461524) (xy 34.100516 -373.451374)
			(xy 34.100516 -373.293894) (xy 34.100105 -373.284707) (xy 34.093592 -373.267523) (xy 34.087816 -373.260366)
			(xy 34.065985 -373.234673) (xy 34.027894 -373.179043) (xy 33.996741 -373.119251) (xy 33.972974 -373.056158)
			(xy 33.956936 -372.990672) (xy 33.948857 -372.923736) (xy 33.948854 -372.856315) (xy 33.956927 -372.789379)
			(xy 33.972959 -372.723891) (xy 33.99672 -372.660796) (xy 34.027868 -372.601001) (xy 34.065953 -372.545367)
			(xy 34.087816 -372.519702) (xy 34.093596 -372.512545) (xy 34.10012 -372.495364) (xy 34.100516 -372.486174)
			(xy 34.100516 -371.993922) (xy 34.100092 -371.984736) (xy 34.093587 -371.967552) (xy 34.087816 -371.960394)
			(xy 34.065914 -371.93476) (xy 34.027826 -371.879121) (xy 33.996676 -371.819321) (xy 33.972913 -371.75622)
			(xy 33.956879 -371.690727) (xy 33.948806 -371.623785) (xy 32.846713 -371.623785) (xy 32.846925 -371.62435)
			(xy 32.862896 -371.689734) (xy 32.870939 -371.756558) (xy 32.870938 -371.823864) (xy 32.862892 -371.890687)
			(xy 32.846918 -371.95607) (xy 32.823244 -372.019075) (xy 32.79221 -372.078799) (xy 32.75426 -372.134386)
			(xy 32.732472 -372.160038) (xy 32.726673 -372.167181) (xy 32.72016 -372.184373) (xy 32.719772 -372.193566)
			(xy 32.719772 -372.351554) (xy 32.719299 -372.361721) (xy 32.711531 -372.380513) (xy 32.69716 -372.394899)
			(xy 32.678377 -372.402688) (xy 32.66821 -372.403116) (xy 31.95193 -372.403116) (xy 31.941755 -372.40271)
			(xy 31.922952 -372.394927) (xy 31.908564 -372.380535) (xy 31.900787 -372.361729) (xy 31.900368 -372.351554)
			(xy 31.900368 -372.193566) (xy 31.899959 -372.184379) (xy 31.893443 -372.167195) (xy 31.887668 -372.160038)
			(xy 31.865893 -372.134375) (xy 31.827942 -372.078791) (xy 31.796907 -372.019069) (xy 31.773232 -371.956066)
			(xy 31.757257 -371.890685) (xy 31.749211 -371.823863) (xy 31.74921 -371.756558) (xy 31.757253 -371.689736)
			(xy 31.773226 -371.624354) (xy 31.796898 -371.56135) (xy 31.827931 -371.501627) (xy 31.86588 -371.446042)
			(xy 31.887668 -371.42039) (xy 31.89346 -371.413242) (xy 31.899975 -371.396053) (xy 31.900368 -371.386862)
			(xy 31.900368 -370.89334) (xy 31.899923 -370.884157) (xy 31.893432 -370.866973) (xy 31.887668 -370.859812)
			(xy 31.865868 -370.83417) (xy 31.827917 -370.778583) (xy 31.796883 -370.718858) (xy 31.77321 -370.655852)
			(xy 31.757237 -370.590468) (xy 31.749193 -370.523644) (xy 28.471153 -370.523644) (xy 28.471153 -370.523703)
			(xy 28.463078 -370.59064) (xy 28.447043 -370.656129) (xy 28.42328 -370.719226) (xy 28.392129 -370.779021)
			(xy 28.35404 -370.834655) (xy 28.332176 -370.86032) (xy 28.326386 -370.867469) (xy 28.319868 -370.884657)
			(xy 28.319476 -370.893848) (xy 28.319476 -371.386354) (xy 28.319914 -371.395538) (xy 28.326409 -371.412722)
			(xy 28.332176 -371.419882) (xy 28.354055 -371.445535) (xy 28.392144 -371.501171) (xy 28.423296 -371.560969)
			(xy 28.446931 -371.623725) (xy 29.549038 -371.623725) (xy 29.549042 -371.556418) (xy 29.557089 -371.489593)
			(xy 29.573066 -371.424209) (xy 29.596742 -371.361203) (xy 29.627778 -371.301478) (xy 29.665731 -371.24589)
			(xy 29.68752 -371.220238) (xy 29.693328 -371.213101) (xy 29.699835 -371.195904) (xy 29.70022 -371.18671)
			(xy 29.70022 -371.028722) (xy 29.700682 -371.018554) (xy 29.708456 -370.999763) (xy 29.72283 -370.985378)
			(xy 29.741614 -370.97759) (xy 29.751782 -370.97716) (xy 30.468062 -370.97716) (xy 30.478234 -370.977596)
			(xy 30.497032 -370.985372) (xy 30.511419 -370.999755) (xy 30.519201 -371.01855) (xy 30.519624 -371.028722)
			(xy 30.519624 -371.18671) (xy 30.520024 -371.195898) (xy 30.526544 -371.213083) (xy 30.532324 -371.220238)
			(xy 30.554075 -371.24592) (xy 30.592028 -371.301502) (xy 30.623065 -371.361221) (xy 30.646741 -371.424221)
			(xy 30.662718 -371.4896) (xy 30.670766 -371.55642) (xy 30.670769 -371.623723) (xy 30.662728 -371.690543)
			(xy 30.646758 -371.755924) (xy 30.623088 -371.818927) (xy 30.592057 -371.878649) (xy 30.554111 -371.934234)
			(xy 30.532324 -371.959886) (xy 30.526511 -371.96702) (xy 30.520005 -371.984219) (xy 30.519624 -371.993414)
			(xy 30.519624 -372.486682) (xy 30.520037 -372.495869) (xy 30.526548 -372.513054) (xy 30.532324 -372.52021)
			(xy 30.554146 -372.545834) (xy 30.592096 -372.601424) (xy 30.62313 -372.661151) (xy 30.646803 -372.724159)
			(xy 30.662774 -372.789545) (xy 30.670816 -372.856371) (xy 30.670813 -372.92368) (xy 30.662765 -372.990505)
			(xy 30.646788 -373.05589) (xy 30.623109 -373.118896) (xy 30.59207 -373.17862) (xy 30.554115 -373.234206)
			(xy 30.532324 -373.259858) (xy 30.526523 -373.267) (xy 30.52001 -373.284193) (xy 30.519624 -373.293386)
			(xy 30.519624 -373.451374) (xy 30.519214 -373.461549) (xy 30.51143 -373.48035) (xy 30.49704 -373.494737)
			(xy 30.478237 -373.502516) (xy 30.468062 -373.502936) (xy 29.751782 -373.502936) (xy 29.741606 -373.50255)
			(xy 29.722806 -373.494754) (xy 29.708421 -373.480357) (xy 29.700641 -373.46155) (xy 29.70022 -373.451374)
			(xy 29.70022 -373.293386) (xy 29.699812 -373.284199) (xy 29.693297 -373.267015) (xy 29.68752 -373.259858)
			(xy 29.665767 -373.234178) (xy 29.627818 -373.178595) (xy 29.596784 -373.118875) (xy 29.57311 -373.055874)
			(xy 29.557136 -372.990496) (xy 29.549089 -372.923677) (xy 29.549086 -372.856375) (xy 29.557127 -372.789555)
			(xy 29.573095 -372.724175) (xy 29.596763 -372.661172) (xy 29.627792 -372.601449) (xy 29.665735 -372.545863)
			(xy 29.68752 -372.52021) (xy 29.69334 -372.513081) (xy 29.69984 -372.495878) (xy 29.70022 -372.486682)
			(xy 29.70022 -371.993414) (xy 29.699798 -371.984228) (xy 29.693292 -371.967044) (xy 29.68752 -371.959886)
			(xy 29.665695 -371.934264) (xy 29.627749 -371.878673) (xy 29.596718 -371.818945) (xy 29.573049 -371.755937)
			(xy 29.557079 -371.690551) (xy 29.549038 -371.623725) (xy 28.446931 -371.623725) (xy 28.44706 -371.624067)
			(xy 28.463096 -371.689558) (xy 28.471171 -371.756498) (xy 28.471169 -371.823923) (xy 28.463092 -371.890863)
			(xy 28.447054 -371.956353) (xy 28.423287 -372.01945) (xy 28.392134 -372.079247) (xy 28.354042 -372.134881)
			(xy 28.332176 -372.160546) (xy 28.326375 -372.167688) (xy 28.319864 -372.184881) (xy 28.319476 -372.194074)
			(xy 28.319476 -372.351554) (xy 28.318936 -372.361676) (xy 28.311226 -372.380393) (xy 28.296956 -372.39475)
			(xy 28.278287 -372.402574) (xy 28.268168 -372.403116) (xy 27.551888 -372.403116) (xy 27.541781 -372.402625)
			(xy 27.523105 -372.394886) (xy 27.508811 -372.380591) (xy 27.501074 -372.361916) (xy 27.50058 -372.351808)
			(xy 27.50058 -372.194074) (xy 27.500187 -372.184885) (xy 27.493662 -372.167701) (xy 27.48788 -372.160546)
			(xy 27.46603 -372.134869) (xy 27.427943 -372.079236) (xy 27.396792 -372.019441) (xy 27.373028 -371.956346)
			(xy 27.356993 -371.890858) (xy 27.348916 -371.823922) (xy 27.348915 -371.756499) (xy 27.356989 -371.689562)
			(xy 27.373022 -371.624074) (xy 27.396784 -371.560978) (xy 27.427932 -371.501182) (xy 27.466018 -371.445548)
			(xy 27.48788 -371.419882) (xy 27.493664 -371.412728) (xy 27.500187 -371.395544) (xy 27.50058 -371.386354)
			(xy 27.50058 -370.893848) (xy 27.500151 -370.884663) (xy 27.493651 -370.867478) (xy 27.48788 -370.86032)
			(xy 27.466005 -370.834664) (xy 27.427918 -370.779028) (xy 27.396769 -370.71923) (xy 27.373006 -370.656132)
			(xy 27.356972 -370.590642) (xy 27.348898 -370.523703) (xy 0.509016 -370.523703) (xy 0.509016 -372.100847)
			(xy 8.642336 -372.100847) (xy 8.642336 -372.040913) (xy 8.650159 -371.981491) (xy 8.665671 -371.923598)
			(xy 8.688607 -371.868226) (xy 8.718575 -371.81632) (xy 8.755061 -371.768771) (xy 8.797441 -371.726391)
			(xy 8.84499 -371.689905) (xy 8.896896 -371.659937) (xy 8.952268 -371.637001) (xy 9.010161 -371.621489)
			(xy 9.069583 -371.613666) (xy 9.09955 -371.613176) (xy 9.96315 -371.613176) (xy 9.993118 -371.613658)
			(xy 10.052541 -371.621481) (xy 10.110435 -371.636994) (xy 10.165808 -371.65993) (xy 10.217714 -371.689898)
			(xy 10.265264 -371.726385) (xy 10.307645 -371.768766) (xy 10.344132 -371.816316) (xy 10.3741 -371.868222)
			(xy 10.397036 -371.923595) (xy 10.412549 -371.981489) (xy 10.420372 -372.040912) (xy 10.420372 -372.100848)
			(xy 10.412549 -372.160271) (xy 10.397036 -372.218165) (xy 10.3741 -372.273538) (xy 10.344132 -372.325444)
			(xy 10.307645 -372.372994) (xy 10.265264 -372.415375) (xy 10.217714 -372.451862) (xy 10.165808 -372.48183)
			(xy 10.110435 -372.504766) (xy 10.052541 -372.520279) (xy 9.993118 -372.528102) (xy 9.96315 -372.528592)
			(xy 9.09955 -372.528592) (xy 9.069583 -372.528094) (xy 9.010161 -372.520271) (xy 8.952268 -372.504759)
			(xy 8.896896 -372.481823) (xy 8.84499 -372.451855) (xy 8.797441 -372.415369) (xy 8.755061 -372.372989)
			(xy 8.718575 -372.32544) (xy 8.688607 -372.273534) (xy 8.665671 -372.218162) (xy 8.650159 -372.160269)
			(xy 8.642336 -372.100847) (xy 0.509016 -372.100847) (xy 0.509016 -374.423871) (xy 27.348897 -374.423871)
			(xy 27.348897 -374.356446) (xy 27.356974 -374.289508) (xy 27.37301 -374.224019) (xy 27.396774 -374.160922)
			(xy 27.427926 -374.101125) (xy 27.466016 -374.045491) (xy 27.48788 -374.019826) (xy 27.493688 -374.012689)
			(xy 27.500197 -373.995492) (xy 27.50058 -373.986298) (xy 27.50058 -373.828818) (xy 27.501042 -373.818688)
			(xy 27.508772 -373.799959) (xy 27.523066 -373.785601) (xy 27.54176 -373.777788) (xy 27.551888 -373.777256)
			(xy 28.268168 -373.777256) (xy 28.278269 -373.77781) (xy 28.296938 -373.785529) (xy 28.311233 -373.799804)
			(xy 28.318977 -373.818463) (xy 28.319476 -373.828564) (xy 28.319476 -373.986298) (xy 28.319892 -373.995484)
			(xy 28.326402 -374.012669) (xy 28.332176 -374.019826) (xy 28.354038 -374.045493) (xy 28.392127 -374.101127)
			(xy 28.423278 -374.160923) (xy 28.447043 -374.22402) (xy 28.463078 -374.289509) (xy 28.471154 -374.356447)
			(xy 28.471155 -374.423823) (xy 31.749171 -374.423823) (xy 31.749175 -374.356514) (xy 31.757224 -374.289688)
			(xy 31.773202 -374.224303) (xy 31.796881 -374.161297) (xy 31.827921 -374.101572) (xy 31.865877 -374.045986)
			(xy 31.887668 -374.020334) (xy 31.893483 -374.013202) (xy 31.899985 -373.996001) (xy 31.900368 -373.986806)
			(xy 31.900368 -373.828818) (xy 31.900779 -373.818644) (xy 31.908564 -373.799844) (xy 31.922954 -373.785457)
			(xy 31.941756 -373.777677) (xy 31.95193 -373.777256) (xy 32.66821 -373.777256) (xy 32.678384 -373.777656)
			(xy 32.697183 -373.785448) (xy 32.711568 -373.799841) (xy 32.719349 -373.818643) (xy 32.719772 -373.828818)
			(xy 32.719772 -373.986806) (xy 32.720185 -373.995993) (xy 32.726697 -374.013177) (xy 32.732472 -374.020334)
			(xy 32.754218 -374.04602) (xy 32.792167 -374.101602) (xy 32.823202 -374.161321) (xy 32.846876 -374.224321)
			(xy 32.862852 -374.289699) (xy 32.870899 -374.356518) (xy 32.870903 -374.423819) (xy 32.870895 -374.423882)
			(xy 36.148964 -374.423882) (xy 36.148968 -374.356455) (xy 36.157048 -374.289515) (xy 36.173087 -374.224024)
			(xy 36.196854 -374.160925) (xy 36.228007 -374.101128) (xy 36.266099 -374.045492) (xy 36.287964 -374.019826)
			(xy 36.293782 -374.012697) (xy 36.300282 -373.995494) (xy 36.300664 -373.986298) (xy 36.300664 -373.828818)
			(xy 36.301142 -373.818689) (xy 36.308868 -373.799964) (xy 36.323158 -373.785606) (xy 36.341846 -373.777791)
			(xy 36.351972 -373.777256) (xy 37.068252 -373.777256) (xy 37.078398 -373.77776) (xy 37.09714 -373.785532)
			(xy 37.111464 -373.799903) (xy 37.119173 -373.818671) (xy 37.11956 -373.828818) (xy 37.11956 -373.986298)
			(xy 37.11998 -373.995484) (xy 37.126488 -374.012668) (xy 37.13226 -374.019826) (xy 37.154084 -374.045525)
			(xy 37.192177 -374.101153) (xy 37.223331 -374.160945) (xy 37.2471 -374.224037) (xy 37.263139 -374.289523)
			(xy 37.271219 -374.356458) (xy 37.271223 -374.423879) (xy 37.271223 -374.423882) (xy 40.548731 -374.423882)
			(xy 40.548735 -374.356454) (xy 40.556815 -374.289512) (xy 40.572857 -374.22402) (xy 40.596628 -374.160921)
			(xy 40.627787 -374.101124) (xy 40.665884 -374.04549) (xy 40.687752 -374.019826) (xy 40.693569 -374.012695)
			(xy 40.70007 -373.995494) (xy 40.700452 -373.986298) (xy 40.700452 -373.828818) (xy 40.700942 -373.818691)
			(xy 40.708666 -373.799968) (xy 40.722951 -373.785611) (xy 40.741636 -373.777793) (xy 40.75176 -373.777256)
			(xy 41.46804 -373.777256) (xy 41.478191 -373.777688) (xy 41.496936 -373.785489) (xy 41.511256 -373.799881)
			(xy 41.518963 -373.818665) (xy 41.519348 -373.828818) (xy 41.519348 -373.986298) (xy 41.519771 -373.995484)
			(xy 41.526277 -374.012667) (xy 41.532048 -374.019826) (xy 41.553873 -374.045524) (xy 41.591966 -374.101153)
			(xy 41.623121 -374.160944) (xy 41.64689 -374.224037) (xy 41.66293 -374.289522) (xy 41.67101 -374.356458)
			(xy 41.671014 -374.423823) (xy 44.94905 -374.423823) (xy 44.949054 -374.356514) (xy 44.957102 -374.289689)
			(xy 44.97308 -374.224304) (xy 44.996757 -374.161298) (xy 45.027796 -374.101573) (xy 45.06575 -374.045986)
			(xy 45.08754 -374.020334) (xy 45.093352 -374.0132) (xy 45.099857 -373.996001) (xy 45.10024 -373.986806)
			(xy 45.10024 -373.828818) (xy 45.100678 -373.818647) (xy 45.108458 -373.799853) (xy 45.122839 -373.785467)
			(xy 45.141631 -373.777682) (xy 45.151802 -373.777256) (xy 45.868082 -373.777256) (xy 45.878255 -373.777679)
			(xy 45.897053 -373.785461) (xy 45.911439 -373.799847) (xy 45.919221 -373.818645) (xy 45.919644 -373.828818)
			(xy 45.919644 -373.986806) (xy 45.920064 -373.995992) (xy 45.926572 -374.013176) (xy 45.932344 -374.020334)
			(xy 45.954091 -374.04602) (xy 45.992042 -374.101601) (xy 46.023078 -374.16132) (xy 46.046754 -374.22432)
			(xy 46.06273 -374.289698) (xy 46.070778 -374.356517) (xy 46.070782 -374.423819) (xy 46.070774 -374.423882)
			(xy 71.348786 -374.423882) (xy 71.348789 -374.356455) (xy 71.356869 -374.289514) (xy 71.372909 -374.224023)
			(xy 71.396677 -374.160924) (xy 71.427833 -374.101127) (xy 71.465926 -374.045491) (xy 71.487792 -374.019826)
			(xy 71.493602 -374.01269) (xy 71.500109 -373.995492) (xy 71.500492 -373.986298) (xy 71.500492 -373.828818)
			(xy 71.50104 -373.818698) (xy 71.508753 -373.799987) (xy 71.52302 -373.785631) (xy 71.541684 -373.777803)
			(xy 71.5518 -373.777256) (xy 72.26808 -373.777256) (xy 72.278227 -373.777737) (xy 72.296971 -373.785518)
			(xy 72.311293 -373.799896) (xy 72.319002 -373.818669) (xy 72.319388 -373.828818) (xy 72.319388 -373.986298)
			(xy 72.319802 -373.995485) (xy 72.326313 -374.012669) (xy 72.332088 -374.019826) (xy 72.353911 -374.045525)
			(xy 72.392002 -374.101154) (xy 72.423155 -374.160946) (xy 72.446922 -374.224038) (xy 72.462961 -374.289523)
			(xy 72.47104 -374.356458) (xy 72.471044 -374.423823) (xy 75.749081 -374.423823) (xy 75.749084 -374.356514)
			(xy 75.757133 -374.289688) (xy 75.773112 -374.224303) (xy 75.796791 -374.161296) (xy 75.827832 -374.101572)
			(xy 75.865788 -374.045985) (xy 75.88758 -374.020334) (xy 75.893385 -374.013194) (xy 75.899895 -373.996)
			(xy 75.90028 -373.986806) (xy 75.90028 -373.828818) (xy 75.900679 -373.818642) (xy 75.908466 -373.79984)
			(xy 75.92286 -373.785453) (xy 75.941666 -373.777675) (xy 75.951842 -373.777256) (xy 76.668122 -373.777256)
			(xy 76.678283 -373.777716) (xy 76.697057 -373.785501) (xy 76.711422 -373.799877) (xy 76.719192 -373.818656)
			(xy 76.719684 -373.828818) (xy 76.719684 -373.986806) (xy 76.720095 -373.995993) (xy 76.726608 -374.013177)
			(xy 76.732384 -374.020334) (xy 76.754129 -374.046021) (xy 76.792078 -374.101603) (xy 76.823112 -374.161322)
			(xy 76.846786 -374.224322) (xy 76.862761 -374.289699) (xy 76.870808 -374.356518) (xy 76.870812 -374.423819)
			(xy 76.870804 -374.423882) (xy 80.148873 -374.423882) (xy 80.148877 -374.356455) (xy 80.156957 -374.289515)
			(xy 80.172996 -374.224023) (xy 80.196764 -374.160925) (xy 80.227918 -374.101127) (xy 80.26601 -374.045492)
			(xy 80.287876 -374.019826) (xy 80.293684 -374.012689) (xy 80.300193 -373.995492) (xy 80.300576 -373.986298)
			(xy 80.300576 -373.828818) (xy 80.301042 -373.818688) (xy 80.308771 -373.79996) (xy 80.323064 -373.785602)
			(xy 80.341756 -373.777789) (xy 80.351884 -373.777256) (xy 81.068164 -373.777256) (xy 81.078265 -373.777814)
			(xy 81.096934 -373.785531) (xy 81.111228 -373.799806) (xy 81.118972 -373.818464) (xy 81.119472 -373.828564)
			(xy 81.119472 -373.986298) (xy 81.119889 -373.995484) (xy 81.126399 -374.012668) (xy 81.132172 -374.019826)
			(xy 81.153996 -374.045525) (xy 81.192087 -374.101154) (xy 81.223242 -374.160945) (xy 81.247009 -374.224038)
			(xy 81.263049 -374.289523) (xy 81.271128 -374.356458) (xy 81.271132 -374.423879) (xy 81.271132 -374.423882)
			(xy 84.548664 -374.423882) (xy 84.548668 -374.356455) (xy 84.556748 -374.289515) (xy 84.572787 -374.224024)
			(xy 84.596554 -374.160925) (xy 84.627707 -374.101128) (xy 84.665799 -374.045492) (xy 84.687664 -374.019826)
			(xy 84.693482 -374.012697) (xy 84.699982 -373.995494) (xy 84.700364 -373.986298) (xy 84.700364 -373.828818)
			(xy 84.700842 -373.818689) (xy 84.708568 -373.799964) (xy 84.722858 -373.785606) (xy 84.741546 -373.777791)
			(xy 84.751672 -373.777256) (xy 85.467952 -373.777256) (xy 85.478066 -373.777754) (xy 85.49676 -373.785478)
			(xy 85.511074 -373.799769) (xy 85.518829 -373.818451) (xy 85.51926 -373.828564) (xy 85.51926 -373.986298)
			(xy 85.51968 -373.995484) (xy 85.526188 -374.012668) (xy 85.53196 -374.019826) (xy 85.553784 -374.045525)
			(xy 85.591877 -374.101153) (xy 85.623031 -374.160945) (xy 85.6468 -374.224037) (xy 85.662839 -374.289523)
			(xy 85.670919 -374.356458) (xy 85.670923 -374.423822) (xy 115.349223 -374.423822) (xy 115.349227 -374.356515)
			(xy 115.357275 -374.28969) (xy 115.373251 -374.224306) (xy 115.396927 -374.1613) (xy 115.427963 -374.101574)
			(xy 115.465915 -374.045987) (xy 115.487704 -374.020334) (xy 115.493512 -374.013197) (xy 115.50002 -373.996)
			(xy 115.500404 -373.986806) (xy 115.500404 -373.828818) (xy 115.500947 -373.818666) (xy 115.508709 -373.799903)
			(xy 115.52306 -373.785539) (xy 115.541814 -373.777757) (xy 115.551966 -373.777256) (xy 116.268246 -373.777256)
			(xy 116.278409 -373.777696) (xy 116.297183 -373.785489) (xy 116.311547 -373.799871) (xy 116.319316 -373.818654)
			(xy 116.319808 -373.828818) (xy 116.319808 -373.986806) (xy 116.320214 -373.995994) (xy 116.32673 -374.013178)
			(xy 116.332508 -374.020334) (xy 116.354256 -374.046019) (xy 116.39221 -374.1016) (xy 116.423248 -374.161318)
			(xy 116.446925 -374.224319) (xy 116.462903 -374.289697) (xy 116.470951 -374.356517) (xy 116.470955 -374.42382)
			(xy 116.470948 -374.423882) (xy 119.748992 -374.423882) (xy 119.748995 -374.356455) (xy 119.757075 -374.289514)
			(xy 119.773115 -374.224022) (xy 119.796884 -374.160924) (xy 119.82804 -374.101126) (xy 119.866134 -374.045491)
			(xy 119.888 -374.019826) (xy 119.89381 -374.012691) (xy 119.900317 -373.995493) (xy 119.9007 -373.986298)
			(xy 119.9007 -373.828818) (xy 119.90124 -373.818697) (xy 119.908955 -373.799984) (xy 119.923224 -373.785629)
			(xy 119.94189 -373.777802) (xy 119.952008 -373.777256) (xy 120.668288 -373.777256) (xy 120.678436 -373.777731)
			(xy 120.69718 -373.785514) (xy 120.711502 -373.799894) (xy 120.71921 -373.818669) (xy 120.719596 -373.828818)
			(xy 120.719596 -373.986298) (xy 120.720008 -373.995485) (xy 120.726521 -374.012669) (xy 120.732296 -374.019826)
			(xy 120.754119 -374.045525) (xy 120.792209 -374.101155) (xy 120.823362 -374.160946) (xy 120.847129 -374.224039)
			(xy 120.863167 -374.289524) (xy 120.871246 -374.356458) (xy 120.87125 -374.423823) (xy 124.149287 -374.423823)
			(xy 124.149291 -374.356514) (xy 124.15734 -374.289688) (xy 124.173319 -374.224302) (xy 124.196998 -374.161296)
			(xy 124.228039 -374.101572) (xy 124.265996 -374.045986) (xy 124.287788 -374.020334) (xy 124.293594 -374.013195)
			(xy 124.300103 -373.996) (xy 124.300488 -373.986806) (xy 124.300488 -373.828818) (xy 124.30088 -373.818641)
			(xy 124.308668 -373.799837) (xy 124.323064 -373.78545) (xy 124.341873 -373.777673) (xy 124.35205 -373.777256)
			(xy 125.06833 -373.777256) (xy 125.078492 -373.777709) (xy 125.097265 -373.785497) (xy 125.11163 -373.799875)
			(xy 125.1194 -373.818656) (xy 125.119892 -373.828818) (xy 125.119892 -373.986806) (xy 125.120301 -373.995993)
			(xy 125.126816 -374.013177) (xy 125.132592 -374.020334) (xy 125.154338 -374.04602) (xy 125.192286 -374.101603)
			(xy 125.223319 -374.161322) (xy 125.246993 -374.224322) (xy 125.262968 -374.2897) (xy 125.271015 -374.356518)
			(xy 125.271019 -374.423819) (xy 125.271019 -374.423823) (xy 128.549078 -374.423823) (xy 128.549081 -374.356514)
			(xy 128.55713 -374.289688) (xy 128.573109 -374.224303) (xy 128.596788 -374.161296) (xy 128.627828 -374.101572)
			(xy 128.665784 -374.045985) (xy 128.687576 -374.020334) (xy 128.69338 -374.013194) (xy 128.699891 -373.996)
			(xy 128.700276 -373.986806) (xy 128.700276 -373.828818) (xy 128.700679 -373.818643) (xy 128.708465 -373.799841)
			(xy 128.722858 -373.785454) (xy 128.741663 -373.777675) (xy 128.751838 -373.777256) (xy 129.468118 -373.777256)
			(xy 129.478279 -373.777719) (xy 129.497052 -373.785503) (xy 129.511418 -373.799878) (xy 129.519188 -373.818656)
			(xy 129.51968 -373.828818) (xy 129.51968 -373.986806) (xy 129.520092 -373.995993) (xy 129.526605 -374.013177)
			(xy 129.53238 -374.020334) (xy 129.554126 -374.046021) (xy 129.592074 -374.101603) (xy 129.623108 -374.161322)
			(xy 129.646783 -374.224321) (xy 129.662758 -374.289699) (xy 129.670805 -374.356518) (xy 129.670809 -374.423819)
			(xy 129.670809 -374.423822) (xy 159.349132 -374.423822) (xy 159.349136 -374.356514) (xy 159.357184 -374.289689)
			(xy 159.373161 -374.224305) (xy 159.396837 -374.161299) (xy 159.427874 -374.101574) (xy 159.465826 -374.045986)
			(xy 159.487616 -374.020334) (xy 159.493425 -374.013198) (xy 159.499932 -373.996) (xy 159.500316 -373.986806)
			(xy 159.500316 -373.828818) (xy 159.500847 -373.818664) (xy 159.508612 -373.799899) (xy 159.522966 -373.785534)
			(xy 159.541724 -373.777755) (xy 159.551878 -373.777256) (xy 160.268158 -373.777256) (xy 160.278329 -373.777699)
			(xy 160.297126 -373.785473) (xy 160.311513 -373.799854) (xy 160.319297 -373.818647) (xy 160.31972 -373.828818)
			(xy 160.31972 -373.986806) (xy 160.320123 -373.995994) (xy 160.326641 -374.013179) (xy 160.33242 -374.020334)
			(xy 160.354168 -374.04602) (xy 160.39212 -374.1016) (xy 160.423158 -374.161319) (xy 160.446835 -374.224319)
			(xy 160.462812 -374.289698) (xy 160.47086 -374.356517) (xy 160.470864 -374.42382) (xy 160.470857 -374.423882)
			(xy 163.748901 -374.423882) (xy 163.748904 -374.356455) (xy 163.756985 -374.289514) (xy 163.773025 -374.224022)
			(xy 163.796794 -374.160923) (xy 163.827951 -374.101126) (xy 163.866045 -374.045491) (xy 163.887912 -374.019826)
			(xy 163.893724 -374.012692) (xy 163.900229 -373.995493) (xy 163.900612 -373.986298) (xy 163.900612 -373.828818)
			(xy 163.90114 -373.818696) (xy 163.908857 -373.79998) (xy 163.92313 -373.785624) (xy 163.941801 -373.7778)
			(xy 163.95192 -373.777256) (xy 164.6682 -373.777256) (xy 164.678349 -373.777721) (xy 164.697092 -373.785508)
			(xy 164.711414 -373.799891) (xy 164.719122 -373.818668) (xy 164.719508 -373.828818) (xy 164.719508 -373.986298)
			(xy 164.719917 -373.995485) (xy 164.726431 -374.01267) (xy 164.732208 -374.019826) (xy 164.75403 -374.045525)
			(xy 164.79212 -374.101155) (xy 164.823272 -374.160947) (xy 164.847038 -374.224039) (xy 164.863076 -374.289524)
			(xy 164.871155 -374.356458) (xy 164.871159 -374.423822) (xy 168.14922 -374.423822) (xy 168.149224 -374.356515)
			(xy 168.157272 -374.28969) (xy 168.173248 -374.224306) (xy 168.196924 -374.1613) (xy 168.22796 -374.101575)
			(xy 168.265911 -374.045987) (xy 168.2877 -374.020334) (xy 168.293507 -374.013196) (xy 168.300015 -373.996)
			(xy 168.3004 -373.986806) (xy 168.3004 -373.828818) (xy 168.300947 -373.818666) (xy 168.308709 -373.799905)
			(xy 168.323058 -373.78554) (xy 168.341811 -373.777758) (xy 168.351962 -373.777256) (xy 169.068242 -373.777256)
			(xy 169.078405 -373.777699) (xy 169.097178 -373.785491) (xy 169.111543 -373.799872) (xy 169.119312 -373.818655)
			(xy 169.119804 -373.828818) (xy 169.119804 -373.986806) (xy 169.120211 -373.995994) (xy 169.126727 -374.013178)
			(xy 169.132504 -374.020334) (xy 169.154249 -374.046021) (xy 169.192196 -374.101603) (xy 169.223229 -374.161322)
			(xy 169.246902 -374.224322) (xy 169.262877 -374.2897) (xy 169.270924 -374.356518) (xy 169.270928 -374.423819)
			(xy 169.270928 -374.423823) (xy 172.548987 -374.423823) (xy 172.548991 -374.356514) (xy 172.55704 -374.289688)
			(xy 172.573019 -374.224302) (xy 172.596698 -374.161296) (xy 172.627739 -374.101572) (xy 172.665696 -374.045986)
			(xy 172.687488 -374.020334) (xy 172.693294 -374.013195) (xy 172.699803 -373.996) (xy 172.700188 -373.986806)
			(xy 172.700188 -373.828818) (xy 172.70058 -373.818641) (xy 172.708368 -373.799837) (xy 172.722764 -373.78545)
			(xy 172.741573 -373.777673) (xy 172.75175 -373.777256) (xy 173.46803 -373.777256) (xy 173.478192 -373.777709)
			(xy 173.496965 -373.785497) (xy 173.51133 -373.799875) (xy 173.5191 -373.818656) (xy 173.519592 -373.828818)
			(xy 173.519592 -373.986806) (xy 173.520001 -373.995993) (xy 173.526516 -374.013177) (xy 173.532292 -374.020334)
			(xy 173.554038 -374.04602) (xy 173.591986 -374.101603) (xy 173.623019 -374.161322) (xy 173.646693 -374.224322)
			(xy 173.662668 -374.2897) (xy 173.670715 -374.356518) (xy 173.670719 -374.423819) (xy 173.662679 -374.490638)
			(xy 173.646712 -374.556018) (xy 173.623045 -374.61902) (xy 173.592018 -374.678743) (xy 173.554076 -374.73433)
			(xy 173.532292 -374.759982) (xy 173.526477 -374.767114) (xy 173.519974 -374.784315) (xy 173.519592 -374.79351)
			(xy 173.519592 -375.286778) (xy 173.520015 -375.295964) (xy 173.52652 -375.313148) (xy 173.532292 -375.320306)
			(xy 173.554108 -375.345934) (xy 173.592054 -375.401525) (xy 173.623084 -375.461252) (xy 173.646754 -375.52426)
			(xy 173.662724 -375.589644) (xy 173.670765 -375.656469) (xy 173.670763 -375.723776) (xy 173.662716 -375.7906)
			(xy 173.646741 -375.855984) (xy 173.623066 -375.918989) (xy 173.592031 -375.978714) (xy 173.554081 -376.034301)
			(xy 173.532292 -376.059954) (xy 173.526489 -376.067095) (xy 173.519978 -376.084289) (xy 173.519592 -376.093482)
			(xy 173.519592 -376.25147) (xy 173.519043 -376.261622) (xy 173.511284 -376.280385) (xy 173.496935 -376.29475)
			(xy 173.478182 -376.302531) (xy 173.46803 -376.303032) (xy 172.75175 -376.303032) (xy 172.741578 -376.302595)
			(xy 172.722779 -376.29482) (xy 172.708391 -376.280438) (xy 172.700609 -376.261642) (xy 172.700188 -376.25147)
			(xy 172.700188 -376.093482) (xy 172.699789 -376.084294) (xy 172.693268 -376.067109) (xy 172.687488 -376.059954)
			(xy 172.665728 -376.034278) (xy 172.627775 -375.978696) (xy 172.596738 -375.918976) (xy 172.573061 -375.855975)
			(xy 172.557085 -375.790595) (xy 172.549038 -375.723774) (xy 172.549035 -375.656471) (xy 172.557077 -375.589649)
			(xy 172.573048 -375.524268) (xy 172.59672 -375.461265) (xy 172.627752 -375.401542) (xy 172.665701 -375.345957)
			(xy 172.687488 -375.320306) (xy 172.693263 -375.313145) (xy 172.699791 -375.295967) (xy 172.700188 -375.286778)
			(xy 172.700188 -374.79351) (xy 172.699776 -374.784323) (xy 172.693264 -374.767138) (xy 172.687488 -374.759982)
			(xy 172.665658 -374.734364) (xy 172.627707 -374.678774) (xy 172.596673 -374.619046) (xy 172.573 -374.556037)
			(xy 172.557029 -374.49065) (xy 172.548987 -374.423823) (xy 169.270928 -374.423823) (xy 169.262888 -374.490638)
			(xy 169.246921 -374.556017) (xy 169.223255 -374.61902) (xy 169.192229 -374.678743) (xy 169.154288 -374.734329)
			(xy 169.132504 -374.759982) (xy 169.126691 -374.767115) (xy 169.120186 -374.784315) (xy 169.119804 -374.79351)
			(xy 169.119804 -375.286778) (xy 169.120224 -375.295964) (xy 169.126731 -375.313149) (xy 169.132504 -375.320306)
			(xy 169.15432 -375.345935) (xy 169.192265 -375.401525) (xy 169.223295 -375.461253) (xy 169.246964 -375.52426)
			(xy 169.262933 -375.589645) (xy 169.270974 -375.656469) (xy 169.270972 -375.723776) (xy 169.262925 -375.7906)
			(xy 169.24695 -375.855983) (xy 169.223276 -375.918989) (xy 169.192242 -375.978713) (xy 169.154292 -376.034301)
			(xy 169.132504 -376.059954) (xy 169.126702 -376.067096) (xy 169.120191 -376.084289) (xy 169.119804 -376.093482)
			(xy 169.119804 -376.25147) (xy 169.119243 -376.261621) (xy 169.111487 -376.280381) (xy 169.097142 -376.294746)
			(xy 169.078392 -376.302529) (xy 169.068242 -376.303032) (xy 168.351962 -376.303032) (xy 168.341798 -376.302597)
			(xy 168.323022 -376.294804) (xy 168.308657 -376.280421) (xy 168.30089 -376.261635) (xy 168.3004 -376.25147)
			(xy 168.3004 -376.093482) (xy 168.299998 -376.084294) (xy 168.293479 -376.06711) (xy 168.2877 -376.059954)
			(xy 168.265943 -376.034277) (xy 168.227996 -375.978693) (xy 168.196963 -375.918973) (xy 168.173291 -375.855972)
			(xy 168.157317 -375.790593) (xy 168.149271 -375.723774) (xy 168.149268 -375.656472) (xy 168.157309 -375.589652)
			(xy 168.173277 -375.524272) (xy 168.196945 -375.461269) (xy 168.227973 -375.401546) (xy 168.265915 -375.345959)
			(xy 168.2877 -375.320306) (xy 168.293477 -375.313147) (xy 168.300003 -375.295967) (xy 168.3004 -375.286778)
			(xy 168.3004 -374.79351) (xy 168.299985 -374.784323) (xy 168.293475 -374.767139) (xy 168.2877 -374.759982)
			(xy 168.265872 -374.734363) (xy 168.227927 -374.678771) (xy 168.196898 -374.619043) (xy 168.173229 -374.556034)
			(xy 168.15726 -374.490648) (xy 168.14922 -374.423822) (xy 164.871159 -374.423822) (xy 164.871159 -374.423879)
			(xy 164.863088 -374.490814) (xy 164.847057 -374.5563) (xy 164.823298 -374.619396) (xy 164.792152 -374.679191)
			(xy 164.754069 -374.734825) (xy 164.732208 -374.76049) (xy 164.726392 -374.767621) (xy 164.719889 -374.784822)
			(xy 164.719508 -374.794018) (xy 164.719508 -375.28627) (xy 164.719931 -375.295456) (xy 164.726435 -375.31264)
			(xy 164.732208 -375.319798) (xy 164.754101 -375.345439) (xy 164.792188 -375.401077) (xy 164.823337 -375.460877)
			(xy 164.8471 -375.523977) (xy 164.863133 -375.589469) (xy 164.871206 -375.65641) (xy 164.871203 -375.723835)
			(xy 164.863125 -375.790776) (xy 164.847086 -375.856266) (xy 164.823319 -375.919364) (xy 164.792165 -375.979161)
			(xy 164.754073 -376.034797) (xy 164.732208 -376.060462) (xy 164.726404 -376.067602) (xy 164.719893 -376.084796)
			(xy 164.719508 -376.09399) (xy 164.719508 -376.25147) (xy 164.71895 -376.261589) (xy 164.711241 -376.2803)
			(xy 164.696977 -376.294656) (xy 164.678316 -376.302485) (xy 164.6682 -376.303032) (xy 163.95192 -376.303032)
			(xy 163.941771 -376.302563) (xy 163.923025 -376.29478) (xy 163.908702 -376.280398) (xy 163.900996 -376.26162)
			(xy 163.900612 -376.25147) (xy 163.900612 -376.09399) (xy 163.900204 -376.084803) (xy 163.893689 -376.067618)
			(xy 163.887912 -376.060462) (xy 163.866077 -376.034773) (xy 163.827987 -375.979142) (xy 163.796834 -375.919349)
			(xy 163.773068 -375.856255) (xy 163.75703 -375.790769) (xy 163.748951 -375.723833) (xy 163.748949 -375.656412)
			(xy 163.757022 -375.589475) (xy 163.773054 -375.523988) (xy 163.796816 -375.460892) (xy 163.827963 -375.401097)
			(xy 163.866049 -375.345463) (xy 163.887912 -375.319798) (xy 163.893693 -375.312642) (xy 163.900217 -375.29546)
			(xy 163.900612 -375.28627) (xy 163.900612 -374.794018) (xy 163.90019 -374.784832) (xy 163.893684 -374.767648)
			(xy 163.887912 -374.76049) (xy 163.866006 -374.734859) (xy 163.827918 -374.67922) (xy 163.796769 -374.619419)
			(xy 163.773006 -374.556318) (xy 163.756973 -374.490824) (xy 163.748901 -374.423882) (xy 160.470857 -374.423882)
			(xy 160.462823 -374.49064) (xy 160.446853 -374.556021) (xy 160.423184 -374.619023) (xy 160.392153 -374.678745)
			(xy 160.354206 -374.73433) (xy 160.33242 -374.759982) (xy 160.326608 -374.767117) (xy 160.320102 -374.784315)
			(xy 160.31972 -374.79351) (xy 160.31972 -375.286778) (xy 160.320136 -375.295965) (xy 160.326645 -375.313149)
			(xy 160.33242 -375.320306) (xy 160.354238 -375.345933) (xy 160.392189 -375.401522) (xy 160.423223 -375.461249)
			(xy 160.446896 -375.524257) (xy 160.462868 -375.589643) (xy 160.470911 -375.656468) (xy 160.470908 -375.723777)
			(xy 160.46286 -375.790602) (xy 160.446883 -375.855986) (xy 160.423205 -375.918992) (xy 160.392166 -375.978716)
			(xy 160.354211 -376.034302) (xy 160.33242 -376.059954) (xy 160.32662 -376.067097) (xy 160.320107 -376.084289)
			(xy 160.31972 -376.093482) (xy 160.31972 -376.25147) (xy 160.31931 -376.261645) (xy 160.311528 -376.280447)
			(xy 160.297137 -376.294834) (xy 160.278333 -376.302613) (xy 160.268158 -376.303032) (xy 159.551878 -376.303032)
			(xy 159.541701 -376.302653) (xy 159.5229 -376.294855) (xy 159.508515 -376.280456) (xy 159.500737 -376.261647)
			(xy 159.500316 -376.25147) (xy 159.500316 -376.093482) (xy 159.499911 -376.084294) (xy 159.493393 -376.06711)
			(xy 159.487616 -376.059954) (xy 159.465858 -376.034277) (xy 159.42791 -375.978694) (xy 159.396877 -375.918973)
			(xy 159.373203 -375.855972) (xy 159.357229 -375.790593) (xy 159.349183 -375.723774) (xy 159.34918 -375.656471)
			(xy 159.357221 -375.589651) (xy 159.37319 -375.524271) (xy 159.396858 -375.461268) (xy 159.427887 -375.401545)
			(xy 159.465831 -375.345958) (xy 159.487616 -375.320306) (xy 159.493394 -375.313148) (xy 159.499919 -375.295967)
			(xy 159.500316 -375.286778) (xy 159.500316 -374.79351) (xy 159.499897 -374.784324) (xy 159.493389 -374.76714)
			(xy 159.487616 -374.759982) (xy 159.465788 -374.734364) (xy 159.427842 -374.678772) (xy 159.396811 -374.619043)
			(xy 159.373142 -374.556034) (xy 159.357173 -374.490648) (xy 159.349132 -374.423822) (xy 129.670809 -374.423822)
			(xy 129.662769 -374.490638) (xy 129.646801 -374.556018) (xy 129.623134 -374.619021) (xy 129.592107 -374.678743)
			(xy 129.554164 -374.734329) (xy 129.53238 -374.759982) (xy 129.526564 -374.767113) (xy 129.520062 -374.784315)
			(xy 129.51968 -374.79351) (xy 129.51968 -375.286778) (xy 129.520105 -375.295963) (xy 129.526609 -375.313148)
			(xy 129.53238 -375.320306) (xy 129.554197 -375.345934) (xy 129.592143 -375.401524) (xy 129.623174 -375.461252)
			(xy 129.646845 -375.524259) (xy 129.662815 -375.589644) (xy 129.670856 -375.656469) (xy 129.670854 -375.723776)
			(xy 129.662807 -375.7906) (xy 129.646831 -375.855984) (xy 129.623156 -375.91899) (xy 129.59212 -375.978714)
			(xy 129.554169 -376.034302) (xy 129.53238 -376.059954) (xy 129.526576 -376.067094) (xy 129.520066 -376.084288)
			(xy 129.51968 -376.093482) (xy 129.51968 -376.25147) (xy 129.519212 -376.261637) (xy 129.51144 -376.280428)
			(xy 129.497068 -376.294813) (xy 129.478285 -376.302602) (xy 129.468118 -376.303032) (xy 128.751838 -376.303032)
			(xy 128.741665 -376.302604) (xy 128.722866 -376.294826) (xy 128.708478 -376.280441) (xy 128.700697 -376.261643)
			(xy 128.700276 -376.25147) (xy 128.700276 -376.093482) (xy 128.69988 -376.084293) (xy 128.693357 -376.067109)
			(xy 128.687576 -376.059954) (xy 128.665817 -376.034278) (xy 128.627865 -375.978696) (xy 128.596828 -375.918976)
			(xy 128.573152 -375.855974) (xy 128.557176 -375.790595) (xy 128.549129 -375.723774) (xy 128.549126 -375.656471)
			(xy 128.557168 -375.58965) (xy 128.573138 -375.524269) (xy 128.59681 -375.461265) (xy 128.627841 -375.401543)
			(xy 128.665789 -375.345958) (xy 128.687576 -375.320306) (xy 128.69335 -375.313144) (xy 128.699879 -375.295967)
			(xy 128.700276 -375.286778) (xy 128.700276 -374.79351) (xy 128.699866 -374.784323) (xy 128.693353 -374.767138)
			(xy 128.687576 -374.759982) (xy 128.665746 -374.734365) (xy 128.627796 -374.678774) (xy 128.596762 -374.619046)
			(xy 128.57309 -374.556037) (xy 128.557119 -374.49065) (xy 128.549078 -374.423823) (xy 125.271019 -374.423823)
			(xy 125.262979 -374.490638) (xy 125.247012 -374.556018) (xy 125.223345 -374.61902) (xy 125.192318 -374.678743)
			(xy 125.154376 -374.73433) (xy 125.132592 -374.759982) (xy 125.126777 -374.767114) (xy 125.120274 -374.784315)
			(xy 125.119892 -374.79351) (xy 125.119892 -375.286778) (xy 125.120315 -375.295964) (xy 125.12682 -375.313148)
			(xy 125.132592 -375.320306) (xy 125.154408 -375.345934) (xy 125.192354 -375.401525) (xy 125.223384 -375.461252)
			(xy 125.247054 -375.52426) (xy 125.263024 -375.589644) (xy 125.271065 -375.656469) (xy 125.271063 -375.723776)
			(xy 125.263016 -375.7906) (xy 125.247041 -375.855984) (xy 125.223366 -375.918989) (xy 125.192331 -375.978714)
			(xy 125.154381 -376.034301) (xy 125.132592 -376.059954) (xy 125.126789 -376.067095) (xy 125.120278 -376.084289)
			(xy 125.119892 -376.093482) (xy 125.119892 -376.25147) (xy 125.119343 -376.261622) (xy 125.111584 -376.280385)
			(xy 125.097235 -376.29475) (xy 125.078482 -376.302531) (xy 125.06833 -376.303032) (xy 124.35205 -376.303032)
			(xy 124.341878 -376.302595) (xy 124.323079 -376.29482) (xy 124.308691 -376.280438) (xy 124.300909 -376.261642)
			(xy 124.300488 -376.25147) (xy 124.300488 -376.093482) (xy 124.300089 -376.084294) (xy 124.293568 -376.067109)
			(xy 124.287788 -376.059954) (xy 124.266028 -376.034278) (xy 124.228075 -375.978696) (xy 124.197038 -375.918976)
			(xy 124.173361 -375.855975) (xy 124.157385 -375.790595) (xy 124.149338 -375.723774) (xy 124.149335 -375.656471)
			(xy 124.157377 -375.589649) (xy 124.173348 -375.524268) (xy 124.19702 -375.461265) (xy 124.228052 -375.401542)
			(xy 124.266001 -375.345957) (xy 124.287788 -375.320306) (xy 124.293563 -375.313145) (xy 124.300091 -375.295967)
			(xy 124.300488 -375.286778) (xy 124.300488 -374.79351) (xy 124.300076 -374.784323) (xy 124.293564 -374.767138)
			(xy 124.287788 -374.759982) (xy 124.265958 -374.734364) (xy 124.228007 -374.678774) (xy 124.196973 -374.619046)
			(xy 124.1733 -374.556037) (xy 124.157329 -374.49065) (xy 124.149287 -374.423823) (xy 120.87125 -374.423823)
			(xy 120.87125 -374.423879) (xy 120.863178 -374.490814) (xy 120.847147 -374.556301) (xy 120.823388 -374.619396)
			(xy 120.792242 -374.679191) (xy 120.754158 -374.734825) (xy 120.732296 -374.76049) (xy 120.726478 -374.76762)
			(xy 120.719976 -374.784822) (xy 120.719596 -374.794018) (xy 120.719596 -375.28627) (xy 120.720022 -375.295456)
			(xy 120.726525 -375.31264) (xy 120.732296 -375.319798) (xy 120.75419 -375.345439) (xy 120.792278 -375.401077)
			(xy 120.823427 -375.460876) (xy 120.84719 -375.523976) (xy 120.863223 -375.589468) (xy 120.871297 -375.656409)
			(xy 120.871294 -375.723836) (xy 120.863215 -375.790776) (xy 120.847177 -375.856267) (xy 120.823409 -375.919365)
			(xy 120.792254 -375.979162) (xy 120.754162 -376.034797) (xy 120.732296 -376.060462) (xy 120.72649 -376.067601)
			(xy 120.719981 -376.084796) (xy 120.719596 -376.09399) (xy 120.719596 -376.25147) (xy 120.71905 -376.26159)
			(xy 120.711339 -376.280304) (xy 120.697071 -376.29466) (xy 120.678405 -376.302487) (xy 120.668288 -376.303032)
			(xy 119.952008 -376.303032) (xy 119.941858 -376.302572) (xy 119.923112 -376.294786) (xy 119.90879 -376.280401)
			(xy 119.901084 -376.261621) (xy 119.9007 -376.25147) (xy 119.9007 -376.09399) (xy 119.900294 -376.084802)
			(xy 119.893777 -376.067618) (xy 119.888 -376.060462) (xy 119.866166 -376.034772) (xy 119.828076 -375.979141)
			(xy 119.796924 -375.919349) (xy 119.773158 -375.856255) (xy 119.75712 -375.790769) (xy 119.749042 -375.723833)
			(xy 119.749039 -375.656412) (xy 119.757112 -375.589476) (xy 119.773145 -375.523988) (xy 119.796905 -375.460893)
			(xy 119.828053 -375.401097) (xy 119.866138 -375.345463) (xy 119.888 -375.319798) (xy 119.89378 -375.312641)
			(xy 119.900305 -375.29546) (xy 119.9007 -375.28627) (xy 119.9007 -374.794018) (xy 119.900281 -374.784832)
			(xy 119.893773 -374.767647) (xy 119.888 -374.76049) (xy 119.866095 -374.734859) (xy 119.828007 -374.679219)
			(xy 119.796858 -374.619418) (xy 119.773097 -374.556317) (xy 119.757064 -374.490824) (xy 119.748992 -374.423882)
			(xy 116.470948 -374.423882) (xy 116.462914 -374.49064) (xy 116.446944 -374.556021) (xy 116.423273 -374.619024)
			(xy 116.392242 -374.678746) (xy 116.354295 -374.734331) (xy 116.332508 -374.759982) (xy 116.326695 -374.767116)
			(xy 116.32019 -374.784315) (xy 116.319808 -374.79351) (xy 116.319808 -375.286778) (xy 116.320227 -375.295964)
			(xy 116.326734 -375.313149) (xy 116.332508 -375.320306) (xy 116.354327 -375.345933) (xy 116.392278 -375.401522)
			(xy 116.423313 -375.461249) (xy 116.446986 -375.524256) (xy 116.462959 -375.589642) (xy 116.471001 -375.656468)
			(xy 116.470999 -375.723777) (xy 116.462951 -375.790602) (xy 116.446973 -375.855987) (xy 116.423295 -375.918993)
			(xy 116.392255 -375.978717) (xy 116.354299 -376.034303) (xy 116.332508 -376.059954) (xy 116.326707 -376.067096)
			(xy 116.320195 -376.084289) (xy 116.319808 -376.093482) (xy 116.319808 -376.25147) (xy 116.319243 -376.26162)
			(xy 116.311487 -376.28038) (xy 116.297144 -376.294745) (xy 116.278395 -376.302528) (xy 116.268246 -376.303032)
			(xy 115.551966 -376.303032) (xy 115.541802 -376.302594) (xy 115.523027 -376.294803) (xy 115.508662 -376.28042)
			(xy 115.500894 -376.261634) (xy 115.500404 -376.25147) (xy 115.500404 -376.093482) (xy 115.500002 -376.084294)
			(xy 115.493483 -376.06711) (xy 115.487704 -376.059954) (xy 115.465947 -376.034277) (xy 115.427999 -375.978693)
			(xy 115.396967 -375.918973) (xy 115.373294 -375.855972) (xy 115.35732 -375.790593) (xy 115.349274 -375.723774)
			(xy 115.349271 -375.656472) (xy 115.357312 -375.589652) (xy 115.37328 -375.524271) (xy 115.396948 -375.461268)
			(xy 115.427976 -375.401545) (xy 115.465919 -375.345959) (xy 115.487704 -375.320306) (xy 115.493481 -375.313147)
			(xy 115.500007 -375.295967) (xy 115.500404 -375.286778) (xy 115.500404 -374.79351) (xy 115.499988 -374.784323)
			(xy 115.493478 -374.767139) (xy 115.487704 -374.759982) (xy 115.465876 -374.734363) (xy 115.427931 -374.678771)
			(xy 115.396901 -374.619043) (xy 115.373232 -374.556034) (xy 115.357263 -374.490648) (xy 115.349223 -374.423822)
			(xy 85.670923 -374.423822) (xy 85.670923 -374.423879) (xy 85.662851 -374.490815) (xy 85.646818 -374.556302)
			(xy 85.623057 -374.619398) (xy 85.591909 -374.679192) (xy 85.553823 -374.734826) (xy 85.53196 -374.76049)
			(xy 85.526138 -374.767617) (xy 85.519639 -374.784822) (xy 85.51926 -374.794018) (xy 85.51926 -375.28627)
			(xy 85.519694 -375.295454) (xy 85.526192 -375.312639) (xy 85.53196 -375.319798) (xy 85.553855 -375.345438)
			(xy 85.591945 -375.401075) (xy 85.623097 -375.460875) (xy 85.646861 -375.523975) (xy 85.662896 -375.589467)
			(xy 85.67097 -375.656409) (xy 85.670967 -375.723836) (xy 85.662888 -375.790777) (xy 85.646848 -375.856268)
			(xy 85.623079 -375.919367) (xy 85.591922 -375.979163) (xy 85.553827 -376.034797) (xy 85.53196 -376.060462)
			(xy 85.52615 -376.067597) (xy 85.519644 -376.084796) (xy 85.51926 -376.09399) (xy 85.51926 -376.25147)
			(xy 85.518749 -376.261595) (xy 85.511031 -376.280315) (xy 85.496752 -376.294673) (xy 85.478074 -376.302493)
			(xy 85.467952 -376.303032) (xy 84.751672 -376.303032) (xy 84.741565 -376.302539) (xy 84.722893 -376.294798)
			(xy 84.7086 -376.280504) (xy 84.700861 -376.261831) (xy 84.700364 -376.251724) (xy 84.700364 -376.09399)
			(xy 84.699944 -376.084804) (xy 84.693436 -376.06762) (xy 84.687664 -376.060462) (xy 84.665831 -376.034772)
			(xy 84.627744 -375.97914) (xy 84.596594 -375.919347) (xy 84.572829 -375.856253) (xy 84.556793 -375.790768)
			(xy 84.548715 -375.723833) (xy 84.548712 -375.656412) (xy 84.556785 -375.589477) (xy 84.572816 -375.52399)
			(xy 84.596575 -375.460894) (xy 84.62772 -375.401099) (xy 84.665803 -375.345464) (xy 84.687664 -375.319798)
			(xy 84.693452 -375.312647) (xy 84.69997 -375.295461) (xy 84.700364 -375.28627) (xy 84.700364 -374.794018)
			(xy 84.699931 -374.784834) (xy 84.693432 -374.76765) (xy 84.687664 -374.76049) (xy 84.66576 -374.734858)
			(xy 84.627675 -374.679218) (xy 84.596528 -374.619417) (xy 84.572768 -374.556316) (xy 84.556736 -374.490823)
			(xy 84.548664 -374.423882) (xy 81.271132 -374.423882) (xy 81.26306 -374.490815) (xy 81.247028 -374.556302)
			(xy 81.223267 -374.619397) (xy 81.19212 -374.679192) (xy 81.154034 -374.734825) (xy 81.132172 -374.76049)
			(xy 81.126351 -374.767618) (xy 81.119852 -374.784822) (xy 81.119472 -374.794018) (xy 81.119472 -375.28627)
			(xy 81.119903 -375.295455) (xy 81.126403 -375.312639) (xy 81.132172 -375.319798) (xy 81.154066 -375.345438)
			(xy 81.192156 -375.401076) (xy 81.223307 -375.460875) (xy 81.247071 -375.523975) (xy 81.263105 -375.589468)
			(xy 81.271179 -375.656409) (xy 81.271176 -375.723836) (xy 81.263097 -375.790777) (xy 81.247057 -375.856268)
			(xy 81.223289 -375.919366) (xy 81.192133 -375.979163) (xy 81.154039 -376.034797) (xy 81.132172 -376.060462)
			(xy 81.126363 -376.067598) (xy 81.119856 -376.084796) (xy 81.119472 -376.09399) (xy 81.119472 -376.25147)
			(xy 81.118949 -376.261593) (xy 81.111234 -376.280312) (xy 81.096958 -376.294669) (xy 81.078284 -376.302491)
			(xy 81.068164 -376.303032) (xy 80.351884 -376.303032) (xy 80.341778 -376.302529) (xy 80.323106 -376.294792)
			(xy 80.308813 -376.280501) (xy 80.301073 -376.26183) (xy 80.300576 -376.251724) (xy 80.300576 -376.09399)
			(xy 80.300176 -376.084802) (xy 80.293656 -376.067617) (xy 80.287876 -376.060462) (xy 80.266042 -376.034772)
			(xy 80.227954 -375.97914) (xy 80.196804 -375.919347) (xy 80.173039 -375.856254) (xy 80.157002 -375.790768)
			(xy 80.148924 -375.723833) (xy 80.148921 -375.656412) (xy 80.156994 -375.589476) (xy 80.173025 -375.523989)
			(xy 80.196785 -375.460894) (xy 80.227931 -375.401098) (xy 80.266015 -375.345464) (xy 80.287876 -375.319798)
			(xy 80.293653 -375.312639) (xy 80.30018 -375.295459) (xy 80.300576 -375.28627) (xy 80.300576 -374.794018)
			(xy 80.300163 -374.784831) (xy 80.293652 -374.767646) (xy 80.287876 -374.76049) (xy 80.265972 -374.734858)
			(xy 80.227886 -374.679218) (xy 80.196738 -374.619417) (xy 80.172977 -374.556316) (xy 80.156946 -374.490823)
			(xy 80.148873 -374.423882) (xy 76.870804 -374.423882) (xy 76.862772 -374.490638) (xy 76.846805 -374.556018)
			(xy 76.823138 -374.619021) (xy 76.79211 -374.678743) (xy 76.754168 -374.734329) (xy 76.732384 -374.759982)
			(xy 76.726568 -374.767114) (xy 76.720066 -374.784315) (xy 76.719684 -374.79351) (xy 76.719684 -375.286778)
			(xy 76.720108 -375.295964) (xy 76.726613 -375.313148) (xy 76.732384 -375.320306) (xy 76.754201 -375.345934)
			(xy 76.792147 -375.401525) (xy 76.823178 -375.461252) (xy 76.846848 -375.524259) (xy 76.862818 -375.589644)
			(xy 76.870859 -375.656469) (xy 76.870857 -375.723776) (xy 76.86281 -375.7906) (xy 76.846834 -375.855984)
			(xy 76.823159 -375.91899) (xy 76.792124 -375.978714) (xy 76.754173 -376.034302) (xy 76.732384 -376.059954)
			(xy 76.72658 -376.067094) (xy 76.72007 -376.084289) (xy 76.719684 -376.093482) (xy 76.719684 -376.25147)
			(xy 76.719212 -376.261637) (xy 76.711441 -376.280427) (xy 76.69707 -376.294812) (xy 76.678288 -376.302602)
			(xy 76.668122 -376.303032) (xy 75.951842 -376.303032) (xy 75.941669 -376.302601) (xy 75.92287 -376.294824)
			(xy 75.908482 -376.28044) (xy 75.900701 -376.261643) (xy 75.90028 -376.25147) (xy 75.90028 -376.093482)
			(xy 75.899883 -376.084293) (xy 75.893361 -376.067109) (xy 75.88758 -376.059954) (xy 75.865821 -376.034278)
			(xy 75.827868 -375.978696) (xy 75.796831 -375.918976) (xy 75.773155 -375.855975) (xy 75.757179 -375.790595)
			(xy 75.749132 -375.723774) (xy 75.749129 -375.656471) (xy 75.757171 -375.58965) (xy 75.773142 -375.524269)
			(xy 75.796813 -375.461265) (xy 75.827845 -375.401543) (xy 75.865793 -375.345958) (xy 75.88758 -375.320306)
			(xy 75.893354 -375.313145) (xy 75.899883 -375.295967) (xy 75.90028 -375.286778) (xy 75.90028 -374.79351)
			(xy 75.89987 -374.784323) (xy 75.893357 -374.767138) (xy 75.88758 -374.759982) (xy 75.865749 -374.734365)
			(xy 75.827799 -374.678774) (xy 75.796765 -374.619046) (xy 75.773093 -374.556037) (xy 75.757122 -374.49065)
			(xy 75.749081 -374.423823) (xy 72.471044 -374.423823) (xy 72.471044 -374.423879) (xy 72.462972 -374.490814)
			(xy 72.446941 -374.556301) (xy 72.423181 -374.619396) (xy 72.392034 -374.679191) (xy 72.35395 -374.734825)
			(xy 72.332088 -374.76049) (xy 72.326269 -374.76762) (xy 72.319768 -374.784822) (xy 72.319388 -374.794018)
			(xy 72.319388 -375.28627) (xy 72.319815 -375.295455) (xy 72.326317 -375.31264) (xy 72.332088 -375.319798)
			(xy 72.353982 -375.345439) (xy 72.39207 -375.401076) (xy 72.423221 -375.460876) (xy 72.446984 -375.523976)
			(xy 72.463017 -375.589468) (xy 72.471091 -375.656409) (xy 72.471088 -375.723836) (xy 72.463009 -375.790776)
			(xy 72.44697 -375.856267) (xy 72.423202 -375.919365) (xy 72.392047 -375.979162) (xy 72.353954 -376.034797)
			(xy 72.332088 -376.060462) (xy 72.326281 -376.0676) (xy 72.319773 -376.084796) (xy 72.319388 -376.09399)
			(xy 72.319388 -376.25147) (xy 72.31885 -376.261591) (xy 72.311137 -376.280307) (xy 72.296867 -376.294663)
			(xy 72.278198 -376.302488) (xy 72.26808 -376.303032) (xy 71.5518 -376.303032) (xy 71.54165 -376.302579)
			(xy 71.522904 -376.294789) (xy 71.508582 -376.280403) (xy 71.500876 -376.261622) (xy 71.500492 -376.25147)
			(xy 71.500492 -376.09399) (xy 71.500088 -376.084802) (xy 71.49357 -376.067618) (xy 71.487792 -376.060462)
			(xy 71.465958 -376.034772) (xy 71.427869 -375.979141) (xy 71.396717 -375.919348) (xy 71.372952 -375.856255)
			(xy 71.356914 -375.790769) (xy 71.348836 -375.723833) (xy 71.348833 -375.656412) (xy 71.356906 -375.589476)
			(xy 71.372938 -375.523989) (xy 71.396699 -375.460893) (xy 71.427845 -375.401098) (xy 71.46593 -375.345463)
			(xy 71.487792 -375.319798) (xy 71.493571 -375.31264) (xy 71.500096 -375.295459) (xy 71.500492 -375.28627)
			(xy 71.500492 -374.794018) (xy 71.500075 -374.784832) (xy 71.493566 -374.767647) (xy 71.487792 -374.76049)
			(xy 71.465887 -374.734859) (xy 71.4278 -374.679219) (xy 71.396652 -374.619418) (xy 71.37289 -374.556317)
			(xy 71.356858 -374.490824) (xy 71.348786 -374.423882) (xy 46.070774 -374.423882) (xy 46.062742 -374.490639)
			(xy 46.046773 -374.55602) (xy 46.023104 -374.619022) (xy 45.992075 -374.678745) (xy 45.95413 -374.73433)
			(xy 45.932344 -374.759982) (xy 45.926523 -374.76711) (xy 45.920025 -374.784314) (xy 45.919644 -374.79351)
			(xy 45.919644 -375.286778) (xy 45.920077 -375.295962) (xy 45.926576 -375.313146) (xy 45.932344 -375.320306)
			(xy 45.954162 -375.345934) (xy 45.992111 -375.401523) (xy 46.023144 -375.46125) (xy 46.046816 -375.524258)
			(xy 46.062787 -375.589643) (xy 46.070829 -375.656469) (xy 46.070826 -375.723776) (xy 46.062779 -375.790601)
			(xy 46.046802 -375.855985) (xy 46.023125 -375.918991) (xy 45.992088 -375.978716) (xy 45.954134 -376.034302)
			(xy 45.932344 -376.059954) (xy 45.926535 -376.06709) (xy 45.920029 -376.084288) (xy 45.919644 -376.093482)
			(xy 45.919644 -376.25147) (xy 45.919211 -376.261642) (xy 45.911433 -376.280439) (xy 45.897049 -376.294826)
			(xy 45.878254 -376.302609) (xy 45.868082 -376.303032) (xy 45.151802 -376.303032) (xy 45.141627 -376.302634)
			(xy 45.122826 -376.294844) (xy 45.10844 -376.28045) (xy 45.100661 -376.261645) (xy 45.10024 -376.25147)
			(xy 45.10024 -376.093482) (xy 45.09983 -376.084295) (xy 45.093315 -376.067111) (xy 45.08754 -376.059954)
			(xy 45.065782 -376.034277) (xy 45.027832 -375.978695) (xy 44.996798 -375.918974) (xy 44.973123 -375.855973)
			(xy 44.957148 -375.790594) (xy 44.949101 -375.723774) (xy 44.949099 -375.656471) (xy 44.95714 -375.589651)
			(xy 44.97311 -375.52427) (xy 44.996779 -375.461267) (xy 45.027809 -375.401544) (xy 45.065754 -375.345958)
			(xy 45.08754 -375.320306) (xy 45.093322 -375.31315) (xy 45.099844 -375.295968) (xy 45.10024 -375.286778)
			(xy 45.10024 -374.79351) (xy 45.099816 -374.784324) (xy 45.093311 -374.76714) (xy 45.08754 -374.759982)
			(xy 45.065711 -374.734364) (xy 45.027763 -374.678773) (xy 44.996732 -374.619044) (xy 44.973061 -374.556035)
			(xy 44.957091 -374.490649) (xy 44.94905 -374.423823) (xy 41.671014 -374.423823) (xy 41.671014 -374.423879)
			(xy 41.662941 -374.490816) (xy 41.646909 -374.556303) (xy 41.623147 -374.619398) (xy 41.591998 -374.679193)
			(xy 41.553911 -374.734826) (xy 41.532048 -374.76049) (xy 41.526224 -374.767616) (xy 41.519727 -374.784821)
			(xy 41.519348 -374.794018) (xy 41.519348 -375.28627) (xy 41.519784 -375.295454) (xy 41.526281 -375.312638)
			(xy 41.532048 -375.319798) (xy 41.553943 -375.345438) (xy 41.592035 -375.401075) (xy 41.623187 -375.460874)
			(xy 41.646952 -375.523974) (xy 41.662987 -375.589467) (xy 41.671061 -375.656409) (xy 41.671058 -375.723836)
			(xy 41.662978 -375.790777) (xy 41.646938 -375.856269) (xy 41.623168 -375.919367) (xy 41.592011 -375.979164)
			(xy 41.553916 -376.034798) (xy 41.532048 -376.060462) (xy 41.526236 -376.067596) (xy 41.519732 -376.084795)
			(xy 41.519348 -376.09399) (xy 41.519348 -376.25147) (xy 41.518849 -376.261596) (xy 41.511129 -376.280319)
			(xy 41.496846 -376.294677) (xy 41.478164 -376.302495) (xy 41.46804 -376.303032) (xy 40.75176 -376.303032)
			(xy 40.741607 -376.302612) (xy 40.72286 -376.294809) (xy 40.708539 -376.280413) (xy 40.700835 -376.261625)
			(xy 40.700452 -376.25147) (xy 40.700452 -376.09399) (xy 40.700035 -376.084804) (xy 40.693525 -376.06762)
			(xy 40.687752 -376.060462) (xy 40.665916 -376.034773) (xy 40.627823 -375.979143) (xy 40.596668 -375.919351)
			(xy 40.5729 -375.856257) (xy 40.55686 -375.79077) (xy 40.548781 -375.723834) (xy 40.548779 -375.656411)
			(xy 40.556852 -375.589474) (xy 40.572886 -375.523986) (xy 40.596649 -375.46089) (xy 40.627799 -375.401095)
			(xy 40.665888 -375.345462) (xy 40.687752 -375.319798) (xy 40.693538 -375.312646) (xy 40.700058 -375.29546)
			(xy 40.700452 -375.28627) (xy 40.700452 -374.794018) (xy 40.700022 -374.784833) (xy 40.693521 -374.767649)
			(xy 40.687752 -374.76049) (xy 40.665845 -374.73486) (xy 40.627754 -374.679221) (xy 40.596602 -374.619421)
			(xy 40.572838 -374.556319) (xy 40.556804 -374.490825) (xy 40.548731 -374.423882) (xy 37.271223 -374.423882)
			(xy 37.263151 -374.490815) (xy 37.247118 -374.556302) (xy 37.223357 -374.619398) (xy 37.192209 -374.679192)
			(xy 37.154123 -374.734826) (xy 37.13226 -374.76049) (xy 37.126438 -374.767617) (xy 37.119939 -374.784822)
			(xy 37.11956 -374.794018) (xy 37.11956 -375.28627) (xy 37.119994 -375.295454) (xy 37.126492 -375.312639)
			(xy 37.13226 -375.319798) (xy 37.154155 -375.345438) (xy 37.192245 -375.401075) (xy 37.223397 -375.460875)
			(xy 37.247161 -375.523975) (xy 37.263196 -375.589467) (xy 37.27127 -375.656409) (xy 37.271267 -375.723836)
			(xy 37.263188 -375.790777) (xy 37.247148 -375.856268) (xy 37.223379 -375.919367) (xy 37.192222 -375.979163)
			(xy 37.154127 -376.034797) (xy 37.13226 -376.060462) (xy 37.12645 -376.067597) (xy 37.119944 -376.084796)
			(xy 37.11956 -376.09399) (xy 37.11956 -376.25147) (xy 37.119049 -376.261595) (xy 37.111331 -376.280315)
			(xy 37.097052 -376.294673) (xy 37.078374 -376.302493) (xy 37.068252 -376.303032) (xy 36.351972 -376.303032)
			(xy 36.34182 -376.302602) (xy 36.323073 -376.294803) (xy 36.308752 -376.28041) (xy 36.301047 -376.261624)
			(xy 36.300664 -376.25147) (xy 36.300664 -376.09399) (xy 36.300244 -376.084804) (xy 36.293736 -376.06762)
			(xy 36.287964 -376.060462) (xy 36.266131 -376.034772) (xy 36.228044 -375.97914) (xy 36.196894 -375.919347)
			(xy 36.173129 -375.856253) (xy 36.157093 -375.790768) (xy 36.149015 -375.723833) (xy 36.149012 -375.656412)
			(xy 36.157085 -375.589477) (xy 36.173116 -375.52399) (xy 36.196875 -375.460894) (xy 36.22802 -375.401099)
			(xy 36.266103 -375.345464) (xy 36.287964 -375.319798) (xy 36.293752 -375.312647) (xy 36.30027 -375.295461)
			(xy 36.300664 -375.28627) (xy 36.300664 -374.794018) (xy 36.300231 -374.784834) (xy 36.293732 -374.76765)
			(xy 36.287964 -374.76049) (xy 36.26606 -374.734858) (xy 36.227975 -374.679218) (xy 36.196828 -374.619417)
			(xy 36.173068 -374.556316) (xy 36.157036 -374.490823) (xy 36.148964 -374.423882) (xy 32.870895 -374.423882)
			(xy 32.862863 -374.490639) (xy 32.846895 -374.556018) (xy 32.823227 -374.619021) (xy 32.7922 -374.678743)
			(xy 32.754257 -374.73433) (xy 32.732472 -374.759982) (xy 32.726654 -374.767112) (xy 32.720153 -374.784314)
			(xy 32.719772 -374.79351) (xy 32.719772 -375.286778) (xy 32.720199 -375.295963) (xy 32.726702 -375.313147)
			(xy 32.732472 -375.320306) (xy 32.754289 -375.345934) (xy 32.792236 -375.401524) (xy 32.823268 -375.461251)
			(xy 32.846938 -375.524259) (xy 32.862909 -375.589644) (xy 32.87095 -375.656469) (xy 32.870948 -375.723776)
			(xy 32.862901 -375.790601) (xy 32.846925 -375.855984) (xy 32.823249 -375.91899) (xy 32.792213 -375.978715)
			(xy 32.754261 -376.034302) (xy 32.732472 -376.059954) (xy 32.726666 -376.067093) (xy 32.720158 -376.084288)
			(xy 32.719772 -376.093482) (xy 32.719772 -376.25147) (xy 32.719312 -376.261638) (xy 32.711538 -376.28043)
			(xy 32.697164 -376.294816) (xy 32.678378 -376.302604) (xy 32.66821 -376.303032) (xy 31.95193 -376.303032)
			(xy 31.941757 -376.302611) (xy 31.922957 -376.29483) (xy 31.90857 -376.280443) (xy 31.900789 -376.261643)
			(xy 31.900368 -376.25147) (xy 31.900368 -376.093482) (xy 31.899951 -376.084296) (xy 31.89344 -376.067112)
			(xy 31.887668 -376.059954) (xy 31.865909 -376.034278) (xy 31.827957 -375.978696) (xy 31.796921 -375.918976)
			(xy 31.773245 -375.855974) (xy 31.75727 -375.790595) (xy 31.749223 -375.723774) (xy 31.74922 -375.656471)
			(xy 31.757261 -375.58965) (xy 31.773232 -375.524269) (xy 31.796903 -375.461266) (xy 31.827934 -375.401543)
			(xy 31.865881 -375.345958) (xy 31.887668 -375.320306) (xy 31.893453 -375.313153) (xy 31.899973 -375.295968)
			(xy 31.900368 -375.286778) (xy 31.900368 -374.79351) (xy 31.899938 -374.784325) (xy 31.893436 -374.767142)
			(xy 31.887668 -374.759982) (xy 31.865838 -374.734364) (xy 31.827888 -374.678774) (xy 31.796855 -374.619046)
			(xy 31.773184 -374.556036) (xy 31.757213 -374.49065) (xy 31.749171 -374.423823) (xy 28.471155 -374.423823)
			(xy 28.471155 -374.42387) (xy 28.463079 -374.490809) (xy 28.447044 -374.556297) (xy 28.423279 -374.619394)
			(xy 28.392129 -374.67919) (xy 28.35404 -374.734825) (xy 28.332176 -374.76049) (xy 28.326356 -374.767618)
			(xy 28.319856 -374.784822) (xy 28.319476 -374.794018) (xy 28.319476 -375.28627) (xy 28.319906 -375.295455)
			(xy 28.326407 -375.312639) (xy 28.332176 -375.319798) (xy 28.35407 -375.345439) (xy 28.39216 -375.401076)
			(xy 28.42331 -375.460875) (xy 28.447074 -375.523976) (xy 28.463108 -375.589468) (xy 28.471182 -375.656409)
			(xy 28.471179 -375.723836) (xy 28.4631 -375.790777) (xy 28.447061 -375.856268) (xy 28.423292 -375.919366)
			(xy 28.392136 -375.979163) (xy 28.354043 -376.034797) (xy 28.332176 -376.060462) (xy 28.326368 -376.067599)
			(xy 28.319861 -376.084796) (xy 28.319476 -376.09399) (xy 28.319476 -376.25147) (xy 28.31895 -376.261593)
			(xy 28.311235 -376.28031) (xy 28.29696 -376.294667) (xy 28.278288 -376.30249) (xy 28.268168 -376.303032)
			(xy 27.551888 -376.303032) (xy 27.541783 -376.302525) (xy 27.52311 -376.29479) (xy 27.508817 -376.2805)
			(xy 27.501077 -376.261829) (xy 27.50058 -376.251724) (xy 27.50058 -376.09399) (xy 27.500179 -376.084802)
			(xy 27.493659 -376.067617) (xy 27.48788 -376.060462) (xy 27.466046 -376.034772) (xy 27.427958 -375.979141)
			(xy 27.396807 -375.919348) (xy 27.373042 -375.856254) (xy 27.357005 -375.790768) (xy 27.348927 -375.723833)
			(xy 27.348924 -375.656412) (xy 27.356997 -375.589476) (xy 27.373029 -375.523989) (xy 27.396789 -375.460894)
			(xy 27.427935 -375.401098) (xy 27.466019 -375.345464) (xy 27.48788 -375.319798) (xy 27.493658 -375.312639)
			(xy 27.500184 -375.295459) (xy 27.50058 -375.28627) (xy 27.50058 -374.794018) (xy 27.500166 -374.784831)
			(xy 27.493655 -374.767646) (xy 27.48788 -374.76049) (xy 27.466014 -374.734827) (xy 27.427924 -374.679192)
			(xy 27.396773 -374.619396) (xy 27.373009 -374.556299) (xy 27.356973 -374.490809) (xy 27.348897 -374.423871)
			(xy 0.509016 -374.423871) (xy 0.509016 -376.756551) (xy 29.549067 -376.756551) (xy 29.557111 -376.689729)
			(xy 29.573083 -376.624347) (xy 29.596754 -376.561343) (xy 29.627786 -376.501619) (xy 29.665733 -376.446032)
			(xy 29.68752 -376.42038) (xy 29.69331 -376.41323) (xy 29.699828 -376.396043) (xy 29.70022 -376.386852)
			(xy 29.70022 -375.893584) (xy 29.699813 -375.884397) (xy 29.693297 -375.867212) (xy 29.68752 -375.860056)
			(xy 29.665765 -375.834378) (xy 29.627816 -375.778794) (xy 29.596782 -375.719074) (xy 29.573109 -375.656073)
			(xy 29.557134 -375.590694) (xy 29.549088 -375.523875) (xy 29.549085 -375.456573) (xy 29.557126 -375.389753)
			(xy 29.573095 -375.324373) (xy 29.596763 -375.26137) (xy 29.627791 -375.201647) (xy 29.665735 -375.146061)
			(xy 29.68752 -375.120408) (xy 29.693298 -375.11325) (xy 29.699823 -375.096069) (xy 29.70022 -375.08688)
			(xy 29.70022 -374.928638) (xy 29.700695 -374.918471) (xy 29.708464 -374.899681) (xy 29.722834 -374.885295)
			(xy 29.741616 -374.877506) (xy 29.751782 -374.877076) (xy 30.468062 -374.877076) (xy 30.478236 -374.877496)
			(xy 30.497037 -374.885276) (xy 30.511424 -374.899663) (xy 30.519204 -374.918464) (xy 30.519624 -374.928638)
			(xy 30.519624 -375.08688) (xy 30.520038 -375.096067) (xy 30.526548 -375.113252) (xy 30.532324 -375.120408)
			(xy 30.554144 -375.146034) (xy 30.592094 -375.201623) (xy 30.623128 -375.26135) (xy 30.646801 -375.324358)
			(xy 30.662773 -375.389744) (xy 30.670815 -375.45657) (xy 30.670812 -375.523878) (xy 30.662764 -375.590704)
			(xy 30.646787 -375.656088) (xy 30.623109 -375.719094) (xy 30.59207 -375.778818) (xy 30.554115 -375.834404)
			(xy 30.532324 -375.860056) (xy 30.526524 -375.867199) (xy 30.520011 -375.884391) (xy 30.519624 -375.893584)
			(xy 30.519624 -376.386852) (xy 30.520052 -376.396037) (xy 30.526553 -376.413222) (xy 30.532324 -376.42038)
			(xy 30.554117 -376.446028) (xy 30.592068 -376.501615) (xy 30.623103 -376.561338) (xy 30.646777 -376.624343)
			(xy 30.662751 -376.689726) (xy 30.670795 -376.75655) (xy 30.670795 -376.823856) (xy 30.670788 -376.823915)
			(xy 33.948836 -376.823915) (xy 33.948836 -376.756491) (xy 33.956911 -376.689553) (xy 33.972947 -376.624064)
			(xy 33.996711 -376.560967) (xy 34.027862 -376.501171) (xy 34.065952 -376.445537) (xy 34.087816 -376.419872)
			(xy 34.093609 -376.412724) (xy 34.100125 -376.395536) (xy 34.100516 -376.386344) (xy 34.100516 -375.894092)
			(xy 34.100106 -375.884905) (xy 34.093592 -375.867721) (xy 34.087816 -375.860564) (xy 34.065983 -375.834873)
			(xy 34.027892 -375.779243) (xy 33.996739 -375.71945) (xy 33.972973 -375.656357) (xy 33.956934 -375.59087)
			(xy 33.948856 -375.523935) (xy 33.948853 -375.456513) (xy 33.956926 -375.389577) (xy 33.972958 -375.324089)
			(xy 33.99672 -375.260994) (xy 34.027867 -375.201199) (xy 34.065953 -375.145565) (xy 34.087816 -375.1199)
			(xy 34.093597 -375.112744) (xy 34.10012 -375.095562) (xy 34.100516 -375.086372) (xy 34.100516 -374.928638)
			(xy 34.101057 -374.918517) (xy 34.108768 -374.899801) (xy 34.123038 -374.885444) (xy 34.141706 -374.87762)
			(xy 34.151824 -374.877076) (xy 34.868104 -374.877076) (xy 34.878255 -374.877518) (xy 34.897003 -374.88531)
			(xy 34.911325 -374.8997) (xy 34.919029 -374.918485) (xy 34.919412 -374.928638) (xy 34.919412 -375.086372)
			(xy 34.919833 -375.095558) (xy 34.926339 -375.112743) (xy 34.932112 -375.1199) (xy 34.954007 -375.14554)
			(xy 34.992094 -375.201178) (xy 35.023243 -375.260978) (xy 35.047004 -375.324078) (xy 35.063037 -375.38957)
			(xy 35.07111 -375.456511) (xy 35.071108 -375.523937) (xy 35.063029 -375.590877) (xy 35.04699 -375.656368)
			(xy 35.023223 -375.719466) (xy 34.992069 -375.779263) (xy 34.953977 -375.834899) (xy 34.932112 -375.860564)
			(xy 34.926307 -375.867703) (xy 34.919797 -375.884898) (xy 34.919412 -375.894092) (xy 34.919412 -376.386344)
			(xy 34.919798 -376.395534) (xy 34.926328 -376.412718) (xy 34.932112 -376.419872) (xy 34.953979 -376.445534)
			(xy 34.992067 -376.501169) (xy 35.023217 -376.560966) (xy 35.046981 -376.624063) (xy 35.063015 -376.689553)
			(xy 35.071091 -376.756491) (xy 35.071091 -376.756551) (xy 38.349155 -376.756551) (xy 38.357198 -376.689729)
			(xy 38.37317 -376.624348) (xy 38.396841 -376.561343) (xy 38.427872 -376.50162) (xy 38.465818 -376.446033)
			(xy 38.487604 -376.42038) (xy 38.493392 -376.413229) (xy 38.499912 -376.396043) (xy 38.500304 -376.386852)
			(xy 38.500304 -375.893584) (xy 38.499901 -375.884396) (xy 38.493382 -375.867212) (xy 38.487604 -375.860056)
			(xy 38.465849 -375.834378) (xy 38.427901 -375.778794) (xy 38.396869 -375.719074) (xy 38.373195 -375.656073)
			(xy 38.357221 -375.590694) (xy 38.349175 -375.523875) (xy 38.349172 -375.456573) (xy 38.357213 -375.389753)
			(xy 38.373181 -375.324373) (xy 38.396849 -375.26137) (xy 38.427876 -375.201647) (xy 38.465819 -375.146061)
			(xy 38.487604 -375.120408) (xy 38.49338 -375.113248) (xy 38.499907 -375.096069) (xy 38.500304 -375.08688)
			(xy 38.500304 -374.928638) (xy 38.500794 -374.918473) (xy 38.50856 -374.899686) (xy 38.522925 -374.885301)
			(xy 38.541702 -374.877508) (xy 38.551866 -374.877076) (xy 39.268146 -374.877076) (xy 39.278311 -374.877497)
			(xy 39.297089 -374.885293) (xy 39.311454 -374.899682) (xy 39.31922 -374.918472) (xy 39.319708 -374.928638)
			(xy 39.319708 -375.08688) (xy 39.320126 -375.096066) (xy 39.326634 -375.113251) (xy 39.332408 -375.120408)
			(xy 39.354229 -375.146034) (xy 39.39218 -375.201623) (xy 39.423215 -375.261349) (xy 39.446888 -375.324357)
			(xy 39.462861 -375.389743) (xy 39.470903 -375.45657) (xy 39.4709 -375.523878) (xy 39.462852 -375.590704)
			(xy 39.446874 -375.656089) (xy 39.423195 -375.719095) (xy 39.392155 -375.778819) (xy 39.354199 -375.834405)
			(xy 39.332408 -375.860056) (xy 39.326606 -375.867197) (xy 39.320094 -375.884391) (xy 39.319708 -375.893584)
			(xy 39.319708 -376.386852) (xy 39.320139 -376.396037) (xy 39.326638 -376.413222) (xy 39.332408 -376.42038)
			(xy 39.354201 -376.446028) (xy 39.392153 -376.501614) (xy 39.423189 -376.561338) (xy 39.446864 -376.624343)
			(xy 39.462839 -376.689726) (xy 39.470883 -376.75655) (xy 39.470883 -376.823856) (xy 39.470876 -376.823915)
			(xy 42.748924 -376.823915) (xy 42.748924 -376.756491) (xy 42.756999 -376.689553) (xy 42.773034 -376.624064)
			(xy 42.796798 -376.560968) (xy 42.827948 -376.501172) (xy 42.866036 -376.445537) (xy 42.8879 -376.419872)
			(xy 42.893691 -376.412723) (xy 42.900209 -376.395535) (xy 42.9006 -376.386344) (xy 42.9006 -375.894092)
			(xy 42.900194 -375.884904) (xy 42.893677 -375.86772) (xy 42.8879 -375.860564) (xy 42.866067 -375.834873)
			(xy 42.827978 -375.779242) (xy 42.796826 -375.719449) (xy 42.77306 -375.656356) (xy 42.757022 -375.59087)
			(xy 42.748944 -375.523935) (xy 42.748941 -375.456513) (xy 42.757013 -375.389577) (xy 42.773045 -375.32409)
			(xy 42.796806 -375.260995) (xy 42.827953 -375.201199) (xy 42.866038 -375.145565) (xy 42.8879 -375.1199)
			(xy 42.893679 -375.112742) (xy 42.900204 -375.095561) (xy 42.9006 -375.086372) (xy 42.9006 -374.928638)
			(xy 42.901157 -374.918519) (xy 42.908865 -374.899806) (xy 42.923129 -374.88545) (xy 42.941792 -374.877622)
			(xy 42.951908 -374.877076) (xy 43.668188 -374.877076) (xy 43.678338 -374.877531) (xy 43.697086 -374.885318)
			(xy 43.711409 -374.899704) (xy 43.719113 -374.918486) (xy 43.719496 -374.928638) (xy 43.719496 -375.086372)
			(xy 43.719921 -375.095558) (xy 43.726424 -375.112742) (xy 43.732196 -375.1199) (xy 43.754092 -375.145539)
			(xy 43.79218 -375.201177) (xy 43.823329 -375.260977) (xy 43.847092 -375.324077) (xy 43.863125 -375.38957)
			(xy 43.871198 -375.456511) (xy 43.871196 -375.523937) (xy 43.863116 -375.590878) (xy 43.847077 -375.656369)
			(xy 43.823309 -375.719467) (xy 43.792155 -375.779264) (xy 43.754062 -375.834899) (xy 43.732196 -375.860564)
			(xy 43.726389 -375.867702) (xy 43.719881 -375.884898) (xy 43.719496 -375.894092) (xy 43.719496 -376.386344)
			(xy 43.719886 -376.395533) (xy 43.726414 -376.412717) (xy 43.732196 -376.419872) (xy 43.754064 -376.445534)
			(xy 43.792153 -376.501169) (xy 43.823304 -376.560965) (xy 43.847068 -376.624063) (xy 43.863103 -376.689552)
			(xy 43.871179 -376.756491) (xy 43.871178 -376.823856) (xy 47.149219 -376.823856) (xy 47.149219 -376.75655)
			(xy 47.157264 -376.689727) (xy 47.173238 -376.624344) (xy 47.196912 -376.56134) (xy 47.227948 -376.501617)
			(xy 47.265899 -376.446031) (xy 47.287688 -376.42038) (xy 47.293474 -376.413227) (xy 47.299995 -376.396043)
			(xy 47.300388 -376.386852) (xy 47.300388 -375.893584) (xy 47.299988 -375.884396) (xy 47.293468 -375.867211)
			(xy 47.287688 -375.860056) (xy 47.26593 -375.834379) (xy 47.227977 -375.778797) (xy 47.19694 -375.719077)
			(xy 47.173263 -375.656076) (xy 47.157287 -375.590696) (xy 47.149239 -375.523876) (xy 47.149236 -375.456572)
			(xy 47.157278 -375.389751) (xy 47.173249 -375.32437) (xy 47.19692 -375.261367) (xy 47.227952 -375.201644)
			(xy 47.265901 -375.146059) (xy 47.287688 -375.120408) (xy 47.293462 -375.113247) (xy 47.299991 -375.096069)
			(xy 47.300388 -375.08688) (xy 47.300388 -374.928892) (xy 47.300815 -374.918739) (xy 47.308611 -374.899989)
			(xy 47.323006 -374.885666) (xy 47.341795 -374.877965) (xy 47.35195 -374.877584) (xy 48.06823 -374.877584)
			(xy 48.078364 -374.878003) (xy 48.097094 -374.885749) (xy 48.111451 -374.900056) (xy 48.119261 -374.91876)
			(xy 48.119792 -374.928892) (xy 48.119792 -375.08688) (xy 48.120214 -375.096066) (xy 48.12672 -375.11325)
			(xy 48.132492 -375.120408) (xy 48.15431 -375.146035) (xy 48.192256 -375.201626) (xy 48.223286 -375.261353)
			(xy 48.246956 -375.324361) (xy 48.262926 -375.389746) (xy 48.270967 -375.456571) (xy 48.270964 -375.523878)
			(xy 48.262917 -375.590702) (xy 48.246942 -375.656085) (xy 48.223267 -375.719091) (xy 48.192231 -375.778816)
			(xy 48.154281 -375.834403) (xy 48.132492 -375.860056) (xy 48.126688 -375.867196) (xy 48.120178 -375.884391)
			(xy 48.119792 -375.893584) (xy 48.119792 -376.386852) (xy 48.120227 -376.396037) (xy 48.126724 -376.413221)
			(xy 48.132492 -376.42038) (xy 48.154283 -376.446029) (xy 48.192229 -376.501617) (xy 48.223261 -376.561341)
			(xy 48.246932 -376.624346) (xy 48.262904 -376.689728) (xy 48.270947 -376.756551) (xy 73.548976 -376.756551)
			(xy 73.55702 -376.689728) (xy 73.572992 -376.624347) (xy 73.596664 -376.561342) (xy 73.627697 -376.501619)
			(xy 73.665645 -376.446032) (xy 73.687432 -376.42038) (xy 73.693224 -376.413231) (xy 73.699741 -376.396043)
			(xy 73.700132 -376.386852) (xy 73.700132 -375.893584) (xy 73.699722 -375.884397) (xy 73.693208 -375.867213)
			(xy 73.687432 -375.860056) (xy 73.665676 -375.834378) (xy 73.627727 -375.778795) (xy 73.596693 -375.719075)
			(xy 73.573018 -375.656074) (xy 73.557043 -375.590695) (xy 73.548997 -375.523875) (xy 73.548994 -375.456573)
			(xy 73.557035 -375.389753) (xy 73.573004 -375.324372) (xy 73.596673 -375.261369) (xy 73.627702 -375.201647)
			(xy 73.665647 -375.14606) (xy 73.687432 -375.120408) (xy 73.693212 -375.113251) (xy 73.699736 -375.096069)
			(xy 73.700132 -375.08688) (xy 73.700132 -374.928638) (xy 73.700595 -374.91847) (xy 73.708366 -374.899677)
			(xy 73.72274 -374.885291) (xy 73.741526 -374.877504) (xy 73.751694 -374.877076) (xy 74.467974 -374.877076)
			(xy 74.478149 -374.877486) (xy 74.49695 -374.88527) (xy 74.511337 -374.89966) (xy 74.519116 -374.918463)
			(xy 74.519536 -374.928638) (xy 74.519536 -375.08688) (xy 74.51997 -375.096064) (xy 74.526469 -375.113248)
			(xy 74.532236 -375.120408) (xy 74.554056 -375.146034) (xy 74.592006 -375.201623) (xy 74.623039 -375.26135)
			(xy 74.646711 -375.324358) (xy 74.662683 -375.389744) (xy 74.670725 -375.45657) (xy 74.670722 -375.523878)
			(xy 74.662674 -375.590703) (xy 74.646697 -375.656088) (xy 74.623019 -375.719094) (xy 74.591981 -375.778818)
			(xy 74.554027 -375.834404) (xy 74.532236 -375.860056) (xy 74.526425 -375.867191) (xy 74.519921 -375.88439)
			(xy 74.519536 -375.893584) (xy 74.519536 -376.386852) (xy 74.519983 -376.396035) (xy 74.526473 -376.413219)
			(xy 74.532236 -376.42038) (xy 74.554028 -376.446029) (xy 74.591979 -376.501615) (xy 74.623013 -376.561339)
			(xy 74.646687 -376.624344) (xy 74.66266 -376.689727) (xy 74.670704 -376.75655) (xy 74.670704 -376.823856)
			(xy 74.670697 -376.823915) (xy 77.948745 -376.823915) (xy 77.948745 -376.756491) (xy 77.956821 -376.689553)
			(xy 77.972856 -376.624063) (xy 77.996621 -376.560967) (xy 78.027773 -376.501171) (xy 78.065863 -376.445537)
			(xy 78.087728 -376.419872) (xy 78.093523 -376.412726) (xy 78.100038 -376.395536) (xy 78.100428 -376.386344)
			(xy 78.100428 -375.894092) (xy 78.100016 -375.884905) (xy 78.093503 -375.867721) (xy 78.087728 -375.860564)
			(xy 78.065894 -375.834873) (xy 78.027803 -375.779243) (xy 77.996649 -375.719451) (xy 77.972882 -375.656357)
			(xy 77.956844 -375.590871) (xy 77.948765 -375.523935) (xy 77.948762 -375.456513) (xy 77.956835 -375.389577)
			(xy 77.972868 -375.324089) (xy 77.99663 -375.260993) (xy 78.027778 -375.201198) (xy 78.065865 -375.145565)
			(xy 78.087728 -375.1199) (xy 78.093511 -375.112745) (xy 78.100033 -375.095562) (xy 78.100428 -375.086372)
			(xy 78.100428 -374.928638) (xy 78.100958 -374.918515) (xy 78.108671 -374.899797) (xy 78.122944 -374.88544)
			(xy 78.141616 -374.877618) (xy 78.151736 -374.877076) (xy 78.868016 -374.877076) (xy 78.878123 -374.877572)
			(xy 78.896797 -374.88531) (xy 78.91109 -374.899603) (xy 78.918828 -374.918277) (xy 78.919324 -374.928384)
			(xy 78.919324 -375.086372) (xy 78.919742 -375.095558) (xy 78.92625 -375.112743) (xy 78.932024 -375.1199)
			(xy 78.953919 -375.14554) (xy 78.992005 -375.201178) (xy 79.023153 -375.260978) (xy 79.046914 -375.324079)
			(xy 79.062947 -375.38957) (xy 79.07102 -375.456511) (xy 79.071017 -375.523937) (xy 79.062938 -375.590877)
			(xy 79.0469 -375.656367) (xy 79.023133 -375.719466) (xy 78.99198 -375.779263) (xy 78.953889 -375.834898)
			(xy 78.932024 -375.860564) (xy 78.926221 -375.867704) (xy 78.919709 -375.884898) (xy 78.919324 -375.894092)
			(xy 78.919324 -376.386344) (xy 78.919708 -376.395534) (xy 78.926239 -376.412718) (xy 78.932024 -376.419872)
			(xy 78.953891 -376.445534) (xy 78.991978 -376.50117) (xy 79.023127 -376.560967) (xy 79.04689 -376.624064)
			(xy 79.062925 -376.689553) (xy 79.071 -376.756491) (xy 79.071 -376.756551) (xy 82.349064 -376.756551)
			(xy 82.357108 -376.689729) (xy 82.373079 -376.624347) (xy 82.396751 -376.561343) (xy 82.427782 -376.501619)
			(xy 82.465729 -376.446032) (xy 82.487516 -376.42038) (xy 82.493305 -376.41323) (xy 82.499824 -376.396043)
			(xy 82.500216 -376.386852) (xy 82.500216 -375.893584) (xy 82.49981 -375.884396) (xy 82.493293 -375.867212)
			(xy 82.487516 -375.860056) (xy 82.46576 -375.834378) (xy 82.427812 -375.778795) (xy 82.396779 -375.719074)
			(xy 82.373105 -375.656073) (xy 82.357131 -375.590694) (xy 82.349084 -375.523875) (xy 82.349081 -375.456573)
			(xy 82.357122 -375.389753) (xy 82.373091 -375.324373) (xy 82.396759 -375.26137) (xy 82.427787 -375.201647)
			(xy 82.465731 -375.14606) (xy 82.487516 -375.120408) (xy 82.493294 -375.113249) (xy 82.499819 -375.096069)
			(xy 82.500216 -375.08688) (xy 82.500216 -374.928638) (xy 82.500694 -374.918472) (xy 82.508463 -374.899682)
			(xy 82.522832 -374.885297) (xy 82.541612 -374.877506) (xy 82.551778 -374.877076) (xy 83.268058 -374.877076)
			(xy 83.278232 -374.877499) (xy 83.297033 -374.885277) (xy 83.31142 -374.899664) (xy 83.3192 -374.918464)
			(xy 83.31962 -374.928638) (xy 83.31962 -375.08688) (xy 83.320035 -375.096067) (xy 83.326545 -375.113251)
			(xy 83.33232 -375.120408) (xy 83.35414 -375.146034) (xy 83.392091 -375.201623) (xy 83.423125 -375.26135)
			(xy 83.446798 -375.324358) (xy 83.46277 -375.389744) (xy 83.470812 -375.45657) (xy 83.470809 -375.523878)
			(xy 83.462761 -375.590704) (xy 83.446784 -375.656088) (xy 83.423105 -375.719094) (xy 83.392066 -375.778818)
			(xy 83.354111 -375.834404) (xy 83.33232 -375.860056) (xy 83.326519 -375.867199) (xy 83.320007 -375.884391)
			(xy 83.31962 -375.893584) (xy 83.31962 -376.386852) (xy 83.320049 -376.396037) (xy 83.326549 -376.413222)
			(xy 83.33232 -376.42038) (xy 83.354113 -376.446028) (xy 83.392064 -376.501614) (xy 83.4231 -376.561338)
			(xy 83.446774 -376.624343) (xy 83.462748 -376.689726) (xy 83.470792 -376.75655) (xy 83.470792 -376.823856)
			(xy 83.470785 -376.823915) (xy 86.748833 -376.823915) (xy 86.748833 -376.756491) (xy 86.756908 -376.689553)
			(xy 86.772944 -376.624064) (xy 86.796708 -376.560967) (xy 86.827859 -376.501171) (xy 86.865948 -376.445537)
			(xy 86.887812 -376.419872) (xy 86.893604 -376.412724) (xy 86.900121 -376.395536) (xy 86.900512 -376.386344)
			(xy 86.900512 -375.894092) (xy 86.900103 -375.884905) (xy 86.893588 -375.86772) (xy 86.887812 -375.860564)
			(xy 86.865979 -375.834873) (xy 86.827889 -375.779242) (xy 86.796736 -375.71945) (xy 86.772969 -375.656356)
			(xy 86.756931 -375.59087) (xy 86.748853 -375.523935) (xy 86.74885 -375.456513) (xy 86.756923 -375.389577)
			(xy 86.772955 -375.32409) (xy 86.796716 -375.260994) (xy 86.827864 -375.201199) (xy 86.86595 -375.145565)
			(xy 86.887812 -375.1199) (xy 86.893592 -375.112743) (xy 86.900116 -375.095562) (xy 86.900512 -375.086372)
			(xy 86.900512 -374.928638) (xy 86.901057 -374.918517) (xy 86.908767 -374.899802) (xy 86.923035 -374.885446)
			(xy 86.941702 -374.87762) (xy 86.95182 -374.877076) (xy 87.6681 -374.877076) (xy 87.678206 -374.877585)
			(xy 87.696879 -374.885318) (xy 87.711173 -374.899607) (xy 87.718912 -374.918278) (xy 87.719408 -374.928384)
			(xy 87.719408 -375.086372) (xy 87.71983 -375.095558) (xy 87.726335 -375.112743) (xy 87.732108 -375.1199)
			(xy 87.754003 -375.145539) (xy 87.79209 -375.201178) (xy 87.798441 -375.213371) (xy 104.681961 -375.213371)
			(xy 104.681961 -375.153429) (xy 104.689785 -375.094001) (xy 104.7053 -375.036103) (xy 104.72824 -374.980725)
			(xy 104.758212 -374.928815) (xy 104.794703 -374.881262) (xy 104.837089 -374.838879) (xy 104.884645 -374.802391)
			(xy 104.936557 -374.772424) (xy 104.991937 -374.749489) (xy 105.049837 -374.733978) (xy 105.109265 -374.726159)
			(xy 105.139236 -374.725692) (xy 106.002836 -374.725692) (xy 106.032802 -374.726184) (xy 106.092221 -374.734011)
			(xy 106.15011 -374.749527) (xy 106.205479 -374.772465) (xy 106.25738 -374.802434) (xy 106.304926 -374.838921)
			(xy 106.347303 -374.881301) (xy 106.383786 -374.92885) (xy 106.413751 -374.980753) (xy 106.436685 -375.036124)
			(xy 106.452196 -375.094014) (xy 106.460018 -375.153434) (xy 106.460018 -375.213366) (xy 106.452196 -375.272786)
			(xy 106.436685 -375.330676) (xy 106.413751 -375.386047) (xy 106.383786 -375.43795) (xy 106.347303 -375.485499)
			(xy 106.304926 -375.527879) (xy 106.25738 -375.564366) (xy 106.205479 -375.594335) (xy 106.15011 -375.617273)
			(xy 106.092221 -375.632789) (xy 106.032802 -375.640616) (xy 106.002836 -375.641108) (xy 105.139236 -375.641108)
			(xy 105.109265 -375.640641) (xy 105.049837 -375.632822) (xy 104.991937 -375.617311) (xy 104.936557 -375.594376)
			(xy 104.884645 -375.564409) (xy 104.837089 -375.527921) (xy 104.794703 -375.485538) (xy 104.758212 -375.437985)
			(xy 104.72824 -375.386075) (xy 104.7053 -375.330697) (xy 104.689785 -375.272799) (xy 104.681961 -375.213371)
			(xy 87.798441 -375.213371) (xy 87.823239 -375.260978) (xy 87.847001 -375.324078) (xy 87.863034 -375.38957)
			(xy 87.871107 -375.456511) (xy 87.871105 -375.523937) (xy 87.863026 -375.590877) (xy 87.846987 -375.656368)
			(xy 87.82322 -375.719466) (xy 87.792066 -375.779263) (xy 87.753974 -375.834899) (xy 87.732108 -375.860564)
			(xy 87.726303 -375.867703) (xy 87.719793 -375.884898) (xy 87.719408 -375.894092) (xy 87.719408 -376.386344)
			(xy 87.719795 -376.395534) (xy 87.726324 -376.412718) (xy 87.732108 -376.419872) (xy 87.753976 -376.445534)
			(xy 87.792064 -376.501169) (xy 87.823214 -376.560966) (xy 87.846977 -376.624063) (xy 87.863012 -376.689553)
			(xy 87.871088 -376.756491) (xy 87.871087 -376.823915) (xy 117.548863 -376.823915) (xy 117.548863 -376.756491)
			(xy 117.556939 -376.689552) (xy 117.572976 -376.624062) (xy 117.596742 -376.560965) (xy 117.627895 -376.50117)
			(xy 117.665986 -376.445536) (xy 117.687852 -376.419872) (xy 117.693649 -376.412728) (xy 117.700162 -376.395536)
			(xy 117.700552 -376.386344) (xy 117.700552 -375.894092) (xy 117.700134 -375.884906) (xy 117.693625 -375.867722)
			(xy 117.687852 -375.860564) (xy 117.666018 -375.834874) (xy 117.627925 -375.779244) (xy 117.59677 -375.719452)
			(xy 117.573001 -375.656358) (xy 117.556962 -375.590871) (xy 117.548883 -375.523935) (xy 117.54888 -375.456513)
			(xy 117.556953 -375.389576) (xy 117.572987 -375.324088) (xy 117.59675 -375.260992) (xy 117.6279 -375.201197)
			(xy 117.665988 -375.145564) (xy 117.687852 -375.1199) (xy 117.693638 -375.112747) (xy 117.700157 -375.095562)
			(xy 117.700552 -375.086372) (xy 117.700552 -374.928638) (xy 117.701058 -374.918512) (xy 117.708776 -374.89979)
			(xy 117.723056 -374.885432) (xy 117.741737 -374.877613) (xy 117.75186 -374.877076) (xy 118.46814 -374.877076)
			(xy 118.478294 -374.877488) (xy 118.497042 -374.885293) (xy 118.511363 -374.899691) (xy 118.519066 -374.918482)
			(xy 118.519448 -374.928638) (xy 118.519448 -375.086372) (xy 118.519883 -375.095556) (xy 118.526381 -375.11274)
			(xy 118.532148 -375.1199) (xy 118.554045 -375.145538) (xy 118.592136 -375.201176) (xy 118.623289 -375.260975)
			(xy 118.647053 -375.324075) (xy 118.663088 -375.389568) (xy 118.671162 -375.45651) (xy 118.671159 -375.523938)
			(xy 118.66308 -375.590879) (xy 118.647039 -375.656371) (xy 118.623269 -375.719469) (xy 118.592112 -375.779266)
			(xy 118.554016 -375.8349) (xy 118.532148 -375.860564) (xy 118.526335 -375.867698) (xy 118.519832 -375.884897)
			(xy 118.519448 -375.894092) (xy 118.519448 -376.386344) (xy 118.519849 -376.395532) (xy 118.52637 -376.412715)
			(xy 118.532148 -376.419872) (xy 118.554018 -376.445533) (xy 118.59211 -376.501167) (xy 118.623263 -376.560963)
			(xy 118.647029 -376.624061) (xy 118.663066 -376.689551) (xy 118.671143 -376.75649) (xy 118.671143 -376.756551)
			(xy 121.949182 -376.756551) (xy 121.957226 -376.689728) (xy 121.973199 -376.624346) (xy 121.996871 -376.561342)
			(xy 122.027904 -376.501618) (xy 122.065852 -376.446032) (xy 122.08764 -376.42038) (xy 122.093433 -376.413232)
			(xy 122.099949 -376.396044) (xy 122.10034 -376.386852) (xy 122.10034 -375.893584) (xy 122.099929 -375.884397)
			(xy 122.093415 -375.867213) (xy 122.08764 -375.860056) (xy 122.065884 -375.834378) (xy 122.027934 -375.778795)
			(xy 121.996899 -375.719075) (xy 121.973225 -375.656074) (xy 121.95725 -375.590695) (xy 121.949203 -375.523875)
			(xy 121.9492 -375.456573) (xy 121.957241 -375.389752) (xy 121.973211 -375.324372) (xy 121.99688 -375.261369)
			(xy 122.027909 -375.201646) (xy 122.065854 -375.14606) (xy 122.08764 -375.120408) (xy 122.093421 -375.113252)
			(xy 122.099944 -375.09607) (xy 122.10034 -375.08688) (xy 122.10034 -374.928638) (xy 122.100795 -374.918469)
			(xy 122.108568 -374.899674) (xy 122.122944 -374.885288) (xy 122.141733 -374.877502) (xy 122.151902 -374.877076)
			(xy 122.868182 -374.877076) (xy 122.878357 -374.877479) (xy 122.897159 -374.885265) (xy 122.911546 -374.899658)
			(xy 122.919325 -374.918463) (xy 122.919744 -374.928638) (xy 122.919744 -375.08688) (xy 122.920176 -375.096065)
			(xy 122.926676 -375.113249) (xy 122.932444 -375.120408) (xy 122.954264 -375.146034) (xy 122.992213 -375.201624)
			(xy 123.023246 -375.261351) (xy 123.046917 -375.324359) (xy 123.062889 -375.389744) (xy 123.070931 -375.45657)
			(xy 123.070928 -375.523878) (xy 123.06288 -375.590703) (xy 123.046903 -375.656087) (xy 123.023226 -375.719093)
			(xy 122.992188 -375.778818) (xy 122.954234 -375.834404) (xy 122.932444 -375.860056) (xy 122.926634 -375.867192)
			(xy 122.920129 -375.88439) (xy 122.919744 -375.893584) (xy 122.919744 -376.386852) (xy 122.92019 -376.396035)
			(xy 122.92668 -376.413219) (xy 122.932444 -376.42038) (xy 122.954236 -376.446029) (xy 122.992186 -376.501615)
			(xy 123.02322 -376.561339) (xy 123.046893 -376.624344) (xy 123.062866 -376.689727) (xy 123.07091 -376.75655)
			(xy 123.07091 -376.823856) (xy 123.070903 -376.823915) (xy 126.348951 -376.823915) (xy 126.348951 -376.756491)
			(xy 126.357027 -376.689552) (xy 126.373063 -376.624063) (xy 126.396828 -376.560966) (xy 126.42798 -376.50117)
			(xy 126.466071 -376.445537) (xy 126.487936 -376.419872) (xy 126.493732 -376.412726) (xy 126.500246 -376.395536)
			(xy 126.500636 -376.386344) (xy 126.500636 -375.894092) (xy 126.500222 -375.884905) (xy 126.49371 -375.867721)
			(xy 126.487936 -375.860564) (xy 126.466102 -375.834873) (xy 126.42801 -375.779243) (xy 126.396856 -375.719451)
			(xy 126.373088 -375.656357) (xy 126.35705 -375.590871) (xy 126.348971 -375.523935) (xy 126.348968 -375.456513)
			(xy 126.357041 -375.389576) (xy 126.373074 -375.324089) (xy 126.396836 -375.260993) (xy 126.427985 -375.201198)
			(xy 126.466073 -375.145565) (xy 126.487936 -375.1199) (xy 126.49372 -375.112746) (xy 126.500241 -375.095562)
			(xy 126.500636 -375.086372) (xy 126.500636 -374.928638) (xy 126.501158 -374.918514) (xy 126.508872 -374.899795)
			(xy 126.523148 -374.885437) (xy 126.541823 -374.877616) (xy 126.551944 -374.877076) (xy 127.268224 -374.877076)
			(xy 127.278377 -374.877501) (xy 127.297125 -374.8853) (xy 127.311447 -374.899695) (xy 127.31915 -374.918483)
			(xy 127.319532 -374.928638) (xy 127.319532 -375.086372) (xy 127.319971 -375.095556) (xy 127.326466 -375.11274)
			(xy 127.332232 -375.1199) (xy 127.354126 -375.14554) (xy 127.392212 -375.201179) (xy 127.423359 -375.260979)
			(xy 127.44712 -375.324079) (xy 127.463153 -375.389571) (xy 127.471226 -375.456511) (xy 127.471223 -375.523937)
			(xy 127.463144 -375.590877) (xy 127.447106 -375.656367) (xy 127.42334 -375.719465) (xy 127.392187 -375.779263)
			(xy 127.354097 -375.834898) (xy 127.332232 -375.860564) (xy 127.326417 -375.867696) (xy 127.319915 -375.884897)
			(xy 127.319532 -375.894092) (xy 127.319532 -376.386344) (xy 127.319936 -376.395532) (xy 127.326456 -376.412715)
			(xy 127.332232 -376.419872) (xy 127.354099 -376.445535) (xy 127.392185 -376.50117) (xy 127.423334 -376.560967)
			(xy 127.447097 -376.624064) (xy 127.463131 -376.689553) (xy 127.471206 -376.756491) (xy 127.471206 -376.756551)
			(xy 130.74927 -376.756551) (xy 130.757314 -376.689729) (xy 130.773286 -376.624347) (xy 130.796958 -376.561343)
			(xy 130.827989 -376.501619) (xy 130.865937 -376.446032) (xy 130.887724 -376.42038) (xy 130.893514 -376.413231)
			(xy 130.900032 -376.396043) (xy 130.900424 -376.386852) (xy 130.900424 -375.893584) (xy 130.900016 -375.884397)
			(xy 130.8935 -375.867213) (xy 130.887724 -375.860056) (xy 130.865968 -375.834378) (xy 130.82802 -375.778795)
			(xy 130.796986 -375.719074) (xy 130.773312 -375.656073) (xy 130.757337 -375.590695) (xy 130.749291 -375.523875)
			(xy 130.749288 -375.456573) (xy 130.757329 -375.389753) (xy 130.773298 -375.324373) (xy 130.796966 -375.26137)
			(xy 130.827995 -375.201647) (xy 130.865939 -375.146061) (xy 130.887724 -375.120408) (xy 130.893502 -375.11325)
			(xy 130.900027 -375.096069) (xy 130.900424 -375.08688) (xy 130.900424 -374.928638) (xy 130.900895 -374.918471)
			(xy 130.908665 -374.899679) (xy 130.923036 -374.885294) (xy 130.941819 -374.877505) (xy 130.951986 -374.877076)
			(xy 131.668266 -374.877076) (xy 131.67844 -374.877493) (xy 131.697241 -374.885274) (xy 131.711629 -374.899662)
			(xy 131.719408 -374.918464) (xy 131.719828 -374.928638) (xy 131.719828 -375.08688) (xy 131.720241 -375.096067)
			(xy 131.726752 -375.113252) (xy 131.732528 -375.120408) (xy 131.754348 -375.146034) (xy 131.792298 -375.201623)
			(xy 131.823332 -375.26135) (xy 131.847005 -375.324358) (xy 131.862976 -375.389744) (xy 131.871018 -375.45657)
			(xy 131.871016 -375.523878) (xy 131.862968 -375.590704) (xy 131.84699 -375.656088) (xy 131.823313 -375.719094)
			(xy 131.792274 -375.778818) (xy 131.754319 -375.834404) (xy 131.732528 -375.860056) (xy 131.726716 -375.86719)
			(xy 131.720213 -375.884389) (xy 131.719828 -375.893584) (xy 131.719828 -376.386852) (xy 131.720255 -376.396037)
			(xy 131.726756 -376.413222) (xy 131.732528 -376.42038) (xy 131.754321 -376.446029) (xy 131.792271 -376.501615)
			(xy 131.823306 -376.561338) (xy 131.84698 -376.624344) (xy 131.862954 -376.689727) (xy 131.870991 -376.756492)
			(xy 161.548796 -376.756492) (xy 161.556871 -376.689554) (xy 161.572905 -376.624066) (xy 161.596667 -376.560969)
			(xy 161.627816 -376.501173) (xy 161.665902 -376.445538) (xy 161.687764 -376.419872) (xy 161.693563 -376.412729)
			(xy 161.700074 -376.395536) (xy 161.700464 -376.386344) (xy 161.700464 -375.894092) (xy 161.700043 -375.884906)
			(xy 161.693535 -375.867723) (xy 161.687764 -375.860564) (xy 161.665933 -375.834872) (xy 161.627845 -375.779241)
			(xy 161.596695 -375.719448) (xy 161.572931 -375.656354) (xy 161.556894 -375.590869) (xy 161.548816 -375.523934)
			(xy 161.548814 -375.456514) (xy 161.556886 -375.389578) (xy 161.572917 -375.324092) (xy 161.596676 -375.260996)
			(xy 161.627821 -375.201201) (xy 161.665903 -375.145566) (xy 161.687764 -375.1199) (xy 161.693551 -375.112748)
			(xy 161.70007 -375.095562) (xy 161.700464 -375.086372) (xy 161.700464 -374.928638) (xy 161.700959 -374.918511)
			(xy 161.708678 -374.899786) (xy 161.722963 -374.885428) (xy 161.741647 -374.877611) (xy 161.751772 -374.877076)
			(xy 162.468052 -374.877076) (xy 162.478168 -374.877555) (xy 162.496866 -374.885283) (xy 162.511181 -374.89958)
			(xy 162.518933 -374.918268) (xy 162.51936 -374.928384) (xy 162.51936 -375.086372) (xy 162.519793 -375.095557)
			(xy 162.526292 -375.112741) (xy 162.53206 -375.1199) (xy 162.553957 -375.145539) (xy 162.592047 -375.201176)
			(xy 162.623199 -375.260976) (xy 162.646963 -375.324076) (xy 162.662997 -375.389569) (xy 162.671071 -375.456511)
			(xy 162.671068 -375.523938) (xy 162.662989 -375.590879) (xy 162.646949 -375.65637) (xy 162.623179 -375.719468)
			(xy 162.592022 -375.779265) (xy 162.553927 -375.834899) (xy 162.53206 -375.860564) (xy 162.526249 -375.867699)
			(xy 162.519744 -375.884897) (xy 162.51936 -375.894092) (xy 162.51936 -376.386344) (xy 162.519758 -376.395532)
			(xy 162.526281 -376.412716) (xy 162.53206 -376.419872) (xy 162.553929 -376.445533) (xy 162.592021 -376.501167)
			(xy 162.623173 -376.560964) (xy 162.646939 -376.624061) (xy 162.662975 -376.689551) (xy 162.671052 -376.756491)
			(xy 162.671051 -376.823855) (xy 165.949092 -376.823855) (xy 165.949092 -376.756551) (xy 165.957136 -376.689728)
			(xy 165.973109 -376.624346) (xy 165.996782 -376.561342) (xy 166.027815 -376.501618) (xy 166.065764 -376.446032)
			(xy 166.087552 -376.42038) (xy 166.093346 -376.413233) (xy 166.099861 -376.396044) (xy 166.100252 -376.386852)
			(xy 166.100252 -375.893584) (xy 166.099838 -375.884397) (xy 166.093326 -375.867214) (xy 166.087552 -375.860056)
			(xy 166.065795 -375.834378) (xy 166.027845 -375.778796) (xy 165.996809 -375.719076) (xy 165.973134 -375.656075)
			(xy 165.957159 -375.590695) (xy 165.949112 -375.523875) (xy 165.949109 -375.456573) (xy 165.95715 -375.389752)
			(xy 165.97312 -375.324371) (xy 165.99679 -375.261368) (xy 166.02782 -375.201646) (xy 166.065766 -375.14606)
			(xy 166.087552 -375.120408) (xy 166.093334 -375.113253) (xy 166.099856 -375.09607) (xy 166.100252 -375.08688)
			(xy 166.100252 -374.928638) (xy 166.100695 -374.918467) (xy 166.10847 -374.899671) (xy 166.12285 -374.885284)
			(xy 166.141643 -374.8775) (xy 166.151814 -374.877076) (xy 166.868094 -374.877076) (xy 166.87827 -374.87747)
			(xy 166.897072 -374.88526) (xy 166.911458 -374.899655) (xy 166.919237 -374.918462) (xy 166.919656 -374.928638)
			(xy 166.919656 -375.08688) (xy 166.920085 -375.096065) (xy 166.926587 -375.113249) (xy 166.932356 -375.120408)
			(xy 166.954175 -375.146034) (xy 166.992124 -375.201624) (xy 167.023156 -375.261351) (xy 167.046827 -375.324359)
			(xy 167.062798 -375.389745) (xy 167.07084 -375.45657) (xy 167.070837 -375.523878) (xy 167.062789 -375.590703)
			(xy 167.046813 -375.656087) (xy 167.023136 -375.719093) (xy 166.992099 -375.778817) (xy 166.954146 -375.834404)
			(xy 166.932356 -375.860056) (xy 166.926548 -375.867193) (xy 166.920041 -375.88439) (xy 166.919656 -375.893584)
			(xy 166.919656 -376.386852) (xy 166.920099 -376.396035) (xy 166.926591 -376.41322) (xy 166.932356 -376.42038)
			(xy 166.954148 -376.446029) (xy 166.992097 -376.501616) (xy 167.02313 -376.56134) (xy 167.046803 -376.624345)
			(xy 167.062776 -376.689727) (xy 167.07082 -376.75655) (xy 167.07082 -376.823856) (xy 167.070813 -376.823915)
			(xy 170.34886 -376.823915) (xy 170.34886 -376.756491) (xy 170.356936 -376.689552) (xy 170.372972 -376.624063)
			(xy 170.396738 -376.560966) (xy 170.427891 -376.50117) (xy 170.465983 -376.445536) (xy 170.487848 -376.419872)
			(xy 170.493645 -376.412727) (xy 170.500158 -376.395536) (xy 170.500548 -376.386344) (xy 170.500548 -375.894092)
			(xy 170.500131 -375.884906) (xy 170.493621 -375.867722) (xy 170.487848 -375.860564) (xy 170.466014 -375.834874)
			(xy 170.427921 -375.779244) (xy 170.396766 -375.719452) (xy 170.372998 -375.656358) (xy 170.356959 -375.590871)
			(xy 170.34888 -375.523935) (xy 170.348877 -375.456513) (xy 170.35695 -375.389576) (xy 170.372984 -375.324088)
			(xy 170.396747 -375.260992) (xy 170.427896 -375.201197) (xy 170.465984 -375.145564) (xy 170.487848 -375.1199)
			(xy 170.493633 -375.112747) (xy 170.500153 -375.095562) (xy 170.500548 -375.086372) (xy 170.500548 -374.928638)
			(xy 170.501058 -374.918513) (xy 170.508775 -374.899791) (xy 170.523054 -374.885433) (xy 170.541734 -374.877614)
			(xy 170.551856 -374.877076) (xy 171.268136 -374.877076) (xy 171.278289 -374.877492) (xy 171.297038 -374.885295)
			(xy 171.311359 -374.899692) (xy 171.319062 -374.918482) (xy 171.319444 -374.928638) (xy 171.319444 -375.086372)
			(xy 171.31988 -375.095556) (xy 171.326377 -375.11274) (xy 171.332144 -375.1199) (xy 171.354041 -375.145538)
			(xy 171.392133 -375.201175) (xy 171.423285 -375.260975) (xy 171.44705 -375.324075) (xy 171.463085 -375.389568)
			(xy 171.471159 -375.45651) (xy 171.471156 -375.523938) (xy 171.463076 -375.590879) (xy 171.447036 -375.656371)
			(xy 171.423266 -375.719469) (xy 171.392108 -375.779266) (xy 171.354012 -375.8349) (xy 171.332144 -375.860564)
			(xy 171.326331 -375.867697) (xy 171.319828 -375.884897) (xy 171.319444 -375.894092) (xy 171.319444 -376.386344)
			(xy 171.319845 -376.395532) (xy 171.326366 -376.412716) (xy 171.332144 -376.419872) (xy 171.354014 -376.445533)
			(xy 171.392106 -376.501167) (xy 171.42326 -376.560963) (xy 171.447026 -376.624061) (xy 171.463063 -376.689551)
			(xy 171.47114 -376.75649) (xy 171.47114 -376.756551) (xy 174.749179 -376.756551) (xy 174.757223 -376.689728)
			(xy 174.773195 -376.624346) (xy 174.796868 -376.561342) (xy 174.8279 -376.501619) (xy 174.865848 -376.446032)
			(xy 174.887636 -376.42038) (xy 174.893428 -376.413232) (xy 174.899945 -376.396043) (xy 174.900336 -376.386852)
			(xy 174.900336 -375.893584) (xy 174.899926 -375.884397) (xy 174.893411 -375.867213) (xy 174.887636 -375.860056)
			(xy 174.86588 -375.834378) (xy 174.82793 -375.778795) (xy 174.796896 -375.719075) (xy 174.773222 -375.656074)
			(xy 174.757246 -375.590695) (xy 174.7492 -375.523875) (xy 174.749197 -375.456573) (xy 174.757238 -375.389752)
			(xy 174.773207 -375.324372) (xy 174.796876 -375.261369) (xy 174.827906 -375.201646) (xy 174.865851 -375.14606)
			(xy 174.887636 -375.120408) (xy 174.893416 -375.113251) (xy 174.89994 -375.096069) (xy 174.900336 -375.08688)
			(xy 174.900336 -374.928638) (xy 174.900795 -374.918469) (xy 174.908567 -374.899676) (xy 174.922942 -374.88529)
			(xy 174.941729 -374.877503) (xy 174.951898 -374.877076) (xy 175.668178 -374.877076) (xy 175.678353 -374.877483)
			(xy 175.697154 -374.885268) (xy 175.711541 -374.899659) (xy 175.71932 -374.918463) (xy 175.71974 -374.928638)
			(xy 175.71974 -375.08688) (xy 175.720173 -375.096064) (xy 175.726672 -375.113248) (xy 175.73244 -375.120408)
			(xy 175.75426 -375.146034) (xy 175.792209 -375.201624) (xy 175.823242 -375.261351) (xy 175.846914 -375.324359)
			(xy 175.862886 -375.389744) (xy 175.870928 -375.45657) (xy 175.870925 -375.523878) (xy 175.862877 -375.590703)
			(xy 175.8469 -375.656087) (xy 175.823223 -375.719093) (xy 175.792185 -375.778818) (xy 175.754231 -375.834404)
			(xy 175.73244 -375.860056) (xy 175.72663 -375.867191) (xy 175.720125 -375.88439) (xy 175.71974 -375.893584)
			(xy 175.71974 -376.386852) (xy 175.720186 -376.396035) (xy 175.726676 -376.413219) (xy 175.73244 -376.42038)
			(xy 175.754232 -376.446029) (xy 175.792182 -376.501615) (xy 175.823216 -376.561339) (xy 175.84689 -376.624344)
			(xy 175.862863 -376.689727) (xy 175.870907 -376.75655) (xy 175.870907 -376.823856) (xy 175.862862 -376.890679)
			(xy 175.846888 -376.956062) (xy 175.823214 -377.019066) (xy 175.792179 -377.07879) (xy 175.754228 -377.134376)
			(xy 175.73244 -377.160028) (xy 175.726642 -377.167172) (xy 175.72013 -377.184364) (xy 175.71974 -377.193556)
			(xy 175.71974 -377.35129) (xy 175.719328 -377.361464) (xy 175.711542 -377.380262) (xy 175.697152 -377.394648)
			(xy 175.678352 -377.40243) (xy 175.668178 -377.402852) (xy 174.951898 -377.402852) (xy 174.941725 -377.402438)
			(xy 174.922928 -377.39465) (xy 174.908543 -377.380262) (xy 174.90076 -377.361463) (xy 174.900336 -377.35129)
			(xy 174.900336 -377.193556) (xy 174.899939 -377.184368) (xy 174.893415 -377.167184) (xy 174.887636 -377.160028)
			(xy 174.865852 -377.134373) (xy 174.827903 -377.078787) (xy 174.79687 -377.019063) (xy 174.773197 -376.956059)
			(xy 174.757224 -376.890678) (xy 174.74918 -376.823855) (xy 174.749179 -376.756551) (xy 171.47114 -376.756551)
			(xy 171.471139 -376.823916) (xy 171.463062 -376.890855) (xy 171.447024 -376.956345) (xy 171.423257 -377.019442)
			(xy 171.392103 -377.079238) (xy 171.35401 -377.134872) (xy 171.332144 -377.160536) (xy 171.326343 -377.167678)
			(xy 171.319832 -377.184871) (xy 171.319444 -377.194064) (xy 171.319444 -377.35129) (xy 171.318965 -377.361418)
			(xy 171.311237 -377.380142) (xy 171.296948 -377.394499) (xy 171.278262 -377.402316) (xy 171.268136 -377.402852)
			(xy 170.551856 -377.402852) (xy 170.541706 -377.402415) (xy 170.522962 -377.394615) (xy 170.508642 -377.380224)
			(xy 170.500935 -377.361442) (xy 170.500548 -377.35129) (xy 170.500548 -377.194064) (xy 170.500144 -377.184876)
			(xy 170.493625 -377.167693) (xy 170.487848 -377.160536) (xy 170.465986 -377.134868) (xy 170.427894 -377.079235)
			(xy 170.396741 -377.01944) (xy 170.372974 -376.956343) (xy 170.356937 -376.890854) (xy 170.34886 -376.823915)
			(xy 167.070813 -376.823915) (xy 167.062775 -376.890679) (xy 167.046801 -376.956061) (xy 167.023128 -377.019066)
			(xy 166.992094 -377.07879) (xy 166.954144 -377.134376) (xy 166.932356 -377.160028) (xy 166.92656 -377.167173)
			(xy 166.920046 -377.184364) (xy 166.919656 -377.193556) (xy 166.919656 -377.35129) (xy 166.919228 -377.361462)
			(xy 166.911445 -377.380257) (xy 166.897061 -377.394643) (xy 166.878266 -377.402427) (xy 166.868094 -377.402852)
			(xy 166.151814 -377.402852) (xy 166.141642 -377.402425) (xy 166.122846 -377.394642) (xy 166.10846 -377.380258)
			(xy 166.100676 -377.361462) (xy 166.100252 -377.35129) (xy 166.100252 -377.193556) (xy 166.099851 -377.184368)
			(xy 166.09333 -377.167185) (xy 166.087552 -377.160028) (xy 166.065768 -377.134373) (xy 166.027818 -377.078787)
			(xy 165.996784 -377.019064) (xy 165.97311 -376.95606) (xy 165.957137 -376.890678) (xy 165.949092 -376.823855)
			(xy 162.671051 -376.823855) (xy 162.671051 -376.823915) (xy 162.662974 -376.890855) (xy 162.646937 -376.956344)
			(xy 162.623171 -377.019442) (xy 162.592017 -377.079238) (xy 162.553926 -377.134871) (xy 162.53206 -377.160536)
			(xy 162.526261 -377.167679) (xy 162.519749 -377.184871) (xy 162.51936 -377.194064) (xy 162.51936 -377.35129)
			(xy 162.518865 -377.361416) (xy 162.511141 -377.380137) (xy 162.496857 -377.394494) (xy 162.478175 -377.402313)
			(xy 162.468052 -377.402852) (xy 161.751772 -377.402852) (xy 161.741668 -377.402339) (xy 161.722999 -377.394602)
			(xy 161.708707 -377.380314) (xy 161.700964 -377.361648) (xy 161.700464 -377.351544) (xy 161.700464 -377.194064)
			(xy 161.700057 -377.184877) (xy 161.69354 -377.167693) (xy 161.687764 -377.160536) (xy 161.665905 -377.134867)
			(xy 161.627819 -377.079232) (xy 161.59667 -377.019436) (xy 161.572907 -376.95634) (xy 161.556872 -376.890852)
			(xy 161.548797 -376.823914) (xy 161.548796 -376.756492) (xy 131.870991 -376.756492) (xy 131.870998 -376.75655)
			(xy 131.870998 -376.823856) (xy 131.862953 -376.890679) (xy 131.846979 -376.956062) (xy 131.823304 -377.019067)
			(xy 131.792268 -377.07879) (xy 131.754317 -377.134376) (xy 131.732528 -377.160028) (xy 131.726728 -377.167171)
			(xy 131.720218 -377.184363) (xy 131.719828 -377.193556) (xy 131.719828 -377.35129) (xy 131.719427 -377.361465)
			(xy 131.711639 -377.380266) (xy 131.697246 -377.394653) (xy 131.678441 -377.402432) (xy 131.668266 -377.402852)
			(xy 130.951986 -377.402852) (xy 130.941826 -377.402378) (xy 130.923055 -377.394597) (xy 130.90869 -377.380225)
			(xy 130.900918 -377.36145) (xy 130.900424 -377.35129) (xy 130.900424 -377.193556) (xy 130.90003 -377.184367)
			(xy 130.893504 -377.167183) (xy 130.887724 -377.160028) (xy 130.865941 -377.134372) (xy 130.827993 -377.078786)
			(xy 130.79696 -377.019063) (xy 130.773288 -376.956059) (xy 130.757315 -376.890677) (xy 130.749271 -376.823855)
			(xy 130.74927 -376.756551) (xy 127.471206 -376.756551) (xy 127.471205 -376.823915) (xy 127.46313 -376.890853)
			(xy 127.447095 -376.956342) (xy 127.423332 -377.019438) (xy 127.392182 -377.079235) (xy 127.354095 -377.13487)
			(xy 127.332232 -377.160536) (xy 127.326429 -377.167677) (xy 127.31992 -377.184871) (xy 127.319532 -377.194064)
			(xy 127.319532 -377.35129) (xy 127.319064 -377.36142) (xy 127.311335 -377.380146) (xy 127.297042 -377.394503)
			(xy 127.278351 -377.402318) (xy 127.268224 -377.402852) (xy 126.551944 -377.402852) (xy 126.541799 -377.402343)
			(xy 126.523058 -377.394572) (xy 126.508735 -377.380202) (xy 126.501024 -377.361436) (xy 126.500636 -377.35129)
			(xy 126.500636 -377.194064) (xy 126.500235 -377.184876) (xy 126.493714 -377.167692) (xy 126.487936 -377.160536)
			(xy 126.466075 -377.134868) (xy 126.427984 -377.079235) (xy 126.396831 -377.019439) (xy 126.373065 -376.956343)
			(xy 126.357028 -376.890854) (xy 126.348951 -376.823915) (xy 123.070903 -376.823915) (xy 123.062865 -376.890679)
			(xy 123.046891 -376.956062) (xy 123.023217 -377.019066) (xy 122.992183 -377.07879) (xy 122.954232 -377.134376)
			(xy 122.932444 -377.160028) (xy 122.926646 -377.167172) (xy 122.920134 -377.184364) (xy 122.919744 -377.193556)
			(xy 122.919744 -377.35129) (xy 122.919328 -377.361463) (xy 122.911543 -377.380261) (xy 122.897154 -377.394647)
			(xy 122.878355 -377.402429) (xy 122.868182 -377.402852) (xy 122.151902 -377.402852) (xy 122.141729 -377.402434)
			(xy 122.122933 -377.394648) (xy 122.108547 -377.380261) (xy 122.100764 -377.361463) (xy 122.10034 -377.35129)
			(xy 122.10034 -377.193556) (xy 122.099942 -377.184368) (xy 122.093419 -377.167184) (xy 122.08764 -377.160028)
			(xy 122.065856 -377.134373) (xy 122.027907 -377.078787) (xy 121.996873 -377.019064) (xy 121.9732 -376.95606)
			(xy 121.957227 -376.890678) (xy 121.949183 -376.823855) (xy 121.949182 -376.756551) (xy 118.671143 -376.756551)
			(xy 118.671142 -376.823916) (xy 118.663065 -376.890855) (xy 118.647028 -376.956345) (xy 118.623261 -377.019442)
			(xy 118.592107 -377.079238) (xy 118.554014 -377.134872) (xy 118.532148 -377.160536) (xy 118.526347 -377.167678)
			(xy 118.519836 -377.184871) (xy 118.519448 -377.194064) (xy 118.519448 -377.35129) (xy 118.518965 -377.361418)
			(xy 118.511238 -377.380141) (xy 118.496951 -377.394498) (xy 118.478265 -377.402315) (xy 118.46814 -377.402852)
			(xy 117.75186 -377.402852) (xy 117.74171 -377.402412) (xy 117.722967 -377.394613) (xy 117.708647 -377.380223)
			(xy 117.700939 -377.361442) (xy 117.700552 -377.35129) (xy 117.700552 -377.194064) (xy 117.700147 -377.184876)
			(xy 117.693628 -377.167693) (xy 117.687852 -377.160536) (xy 117.66599 -377.134868) (xy 117.627898 -377.079235)
			(xy 117.596744 -377.01944) (xy 117.572977 -376.956343) (xy 117.55694 -376.890854) (xy 117.548863 -376.823915)
			(xy 87.871087 -376.823915) (xy 87.863011 -376.890853) (xy 87.846976 -376.956342) (xy 87.823211 -377.019439)
			(xy 87.792061 -377.079236) (xy 87.753972 -377.134871) (xy 87.732108 -377.160536) (xy 87.726315 -377.167684)
			(xy 87.719798 -377.184872) (xy 87.719408 -377.194064) (xy 87.719408 -377.35129) (xy 87.718867 -377.36141)
			(xy 87.711151 -377.380122) (xy 87.696882 -377.394477) (xy 87.678217 -377.402305) (xy 87.6681 -377.402852)
			(xy 86.95182 -377.402852) (xy 86.941719 -377.4023) (xy 86.923051 -377.394578) (xy 86.908757 -377.380303)
			(xy 86.901013 -377.361644) (xy 86.900512 -377.351544) (xy 86.900512 -377.194064) (xy 86.900117 -377.184875)
			(xy 86.893592 -377.167691) (xy 86.887812 -377.160536) (xy 86.865952 -377.134868) (xy 86.827862 -377.079234)
			(xy 86.79671 -377.019438) (xy 86.772945 -376.956342) (xy 86.756909 -376.890853) (xy 86.748833 -376.823915)
			(xy 83.470785 -376.823915) (xy 83.462747 -376.89068) (xy 83.446772 -376.956063) (xy 83.423097 -377.019067)
			(xy 83.392061 -377.078791) (xy 83.354109 -377.134376) (xy 83.33232 -377.160028) (xy 83.326531 -377.167179)
			(xy 83.320011 -377.184365) (xy 83.31962 -377.193556) (xy 83.31962 -377.35129) (xy 83.319227 -377.361466)
			(xy 83.311438 -377.380269) (xy 83.297042 -377.394655) (xy 83.278234 -377.402433) (xy 83.268058 -377.402852)
			(xy 82.551778 -377.402852) (xy 82.541618 -377.402385) (xy 82.522846 -377.394601) (xy 82.508481 -377.380227)
			(xy 82.500709 -377.361451) (xy 82.500216 -377.35129) (xy 82.500216 -377.193556) (xy 82.499823 -377.184367)
			(xy 82.493297 -377.167183) (xy 82.487516 -377.160028) (xy 82.465733 -377.134372) (xy 82.427785 -377.078786)
			(xy 82.396753 -377.019063) (xy 82.373081 -376.956059) (xy 82.357109 -376.890677) (xy 82.349065 -376.823855)
			(xy 82.349064 -376.756551) (xy 79.071 -376.756551) (xy 79.070999 -376.823915) (xy 79.062924 -376.890853)
			(xy 79.046888 -376.956342) (xy 79.023125 -377.019439) (xy 78.991975 -377.079235) (xy 78.953887 -377.13487)
			(xy 78.932024 -377.160536) (xy 78.926232 -377.167685) (xy 78.919714 -377.184872) (xy 78.919324 -377.194064)
			(xy 78.919324 -377.35129) (xy 78.918864 -377.36142) (xy 78.911133 -377.380148) (xy 78.896838 -377.394506)
			(xy 78.878144 -377.402319) (xy 78.868016 -377.402852) (xy 78.151736 -377.402852) (xy 78.141636 -377.402286)
			(xy 78.122969 -377.39457) (xy 78.108674 -377.380299) (xy 78.100929 -377.361643) (xy 78.100428 -377.351544)
			(xy 78.100428 -377.194064) (xy 78.100029 -377.184876) (xy 78.093507 -377.167692) (xy 78.087728 -377.160536)
			(xy 78.065867 -377.134868) (xy 78.027776 -377.079235) (xy 77.996624 -377.019439) (xy 77.972858 -376.956342)
			(xy 77.956822 -376.890853) (xy 77.948745 -376.823915) (xy 74.670697 -376.823915) (xy 74.662659 -376.890679)
			(xy 74.646685 -376.956062) (xy 74.623011 -377.019067) (xy 74.591976 -377.07879) (xy 74.554025 -377.134376)
			(xy 74.532236 -377.160028) (xy 74.526437 -377.167171) (xy 74.519926 -377.184364) (xy 74.519536 -377.193556)
			(xy 74.519536 -377.35129) (xy 74.519127 -377.361464) (xy 74.511341 -377.380264) (xy 74.49695 -377.39465)
			(xy 74.478148 -377.402431) (xy 74.467974 -377.402852) (xy 73.751694 -377.402852) (xy 73.741521 -377.402441)
			(xy 73.722724 -377.394652) (xy 73.708339 -377.380263) (xy 73.700556 -377.361463) (xy 73.700132 -377.35129)
			(xy 73.700132 -377.193556) (xy 73.699736 -377.184367) (xy 73.693212 -377.167184) (xy 73.687432 -377.160028)
			(xy 73.665648 -377.134373) (xy 73.6277 -377.078786) (xy 73.596667 -377.019063) (xy 73.572994 -376.956059)
			(xy 73.557021 -376.890677) (xy 73.548977 -376.823855) (xy 73.548976 -376.756551) (xy 48.270947 -376.756551)
			(xy 48.270947 -376.823855) (xy 48.262903 -376.890678) (xy 48.24693 -376.95606) (xy 48.223258 -377.019064)
			(xy 48.192226 -377.078788) (xy 48.154279 -377.134375) (xy 48.132492 -377.160028) (xy 48.1267 -377.167176)
			(xy 48.120183 -377.184365) (xy 48.119792 -377.193556) (xy 48.119792 -377.351544) (xy 48.119414 -377.361702)
			(xy 48.111603 -377.380457) (xy 48.097193 -377.394779) (xy 48.07839 -377.402476) (xy 48.06823 -377.402852)
			(xy 47.35195 -377.402852) (xy 47.341825 -377.402332) (xy 47.323104 -377.394619) (xy 47.308746 -377.380343)
			(xy 47.300926 -377.361666) (xy 47.300388 -377.351544) (xy 47.300388 -377.193556) (xy 47.300002 -377.184366)
			(xy 47.293472 -377.167182) (xy 47.287688 -377.160028) (xy 47.265903 -377.134373) (xy 47.227951 -377.078788)
			(xy 47.196914 -377.019066) (xy 47.173239 -376.956061) (xy 47.157265 -376.890679) (xy 47.149219 -376.823856)
			(xy 43.871178 -376.823856) (xy 43.871178 -376.823915) (xy 43.863102 -376.890854) (xy 43.847066 -376.956343)
			(xy 43.823301 -377.01944) (xy 43.79215 -377.079236) (xy 43.75406 -377.134871) (xy 43.732196 -377.160536)
			(xy 43.726401 -377.167682) (xy 43.719886 -377.184872) (xy 43.719496 -377.194064) (xy 43.719496 -377.35129)
			(xy 43.718966 -377.361412) (xy 43.711248 -377.380126) (xy 43.696976 -377.394481) (xy 43.678307 -377.402307)
			(xy 43.668188 -377.402852) (xy 42.951908 -377.402852) (xy 42.941761 -377.402373) (xy 42.923019 -377.39459)
			(xy 42.908697 -377.380211) (xy 42.900988 -377.361439) (xy 42.9006 -377.35129) (xy 42.9006 -377.194064)
			(xy 42.900207 -377.184875) (xy 42.893682 -377.167691) (xy 42.8879 -377.160536) (xy 42.86604 -377.134868)
			(xy 42.827951 -377.079233) (xy 42.7968 -377.019438) (xy 42.773036 -376.956341) (xy 42.757 -376.890853)
			(xy 42.748924 -376.823915) (xy 39.470876 -376.823915) (xy 39.462838 -376.89068) (xy 39.446863 -376.956063)
			(xy 39.423187 -377.019068) (xy 39.39215 -377.078791) (xy 39.354198 -377.134377) (xy 39.332408 -377.160028)
			(xy 39.326618 -377.167178) (xy 39.320099 -377.184365) (xy 39.319708 -377.193556) (xy 39.319708 -377.35129)
			(xy 39.31916 -377.361441) (xy 39.311397 -377.380202) (xy 39.297049 -377.394566) (xy 39.278297 -377.402349)
			(xy 39.268146 -377.402852) (xy 38.551866 -377.402852) (xy 38.541705 -377.402394) (xy 38.522933 -377.394607)
			(xy 38.508569 -377.38023) (xy 38.500797 -377.361452) (xy 38.500304 -377.35129) (xy 38.500304 -377.193556)
			(xy 38.499914 -377.184367) (xy 38.493386 -377.167183) (xy 38.487604 -377.160028) (xy 38.465821 -377.134372)
			(xy 38.427875 -377.078785) (xy 38.396843 -377.019062) (xy 38.373172 -376.956058) (xy 38.357199 -376.890677)
			(xy 38.349156 -376.823855) (xy 38.349155 -376.756551) (xy 35.071091 -376.756551) (xy 35.07109 -376.823915)
			(xy 35.063014 -376.890853) (xy 35.046979 -376.956342) (xy 35.023215 -377.019439) (xy 34.992064 -377.079236)
			(xy 34.953976 -377.134871) (xy 34.932112 -377.160536) (xy 34.926319 -377.167684) (xy 34.919802 -377.184872)
			(xy 34.919412 -377.194064) (xy 34.919412 -377.35129) (xy 34.918867 -377.36141) (xy 34.911152 -377.380121)
			(xy 34.896884 -377.394476) (xy 34.878221 -377.402304) (xy 34.868104 -377.402852) (xy 34.151824 -377.402852)
			(xy 34.141678 -377.40236) (xy 34.122936 -377.394582) (xy 34.108614 -377.380208) (xy 34.100904 -377.361438)
			(xy 34.100516 -377.35129) (xy 34.100516 -377.194064) (xy 34.10012 -377.184875) (xy 34.093596 -377.167691)
			(xy 34.087816 -377.160536) (xy 34.065955 -377.134868) (xy 34.027866 -377.079234) (xy 33.996714 -377.019438)
			(xy 33.972949 -376.956342) (xy 33.956912 -376.890853) (xy 33.948836 -376.823915) (xy 30.670788 -376.823915)
			(xy 30.66275 -376.89068) (xy 30.646775 -376.956062) (xy 30.6231 -377.019067) (xy 30.592065 -377.078791)
			(xy 30.554113 -377.134376) (xy 30.532324 -377.160028) (xy 30.526536 -377.167179) (xy 30.520015 -377.184365)
			(xy 30.519624 -377.193556) (xy 30.519624 -377.35129) (xy 30.519227 -377.361466) (xy 30.511438 -377.380267)
			(xy 30.497044 -377.394654) (xy 30.478238 -377.402433) (xy 30.468062 -377.402852) (xy 29.751782 -377.402852)
			(xy 29.741622 -377.402381) (xy 29.72285 -377.394599) (xy 29.708485 -377.380226) (xy 29.700713 -377.36145)
			(xy 29.70022 -377.35129) (xy 29.70022 -377.193556) (xy 29.699827 -377.184367) (xy 29.693301 -377.167183)
			(xy 29.68752 -377.160028) (xy 29.665737 -377.134372) (xy 29.627789 -377.078786) (xy 29.596757 -377.019063)
			(xy 29.573084 -376.956059) (xy 29.557112 -376.890677) (xy 29.549068 -376.823855) (xy 29.549067 -376.756551)
			(xy 0.509016 -376.756551) (xy 0.509016 -378.323793) (xy 27.348888 -378.323793) (xy 27.34889 -378.256368)
			(xy 27.356968 -378.189428) (xy 27.373006 -378.123938) (xy 27.396772 -378.06084) (xy 27.427925 -378.001043)
			(xy 27.466015 -377.945408) (xy 27.48788 -377.919742) (xy 27.493681 -377.9126) (xy 27.500194 -377.895407)
			(xy 27.50058 -377.886214) (xy 27.50058 -377.728734) (xy 27.501056 -377.718605) (xy 27.50878 -377.699877)
			(xy 27.52307 -377.685518) (xy 27.541761 -377.677705) (xy 27.551888 -377.677172) (xy 28.268168 -377.677172)
			(xy 28.278285 -377.677641) (xy 28.296983 -377.685374) (xy 28.311297 -377.699674) (xy 28.319048 -377.718363)
			(xy 28.319476 -377.72848) (xy 28.319476 -377.886214) (xy 28.319885 -377.895401) (xy 28.3264 -377.912585)
			(xy 28.332176 -377.919742) (xy 28.354015 -377.945428) (xy 28.392106 -378.001059) (xy 28.42326 -378.060852)
			(xy 28.447026 -378.123946) (xy 28.463064 -378.189433) (xy 28.471143 -378.256369) (xy 28.471145 -378.323734)
			(xy 31.749183 -378.323734) (xy 31.749186 -378.256427) (xy 31.757233 -378.189602) (xy 31.773209 -378.124218)
			(xy 31.796886 -378.061212) (xy 31.827924 -378.001488) (xy 31.865878 -377.945902) (xy 31.887668 -377.92025)
			(xy 31.893477 -377.913114) (xy 31.899982 -377.895916) (xy 31.900368 -377.886722) (xy 31.900368 -377.728734)
			(xy 31.900793 -377.718561) (xy 31.908572 -377.699761) (xy 31.922958 -377.685374) (xy 31.941757 -377.677593)
			(xy 31.95193 -377.677172) (xy 32.66821 -377.677172) (xy 32.678386 -377.677557) (xy 32.697188 -377.685351)
			(xy 32.711574 -377.699749) (xy 32.719352 -377.718557) (xy 32.719772 -377.728734) (xy 32.719772 -377.886722)
			(xy 32.720178 -377.89591) (xy 32.726695 -377.913094) (xy 32.732472 -377.92025) (xy 32.754234 -377.945924)
			(xy 32.792182 -378.001507) (xy 32.823216 -378.061228) (xy 32.84689 -378.12423) (xy 32.862864 -378.189609)
			(xy 32.87091 -378.256429) (xy 32.870913 -378.323732) (xy 32.870906 -378.323793) (xy 36.148976 -378.323793)
			(xy 36.148978 -378.256368) (xy 36.157056 -378.189429) (xy 36.173093 -378.123939) (xy 36.196859 -378.060841)
			(xy 36.22801 -378.001044) (xy 36.2661 -377.945408) (xy 36.287964 -377.919742) (xy 36.293775 -377.912608)
			(xy 36.300279 -377.895409) (xy 36.300664 -377.886214) (xy 36.300664 -377.728734) (xy 36.301155 -377.718607)
			(xy 36.308876 -377.699882) (xy 36.323162 -377.685523) (xy 36.341847 -377.677707) (xy 36.351972 -377.677172)
			(xy 37.068252 -377.677172) (xy 37.0784 -377.67766) (xy 37.097145 -377.685435) (xy 37.11147 -377.699811)
			(xy 37.119176 -377.718585) (xy 37.11956 -377.728734) (xy 37.11956 -377.886214) (xy 37.119972 -377.895401)
			(xy 37.126485 -377.912585) (xy 37.13226 -377.919742) (xy 37.1541 -377.945428) (xy 37.192192 -378.001058)
			(xy 37.223346 -378.060851) (xy 37.247113 -378.123946) (xy 37.263152 -378.189433) (xy 37.27123 -378.256369)
			(xy 37.271233 -378.323792) (xy 37.271233 -378.323794) (xy 40.548742 -378.323794) (xy 40.548744 -378.256367)
			(xy 40.556824 -378.189426) (xy 40.572863 -378.123935) (xy 40.596633 -378.060837) (xy 40.627789 -378.00104)
			(xy 40.665885 -377.945406) (xy 40.687752 -377.919742) (xy 40.693562 -377.912607) (xy 40.700067 -377.895408)
			(xy 40.700452 -377.886214) (xy 40.700452 -377.728734) (xy 40.700955 -377.718608) (xy 40.708674 -377.699885)
			(xy 40.722955 -377.685528) (xy 40.741637 -377.677709) (xy 40.75176 -377.677172) (xy 41.46804 -377.677172)
			(xy 41.478193 -377.677588) (xy 41.496941 -377.685392) (xy 41.511262 -377.699789) (xy 41.518965 -377.718579)
			(xy 41.519348 -377.728734) (xy 41.519348 -377.886214) (xy 41.519763 -377.8954) (xy 41.526275 -377.912584)
			(xy 41.532048 -377.919742) (xy 41.553888 -377.945427) (xy 41.591981 -378.001058) (xy 41.623136 -378.060851)
			(xy 41.646904 -378.123945) (xy 41.662943 -378.189432) (xy 41.671021 -378.256369) (xy 41.671024 -378.323792)
			(xy 41.671024 -378.323793) (xy 71.348797 -378.323793) (xy 71.348799 -378.256368) (xy 71.356877 -378.189428)
			(xy 71.372915 -378.123937) (xy 71.396682 -378.060839) (xy 71.427835 -378.001042) (xy 71.465927 -377.945407)
			(xy 71.487792 -377.919742) (xy 71.493595 -377.912601) (xy 71.500106 -377.895407) (xy 71.500492 -377.886214)
			(xy 71.500492 -377.728734) (xy 71.501053 -377.718615) (xy 71.508761 -377.699904) (xy 71.523024 -377.685548)
			(xy 71.541685 -377.67772) (xy 71.5518 -377.677172) (xy 72.26808 -377.677172) (xy 72.278229 -377.677637)
			(xy 72.296976 -377.685421) (xy 72.311299 -377.699804) (xy 72.319005 -377.718583) (xy 72.319388 -377.728734)
			(xy 72.319388 -377.886214) (xy 72.319794 -377.895402) (xy 72.326311 -377.912586) (xy 72.332088 -377.919742)
			(xy 72.353927 -377.945428) (xy 72.392017 -378.001059) (xy 72.42317 -378.060853) (xy 72.446936 -378.123947)
			(xy 72.462973 -378.189433) (xy 72.471052 -378.25637) (xy 72.471054 -378.323734) (xy 75.749092 -378.323734)
			(xy 75.749095 -378.256427) (xy 75.757142 -378.189601) (xy 75.773119 -378.124217) (xy 75.796796 -378.061212)
			(xy 75.827835 -378.001488) (xy 75.86579 -377.945902) (xy 75.88758 -377.92025) (xy 75.893378 -377.913106)
			(xy 75.899892 -377.895915) (xy 75.90028 -377.886722) (xy 75.90028 -377.728734) (xy 75.900693 -377.718559)
			(xy 75.908474 -377.699757) (xy 75.922864 -377.68537) (xy 75.941667 -377.677591) (xy 75.951842 -377.677172)
			(xy 76.668122 -377.677172) (xy 76.678299 -377.677547) (xy 76.697101 -377.685345) (xy 76.711486 -377.699746)
			(xy 76.719264 -377.718556) (xy 76.719684 -377.728734) (xy 76.719684 -377.886722) (xy 76.720087 -377.89591)
			(xy 76.726606 -377.913094) (xy 76.732384 -377.92025) (xy 76.754146 -377.945923) (xy 76.792094 -378.001507)
			(xy 76.823127 -378.061228) (xy 76.8468 -378.12423) (xy 76.862774 -378.189609) (xy 76.87082 -378.256429)
			(xy 76.870822 -378.323732) (xy 76.870815 -378.323793) (xy 80.148885 -378.323793) (xy 80.148887 -378.256368)
			(xy 80.156965 -378.189428) (xy 80.173003 -378.123938) (xy 80.196769 -378.06084) (xy 80.227921 -378.001043)
			(xy 80.266011 -377.945408) (xy 80.287876 -377.919742) (xy 80.293677 -377.9126) (xy 80.30019 -377.895407)
			(xy 80.300576 -377.886214) (xy 80.300576 -377.728734) (xy 80.301056 -377.718605) (xy 80.308779 -377.699878)
			(xy 80.323068 -377.685519) (xy 80.341758 -377.677705) (xy 80.351884 -377.677172) (xy 81.068164 -377.677172)
			(xy 81.078281 -377.677645) (xy 81.096978 -377.685376) (xy 81.111293 -377.699675) (xy 81.119044 -377.718364)
			(xy 81.119472 -377.72848) (xy 81.119472 -377.886214) (xy 81.119882 -377.895401) (xy 81.126396 -377.912585)
			(xy 81.132172 -377.919742) (xy 81.154011 -377.945428) (xy 81.192103 -378.001059) (xy 81.223256 -378.060852)
			(xy 81.247023 -378.123946) (xy 81.263061 -378.189433) (xy 81.27114 -378.256369) (xy 81.271142 -378.323792)
			(xy 81.271142 -378.323793) (xy 84.548676 -378.323793) (xy 84.548678 -378.256368) (xy 84.556756 -378.189429)
			(xy 84.572793 -378.123939) (xy 84.596559 -378.060841) (xy 84.62771 -378.001044) (xy 84.6658 -377.945408)
			(xy 84.687664 -377.919742) (xy 84.693475 -377.912608) (xy 84.699979 -377.895409) (xy 84.700364 -377.886214)
			(xy 84.700364 -377.728734) (xy 84.700855 -377.718607) (xy 84.708576 -377.699882) (xy 84.722862 -377.685523)
			(xy 84.741547 -377.677707) (xy 84.751672 -377.677172) (xy 85.467952 -377.677172) (xy 85.478068 -377.677655)
			(xy 85.496765 -377.685382) (xy 85.51108 -377.699678) (xy 85.518832 -377.718365) (xy 85.51926 -377.72848)
			(xy 85.51926 -377.886214) (xy 85.519672 -377.895401) (xy 85.526185 -377.912585) (xy 85.53196 -377.919742)
			(xy 85.5538 -377.945428) (xy 85.591892 -378.001058) (xy 85.623046 -378.060851) (xy 85.646813 -378.123946)
			(xy 85.662852 -378.189433) (xy 85.67093 -378.256369) (xy 85.670933 -378.323734) (xy 115.349234 -378.323734)
			(xy 115.349237 -378.256427) (xy 115.357283 -378.189603) (xy 115.373258 -378.12422) (xy 115.396932 -378.061215)
			(xy 115.427966 -378.00149) (xy 115.465916 -377.945903) (xy 115.487704 -377.92025) (xy 115.493505 -377.913108)
			(xy 115.500017 -377.895915) (xy 115.500404 -377.886722) (xy 115.500404 -377.728734) (xy 115.500961 -377.718583)
			(xy 115.508717 -377.699821) (xy 115.523064 -377.685456) (xy 115.541815 -377.677674) (xy 115.551966 -377.677172)
			(xy 116.268246 -377.677172) (xy 116.278411 -377.677597) (xy 116.297188 -377.685393) (xy 116.311552 -377.69978)
			(xy 116.319319 -377.718568) (xy 116.319808 -377.728734) (xy 116.319808 -377.886722) (xy 116.320206 -377.895911)
			(xy 116.326728 -377.913095) (xy 116.332508 -377.92025) (xy 116.354272 -377.945922) (xy 116.392225 -378.001505)
			(xy 116.423262 -378.061225) (xy 116.446939 -378.124227) (xy 116.462915 -378.189607) (xy 116.470962 -378.256428)
			(xy 116.470964 -378.323732) (xy 116.470957 -378.323793) (xy 119.749003 -378.323793) (xy 119.749005 -378.256368)
			(xy 119.757084 -378.189428) (xy 119.773122 -378.123937) (xy 119.796889 -378.060839) (xy 119.828043 -378.001042)
			(xy 119.866134 -377.945407) (xy 119.888 -377.919742) (xy 119.893804 -377.912602) (xy 119.900314 -377.895407)
			(xy 119.9007 -377.886214) (xy 119.9007 -377.728734) (xy 119.901253 -377.718614) (xy 119.908963 -377.699902)
			(xy 119.923228 -377.685546) (xy 119.941892 -377.677718) (xy 119.952008 -377.677172) (xy 120.668288 -377.677172)
			(xy 120.678438 -377.677631) (xy 120.697185 -377.685417) (xy 120.711507 -377.699802) (xy 120.719213 -377.718582)
			(xy 120.719596 -377.728734) (xy 120.719596 -377.886214) (xy 120.72 -377.895402) (xy 120.726518 -377.912586)
			(xy 120.732296 -377.919742) (xy 120.754135 -377.945428) (xy 120.792224 -378.00106) (xy 120.823376 -378.060853)
			(xy 120.847142 -378.123947) (xy 120.86318 -378.189434) (xy 120.871258 -378.25637) (xy 120.87126 -378.323734)
			(xy 124.149298 -378.323734) (xy 124.149301 -378.256426) (xy 124.157348 -378.189601) (xy 124.173325 -378.124217)
			(xy 124.197003 -378.061211) (xy 124.228042 -378.001487) (xy 124.265997 -377.945902) (xy 124.287788 -377.92025)
			(xy 124.293587 -377.913106) (xy 124.300101 -377.895915) (xy 124.300488 -377.886722) (xy 124.300488 -377.728734)
			(xy 124.300893 -377.718558) (xy 124.308676 -377.699755) (xy 124.323068 -377.685367) (xy 124.341874 -377.67759)
			(xy 124.35205 -377.677172) (xy 125.06833 -377.677172) (xy 125.078508 -377.67754) (xy 125.09731 -377.685341)
			(xy 125.111695 -377.699744) (xy 125.119473 -377.718556) (xy 125.119892 -377.728734) (xy 125.119892 -377.886722)
			(xy 125.120293 -377.89591) (xy 125.126813 -377.913094) (xy 125.132592 -377.92025) (xy 125.154353 -377.945924)
			(xy 125.192301 -378.001508) (xy 125.223334 -378.061229) (xy 125.247006 -378.12423) (xy 125.26298 -378.189609)
			(xy 125.271026 -378.256429) (xy 125.271028 -378.323732) (xy 125.271028 -378.323734) (xy 128.549089 -378.323734)
			(xy 128.549092 -378.256427) (xy 128.557139 -378.189602) (xy 128.573116 -378.124218) (xy 128.596793 -378.061212)
			(xy 128.627831 -378.001488) (xy 128.665786 -377.945902) (xy 128.687576 -377.92025) (xy 128.693374 -377.913105)
			(xy 128.699888 -377.895915) (xy 128.700276 -377.886722) (xy 128.700276 -377.728734) (xy 128.700693 -377.71856)
			(xy 128.708474 -377.699759) (xy 128.722862 -377.685371) (xy 128.741664 -377.677592) (xy 128.751838 -377.677172)
			(xy 129.468118 -377.677172) (xy 129.478295 -377.67755) (xy 129.497097 -377.685347) (xy 129.511482 -377.699747)
			(xy 129.51926 -377.718557) (xy 129.51968 -377.728734) (xy 129.51968 -377.886722) (xy 129.520084 -377.89591)
			(xy 129.526602 -377.913094) (xy 129.53238 -377.92025) (xy 129.554142 -377.945923) (xy 129.59209 -378.001507)
			(xy 129.623123 -378.061228) (xy 129.646797 -378.12423) (xy 129.662771 -378.189609) (xy 129.670817 -378.256429)
			(xy 129.670819 -378.323732) (xy 129.670819 -378.323734) (xy 159.349143 -378.323734) (xy 159.349146 -378.256427)
			(xy 159.357192 -378.189603) (xy 159.373167 -378.12422) (xy 159.396842 -378.061214) (xy 159.427877 -378.00149)
			(xy 159.465827 -377.945902) (xy 159.487616 -377.92025) (xy 159.493418 -377.913109) (xy 159.499929 -377.895915)
			(xy 159.500316 -377.886722) (xy 159.500316 -377.728734) (xy 159.500791 -377.718567) (xy 159.508561 -377.699778)
			(xy 159.522931 -377.685392) (xy 159.541712 -377.677602) (xy 159.551878 -377.677172) (xy 160.268158 -377.677172)
			(xy 160.278331 -377.677599) (xy 160.297131 -377.685377) (xy 160.311519 -377.699762) (xy 160.319299 -377.718561)
			(xy 160.31972 -377.728734) (xy 160.31972 -377.886722) (xy 160.320115 -377.895911) (xy 160.326639 -377.913095)
			(xy 160.33242 -377.92025) (xy 160.354183 -377.945923) (xy 160.392136 -378.001505) (xy 160.423172 -378.061226)
			(xy 160.446848 -378.124227) (xy 160.462824 -378.189608) (xy 160.470871 -378.256429) (xy 160.470874 -378.323732)
			(xy 160.470867 -378.323793) (xy 163.748912 -378.323793) (xy 163.748914 -378.256367) (xy 163.756993 -378.189427)
			(xy 163.773031 -378.123937) (xy 163.796799 -378.060839) (xy 163.827953 -378.001042) (xy 163.866046 -377.945407)
			(xy 163.887912 -377.919742) (xy 163.893717 -377.912603) (xy 163.900226 -377.895408) (xy 163.900612 -377.886214)
			(xy 163.900612 -377.728734) (xy 163.901154 -377.718613) (xy 163.908865 -377.699898) (xy 163.923134 -377.685542)
			(xy 163.941802 -377.677716) (xy 163.95192 -377.677172) (xy 164.6682 -377.677172) (xy 164.678351 -377.677621)
			(xy 164.697098 -377.685411) (xy 164.71142 -377.699799) (xy 164.719125 -377.718582) (xy 164.719508 -377.728734)
			(xy 164.719508 -377.886214) (xy 164.71991 -377.895402) (xy 164.726429 -377.912586) (xy 164.732208 -377.919742)
			(xy 164.754046 -377.945428) (xy 164.792135 -378.00106) (xy 164.823286 -378.060853) (xy 164.847052 -378.123948)
			(xy 164.863089 -378.189434) (xy 164.871167 -378.25637) (xy 164.871169 -378.323734) (xy 168.149231 -378.323734)
			(xy 168.149234 -378.256427) (xy 168.15728 -378.189604) (xy 168.173254 -378.12422) (xy 168.196928 -378.061215)
			(xy 168.227963 -378.00149) (xy 168.265912 -377.945903) (xy 168.2877 -377.92025) (xy 168.2935 -377.913107)
			(xy 168.300013 -377.895915) (xy 168.3004 -377.886722) (xy 168.3004 -377.728734) (xy 168.30096 -377.718583)
			(xy 168.308717 -377.699822) (xy 168.323062 -377.685457) (xy 168.341812 -377.677675) (xy 168.351962 -377.677172)
			(xy 169.068242 -377.677172) (xy 169.078407 -377.6776) (xy 169.097183 -377.685394) (xy 169.111548 -377.699781)
			(xy 169.119315 -377.718569) (xy 169.119804 -377.728734) (xy 169.119804 -377.886722) (xy 169.120203 -377.89591)
			(xy 169.126724 -377.913095) (xy 169.132504 -377.92025) (xy 169.154265 -377.945924) (xy 169.192212 -378.001508)
			(xy 169.223244 -378.061229) (xy 169.246916 -378.124231) (xy 169.26289 -378.18961) (xy 169.270935 -378.256429)
			(xy 169.270937 -378.323732) (xy 169.270937 -378.323734) (xy 172.548998 -378.323734) (xy 172.549001 -378.256426)
			(xy 172.557048 -378.189601) (xy 172.573025 -378.124217) (xy 172.596703 -378.061211) (xy 172.627742 -378.001487)
			(xy 172.665697 -377.945902) (xy 172.687488 -377.92025) (xy 172.693287 -377.913106) (xy 172.699801 -377.895915)
			(xy 172.700188 -377.886722) (xy 172.700188 -377.728734) (xy 172.700593 -377.718558) (xy 172.708376 -377.699755)
			(xy 172.722768 -377.685367) (xy 172.741574 -377.67759) (xy 172.75175 -377.677172) (xy 173.46803 -377.677172)
			(xy 173.478208 -377.67754) (xy 173.49701 -377.685341) (xy 173.511395 -377.699744) (xy 173.519173 -377.718556)
			(xy 173.519592 -377.728734) (xy 173.519592 -377.886722) (xy 173.519993 -377.89591) (xy 173.526513 -377.913094)
			(xy 173.532292 -377.92025) (xy 173.554053 -377.945924) (xy 173.592001 -378.001508) (xy 173.623034 -378.061229)
			(xy 173.646706 -378.12423) (xy 173.66268 -378.189609) (xy 173.670726 -378.256429) (xy 173.670728 -378.323732)
			(xy 173.662687 -378.390552) (xy 173.646718 -378.455932) (xy 173.623049 -378.518936) (xy 173.592021 -378.578659)
			(xy 173.554077 -378.634245) (xy 173.532292 -378.659898) (xy 173.526513 -378.667056) (xy 173.519988 -378.684237)
			(xy 173.519592 -378.693426) (xy 173.519592 -378.766811) (xy 193.48983 -378.766811) (xy 193.48983 -378.633249)
			(xy 193.497894 -378.499931) (xy 193.513994 -378.367343) (xy 193.538069 -378.235969) (xy 193.570032 -378.106288)
			(xy 193.609767 -377.978774) (xy 193.657129 -377.853891) (xy 193.711944 -377.732096) (xy 193.774014 -377.613833)
			(xy 193.84311 -377.499534) (xy 193.918982 -377.389614) (xy 194.001352 -377.284477) (xy 194.08992 -377.184504)
			(xy 194.184362 -377.090062) (xy 194.284335 -377.001494) (xy 194.389472 -376.919124) (xy 194.499392 -376.843252)
			(xy 194.613691 -376.774156) (xy 194.731954 -376.712086) (xy 194.853749 -376.657271) (xy 194.978632 -376.609909)
			(xy 195.106146 -376.570174) (xy 195.235827 -376.538211) (xy 195.367201 -376.514136) (xy 195.499789 -376.498036)
			(xy 195.633107 -376.489972) (xy 195.766669 -376.489972) (xy 195.899987 -376.498036) (xy 196.032575 -376.514136)
			(xy 196.163949 -376.538211) (xy 196.29363 -376.570174) (xy 196.421144 -376.609909) (xy 196.546027 -376.657271)
			(xy 196.667822 -376.712086) (xy 196.786085 -376.774156) (xy 196.900384 -376.843252) (xy 197.010304 -376.919124)
			(xy 197.115441 -377.001494) (xy 197.215414 -377.090062) (xy 197.309856 -377.184504) (xy 197.398424 -377.284477)
			(xy 197.480794 -377.389614) (xy 197.556666 -377.499534) (xy 197.625762 -377.613833) (xy 197.687832 -377.732096)
			(xy 197.742647 -377.853891) (xy 197.790009 -377.978774) (xy 197.829744 -378.106288) (xy 197.861707 -378.235969)
			(xy 197.862607 -378.240882) (xy 204.068504 -378.240882) (xy 204.076595 -378.185806) (xy 204.092605 -378.132491)
			(xy 204.116196 -378.082071) (xy 204.146866 -378.035615) (xy 204.183964 -377.994111) (xy 204.226701 -377.958442)
			(xy 204.274169 -377.929363) (xy 204.299566 -377.917964) (xy 204.31379 -377.911868) (xy 204.3303 -377.886722)
			(xy 204.3303 -374.878092) (xy 204.329857 -374.868543) (xy 204.322824 -374.850787) (xy 204.316584 -374.843548)
			(xy 204.300697 -374.825797) (xy 204.273817 -374.786469) (xy 204.25311 -374.743569) (xy 204.23904 -374.698059)
			(xy 204.231922 -374.650958) (xy 204.231494 -374.62714) (xy 204.231494 -371.243098) (xy 204.231071 -371.233029)
			(xy 204.223349 -371.214431) (xy 204.216508 -371.20703) (xy 204.18298 -371.173502) (xy 204.165683 -371.155513)
			(xy 204.136361 -371.115135) (xy 204.113715 -371.070668) (xy 204.098302 -371.023206) (xy 204.090502 -370.973917)
			(xy 204.090016 -370.948966) (xy 204.090016 -367.26876) (xy 204.090486 -367.24381) (xy 204.098304 -367.194525)
			(xy 204.113727 -367.147067) (xy 204.136375 -367.102602) (xy 204.165692 -367.062221) (xy 204.18298 -367.044224)
			(xy 204.446632 -366.780572) (xy 204.464604 -366.763255) (xy 204.504984 -366.733927) (xy 204.549455 -366.711277)
			(xy 204.596921 -366.695864) (xy 204.646215 -366.688067) (xy 204.671168 -366.687608) (xy 208.09839 -366.687608)
			(xy 208.123339 -366.688112) (xy 208.172622 -366.695922) (xy 208.220079 -366.711337) (xy 208.264545 -366.733977)
			(xy 208.304928 -366.763287) (xy 208.322926 -366.780572) (xy 208.566512 -367.024158) (xy 208.583789 -367.042165)
			(xy 208.613114 -367.082538) (xy 208.635764 -367.127001) (xy 208.651181 -367.174459) (xy 208.658986 -367.223744)
			(xy 208.659476 -367.248694) (xy 208.659476 -369.788186) (xy 208.659999 -369.79819) (xy 208.667649 -369.816677)
			(xy 208.681791 -369.830829) (xy 208.700273 -369.838494) (xy 208.710276 -369.838986) (xy 208.785968 -369.838986)
			(xy 208.810919 -369.839447) (xy 208.860203 -369.847269) (xy 208.907661 -369.862694) (xy 208.952126 -369.885344)
			(xy 208.992507 -369.914662) (xy 209.010504 -369.93195) (xy 209.67573 -370.597176) (xy 209.683128 -370.604019)
			(xy 209.701729 -370.611738) (xy 209.711798 -370.612162) (xy 210.06562 -370.612162) (xy 210.090569 -370.61266)
			(xy 210.139852 -370.620474) (xy 210.187309 -370.635891) (xy 210.231774 -370.658532) (xy 210.272157 -370.687842)
			(xy 210.290156 -370.705126) (xy 210.516978 -370.931948) (xy 210.534292 -370.949922) (xy 210.563614 -370.990303)
			(xy 210.586257 -371.034774) (xy 210.601666 -371.08224) (xy 210.609459 -371.131532) (xy 210.609942 -371.156484)
			(xy 210.609942 -371.380512) (xy 210.610311 -371.390539) (xy 210.617993 -371.409064) (xy 210.632181 -371.423238)
			(xy 210.650714 -371.4309) (xy 210.660742 -371.431312) (xy 216.45245 -371.431312) (xy 216.462519 -371.430884)
			(xy 216.481119 -371.423168) (xy 216.488518 -371.416326) (xy 217.302334 -370.60251) (xy 217.309167 -370.595105)
			(xy 217.31689 -370.576509) (xy 217.31732 -370.566442) (xy 217.31732 -367.318036) (xy 217.317803 -367.293087)
			(xy 217.325622 -367.243804) (xy 217.341043 -367.196347) (xy 217.363688 -367.151882) (xy 217.392999 -367.111499)
			(xy 217.410284 -367.0935) (xy 217.733118 -366.770666) (xy 217.751095 -366.753355) (xy 217.791474 -366.724026)
			(xy 217.835943 -366.701376) (xy 217.883409 -366.685961) (xy 217.932701 -366.678162) (xy 217.957654 -366.677702)
			(xy 221.342458 -366.677702) (xy 221.367409 -366.678165) (xy 221.416693 -366.685986) (xy 221.464151 -366.70141)
			(xy 221.508616 -366.724059) (xy 221.548997 -366.753378) (xy 221.566994 -366.770666) (xy 221.81058 -367.014252)
			(xy 221.827896 -367.032223) (xy 221.857217 -367.072606) (xy 221.879861 -367.117077) (xy 221.895269 -367.164543)
			(xy 221.903062 -367.213836) (xy 221.903544 -367.238788) (xy 221.903544 -370.592604) (xy 221.903956 -370.602675)
			(xy 221.911685 -370.621273) (xy 221.91853 -370.628672) (xy 222.004382 -370.714524) (xy 222.021685 -370.732507)
			(xy 222.051008 -370.772886) (xy 222.073654 -370.817355) (xy 222.089065 -370.864819) (xy 222.096861 -370.914109)
			(xy 222.097346 -370.93906) (xy 222.097346 -373.42191) (xy 222.097754 -373.431981) (xy 222.105485 -373.45058)
			(xy 222.112332 -373.457978) (xy 223.764602 -375.110248) (xy 223.772013 -375.117074) (xy 223.790604 -375.124804)
			(xy 223.80067 -375.125234) (xy 225.416872 -375.125234) (xy 225.426942 -375.124811) (xy 225.445541 -375.117091)
			(xy 225.45294 -375.110248) (xy 226.51339 -374.049798) (xy 226.520222 -374.042392) (xy 226.527947 -374.023797)
			(xy 226.528376 -374.01373) (xy 226.528376 -372.656862) (xy 226.528859 -372.631912) (xy 226.536676 -372.582629)
			(xy 226.552096 -372.535172) (xy 226.574741 -372.490706) (xy 226.604054 -372.450324) (xy 226.62134 -372.432326)
			(xy 227.816156 -371.23751) (xy 227.822978 -371.230095) (xy 227.83071 -371.211508) (xy 227.831142 -371.201442)
			(xy 227.831142 -370.936012) (xy 227.831666 -370.911064) (xy 227.839474 -370.861783) (xy 227.854885 -370.814326)
			(xy 227.877521 -370.76986) (xy 227.906825 -370.729476) (xy 227.924106 -370.711476) (xy 228.003608 -370.631974)
			(xy 228.010453 -370.624578) (xy 228.01817 -370.605976) (xy 228.018594 -370.595906) (xy 228.018594 -367.245138)
			(xy 228.019057 -367.220188) (xy 228.026878 -367.170903) (xy 228.042302 -367.123445) (xy 228.064952 -367.07898)
			(xy 228.09427 -367.038599) (xy 228.111558 -367.020602) (xy 228.364796 -366.767364) (xy 228.382783 -366.750063)
			(xy 228.423159 -366.720733) (xy 228.467626 -366.698081) (xy 228.515089 -366.682663) (xy 228.56438 -366.674861)
			(xy 228.589332 -366.6744) (xy 232.007156 -366.6744) (xy 232.032106 -366.674865) (xy 232.081391 -366.682685)
			(xy 232.128849 -366.698109) (xy 232.173314 -366.720758) (xy 232.213695 -366.750076) (xy 232.231692 -366.767364)
			(xy 232.48493 -367.020602) (xy 232.502233 -367.038587) (xy 232.531563 -367.078963) (xy 232.554215 -367.123431)
			(xy 232.569632 -367.170894) (xy 232.577433 -367.220186) (xy 232.577894 -367.245138) (xy 232.577894 -370.60251)
			(xy 232.578289 -370.612583) (xy 232.586028 -370.631182) (xy 232.59288 -370.638578) (xy 232.652824 -370.698522)
			(xy 232.670133 -370.716499) (xy 232.699454 -370.756881) (xy 232.722098 -370.801351) (xy 232.737507 -370.848816)
			(xy 232.745303 -370.898106) (xy 232.745788 -370.923058) (xy 232.745788 -371.05971) (xy 232.746185 -371.069783)
			(xy 232.753923 -371.088382) (xy 232.760774 -371.095778) (xy 233.402886 -371.73789) (xy 233.420173 -371.755888)
			(xy 233.449498 -371.796263) (xy 233.472147 -371.840728) (xy 233.487562 -371.888188) (xy 233.495363 -371.937476)
			(xy 233.49585 -371.962426) (xy 233.49585 -375.346214) (xy 233.496255 -375.356286) (xy 233.503988 -375.374884)
			(xy 233.510836 -375.382282) (xy 234.427522 -376.298968) (xy 235.473748 -376.298968) (xy 235.473748 -368.60607)
			(xy 235.474244 -368.581121) (xy 235.482059 -368.531838) (xy 235.497476 -368.484382) (xy 235.520118 -368.439916)
			(xy 235.549428 -368.399533) (xy 235.566712 -368.381534) (xy 235.993178 -367.955068) (xy 236.011173 -367.937776)
			(xy 236.051547 -367.908445) (xy 236.096012 -367.885791) (xy 236.143473 -367.870371) (xy 236.192762 -367.862567)
			(xy 236.217714 -367.862104) (xy 265.631168 -367.862104) (xy 265.656119 -367.86256) (xy 265.705404 -367.870382)
			(xy 265.752862 -367.885808) (xy 265.797327 -367.908459) (xy 265.837707 -367.937779) (xy 265.855704 -367.955068)
			(xy 266.408408 -368.507772) (xy 266.425691 -368.525774) (xy 266.455015 -368.566148) (xy 266.477664 -368.610612)
			(xy 266.49308 -368.658072) (xy 266.500884 -368.707358) (xy 266.501372 -368.732308) (xy 266.501372 -370.523704)
			(xy 286.928752 -370.523704) (xy 286.928753 -370.456278) (xy 286.936831 -370.389338) (xy 286.952869 -370.323848)
			(xy 286.976637 -370.26075) (xy 287.007792 -370.200954) (xy 287.045885 -370.14532) (xy 287.067752 -370.119656)
			(xy 287.073556 -370.112516) (xy 287.080065 -370.095321) (xy 287.080452 -370.086128) (xy 287.080452 -369.928902)
			(xy 287.080929 -369.918774) (xy 287.088658 -369.900051) (xy 287.102947 -369.885694) (xy 287.121634 -369.877877)
			(xy 287.13176 -369.87734) (xy 287.84804 -369.87734) (xy 287.85817 -369.877684) (xy 287.876882 -369.885453)
			(xy 287.891196 -369.899792) (xy 287.898933 -369.918517) (xy 287.899348 -369.928648) (xy 287.899348 -370.086128)
			(xy 287.899756 -370.095315) (xy 287.906273 -370.112499) (xy 287.912048 -370.119656) (xy 287.933902 -370.14533)
			(xy 287.971994 -370.200962) (xy 288.003149 -370.260757) (xy 288.026916 -370.323852) (xy 288.042954 -370.389341)
			(xy 288.051031 -370.456279) (xy 288.051032 -370.523644) (xy 291.329071 -370.523644) (xy 291.329073 -370.456338)
			(xy 291.337118 -370.389515) (xy 291.353092 -370.324132) (xy 291.376766 -370.261127) (xy 291.407801 -370.201403)
			(xy 291.445751 -370.145816) (xy 291.46754 -370.120164) (xy 291.473339 -370.113021) (xy 291.479851 -370.095829)
			(xy 291.48024 -370.086636) (xy 291.48024 -369.928902) (xy 291.480665 -369.91873) (xy 291.48845 -369.899935)
			(xy 291.502835 -369.88555) (xy 291.52163 -369.877765) (xy 291.531802 -369.87734) (xy 292.248082 -369.87734)
			(xy 292.258253 -369.877778) (xy 292.277047 -369.885558) (xy 292.291433 -369.899939) (xy 292.299218 -369.918731)
			(xy 292.299644 -369.928902) (xy 292.299644 -370.086636) (xy 292.30005 -370.095823) (xy 292.306568 -370.113007)
			(xy 292.312344 -370.120164) (xy 292.33412 -370.145826) (xy 292.372071 -370.20141) (xy 292.403105 -370.261132)
			(xy 292.426779 -370.324136) (xy 292.442754 -370.389517) (xy 292.450799 -370.456339) (xy 292.4508 -370.523643)
			(xy 292.450793 -370.523704) (xy 295.72884 -370.523704) (xy 295.728841 -370.456278) (xy 295.736918 -370.389339)
			(xy 295.752956 -370.323848) (xy 295.776723 -370.260751) (xy 295.807878 -370.200955) (xy 295.84597 -370.145321)
			(xy 295.867836 -370.119656) (xy 295.873638 -370.112515) (xy 295.880149 -370.095321) (xy 295.880536 -370.086128)
			(xy 295.880536 -369.928902) (xy 295.881028 -369.918776) (xy 295.888755 -369.900056) (xy 295.903039 -369.885699)
			(xy 295.92172 -369.877879) (xy 295.931844 -369.87734) (xy 296.648124 -369.87734) (xy 296.658285 -369.877703)
			(xy 296.677045 -369.885514) (xy 296.691369 -369.899929) (xy 296.699061 -369.918739) (xy 296.699432 -369.928902)
			(xy 296.699432 -370.086128) (xy 296.699844 -370.095315) (xy 296.706358 -370.112498) (xy 296.712132 -370.119656)
			(xy 296.733983 -370.145332) (xy 296.77207 -370.200965) (xy 296.803219 -370.26076) (xy 296.826983 -370.323856)
			(xy 296.843018 -370.389343) (xy 296.851095 -370.45628) (xy 296.851096 -370.523702) (xy 296.851096 -370.523704)
			(xy 300.128631 -370.523704) (xy 300.128632 -370.456278) (xy 300.136709 -370.389339) (xy 300.152747 -370.323849)
			(xy 300.176513 -370.260751) (xy 300.207667 -370.200955) (xy 300.245758 -370.145321) (xy 300.267624 -370.119656)
			(xy 300.273425 -370.112514) (xy 300.279936 -370.095321) (xy 300.280324 -370.086128) (xy 300.280324 -369.928902)
			(xy 300.280828 -369.918777) (xy 300.288552 -369.900059) (xy 300.302833 -369.885704) (xy 300.32151 -369.877882)
			(xy 300.331632 -369.87734) (xy 301.047912 -369.87734) (xy 301.058072 -369.877712) (xy 301.076832 -369.885519)
			(xy 301.091157 -369.899932) (xy 301.098849 -369.91874) (xy 301.09922 -369.928902) (xy 301.09922 -370.086128)
			(xy 301.099612 -370.095317) (xy 301.106138 -370.112502) (xy 301.11192 -370.119656) (xy 301.133771 -370.145331)
			(xy 301.171859 -370.200965) (xy 301.203009 -370.26076) (xy 301.226773 -370.323855) (xy 301.242809 -370.389343)
			(xy 301.250886 -370.45628) (xy 301.250887 -370.523644) (xy 330.92919 -370.523644) (xy 330.929191 -370.456338)
			(xy 330.937237 -370.389514) (xy 330.953212 -370.324131) (xy 330.976887 -370.261126) (xy 331.007923 -370.201402)
			(xy 331.045875 -370.145816) (xy 331.067664 -370.120164) (xy 331.073466 -370.113023) (xy 331.079976 -370.095829)
			(xy 331.080364 -370.086636) (xy 331.080364 -369.928902) (xy 331.080766 -369.918727) (xy 331.088555 -369.899928)
			(xy 331.102948 -369.885542) (xy 331.121751 -369.877761) (xy 331.131926 -369.87734) (xy 331.848206 -369.87734)
			(xy 331.858364 -369.877829) (xy 331.877134 -369.885605) (xy 331.891499 -369.899973) (xy 331.899273 -369.918744)
			(xy 331.899768 -369.928902) (xy 331.899768 -370.086636) (xy 331.900168 -370.095824) (xy 331.90669 -370.113008)
			(xy 331.912468 -370.120164) (xy 331.934244 -370.145826) (xy 331.972193 -370.201411) (xy 332.003226 -370.261133)
			(xy 332.026899 -370.324137) (xy 332.042873 -370.389518) (xy 332.050918 -370.456339) (xy 332.050919 -370.523643)
			(xy 332.050912 -370.523703) (xy 335.328983 -370.523703) (xy 335.328984 -370.456279) (xy 335.33706 -370.389341)
			(xy 335.353096 -370.323852) (xy 335.376859 -370.260754) (xy 335.408009 -370.200957) (xy 335.446097 -370.145322)
			(xy 335.46796 -370.119656) (xy 335.473765 -370.112517) (xy 335.480273 -370.095322) (xy 335.48066 -370.086128)
			(xy 335.48066 -369.928902) (xy 335.481129 -369.918773) (xy 335.48886 -369.900048) (xy 335.503152 -369.885691)
			(xy 335.521841 -369.877875) (xy 335.531968 -369.87734) (xy 336.248248 -369.87734) (xy 336.25841 -369.877683)
			(xy 336.277171 -369.885502) (xy 336.291494 -369.899923) (xy 336.299185 -369.918737) (xy 336.299556 -369.928902)
			(xy 336.299556 -370.086128) (xy 336.299963 -370.095315) (xy 336.30648 -370.112499) (xy 336.312256 -370.119656)
			(xy 336.33411 -370.14533) (xy 336.372202 -370.200962) (xy 336.403355 -370.260757) (xy 336.427122 -370.323853)
			(xy 336.44316 -370.389341) (xy 336.451237 -370.456279) (xy 336.451238 -370.523644) (xy 339.729277 -370.523644)
			(xy 339.729279 -370.456338) (xy 339.737324 -370.389514) (xy 339.753299 -370.324131) (xy 339.776973 -370.261126)
			(xy 339.808008 -370.201402) (xy 339.845959 -370.145816) (xy 339.867748 -370.120164) (xy 339.873548 -370.113022)
			(xy 339.880059 -370.095829) (xy 339.880448 -370.086636) (xy 339.880448 -369.928902) (xy 339.880866 -369.918729)
			(xy 339.888652 -369.899933) (xy 339.903039 -369.885547) (xy 339.921837 -369.877764) (xy 339.93201 -369.87734)
			(xy 340.64829 -369.87734) (xy 340.658461 -369.877772) (xy 340.677256 -369.885554) (xy 340.691641 -369.899937)
			(xy 340.699426 -369.918731) (xy 340.699852 -369.928902) (xy 340.699852 -370.086636) (xy 340.700256 -370.095824)
			(xy 340.706775 -370.113007) (xy 340.712552 -370.120164) (xy 340.734328 -370.145826) (xy 340.772278 -370.201411)
			(xy 340.803312 -370.261133) (xy 340.826986 -370.324136) (xy 340.84296 -370.389517) (xy 340.851005 -370.456339)
			(xy 340.851006 -370.523643) (xy 340.851006 -370.523644) (xy 344.129068 -370.523644) (xy 344.129069 -370.456338)
			(xy 344.137115 -370.389515) (xy 344.153089 -370.324132) (xy 344.176763 -370.261127) (xy 344.207797 -370.201403)
			(xy 344.245748 -370.145816) (xy 344.267536 -370.120164) (xy 344.273335 -370.113021) (xy 344.279847 -370.095829)
			(xy 344.280236 -370.086636) (xy 344.280236 -369.928902) (xy 344.280735 -369.918745) (xy 344.288508 -369.899976)
			(xy 344.302873 -369.885611) (xy 344.321641 -369.877836) (xy 344.331798 -369.87734) (xy 345.048078 -369.87734)
			(xy 345.058248 -369.877782) (xy 345.077043 -369.88556) (xy 345.091429 -369.89994) (xy 345.099214 -369.918732)
			(xy 345.09964 -369.928902) (xy 345.09964 -370.086636) (xy 345.100046 -370.095823) (xy 345.106564 -370.113007)
			(xy 345.11234 -370.120164) (xy 345.134116 -370.145826) (xy 345.172067 -370.20141) (xy 345.203102 -370.261132)
			(xy 345.226776 -370.324136) (xy 345.242751 -370.389517) (xy 345.250796 -370.456339) (xy 345.250797 -370.523643)
			(xy 345.250797 -370.523644) (xy 374.929099 -370.523644) (xy 374.9291 -370.456338) (xy 374.937146 -370.389514)
			(xy 374.953121 -370.32413) (xy 374.976797 -370.261125) (xy 375.007834 -370.201402) (xy 375.045787 -370.145816)
			(xy 375.067576 -370.120164) (xy 375.073368 -370.113015) (xy 375.079886 -370.095828) (xy 375.080276 -370.086636)
			(xy 375.080276 -369.928902) (xy 375.080666 -369.918726) (xy 375.088458 -369.899924) (xy 375.102854 -369.885538)
			(xy 375.121661 -369.877759) (xy 375.131838 -369.87734) (xy 375.848118 -369.87734) (xy 375.858277 -369.877818)
			(xy 375.877047 -369.885599) (xy 375.891412 -369.89997) (xy 375.899185 -369.918743) (xy 375.89968 -369.928902)
			(xy 375.89968 -370.086636) (xy 375.900077 -370.095824) (xy 375.9066 -370.113008) (xy 375.91238 -370.120164)
			(xy 375.934155 -370.145826) (xy 375.972103 -370.201412) (xy 376.003136 -370.261134) (xy 376.026809 -370.324137)
			(xy 376.042782 -370.389518) (xy 376.050827 -370.456339) (xy 376.050828 -370.523643) (xy 376.050821 -370.523703)
			(xy 379.328892 -370.523703) (xy 379.328893 -370.456279) (xy 379.336969 -370.38934) (xy 379.353005 -370.323851)
			(xy 379.376769 -370.260754) (xy 379.40792 -370.200957) (xy 379.446008 -370.145322) (xy 379.467872 -370.119656)
			(xy 379.473678 -370.112518) (xy 379.480185 -370.095322) (xy 379.480572 -370.086128) (xy 379.480572 -369.928902)
			(xy 379.481029 -369.918772) (xy 379.488762 -369.900044) (xy 379.503058 -369.885687) (xy 379.521752 -369.877873)
			(xy 379.53188 -369.87734) (xy 380.24816 -369.87734) (xy 380.258316 -369.877755) (xy 380.277076 -369.885545)
			(xy 380.291402 -369.899945) (xy 380.299096 -369.918743) (xy 380.299468 -369.928902) (xy 380.299468 -370.086128)
			(xy 380.299872 -370.095316) (xy 380.306391 -370.1125) (xy 380.312168 -370.119656) (xy 380.334021 -370.14533)
			(xy 380.372112 -370.200963) (xy 380.403265 -370.260758) (xy 380.427032 -370.323853) (xy 380.443069 -370.389342)
			(xy 380.451146 -370.456279) (xy 380.451147 -370.523644) (xy 383.729187 -370.523644) (xy 383.729188 -370.456338)
			(xy 383.737234 -370.389514) (xy 383.753209 -370.324131) (xy 383.776884 -370.261126) (xy 383.807919 -370.201402)
			(xy 383.845871 -370.145816) (xy 383.86766 -370.120164) (xy 383.873462 -370.113023) (xy 383.879972 -370.095829)
			(xy 383.88036 -370.086636) (xy 383.88036 -369.928902) (xy 383.880766 -369.918728) (xy 383.888554 -369.899929)
			(xy 383.902946 -369.885543) (xy 383.921748 -369.877762) (xy 383.931922 -369.87734) (xy 384.648202 -369.87734)
			(xy 384.65836 -369.877832) (xy 384.67713 -369.885607) (xy 384.691495 -369.899974) (xy 384.699269 -369.918744)
			(xy 384.699764 -369.928902) (xy 384.699764 -370.086636) (xy 384.700165 -370.095824) (xy 384.706686 -370.113008)
			(xy 384.712464 -370.120164) (xy 384.73424 -370.145826) (xy 384.772189 -370.201411) (xy 384.803222 -370.261133)
			(xy 384.826895 -370.324137) (xy 384.842869 -370.389518) (xy 384.850914 -370.456339) (xy 384.850915 -370.523643)
			(xy 384.850915 -370.523644) (xy 388.128977 -370.523644) (xy 388.128979 -370.456338) (xy 388.137024 -370.389514)
			(xy 388.152999 -370.324131) (xy 388.176673 -370.261126) (xy 388.207708 -370.201402) (xy 388.245659 -370.145816)
			(xy 388.267448 -370.120164) (xy 388.273248 -370.113022) (xy 388.279759 -370.095829) (xy 388.280148 -370.086636)
			(xy 388.280148 -369.928902) (xy 388.280566 -369.918729) (xy 388.288352 -369.899933) (xy 388.302739 -369.885547)
			(xy 388.321537 -369.877764) (xy 388.33171 -369.87734) (xy 389.04799 -369.87734) (xy 389.058161 -369.877772)
			(xy 389.076956 -369.885554) (xy 389.091341 -369.899937) (xy 389.099126 -369.918731) (xy 389.099552 -369.928902)
			(xy 389.099552 -370.086636) (xy 389.099956 -370.095824) (xy 389.106475 -370.113007) (xy 389.112252 -370.120164)
			(xy 389.134028 -370.145826) (xy 389.171978 -370.201411) (xy 389.203012 -370.261133) (xy 389.226686 -370.324136)
			(xy 389.24266 -370.389517) (xy 389.250705 -370.456339) (xy 389.250706 -370.523643) (xy 389.250706 -370.523644)
			(xy 418.929008 -370.523644) (xy 418.929009 -370.456338) (xy 418.937055 -370.389513) (xy 418.953031 -370.32413)
			(xy 418.976707 -370.261125) (xy 419.007745 -370.201401) (xy 419.045698 -370.145816) (xy 419.067488 -370.120164)
			(xy 419.073281 -370.113016) (xy 419.079798 -370.095828) (xy 419.080188 -370.086636) (xy 419.080188 -369.928902)
			(xy 419.080567 -369.918724) (xy 419.08836 -369.89992) (xy 419.10276 -369.885533) (xy 419.121572 -369.877757)
			(xy 419.13175 -369.87734) (xy 419.84803 -369.87734) (xy 419.85819 -369.877809) (xy 419.87696 -369.885593)
			(xy 419.891325 -369.899967) (xy 419.899098 -369.918742) (xy 419.899592 -369.928902) (xy 419.899592 -370.086636)
			(xy 419.899986 -370.095825) (xy 419.906511 -370.113009) (xy 419.912292 -370.120164) (xy 419.934067 -370.145826)
			(xy 419.972014 -370.201412) (xy 420.003046 -370.261134) (xy 420.026718 -370.324138) (xy 420.042691 -370.389518)
			(xy 420.050736 -370.456339) (xy 420.050737 -370.523643) (xy 420.05073 -370.523703) (xy 423.328801 -370.523703)
			(xy 423.328802 -370.456279) (xy 423.336878 -370.38934) (xy 423.352915 -370.323851) (xy 423.37668 -370.260753)
			(xy 423.407831 -370.200957) (xy 423.44592 -370.145322) (xy 423.467784 -370.119656) (xy 423.47358 -370.11251)
			(xy 423.480095 -370.09532) (xy 423.480484 -370.086128) (xy 423.480484 -369.928902) (xy 423.48093 -369.91877)
			(xy 423.488665 -369.900041) (xy 423.502964 -369.885683) (xy 423.521662 -369.877871) (xy 423.531792 -369.87734)
			(xy 424.248072 -369.87734) (xy 424.258198 -369.87774) (xy 424.276908 -369.885486) (xy 424.291225 -369.899808)
			(xy 424.298964 -369.918522) (xy 424.29938 -369.928648) (xy 424.29938 -370.086128) (xy 424.299781 -370.095316)
			(xy 424.306302 -370.1125) (xy 424.31208 -370.119656) (xy 424.333933 -370.145331) (xy 424.372023 -370.200963)
			(xy 424.403176 -370.260758) (xy 424.426941 -370.323854) (xy 424.442978 -370.389342) (xy 424.451055 -370.456279)
			(xy 424.451056 -370.523644) (xy 427.729096 -370.523644) (xy 427.729097 -370.456338) (xy 427.737143 -370.389514)
			(xy 427.753118 -370.32413) (xy 427.776794 -370.261125) (xy 427.80783 -370.201402) (xy 427.845783 -370.145816)
			(xy 427.867572 -370.120164) (xy 427.873375 -370.113024) (xy 427.879884 -370.095829) (xy 427.880272 -370.086636)
			(xy 427.880272 -369.928902) (xy 427.880666 -369.918726) (xy 427.888457 -369.899925) (xy 427.902852 -369.885539)
			(xy 427.921658 -369.87776) (xy 427.931834 -369.87734) (xy 428.648114 -369.87734) (xy 428.658273 -369.877822)
			(xy 428.677043 -369.885602) (xy 428.691407 -369.899971) (xy 428.699181 -369.918743) (xy 428.699676 -369.928902)
			(xy 428.699676 -370.086636) (xy 428.700074 -370.095824) (xy 428.706597 -370.113008) (xy 428.712376 -370.120164)
			(xy 428.734152 -370.145826) (xy 428.7721 -370.201411) (xy 428.803133 -370.261134) (xy 428.826806 -370.324137)
			(xy 428.842779 -370.389518) (xy 428.850824 -370.456339) (xy 428.850825 -370.523643) (xy 428.850825 -370.523644)
			(xy 432.128887 -370.523644) (xy 432.128888 -370.456338) (xy 432.136934 -370.389514) (xy 432.152909 -370.324131)
			(xy 432.176584 -370.261126) (xy 432.207619 -370.201402) (xy 432.245571 -370.145816) (xy 432.26736 -370.120164)
			(xy 432.273162 -370.113023) (xy 432.279672 -370.095829) (xy 432.28006 -370.086636) (xy 432.28006 -369.928902)
			(xy 432.280466 -369.918728) (xy 432.288254 -369.899929) (xy 432.302646 -369.885543) (xy 432.321448 -369.877762)
			(xy 432.331622 -369.87734) (xy 433.047902 -369.87734) (xy 433.05806 -369.877832) (xy 433.07683 -369.885607)
			(xy 433.091195 -369.899974) (xy 433.098969 -369.918744) (xy 433.099464 -369.928902) (xy 433.099464 -370.086636)
			(xy 433.099865 -370.095824) (xy 433.106386 -370.113008) (xy 433.112164 -370.120164) (xy 433.13394 -370.145826)
			(xy 433.171889 -370.201411) (xy 433.202922 -370.261133) (xy 433.226595 -370.324137) (xy 433.242569 -370.389518)
			(xy 433.250614 -370.456339) (xy 433.250615 -370.523643) (xy 433.242572 -370.590465) (xy 433.226601 -370.655846)
			(xy 433.20293 -370.71885) (xy 433.171898 -370.778573) (xy 433.133951 -370.83416) (xy 433.112164 -370.859812)
			(xy 433.106375 -370.866963) (xy 433.099857 -370.884149) (xy 433.099464 -370.89334) (xy 433.099464 -371.386862)
			(xy 433.099901 -371.396046) (xy 433.106397 -371.41323) (xy 433.112164 -371.42039) (xy 433.133966 -371.446031)
			(xy 433.171914 -371.501619) (xy 433.202946 -371.561344) (xy 433.226383 -371.623725) (xy 434.329029 -371.623725)
			(xy 434.329032 -371.556418) (xy 434.33708 -371.489593) (xy 434.353056 -371.424209) (xy 434.376732 -371.361203)
			(xy 434.407768 -371.301478) (xy 434.445719 -371.245891) (xy 434.467508 -371.220238) (xy 434.473314 -371.2131)
			(xy 434.479823 -371.195904) (xy 434.480208 -371.18671) (xy 434.480208 -371.028722) (xy 434.48075 -371.018569)
			(xy 434.488512 -370.999806) (xy 434.502863 -370.985441) (xy 434.521618 -370.977661) (xy 434.53177 -370.97716)
			(xy 435.24805 -370.97716) (xy 435.258221 -370.977605) (xy 435.277019 -370.985378) (xy 435.291406 -370.999758)
			(xy 435.299189 -371.018551) (xy 435.299612 -371.028722) (xy 435.299612 -371.18671) (xy 435.300015 -371.195898)
			(xy 435.306533 -371.213082) (xy 435.312312 -371.220238) (xy 435.334064 -371.24592) (xy 435.372017 -371.301501)
			(xy 435.403055 -371.36122) (xy 435.426732 -371.424221) (xy 435.442709 -371.4896) (xy 435.450757 -371.55642)
			(xy 435.45076 -371.623723) (xy 435.442719 -371.690544) (xy 435.426749 -371.755924) (xy 435.403078 -371.818928)
			(xy 435.372046 -371.87865) (xy 435.334099 -371.934235) (xy 435.312312 -371.959886) (xy 435.306498 -371.967019)
			(xy 435.299993 -371.984219) (xy 435.299612 -371.993414) (xy 435.299612 -372.486682) (xy 435.300028 -372.495869)
			(xy 435.306537 -372.513053) (xy 435.312312 -372.52021) (xy 435.334135 -372.545834) (xy 435.372086 -372.601423)
			(xy 435.40312 -372.66115) (xy 435.426793 -372.724159) (xy 435.442765 -372.789545) (xy 435.450807 -372.856371)
			(xy 435.450804 -372.92368) (xy 435.442756 -372.990506) (xy 435.426778 -373.05589) (xy 435.403099 -373.118896)
			(xy 435.372059 -373.178621) (xy 435.334103 -373.234206) (xy 435.312312 -373.259858) (xy 435.30651 -373.266999)
			(xy 435.299998 -373.284193) (xy 435.299612 -373.293386) (xy 435.299612 -373.451374) (xy 435.299213 -373.46155)
			(xy 435.291428 -373.480354) (xy 435.277034 -373.494741) (xy 435.258226 -373.502518) (xy 435.24805 -373.502936)
			(xy 434.53177 -373.502936) (xy 434.521607 -373.502491) (xy 434.502832 -373.494701) (xy 434.488467 -373.480321)
			(xy 434.480698 -373.461537) (xy 434.480208 -373.451374) (xy 434.480208 -373.293386) (xy 434.479803 -373.284198)
			(xy 434.473286 -373.267014) (xy 434.467508 -373.259858) (xy 434.445755 -373.234178) (xy 434.407807 -373.178595)
			(xy 434.376774 -373.118875) (xy 434.3531 -373.055874) (xy 434.337126 -372.990495) (xy 434.32908 -372.923676)
			(xy 434.329077 -372.856375) (xy 434.337117 -372.789555) (xy 434.353085 -372.724175) (xy 434.376753 -372.661172)
			(xy 434.40778 -372.601449) (xy 434.445723 -372.545863) (xy 434.467508 -372.52021) (xy 434.473326 -372.51308)
			(xy 434.479828 -372.495878) (xy 434.480208 -372.486682) (xy 434.480208 -371.993414) (xy 434.479789 -371.984228)
			(xy 434.473281 -371.967043) (xy 434.467508 -371.959886) (xy 434.445684 -371.934264) (xy 434.407738 -371.878673)
			(xy 434.376708 -371.818945) (xy 434.353039 -371.755936) (xy 434.33707 -371.690551) (xy 434.329029 -371.623725)
			(xy 433.226383 -371.623725) (xy 433.226618 -371.62435) (xy 433.24259 -371.689734) (xy 433.250633 -371.756557)
			(xy 433.250632 -371.823864) (xy 433.242586 -371.890687) (xy 433.226612 -371.95607) (xy 433.202938 -372.019075)
			(xy 433.171903 -372.078799) (xy 433.133953 -372.134386) (xy 433.112164 -372.160038) (xy 433.106364 -372.167181)
			(xy 433.099852 -372.184373) (xy 433.099464 -372.193566) (xy 433.099464 -372.351554) (xy 433.098999 -372.361722)
			(xy 433.091229 -372.380516) (xy 433.076856 -372.394902) (xy 433.05807 -372.402689) (xy 433.047902 -372.403116)
			(xy 432.331622 -372.403116) (xy 432.321446 -372.402717) (xy 432.302643 -372.394931) (xy 432.288256 -372.380537)
			(xy 432.280478 -372.36173) (xy 432.28006 -372.351554) (xy 432.28006 -372.193566) (xy 432.279653 -372.184379)
			(xy 432.273135 -372.167195) (xy 432.26736 -372.160038) (xy 432.245586 -372.134375) (xy 432.207635 -372.07879)
			(xy 432.1766 -372.019069) (xy 432.152925 -371.956065) (xy 432.136951 -371.890684) (xy 432.128905 -371.823863)
			(xy 432.128904 -371.756558) (xy 432.136947 -371.689736) (xy 432.152919 -371.624355) (xy 432.176591 -371.561351)
			(xy 432.207624 -371.501628) (xy 432.245573 -371.446042) (xy 432.26736 -371.42039) (xy 432.273151 -371.413241)
			(xy 432.279667 -371.396053) (xy 432.28006 -371.386862) (xy 432.28006 -370.89334) (xy 432.279617 -370.884157)
			(xy 432.273125 -370.866972) (xy 432.26736 -370.859812) (xy 432.24556 -370.83417) (xy 432.20761 -370.778582)
			(xy 432.176576 -370.718858) (xy 432.152903 -370.655852) (xy 432.136931 -370.590468) (xy 432.128887 -370.523644)
			(xy 428.850825 -370.523644) (xy 428.842782 -370.590464) (xy 428.826811 -370.655846) (xy 428.80314 -370.71885)
			(xy 428.772109 -370.778573) (xy 428.734163 -370.83416) (xy 428.712376 -370.859812) (xy 428.706589 -370.866964)
			(xy 428.700069 -370.884149) (xy 428.699676 -370.89334) (xy 428.699676 -371.386862) (xy 428.70011 -371.396047)
			(xy 428.706608 -371.413231) (xy 428.712376 -371.42039) (xy 428.734177 -371.446031) (xy 428.772125 -371.501619)
			(xy 428.803156 -371.561345) (xy 428.826615 -371.623785) (xy 429.928709 -371.623785) (xy 429.928713 -371.556358)
			(xy 429.936793 -371.489417) (xy 429.952833 -371.423925) (xy 429.976602 -371.360827) (xy 430.007759 -371.30103)
			(xy 430.045853 -371.245395) (xy 430.06772 -371.21973) (xy 430.073531 -371.212595) (xy 430.080036 -371.195397)
			(xy 430.08042 -371.186202) (xy 430.08042 -371.028722) (xy 430.080944 -371.018599) (xy 430.088661 -370.999882)
			(xy 430.102935 -370.985526) (xy 430.121608 -370.977702) (xy 430.131728 -370.97716) (xy 430.848008 -370.97716)
			(xy 430.858158 -370.977614) (xy 430.876902 -370.985405) (xy 430.891224 -370.999791) (xy 430.898931 -371.018571)
			(xy 430.899316 -371.028722) (xy 430.899316 -371.186202) (xy 430.899722 -371.19539) (xy 430.906238 -371.212574)
			(xy 430.912016 -371.21973) (xy 430.933842 -371.245426) (xy 430.971931 -371.301057) (xy 431.003082 -371.360849)
			(xy 431.026848 -371.423942) (xy 431.042886 -371.489427) (xy 431.050964 -371.556361) (xy 431.050968 -371.623782)
			(xy 431.042896 -371.690717) (xy 431.026865 -371.756204) (xy 431.003106 -371.819299) (xy 430.97196 -371.879094)
			(xy 430.933877 -371.934729) (xy 430.912016 -371.960394) (xy 430.906241 -371.967555) (xy 430.899713 -371.984733)
			(xy 430.899316 -371.993922) (xy 430.899316 -372.486174) (xy 430.899735 -372.49536) (xy 430.906242 -372.512545)
			(xy 430.912016 -372.519702) (xy 430.933913 -372.54534) (xy 430.971999 -372.600979) (xy 431.003148 -372.660779)
			(xy 431.026909 -372.723879) (xy 431.042942 -372.789371) (xy 431.051015 -372.856313) (xy 431.051012 -372.923739)
			(xy 431.042933 -372.990679) (xy 431.026894 -373.05617) (xy 431.003127 -373.119268) (xy 430.971973 -373.179065)
			(xy 430.933881 -373.2347) (xy 430.912016 -373.260366) (xy 430.906211 -373.267505) (xy 430.899701 -373.2847)
			(xy 430.899316 -373.293894) (xy 430.899316 -373.451374) (xy 430.898851 -373.461504) (xy 430.891124 -373.480233)
			(xy 430.87683 -373.494592) (xy 430.858136 -373.502405) (xy 430.848008 -373.502936) (xy 430.131728 -373.502936)
			(xy 430.12158 -373.502456) (xy 430.102835 -373.494677) (xy 430.088512 -373.480298) (xy 430.080805 -373.461523)
			(xy 430.08042 -373.451374) (xy 430.08042 -373.293894) (xy 430.080008 -373.284707) (xy 430.073495 -373.267523)
			(xy 430.06772 -373.260366) (xy 430.045889 -373.234674) (xy 430.007798 -373.179043) (xy 429.976644 -373.119251)
			(xy 429.952877 -373.056158) (xy 429.936839 -372.990672) (xy 429.92876 -372.923736) (xy 429.928757 -372.856315)
			(xy 429.93683 -372.789379) (xy 429.952862 -372.723891) (xy 429.976624 -372.660796) (xy 430.007771 -372.601)
			(xy 430.045857 -372.545367) (xy 430.06772 -372.519702) (xy 430.073501 -372.512546) (xy 430.080024 -372.495364)
			(xy 430.08042 -372.486174) (xy 430.08042 -371.993922) (xy 430.079995 -371.984737) (xy 430.073491 -371.967552)
			(xy 430.06772 -371.960394) (xy 430.045818 -371.93476) (xy 430.007729 -371.879121) (xy 429.976579 -371.819321)
			(xy 429.952816 -371.75622) (xy 429.936783 -371.690727) (xy 429.928709 -371.623785) (xy 428.826615 -371.623785)
			(xy 428.826828 -371.624351) (xy 428.842799 -371.689734) (xy 428.850842 -371.756558) (xy 428.850841 -371.823863)
			(xy 428.842795 -371.890687) (xy 428.826821 -371.95607) (xy 428.803148 -372.019075) (xy 428.772114 -372.078799)
			(xy 428.734164 -372.134386) (xy 428.712376 -372.160038) (xy 428.706578 -372.167182) (xy 428.700065 -372.184374)
			(xy 428.699676 -372.193566) (xy 428.699676 -372.351554) (xy 428.699199 -372.361721) (xy 428.691432 -372.380512)
			(xy 428.677062 -372.394898) (xy 428.65828 -372.402687) (xy 428.648114 -372.403116) (xy 427.931834 -372.403116)
			(xy 427.921659 -372.402707) (xy 427.902856 -372.394925) (xy 427.888469 -372.380534) (xy 427.880691 -372.361729)
			(xy 427.880272 -372.351554) (xy 427.880272 -372.193566) (xy 427.879884 -372.184376) (xy 427.873356 -372.167192)
			(xy 427.867572 -372.160038) (xy 427.845797 -372.134375) (xy 427.807846 -372.078791) (xy 427.77681 -372.019069)
			(xy 427.753135 -371.956066) (xy 427.73716 -371.890685) (xy 427.729114 -371.823863) (xy 427.729113 -371.756558)
			(xy 427.737156 -371.689736) (xy 427.753129 -371.624354) (xy 427.776801 -371.56135) (xy 427.807835 -371.501627)
			(xy 427.845784 -371.446042) (xy 427.867572 -371.42039) (xy 427.873364 -371.413242) (xy 427.879879 -371.396053)
			(xy 427.880272 -371.386862) (xy 427.880272 -370.89334) (xy 427.879849 -370.884154) (xy 427.873345 -370.866969)
			(xy 427.867572 -370.859812) (xy 427.845772 -370.83417) (xy 427.807821 -370.778583) (xy 427.776786 -370.718858)
			(xy 427.753113 -370.655852) (xy 427.73714 -370.590468) (xy 427.729096 -370.523644) (xy 424.451056 -370.523644)
			(xy 424.451056 -370.523703) (xy 424.442981 -370.59064) (xy 424.426947 -370.656129) (xy 424.403183 -370.719225)
			(xy 424.372033 -370.779021) (xy 424.333944 -370.834655) (xy 424.31208 -370.86032) (xy 424.30629 -370.86747)
			(xy 424.299772 -370.884657) (xy 424.29938 -370.893848) (xy 424.29938 -371.386354) (xy 424.299817 -371.395538)
			(xy 424.306312 -371.412723) (xy 424.31208 -371.419882) (xy 424.333958 -371.445536) (xy 424.372048 -371.501171)
			(xy 424.403199 -371.560969) (xy 424.426835 -371.623725) (xy 425.528941 -371.623725) (xy 425.528945 -371.556418)
			(xy 425.536992 -371.489593) (xy 425.552969 -371.424208) (xy 425.576645 -371.361202) (xy 425.607682 -371.301478)
			(xy 425.645634 -371.24589) (xy 425.667424 -371.220238) (xy 425.673232 -371.213101) (xy 425.679739 -371.195904)
			(xy 425.680124 -371.18671) (xy 425.680124 -371.028722) (xy 425.680582 -371.018554) (xy 425.688357 -370.999762)
			(xy 425.702732 -370.985377) (xy 425.721518 -370.977589) (xy 425.731686 -370.97716) (xy 426.447966 -370.97716)
			(xy 426.458138 -370.977592) (xy 426.476936 -370.98537) (xy 426.491323 -370.999754) (xy 426.499105 -371.01855)
			(xy 426.499528 -371.028722) (xy 426.499528 -371.18671) (xy 426.499927 -371.195898) (xy 426.506448 -371.213083)
			(xy 426.512228 -371.220238) (xy 426.533979 -371.24592) (xy 426.571931 -371.301502) (xy 426.602968 -371.361221)
			(xy 426.626645 -371.424221) (xy 426.642621 -371.4896) (xy 426.650669 -371.55642) (xy 426.650672 -371.623723)
			(xy 426.642631 -371.690543) (xy 426.626661 -371.755924) (xy 426.602991 -371.818927) (xy 426.571961 -371.878649)
			(xy 426.534014 -371.934234) (xy 426.512228 -371.959886) (xy 426.506404 -371.967011) (xy 426.499908 -371.984217)
			(xy 426.499528 -371.993414) (xy 426.499528 -372.486682) (xy 426.49994 -372.495869) (xy 426.506452 -372.513054)
			(xy 426.512228 -372.52021) (xy 426.53405 -372.545834) (xy 426.572 -372.601424) (xy 426.603034 -372.661151)
			(xy 426.626706 -372.724159) (xy 426.642678 -372.789545) (xy 426.65072 -372.856371) (xy 426.650717 -372.92368)
			(xy 426.642669 -372.990505) (xy 426.626691 -373.05589) (xy 426.603013 -373.118896) (xy 426.571974 -373.17862)
			(xy 426.534019 -373.234206) (xy 426.512228 -373.259858) (xy 426.506416 -373.266992) (xy 426.499912 -373.284191)
			(xy 426.499528 -373.293386) (xy 426.499528 -373.451374) (xy 426.499114 -373.461548) (xy 426.491331 -373.480349)
			(xy 426.476942 -373.494736) (xy 426.45814 -373.502515) (xy 426.447966 -373.502936) (xy 425.731686 -373.502936)
			(xy 425.72151 -373.502547) (xy 425.70271 -373.494752) (xy 425.688325 -373.480356) (xy 425.680545 -373.46155)
			(xy 425.680124 -373.451374) (xy 425.680124 -373.293386) (xy 425.679715 -373.284199) (xy 425.6732 -373.267015)
			(xy 425.667424 -373.259858) (xy 425.64567 -373.234178) (xy 425.607722 -373.178595) (xy 425.576688 -373.118875)
			(xy 425.553014 -373.055874) (xy 425.537039 -372.990496) (xy 425.528992 -372.923677) (xy 425.528989 -372.856375)
			(xy 425.53703 -372.789555) (xy 425.552999 -372.724174) (xy 425.576667 -372.661171) (xy 425.607695 -372.601449)
			(xy 425.645639 -372.545863) (xy 425.667424 -372.52021) (xy 425.673244 -372.513082) (xy 425.679744 -372.495878)
			(xy 425.680124 -372.486682) (xy 425.680124 -371.993414) (xy 425.679702 -371.984228) (xy 425.673196 -371.967044)
			(xy 425.667424 -371.959886) (xy 425.645599 -371.934264) (xy 425.607653 -371.878673) (xy 425.576622 -371.818945)
			(xy 425.552952 -371.755937) (xy 425.536982 -371.690551) (xy 425.528941 -371.623725) (xy 424.426835 -371.623725)
			(xy 424.426964 -371.624067) (xy 424.442999 -371.689558) (xy 424.451074 -371.756498) (xy 424.451072 -371.823923)
			(xy 424.442995 -371.890863) (xy 424.426957 -371.956353) (xy 424.403191 -372.01945) (xy 424.372037 -372.079247)
			(xy 424.333946 -372.134881) (xy 424.31208 -372.160546) (xy 424.306279 -372.167688) (xy 424.299768 -372.184881)
			(xy 424.29938 -372.194074) (xy 424.29938 -372.351554) (xy 424.298836 -372.361675) (xy 424.291127 -372.380392)
			(xy 424.276858 -372.394749) (xy 424.25819 -372.402573) (xy 424.248072 -372.403116) (xy 423.531792 -372.403116)
			(xy 423.521685 -372.402622) (xy 423.50301 -372.394884) (xy 423.488716 -372.38059) (xy 423.480978 -372.361915)
			(xy 423.480484 -372.351808) (xy 423.480484 -372.194074) (xy 423.48009 -372.184885) (xy 423.473565 -372.167701)
			(xy 423.467784 -372.160546) (xy 423.445934 -372.134869) (xy 423.407846 -372.079236) (xy 423.376696 -372.019441)
			(xy 423.352932 -371.956346) (xy 423.336896 -371.890858) (xy 423.328819 -371.823922) (xy 423.328818 -371.756499)
			(xy 423.336892 -371.689562) (xy 423.352925 -371.624074) (xy 423.376687 -371.560978) (xy 423.407835 -371.501182)
			(xy 423.445921 -371.445547) (xy 423.467784 -371.419882) (xy 423.473569 -371.412728) (xy 423.480091 -371.395544)
			(xy 423.480484 -371.386354) (xy 423.480484 -370.893848) (xy 423.480055 -370.884663) (xy 423.473555 -370.867478)
			(xy 423.467784 -370.86032) (xy 423.445909 -370.834664) (xy 423.407821 -370.779028) (xy 423.376672 -370.71923)
			(xy 423.352909 -370.656132) (xy 423.336875 -370.590642) (xy 423.328801 -370.523703) (xy 420.05073 -370.523703)
			(xy 420.042694 -370.590464) (xy 420.026724 -370.655845) (xy 420.003054 -370.718849) (xy 419.972023 -370.778573)
			(xy 419.934078 -370.834159) (xy 419.912292 -370.859812) (xy 419.906507 -370.866965) (xy 419.899986 -370.88415)
			(xy 419.899592 -370.89334) (xy 419.899592 -371.386862) (xy 419.900022 -371.396047) (xy 419.906522 -371.413231)
			(xy 419.912292 -371.42039) (xy 419.934093 -371.446031) (xy 419.972039 -371.50162) (xy 420.00307 -371.561345)
			(xy 420.026528 -371.623785) (xy 421.128621 -371.623785) (xy 421.128625 -371.556358) (xy 421.136705 -371.489416)
			(xy 421.152746 -371.423925) (xy 421.176516 -371.360826) (xy 421.207673 -371.301029) (xy 421.245769 -371.245395)
			(xy 421.267636 -371.21973) (xy 421.273449 -371.212597) (xy 421.279953 -371.195397) (xy 421.280336 -371.186202)
			(xy 421.280336 -371.028722) (xy 421.280844 -371.018597) (xy 421.288564 -370.999877) (xy 421.302844 -370.98552)
			(xy 421.321522 -370.9777) (xy 421.331644 -370.97716) (xy 422.047924 -370.97716) (xy 422.058029 -370.977664)
			(xy 422.076701 -370.985402) (xy 422.090993 -370.999693) (xy 422.098734 -371.018363) (xy 422.099232 -371.028468)
			(xy 422.099232 -371.186202) (xy 422.099656 -371.195387) (xy 422.106162 -371.212571) (xy 422.111932 -371.21973)
			(xy 422.133758 -371.245427) (xy 422.171845 -371.301057) (xy 422.202996 -371.36085) (xy 422.226761 -371.423942)
			(xy 422.242798 -371.489427) (xy 422.250876 -371.556361) (xy 422.25088 -371.623781) (xy 422.242808 -371.690717)
			(xy 422.226778 -371.756203) (xy 422.203019 -371.819298) (xy 422.171875 -371.879094) (xy 422.133793 -371.934728)
			(xy 422.111932 -371.960394) (xy 422.106147 -371.967547) (xy 422.099627 -371.984732) (xy 422.099232 -371.993922)
			(xy 422.099232 -372.486174) (xy 422.09967 -372.495358) (xy 422.106166 -372.512542) (xy 422.111932 -372.519702)
			(xy 422.133828 -372.54534) (xy 422.171914 -372.600979) (xy 422.203061 -372.66078) (xy 422.226822 -372.72388)
			(xy 422.242854 -372.789372) (xy 422.250927 -372.856313) (xy 422.250924 -372.923738) (xy 422.242845 -372.990678)
			(xy 422.226807 -373.056169) (xy 422.20304 -373.119267) (xy 422.171888 -373.179064) (xy 422.133797 -373.2347)
			(xy 422.111932 -373.260366) (xy 422.106117 -373.267498) (xy 422.099615 -373.284699) (xy 422.099232 -373.293894)
			(xy 422.099232 -373.451374) (xy 422.098751 -373.461503) (xy 422.091027 -373.480228) (xy 422.076738 -373.494587)
			(xy 422.05805 -373.502402) (xy 422.047924 -373.502936) (xy 421.331644 -373.502936) (xy 421.321529 -373.502449)
			(xy 421.302833 -373.494722) (xy 421.288519 -373.480427) (xy 421.280765 -373.461743) (xy 421.280336 -373.451628)
			(xy 421.280336 -373.293894) (xy 421.279921 -373.284708) (xy 421.27341 -373.267524) (xy 421.267636 -373.260366)
			(xy 421.245804 -373.234674) (xy 421.207712 -373.179044) (xy 421.176558 -373.119252) (xy 421.15279 -373.056158)
			(xy 421.136751 -372.990672) (xy 421.128672 -372.923736) (xy 421.128669 -372.856315) (xy 421.136742 -372.789378)
			(xy 421.152775 -372.72389) (xy 421.176537 -372.660795) (xy 421.207686 -372.601) (xy 421.245773 -372.545367)
			(xy 421.267636 -372.519702) (xy 421.273419 -372.512547) (xy 421.279941 -372.495364) (xy 421.280336 -372.486174)
			(xy 421.280336 -371.993922) (xy 421.279907 -371.984737) (xy 421.273406 -371.967553) (xy 421.267636 -371.960394)
			(xy 421.245733 -371.93476) (xy 421.207643 -371.879122) (xy 421.176492 -371.819322) (xy 421.152729 -371.756221)
			(xy 421.136695 -371.690727) (xy 421.128621 -371.623785) (xy 420.026528 -371.623785) (xy 420.026741 -371.624351)
			(xy 420.042712 -371.689734) (xy 420.050754 -371.756558) (xy 420.050753 -371.823863) (xy 420.042708 -371.890686)
			(xy 420.026734 -371.956069) (xy 420.003061 -372.019074) (xy 419.972028 -372.078798) (xy 419.93408 -372.134385)
			(xy 419.912292 -372.160038) (xy 419.906496 -372.167183) (xy 419.899981 -372.184374) (xy 419.899592 -372.193566)
			(xy 419.899592 -372.351554) (xy 419.899099 -372.361719) (xy 419.891335 -372.380507) (xy 419.876971 -372.394892)
			(xy 419.858194 -372.402684) (xy 419.84803 -372.403116) (xy 419.13175 -372.403116) (xy 419.121576 -372.402694)
			(xy 419.102773 -372.394917) (xy 419.088385 -372.38053) (xy 419.080607 -372.361728) (xy 419.080188 -372.351554)
			(xy 419.080188 -372.193566) (xy 419.079797 -372.184377) (xy 419.07327 -372.167192) (xy 419.067488 -372.160038)
			(xy 419.045713 -372.134375) (xy 419.00776 -372.078791) (xy 418.976724 -372.01907) (xy 418.953048 -371.956067)
			(xy 418.937072 -371.890685) (xy 418.929026 -371.823863) (xy 418.929025 -371.756558) (xy 418.937069 -371.689736)
			(xy 418.953042 -371.624354) (xy 418.976715 -371.561349) (xy 419.007749 -371.501627) (xy 419.0457 -371.446041)
			(xy 419.067488 -371.42039) (xy 419.07327 -371.413234) (xy 419.079794 -371.396052) (xy 419.080188 -371.386862)
			(xy 419.080188 -370.89334) (xy 419.079761 -370.884154) (xy 419.07326 -370.86697) (xy 419.067488 -370.859812)
			(xy 419.045687 -370.83417) (xy 419.007735 -370.778583) (xy 418.9767 -370.718859) (xy 418.953026 -370.655853)
			(xy 418.937052 -370.590469) (xy 418.929008 -370.523644) (xy 389.250706 -370.523644) (xy 389.242663 -370.590465)
			(xy 389.226691 -370.655847) (xy 389.203019 -370.718851) (xy 389.171987 -370.778574) (xy 389.134039 -370.83416)
			(xy 389.112252 -370.859812) (xy 389.106462 -370.866962) (xy 389.099945 -370.884149) (xy 389.099552 -370.89334)
			(xy 389.099552 -371.386862) (xy 389.099991 -371.396046) (xy 389.106486 -371.41323) (xy 389.112252 -371.42039)
			(xy 389.134054 -371.446031) (xy 389.172003 -371.501618) (xy 389.203036 -371.561344) (xy 389.226474 -371.623725)
			(xy 390.32912 -371.623725) (xy 390.329123 -371.556418) (xy 390.337171 -371.489593) (xy 390.353146 -371.42421)
			(xy 390.376822 -371.361204) (xy 390.407857 -371.301479) (xy 390.445807 -371.245891) (xy 390.467596 -371.220238)
			(xy 390.473401 -371.213099) (xy 390.479911 -371.195904) (xy 390.480296 -371.18671) (xy 390.480296 -371.028722)
			(xy 390.48085 -371.018571) (xy 390.48861 -370.99981) (xy 390.502956 -370.985446) (xy 390.521707 -370.977663)
			(xy 390.531858 -370.97716) (xy 391.248138 -370.97716) (xy 391.258301 -370.977603) (xy 391.277075 -370.985394)
			(xy 391.29144 -370.999775) (xy 391.299209 -371.018558) (xy 391.2997 -371.028722) (xy 391.2997 -371.18671)
			(xy 391.300106 -371.195898) (xy 391.306623 -371.213082) (xy 391.3124 -371.220238) (xy 391.334149 -371.245921)
			(xy 391.372097 -371.301504) (xy 391.403129 -371.361224) (xy 391.426803 -371.424224) (xy 391.442777 -371.489602)
			(xy 391.450824 -371.556421) (xy 391.450827 -371.623722) (xy 391.442787 -371.690541) (xy 391.42682 -371.755921)
			(xy 391.403153 -371.818924) (xy 391.372126 -371.878647) (xy 391.334184 -371.934233) (xy 391.3124 -371.959886)
			(xy 391.306584 -371.967018) (xy 391.300081 -371.984219) (xy 391.2997 -371.993414) (xy 391.2997 -372.486682)
			(xy 391.300119 -372.495868) (xy 391.306627 -372.513053) (xy 391.3124 -372.52021) (xy 391.33422 -372.545835)
			(xy 391.372165 -372.601426) (xy 391.403195 -372.661154) (xy 391.426864 -372.724162) (xy 391.442833 -372.789547)
			(xy 391.450874 -372.856372) (xy 391.450871 -372.923679) (xy 391.442824 -372.990503) (xy 391.426849 -373.055887)
			(xy 391.403174 -373.118893) (xy 391.372139 -373.178617) (xy 391.334189 -373.234205) (xy 391.3124 -373.259858)
			(xy 391.306596 -373.266998) (xy 391.300086 -373.284193) (xy 391.2997 -373.293386) (xy 391.2997 -373.451374)
			(xy 391.299146 -373.461525) (xy 391.291388 -373.480287) (xy 391.277041 -373.494652) (xy 391.258289 -373.502434)
			(xy 391.248138 -373.502936) (xy 390.531858 -373.502936) (xy 390.521694 -373.5025) (xy 390.502919 -373.494707)
			(xy 390.488555 -373.480324) (xy 390.480786 -373.461538) (xy 390.480296 -373.451374) (xy 390.480296 -373.293386)
			(xy 390.479893 -373.284198) (xy 390.473374 -373.267014) (xy 390.467596 -373.259858) (xy 390.445843 -373.234178)
			(xy 390.407896 -373.178594) (xy 390.376864 -373.118874) (xy 390.353191 -373.055874) (xy 390.337217 -372.990495)
			(xy 390.329171 -372.923676) (xy 390.329167 -372.856375) (xy 390.337208 -372.789555) (xy 390.353176 -372.724175)
			(xy 390.376843 -372.661173) (xy 390.40787 -372.60145) (xy 390.445812 -372.545863) (xy 390.467596 -372.52021)
			(xy 390.473413 -372.513079) (xy 390.479916 -372.495878) (xy 390.480296 -372.486682) (xy 390.480296 -371.993414)
			(xy 390.47988 -371.984227) (xy 390.47337 -371.967043) (xy 390.467596 -371.959886) (xy 390.445772 -371.934264)
			(xy 390.407827 -371.878672) (xy 390.376798 -371.818944) (xy 390.353129 -371.755936) (xy 390.33716 -371.69055)
			(xy 390.32912 -371.623725) (xy 389.226474 -371.623725) (xy 389.226709 -371.62435) (xy 389.242681 -371.689733)
			(xy 389.250724 -371.756557) (xy 389.250723 -371.823864) (xy 389.242677 -371.890687) (xy 389.226702 -371.956071)
			(xy 389.203028 -372.019076) (xy 389.171992 -372.0788) (xy 389.134041 -372.134386) (xy 389.112252 -372.160038)
			(xy 389.106451 -372.16718) (xy 389.09994 -372.184373) (xy 389.099552 -372.193566) (xy 389.099552 -372.351554)
			(xy 389.099098 -372.361724) (xy 389.091327 -372.380519) (xy 389.07695 -372.394906) (xy 389.05816 -372.402691)
			(xy 389.04799 -372.403116) (xy 388.33171 -372.403116) (xy 388.321533 -372.402727) (xy 388.30273 -372.394937)
			(xy 388.288343 -372.38054) (xy 388.280566 -372.361731) (xy 388.280148 -372.351554) (xy 388.280148 -372.193566)
			(xy 388.279743 -372.184378) (xy 388.273225 -372.167195) (xy 388.267448 -372.160038) (xy 388.245674 -372.134375)
			(xy 388.207724 -372.07879) (xy 388.17669 -372.019068) (xy 388.153016 -371.956065) (xy 388.137042 -371.890684)
			(xy 388.128996 -371.823863) (xy 388.128995 -371.756558) (xy 388.137038 -371.689737) (xy 388.15301 -371.624355)
			(xy 388.176681 -371.561351) (xy 388.207713 -371.501628) (xy 388.245661 -371.446042) (xy 388.267448 -371.42039)
			(xy 388.273237 -371.41324) (xy 388.279755 -371.396053) (xy 388.280148 -371.386862) (xy 388.280148 -370.89334)
			(xy 388.279708 -370.884156) (xy 388.273214 -370.866972) (xy 388.267448 -370.859812) (xy 388.245648 -370.83417)
			(xy 388.207699 -370.778582) (xy 388.176666 -370.718857) (xy 388.152993 -370.655851) (xy 388.137021 -370.590468)
			(xy 388.128977 -370.523644) (xy 384.850915 -370.523644) (xy 384.842872 -370.590465) (xy 384.826901 -370.655846)
			(xy 384.80323 -370.71885) (xy 384.772198 -370.778573) (xy 384.734251 -370.83416) (xy 384.712464 -370.859812)
			(xy 384.706675 -370.866963) (xy 384.700157 -370.884149) (xy 384.699764 -370.89334) (xy 384.699764 -371.386862)
			(xy 384.700201 -371.396046) (xy 384.706697 -371.41323) (xy 384.712464 -371.42039) (xy 384.734266 -371.446031)
			(xy 384.772214 -371.501619) (xy 384.803246 -371.561344) (xy 384.826706 -371.623785) (xy 385.9288 -371.623785)
			(xy 385.928804 -371.556358) (xy 385.936884 -371.489417) (xy 385.952923 -371.423926) (xy 385.976692 -371.360827)
			(xy 386.007848 -371.30103) (xy 386.045941 -371.245395) (xy 386.067808 -371.21973) (xy 386.073618 -371.212594)
			(xy 386.080124 -371.195396) (xy 386.080508 -371.186202) (xy 386.080508 -371.028722) (xy 386.081044 -371.018601)
			(xy 386.088758 -370.999886) (xy 386.103029 -370.98553) (xy 386.121698 -370.977704) (xy 386.131816 -370.97716)
			(xy 386.848096 -370.97716) (xy 386.858245 -370.977624) (xy 386.876989 -370.985411) (xy 386.891311 -370.999794)
			(xy 386.899019 -371.018571) (xy 386.899404 -371.028722) (xy 386.899404 -371.186202) (xy 386.899812 -371.195389)
			(xy 386.906327 -371.212574) (xy 386.912104 -371.21973) (xy 386.93393 -371.245426) (xy 386.97202 -371.301056)
			(xy 387.003172 -371.360848) (xy 387.026938 -371.423941) (xy 387.042976 -371.489426) (xy 387.051055 -371.556361)
			(xy 387.051059 -371.623782) (xy 387.042987 -371.690717) (xy 387.026955 -371.756204) (xy 387.003196 -371.8193)
			(xy 386.972049 -371.879095) (xy 386.933966 -371.934729) (xy 386.912104 -371.960394) (xy 386.906328 -371.967554)
			(xy 386.899801 -371.984733) (xy 386.899404 -371.993922) (xy 386.899404 -372.486174) (xy 386.899826 -372.49536)
			(xy 386.906331 -372.512545) (xy 386.912104 -372.519702) (xy 386.934001 -372.54534) (xy 386.972089 -372.600978)
			(xy 387.003238 -372.660778) (xy 387.027 -372.723879) (xy 387.043033 -372.789371) (xy 387.051106 -372.856312)
			(xy 387.051103 -372.923739) (xy 387.043024 -372.990679) (xy 387.026985 -373.05617) (xy 387.003217 -373.119268)
			(xy 386.972062 -373.179066) (xy 386.93397 -373.234701) (xy 386.912104 -373.260366) (xy 386.906297 -373.267504)
			(xy 386.899789 -373.2847) (xy 386.899404 -373.293894) (xy 386.899404 -373.451374) (xy 386.898854 -373.461494)
			(xy 386.891142 -373.480206) (xy 386.876876 -373.494562) (xy 386.858212 -373.50239) (xy 386.848096 -373.502936)
			(xy 386.131816 -373.502936) (xy 386.121667 -373.502466) (xy 386.102922 -373.494683) (xy 386.0886 -373.480301)
			(xy 386.080893 -373.461524) (xy 386.080508 -373.451374) (xy 386.080508 -373.293894) (xy 386.080099 -373.284707)
			(xy 386.073584 -373.267523) (xy 386.067808 -373.260366) (xy 386.045977 -373.234673) (xy 386.007887 -373.179043)
			(xy 385.976734 -373.119251) (xy 385.952968 -373.056157) (xy 385.93693 -372.990671) (xy 385.928851 -372.923736)
			(xy 385.928848 -372.856315) (xy 385.936921 -372.789379) (xy 385.952953 -372.723892) (xy 385.976713 -372.660796)
			(xy 386.007861 -372.601001) (xy 386.045946 -372.545367) (xy 386.067808 -372.519702) (xy 386.073587 -372.512544)
			(xy 386.080112 -372.495363) (xy 386.080508 -372.486174) (xy 386.080508 -371.993922) (xy 386.080085 -371.984736)
			(xy 386.07358 -371.967552) (xy 386.067808 -371.960394) (xy 386.045906 -371.93476) (xy 386.007818 -371.879121)
			(xy 385.976669 -371.819321) (xy 385.952906 -371.75622) (xy 385.936873 -371.690727) (xy 385.9288 -371.623785)
			(xy 384.826706 -371.623785) (xy 384.826918 -371.62435) (xy 384.84289 -371.689734) (xy 384.850933 -371.756557)
			(xy 384.850932 -371.823864) (xy 384.842886 -371.890687) (xy 384.826912 -371.95607) (xy 384.803238 -372.019075)
			(xy 384.772203 -372.078799) (xy 384.734253 -372.134386) (xy 384.712464 -372.160038) (xy 384.706664 -372.167181)
			(xy 384.700152 -372.184373) (xy 384.699764 -372.193566) (xy 384.699764 -372.351554) (xy 384.699299 -372.361722)
			(xy 384.691529 -372.380516) (xy 384.677156 -372.394902) (xy 384.65837 -372.402689) (xy 384.648202 -372.403116)
			(xy 383.931922 -372.403116) (xy 383.921746 -372.402717) (xy 383.902943 -372.394931) (xy 383.888556 -372.380537)
			(xy 383.880778 -372.36173) (xy 383.88036 -372.351554) (xy 383.88036 -372.193566) (xy 383.879953 -372.184379)
			(xy 383.873435 -372.167195) (xy 383.86766 -372.160038) (xy 383.845886 -372.134375) (xy 383.807935 -372.07879)
			(xy 383.7769 -372.019069) (xy 383.753225 -371.956065) (xy 383.737251 -371.890684) (xy 383.729205 -371.823863)
			(xy 383.729204 -371.756558) (xy 383.737247 -371.689736) (xy 383.753219 -371.624355) (xy 383.776891 -371.561351)
			(xy 383.807924 -371.501628) (xy 383.845873 -371.446042) (xy 383.86766 -371.42039) (xy 383.873451 -371.413241)
			(xy 383.879967 -371.396053) (xy 383.88036 -371.386862) (xy 383.88036 -370.89334) (xy 383.879917 -370.884157)
			(xy 383.873425 -370.866972) (xy 383.86766 -370.859812) (xy 383.84586 -370.83417) (xy 383.80791 -370.778582)
			(xy 383.776876 -370.718858) (xy 383.753203 -370.655852) (xy 383.737231 -370.590468) (xy 383.729187 -370.523644)
			(xy 380.451147 -370.523644) (xy 380.451147 -370.523703) (xy 380.443072 -370.590641) (xy 380.427037 -370.656129)
			(xy 380.403273 -370.719226) (xy 380.372122 -370.779022) (xy 380.334032 -370.834655) (xy 380.312168 -370.86032)
			(xy 380.306376 -370.867469) (xy 380.299859 -370.884657) (xy 380.299468 -370.893848) (xy 380.299468 -371.386354)
			(xy 380.299908 -371.395538) (xy 380.306402 -371.412722) (xy 380.312168 -371.419882) (xy 380.334047 -371.445535)
			(xy 380.372137 -371.501171) (xy 380.403289 -371.560968) (xy 380.426925 -371.623725) (xy 381.529032 -371.623725)
			(xy 381.529035 -371.556418) (xy 381.537083 -371.489593) (xy 381.553059 -371.424209) (xy 381.576735 -371.361203)
			(xy 381.607771 -371.301478) (xy 381.645723 -371.245891) (xy 381.667512 -371.220238) (xy 381.673319 -371.2131)
			(xy 381.679827 -371.195904) (xy 381.680212 -371.18671) (xy 381.680212 -371.028722) (xy 381.680751 -371.018569)
			(xy 381.688513 -370.999805) (xy 381.702865 -370.98544) (xy 381.721621 -370.97766) (xy 381.731774 -370.97716)
			(xy 382.448054 -370.97716) (xy 382.458225 -370.977602) (xy 382.477023 -370.985376) (xy 382.491411 -370.999757)
			(xy 382.499193 -371.018551) (xy 382.499616 -371.028722) (xy 382.499616 -371.18671) (xy 382.500018 -371.195898)
			(xy 382.506537 -371.213083) (xy 382.512316 -371.220238) (xy 382.534068 -371.24592) (xy 382.572021 -371.301501)
			(xy 382.603058 -371.36122) (xy 382.626735 -371.424221) (xy 382.642712 -371.4896) (xy 382.65076 -371.55642)
			(xy 382.650763 -371.623723) (xy 382.642722 -371.690544) (xy 382.626752 -371.755924) (xy 382.603081 -371.818927)
			(xy 382.57205 -371.87865) (xy 382.534103 -371.934234) (xy 382.512316 -371.959886) (xy 382.506502 -371.967019)
			(xy 382.499997 -371.984219) (xy 382.499616 -371.993414) (xy 382.499616 -372.486682) (xy 382.500031 -372.495869)
			(xy 382.506541 -372.513053) (xy 382.512316 -372.52021) (xy 382.534138 -372.545834) (xy 382.572089 -372.601424)
			(xy 382.603123 -372.661151) (xy 382.626796 -372.724159) (xy 382.642768 -372.789545) (xy 382.65081 -372.856371)
			(xy 382.650807 -372.92368) (xy 382.642759 -372.990506) (xy 382.626781 -373.05589) (xy 382.603103 -373.118896)
			(xy 382.572063 -373.17862) (xy 382.534107 -373.234206) (xy 382.512316 -373.259858) (xy 382.506514 -373.267)
			(xy 382.500002 -373.284193) (xy 382.499616 -373.293386) (xy 382.499616 -373.451374) (xy 382.499214 -373.46155)
			(xy 382.491429 -373.480352) (xy 382.477036 -373.49474) (xy 382.45823 -373.502517) (xy 382.448054 -373.502936)
			(xy 381.731774 -373.502936) (xy 381.721611 -373.502487) (xy 381.702837 -373.4947) (xy 381.688471 -373.48032)
			(xy 381.680702 -373.461537) (xy 381.680212 -373.451374) (xy 381.680212 -373.293386) (xy 381.679806 -373.284198)
			(xy 381.673289 -373.267014) (xy 381.667512 -373.259858) (xy 381.645758 -373.234178) (xy 381.60781 -373.178595)
			(xy 381.576777 -373.118875) (xy 381.553104 -373.055874) (xy 381.537129 -372.990496) (xy 381.529083 -372.923676)
			(xy 381.52908 -372.856375) (xy 381.53712 -372.789555) (xy 381.553088 -372.724175) (xy 381.576756 -372.661172)
			(xy 381.607784 -372.601449) (xy 381.645727 -372.545862) (xy 381.667512 -372.52021) (xy 381.673331 -372.51308)
			(xy 381.679832 -372.495878) (xy 381.680212 -372.486682) (xy 381.680212 -371.993414) (xy 381.679792 -371.984228)
			(xy 381.673285 -371.967044) (xy 381.667512 -371.959886) (xy 381.645688 -371.934264) (xy 381.607742 -371.878673)
			(xy 381.576712 -371.818945) (xy 381.553042 -371.755936) (xy 381.537073 -371.690551) (xy 381.529032 -371.623725)
			(xy 380.426925 -371.623725) (xy 380.427054 -371.624067) (xy 380.443089 -371.689558) (xy 380.451165 -371.756498)
			(xy 380.451163 -371.823923) (xy 380.443086 -371.890863) (xy 380.427048 -371.956353) (xy 380.403281 -372.019451)
			(xy 380.372126 -372.079247) (xy 380.334034 -372.134881) (xy 380.312168 -372.160546) (xy 380.306365 -372.167687)
			(xy 380.299855 -372.184881) (xy 380.299468 -372.194074) (xy 380.299468 -372.351554) (xy 380.298936 -372.361677)
			(xy 380.291225 -372.380395) (xy 380.276952 -372.394753) (xy 380.25828 -372.402575) (xy 380.24816 -372.403116)
			(xy 379.53188 -372.403116) (xy 379.521727 -372.402695) (xy 379.502977 -372.394896) (xy 379.488655 -372.3805)
			(xy 379.480953 -372.36171) (xy 379.480572 -372.351554) (xy 379.480572 -372.194074) (xy 379.480181 -372.184885)
			(xy 379.473655 -372.1677) (xy 379.467872 -372.160546) (xy 379.446023 -372.134869) (xy 379.407935 -372.079235)
			(xy 379.376786 -372.019441) (xy 379.353022 -371.956345) (xy 379.336986 -371.890858) (xy 379.32891 -371.823922)
			(xy 379.328909 -371.7565) (xy 379.336983 -371.689563) (xy 379.353016 -371.624075) (xy 379.376777 -371.560979)
			(xy 379.407925 -371.501183) (xy 379.44601 -371.445548) (xy 379.467872 -371.419882) (xy 379.473667 -371.412736)
			(xy 379.480181 -371.395546) (xy 379.480572 -371.386354) (xy 379.480572 -370.893848) (xy 379.480145 -370.884663)
			(xy 379.473644 -370.867478) (xy 379.467872 -370.86032) (xy 379.445997 -370.834664) (xy 379.407911 -370.779027)
			(xy 379.376762 -370.71923) (xy 379.353 -370.656132) (xy 379.336966 -370.590642) (xy 379.328892 -370.523703)
			(xy 376.050821 -370.523703) (xy 376.042785 -370.590464) (xy 376.026814 -370.655846) (xy 376.003143 -370.71885)
			(xy 375.972113 -370.778573) (xy 375.934166 -370.83416) (xy 375.91238 -370.859812) (xy 375.906594 -370.866964)
			(xy 375.900073 -370.884149) (xy 375.89968 -370.89334) (xy 375.89968 -371.386862) (xy 375.900113 -371.396047)
			(xy 375.906611 -371.413231) (xy 375.91238 -371.42039) (xy 375.934181 -371.446031) (xy 375.972128 -371.50162)
			(xy 376.00316 -371.561345) (xy 376.026618 -371.623785) (xy 377.128712 -371.623785) (xy 377.128716 -371.556358)
			(xy 377.136796 -371.489417) (xy 377.152836 -371.423925) (xy 377.176606 -371.360827) (xy 377.207762 -371.301029)
			(xy 377.245857 -371.245395) (xy 377.267724 -371.21973) (xy 377.273536 -371.212596) (xy 377.28004 -371.195397)
			(xy 377.280424 -371.186202) (xy 377.280424 -371.028722) (xy 377.280944 -371.018599) (xy 377.288662 -370.999881)
			(xy 377.302938 -370.985524) (xy 377.321612 -370.977702) (xy 377.331732 -370.97716) (xy 378.048012 -370.97716)
			(xy 378.058162 -370.977611) (xy 378.076907 -370.985403) (xy 378.091229 -370.99979) (xy 378.098935 -371.01857)
			(xy 378.09932 -371.028722) (xy 378.09932 -371.186202) (xy 378.099725 -371.19539) (xy 378.106242 -371.212574)
			(xy 378.11202 -371.21973) (xy 378.133846 -371.245426) (xy 378.171934 -371.301057) (xy 378.203086 -371.360849)
			(xy 378.226851 -371.423942) (xy 378.242889 -371.489427) (xy 378.250967 -371.556361) (xy 378.250971 -371.623782)
			(xy 378.242899 -371.690717) (xy 378.226868 -371.756204) (xy 378.203109 -371.819299) (xy 378.171964 -371.879094)
			(xy 378.133881 -371.934728) (xy 378.11202 -371.960394) (xy 378.106246 -371.967555) (xy 378.099717 -371.984733)
			(xy 378.09932 -371.993922) (xy 378.09932 -372.486174) (xy 378.099738 -372.49536) (xy 378.106246 -372.512545)
			(xy 378.11202 -372.519702) (xy 378.133917 -372.54534) (xy 378.172003 -372.600979) (xy 378.203151 -372.660779)
			(xy 378.226913 -372.723879) (xy 378.242945 -372.789372) (xy 378.251018 -372.856313) (xy 378.251015 -372.923739)
			(xy 378.242936 -372.990679) (xy 378.226897 -373.056169) (xy 378.20313 -373.119268) (xy 378.171977 -373.179065)
			(xy 378.133885 -373.2347) (xy 378.11202 -373.260366) (xy 378.106215 -373.267506) (xy 378.099705 -373.2847)
			(xy 378.09932 -373.293894) (xy 378.09932 -373.451374) (xy 378.098851 -373.461504) (xy 378.091125 -373.480232)
			(xy 378.076832 -373.494591) (xy 378.05814 -373.502404) (xy 378.048012 -373.502936) (xy 377.331732 -373.502936)
			(xy 377.321584 -373.502453) (xy 377.30284 -373.494675) (xy 377.288516 -373.480297) (xy 377.280809 -373.461523)
			(xy 377.280424 -373.451374) (xy 377.280424 -373.293894) (xy 377.280012 -373.284707) (xy 377.273499 -373.267523)
			(xy 377.267724 -373.260366) (xy 377.245893 -373.234674) (xy 377.207801 -373.179044) (xy 377.176648 -373.119251)
			(xy 377.152881 -373.056158) (xy 377.136842 -372.990672) (xy 377.128763 -372.923736) (xy 377.12876 -372.856315)
			(xy 377.136833 -372.789378) (xy 377.152865 -372.723891) (xy 377.176627 -372.660795) (xy 377.207775 -372.601)
			(xy 377.245861 -372.545367) (xy 377.267724 -372.519702) (xy 377.273505 -372.512546) (xy 377.280028 -372.495364)
			(xy 377.280424 -372.486174) (xy 377.280424 -371.993922) (xy 377.279998 -371.984737) (xy 377.273495 -371.967552)
			(xy 377.267724 -371.960394) (xy 377.245822 -371.93476) (xy 377.207733 -371.879122) (xy 377.176582 -371.819321)
			(xy 377.152819 -371.75622) (xy 377.136786 -371.690727) (xy 377.128712 -371.623785) (xy 376.026618 -371.623785)
			(xy 376.026831 -371.624351) (xy 376.042802 -371.689734) (xy 376.050845 -371.756558) (xy 376.050844 -371.823863)
			(xy 376.042799 -371.890687) (xy 376.026825 -371.956069) (xy 376.003151 -372.019074) (xy 375.972117 -372.078799)
			(xy 375.934168 -372.134386) (xy 375.91238 -372.160038) (xy 375.906582 -372.167182) (xy 375.900069 -372.184374)
			(xy 375.89968 -372.193566) (xy 375.89968 -372.351554) (xy 375.899199 -372.36172) (xy 375.891432 -372.380511)
			(xy 375.877064 -372.394896) (xy 375.858284 -372.402686) (xy 375.848118 -372.403116) (xy 375.131838 -372.403116)
			(xy 375.121663 -372.402704) (xy 375.102861 -372.394923) (xy 375.088473 -372.380533) (xy 375.080695 -372.361729)
			(xy 375.080276 -372.351554) (xy 375.080276 -372.193566) (xy 375.079887 -372.184376) (xy 375.073359 -372.167192)
			(xy 375.067576 -372.160038) (xy 375.045801 -372.134375) (xy 375.007849 -372.078791) (xy 374.976813 -372.019069)
			(xy 374.953138 -371.956066) (xy 374.937163 -371.890685) (xy 374.929117 -371.823863) (xy 374.929116 -371.756558)
			(xy 374.937159 -371.689736) (xy 374.953132 -371.624354) (xy 374.976805 -371.56135) (xy 375.007838 -371.501627)
			(xy 375.045788 -371.446042) (xy 375.067576 -371.42039) (xy 375.073357 -371.413233) (xy 375.079882 -371.396052)
			(xy 375.080276 -371.386862) (xy 375.080276 -370.89334) (xy 375.079852 -370.884154) (xy 375.073349 -370.866969)
			(xy 375.067576 -370.859812) (xy 375.045775 -370.83417) (xy 375.007825 -370.778583) (xy 374.97679 -370.718858)
			(xy 374.953116 -370.655852) (xy 374.937143 -370.590469) (xy 374.929099 -370.523644) (xy 345.250797 -370.523644)
			(xy 345.242754 -370.590465) (xy 345.226782 -370.655847) (xy 345.203109 -370.718851) (xy 345.172076 -370.778574)
			(xy 345.134128 -370.83416) (xy 345.11234 -370.859812) (xy 345.106548 -370.86696) (xy 345.100032 -370.884149)
			(xy 345.09964 -370.89334) (xy 345.09964 -371.386862) (xy 345.100082 -371.396046) (xy 345.106575 -371.41323)
			(xy 345.11234 -371.42039) (xy 345.134142 -371.446031) (xy 345.172092 -371.501618) (xy 345.203126 -371.561343)
			(xy 345.226564 -371.623726) (xy 346.329187 -371.623726) (xy 346.32919 -371.556417) (xy 346.337239 -371.489591)
			(xy 346.353217 -371.424206) (xy 346.376896 -371.3612) (xy 346.407936 -371.301476) (xy 346.445893 -371.24589)
			(xy 346.467684 -371.220238) (xy 346.473488 -371.213098) (xy 346.479999 -371.195904) (xy 346.480384 -371.18671)
			(xy 346.480384 -371.028722) (xy 346.480783 -371.018546) (xy 346.488569 -370.999743) (xy 346.502963 -370.985356)
			(xy 346.52177 -370.977578) (xy 346.531946 -370.97716) (xy 347.248226 -370.97716) (xy 347.258388 -370.977612)
			(xy 347.277162 -370.9854) (xy 347.291527 -370.999778) (xy 347.299297 -371.018559) (xy 347.299788 -371.028722)
			(xy 347.299788 -371.18671) (xy 347.300196 -371.195897) (xy 347.306711 -371.213082) (xy 347.312488 -371.220238)
			(xy 347.334237 -371.245921) (xy 347.372185 -371.301504) (xy 347.403219 -371.361224) (xy 347.426893 -371.424224)
			(xy 347.442867 -371.489602) (xy 347.450914 -371.556421) (xy 347.450918 -371.623722) (xy 347.442878 -371.690542)
			(xy 347.426909 -371.755921) (xy 347.403242 -371.818924) (xy 347.372215 -371.878647) (xy 347.334272 -371.934233)
			(xy 347.312488 -371.959886) (xy 347.306671 -371.967017) (xy 347.300169 -371.984218) (xy 347.299788 -371.993414)
			(xy 347.299788 -372.486682) (xy 347.30021 -372.495868) (xy 347.306716 -372.513052) (xy 347.312488 -372.52021)
			(xy 347.334308 -372.545835) (xy 347.372254 -372.601426) (xy 347.403285 -372.661154) (xy 347.426954 -372.724162)
			(xy 347.442924 -372.789547) (xy 347.450965 -372.856372) (xy 347.450962 -372.923679) (xy 347.442915 -372.990504)
			(xy 347.426939 -373.055887) (xy 347.403264 -373.118893) (xy 347.372228 -373.178618) (xy 347.334277 -373.234205)
			(xy 347.312488 -373.259858) (xy 347.306683 -373.266997) (xy 347.300174 -373.284192) (xy 347.299788 -373.293386)
			(xy 347.299788 -373.451374) (xy 347.299246 -373.461527) (xy 347.291485 -373.480291) (xy 347.277134 -373.494656)
			(xy 347.258378 -373.502436) (xy 347.248226 -373.502936) (xy 346.531946 -373.502936) (xy 346.521774 -373.502498)
			(xy 346.502975 -373.494723) (xy 346.488588 -373.480341) (xy 346.480806 -373.461546) (xy 346.480384 -373.451374)
			(xy 346.480384 -373.293386) (xy 346.479984 -373.284198) (xy 346.473464 -373.267013) (xy 346.467684 -373.259858)
			(xy 346.445928 -373.234179) (xy 346.407976 -373.178597) (xy 346.376938 -373.118878) (xy 346.353262 -373.055877)
			(xy 346.337285 -372.990498) (xy 346.329237 -372.923677) (xy 346.329234 -372.856374) (xy 346.337276 -372.789553)
			(xy 346.353247 -372.724172) (xy 346.376917 -372.661169) (xy 346.407949 -372.601447) (xy 346.445897 -372.545862)
			(xy 346.467684 -372.52021) (xy 346.473499 -372.513078) (xy 346.480003 -372.495877) (xy 346.480384 -372.486682)
			(xy 346.480384 -371.993414) (xy 346.479971 -371.984227) (xy 346.47346 -371.967042) (xy 346.467684 -371.959886)
			(xy 346.445858 -371.934265) (xy 346.407907 -371.878675) (xy 346.376873 -371.818948) (xy 346.3532 -371.755939)
			(xy 346.337229 -371.690553) (xy 346.329187 -371.623726) (xy 345.226564 -371.623726) (xy 345.226798 -371.624349)
			(xy 345.242771 -371.689733) (xy 345.250814 -371.756557) (xy 345.250813 -371.823864) (xy 345.242767 -371.890688)
			(xy 345.226792 -371.956071) (xy 345.203117 -372.019076) (xy 345.172081 -372.0788) (xy 345.134129 -372.134386)
			(xy 345.11234 -372.160038) (xy 345.106537 -372.167179) (xy 345.100028 -372.184373) (xy 345.09964 -372.193566)
			(xy 345.09964 -372.351554) (xy 345.099198 -372.361725) (xy 345.091424 -372.380523) (xy 345.077043 -372.394911)
			(xy 345.058249 -372.402693) (xy 345.048078 -372.403116) (xy 344.331798 -372.403116) (xy 344.321621 -372.402737)
			(xy 344.302817 -372.394942) (xy 344.288431 -372.380543) (xy 344.280654 -372.361732) (xy 344.280236 -372.351554)
			(xy 344.280236 -372.193566) (xy 344.279834 -372.184378) (xy 344.273314 -372.167194) (xy 344.267536 -372.160038)
			(xy 344.245762 -372.134374) (xy 344.207813 -372.078789) (xy 344.17678 -372.019067) (xy 344.153106 -371.956064)
			(xy 344.137132 -371.890684) (xy 344.129087 -371.823862) (xy 344.129086 -371.756559) (xy 344.137129 -371.689737)
			(xy 344.1531 -371.624356) (xy 344.176771 -371.561352) (xy 344.207803 -371.501629) (xy 344.245749 -371.446042)
			(xy 344.267536 -371.42039) (xy 344.273324 -371.413239) (xy 344.279843 -371.396053) (xy 344.280236 -371.386862)
			(xy 344.280236 -370.89334) (xy 344.279798 -370.884156) (xy 344.273303 -370.866972) (xy 344.267536 -370.859812)
			(xy 344.245736 -370.83417) (xy 344.207788 -370.778582) (xy 344.176756 -370.718857) (xy 344.153084 -370.655851)
			(xy 344.137112 -370.590468) (xy 344.129068 -370.523644) (xy 340.851006 -370.523644) (xy 340.842963 -370.590465)
			(xy 340.826991 -370.655847) (xy 340.803319 -370.718851) (xy 340.772287 -370.778574) (xy 340.734339 -370.83416)
			(xy 340.712552 -370.859812) (xy 340.706762 -370.866962) (xy 340.700245 -370.884149) (xy 340.699852 -370.89334)
			(xy 340.699852 -371.386862) (xy 340.700291 -371.396046) (xy 340.706786 -371.41323) (xy 340.712552 -371.42039)
			(xy 340.734354 -371.446031) (xy 340.772303 -371.501618) (xy 340.803336 -371.561344) (xy 340.826797 -371.623785)
			(xy 341.928891 -371.623785) (xy 341.928895 -371.556358) (xy 341.936974 -371.489417) (xy 341.953014 -371.423926)
			(xy 341.976782 -371.360828) (xy 342.007937 -371.301031) (xy 342.04603 -371.245395) (xy 342.067896 -371.21973)
			(xy 342.073704 -371.212593) (xy 342.080212 -371.195396) (xy 342.080596 -371.186202) (xy 342.080596 -371.028722)
			(xy 342.081143 -371.018602) (xy 342.088856 -370.99989) (xy 342.103123 -370.985534) (xy 342.121787 -370.977706)
			(xy 342.131904 -370.97716) (xy 342.848184 -370.97716) (xy 342.858332 -370.977634) (xy 342.877076 -370.985417)
			(xy 342.891399 -370.999797) (xy 342.899106 -371.018572) (xy 342.899492 -371.028722) (xy 342.899492 -371.186202)
			(xy 342.899903 -371.195389) (xy 342.906416 -371.212573) (xy 342.912192 -371.21973) (xy 342.934019 -371.245426)
			(xy 342.972109 -371.301056) (xy 343.003262 -371.360848) (xy 343.027029 -371.423941) (xy 343.043067 -371.489426)
			(xy 343.051146 -371.556361) (xy 343.05115 -371.623782) (xy 343.043077 -371.690718) (xy 343.027046 -371.756205)
			(xy 343.003285 -371.8193) (xy 342.972139 -371.879095) (xy 342.934054 -371.934729) (xy 342.912192 -371.960394)
			(xy 342.906415 -371.967553) (xy 342.899889 -371.984733) (xy 342.899492 -371.993922) (xy 342.899492 -372.486174)
			(xy 342.899917 -372.49536) (xy 342.90642 -372.512544) (xy 342.912192 -372.519702) (xy 342.93409 -372.54534)
			(xy 342.972178 -372.600978) (xy 343.003328 -372.660778) (xy 343.02709 -372.723878) (xy 343.043124 -372.789371)
			(xy 343.051197 -372.856312) (xy 343.051194 -372.923739) (xy 343.043114 -372.99068) (xy 343.027075 -373.056171)
			(xy 343.003307 -373.119269) (xy 342.972152 -373.179066) (xy 342.934058 -373.234701) (xy 342.912192 -373.260366)
			(xy 342.906384 -373.267503) (xy 342.899876 -373.2847) (xy 342.899492 -373.293894) (xy 342.899492 -373.451374)
			(xy 342.898953 -373.461495) (xy 342.89124 -373.48021) (xy 342.87697 -373.494566) (xy 342.858302 -373.502392)
			(xy 342.848184 -373.502936) (xy 342.131904 -373.502936) (xy 342.121755 -373.502476) (xy 342.103009 -373.494688)
			(xy 342.088687 -373.480304) (xy 342.080981 -373.461525) (xy 342.080596 -373.451374) (xy 342.080596 -373.293894)
			(xy 342.080189 -373.284706) (xy 342.073673 -373.267522) (xy 342.067896 -373.260366) (xy 342.046066 -373.234673)
			(xy 342.007976 -373.179042) (xy 341.976824 -373.11925) (xy 341.953058 -373.056157) (xy 341.937021 -372.990671)
			(xy 341.928942 -372.923736) (xy 341.928939 -372.856315) (xy 341.937011 -372.789379) (xy 341.953043 -372.723892)
			(xy 341.976803 -372.660797) (xy 342.00795 -372.601001) (xy 342.046034 -372.545367) (xy 342.067896 -372.519702)
			(xy 342.073674 -372.512543) (xy 342.0802 -372.495363) (xy 342.080596 -372.486174) (xy 342.080596 -371.993922)
			(xy 342.080176 -371.984736) (xy 342.073669 -371.967551) (xy 342.067896 -371.960394) (xy 342.045995 -371.934759)
			(xy 342.007908 -371.87912) (xy 341.976759 -371.81932) (xy 341.952997 -371.756219) (xy 341.936964 -371.690726)
			(xy 341.928891 -371.623785) (xy 340.826797 -371.623785) (xy 340.827009 -371.62435) (xy 340.842981 -371.689733)
			(xy 340.851024 -371.756557) (xy 340.851023 -371.823864) (xy 340.842977 -371.890687) (xy 340.827002 -371.956071)
			(xy 340.803328 -372.019076) (xy 340.772292 -372.0788) (xy 340.734341 -372.134386) (xy 340.712552 -372.160038)
			(xy 340.706751 -372.16718) (xy 340.70024 -372.184373) (xy 340.699852 -372.193566) (xy 340.699852 -372.351554)
			(xy 340.699398 -372.361724) (xy 340.691627 -372.380519) (xy 340.67725 -372.394906) (xy 340.65846 -372.402691)
			(xy 340.64829 -372.403116) (xy 339.93201 -372.403116) (xy 339.921833 -372.402727) (xy 339.90303 -372.394937)
			(xy 339.888643 -372.38054) (xy 339.880866 -372.361731) (xy 339.880448 -372.351554) (xy 339.880448 -372.193566)
			(xy 339.880043 -372.184378) (xy 339.873525 -372.167195) (xy 339.867748 -372.160038) (xy 339.845974 -372.134375)
			(xy 339.808024 -372.07879) (xy 339.77699 -372.019068) (xy 339.753316 -371.956065) (xy 339.737342 -371.890684)
			(xy 339.729296 -371.823863) (xy 339.729295 -371.756558) (xy 339.737338 -371.689737) (xy 339.75331 -371.624355)
			(xy 339.776981 -371.561351) (xy 339.808013 -371.501628) (xy 339.845961 -371.446042) (xy 339.867748 -371.42039)
			(xy 339.873537 -371.41324) (xy 339.880055 -371.396053) (xy 339.880448 -371.386862) (xy 339.880448 -370.89334)
			(xy 339.880008 -370.884156) (xy 339.873514 -370.866972) (xy 339.867748 -370.859812) (xy 339.845948 -370.83417)
			(xy 339.807999 -370.778582) (xy 339.776966 -370.718857) (xy 339.753293 -370.655851) (xy 339.737321 -370.590468)
			(xy 339.729277 -370.523644) (xy 336.451238 -370.523644) (xy 336.451238 -370.523703) (xy 336.443163 -370.590641)
			(xy 336.427128 -370.65613) (xy 336.403363 -370.719227) (xy 336.372211 -370.779022) (xy 336.334121 -370.834656)
			(xy 336.312256 -370.86032) (xy 336.306463 -370.867467) (xy 336.299947 -370.884656) (xy 336.299556 -370.893848)
			(xy 336.299556 -371.386354) (xy 336.299998 -371.395538) (xy 336.306491 -371.412722) (xy 336.312256 -371.419882)
			(xy 336.334135 -371.445535) (xy 336.372226 -371.50117) (xy 336.403379 -371.560968) (xy 336.427016 -371.623725)
			(xy 337.529123 -371.623725) (xy 337.529126 -371.556418) (xy 337.537174 -371.489593) (xy 337.55315 -371.424209)
			(xy 337.576825 -371.361204) (xy 337.60786 -371.301479) (xy 337.645811 -371.245891) (xy 337.6676 -371.220238)
			(xy 337.673405 -371.213099) (xy 337.679915 -371.195904) (xy 337.6803 -371.18671) (xy 337.6803 -371.028722)
			(xy 337.68085 -371.01857) (xy 337.68861 -370.999809) (xy 337.702958 -370.985444) (xy 337.721711 -370.977662)
			(xy 337.731862 -370.97716) (xy 338.448142 -370.97716) (xy 338.458305 -370.9776) (xy 338.477079 -370.985392)
			(xy 338.491444 -370.999774) (xy 338.499213 -371.018558) (xy 338.499704 -371.028722) (xy 338.499704 -371.18671)
			(xy 338.500109 -371.195898) (xy 338.506626 -371.213082) (xy 338.512404 -371.220238) (xy 338.534153 -371.245921)
			(xy 338.5721 -371.301504) (xy 338.603133 -371.361224) (xy 338.626806 -371.424224) (xy 338.64278 -371.489602)
			(xy 338.650827 -371.556421) (xy 338.65083 -371.623722) (xy 338.64279 -371.690541) (xy 338.626823 -371.755921)
			(xy 338.603156 -371.818924) (xy 338.57213 -371.878646) (xy 338.534188 -371.934233) (xy 338.512404 -371.959886)
			(xy 338.506589 -371.967018) (xy 338.500085 -371.984219) (xy 338.499704 -371.993414) (xy 338.499704 -372.486682)
			(xy 338.500122 -372.495868) (xy 338.50663 -372.513053) (xy 338.512404 -372.52021) (xy 338.534224 -372.545835)
			(xy 338.572169 -372.601427) (xy 338.603198 -372.661154) (xy 338.626867 -372.724162) (xy 338.642836 -372.789547)
			(xy 338.650877 -372.856372) (xy 338.650874 -372.923679) (xy 338.642827 -372.990503) (xy 338.626852 -373.055887)
			(xy 338.603177 -373.118892) (xy 338.572142 -373.178617) (xy 338.534192 -373.234205) (xy 338.512404 -373.259858)
			(xy 338.506601 -373.266999) (xy 338.50009 -373.284193) (xy 338.499704 -373.293386) (xy 338.499704 -373.451374)
			(xy 338.499147 -373.461525) (xy 338.491388 -373.480286) (xy 338.477043 -373.49465) (xy 338.458292 -373.502433)
			(xy 338.448142 -373.502936) (xy 337.731862 -373.502936) (xy 337.721699 -373.502497) (xy 337.702924 -373.494705)
			(xy 337.688559 -373.480323) (xy 337.68079 -373.461538) (xy 337.6803 -373.451374) (xy 337.6803 -373.293386)
			(xy 337.679896 -373.284198) (xy 337.673378 -373.267014) (xy 337.6676 -373.259858) (xy 337.645847 -373.234178)
			(xy 337.6079 -373.178595) (xy 337.576867 -373.118874) (xy 337.553194 -373.055874) (xy 337.53722 -372.990495)
			(xy 337.529174 -372.923676) (xy 337.52917 -372.856375) (xy 337.537211 -372.789555) (xy 337.553179 -372.724175)
			(xy 337.576846 -372.661172) (xy 337.607873 -372.601449) (xy 337.645816 -372.545863) (xy 337.6676 -372.52021)
			(xy 337.673417 -372.513079) (xy 337.67992 -372.495878) (xy 337.6803 -372.486682) (xy 337.6803 -371.993414)
			(xy 337.679883 -371.984228) (xy 337.673374 -371.967043) (xy 337.6676 -371.959886) (xy 337.645776 -371.934264)
			(xy 337.607831 -371.878672) (xy 337.576802 -371.818944) (xy 337.553133 -371.755936) (xy 337.537163 -371.69055)
			(xy 337.529123 -371.623725) (xy 336.427016 -371.623725) (xy 336.427144 -371.624066) (xy 336.44318 -371.689557)
			(xy 336.451256 -371.756498) (xy 336.451254 -371.823923) (xy 336.443176 -371.890863) (xy 336.427138 -371.956354)
			(xy 336.40337 -372.019451) (xy 336.372216 -372.079248) (xy 336.334122 -372.134881) (xy 336.312256 -372.160546)
			(xy 336.306452 -372.167686) (xy 336.299943 -372.184881) (xy 336.299556 -372.194074) (xy 336.299556 -372.351554)
			(xy 336.299036 -372.361678) (xy 336.291322 -372.380399) (xy 336.277046 -372.394757) (xy 336.258369 -372.402577)
			(xy 336.248248 -372.403116) (xy 335.531968 -372.403116) (xy 335.521814 -372.402705) (xy 335.503064 -372.394902)
			(xy 335.488742 -372.380502) (xy 335.481041 -372.36171) (xy 335.48066 -372.351554) (xy 335.48066 -372.194074)
			(xy 335.480249 -372.184887) (xy 335.473734 -372.167704) (xy 335.46796 -372.160546) (xy 335.446111 -372.134869)
			(xy 335.408025 -372.079235) (xy 335.376876 -372.01944) (xy 335.353112 -371.956345) (xy 335.337077 -371.890858)
			(xy 335.329001 -371.823921) (xy 335.329 -371.7565) (xy 335.337073 -371.689563) (xy 335.353106 -371.624075)
			(xy 335.376867 -371.560979) (xy 335.408014 -371.501183) (xy 335.446098 -371.445548) (xy 335.46796 -371.419882)
			(xy 335.473754 -371.412735) (xy 335.480269 -371.395546) (xy 335.48066 -371.386354) (xy 335.48066 -370.893848)
			(xy 335.480214 -370.884665) (xy 335.473724 -370.867481) (xy 335.46796 -370.86032) (xy 335.446086 -370.834664)
			(xy 335.408 -370.779027) (xy 335.376852 -370.719229) (xy 335.35309 -370.656131) (xy 335.337057 -370.590642)
			(xy 335.328983 -370.523703) (xy 332.050912 -370.523703) (xy 332.042876 -370.590465) (xy 332.026905 -370.655846)
			(xy 332.003233 -370.71885) (xy 331.972202 -370.778573) (xy 331.934255 -370.83416) (xy 331.912468 -370.859812)
			(xy 331.90668 -370.866963) (xy 331.900161 -370.884149) (xy 331.899768 -370.89334) (xy 331.899768 -371.386862)
			(xy 331.900204 -371.396046) (xy 331.906701 -371.41323) (xy 331.912468 -371.42039) (xy 331.934269 -371.446031)
			(xy 331.972217 -371.501619) (xy 332.00325 -371.561344) (xy 332.026709 -371.623785) (xy 333.128803 -371.623785)
			(xy 333.128807 -371.556358) (xy 333.136887 -371.489417) (xy 333.152927 -371.423926) (xy 333.176696 -371.360827)
			(xy 333.207851 -371.30103) (xy 333.245945 -371.245395) (xy 333.267812 -371.21973) (xy 333.273622 -371.212594)
			(xy 333.280128 -371.195397) (xy 333.280512 -371.186202) (xy 333.280512 -371.028722) (xy 333.281044 -371.0186)
			(xy 333.288759 -370.999885) (xy 333.303031 -370.985529) (xy 333.321701 -370.977704) (xy 333.33182 -370.97716)
			(xy 334.0481 -370.97716) (xy 334.058249 -370.977621) (xy 334.076994 -370.985409) (xy 334.091316 -370.999793)
			(xy 334.099023 -371.018571) (xy 334.099408 -371.028722) (xy 334.099408 -371.186202) (xy 334.099815 -371.195389)
			(xy 334.106331 -371.212574) (xy 334.112108 -371.21973) (xy 334.133934 -371.245426) (xy 334.172024 -371.301056)
			(xy 334.203176 -371.360848) (xy 334.226942 -371.423941) (xy 334.242979 -371.489426) (xy 334.251058 -371.556361)
			(xy 334.251062 -371.623782) (xy 334.24299 -371.690717) (xy 334.226958 -371.756204) (xy 334.203199 -371.819299)
			(xy 334.172053 -371.879095) (xy 334.133969 -371.934729) (xy 334.112108 -371.960394) (xy 334.106332 -371.967554)
			(xy 334.099805 -371.984733) (xy 334.099408 -371.993922) (xy 334.099408 -372.486174) (xy 334.099829 -372.49536)
			(xy 334.106335 -372.512545) (xy 334.112108 -372.519702) (xy 334.134005 -372.54534) (xy 334.172092 -372.600978)
			(xy 334.203241 -372.660779) (xy 334.227003 -372.723879) (xy 334.243036 -372.789371) (xy 334.251109 -372.856312)
			(xy 334.251106 -372.923739) (xy 334.243027 -372.990679) (xy 334.226988 -373.05617) (xy 334.20322 -373.119268)
			(xy 334.172066 -373.179065) (xy 334.133974 -373.234701) (xy 334.112108 -373.260366) (xy 334.106302 -373.267504)
			(xy 334.099793 -373.2847) (xy 334.099408 -373.293894) (xy 334.099408 -373.451374) (xy 334.098854 -373.461493)
			(xy 334.091143 -373.480205) (xy 334.076878 -373.49456) (xy 334.058216 -373.502389) (xy 334.0481 -373.502936)
			(xy 333.33182 -373.502936) (xy 333.321672 -373.502463) (xy 333.302927 -373.494681) (xy 333.288604 -373.4803)
			(xy 333.280897 -373.461524) (xy 333.280512 -373.451374) (xy 333.280512 -373.293894) (xy 333.280102 -373.284707)
			(xy 333.273588 -373.267523) (xy 333.267812 -373.260366) (xy 333.245981 -373.234673) (xy 333.20789 -373.179043)
			(xy 333.176738 -373.119251) (xy 333.152971 -373.056157) (xy 333.136933 -372.990672) (xy 333.128854 -372.923736)
			(xy 333.128851 -372.856315) (xy 333.136924 -372.789379) (xy 333.152956 -372.723891) (xy 333.176717 -372.660796)
			(xy 333.207864 -372.601001) (xy 333.24595 -372.545367) (xy 333.267812 -372.519702) (xy 333.273592 -372.512545)
			(xy 333.280116 -372.495363) (xy 333.280512 -372.486174) (xy 333.280512 -371.993922) (xy 333.280088 -371.984736)
			(xy 333.273584 -371.967552) (xy 333.267812 -371.960394) (xy 333.24591 -371.93476) (xy 333.207822 -371.879121)
			(xy 333.176672 -371.819321) (xy 333.15291 -371.75622) (xy 333.136876 -371.690727) (xy 333.128803 -371.623785)
			(xy 332.026709 -371.623785) (xy 332.026921 -371.62435) (xy 332.042893 -371.689734) (xy 332.050936 -371.756558)
			(xy 332.050935 -371.823864) (xy 332.042889 -371.890687) (xy 332.026915 -371.95607) (xy 332.003241 -372.019075)
			(xy 331.972207 -372.078799) (xy 331.934256 -372.134386) (xy 331.912468 -372.160038) (xy 331.906669 -372.167181)
			(xy 331.900156 -372.184373) (xy 331.899768 -372.193566) (xy 331.899768 -372.351554) (xy 331.899299 -372.361722)
			(xy 331.89153 -372.380514) (xy 331.877158 -372.394901) (xy 331.858373 -372.402688) (xy 331.848206 -372.403116)
			(xy 331.131926 -372.403116) (xy 331.12175 -372.402714) (xy 331.102948 -372.394929) (xy 331.08856 -372.380536)
			(xy 331.080783 -372.36173) (xy 331.080364 -372.351554) (xy 331.080364 -372.193566) (xy 331.079956 -372.184379)
			(xy 331.073439 -372.167195) (xy 331.067664 -372.160038) (xy 331.045889 -372.134375) (xy 331.007939 -372.078791)
			(xy 330.976903 -372.019069) (xy 330.953229 -371.956066) (xy 330.937254 -371.890684) (xy 330.929208 -371.823863)
			(xy 330.929207 -371.756558) (xy 330.93725 -371.689736) (xy 330.953222 -371.624355) (xy 330.976895 -371.561351)
			(xy 331.007928 -371.501628) (xy 331.045876 -371.446042) (xy 331.067664 -371.42039) (xy 331.073455 -371.413241)
			(xy 331.079971 -371.396053) (xy 331.080364 -371.386862) (xy 331.080364 -370.89334) (xy 331.07992 -370.884157)
			(xy 331.073428 -370.866973) (xy 331.067664 -370.859812) (xy 331.045864 -370.83417) (xy 331.007914 -370.778582)
			(xy 330.97688 -370.718858) (xy 330.953206 -370.655852) (xy 330.937234 -370.590468) (xy 330.92919 -370.523644)
			(xy 301.250887 -370.523644) (xy 301.250887 -370.523702) (xy 301.242812 -370.590639) (xy 301.226779 -370.656127)
			(xy 301.203017 -370.719224) (xy 301.171869 -370.77902) (xy 301.133783 -370.834654) (xy 301.11192 -370.86032)
			(xy 301.106135 -370.867473) (xy 301.099613 -370.884658) (xy 301.09922 -370.893848) (xy 301.09922 -371.386354)
			(xy 301.099648 -371.395539) (xy 301.106149 -371.412724) (xy 301.11192 -371.419882) (xy 301.133797 -371.445536)
			(xy 301.171884 -371.501173) (xy 301.203033 -371.560971) (xy 301.226688 -371.623785) (xy 302.328773 -371.623785)
			(xy 302.328777 -371.556358) (xy 302.336856 -371.489418) (xy 302.352895 -371.423927) (xy 302.376662 -371.360829)
			(xy 302.407815 -371.301031) (xy 302.445907 -371.245396) (xy 302.467772 -371.21973) (xy 302.47359 -371.2126)
			(xy 302.48009 -371.195398) (xy 302.480472 -371.186202) (xy 302.480472 -371.028722) (xy 302.480945 -371.018593)
			(xy 302.488672 -370.999866) (xy 302.502963 -370.985508) (xy 302.521653 -370.977693) (xy 302.53178 -370.97716)
			(xy 303.24806 -370.97716) (xy 303.258207 -370.977654) (xy 303.27695 -370.985429) (xy 303.291274 -370.999803)
			(xy 303.298982 -371.018574) (xy 303.299368 -371.028722) (xy 303.299368 -371.186202) (xy 303.299784 -371.195388)
			(xy 303.306294 -371.212572) (xy 303.312068 -371.21973) (xy 303.333896 -371.245425) (xy 303.371988 -371.301055)
			(xy 303.403142 -371.360847) (xy 303.42691 -371.42394) (xy 303.442949 -371.489425) (xy 303.451028 -371.556361)
			(xy 303.451031 -371.623782) (xy 303.442959 -371.690718) (xy 303.426926 -371.756206) (xy 303.403165 -371.819301)
			(xy 303.372017 -371.879096) (xy 303.333931 -371.934729) (xy 303.312068 -371.960394) (xy 303.306287 -371.96755)
			(xy 303.299764 -371.984732) (xy 303.299368 -371.993922) (xy 303.299368 -372.486174) (xy 303.299798 -372.495359)
			(xy 303.306299 -372.512543) (xy 303.312068 -372.519702) (xy 303.333966 -372.545339) (xy 303.372056 -372.600977)
			(xy 303.403207 -372.660777) (xy 303.426971 -372.723877) (xy 303.443005 -372.78937) (xy 303.451079 -372.856312)
			(xy 303.451076 -372.923739) (xy 303.442996 -372.99068) (xy 303.426956 -373.056172) (xy 303.403186 -373.11927)
			(xy 303.37203 -373.179067) (xy 303.333935 -373.234701) (xy 303.312068 -373.260366) (xy 303.306257 -373.267501)
			(xy 303.299752 -373.284699) (xy 303.299368 -373.293894) (xy 303.299368 -373.451374) (xy 303.298853 -373.461498)
			(xy 303.291135 -373.480217) (xy 303.276857 -373.494574) (xy 303.258181 -373.502396) (xy 303.24806 -373.502936)
			(xy 302.53178 -373.502936) (xy 302.521629 -373.502496) (xy 302.502883 -373.4947) (xy 302.488562 -373.48031)
			(xy 302.480856 -373.461527) (xy 302.480472 -373.451374) (xy 302.480472 -373.293894) (xy 302.480071 -373.284706)
			(xy 302.473552 -373.267521) (xy 302.467772 -373.260366) (xy 302.445942 -373.234673) (xy 302.407855 -373.179042)
			(xy 302.376704 -373.119249) (xy 302.352939 -373.056156) (xy 302.336902 -372.99067) (xy 302.328824 -372.923736)
			(xy 302.328821 -372.856315) (xy 302.336893 -372.78938) (xy 302.352924 -372.723893) (xy 302.376683 -372.660798)
			(xy 302.407828 -372.601002) (xy 302.445911 -372.545368) (xy 302.467772 -372.519702) (xy 302.473559 -372.51255)
			(xy 302.480077 -372.495364) (xy 302.480472 -372.486174) (xy 302.480472 -371.993922) (xy 302.480058 -371.984735)
			(xy 302.473548 -371.96755) (xy 302.467772 -371.960394) (xy 302.445872 -371.934759) (xy 302.407786 -371.87912)
			(xy 302.376638 -371.819319) (xy 302.352878 -371.756218) (xy 302.336846 -371.690726) (xy 302.328773 -371.623785)
			(xy 301.226688 -371.623785) (xy 301.226795 -371.624069) (xy 301.242829 -371.689559) (xy 301.250904 -371.756498)
			(xy 301.250903 -371.823923) (xy 301.242826 -371.890862) (xy 301.226789 -371.956351) (xy 301.203024 -372.019449)
			(xy 301.171873 -372.079245) (xy 301.133784 -372.13488) (xy 301.11192 -372.160546) (xy 301.106124 -372.167692)
			(xy 301.099608 -372.184882) (xy 301.09922 -372.194074) (xy 301.09922 -372.351554) (xy 301.098734 -372.361683)
			(xy 301.091014 -372.38041) (xy 301.076727 -372.39477) (xy 301.058038 -372.402583) (xy 301.047912 -372.403116)
			(xy 300.331632 -372.403116) (xy 300.321482 -372.402653) (xy 300.302733 -372.394871) (xy 300.288409 -372.380487)
			(xy 300.280705 -372.361706) (xy 300.280324 -372.351554) (xy 300.280324 -372.194074) (xy 300.279921 -372.184886)
			(xy 300.273402 -372.167702) (xy 300.267624 -372.160546) (xy 300.245773 -372.13487) (xy 300.207682 -372.079237)
			(xy 300.17653 -372.019443) (xy 300.152764 -371.956347) (xy 300.136726 -371.890859) (xy 300.128649 -371.823922)
			(xy 300.128648 -371.756499) (xy 300.136723 -371.689561) (xy 300.152757 -371.624073) (xy 300.176521 -371.560976)
			(xy 300.207671 -371.501181) (xy 300.24576 -371.445547) (xy 300.267624 -371.419882) (xy 300.273413 -371.412732)
			(xy 300.279932 -371.395545) (xy 300.280324 -371.386354) (xy 300.280324 -370.893848) (xy 300.279885 -370.884664)
			(xy 300.273391 -370.86748) (xy 300.267624 -370.86032) (xy 300.245747 -370.834665) (xy 300.207657 -370.779029)
			(xy 300.176506 -370.719232) (xy 300.152741 -370.656134) (xy 300.136706 -370.590643) (xy 300.128631 -370.523704)
			(xy 296.851096 -370.523704) (xy 296.843021 -370.590639) (xy 296.826988 -370.656127) (xy 296.803227 -370.719223)
			(xy 296.772079 -370.779019) (xy 296.733994 -370.834654) (xy 296.712132 -370.86032) (xy 296.706336 -370.867465)
			(xy 296.699823 -370.884656) (xy 296.699432 -370.893848) (xy 296.699432 -371.386354) (xy 296.699879 -371.395537)
			(xy 296.706369 -371.412721) (xy 296.712132 -371.419882) (xy 296.734009 -371.445536) (xy 296.772095 -371.501173)
			(xy 296.803243 -371.560971) (xy 296.826876 -371.623726) (xy 297.92898 -371.623726) (xy 297.928984 -371.556417)
			(xy 297.937032 -371.489591) (xy 297.95301 -371.424206) (xy 297.976689 -371.3612) (xy 298.007729 -371.301476)
			(xy 298.045685 -371.245889) (xy 298.067476 -371.220238) (xy 298.073279 -371.213097) (xy 298.07979 -371.195903)
			(xy 298.080176 -371.18671) (xy 298.080176 -371.028722) (xy 298.080583 -371.018547) (xy 298.088368 -370.999746)
			(xy 298.102759 -370.985359) (xy 298.121563 -370.97758) (xy 298.131738 -370.97716) (xy 298.848018 -370.97716)
			(xy 298.858193 -370.97755) (xy 298.876993 -370.985345) (xy 298.891378 -370.999741) (xy 298.899158 -371.018546)
			(xy 298.89958 -371.028722) (xy 298.89958 -371.18671) (xy 298.89999 -371.195897) (xy 298.906504 -371.213081)
			(xy 298.91228 -371.220238) (xy 298.93403 -371.245921) (xy 298.971978 -371.301504) (xy 299.003012 -371.361223)
			(xy 299.026686 -371.424224) (xy 299.042661 -371.489602) (xy 299.050708 -371.556421) (xy 299.050711 -371.623722)
			(xy 299.042671 -371.690542) (xy 299.026703 -371.755922) (xy 299.003035 -371.818925) (xy 298.972008 -371.878647)
			(xy 298.934065 -371.934233) (xy 298.91228 -371.959886) (xy 298.906462 -371.967016) (xy 298.899961 -371.984218)
			(xy 298.89958 -371.993414) (xy 298.89958 -372.486682) (xy 298.900003 -372.495868) (xy 298.906508 -372.513052)
			(xy 298.91228 -372.52021) (xy 298.934101 -372.545835) (xy 298.972047 -372.601426) (xy 299.003078 -372.661153)
			(xy 299.026748 -372.724161) (xy 299.042718 -372.789547) (xy 299.050759 -372.856372) (xy 299.050756 -372.923679)
			(xy 299.042709 -372.990504) (xy 299.026733 -373.055888) (xy 299.003057 -373.118894) (xy 298.972021 -373.178618)
			(xy 298.934069 -373.234206) (xy 298.91228 -373.259858) (xy 298.906474 -373.266996) (xy 298.899966 -373.284192)
			(xy 298.89958 -373.293386) (xy 298.89958 -373.451374) (xy 298.899115 -373.461542) (xy 298.891342 -373.480332)
			(xy 298.876969 -373.494717) (xy 298.858185 -373.502506) (xy 298.848018 -373.502936) (xy 298.131738 -373.502936)
			(xy 298.121566 -373.502504) (xy 298.102767 -373.494727) (xy 298.08838 -373.480343) (xy 298.080598 -373.461546)
			(xy 298.080176 -373.451374) (xy 298.080176 -373.293386) (xy 298.079778 -373.284197) (xy 298.073256 -373.267013)
			(xy 298.067476 -373.259858) (xy 298.045721 -373.234179) (xy 298.007768 -373.178597) (xy 297.976732 -373.118878)
			(xy 297.953055 -373.055877) (xy 297.937079 -372.990497) (xy 297.929031 -372.923677) (xy 297.929028 -372.856374)
			(xy 297.93707 -372.789553) (xy 297.95304 -372.724172) (xy 297.976711 -372.661169) (xy 298.007742 -372.601447)
			(xy 298.045689 -372.545862) (xy 298.067476 -372.52021) (xy 298.073291 -372.513077) (xy 298.079795 -372.495877)
			(xy 298.080176 -372.486682) (xy 298.080176 -371.993414) (xy 298.079765 -371.984227) (xy 298.073252 -371.967042)
			(xy 298.067476 -371.959886) (xy 298.04565 -371.934265) (xy 298.007699 -371.878675) (xy 297.976666 -371.818948)
			(xy 297.952993 -371.755939) (xy 297.937022 -371.690552) (xy 297.92898 -371.623726) (xy 296.826876 -371.623726)
			(xy 296.827005 -371.624069) (xy 296.843039 -371.689559) (xy 296.851113 -371.756498) (xy 296.851112 -371.823923)
			(xy 296.843035 -371.890861) (xy 296.826999 -371.956351) (xy 296.803235 -372.019448) (xy 296.772084 -372.079245)
			(xy 296.733996 -372.13488) (xy 296.712132 -372.160546) (xy 296.706325 -372.167684) (xy 296.699819 -372.18488)
			(xy 296.699432 -372.194074) (xy 296.699432 -372.351554) (xy 296.698935 -372.361681) (xy 296.691217 -372.380407)
			(xy 296.676933 -372.394765) (xy 296.658249 -372.402581) (xy 296.648124 -372.403116) (xy 295.931844 -372.403116)
			(xy 295.921695 -372.402643) (xy 295.902946 -372.394865) (xy 295.888622 -372.380484) (xy 295.880918 -372.361705)
			(xy 295.880536 -372.351554) (xy 295.880536 -372.194074) (xy 295.88013 -372.184887) (xy 295.873613 -372.167703)
			(xy 295.867836 -372.160546) (xy 295.845985 -372.13487) (xy 295.807893 -372.079238) (xy 295.77674 -372.019444)
			(xy 295.752973 -371.956348) (xy 295.736936 -371.89086) (xy 295.728858 -371.823922) (xy 295.728857 -371.756499)
			(xy 295.736932 -371.689561) (xy 295.752967 -371.624072) (xy 295.776731 -371.560976) (xy 295.807882 -371.50118)
			(xy 295.845972 -371.445547) (xy 295.867836 -371.419882) (xy 295.873627 -371.412733) (xy 295.880144 -371.395545)
			(xy 295.880536 -371.386354) (xy 295.880536 -370.893848) (xy 295.880095 -370.884664) (xy 295.873602 -370.86748)
			(xy 295.867836 -370.86032) (xy 295.845959 -370.834665) (xy 295.807868 -370.77903) (xy 295.776716 -370.719233)
			(xy 295.752951 -370.656134) (xy 295.736915 -370.590644) (xy 295.72884 -370.523704) (xy 292.450793 -370.523704)
			(xy 292.442757 -370.590465) (xy 292.426785 -370.655847) (xy 292.403113 -370.718851) (xy 292.37208 -370.778574)
			(xy 292.334131 -370.83416) (xy 292.312344 -370.859812) (xy 292.306553 -370.866961) (xy 292.300036 -370.884149)
			(xy 292.299644 -370.89334) (xy 292.299644 -371.386862) (xy 292.300085 -371.396046) (xy 292.306578 -371.41323)
			(xy 292.312344 -371.42039) (xy 292.334146 -371.44603) (xy 292.372096 -371.501618) (xy 292.403129 -371.561343)
			(xy 292.42659 -371.623785) (xy 293.528685 -371.623785) (xy 293.528689 -371.556358) (xy 293.536768 -371.489418)
			(xy 293.552807 -371.423927) (xy 293.576575 -371.360828) (xy 293.60773 -371.301031) (xy 293.645822 -371.245395)
			(xy 293.667688 -371.21973) (xy 293.673495 -371.212592) (xy 293.680004 -371.195396) (xy 293.680388 -371.186202)
			(xy 293.680388 -371.028722) (xy 293.680943 -371.018603) (xy 293.688654 -370.999892) (xy 293.702919 -370.985537)
			(xy 293.72158 -370.977708) (xy 293.731696 -370.97716) (xy 294.447976 -370.97716) (xy 294.458078 -370.977704)
			(xy 294.476748 -370.985426) (xy 294.491043 -370.999705) (xy 294.498785 -371.018366) (xy 294.499284 -371.028468)
			(xy 294.499284 -371.186202) (xy 294.499697 -371.195389) (xy 294.506209 -371.212573) (xy 294.511984 -371.21973)
			(xy 294.533811 -371.245426) (xy 294.571902 -371.301056) (xy 294.603055 -371.360847) (xy 294.626822 -371.42394)
			(xy 294.642861 -371.489426) (xy 294.65094 -371.556361) (xy 294.650944 -371.623782) (xy 294.642871 -371.690718)
			(xy 294.626839 -371.756205) (xy 294.603079 -371.8193) (xy 294.571932 -371.879095) (xy 294.533846 -371.934729)
			(xy 294.511984 -371.960394) (xy 294.506206 -371.967552) (xy 294.499681 -371.984733) (xy 294.499284 -371.993922)
			(xy 294.499284 -372.486174) (xy 294.49971 -372.495359) (xy 294.506213 -372.512544) (xy 294.511984 -372.519702)
			(xy 294.533882 -372.545339) (xy 294.571971 -372.600978) (xy 294.603121 -372.660777) (xy 294.626884 -372.723878)
			(xy 294.642917 -372.789371) (xy 294.650991 -372.856312) (xy 294.650988 -372.923739) (xy 294.642908 -372.99068)
			(xy 294.626869 -373.056171) (xy 294.6031 -373.119269) (xy 294.571944 -373.179066) (xy 294.533851 -373.234701)
			(xy 294.511984 -373.260366) (xy 294.506175 -373.267502) (xy 294.499668 -373.2847) (xy 294.499284 -373.293894)
			(xy 294.499284 -373.451374) (xy 294.498753 -373.461496) (xy 294.491038 -373.480212) (xy 294.476766 -373.494569)
			(xy 294.458095 -373.502393) (xy 294.447976 -373.502936) (xy 293.731696 -373.502936) (xy 293.721591 -373.502419)
			(xy 293.70292 -373.494687) (xy 293.688627 -373.4804) (xy 293.680886 -373.461732) (xy 293.680388 -373.451628)
			(xy 293.680388 -373.293894) (xy 293.679983 -373.284706) (xy 293.673466 -373.267522) (xy 293.667688 -373.260366)
			(xy 293.645858 -373.234673) (xy 293.607769 -373.179042) (xy 293.576617 -373.11925) (xy 293.552852 -373.056156)
			(xy 293.536814 -372.990671) (xy 293.528736 -372.923736) (xy 293.528733 -372.856315) (xy 293.536805 -372.789379)
			(xy 293.552837 -372.723892) (xy 293.576597 -372.660797) (xy 293.607743 -372.601002) (xy 293.645826 -372.545367)
			(xy 293.667688 -372.519702) (xy 293.673465 -372.512543) (xy 293.679992 -372.495363) (xy 293.680388 -372.486174)
			(xy 293.680388 -371.993922) (xy 293.67997 -371.984736) (xy 293.673462 -371.967551) (xy 293.667688 -371.960394)
			(xy 293.645787 -371.934759) (xy 293.6077 -371.87912) (xy 293.576552 -371.81932) (xy 293.55279 -371.756219)
			(xy 293.536758 -371.690726) (xy 293.528685 -371.623785) (xy 292.42659 -371.623785) (xy 292.426802 -371.624349)
			(xy 292.442775 -371.689733) (xy 292.450818 -371.756557) (xy 292.450817 -371.823864) (xy 292.442771 -371.890688)
			(xy 292.426796 -371.956071) (xy 292.403121 -372.019076) (xy 292.372085 -372.0788) (xy 292.334133 -372.134386)
			(xy 292.312344 -372.160038) (xy 292.306542 -372.167179) (xy 292.300032 -372.184373) (xy 292.299644 -372.193566)
			(xy 292.299644 -372.351554) (xy 292.299198 -372.361725) (xy 292.291425 -372.380522) (xy 292.277046 -372.394909)
			(xy 292.258253 -372.402693) (xy 292.248082 -372.403116) (xy 291.531802 -372.403116) (xy 291.521625 -372.402733)
			(xy 291.502821 -372.394941) (xy 291.488435 -372.380542) (xy 291.480658 -372.361732) (xy 291.48024 -372.351554)
			(xy 291.48024 -372.193566) (xy 291.479837 -372.184378) (xy 291.473317 -372.167194) (xy 291.46754 -372.160038)
			(xy 291.445766 -372.134374) (xy 291.407817 -372.07879) (xy 291.376783 -372.019068) (xy 291.353109 -371.956065)
			(xy 291.337135 -371.890684) (xy 291.32909 -371.823862) (xy 291.329089 -371.756559) (xy 291.337132 -371.689737)
			(xy 291.353103 -371.624356) (xy 291.376774 -371.561352) (xy 291.407806 -371.501628) (xy 291.445753 -371.446042)
			(xy 291.46754 -371.42039) (xy 291.473328 -371.413239) (xy 291.479847 -371.396053) (xy 291.48024 -371.386862)
			(xy 291.48024 -370.89334) (xy 291.479801 -370.884156) (xy 291.473306 -370.866972) (xy 291.46754 -370.859812)
			(xy 291.44574 -370.83417) (xy 291.407792 -370.778582) (xy 291.376759 -370.718857) (xy 291.353087 -370.655851)
			(xy 291.337115 -370.590468) (xy 291.329071 -370.523644) (xy 288.051032 -370.523644) (xy 288.051032 -370.523703)
			(xy 288.042957 -370.590641) (xy 288.026921 -370.65613) (xy 288.003156 -370.719227) (xy 287.972004 -370.779022)
			(xy 287.933913 -370.834656) (xy 287.912048 -370.86032) (xy 287.906254 -370.867467) (xy 287.899739 -370.884656)
			(xy 287.899348 -370.893848) (xy 287.899348 -371.386354) (xy 287.899792 -371.395537) (xy 287.906284 -371.412721)
			(xy 287.912048 -371.419882) (xy 287.933928 -371.445535) (xy 287.972019 -371.50117) (xy 288.003172 -371.560967)
			(xy 288.02681 -371.623726) (xy 289.128893 -371.623726) (xy 289.128896 -371.556417) (xy 289.136945 -371.489591)
			(xy 289.152924 -371.424206) (xy 289.176603 -371.3612) (xy 289.207644 -371.301475) (xy 289.2456 -371.245889)
			(xy 289.267392 -371.220238) (xy 289.273196 -371.213098) (xy 289.279707 -371.195904) (xy 289.280092 -371.18671)
			(xy 289.280092 -371.028722) (xy 289.28065 -371.018571) (xy 289.288409 -370.999811) (xy 289.302754 -370.985447)
			(xy 289.321504 -370.977663) (xy 289.331654 -370.97716) (xy 290.047934 -370.97716) (xy 290.058097 -370.977606)
			(xy 290.076871 -370.985396) (xy 290.091236 -370.999776) (xy 290.099005 -371.018559) (xy 290.099496 -371.028722)
			(xy 290.099496 -371.18671) (xy 290.099902 -371.195898) (xy 290.106419 -371.213082) (xy 290.112196 -371.220238)
			(xy 290.133945 -371.245921) (xy 290.171893 -371.301504) (xy 290.202926 -371.361224) (xy 290.226599 -371.424224)
			(xy 290.242574 -371.489602) (xy 290.250621 -371.556421) (xy 290.250624 -371.623722) (xy 290.242584 -371.690542)
			(xy 290.226616 -371.755921) (xy 290.202949 -371.818924) (xy 290.171922 -371.878647) (xy 290.13398 -371.934233)
			(xy 290.112196 -371.959886) (xy 290.10638 -371.967017) (xy 290.099877 -371.984218) (xy 290.099496 -371.993414)
			(xy 290.099496 -372.486682) (xy 290.099916 -372.495868) (xy 290.106423 -372.513053) (xy 290.112196 -372.52021)
			(xy 290.134016 -372.545835) (xy 290.171962 -372.601426) (xy 290.202991 -372.661154) (xy 290.226661 -372.724162)
			(xy 290.24263 -372.789547) (xy 290.250671 -372.856372) (xy 290.250668 -372.923679) (xy 290.242621 -372.990503)
			(xy 290.226646 -373.055887) (xy 290.202971 -373.118893) (xy 290.171935 -373.178618) (xy 290.133985 -373.234205)
			(xy 290.112196 -373.259858) (xy 290.106392 -373.266998) (xy 290.099882 -373.284192) (xy 290.099496 -373.293386)
			(xy 290.099496 -373.451374) (xy 290.098946 -373.461526) (xy 290.091187 -373.480288) (xy 290.076838 -373.494653)
			(xy 290.058085 -373.502435) (xy 290.047934 -373.502936) (xy 289.331654 -373.502936) (xy 289.32149 -373.502504)
			(xy 289.302715 -373.494709) (xy 289.28835 -373.480325) (xy 289.280582 -373.461539) (xy 289.280092 -373.451374)
			(xy 289.280092 -373.293386) (xy 289.27969 -373.284198) (xy 289.273171 -373.267014) (xy 289.267392 -373.259858)
			(xy 289.245636 -373.234179) (xy 289.207683 -373.178598) (xy 289.176645 -373.118878) (xy 289.152968 -373.055877)
			(xy 289.136991 -372.990498) (xy 289.128943 -372.923677) (xy 289.12894 -372.856374) (xy 289.136982 -372.789553)
			(xy 289.152953 -372.724172) (xy 289.176624 -372.661168) (xy 289.207656 -372.601446) (xy 289.245605 -372.545861)
			(xy 289.267392 -372.52021) (xy 289.273208 -372.513079) (xy 289.279711 -372.495878) (xy 289.280092 -372.486682)
			(xy 289.280092 -371.993414) (xy 289.279677 -371.984227) (xy 289.273167 -371.967043) (xy 289.267392 -371.959886)
			(xy 289.245565 -371.934265) (xy 289.207614 -371.878676) (xy 289.17658 -371.818948) (xy 289.152907 -371.755939)
			(xy 289.136935 -371.690553) (xy 289.128893 -371.623726) (xy 288.02681 -371.623726) (xy 288.026938 -371.624066)
			(xy 288.042974 -371.689557) (xy 288.05105 -371.756498) (xy 288.051048 -371.823923) (xy 288.04297 -371.890864)
			(xy 288.026932 -371.956354) (xy 288.003164 -372.019452) (xy 287.972008 -372.079248) (xy 287.933915 -372.134882)
			(xy 287.912048 -372.160546) (xy 287.906243 -372.167685) (xy 287.899735 -372.18488) (xy 287.899348 -372.194074)
			(xy 287.899348 -372.351554) (xy 287.898835 -372.361679) (xy 287.89112 -372.380402) (xy 287.876842 -372.39476)
			(xy 287.858162 -372.402579) (xy 287.84804 -372.403116) (xy 287.13176 -372.403116) (xy 287.121651 -372.402648)
			(xy 287.102975 -372.3949) (xy 287.088682 -372.380598) (xy 287.080946 -372.361918) (xy 287.080452 -372.351808)
			(xy 287.080452 -372.194074) (xy 287.080043 -372.184887) (xy 287.073527 -372.167703) (xy 287.067752 -372.160546)
			(xy 287.0459 -372.13487) (xy 287.007807 -372.079238) (xy 286.976653 -372.019444) (xy 286.952886 -371.956349)
			(xy 286.936848 -371.89086) (xy 286.92877 -371.823922) (xy 286.928769 -371.756499) (xy 286.936844 -371.68956)
			(xy 286.95288 -371.624072) (xy 286.976645 -371.560975) (xy 287.007797 -371.50118) (xy 287.045887 -371.445546)
			(xy 287.067752 -371.419882) (xy 287.073545 -371.412735) (xy 287.08006 -371.395546) (xy 287.080452 -371.386354)
			(xy 287.080452 -370.893848) (xy 287.080007 -370.884665) (xy 287.073516 -370.867481) (xy 287.067752 -370.86032)
			(xy 287.045874 -370.834665) (xy 287.007783 -370.779031) (xy 286.97663 -370.719233) (xy 286.952864 -370.656135)
			(xy 286.936828 -370.590644) (xy 286.928752 -370.523704) (xy 266.501372 -370.523704) (xy 266.501372 -374.423882)
			(xy 286.928731 -374.423882) (xy 286.928735 -374.356454) (xy 286.936815 -374.289512) (xy 286.952857 -374.22402)
			(xy 286.976628 -374.160921) (xy 287.007787 -374.101124) (xy 287.045884 -374.04549) (xy 287.067752 -374.019826)
			(xy 287.073569 -374.012695) (xy 287.08007 -373.995494) (xy 287.080452 -373.986298) (xy 287.080452 -373.828818)
			(xy 287.080942 -373.818691) (xy 287.088666 -373.799968) (xy 287.102951 -373.785611) (xy 287.121636 -373.777793)
			(xy 287.13176 -373.777256) (xy 287.84804 -373.777256) (xy 287.858146 -373.777751) (xy 287.876817 -373.785494)
			(xy 287.891108 -373.799787) (xy 287.898849 -373.818458) (xy 287.899348 -373.828564) (xy 287.899348 -373.986298)
			(xy 287.899771 -373.995484) (xy 287.906277 -374.012667) (xy 287.912048 -374.019826) (xy 287.933873 -374.045524)
			(xy 287.971966 -374.101153) (xy 288.003121 -374.160944) (xy 288.02689 -374.224037) (xy 288.04293 -374.289522)
			(xy 288.05101 -374.356458) (xy 288.051014 -374.423823) (xy 291.32905 -374.423823) (xy 291.329054 -374.356514)
			(xy 291.337102 -374.289689) (xy 291.35308 -374.224304) (xy 291.376757 -374.161298) (xy 291.407796 -374.101573)
			(xy 291.44575 -374.045986) (xy 291.46754 -374.020334) (xy 291.473352 -374.0132) (xy 291.479857 -373.996001)
			(xy 291.48024 -373.986806) (xy 291.48024 -373.828818) (xy 291.480678 -373.818647) (xy 291.488458 -373.799853)
			(xy 291.502839 -373.785467) (xy 291.521631 -373.777682) (xy 291.531802 -373.777256) (xy 292.248082 -373.777256)
			(xy 292.258255 -373.777679) (xy 292.277053 -373.785461) (xy 292.291439 -373.799847) (xy 292.299221 -373.818645)
			(xy 292.299644 -373.828818) (xy 292.299644 -373.986806) (xy 292.300064 -373.995992) (xy 292.306572 -374.013176)
			(xy 292.312344 -374.020334) (xy 292.334091 -374.04602) (xy 292.372042 -374.101601) (xy 292.403078 -374.16132)
			(xy 292.426754 -374.22432) (xy 292.44273 -374.289698) (xy 292.450778 -374.356517) (xy 292.450782 -374.423819)
			(xy 292.450774 -374.423882) (xy 295.728819 -374.423882) (xy 295.728822 -374.356455) (xy 295.736903 -374.289513)
			(xy 295.752944 -374.224021) (xy 295.776715 -374.160922) (xy 295.807872 -374.101125) (xy 295.845968 -374.045491)
			(xy 295.867836 -374.019826) (xy 295.873651 -374.012694) (xy 295.880154 -373.995493) (xy 295.880536 -373.986298)
			(xy 295.880536 -373.828818) (xy 295.881041 -373.818693) (xy 295.888762 -373.799973) (xy 295.903043 -373.785616)
			(xy 295.921722 -373.777796) (xy 295.931844 -373.777256) (xy 296.648124 -373.777256) (xy 296.658274 -373.777701)
			(xy 296.677019 -373.785496) (xy 296.69134 -373.799885) (xy 296.699046 -373.818666) (xy 296.699432 -373.828818)
			(xy 296.699432 -373.986298) (xy 296.699858 -373.995483) (xy 296.706362 -374.012667) (xy 296.712132 -374.019826)
			(xy 296.733954 -374.045526) (xy 296.772041 -374.101156) (xy 296.803192 -374.160948) (xy 296.826957 -374.22404)
			(xy 296.842995 -374.289525) (xy 296.851073 -374.356459) (xy 296.851077 -374.423878) (xy 296.851077 -374.423882)
			(xy 300.12861 -374.423882) (xy 300.128613 -374.356455) (xy 300.136694 -374.289513) (xy 300.152734 -374.224021)
			(xy 300.176504 -374.160923) (xy 300.207661 -374.101126) (xy 300.245757 -374.045491) (xy 300.267624 -374.019826)
			(xy 300.273437 -374.012693) (xy 300.279941 -373.995493) (xy 300.280324 -373.986298) (xy 300.280324 -373.828818)
			(xy 300.280841 -373.818694) (xy 300.28856 -373.799977) (xy 300.302837 -373.78562) (xy 300.321511 -373.777798)
			(xy 300.331632 -373.777256) (xy 301.047912 -373.777256) (xy 301.058061 -373.777711) (xy 301.076806 -373.785502)
			(xy 301.091127 -373.799888) (xy 301.098834 -373.818667) (xy 301.09922 -373.828818) (xy 301.09922 -373.986298)
			(xy 301.099627 -373.995486) (xy 301.106142 -374.01267) (xy 301.11192 -374.019826) (xy 301.133742 -374.045526)
			(xy 301.171831 -374.101156) (xy 301.202982 -374.160947) (xy 301.226748 -374.22404) (xy 301.242785 -374.289524)
			(xy 301.250864 -374.356458) (xy 301.250868 -374.423823) (xy 330.929168 -374.423823) (xy 330.929172 -374.356514)
			(xy 330.937221 -374.289688) (xy 330.953199 -374.224303) (xy 330.976878 -374.161297) (xy 331.007917 -374.101572)
			(xy 331.045873 -374.045986) (xy 331.067664 -374.020334) (xy 331.073479 -374.013202) (xy 331.079981 -373.996001)
			(xy 331.080364 -373.986806) (xy 331.080364 -373.828818) (xy 331.080779 -373.818644) (xy 331.088563 -373.799845)
			(xy 331.102952 -373.785458) (xy 331.121752 -373.777677) (xy 331.131926 -373.777256) (xy 331.848206 -373.777256)
			(xy 331.85838 -373.777659) (xy 331.877178 -373.78545) (xy 331.891564 -373.799842) (xy 331.899345 -373.818644)
			(xy 331.899768 -373.828818) (xy 331.899768 -373.986806) (xy 331.900182 -373.995993) (xy 331.906694 -374.013177)
			(xy 331.912468 -374.020334) (xy 331.934214 -374.04602) (xy 331.972164 -374.101602) (xy 332.003198 -374.161321)
			(xy 332.026873 -374.224321) (xy 332.042849 -374.289699) (xy 332.050896 -374.356518) (xy 332.0509 -374.423819)
			(xy 332.050892 -374.423882) (xy 335.328961 -374.423882) (xy 335.328965 -374.356455) (xy 335.337045 -374.289515)
			(xy 335.353083 -374.224024) (xy 335.37685 -374.160926) (xy 335.408004 -374.101128) (xy 335.446095 -374.045492)
			(xy 335.46796 -374.019826) (xy 335.473778 -374.012696) (xy 335.480278 -373.995494) (xy 335.48066 -373.986298)
			(xy 335.48066 -373.828818) (xy 335.481142 -373.81869) (xy 335.488867 -373.799965) (xy 335.503156 -373.785608)
			(xy 335.521842 -373.777791) (xy 335.531968 -373.777256) (xy 336.248248 -373.777256) (xy 336.2584 -373.777682)
			(xy 336.277145 -373.785485) (xy 336.291465 -373.799879) (xy 336.299171 -373.818664) (xy 336.299556 -373.828818)
			(xy 336.299556 -373.986298) (xy 336.299977 -373.995484) (xy 336.306484 -374.012668) (xy 336.312256 -374.019826)
			(xy 336.33408 -374.045525) (xy 336.372173 -374.101153) (xy 336.403328 -374.160944) (xy 336.427097 -374.224037)
			(xy 336.443136 -374.289523) (xy 336.451216 -374.356458) (xy 336.45122 -374.423823) (xy 339.729256 -374.423823)
			(xy 339.72926 -374.356514) (xy 339.737309 -374.289689) (xy 339.753286 -374.224304) (xy 339.776964 -374.161298)
			(xy 339.808003 -374.101573) (xy 339.845957 -374.045986) (xy 339.867748 -374.020334) (xy 339.873561 -374.013201)
			(xy 339.880065 -373.996001) (xy 339.880448 -373.986806) (xy 339.880448 -373.828818) (xy 339.880879 -373.818646)
			(xy 339.88866 -373.79985) (xy 339.903043 -373.785464) (xy 339.921838 -373.77768) (xy 339.93201 -373.777256)
			(xy 340.64829 -373.777256) (xy 340.658463 -373.777672) (xy 340.677261 -373.785457) (xy 340.691647 -373.799846)
			(xy 340.699429 -373.818645) (xy 340.699852 -373.828818) (xy 340.699852 -373.986806) (xy 340.70027 -373.995992)
			(xy 340.706779 -374.013176) (xy 340.712552 -374.020334) (xy 340.734299 -374.04602) (xy 340.772249 -374.101601)
			(xy 340.803285 -374.16132) (xy 340.82696 -374.22432) (xy 340.842936 -374.289699) (xy 340.850984 -374.356517)
			(xy 340.850988 -374.423819) (xy 340.850988 -374.423823) (xy 344.129047 -374.423823) (xy 344.129051 -374.356514)
			(xy 344.137099 -374.289689) (xy 344.153077 -374.224304) (xy 344.176754 -374.161298) (xy 344.207792 -374.101573)
			(xy 344.245746 -374.045986) (xy 344.267536 -374.020334) (xy 344.273348 -374.0132) (xy 344.279852 -373.996001)
			(xy 344.280236 -373.986806) (xy 344.280236 -373.828818) (xy 344.280678 -373.818648) (xy 344.288457 -373.799854)
			(xy 344.302837 -373.785468) (xy 344.321628 -373.777682) (xy 344.331798 -373.777256) (xy 345.048078 -373.777256)
			(xy 345.05825 -373.777683) (xy 345.077048 -373.785464) (xy 345.091434 -373.799849) (xy 345.099217 -373.818646)
			(xy 345.09964 -373.828818) (xy 345.09964 -373.986806) (xy 345.100061 -373.995992) (xy 345.106569 -374.013175)
			(xy 345.11234 -374.020334) (xy 345.134087 -374.04602) (xy 345.172038 -374.101601) (xy 345.203075 -374.16132)
			(xy 345.226751 -374.22432) (xy 345.242727 -374.289698) (xy 345.250775 -374.356517) (xy 345.250779 -374.423819)
			(xy 345.250779 -374.423823) (xy 374.929078 -374.423823) (xy 374.929081 -374.356514) (xy 374.93713 -374.289688)
			(xy 374.953109 -374.224303) (xy 374.976788 -374.161296) (xy 375.007828 -374.101572) (xy 375.045784 -374.045985)
			(xy 375.067576 -374.020334) (xy 375.07338 -374.013194) (xy 375.079891 -373.996) (xy 375.080276 -373.986806)
			(xy 375.080276 -373.828818) (xy 375.080679 -373.818643) (xy 375.088465 -373.799841) (xy 375.102858 -373.785454)
			(xy 375.121663 -373.777675) (xy 375.131838 -373.777256) (xy 375.848118 -373.777256) (xy 375.858279 -373.777719)
			(xy 375.877052 -373.785503) (xy 375.891418 -373.799878) (xy 375.899188 -373.818656) (xy 375.89968 -373.828818)
			(xy 375.89968 -373.986806) (xy 375.900092 -373.995993) (xy 375.906605 -374.013177) (xy 375.91238 -374.020334)
			(xy 375.934126 -374.046021) (xy 375.972074 -374.101603) (xy 376.003108 -374.161322) (xy 376.026783 -374.224321)
			(xy 376.042758 -374.289699) (xy 376.050805 -374.356518) (xy 376.050809 -374.423819) (xy 376.050801 -374.423882)
			(xy 379.32887 -374.423882) (xy 379.328874 -374.356455) (xy 379.336954 -374.289515) (xy 379.352993 -374.224024)
			(xy 379.376761 -374.160925) (xy 379.407915 -374.101127) (xy 379.446007 -374.045492) (xy 379.467872 -374.019826)
			(xy 379.473691 -374.012697) (xy 379.48019 -373.995494) (xy 379.480572 -373.986298) (xy 379.480572 -373.828818)
			(xy 379.481042 -373.818688) (xy 379.48877 -373.799962) (xy 379.503062 -373.785604) (xy 379.521753 -373.777789)
			(xy 379.53188 -373.777256) (xy 380.24816 -373.777256) (xy 380.258306 -373.777754) (xy 380.277049 -373.785528)
			(xy 380.291372 -373.799901) (xy 380.299081 -373.818671) (xy 380.299468 -373.828818) (xy 380.299468 -373.986298)
			(xy 380.299886 -373.995484) (xy 380.306395 -374.012668) (xy 380.312168 -374.019826) (xy 380.333992 -374.045525)
			(xy 380.372084 -374.101154) (xy 380.403238 -374.160945) (xy 380.427006 -374.224038) (xy 380.443046 -374.289523)
			(xy 380.451125 -374.356458) (xy 380.451129 -374.423823) (xy 383.729165 -374.423823) (xy 383.729169 -374.356514)
			(xy 383.737218 -374.289688) (xy 383.753196 -374.224303) (xy 383.776874 -374.161297) (xy 383.807914 -374.101572)
			(xy 383.845869 -374.045986) (xy 383.86766 -374.020334) (xy 383.873474 -374.013202) (xy 383.879977 -373.996001)
			(xy 383.88036 -373.986806) (xy 383.88036 -373.828818) (xy 383.880779 -373.818645) (xy 383.888562 -373.799846)
			(xy 383.90295 -373.78546) (xy 383.921749 -373.777678) (xy 383.931922 -373.777256) (xy 384.648202 -373.777256)
			(xy 384.658376 -373.777663) (xy 384.677174 -373.785452) (xy 384.69156 -373.799843) (xy 384.699341 -373.818644)
			(xy 384.699764 -373.828818) (xy 384.699764 -373.986806) (xy 384.700179 -373.995992) (xy 384.70669 -374.013176)
			(xy 384.712464 -374.020334) (xy 384.73421 -374.04602) (xy 384.77216 -374.101602) (xy 384.803195 -374.161321)
			(xy 384.82687 -374.224321) (xy 384.842846 -374.289699) (xy 384.850893 -374.356518) (xy 384.850897 -374.423819)
			(xy 384.850897 -374.423823) (xy 388.128956 -374.423823) (xy 388.12896 -374.356514) (xy 388.137009 -374.289689)
			(xy 388.152986 -374.224304) (xy 388.176664 -374.161298) (xy 388.207703 -374.101573) (xy 388.245657 -374.045986)
			(xy 388.267448 -374.020334) (xy 388.273261 -374.013201) (xy 388.279765 -373.996001) (xy 388.280148 -373.986806)
			(xy 388.280148 -373.828818) (xy 388.280579 -373.818646) (xy 388.28836 -373.79985) (xy 388.302743 -373.785464)
			(xy 388.321538 -373.77768) (xy 388.33171 -373.777256) (xy 389.04799 -373.777256) (xy 389.058163 -373.777672)
			(xy 389.076961 -373.785457) (xy 389.091347 -373.799846) (xy 389.099129 -373.818645) (xy 389.099552 -373.828818)
			(xy 389.099552 -373.986806) (xy 389.09997 -373.995992) (xy 389.106479 -374.013176) (xy 389.112252 -374.020334)
			(xy 389.133999 -374.04602) (xy 389.171949 -374.101601) (xy 389.202985 -374.16132) (xy 389.22666 -374.22432)
			(xy 389.242636 -374.289699) (xy 389.250684 -374.356517) (xy 389.250688 -374.423819) (xy 389.250688 -374.423823)
			(xy 418.928987 -374.423823) (xy 418.928991 -374.356514) (xy 418.93704 -374.289688) (xy 418.953019 -374.224302)
			(xy 418.976698 -374.161296) (xy 419.007739 -374.101572) (xy 419.045696 -374.045986) (xy 419.067488 -374.020334)
			(xy 419.073294 -374.013195) (xy 419.079803 -373.996) (xy 419.080188 -373.986806) (xy 419.080188 -373.828818)
			(xy 419.08058 -373.818641) (xy 419.088368 -373.799837) (xy 419.102764 -373.78545) (xy 419.121573 -373.777673)
			(xy 419.13175 -373.777256) (xy 419.84803 -373.777256) (xy 419.858192 -373.777709) (xy 419.876965 -373.785497)
			(xy 419.89133 -373.799875) (xy 419.8991 -373.818656) (xy 419.899592 -373.828818) (xy 419.899592 -373.986806)
			(xy 419.900001 -373.995993) (xy 419.906516 -374.013177) (xy 419.912292 -374.020334) (xy 419.934038 -374.04602)
			(xy 419.971986 -374.101603) (xy 420.003019 -374.161322) (xy 420.026693 -374.224322) (xy 420.042668 -374.2897)
			(xy 420.050715 -374.356518) (xy 420.050719 -374.423819) (xy 420.050711 -374.423882) (xy 423.328779 -374.423882)
			(xy 423.328783 -374.356455) (xy 423.336863 -374.289514) (xy 423.352903 -374.224023) (xy 423.376671 -374.160925)
			(xy 423.407825 -374.101127) (xy 423.445918 -374.045492) (xy 423.467784 -374.019826) (xy 423.473593 -374.012689)
			(xy 423.480101 -373.995492) (xy 423.480484 -373.986298) (xy 423.480484 -373.828818) (xy 423.480942 -373.818687)
			(xy 423.488672 -373.799958) (xy 423.502968 -373.785599) (xy 423.521663 -373.777787) (xy 423.531792 -373.777256)
			(xy 424.248072 -373.777256) (xy 424.258174 -373.777807) (xy 424.276843 -373.785527) (xy 424.291137 -373.799803)
			(xy 424.298881 -373.818463) (xy 424.29938 -373.828564) (xy 424.29938 -373.986298) (xy 424.299795 -373.995485)
			(xy 424.306306 -374.012669) (xy 424.31208 -374.019826) (xy 424.333903 -374.045525) (xy 424.371995 -374.101154)
			(xy 424.403148 -374.160946) (xy 424.426916 -374.224038) (xy 424.442955 -374.289523) (xy 424.451034 -374.356458)
			(xy 424.451038 -374.423823) (xy 427.729074 -374.423823) (xy 427.729078 -374.356514) (xy 427.737127 -374.289688)
			(xy 427.753106 -374.224303) (xy 427.776784 -374.161296) (xy 427.807824 -374.101572) (xy 427.84578 -374.045986)
			(xy 427.867572 -374.020334) (xy 427.873388 -374.013203) (xy 427.879889 -373.996001) (xy 427.880272 -373.986806)
			(xy 427.880272 -373.828818) (xy 427.880679 -373.818643) (xy 427.888465 -373.799842) (xy 427.902856 -373.785456)
			(xy 427.921659 -373.777676) (xy 427.931834 -373.777256) (xy 428.648114 -373.777256) (xy 428.658289 -373.777653)
			(xy 428.677087 -373.785446) (xy 428.691472 -373.79984) (xy 428.699253 -373.818643) (xy 428.699676 -373.828818)
			(xy 428.699676 -373.986806) (xy 428.700088 -373.995993) (xy 428.706601 -374.013177) (xy 428.712376 -374.020334)
			(xy 428.734122 -374.04602) (xy 428.772071 -374.101602) (xy 428.803105 -374.161321) (xy 428.82678 -374.224321)
			(xy 428.842755 -374.289699) (xy 428.850802 -374.356518) (xy 428.850806 -374.423819) (xy 428.850806 -374.423823)
			(xy 432.128865 -374.423823) (xy 432.128869 -374.356514) (xy 432.136918 -374.289688) (xy 432.152896 -374.224303)
			(xy 432.176574 -374.161297) (xy 432.207614 -374.101572) (xy 432.245569 -374.045986) (xy 432.26736 -374.020334)
			(xy 432.273174 -374.013202) (xy 432.279677 -373.996001) (xy 432.28006 -373.986806) (xy 432.28006 -373.828818)
			(xy 432.280479 -373.818645) (xy 432.288262 -373.799846) (xy 432.30265 -373.78546) (xy 432.321449 -373.777678)
			(xy 432.331622 -373.777256) (xy 433.047902 -373.777256) (xy 433.058076 -373.777663) (xy 433.076874 -373.785452)
			(xy 433.09126 -373.799843) (xy 433.099041 -373.818644) (xy 433.099464 -373.828818) (xy 433.099464 -373.986806)
			(xy 433.099879 -373.995992) (xy 433.10639 -374.013176) (xy 433.112164 -374.020334) (xy 433.13391 -374.04602)
			(xy 433.17186 -374.101602) (xy 433.202895 -374.161321) (xy 433.22657 -374.224321) (xy 433.242546 -374.289699)
			(xy 433.250593 -374.356518) (xy 433.250597 -374.423819) (xy 433.242557 -374.490639) (xy 433.226589 -374.556019)
			(xy 433.202921 -374.619021) (xy 433.171892 -374.678744) (xy 433.133949 -374.73433) (xy 433.112164 -374.759982)
			(xy 433.106346 -374.767112) (xy 433.099845 -374.784314) (xy 433.099464 -374.79351) (xy 433.099464 -375.286778)
			(xy 433.099893 -375.295963) (xy 433.106394 -375.313147) (xy 433.112164 -375.320306) (xy 433.133981 -375.345934)
			(xy 433.171929 -375.401524) (xy 433.202961 -375.461251) (xy 433.226632 -375.524259) (xy 433.242603 -375.589644)
			(xy 433.250644 -375.656469) (xy 433.250642 -375.723776) (xy 433.242594 -375.790601) (xy 433.226618 -375.855985)
			(xy 433.202942 -375.91899) (xy 433.171906 -375.978715) (xy 433.133954 -376.034302) (xy 433.112164 -376.059954)
			(xy 433.106357 -376.067092) (xy 433.09985 -376.084288) (xy 433.099464 -376.093482) (xy 433.099464 -376.25147)
			(xy 433.099011 -376.261639) (xy 433.091237 -376.280433) (xy 433.07686 -376.294819) (xy 433.058071 -376.302605)
			(xy 433.047902 -376.303032) (xy 432.331622 -376.303032) (xy 432.321448 -376.302617) (xy 432.302648 -376.294834)
			(xy 432.288262 -376.280445) (xy 432.280481 -376.261644) (xy 432.28006 -376.25147) (xy 432.28006 -376.093482)
			(xy 432.279645 -376.084296) (xy 432.273133 -376.067112) (xy 432.26736 -376.059954) (xy 432.245601 -376.034278)
			(xy 432.20765 -375.978695) (xy 432.176614 -375.918975) (xy 432.152939 -375.855974) (xy 432.136963 -375.790594)
			(xy 432.128917 -375.723774) (xy 432.128914 -375.656471) (xy 432.136955 -375.58965) (xy 432.152926 -375.524269)
			(xy 432.176596 -375.461266) (xy 432.207627 -375.401543) (xy 432.245574 -375.345958) (xy 432.26736 -375.320306)
			(xy 432.273144 -375.313152) (xy 432.279664 -375.295968) (xy 432.28006 -375.286778) (xy 432.28006 -374.79351)
			(xy 432.279632 -374.784325) (xy 432.273129 -374.767141) (xy 432.26736 -374.759982) (xy 432.24553 -374.734364)
			(xy 432.207581 -374.678773) (xy 432.176549 -374.619045) (xy 432.152877 -374.556036) (xy 432.136907 -374.49065)
			(xy 432.128865 -374.423823) (xy 428.850806 -374.423823) (xy 428.842766 -374.490639) (xy 428.826798 -374.556018)
			(xy 428.803131 -374.619021) (xy 428.772103 -374.678743) (xy 428.73416 -374.734329) (xy 428.712376 -374.759982)
			(xy 428.706559 -374.767113) (xy 428.700057 -374.784314) (xy 428.699676 -374.79351) (xy 428.699676 -375.286778)
			(xy 428.700102 -375.295963) (xy 428.706605 -375.313148) (xy 428.712376 -375.320306) (xy 428.734193 -375.345934)
			(xy 428.77214 -375.401524) (xy 428.803171 -375.461251) (xy 428.826841 -375.524259) (xy 428.842812 -375.589644)
			(xy 428.850853 -375.656469) (xy 428.850851 -375.723776) (xy 428.842804 -375.790601) (xy 428.826828 -375.855984)
			(xy 428.803152 -375.91899) (xy 428.772117 -375.978714) (xy 428.734165 -376.034302) (xy 428.712376 -376.059954)
			(xy 428.706571 -376.067093) (xy 428.700062 -376.084288) (xy 428.699676 -376.093482) (xy 428.699676 -376.25147)
			(xy 428.699212 -376.261638) (xy 428.691439 -376.280429) (xy 428.677066 -376.294815) (xy 428.658282 -376.302603)
			(xy 428.648114 -376.303032) (xy 427.931834 -376.303032) (xy 427.921661 -376.302607) (xy 427.902861 -376.294828)
			(xy 427.888474 -376.280442) (xy 427.880693 -376.261643) (xy 427.880272 -376.25147) (xy 427.880272 -376.093482)
			(xy 427.879877 -376.084293) (xy 427.873353 -376.067109) (xy 427.867572 -376.059954) (xy 427.845813 -376.034278)
			(xy 427.807861 -375.978696) (xy 427.776825 -375.918976) (xy 427.753149 -375.855974) (xy 427.737173 -375.790595)
			(xy 427.729126 -375.723774) (xy 427.729123 -375.656471) (xy 427.737165 -375.58965) (xy 427.753135 -375.524269)
			(xy 427.776806 -375.461266) (xy 427.807838 -375.401543) (xy 427.845785 -375.345958) (xy 427.867572 -375.320306)
			(xy 427.873357 -375.313153) (xy 427.879877 -375.295968) (xy 427.880272 -375.286778) (xy 427.880272 -374.79351)
			(xy 427.879863 -374.784323) (xy 427.873349 -374.767138) (xy 427.867572 -374.759982) (xy 427.845742 -374.734364)
			(xy 427.807792 -374.678774) (xy 427.776759 -374.619046) (xy 427.753087 -374.556037) (xy 427.737116 -374.49065)
			(xy 427.729074 -374.423823) (xy 424.451038 -374.423823) (xy 424.451038 -374.423879) (xy 424.442966 -374.490815)
			(xy 424.426934 -374.556302) (xy 424.403174 -374.619397) (xy 424.372027 -374.679192) (xy 424.333942 -374.734825)
			(xy 424.31208 -374.76049) (xy 424.30626 -374.767619) (xy 424.29976 -374.784822) (xy 424.29938 -374.794018)
			(xy 424.29938 -375.28627) (xy 424.299809 -375.295455) (xy 424.30631 -375.312639) (xy 424.31208 -375.319798)
			(xy 424.333974 -375.345439) (xy 424.372063 -375.401076) (xy 424.403214 -375.460876) (xy 424.426977 -375.523976)
			(xy 424.443011 -375.589468) (xy 424.451085 -375.656409) (xy 424.451082 -375.723836) (xy 424.443003 -375.790776)
			(xy 424.426964 -375.856267) (xy 424.403195 -375.919366) (xy 424.37204 -375.979163) (xy 424.333946 -376.034797)
			(xy 424.31208 -376.060462) (xy 424.306272 -376.067599) (xy 424.299765 -376.084796) (xy 424.29938 -376.09399)
			(xy 424.29938 -376.25147) (xy 424.29885 -376.261592) (xy 424.291135 -376.280309) (xy 424.276863 -376.294666)
			(xy 424.258191 -376.30249) (xy 424.248072 -376.303032) (xy 423.531792 -376.303032) (xy 423.521687 -376.302522)
			(xy 423.503015 -376.294788) (xy 423.488721 -376.280499) (xy 423.480981 -376.261829) (xy 423.480484 -376.251724)
			(xy 423.480484 -376.09399) (xy 423.480082 -376.084802) (xy 423.473563 -376.067617) (xy 423.467784 -376.060462)
			(xy 423.44595 -376.034772) (xy 423.407862 -375.979141) (xy 423.37671 -375.919348) (xy 423.352945 -375.856254)
			(xy 423.336908 -375.790768) (xy 423.32883 -375.723833) (xy 423.328827 -375.656412) (xy 423.3369 -375.589476)
			(xy 423.352932 -375.523989) (xy 423.376692 -375.460893) (xy 423.407838 -375.401098) (xy 423.445922 -375.345463)
			(xy 423.467784 -375.319798) (xy 423.473562 -375.31264) (xy 423.480088 -375.295459) (xy 423.480484 -375.28627)
			(xy 423.480484 -374.794018) (xy 423.480069 -374.784831) (xy 423.473559 -374.767647) (xy 423.467784 -374.76049)
			(xy 423.445879 -374.734859) (xy 423.407793 -374.679219) (xy 423.376645 -374.619418) (xy 423.352884 -374.556317)
			(xy 423.336852 -374.490824) (xy 423.328779 -374.423882) (xy 420.050711 -374.423882) (xy 420.042679 -374.490638)
			(xy 420.026712 -374.556018) (xy 420.003045 -374.61902) (xy 419.972018 -374.678743) (xy 419.934076 -374.73433)
			(xy 419.912292 -374.759982) (xy 419.906477 -374.767114) (xy 419.899974 -374.784315) (xy 419.899592 -374.79351)
			(xy 419.899592 -375.286778) (xy 419.900015 -375.295964) (xy 419.90652 -375.313148) (xy 419.912292 -375.320306)
			(xy 419.934108 -375.345934) (xy 419.972054 -375.401525) (xy 420.003084 -375.461252) (xy 420.026754 -375.52426)
			(xy 420.042724 -375.589644) (xy 420.050765 -375.656469) (xy 420.050763 -375.723776) (xy 420.042716 -375.7906)
			(xy 420.026741 -375.855984) (xy 420.003066 -375.918989) (xy 419.972031 -375.978714) (xy 419.934081 -376.034301)
			(xy 419.912292 -376.059954) (xy 419.906489 -376.067095) (xy 419.899978 -376.084289) (xy 419.899592 -376.093482)
			(xy 419.899592 -376.25147) (xy 419.899043 -376.261622) (xy 419.891284 -376.280385) (xy 419.876935 -376.29475)
			(xy 419.858182 -376.302531) (xy 419.84803 -376.303032) (xy 419.13175 -376.303032) (xy 419.121578 -376.302595)
			(xy 419.102779 -376.29482) (xy 419.088391 -376.280438) (xy 419.080609 -376.261642) (xy 419.080188 -376.25147)
			(xy 419.080188 -376.093482) (xy 419.079789 -376.084294) (xy 419.073268 -376.067109) (xy 419.067488 -376.059954)
			(xy 419.045728 -376.034278) (xy 419.007775 -375.978696) (xy 418.976738 -375.918976) (xy 418.953061 -375.855975)
			(xy 418.937085 -375.790595) (xy 418.929038 -375.723774) (xy 418.929035 -375.656471) (xy 418.937077 -375.589649)
			(xy 418.953048 -375.524268) (xy 418.97672 -375.461265) (xy 419.007752 -375.401542) (xy 419.045701 -375.345957)
			(xy 419.067488 -375.320306) (xy 419.073263 -375.313145) (xy 419.079791 -375.295967) (xy 419.080188 -375.286778)
			(xy 419.080188 -374.79351) (xy 419.079776 -374.784323) (xy 419.073264 -374.767138) (xy 419.067488 -374.759982)
			(xy 419.045658 -374.734364) (xy 419.007707 -374.678774) (xy 418.976673 -374.619046) (xy 418.953 -374.556037)
			(xy 418.937029 -374.49065) (xy 418.928987 -374.423823) (xy 389.250688 -374.423823) (xy 389.242648 -374.490639)
			(xy 389.226679 -374.556019) (xy 389.203011 -374.619022) (xy 389.171982 -374.678744) (xy 389.134037 -374.73433)
			(xy 389.112252 -374.759982) (xy 389.106432 -374.76711) (xy 389.099933 -374.784314) (xy 389.099552 -374.79351)
			(xy 389.099552 -375.286778) (xy 389.099983 -375.295963) (xy 389.106483 -375.313147) (xy 389.112252 -375.320306)
			(xy 389.13407 -375.345934) (xy 389.172018 -375.401523) (xy 389.203051 -375.46125) (xy 389.226722 -375.524258)
			(xy 389.242693 -375.589643) (xy 389.250735 -375.656469) (xy 389.250732 -375.723776) (xy 389.242685 -375.790601)
			(xy 389.226709 -375.855985) (xy 389.203032 -375.918991) (xy 389.171995 -375.978715) (xy 389.134042 -376.034302)
			(xy 389.112252 -376.059954) (xy 389.106444 -376.067091) (xy 389.099937 -376.084288) (xy 389.099552 -376.093482)
			(xy 389.099552 -376.25147) (xy 389.099111 -376.261641) (xy 389.091334 -376.280437) (xy 389.076954 -376.294823)
			(xy 389.058161 -376.302607) (xy 389.04799 -376.303032) (xy 388.33171 -376.303032) (xy 388.321535 -376.302627)
			(xy 388.302735 -376.29484) (xy 388.288349 -376.280448) (xy 388.280569 -376.261645) (xy 388.280148 -376.25147)
			(xy 388.280148 -376.093482) (xy 388.279736 -376.084295) (xy 388.273222 -376.067111) (xy 388.267448 -376.059954)
			(xy 388.24569 -376.034278) (xy 388.207739 -375.978695) (xy 388.176704 -375.918975) (xy 388.153029 -375.855973)
			(xy 388.137054 -375.790594) (xy 388.129007 -375.723774) (xy 388.129005 -375.656471) (xy 388.137046 -375.58965)
			(xy 388.153016 -375.52427) (xy 388.176686 -375.461267) (xy 388.207716 -375.401544) (xy 388.245662 -375.345958)
			(xy 388.267448 -375.320306) (xy 388.273231 -375.313151) (xy 388.279752 -375.295968) (xy 388.280148 -375.286778)
			(xy 388.280148 -374.79351) (xy 388.279722 -374.784325) (xy 388.273218 -374.767141) (xy 388.267448 -374.759982)
			(xy 388.245619 -374.734364) (xy 388.20767 -374.678773) (xy 388.176638 -374.619045) (xy 388.152968 -374.556036)
			(xy 388.136997 -374.490649) (xy 388.128956 -374.423823) (xy 384.850897 -374.423823) (xy 384.842857 -374.490639)
			(xy 384.826889 -374.556019) (xy 384.803221 -374.619021) (xy 384.772192 -374.678744) (xy 384.734249 -374.73433)
			(xy 384.712464 -374.759982) (xy 384.706646 -374.767112) (xy 384.700145 -374.784314) (xy 384.699764 -374.79351)
			(xy 384.699764 -375.286778) (xy 384.700193 -375.295963) (xy 384.706694 -375.313147) (xy 384.712464 -375.320306)
			(xy 384.734281 -375.345934) (xy 384.772229 -375.401524) (xy 384.803261 -375.461251) (xy 384.826932 -375.524259)
			(xy 384.842903 -375.589644) (xy 384.850944 -375.656469) (xy 384.850942 -375.723776) (xy 384.842894 -375.790601)
			(xy 384.826918 -375.855985) (xy 384.803242 -375.91899) (xy 384.772206 -375.978715) (xy 384.734254 -376.034302)
			(xy 384.712464 -376.059954) (xy 384.706657 -376.067092) (xy 384.70015 -376.084288) (xy 384.699764 -376.093482)
			(xy 384.699764 -376.25147) (xy 384.699311 -376.261639) (xy 384.691537 -376.280433) (xy 384.67716 -376.294819)
			(xy 384.658371 -376.302605) (xy 384.648202 -376.303032) (xy 383.931922 -376.303032) (xy 383.921748 -376.302617)
			(xy 383.902948 -376.294834) (xy 383.888562 -376.280445) (xy 383.880781 -376.261644) (xy 383.88036 -376.25147)
			(xy 383.88036 -376.093482) (xy 383.879945 -376.084296) (xy 383.873433 -376.067112) (xy 383.86766 -376.059954)
			(xy 383.845901 -376.034278) (xy 383.80795 -375.978695) (xy 383.776914 -375.918975) (xy 383.753239 -375.855974)
			(xy 383.737263 -375.790594) (xy 383.729217 -375.723774) (xy 383.729214 -375.656471) (xy 383.737255 -375.58965)
			(xy 383.753226 -375.524269) (xy 383.776896 -375.461266) (xy 383.807927 -375.401543) (xy 383.845874 -375.345958)
			(xy 383.86766 -375.320306) (xy 383.873444 -375.313152) (xy 383.879964 -375.295968) (xy 383.88036 -375.286778)
			(xy 383.88036 -374.79351) (xy 383.879932 -374.784325) (xy 383.873429 -374.767141) (xy 383.86766 -374.759982)
			(xy 383.84583 -374.734364) (xy 383.807881 -374.678773) (xy 383.776849 -374.619045) (xy 383.753177 -374.556036)
			(xy 383.737207 -374.49065) (xy 383.729165 -374.423823) (xy 380.451129 -374.423823) (xy 380.451129 -374.423879)
			(xy 380.443057 -374.490815) (xy 380.427025 -374.556302) (xy 380.403264 -374.619397) (xy 380.372116 -374.679192)
			(xy 380.334031 -374.734825) (xy 380.312168 -374.76049) (xy 380.306347 -374.767617) (xy 380.299847 -374.784822)
			(xy 380.299468 -374.794018) (xy 380.299468 -375.28627) (xy 380.2999 -375.295455) (xy 380.306399 -375.312639)
			(xy 380.312168 -375.319798) (xy 380.334063 -375.345438) (xy 380.372152 -375.401076) (xy 380.403304 -375.460875)
			(xy 380.427068 -375.523975) (xy 380.443102 -375.589468) (xy 380.451176 -375.656409) (xy 380.451173 -375.723836)
			(xy 380.443094 -375.790777) (xy 380.427054 -375.856268) (xy 380.403285 -375.919366) (xy 380.372129 -375.979163)
			(xy 380.334035 -376.034797) (xy 380.312168 -376.060462) (xy 380.306358 -376.067598) (xy 380.299852 -376.084796)
			(xy 380.299468 -376.09399) (xy 380.299468 -376.25147) (xy 380.298949 -376.261594) (xy 380.291233 -376.280313)
			(xy 380.276956 -376.29467) (xy 380.258281 -376.302492) (xy 380.24816 -376.303032) (xy 379.53188 -376.303032)
			(xy 379.521729 -376.302596) (xy 379.502982 -376.294799) (xy 379.48866 -376.280408) (xy 379.480955 -376.261623)
			(xy 379.480572 -376.25147) (xy 379.480572 -376.09399) (xy 379.480173 -376.084802) (xy 379.473652 -376.067617)
			(xy 379.467872 -376.060462) (xy 379.446038 -376.034772) (xy 379.407951 -375.97914) (xy 379.3768 -375.919347)
			(xy 379.353036 -375.856254) (xy 379.336999 -375.790768) (xy 379.328921 -375.723833) (xy 379.328918 -375.656412)
			(xy 379.336991 -375.589476) (xy 379.353022 -375.523989) (xy 379.376782 -375.460894) (xy 379.407928 -375.401098)
			(xy 379.446011 -375.345464) (xy 379.467872 -375.319798) (xy 379.473661 -375.312648) (xy 379.480178 -375.295461)
			(xy 379.480572 -375.28627) (xy 379.480572 -374.794018) (xy 379.48016 -374.784831) (xy 379.473648 -374.767646)
			(xy 379.467872 -374.76049) (xy 379.445968 -374.734858) (xy 379.407882 -374.679218) (xy 379.376735 -374.619417)
			(xy 379.352974 -374.556316) (xy 379.336943 -374.490823) (xy 379.32887 -374.423882) (xy 376.050801 -374.423882)
			(xy 376.042769 -374.490638) (xy 376.026801 -374.556018) (xy 376.003134 -374.619021) (xy 375.972107 -374.678743)
			(xy 375.934164 -374.734329) (xy 375.91238 -374.759982) (xy 375.906564 -374.767113) (xy 375.900062 -374.784315)
			(xy 375.89968 -374.79351) (xy 375.89968 -375.286778) (xy 375.900105 -375.295963) (xy 375.906609 -375.313148)
			(xy 375.91238 -375.320306) (xy 375.934197 -375.345934) (xy 375.972143 -375.401524) (xy 376.003174 -375.461252)
			(xy 376.026845 -375.524259) (xy 376.042815 -375.589644) (xy 376.050856 -375.656469) (xy 376.050854 -375.723776)
			(xy 376.042807 -375.7906) (xy 376.026831 -375.855984) (xy 376.003156 -375.91899) (xy 375.97212 -375.978714)
			(xy 375.934169 -376.034302) (xy 375.91238 -376.059954) (xy 375.906576 -376.067094) (xy 375.900066 -376.084288)
			(xy 375.89968 -376.093482) (xy 375.89968 -376.25147) (xy 375.899212 -376.261637) (xy 375.89144 -376.280428)
			(xy 375.877068 -376.294813) (xy 375.858285 -376.302602) (xy 375.848118 -376.303032) (xy 375.131838 -376.303032)
			(xy 375.121665 -376.302604) (xy 375.102866 -376.294826) (xy 375.088478 -376.280441) (xy 375.080697 -376.261643)
			(xy 375.080276 -376.25147) (xy 375.080276 -376.093482) (xy 375.07988 -376.084293) (xy 375.073357 -376.067109)
			(xy 375.067576 -376.059954) (xy 375.045817 -376.034278) (xy 375.007865 -375.978696) (xy 374.976828 -375.918976)
			(xy 374.953152 -375.855974) (xy 374.937176 -375.790595) (xy 374.929129 -375.723774) (xy 374.929126 -375.656471)
			(xy 374.937168 -375.58965) (xy 374.953138 -375.524269) (xy 374.97681 -375.461265) (xy 375.007841 -375.401543)
			(xy 375.045789 -375.345958) (xy 375.067576 -375.320306) (xy 375.07335 -375.313144) (xy 375.079879 -375.295967)
			(xy 375.080276 -375.286778) (xy 375.080276 -374.79351) (xy 375.079866 -374.784323) (xy 375.073353 -374.767138)
			(xy 375.067576 -374.759982) (xy 375.045746 -374.734365) (xy 375.007796 -374.678774) (xy 374.976762 -374.619046)
			(xy 374.95309 -374.556037) (xy 374.937119 -374.49065) (xy 374.929078 -374.423823) (xy 345.250779 -374.423823)
			(xy 345.242739 -374.49064) (xy 345.226769 -374.55602) (xy 345.2031 -374.619022) (xy 345.172071 -374.678745)
			(xy 345.134126 -374.73433) (xy 345.11234 -374.759982) (xy 345.106519 -374.767109) (xy 345.10002 -374.784314)
			(xy 345.09964 -374.79351) (xy 345.09964 -375.286778) (xy 345.100074 -375.295962) (xy 345.106573 -375.313146)
			(xy 345.11234 -375.320306) (xy 345.134158 -375.345933) (xy 345.172107 -375.401523) (xy 345.203141 -375.46125)
			(xy 345.226813 -375.524258) (xy 345.242784 -375.589643) (xy 345.250826 -375.656469) (xy 345.250823 -375.723776)
			(xy 345.242776 -375.790602) (xy 345.226799 -375.855986) (xy 345.203122 -375.918992) (xy 345.172084 -375.978716)
			(xy 345.13413 -376.034302) (xy 345.11234 -376.059954) (xy 345.106531 -376.06709) (xy 345.100025 -376.084288)
			(xy 345.09964 -376.093482) (xy 345.09964 -376.25147) (xy 345.099211 -376.261642) (xy 345.091432 -376.280441)
			(xy 345.077047 -376.294827) (xy 345.05825 -376.302609) (xy 345.048078 -376.303032) (xy 344.331798 -376.303032)
			(xy 344.321623 -376.302637) (xy 344.302822 -376.294846) (xy 344.288436 -376.280451) (xy 344.280657 -376.261646)
			(xy 344.280236 -376.25147) (xy 344.280236 -376.093482) (xy 344.279826 -376.084295) (xy 344.273311 -376.067111)
			(xy 344.267536 -376.059954) (xy 344.245778 -376.034277) (xy 344.207829 -375.978694) (xy 344.176794 -375.918974)
			(xy 344.15312 -375.855973) (xy 344.137145 -375.790594) (xy 344.129098 -375.723774) (xy 344.129096 -375.656471)
			(xy 344.137137 -375.589651) (xy 344.153106 -375.52427) (xy 344.176776 -375.461267) (xy 344.207805 -375.401544)
			(xy 344.24575 -375.345958) (xy 344.267536 -375.320306) (xy 344.273317 -375.31315) (xy 344.27984 -375.295968)
			(xy 344.280236 -375.286778) (xy 344.280236 -374.79351) (xy 344.279813 -374.784324) (xy 344.273308 -374.76714)
			(xy 344.267536 -374.759982) (xy 344.245707 -374.734364) (xy 344.20776 -374.678772) (xy 344.176728 -374.619044)
			(xy 344.153058 -374.556035) (xy 344.137088 -374.490649) (xy 344.129047 -374.423823) (xy 340.850988 -374.423823)
			(xy 340.842948 -374.490639) (xy 340.826979 -374.556019) (xy 340.803311 -374.619022) (xy 340.772282 -374.678744)
			(xy 340.734337 -374.73433) (xy 340.712552 -374.759982) (xy 340.706732 -374.76711) (xy 340.700233 -374.784314)
			(xy 340.699852 -374.79351) (xy 340.699852 -375.286778) (xy 340.700283 -375.295963) (xy 340.706783 -375.313147)
			(xy 340.712552 -375.320306) (xy 340.73437 -375.345934) (xy 340.772318 -375.401523) (xy 340.803351 -375.46125)
			(xy 340.827022 -375.524258) (xy 340.842993 -375.589643) (xy 340.851035 -375.656469) (xy 340.851032 -375.723776)
			(xy 340.842985 -375.790601) (xy 340.827009 -375.855985) (xy 340.803332 -375.918991) (xy 340.772295 -375.978715)
			(xy 340.734342 -376.034302) (xy 340.712552 -376.059954) (xy 340.706744 -376.067091) (xy 340.700237 -376.084288)
			(xy 340.699852 -376.093482) (xy 340.699852 -376.25147) (xy 340.699411 -376.261641) (xy 340.691634 -376.280437)
			(xy 340.677254 -376.294823) (xy 340.658461 -376.302607) (xy 340.64829 -376.303032) (xy 339.93201 -376.303032)
			(xy 339.921835 -376.302627) (xy 339.903035 -376.29484) (xy 339.888649 -376.280448) (xy 339.880869 -376.261645)
			(xy 339.880448 -376.25147) (xy 339.880448 -376.093482) (xy 339.880036 -376.084295) (xy 339.873522 -376.067111)
			(xy 339.867748 -376.059954) (xy 339.84599 -376.034278) (xy 339.808039 -375.978695) (xy 339.777004 -375.918975)
			(xy 339.753329 -375.855973) (xy 339.737354 -375.790594) (xy 339.729307 -375.723774) (xy 339.729305 -375.656471)
			(xy 339.737346 -375.58965) (xy 339.753316 -375.52427) (xy 339.776986 -375.461267) (xy 339.808016 -375.401544)
			(xy 339.845962 -375.345958) (xy 339.867748 -375.320306) (xy 339.873531 -375.313151) (xy 339.880052 -375.295968)
			(xy 339.880448 -375.286778) (xy 339.880448 -374.79351) (xy 339.880022 -374.784325) (xy 339.873518 -374.767141)
			(xy 339.867748 -374.759982) (xy 339.845919 -374.734364) (xy 339.80797 -374.678773) (xy 339.776938 -374.619045)
			(xy 339.753268 -374.556036) (xy 339.737297 -374.490649) (xy 339.729256 -374.423823) (xy 336.45122 -374.423823)
			(xy 336.45122 -374.423879) (xy 336.443148 -374.490815) (xy 336.427115 -374.556303) (xy 336.403354 -374.619398)
			(xy 336.372206 -374.679193) (xy 336.334119 -374.734826) (xy 336.312256 -374.76049) (xy 336.306433 -374.767616)
			(xy 336.299935 -374.784821) (xy 336.299556 -374.794018) (xy 336.299556 -375.28627) (xy 336.29999 -375.295454)
			(xy 336.306488 -375.312639) (xy 336.312256 -375.319798) (xy 336.334151 -375.345438) (xy 336.372242 -375.401075)
			(xy 336.403394 -375.460875) (xy 336.427158 -375.523975) (xy 336.443193 -375.589467) (xy 336.451267 -375.656409)
			(xy 336.451264 -375.723836) (xy 336.443185 -375.790777) (xy 336.427145 -375.856268) (xy 336.403375 -375.919367)
			(xy 336.372218 -375.979163) (xy 336.334123 -376.034797) (xy 336.312256 -376.060462) (xy 336.306445 -376.067597)
			(xy 336.29994 -376.084795) (xy 336.299556 -376.09399) (xy 336.299556 -376.25147) (xy 336.299049 -376.261595)
			(xy 336.29133 -376.280317) (xy 336.27705 -376.294674) (xy 336.258371 -376.302494) (xy 336.248248 -376.303032)
			(xy 335.531968 -376.303032) (xy 335.521816 -376.302605) (xy 335.503069 -376.294805) (xy 335.488748 -376.280411)
			(xy 335.481043 -376.261624) (xy 335.48066 -376.25147) (xy 335.48066 -376.09399) (xy 335.480241 -376.084804)
			(xy 335.473732 -376.06762) (xy 335.46796 -376.060462) (xy 335.446127 -376.034772) (xy 335.40804 -375.97914)
			(xy 335.37689 -375.919347) (xy 335.353126 -375.856253) (xy 335.33709 -375.790768) (xy 335.329012 -375.723833)
			(xy 335.329009 -375.656412) (xy 335.337082 -375.589477) (xy 335.353113 -375.52399) (xy 335.376872 -375.460894)
			(xy 335.408017 -375.401099) (xy 335.446099 -375.345464) (xy 335.46796 -375.319798) (xy 335.473747 -375.312647)
			(xy 335.480266 -375.295461) (xy 335.48066 -375.28627) (xy 335.48066 -374.794018) (xy 335.480228 -374.784833)
			(xy 335.473728 -374.76765) (xy 335.46796 -374.76049) (xy 335.446056 -374.734858) (xy 335.407971 -374.679218)
			(xy 335.376825 -374.619417) (xy 335.353065 -374.556316) (xy 335.337033 -374.490823) (xy 335.328961 -374.423882)
			(xy 332.050892 -374.423882) (xy 332.04286 -374.490639) (xy 332.026892 -374.556019) (xy 332.003224 -374.619021)
			(xy 331.972196 -374.678744) (xy 331.934253 -374.73433) (xy 331.912468 -374.759982) (xy 331.90665 -374.767112)
			(xy 331.900149 -374.784314) (xy 331.899768 -374.79351) (xy 331.899768 -375.286778) (xy 331.900196 -375.295963)
			(xy 331.906698 -375.313147) (xy 331.912468 -375.320306) (xy 331.934285 -375.345934) (xy 331.972233 -375.401524)
			(xy 332.003264 -375.461251) (xy 332.026935 -375.524259) (xy 332.042906 -375.589644) (xy 332.050947 -375.656469)
			(xy 332.050945 -375.723776) (xy 332.042898 -375.790601) (xy 332.026922 -375.855985) (xy 332.003246 -375.91899)
			(xy 331.972209 -375.978715) (xy 331.934257 -376.034302) (xy 331.912468 -376.059954) (xy 331.906662 -376.067092)
			(xy 331.900154 -376.084288) (xy 331.899768 -376.093482) (xy 331.899768 -376.25147) (xy 331.899312 -376.261639)
			(xy 331.891538 -376.280432) (xy 331.877162 -376.294817) (xy 331.858375 -376.302604) (xy 331.848206 -376.303032)
			(xy 331.131926 -376.303032) (xy 331.121752 -376.302614) (xy 331.102953 -376.294832) (xy 331.088566 -376.280444)
			(xy 331.080785 -376.261644) (xy 331.080364 -376.25147) (xy 331.080364 -376.093482) (xy 331.079948 -376.084296)
			(xy 331.073437 -376.067112) (xy 331.067664 -376.059954) (xy 331.045905 -376.034278) (xy 331.007954 -375.978695)
			(xy 330.976918 -375.918975) (xy 330.953242 -375.855974) (xy 330.937266 -375.790594) (xy 330.92922 -375.723774)
			(xy 330.929217 -375.656471) (xy 330.937258 -375.58965) (xy 330.953229 -375.524269) (xy 330.976899 -375.461266)
			(xy 331.007931 -375.401543) (xy 331.045877 -375.345958) (xy 331.067664 -375.320306) (xy 331.073448 -375.313152)
			(xy 331.079969 -375.295968) (xy 331.080364 -375.286778) (xy 331.080364 -374.79351) (xy 331.079935 -374.784325)
			(xy 331.073433 -374.767141) (xy 331.067664 -374.759982) (xy 331.045834 -374.734364) (xy 331.007885 -374.678773)
			(xy 330.976852 -374.619045) (xy 330.95318 -374.556036) (xy 330.93721 -374.49065) (xy 330.929168 -374.423823)
			(xy 301.250868 -374.423823) (xy 301.250868 -374.423878) (xy 301.242797 -374.490814) (xy 301.226766 -374.5563)
			(xy 301.203008 -374.619395) (xy 301.171863 -374.67919) (xy 301.133781 -374.734824) (xy 301.11192 -374.76049)
			(xy 301.106105 -374.767622) (xy 301.099601 -374.784823) (xy 301.09922 -374.794018) (xy 301.09922 -375.28627)
			(xy 301.09964 -375.295456) (xy 301.106146 -375.312641) (xy 301.11192 -375.319798) (xy 301.133813 -375.345439)
			(xy 301.171899 -375.401078) (xy 301.203048 -375.460877) (xy 301.226809 -375.523977) (xy 301.242842 -375.589469)
			(xy 301.250915 -375.65641) (xy 301.250912 -375.723835) (xy 301.242834 -375.790775) (xy 301.226796 -375.856266)
			(xy 301.203029 -375.919364) (xy 301.171876 -375.979161) (xy 301.133785 -376.034796) (xy 301.11192 -376.060462)
			(xy 301.106117 -376.067603) (xy 301.099605 -376.084797) (xy 301.09922 -376.09399) (xy 301.09922 -376.25147)
			(xy 301.098748 -376.2616) (xy 301.091023 -376.280328) (xy 301.076731 -376.294687) (xy 301.058039 -376.3025)
			(xy 301.047912 -376.303032) (xy 300.331632 -376.303032) (xy 300.321484 -376.302553) (xy 300.302738 -376.294774)
			(xy 300.288415 -376.280395) (xy 300.280708 -376.26162) (xy 300.280324 -376.25147) (xy 300.280324 -376.09399)
			(xy 300.279913 -376.084803) (xy 300.2734 -376.067619) (xy 300.267624 -376.060462) (xy 300.245789 -376.034773)
			(xy 300.207697 -375.979142) (xy 300.176544 -375.91935) (xy 300.152777 -375.856256) (xy 300.136739 -375.790769)
			(xy 300.12866 -375.723833) (xy 300.128658 -375.656412) (xy 300.136731 -375.589475) (xy 300.152764 -375.523987)
			(xy 300.176526 -375.460892) (xy 300.207674 -375.401096) (xy 300.245761 -375.345463) (xy 300.267624 -375.319798)
			(xy 300.273407 -375.312643) (xy 300.279929 -375.29546) (xy 300.280324 -375.28627) (xy 300.280324 -374.794018)
			(xy 300.2799 -374.784832) (xy 300.273395 -374.767648) (xy 300.267624 -374.76049) (xy 300.245718 -374.734859)
			(xy 300.207629 -374.67922) (xy 300.176479 -374.61942) (xy 300.152716 -374.556318) (xy 300.136683 -374.490825)
			(xy 300.12861 -374.423882) (xy 296.851077 -374.423882) (xy 296.843006 -374.490813) (xy 296.826976 -374.556299)
			(xy 296.803218 -374.619394) (xy 296.772074 -374.67919) (xy 296.733992 -374.734824) (xy 296.712132 -374.76049)
			(xy 296.706306 -374.767614) (xy 296.699811 -374.784821) (xy 296.699432 -374.794018) (xy 296.699432 -375.28627)
			(xy 296.699872 -375.295454) (xy 296.706366 -375.312638) (xy 296.712132 -375.319798) (xy 296.734024 -375.345439)
			(xy 296.77211 -375.401078) (xy 296.803258 -375.460878) (xy 296.827019 -375.523978) (xy 296.843051 -375.589469)
			(xy 296.851124 -375.65641) (xy 296.851121 -375.723835) (xy 296.843043 -375.790775) (xy 296.827005 -375.856265)
			(xy 296.803239 -375.919363) (xy 296.772087 -375.979161) (xy 296.733997 -376.034796) (xy 296.712132 -376.060462)
			(xy 296.706318 -376.067595) (xy 296.699816 -376.084795) (xy 296.699432 -376.09399) (xy 296.699432 -376.25147)
			(xy 296.698948 -376.261598) (xy 296.691225 -376.280324) (xy 296.676937 -376.294683) (xy 296.65825 -376.302498)
			(xy 296.648124 -376.303032) (xy 295.931844 -376.303032) (xy 295.921697 -376.302543) (xy 295.902951 -376.294768)
			(xy 295.888628 -376.280392) (xy 295.880921 -376.261619) (xy 295.880536 -376.25147) (xy 295.880536 -376.09399)
			(xy 295.880123 -376.084803) (xy 295.87361 -376.067619) (xy 295.867836 -376.060462) (xy 295.846 -376.034773)
			(xy 295.807908 -375.979143) (xy 295.776754 -375.91935) (xy 295.752987 -375.856256) (xy 295.736948 -375.79077)
			(xy 295.728869 -375.723834) (xy 295.728867 -375.656412) (xy 295.73694 -375.589475) (xy 295.752973 -375.523987)
			(xy 295.776736 -375.460891) (xy 295.807885 -375.401096) (xy 295.845973 -375.345463) (xy 295.867836 -375.319798)
			(xy 295.873621 -375.312644) (xy 295.880142 -375.29546) (xy 295.880536 -375.28627) (xy 295.880536 -374.794018)
			(xy 295.880109 -374.784833) (xy 295.873606 -374.767649) (xy 295.867836 -374.76049) (xy 295.84593 -374.734859)
			(xy 295.80784 -374.679221) (xy 295.776689 -374.61942) (xy 295.752925 -374.556319) (xy 295.736892 -374.490825)
			(xy 295.728819 -374.423882) (xy 292.450774 -374.423882) (xy 292.442742 -374.490639) (xy 292.426773 -374.55602)
			(xy 292.403104 -374.619022) (xy 292.372075 -374.678745) (xy 292.33413 -374.73433) (xy 292.312344 -374.759982)
			(xy 292.306523 -374.76711) (xy 292.300025 -374.784314) (xy 292.299644 -374.79351) (xy 292.299644 -375.286778)
			(xy 292.300077 -375.295962) (xy 292.306576 -375.313146) (xy 292.312344 -375.320306) (xy 292.334162 -375.345934)
			(xy 292.372111 -375.401523) (xy 292.403144 -375.46125) (xy 292.426816 -375.524258) (xy 292.442787 -375.589643)
			(xy 292.450829 -375.656469) (xy 292.450826 -375.723776) (xy 292.442779 -375.790601) (xy 292.426802 -375.855985)
			(xy 292.403125 -375.918991) (xy 292.372088 -375.978716) (xy 292.334134 -376.034302) (xy 292.312344 -376.059954)
			(xy 292.306535 -376.06709) (xy 292.300029 -376.084288) (xy 292.299644 -376.093482) (xy 292.299644 -376.25147)
			(xy 292.299211 -376.261642) (xy 292.291433 -376.280439) (xy 292.277049 -376.294826) (xy 292.258254 -376.302609)
			(xy 292.248082 -376.303032) (xy 291.531802 -376.303032) (xy 291.521627 -376.302634) (xy 291.502826 -376.294844)
			(xy 291.48844 -376.28045) (xy 291.480661 -376.261645) (xy 291.48024 -376.25147) (xy 291.48024 -376.093482)
			(xy 291.47983 -376.084295) (xy 291.473315 -376.067111) (xy 291.46754 -376.059954) (xy 291.445782 -376.034277)
			(xy 291.407832 -375.978695) (xy 291.376798 -375.918974) (xy 291.353123 -375.855973) (xy 291.337148 -375.790594)
			(xy 291.329101 -375.723774) (xy 291.329099 -375.656471) (xy 291.33714 -375.589651) (xy 291.35311 -375.52427)
			(xy 291.376779 -375.461267) (xy 291.407809 -375.401544) (xy 291.445754 -375.345958) (xy 291.46754 -375.320306)
			(xy 291.473322 -375.31315) (xy 291.479844 -375.295968) (xy 291.48024 -375.286778) (xy 291.48024 -374.79351)
			(xy 291.479816 -374.784324) (xy 291.473311 -374.76714) (xy 291.46754 -374.759982) (xy 291.445711 -374.734364)
			(xy 291.407763 -374.678773) (xy 291.376732 -374.619044) (xy 291.353061 -374.556035) (xy 291.337091 -374.490649)
			(xy 291.32905 -374.423823) (xy 288.051014 -374.423823) (xy 288.051014 -374.423879) (xy 288.042941 -374.490816)
			(xy 288.026909 -374.556303) (xy 288.003147 -374.619398) (xy 287.971998 -374.679193) (xy 287.933911 -374.734826)
			(xy 287.912048 -374.76049) (xy 287.906224 -374.767616) (xy 287.899727 -374.784821) (xy 287.899348 -374.794018)
			(xy 287.899348 -375.28627) (xy 287.899784 -375.295454) (xy 287.906281 -375.312638) (xy 287.912048 -375.319798)
			(xy 287.933943 -375.345438) (xy 287.972035 -375.401075) (xy 288.003187 -375.460874) (xy 288.026952 -375.523974)
			(xy 288.042987 -375.589467) (xy 288.051061 -375.656409) (xy 288.051058 -375.723836) (xy 288.042978 -375.790777)
			(xy 288.026938 -375.856269) (xy 288.003168 -375.919367) (xy 287.972011 -375.979164) (xy 287.933916 -376.034798)
			(xy 287.912048 -376.060462) (xy 287.906236 -376.067596) (xy 287.899732 -376.084795) (xy 287.899348 -376.09399)
			(xy 287.899348 -376.25147) (xy 287.898849 -376.261596) (xy 287.891129 -376.280319) (xy 287.876846 -376.294677)
			(xy 287.858164 -376.302495) (xy 287.84804 -376.303032) (xy 287.13176 -376.303032) (xy 287.121653 -376.302548)
			(xy 287.10298 -376.294804) (xy 287.088687 -376.280507) (xy 287.080948 -376.261831) (xy 287.080452 -376.251724)
			(xy 287.080452 -376.09399) (xy 287.080035 -376.084804) (xy 287.073525 -376.06762) (xy 287.067752 -376.060462)
			(xy 287.045916 -376.034773) (xy 287.007823 -375.979143) (xy 286.976668 -375.919351) (xy 286.9529 -375.856257)
			(xy 286.93686 -375.79077) (xy 286.928781 -375.723834) (xy 286.928779 -375.656411) (xy 286.936852 -375.589474)
			(xy 286.952886 -375.523986) (xy 286.976649 -375.46089) (xy 287.007799 -375.401095) (xy 287.045888 -375.345462)
			(xy 287.067752 -375.319798) (xy 287.073538 -375.312646) (xy 287.080058 -375.29546) (xy 287.080452 -375.28627)
			(xy 287.080452 -374.794018) (xy 287.080022 -374.784833) (xy 287.073521 -374.767649) (xy 287.067752 -374.76049)
			(xy 287.045845 -374.73486) (xy 287.007754 -374.679221) (xy 286.976602 -374.619421) (xy 286.952838 -374.556319)
			(xy 286.936804 -374.490825) (xy 286.928731 -374.423882) (xy 266.501372 -374.423882) (xy 266.501372 -377.582176)
			(xy 266.500836 -377.607123) (xy 266.49303 -377.656404) (xy 266.477622 -377.70386) (xy 266.454989 -377.748327)
			(xy 266.425688 -377.788712) (xy 266.408408 -377.806712) (xy 265.993118 -378.222002) (xy 265.975119 -378.239288)
			(xy 265.934744 -378.268613) (xy 265.890279 -378.291261) (xy 265.842819 -378.306676) (xy 265.793532 -378.314478)
			(xy 265.768582 -378.314966) (xy 243.004086 -378.314966) (xy 242.979138 -378.314456) (xy 242.929856 -378.306644)
			(xy 242.882399 -378.291229) (xy 242.837933 -378.268591) (xy 242.797549 -378.239285) (xy 242.77955 -378.222002)
			(xy 242.203732 -377.646184) (xy 242.186435 -377.628195) (xy 242.157111 -377.587818) (xy 242.134464 -377.543351)
			(xy 242.119051 -377.495888) (xy 242.111253 -377.446599) (xy 242.110768 -377.421648) (xy 242.110768 -377.180602)
			(xy 242.11035 -377.170532) (xy 242.102625 -377.151933) (xy 242.095782 -377.144534) (xy 242.00104 -377.049792)
			(xy 241.993621 -377.042976) (xy 241.975036 -377.035243) (xy 241.964972 -377.034806) (xy 236.209586 -377.034806)
			(xy 236.184637 -377.034313) (xy 236.135353 -377.026499) (xy 236.087896 -377.011082) (xy 236.04343 -376.988439)
			(xy 236.003048 -376.959128) (xy 235.98505 -376.941842) (xy 235.566712 -376.523504) (xy 235.549421 -376.505509)
			(xy 235.520097 -376.465133) (xy 235.497449 -376.420668) (xy 235.482035 -376.373206) (xy 235.474235 -376.323919)
			(xy 235.473748 -376.298968) (xy 234.427522 -376.298968) (xy 237.245652 -379.117098) (xy 237.253075 -379.123909)
			(xy 237.271657 -379.131646) (xy 237.28172 -379.132084) (xy 239.621314 -379.132084) (xy 239.631385 -379.13167)
			(xy 239.649982 -379.123942) (xy 239.657382 -379.117098) (xy 240.207292 -378.567188) (xy 240.225285 -378.549895)
			(xy 240.265662 -378.520572) (xy 240.310128 -378.497925) (xy 240.357589 -378.482511) (xy 240.406877 -378.474711)
			(xy 240.431828 -378.474224) (xy 262.084058 -378.474224) (xy 262.109007 -378.474709) (xy 262.15829 -378.482528)
			(xy 262.205747 -378.497948) (xy 262.250212 -378.520592) (xy 262.290595 -378.549903) (xy 262.308594 -378.567188)
			(xy 262.508217 -378.766811) (xy 269.68983 -378.766811) (xy 269.68983 -378.633249) (xy 269.697894 -378.499931)
			(xy 269.713994 -378.367343) (xy 269.738069 -378.235969) (xy 269.770032 -378.106288) (xy 269.809767 -377.978774)
			(xy 269.857129 -377.853891) (xy 269.911944 -377.732096) (xy 269.974014 -377.613833) (xy 270.04311 -377.499534)
			(xy 270.118982 -377.389614) (xy 270.201352 -377.284477) (xy 270.28992 -377.184504) (xy 270.384362 -377.090062)
			(xy 270.484335 -377.001494) (xy 270.589472 -376.919124) (xy 270.699392 -376.843252) (xy 270.813691 -376.774156)
			(xy 270.931954 -376.712086) (xy 271.053749 -376.657271) (xy 271.178632 -376.609909) (xy 271.306146 -376.570174)
			(xy 271.435827 -376.538211) (xy 271.567201 -376.514136) (xy 271.699789 -376.498036) (xy 271.833107 -376.489972)
			(xy 271.966669 -376.489972) (xy 272.099987 -376.498036) (xy 272.232575 -376.514136) (xy 272.363949 -376.538211)
			(xy 272.49363 -376.570174) (xy 272.621144 -376.609909) (xy 272.746027 -376.657271) (xy 272.867822 -376.712086)
			(xy 272.986085 -376.774156) (xy 273.068299 -376.823856) (xy 289.128922 -376.823856) (xy 289.128922 -376.75655)
			(xy 289.136967 -376.689727) (xy 289.152941 -376.624344) (xy 289.176615 -376.56134) (xy 289.207651 -376.501617)
			(xy 289.245603 -376.446031) (xy 289.267392 -376.42038) (xy 289.273179 -376.413228) (xy 289.2797 -376.396043)
			(xy 289.280092 -376.386852) (xy 289.280092 -375.893584) (xy 289.279691 -375.884396) (xy 289.273171 -375.867212)
			(xy 289.267392 -375.860056) (xy 289.245634 -375.834379) (xy 289.207681 -375.778797) (xy 289.176643 -375.719078)
			(xy 289.152966 -375.656076) (xy 289.13699 -375.590696) (xy 289.128942 -375.523876) (xy 289.128939 -375.456572)
			(xy 289.136981 -375.389751) (xy 289.152952 -375.32437) (xy 289.176624 -375.261367) (xy 289.207656 -375.201644)
			(xy 289.245605 -375.146059) (xy 289.267392 -375.120408) (xy 289.273167 -375.113247) (xy 289.279695 -375.096069)
			(xy 289.280092 -375.08688) (xy 289.280092 -374.928638) (xy 289.280664 -374.918488) (xy 289.288417 -374.899729)
			(xy 289.302758 -374.885364) (xy 289.321505 -374.87758) (xy 289.331654 -374.877076) (xy 290.047934 -374.877076)
			(xy 290.058113 -374.877437) (xy 290.076915 -374.88524) (xy 290.0913 -374.899645) (xy 290.099077 -374.918459)
			(xy 290.099496 -374.928638) (xy 290.099496 -375.08688) (xy 290.099917 -375.096066) (xy 290.106423 -375.11325)
			(xy 290.112196 -375.120408) (xy 290.134014 -375.146035) (xy 290.17196 -375.201626) (xy 290.20299 -375.261353)
			(xy 290.226659 -375.324361) (xy 290.242629 -375.389746) (xy 290.25067 -375.456571) (xy 290.250667 -375.523878)
			(xy 290.24262 -375.590702) (xy 290.226645 -375.656085) (xy 290.20297 -375.719091) (xy 290.171935 -375.778816)
			(xy 290.133985 -375.834403) (xy 290.112196 -375.860056) (xy 290.106393 -375.867196) (xy 290.099882 -375.884391)
			(xy 290.099496 -375.893584) (xy 290.099496 -376.386852) (xy 290.09993 -376.396037) (xy 290.106427 -376.413221)
			(xy 290.112196 -376.42038) (xy 290.133987 -376.446029) (xy 290.171933 -376.501617) (xy 290.202964 -376.561341)
			(xy 290.226635 -376.624346) (xy 290.242607 -376.689728) (xy 290.25065 -376.756551) (xy 290.25065 -376.823855)
			(xy 290.250643 -376.823915) (xy 293.528715 -376.823915) (xy 293.528715 -376.756491) (xy 293.53679 -376.689554)
			(xy 293.552824 -376.624065) (xy 293.576588 -376.560968) (xy 293.607737 -376.501172) (xy 293.645825 -376.445537)
			(xy 293.667688 -376.419872) (xy 293.673478 -376.412722) (xy 293.679997 -376.395535) (xy 293.680388 -376.386344)
			(xy 293.680388 -375.894092) (xy 293.679984 -375.884904) (xy 293.673466 -375.86772) (xy 293.667688 -375.860564)
			(xy 293.645856 -375.834873) (xy 293.607767 -375.779242) (xy 293.576616 -375.719449) (xy 293.55285 -375.656355)
			(xy 293.536813 -375.59087) (xy 293.528735 -375.523934) (xy 293.528732 -375.456514) (xy 293.536804 -375.389578)
			(xy 293.552836 -375.324091) (xy 293.576596 -375.260995) (xy 293.607742 -375.2012) (xy 293.645826 -375.145565)
			(xy 293.667688 -375.1199) (xy 293.673466 -375.112741) (xy 293.679992 -375.095561) (xy 293.680388 -375.086372)
			(xy 293.680388 -374.928638) (xy 293.680956 -374.91852) (xy 293.688662 -374.89981) (xy 293.702923 -374.885454)
			(xy 293.721582 -374.877624) (xy 293.731696 -374.877076) (xy 294.447976 -374.877076) (xy 294.458094 -374.877535)
			(xy 294.476793 -374.885271) (xy 294.491107 -374.899574) (xy 294.498857 -374.918266) (xy 294.499284 -374.928384)
			(xy 294.499284 -375.086372) (xy 294.499711 -375.095557) (xy 294.506214 -375.112742) (xy 294.511984 -375.1199)
			(xy 294.53388 -375.145539) (xy 294.571969 -375.201177) (xy 294.603119 -375.260977) (xy 294.626882 -375.324077)
			(xy 294.642916 -375.389569) (xy 294.650989 -375.456511) (xy 294.650986 -375.523937) (xy 294.642907 -375.590878)
			(xy 294.626868 -375.656369) (xy 294.603099 -375.719467) (xy 294.571944 -375.779264) (xy 294.53385 -375.834899)
			(xy 294.511984 -375.860564) (xy 294.506176 -375.867701) (xy 294.499669 -375.884898) (xy 294.499284 -375.894092)
			(xy 294.499284 -376.386344) (xy 294.499677 -376.395533) (xy 294.506203 -376.412717) (xy 294.511984 -376.419872)
			(xy 294.533852 -376.445534) (xy 294.571942 -376.501168) (xy 294.603094 -376.560965) (xy 294.626858 -376.624062)
			(xy 294.642894 -376.689552) (xy 294.65097 -376.756491) (xy 294.650969 -376.823856) (xy 297.92901 -376.823856)
			(xy 297.92901 -376.75655) (xy 297.937054 -376.689727) (xy 297.953028 -376.624345) (xy 297.976702 -376.56134)
			(xy 298.007737 -376.501617) (xy 298.045687 -376.446032) (xy 298.067476 -376.42038) (xy 298.073261 -376.413226)
			(xy 298.079783 -376.396042) (xy 298.080176 -376.386852) (xy 298.080176 -375.893584) (xy 298.079779 -375.884395)
			(xy 298.073257 -375.867211) (xy 298.067476 -375.860056) (xy 298.045719 -375.834378) (xy 298.007766 -375.778797)
			(xy 297.97673 -375.719077) (xy 297.953054 -375.656076) (xy 297.937077 -375.590696) (xy 297.92903 -375.523876)
			(xy 297.929027 -375.456572) (xy 297.937069 -375.389751) (xy 297.953039 -375.324371) (xy 297.97671 -375.261367)
			(xy 298.007742 -375.201645) (xy 298.045689 -375.14606) (xy 298.067476 -375.120408) (xy 298.073249 -375.113246)
			(xy 298.079778 -375.096068) (xy 298.080176 -375.08688) (xy 298.080176 -374.928638) (xy 298.080596 -374.918464)
			(xy 298.088376 -374.899663) (xy 298.102763 -374.885276) (xy 298.121564 -374.877496) (xy 298.131738 -374.877076)
			(xy 298.848018 -374.877076) (xy 298.858195 -374.87745) (xy 298.876998 -374.885248) (xy 298.891383 -374.899649)
			(xy 298.899161 -374.91846) (xy 298.89958 -374.928638) (xy 298.89958 -375.08688) (xy 298.900004 -375.096066)
			(xy 298.906509 -375.11325) (xy 298.91228 -375.120408) (xy 298.934099 -375.146035) (xy 298.972045 -375.201625)
			(xy 299.003076 -375.261352) (xy 299.026746 -375.32436) (xy 299.042716 -375.389745) (xy 299.050758 -375.45657)
			(xy 299.050755 -375.523878) (xy 299.042708 -375.590702) (xy 299.026732 -375.656086) (xy 299.003056 -375.719092)
			(xy 298.972021 -375.778816) (xy 298.934069 -375.834404) (xy 298.91228 -375.860056) (xy 298.906475 -375.867195)
			(xy 298.899966 -375.88439) (xy 298.89958 -375.893584) (xy 298.89958 -376.386852) (xy 298.900018 -376.396036)
			(xy 298.906513 -376.413221) (xy 298.91228 -376.42038) (xy 298.934071 -376.446029) (xy 298.972019 -376.501616)
			(xy 299.003051 -376.561341) (xy 299.026722 -376.624345) (xy 299.042695 -376.689728) (xy 299.050731 -376.756492)
			(xy 302.328802 -376.756492) (xy 302.336877 -376.689554) (xy 302.352912 -376.624066) (xy 302.376674 -376.560969)
			(xy 302.407823 -376.501173) (xy 302.445909 -376.445538) (xy 302.467772 -376.419872) (xy 302.473572 -376.412729)
			(xy 302.480082 -376.395537) (xy 302.480472 -376.386344) (xy 302.480472 -375.894092) (xy 302.480072 -375.884904)
			(xy 302.473552 -375.867719) (xy 302.467772 -375.860564) (xy 302.44594 -375.834872) (xy 302.407853 -375.779241)
			(xy 302.376702 -375.719448) (xy 302.352937 -375.656355) (xy 302.336901 -375.590869) (xy 302.328823 -375.523934)
			(xy 302.32882 -375.456514) (xy 302.336892 -375.389578) (xy 302.352923 -375.324091) (xy 302.376682 -375.260996)
			(xy 302.407828 -375.2012) (xy 302.445911 -375.145566) (xy 302.467772 -375.1199) (xy 302.47356 -375.112749)
			(xy 302.480078 -375.095563) (xy 302.480472 -375.086372) (xy 302.480472 -374.928638) (xy 302.480959 -374.91851)
			(xy 302.48868 -374.899784) (xy 302.502967 -374.885425) (xy 302.521654 -374.87761) (xy 302.53178 -374.877076)
			(xy 303.24806 -374.877076) (xy 303.258209 -374.877554) (xy 303.276955 -374.885332) (xy 303.291279 -374.899711)
			(xy 303.298985 -374.918488) (xy 303.299368 -374.928638) (xy 303.299368 -375.086372) (xy 303.299799 -375.095557)
			(xy 303.306299 -375.112741) (xy 303.312068 -375.1199) (xy 303.333965 -375.145539) (xy 303.372054 -375.201176)
			(xy 303.403205 -375.260976) (xy 303.426969 -375.324076) (xy 303.443004 -375.389569) (xy 303.451077 -375.456511)
			(xy 303.451074 -375.523937) (xy 303.442995 -375.590878) (xy 303.426955 -375.65637) (xy 303.403186 -375.719468)
			(xy 303.37203 -375.779265) (xy 303.333935 -375.834899) (xy 303.312068 -375.860564) (xy 303.306258 -375.867699)
			(xy 303.299752 -375.884898) (xy 303.299368 -375.894092) (xy 303.299368 -376.386344) (xy 303.299764 -376.395533)
			(xy 303.306288 -376.412716) (xy 303.312068 -376.419872) (xy 303.333937 -376.445533) (xy 303.372028 -376.501168)
			(xy 303.40318 -376.560964) (xy 303.426945 -376.624062) (xy 303.442982 -376.689551) (xy 303.451058 -376.756491)
			(xy 303.451057 -376.823915) (xy 333.128833 -376.823915) (xy 333.128833 -376.756491) (xy 333.136908 -376.689553)
			(xy 333.152944 -376.624064) (xy 333.176708 -376.560967) (xy 333.207859 -376.501171) (xy 333.245948 -376.445537)
			(xy 333.267812 -376.419872) (xy 333.273604 -376.412724) (xy 333.280121 -376.395536) (xy 333.280512 -376.386344)
			(xy 333.280512 -375.894092) (xy 333.280103 -375.884905) (xy 333.273588 -375.86772) (xy 333.267812 -375.860564)
			(xy 333.245979 -375.834873) (xy 333.207889 -375.779242) (xy 333.176736 -375.71945) (xy 333.152969 -375.656356)
			(xy 333.136931 -375.59087) (xy 333.128853 -375.523935) (xy 333.12885 -375.456513) (xy 333.136923 -375.389577)
			(xy 333.152955 -375.32409) (xy 333.176716 -375.260994) (xy 333.207864 -375.201199) (xy 333.24595 -375.145565)
			(xy 333.267812 -375.1199) (xy 333.273592 -375.112743) (xy 333.280116 -375.095562) (xy 333.280512 -375.086372)
			(xy 333.280512 -374.928638) (xy 333.281057 -374.918517) (xy 333.288767 -374.899802) (xy 333.303035 -374.885446)
			(xy 333.321702 -374.87762) (xy 333.33182 -374.877076) (xy 334.0481 -374.877076) (xy 334.058251 -374.877521)
			(xy 334.076999 -374.885312) (xy 334.091321 -374.899701) (xy 334.099025 -374.918485) (xy 334.099408 -374.928638)
			(xy 334.099408 -375.086372) (xy 334.09983 -375.095558) (xy 334.106335 -375.112743) (xy 334.112108 -375.1199)
			(xy 334.134003 -375.145539) (xy 334.17209 -375.201178) (xy 334.203239 -375.260978) (xy 334.227001 -375.324078)
			(xy 334.243034 -375.38957) (xy 334.251107 -375.456511) (xy 334.251105 -375.523937) (xy 334.243026 -375.590877)
			(xy 334.226987 -375.656368) (xy 334.20322 -375.719466) (xy 334.172066 -375.779263) (xy 334.133974 -375.834899)
			(xy 334.112108 -375.860564) (xy 334.106303 -375.867703) (xy 334.099793 -375.884898) (xy 334.099408 -375.894092)
			(xy 334.099408 -376.386344) (xy 334.099795 -376.395534) (xy 334.106324 -376.412718) (xy 334.112108 -376.419872)
			(xy 334.133976 -376.445534) (xy 334.172064 -376.501169) (xy 334.203214 -376.560966) (xy 334.226977 -376.624063)
			(xy 334.243012 -376.689553) (xy 334.251088 -376.756491) (xy 334.251087 -376.823855) (xy 337.529152 -376.823855)
			(xy 337.529152 -376.756551) (xy 337.537195 -376.689729) (xy 337.553167 -376.624348) (xy 337.576837 -376.561344)
			(xy 337.607868 -376.50162) (xy 337.645814 -376.446033) (xy 337.6676 -376.42038) (xy 337.673388 -376.413228)
			(xy 337.679908 -376.396043) (xy 337.6803 -376.386852) (xy 337.6803 -375.893584) (xy 337.679897 -375.884396)
			(xy 337.673378 -375.867212) (xy 337.6676 -375.860056) (xy 337.645845 -375.834377) (xy 337.607898 -375.778794)
			(xy 337.576865 -375.719074) (xy 337.553192 -375.656073) (xy 337.537218 -375.590694) (xy 337.529172 -375.523875)
			(xy 337.529169 -375.456573) (xy 337.53721 -375.389753) (xy 337.553178 -375.324373) (xy 337.576846 -375.26137)
			(xy 337.607873 -375.201647) (xy 337.645815 -375.146061) (xy 337.6676 -375.120408) (xy 337.673376 -375.113248)
			(xy 337.679903 -375.096069) (xy 337.6803 -375.08688) (xy 337.6803 -374.928638) (xy 337.680864 -374.918487)
			(xy 337.688619 -374.899726) (xy 337.702963 -374.885361) (xy 337.721712 -374.877579) (xy 337.731862 -374.877076)
			(xy 338.448142 -374.877076) (xy 338.458307 -374.8775) (xy 338.477085 -374.885295) (xy 338.49145 -374.899683)
			(xy 338.499216 -374.918472) (xy 338.499704 -374.928638) (xy 338.499704 -375.08688) (xy 338.500123 -375.096066)
			(xy 338.50663 -375.113251) (xy 338.512404 -375.120408) (xy 338.534222 -375.146035) (xy 338.572167 -375.201626)
			(xy 338.603196 -375.261353) (xy 338.626865 -375.324361) (xy 338.642835 -375.389746) (xy 338.650876 -375.456571)
			(xy 338.650873 -375.523877) (xy 338.642826 -375.590701) (xy 338.626851 -375.656085) (xy 338.603177 -375.719091)
			(xy 338.572142 -375.778815) (xy 338.534192 -375.834403) (xy 338.512404 -375.860056) (xy 338.506602 -375.867197)
			(xy 338.50009 -375.884391) (xy 338.499704 -375.893584) (xy 338.499704 -376.386852) (xy 338.500136 -376.396037)
			(xy 338.506634 -376.413222) (xy 338.512404 -376.42038) (xy 338.534194 -376.44603) (xy 338.57214 -376.501617)
			(xy 338.603171 -376.561342) (xy 338.626842 -376.624346) (xy 338.642813 -376.689729) (xy 338.650856 -376.756551)
			(xy 338.650856 -376.823855) (xy 338.650849 -376.823915) (xy 341.928921 -376.823915) (xy 341.928921 -376.756491)
			(xy 341.936996 -376.689553) (xy 341.953031 -376.624065) (xy 341.976794 -376.560968) (xy 342.007944 -376.501172)
			(xy 342.046032 -376.445537) (xy 342.067896 -376.419872) (xy 342.073686 -376.412722) (xy 342.080205 -376.395535)
			(xy 342.080596 -376.386344) (xy 342.080596 -375.894092) (xy 342.08019 -375.884904) (xy 342.073674 -375.86772)
			(xy 342.067896 -375.860564) (xy 342.046064 -375.834873) (xy 342.007974 -375.779242) (xy 341.976822 -375.719449)
			(xy 341.953057 -375.656356) (xy 341.937019 -375.59087) (xy 341.928941 -375.523935) (xy 341.928938 -375.456513)
			(xy 341.93701 -375.389577) (xy 341.953042 -375.32409) (xy 341.976803 -375.260995) (xy 342.007949 -375.201199)
			(xy 342.046034 -375.145565) (xy 342.067896 -375.1199) (xy 342.073675 -375.112742) (xy 342.0802 -375.095561)
			(xy 342.080596 -375.086372) (xy 342.080596 -374.928638) (xy 342.081157 -374.918519) (xy 342.088864 -374.899807)
			(xy 342.103127 -374.885451) (xy 342.121789 -374.877623) (xy 342.131904 -374.877076) (xy 342.848184 -374.877076)
			(xy 342.858334 -374.877534) (xy 342.877082 -374.88532) (xy 342.891405 -374.899705) (xy 342.899109 -374.918486)
			(xy 342.899492 -374.928638) (xy 342.899492 -375.086372) (xy 342.899917 -375.095558) (xy 342.906421 -375.112742)
			(xy 342.912192 -375.1199) (xy 342.934088 -375.145539) (xy 342.972176 -375.201177) (xy 343.003326 -375.260977)
			(xy 343.027088 -375.324077) (xy 343.043122 -375.38957) (xy 343.051195 -375.456511) (xy 343.051193 -375.523937)
			(xy 343.043113 -375.590878) (xy 343.027074 -375.656369) (xy 343.003306 -375.719467) (xy 342.972151 -375.779264)
			(xy 342.934058 -375.834899) (xy 342.912192 -375.860564) (xy 342.906385 -375.867702) (xy 342.899877 -375.884898)
			(xy 342.899492 -375.894092) (xy 342.899492 -376.386344) (xy 342.899883 -376.395533) (xy 342.90641 -376.412717)
			(xy 342.912192 -376.419872) (xy 342.93406 -376.445534) (xy 342.972149 -376.501169) (xy 343.0033 -376.560965)
			(xy 343.027065 -376.624063) (xy 343.0431 -376.689552) (xy 343.051176 -376.756491) (xy 343.051175 -376.823856)
			(xy 346.329216 -376.823856) (xy 346.329216 -376.75655) (xy 346.33726 -376.689727) (xy 346.353234 -376.624345)
			(xy 346.376909 -376.56134) (xy 346.407944 -376.501617) (xy 346.445895 -376.446032) (xy 346.467684 -376.42038)
			(xy 346.47347 -376.413227) (xy 346.479991 -376.396043) (xy 346.480384 -376.386852) (xy 346.480384 -375.893584)
			(xy 346.479985 -375.884396) (xy 346.473464 -375.867211) (xy 346.467684 -375.860056) (xy 346.445926 -375.834379)
			(xy 346.407974 -375.778797) (xy 346.376937 -375.719077) (xy 346.35326 -375.656076) (xy 346.337283 -375.590696)
			(xy 346.329236 -375.523876) (xy 346.329233 -375.456572) (xy 346.337275 -375.389751) (xy 346.353246 -375.32437)
			(xy 346.376917 -375.261367) (xy 346.407949 -375.201645) (xy 346.445897 -375.14606) (xy 346.467684 -375.120408)
			(xy 346.473458 -375.113247) (xy 346.479987 -375.096069) (xy 346.480384 -375.08688) (xy 346.480384 -374.928638)
			(xy 346.480796 -374.918463) (xy 346.488577 -374.899661) (xy 346.502967 -374.885273) (xy 346.521771 -374.877495)
			(xy 346.531946 -374.877076) (xy 347.248226 -374.877076) (xy 347.258404 -374.877443) (xy 347.277207 -374.885244)
			(xy 347.291592 -374.899647) (xy 347.299369 -374.918459) (xy 347.299788 -374.928638) (xy 347.299788 -375.08688)
			(xy 347.300211 -375.096066) (xy 347.306716 -375.11325) (xy 347.312488 -375.120408) (xy 347.334306 -375.146035)
			(xy 347.372252 -375.201625) (xy 347.403283 -375.261353) (xy 347.426953 -375.324361) (xy 347.442923 -375.389746)
			(xy 347.450964 -375.456571) (xy 347.450961 -375.523878) (xy 347.442914 -375.590702) (xy 347.426938 -375.656086)
			(xy 347.403263 -375.719091) (xy 347.372228 -375.778816) (xy 347.334277 -375.834403) (xy 347.312488 -375.860056)
			(xy 347.306684 -375.867196) (xy 347.300174 -375.88439) (xy 347.299788 -375.893584) (xy 347.299788 -376.386852)
			(xy 347.300224 -376.396036) (xy 347.30672 -376.413221) (xy 347.312488 -376.42038) (xy 347.334279 -376.446029)
			(xy 347.372226 -376.501617) (xy 347.403257 -376.561341) (xy 347.426929 -376.624346) (xy 347.442901 -376.689728)
			(xy 347.450944 -376.756551) (xy 347.450944 -376.823855) (xy 347.450937 -376.823915) (xy 377.128742 -376.823915)
			(xy 377.128742 -376.756491) (xy 377.136817 -376.689553) (xy 377.152853 -376.624064) (xy 377.176618 -376.560967)
			(xy 377.20777 -376.501171) (xy 377.245859 -376.445537) (xy 377.267724 -376.419872) (xy 377.273518 -376.412725)
			(xy 377.280033 -376.395536) (xy 377.280424 -376.386344) (xy 377.280424 -375.894092) (xy 377.280012 -375.884905)
			(xy 377.273499 -375.867721) (xy 377.267724 -375.860564) (xy 377.245891 -375.834873) (xy 377.207799 -375.779243)
			(xy 377.176646 -375.71945) (xy 377.152879 -375.656357) (xy 377.136841 -375.590871) (xy 377.128762 -375.523935)
			(xy 377.128759 -375.456513) (xy 377.136832 -375.389577) (xy 377.152865 -375.324089) (xy 377.176626 -375.260993)
			(xy 377.207775 -375.201198) (xy 377.245861 -375.145565) (xy 377.267724 -375.1199) (xy 377.273506 -375.112744)
			(xy 377.280029 -375.095562) (xy 377.280424 -375.086372) (xy 377.280424 -374.928638) (xy 377.280957 -374.918516)
			(xy 377.28867 -374.899799) (xy 377.302942 -374.885442) (xy 377.321613 -374.877618) (xy 377.331732 -374.877076)
			(xy 378.048012 -374.877076) (xy 378.058164 -374.877511) (xy 378.076912 -374.885306) (xy 378.091234 -374.899698)
			(xy 378.098938 -374.918484) (xy 378.09932 -374.928638) (xy 378.09932 -375.086372) (xy 378.099739 -375.095558)
			(xy 378.106246 -375.112743) (xy 378.11202 -375.1199) (xy 378.133915 -375.14554) (xy 378.172001 -375.201178)
			(xy 378.203149 -375.260978) (xy 378.226911 -375.324078) (xy 378.242943 -375.38957) (xy 378.251016 -375.456511)
			(xy 378.251014 -375.523937) (xy 378.242935 -375.590877) (xy 378.226897 -375.656368) (xy 378.20313 -375.719466)
			(xy 378.171976 -375.779263) (xy 378.133885 -375.834898) (xy 378.11202 -375.860564) (xy 378.106216 -375.867704)
			(xy 378.099705 -375.884898) (xy 378.09932 -375.894092) (xy 378.09932 -376.386344) (xy 378.099704 -376.395534)
			(xy 378.106235 -376.412718) (xy 378.11202 -376.419872) (xy 378.133887 -376.445534) (xy 378.171974 -376.50117)
			(xy 378.203124 -376.560967) (xy 378.226887 -376.624064) (xy 378.242922 -376.689553) (xy 378.250997 -376.756491)
			(xy 378.250997 -376.756551) (xy 381.529061 -376.756551) (xy 381.537105 -376.689729) (xy 381.553076 -376.624347)
			(xy 381.576747 -376.561343) (xy 381.607779 -376.501619) (xy 381.645725 -376.446032) (xy 381.667512 -376.42038)
			(xy 381.673301 -376.413229) (xy 381.67982 -376.396043) (xy 381.680212 -376.386852) (xy 381.680212 -375.893584)
			(xy 381.679807 -375.884396) (xy 381.67329 -375.867212) (xy 381.667512 -375.860056) (xy 381.645756 -375.834378)
			(xy 381.607808 -375.778794) (xy 381.576775 -375.719074) (xy 381.553102 -375.656073) (xy 381.537127 -375.590694)
			(xy 381.529081 -375.523875) (xy 381.529078 -375.456573) (xy 381.537119 -375.389753) (xy 381.553088 -375.324373)
			(xy 381.576756 -375.26137) (xy 381.607784 -375.201647) (xy 381.645727 -375.14606) (xy 381.667512 -375.120408)
			(xy 381.673289 -375.113249) (xy 381.679815 -375.096069) (xy 381.680212 -375.08688) (xy 381.680212 -374.928638)
			(xy 381.680694 -374.918472) (xy 381.688462 -374.899683) (xy 381.702829 -374.885298) (xy 381.721609 -374.877507)
			(xy 381.731774 -374.877076) (xy 382.448054 -374.877076) (xy 382.458227 -374.877502) (xy 382.477028 -374.885279)
			(xy 382.491416 -374.899665) (xy 382.499196 -374.918465) (xy 382.499616 -374.928638) (xy 382.499616 -375.08688)
			(xy 382.500032 -375.096067) (xy 382.506541 -375.113251) (xy 382.512316 -375.120408) (xy 382.534136 -375.146034)
			(xy 382.572087 -375.201623) (xy 382.603122 -375.26135) (xy 382.626795 -375.324358) (xy 382.642767 -375.389744)
			(xy 382.650809 -375.45657) (xy 382.650806 -375.523878) (xy 382.642758 -375.590704) (xy 382.62678 -375.656088)
			(xy 382.603102 -375.719094) (xy 382.572063 -375.778818) (xy 382.534107 -375.834404) (xy 382.512316 -375.860056)
			(xy 382.506515 -375.867198) (xy 382.500002 -375.884391) (xy 382.499616 -375.893584) (xy 382.499616 -376.386852)
			(xy 382.500045 -376.396037) (xy 382.506545 -376.413222) (xy 382.512316 -376.42038) (xy 382.534109 -376.446028)
			(xy 382.572061 -376.501614) (xy 382.603096 -376.561338) (xy 382.626771 -376.624343) (xy 382.642745 -376.689726)
			(xy 382.650789 -376.75655) (xy 382.650789 -376.823856) (xy 382.650782 -376.823915) (xy 385.92883 -376.823915)
			(xy 385.92883 -376.756491) (xy 385.936905 -376.689553) (xy 385.95294 -376.624064) (xy 385.976705 -376.560967)
			(xy 386.007855 -376.501171) (xy 386.045944 -376.445537) (xy 386.067808 -376.419872) (xy 386.0736 -376.412724)
			(xy 386.080117 -376.395535) (xy 386.080508 -376.386344) (xy 386.080508 -375.894092) (xy 386.0801 -375.884905)
			(xy 386.073584 -375.867721) (xy 386.067808 -375.860564) (xy 386.045975 -375.834873) (xy 386.007885 -375.779242)
			(xy 385.976732 -375.71945) (xy 385.952966 -375.656356) (xy 385.936928 -375.59087) (xy 385.92885 -375.523935)
			(xy 385.928847 -375.456513) (xy 385.93692 -375.389577) (xy 385.952952 -375.32409) (xy 385.976713 -375.260994)
			(xy 386.00786 -375.201199) (xy 386.045946 -375.145565) (xy 386.067808 -375.1199) (xy 386.073588 -375.112743)
			(xy 386.080112 -375.095562) (xy 386.080508 -375.086372) (xy 386.080508 -374.928638) (xy 386.081057 -374.918518)
			(xy 386.088766 -374.899804) (xy 386.103033 -374.885447) (xy 386.121699 -374.877621) (xy 386.131816 -374.877076)
			(xy 386.848096 -374.877076) (xy 386.858247 -374.877524) (xy 386.876995 -374.885314) (xy 386.891317 -374.899702)
			(xy 386.899021 -374.918485) (xy 386.899404 -374.928638) (xy 386.899404 -375.086372) (xy 386.899827 -375.095558)
			(xy 386.906332 -375.112742) (xy 386.912104 -375.1199) (xy 386.933999 -375.145539) (xy 386.972087 -375.201178)
			(xy 387.003236 -375.260978) (xy 387.026998 -375.324078) (xy 387.043031 -375.38957) (xy 387.051104 -375.456511)
			(xy 387.051102 -375.523937) (xy 387.043023 -375.590877) (xy 387.026984 -375.656368) (xy 387.003216 -375.719466)
			(xy 386.972062 -375.779264) (xy 386.93397 -375.834899) (xy 386.912104 -375.860564) (xy 386.906298 -375.867703)
			(xy 386.899789 -375.884898) (xy 386.899404 -375.894092) (xy 386.899404 -376.386344) (xy 386.899792 -376.395534)
			(xy 386.906321 -376.412718) (xy 386.912104 -376.419872) (xy 386.933972 -376.445534) (xy 386.97206 -376.501169)
			(xy 387.00321 -376.560966) (xy 387.026974 -376.624063) (xy 387.043009 -376.689552) (xy 387.051085 -376.756491)
			(xy 387.051084 -376.823855) (xy 390.329149 -376.823855) (xy 390.329149 -376.756551) (xy 390.337192 -376.689729)
			(xy 390.353163 -376.624348) (xy 390.376834 -376.561344) (xy 390.407864 -376.50162) (xy 390.44581 -376.446033)
			(xy 390.467596 -376.42038) (xy 390.473383 -376.413228) (xy 390.479904 -376.396043) (xy 390.480296 -376.386852)
			(xy 390.480296 -375.893584) (xy 390.479894 -375.884396) (xy 390.473375 -375.867212) (xy 390.467596 -375.860056)
			(xy 390.445841 -375.834377) (xy 390.407894 -375.778794) (xy 390.376862 -375.719073) (xy 390.353189 -375.656072)
			(xy 390.337215 -375.590694) (xy 390.329169 -375.523875) (xy 390.329166 -375.456573) (xy 390.337207 -375.389754)
			(xy 390.353175 -375.324374) (xy 390.376842 -375.261371) (xy 390.407869 -375.201648) (xy 390.445812 -375.146061)
			(xy 390.467596 -375.120408) (xy 390.473371 -375.113248) (xy 390.479899 -375.096069) (xy 390.480296 -375.08688)
			(xy 390.480296 -374.928638) (xy 390.480864 -374.918488) (xy 390.488618 -374.899728) (xy 390.502961 -374.885363)
			(xy 390.521709 -374.877579) (xy 390.531858 -374.877076) (xy 391.248138 -374.877076) (xy 391.258303 -374.877503)
			(xy 391.27708 -374.885297) (xy 391.291445 -374.899684) (xy 391.299212 -374.918472) (xy 391.2997 -374.928638)
			(xy 391.2997 -375.08688) (xy 391.30012 -375.096066) (xy 391.306627 -375.113251) (xy 391.3124 -375.120408)
			(xy 391.334218 -375.146035) (xy 391.372163 -375.201626) (xy 391.403193 -375.261353) (xy 391.426862 -375.324361)
			(xy 391.442832 -375.389746) (xy 391.450873 -375.456571) (xy 391.45087 -375.523877) (xy 391.442823 -375.590702)
			(xy 391.426848 -375.656085) (xy 391.403173 -375.719091) (xy 391.372139 -375.778816) (xy 391.334188 -375.834403)
			(xy 391.3124 -375.860056) (xy 391.306597 -375.867197) (xy 391.300086 -375.884391) (xy 391.2997 -375.893584)
			(xy 391.2997 -376.386852) (xy 391.300133 -376.396037) (xy 391.306631 -376.413221) (xy 391.3124 -376.42038)
			(xy 391.33419 -376.446029) (xy 391.372137 -376.501617) (xy 391.403168 -376.561342) (xy 391.426838 -376.624346)
			(xy 391.44281 -376.689728) (xy 391.450853 -376.756551) (xy 391.450853 -376.823855) (xy 391.450846 -376.823915)
			(xy 421.128651 -376.823915) (xy 421.128651 -376.756491) (xy 421.136727 -376.689552) (xy 421.152763 -376.624063)
			(xy 421.176528 -376.560966) (xy 421.20768 -376.50117) (xy 421.245771 -376.445537) (xy 421.267636 -376.419872)
			(xy 421.273432 -376.412726) (xy 421.279946 -376.395536) (xy 421.280336 -376.386344) (xy 421.280336 -375.894092)
			(xy 421.279922 -375.884905) (xy 421.27341 -375.867721) (xy 421.267636 -375.860564) (xy 421.245802 -375.834873)
			(xy 421.20771 -375.779243) (xy 421.176556 -375.719451) (xy 421.152788 -375.656357) (xy 421.13675 -375.590871)
			(xy 421.128671 -375.523935) (xy 421.128668 -375.456513) (xy 421.136741 -375.389576) (xy 421.152774 -375.324089)
			(xy 421.176536 -375.260993) (xy 421.207685 -375.201198) (xy 421.245773 -375.145565) (xy 421.267636 -375.1199)
			(xy 421.27342 -375.112746) (xy 421.279941 -375.095562) (xy 421.280336 -375.086372) (xy 421.280336 -374.928638)
			(xy 421.280858 -374.918514) (xy 421.288572 -374.899795) (xy 421.302848 -374.885437) (xy 421.321523 -374.877616)
			(xy 421.331644 -374.877076) (xy 422.047924 -374.877076) (xy 422.058031 -374.877565) (xy 422.076706 -374.885306)
			(xy 422.090999 -374.899601) (xy 422.098737 -374.918277) (xy 422.099232 -374.928384) (xy 422.099232 -375.086372)
			(xy 422.099671 -375.095556) (xy 422.106166 -375.11274) (xy 422.111932 -375.1199) (xy 422.133826 -375.14554)
			(xy 422.171912 -375.201179) (xy 422.203059 -375.260979) (xy 422.22682 -375.324079) (xy 422.242853 -375.389571)
			(xy 422.250926 -375.456511) (xy 422.250923 -375.523937) (xy 422.242844 -375.590877) (xy 422.226806 -375.656367)
			(xy 422.20304 -375.719465) (xy 422.171887 -375.779263) (xy 422.133797 -375.834898) (xy 422.111932 -375.860564)
			(xy 422.106117 -375.867696) (xy 422.099615 -375.884897) (xy 422.099232 -375.894092) (xy 422.099232 -376.386344)
			(xy 422.099636 -376.395532) (xy 422.106156 -376.412715) (xy 422.111932 -376.419872) (xy 422.133799 -376.445535)
			(xy 422.171885 -376.50117) (xy 422.203034 -376.560967) (xy 422.226797 -376.624064) (xy 422.242831 -376.689553)
			(xy 422.250906 -376.756491) (xy 422.250906 -376.756551) (xy 425.52897 -376.756551) (xy 425.537014 -376.689729)
			(xy 425.552986 -376.624347) (xy 425.576658 -376.561343) (xy 425.607689 -376.501619) (xy 425.645637 -376.446032)
			(xy 425.667424 -376.42038) (xy 425.673214 -376.413231) (xy 425.679732 -376.396043) (xy 425.680124 -376.386852)
			(xy 425.680124 -375.893584) (xy 425.679716 -375.884397) (xy 425.6732 -375.867213) (xy 425.667424 -375.860056)
			(xy 425.645668 -375.834378) (xy 425.60772 -375.778795) (xy 425.576686 -375.719074) (xy 425.553012 -375.656073)
			(xy 425.537037 -375.590695) (xy 425.528991 -375.523875) (xy 425.528988 -375.456573) (xy 425.537029 -375.389753)
			(xy 425.552998 -375.324373) (xy 425.576666 -375.26137) (xy 425.607695 -375.201647) (xy 425.645639 -375.146061)
			(xy 425.667424 -375.120408) (xy 425.673202 -375.11325) (xy 425.679727 -375.096069) (xy 425.680124 -375.08688)
			(xy 425.680124 -374.928638) (xy 425.680595 -374.918471) (xy 425.688365 -374.899679) (xy 425.702736 -374.885294)
			(xy 425.721519 -374.877505) (xy 425.731686 -374.877076) (xy 426.447966 -374.877076) (xy 426.45814 -374.877493)
			(xy 426.476941 -374.885274) (xy 426.491329 -374.899662) (xy 426.499108 -374.918464) (xy 426.499528 -374.928638)
			(xy 426.499528 -375.08688) (xy 426.499941 -375.096067) (xy 426.506452 -375.113252) (xy 426.512228 -375.120408)
			(xy 426.534048 -375.146034) (xy 426.571998 -375.201623) (xy 426.603032 -375.26135) (xy 426.626705 -375.324358)
			(xy 426.642676 -375.389744) (xy 426.650718 -375.45657) (xy 426.650716 -375.523878) (xy 426.642668 -375.590704)
			(xy 426.62669 -375.656088) (xy 426.603013 -375.719094) (xy 426.571974 -375.778818) (xy 426.534019 -375.834404)
			(xy 426.512228 -375.860056) (xy 426.506416 -375.86719) (xy 426.499913 -375.884389) (xy 426.499528 -375.893584)
			(xy 426.499528 -376.386852) (xy 426.499955 -376.396037) (xy 426.506456 -376.413222) (xy 426.512228 -376.42038)
			(xy 426.534021 -376.446029) (xy 426.571971 -376.501615) (xy 426.603006 -376.561338) (xy 426.62668 -376.624344)
			(xy 426.642654 -376.689727) (xy 426.650698 -376.75655) (xy 426.650698 -376.823856) (xy 426.650691 -376.823915)
			(xy 429.928739 -376.823915) (xy 429.928739 -376.756491) (xy 429.936814 -376.689553) (xy 429.95285 -376.624064)
			(xy 429.976615 -376.560967) (xy 430.007766 -376.501171) (xy 430.045856 -376.445537) (xy 430.06772 -376.419872)
			(xy 430.073513 -376.412725) (xy 430.080029 -376.395536) (xy 430.08042 -376.386344) (xy 430.08042 -375.894092)
			(xy 430.080009 -375.884905) (xy 430.073496 -375.867721) (xy 430.06772 -375.860564) (xy 430.045887 -375.834873)
			(xy 430.007796 -375.779243) (xy 429.976643 -375.71945) (xy 429.952876 -375.656357) (xy 429.936837 -375.590871)
			(xy 429.928759 -375.523935) (xy 429.928756 -375.456513) (xy 429.936829 -375.389577) (xy 429.952861 -375.324089)
			(xy 429.976623 -375.260994) (xy 430.007771 -375.201199) (xy 430.045857 -375.145565) (xy 430.06772 -375.1199)
			(xy 430.073501 -375.112744) (xy 430.080024 -375.095562) (xy 430.08042 -375.086372) (xy 430.08042 -374.928638)
			(xy 430.080957 -374.918516) (xy 430.088669 -374.8998) (xy 430.10294 -374.885443) (xy 430.121609 -374.877619)
			(xy 430.131728 -374.877076) (xy 430.848008 -374.877076) (xy 430.85816 -374.877515) (xy 430.876907 -374.885308)
			(xy 430.89123 -374.899699) (xy 430.898933 -374.918484) (xy 430.899316 -374.928638) (xy 430.899316 -375.086372)
			(xy 430.899736 -375.095558) (xy 430.906242 -375.112743) (xy 430.912016 -375.1199) (xy 430.933911 -375.14554)
			(xy 430.971998 -375.201178) (xy 431.003146 -375.260978) (xy 431.026908 -375.324078) (xy 431.04294 -375.38957)
			(xy 431.051013 -375.456511) (xy 431.051011 -375.523937) (xy 431.042932 -375.590877) (xy 431.026893 -375.656368)
			(xy 431.003126 -375.719466) (xy 430.971973 -375.779263) (xy 430.933881 -375.834898) (xy 430.912016 -375.860564)
			(xy 430.906212 -375.867704) (xy 430.899701 -375.884898) (xy 430.899316 -375.894092) (xy 430.899316 -376.386344)
			(xy 430.899701 -376.395534) (xy 430.906232 -376.412718) (xy 430.912016 -376.419872) (xy 430.933883 -376.445534)
			(xy 430.971971 -376.50117) (xy 431.003121 -376.560966) (xy 431.026884 -376.624064) (xy 431.042918 -376.689553)
			(xy 431.050994 -376.756491) (xy 431.050994 -376.756551) (xy 434.329058 -376.756551) (xy 434.337101 -376.689729)
			(xy 434.353073 -376.624348) (xy 434.376744 -376.561343) (xy 434.407775 -376.50162) (xy 434.445721 -376.446033)
			(xy 434.467508 -376.42038) (xy 434.473296 -376.413229) (xy 434.479816 -376.396043) (xy 434.480208 -376.386852)
			(xy 434.480208 -375.893584) (xy 434.479804 -375.884396) (xy 434.473286 -375.867212) (xy 434.467508 -375.860056)
			(xy 434.445753 -375.834378) (xy 434.407805 -375.778794) (xy 434.376772 -375.719074) (xy 434.353099 -375.656073)
			(xy 434.337124 -375.590694) (xy 434.329078 -375.523875) (xy 434.329075 -375.456573) (xy 434.337116 -375.389753)
			(xy 434.353084 -375.324373) (xy 434.376752 -375.26137) (xy 434.40778 -375.201647) (xy 434.445723 -375.146061)
			(xy 434.467508 -375.120408) (xy 434.473285 -375.113249) (xy 434.479811 -375.096069) (xy 434.480208 -375.08688)
			(xy 434.480208 -374.928638) (xy 434.480694 -374.918473) (xy 434.488461 -374.899684) (xy 434.502827 -374.885299)
			(xy 434.521605 -374.877508) (xy 434.53177 -374.877076) (xy 435.24805 -374.877076) (xy 435.258223 -374.877506)
			(xy 435.277024 -374.885281) (xy 435.291412 -374.899666) (xy 435.299192 -374.918465) (xy 435.299612 -374.928638)
			(xy 435.299612 -375.08688) (xy 435.300029 -375.096067) (xy 435.306538 -375.113251) (xy 435.312312 -375.120408)
			(xy 435.334133 -375.146034) (xy 435.372084 -375.201623) (xy 435.403118 -375.26135) (xy 435.426791 -375.324358)
			(xy 435.442764 -375.389744) (xy 435.450806 -375.45657) (xy 435.450803 -375.523878) (xy 435.442755 -375.590704)
			(xy 435.426777 -375.656088) (xy 435.403099 -375.719094) (xy 435.372059 -375.778819) (xy 435.334103 -375.834404)
			(xy 435.312312 -375.860056) (xy 435.306511 -375.867198) (xy 435.299998 -375.884391) (xy 435.299612 -375.893584)
			(xy 435.299612 -376.386852) (xy 435.300042 -376.396037) (xy 435.306542 -376.413222) (xy 435.312312 -376.42038)
			(xy 435.334105 -376.446028) (xy 435.372057 -376.501614) (xy 435.403093 -376.561338) (xy 435.426768 -376.624343)
			(xy 435.442742 -376.689726) (xy 435.450786 -376.75655) (xy 435.450786 -376.823856) (xy 435.442741 -376.89068)
			(xy 435.426766 -376.956063) (xy 435.40309 -377.019068) (xy 435.372054 -377.078791) (xy 435.334101 -377.134376)
			(xy 435.312312 -377.160028) (xy 435.306522 -377.167178) (xy 435.300003 -377.184365) (xy 435.299612 -377.193556)
			(xy 435.299612 -377.35129) (xy 435.299227 -377.361467) (xy 435.291436 -377.380271) (xy 435.277038 -377.394658)
			(xy 435.258228 -377.402435) (xy 435.24805 -377.402852) (xy 434.53177 -377.402852) (xy 434.521609 -377.402391)
			(xy 434.502837 -377.394605) (xy 434.488473 -377.380229) (xy 434.480701 -377.361451) (xy 434.480208 -377.35129)
			(xy 434.480208 -377.193556) (xy 434.479817 -377.184367) (xy 434.47329 -377.167183) (xy 434.467508 -377.160028)
			(xy 434.445725 -377.134372) (xy 434.407778 -377.078786) (xy 434.376746 -377.019062) (xy 434.353075 -376.956058)
			(xy 434.337103 -376.890677) (xy 434.329059 -376.823855) (xy 434.329058 -376.756551) (xy 431.050994 -376.756551)
			(xy 431.050993 -376.823915) (xy 431.042917 -376.890853) (xy 431.026882 -376.956342) (xy 431.003118 -377.019439)
			(xy 430.971968 -377.079236) (xy 430.93388 -377.13487) (xy 430.912016 -377.160536) (xy 430.906223 -377.167684)
			(xy 430.899706 -377.184872) (xy 430.899316 -377.194064) (xy 430.899316 -377.35129) (xy 430.898864 -377.361421)
			(xy 430.891131 -377.380151) (xy 430.876834 -377.394509) (xy 430.858137 -377.402321) (xy 430.848008 -377.402852)
			(xy 430.131728 -377.402852) (xy 430.121582 -377.402357) (xy 430.10284 -377.39458) (xy 430.088518 -377.380207)
			(xy 430.080808 -377.361437) (xy 430.08042 -377.35129) (xy 430.08042 -377.194064) (xy 430.080023 -377.184876)
			(xy 430.0735 -377.167692) (xy 430.06772 -377.160536) (xy 430.045859 -377.134868) (xy 430.007769 -377.079234)
			(xy 429.976617 -377.019439) (xy 429.952852 -376.956342) (xy 429.936815 -376.890853) (xy 429.928739 -376.823915)
			(xy 426.650691 -376.823915) (xy 426.642653 -376.890679) (xy 426.626679 -376.956062) (xy 426.603004 -377.019067)
			(xy 426.571968 -377.07879) (xy 426.534017 -377.134376) (xy 426.512228 -377.160028) (xy 426.506428 -377.167171)
			(xy 426.499918 -377.184363) (xy 426.499528 -377.193556) (xy 426.499528 -377.35129) (xy 426.499127 -377.361465)
			(xy 426.491339 -377.380266) (xy 426.476946 -377.394653) (xy 426.458141 -377.402432) (xy 426.447966 -377.402852)
			(xy 425.731686 -377.402852) (xy 425.721526 -377.402378) (xy 425.702755 -377.394597) (xy 425.68839 -377.380225)
			(xy 425.680618 -377.36145) (xy 425.680124 -377.35129) (xy 425.680124 -377.193556) (xy 425.67973 -377.184367)
			(xy 425.673204 -377.167183) (xy 425.667424 -377.160028) (xy 425.645641 -377.134372) (xy 425.607693 -377.078786)
			(xy 425.57666 -377.019063) (xy 425.552988 -376.956059) (xy 425.537015 -376.890677) (xy 425.528971 -376.823855)
			(xy 425.52897 -376.756551) (xy 422.250906 -376.756551) (xy 422.250905 -376.823915) (xy 422.24283 -376.890853)
			(xy 422.226795 -376.956342) (xy 422.203032 -377.019438) (xy 422.171882 -377.079235) (xy 422.133795 -377.13487)
			(xy 422.111932 -377.160536) (xy 422.106129 -377.167677) (xy 422.09962 -377.184871) (xy 422.099232 -377.194064)
			(xy 422.099232 -377.35129) (xy 422.098764 -377.36142) (xy 422.091035 -377.380146) (xy 422.076742 -377.394503)
			(xy 422.058051 -377.402318) (xy 422.047924 -377.402852) (xy 421.331644 -377.402852) (xy 421.321544 -377.40228)
			(xy 421.302877 -377.394567) (xy 421.288583 -377.380297) (xy 421.280837 -377.361643) (xy 421.280336 -377.351544)
			(xy 421.280336 -377.194064) (xy 421.279935 -377.184876) (xy 421.273414 -377.167692) (xy 421.267636 -377.160536)
			(xy 421.245775 -377.134868) (xy 421.207684 -377.079235) (xy 421.176531 -377.019439) (xy 421.152765 -376.956343)
			(xy 421.136728 -376.890854) (xy 421.128651 -376.823915) (xy 391.450846 -376.823915) (xy 391.442809 -376.890678)
			(xy 391.426837 -376.956059) (xy 391.403165 -377.019064) (xy 391.372134 -377.078788) (xy 391.334187 -377.134375)
			(xy 391.3124 -377.160028) (xy 391.306609 -377.167177) (xy 391.300091 -377.184365) (xy 391.2997 -377.193556)
			(xy 391.2997 -377.35129) (xy 391.299159 -377.361442) (xy 391.291395 -377.380204) (xy 391.277044 -377.394568)
			(xy 391.25829 -377.40235) (xy 391.248138 -377.402852) (xy 390.531858 -377.402852) (xy 390.521696 -377.402401)
			(xy 390.502924 -377.394611) (xy 390.48856 -377.380232) (xy 390.480789 -377.361452) (xy 390.480296 -377.35129)
			(xy 390.480296 -377.193556) (xy 390.479908 -377.184366) (xy 390.473379 -377.167182) (xy 390.467596 -377.160028)
			(xy 390.445814 -377.134372) (xy 390.407867 -377.078785) (xy 390.376836 -377.019062) (xy 390.353165 -376.956058)
			(xy 390.337193 -376.890676) (xy 390.329149 -376.823855) (xy 387.051084 -376.823855) (xy 387.051084 -376.823915)
			(xy 387.043008 -376.890853) (xy 387.026972 -376.956343) (xy 387.003208 -377.01944) (xy 386.972057 -377.079236)
			(xy 386.933968 -377.134871) (xy 386.912104 -377.160536) (xy 386.90631 -377.167683) (xy 386.899794 -377.184872)
			(xy 386.899404 -377.194064) (xy 386.899404 -377.35129) (xy 386.898867 -377.361411) (xy 386.89115 -377.380123)
			(xy 386.87688 -377.394478) (xy 386.858214 -377.402306) (xy 386.848096 -377.402852) (xy 386.131816 -377.402852)
			(xy 386.121669 -377.402366) (xy 386.102927 -377.394586) (xy 386.088605 -377.380209) (xy 386.080896 -377.361438)
			(xy 386.080508 -377.35129) (xy 386.080508 -377.194064) (xy 386.080114 -377.184875) (xy 386.073589 -377.167691)
			(xy 386.067808 -377.160536) (xy 386.045948 -377.134868) (xy 386.007858 -377.079234) (xy 385.976707 -377.019438)
			(xy 385.952942 -376.956342) (xy 385.936906 -376.890853) (xy 385.92883 -376.823915) (xy 382.650782 -376.823915)
			(xy 382.642744 -376.89068) (xy 382.626769 -376.956063) (xy 382.603094 -377.019068) (xy 382.572058 -377.078791)
			(xy 382.534105 -377.134376) (xy 382.512316 -377.160028) (xy 382.506527 -377.167179) (xy 382.500007 -377.184365)
			(xy 382.499616 -377.193556) (xy 382.499616 -377.35129) (xy 382.499227 -377.361467) (xy 382.491437 -377.38027)
			(xy 382.47704 -377.394657) (xy 382.458231 -377.402434) (xy 382.448054 -377.402852) (xy 381.731774 -377.402852)
			(xy 381.721613 -377.402388) (xy 381.702842 -377.394603) (xy 381.688477 -377.380228) (xy 381.680705 -377.361451)
			(xy 381.680212 -377.35129) (xy 381.680212 -377.193556) (xy 381.67982 -377.184367) (xy 381.673294 -377.167183)
			(xy 381.667512 -377.160028) (xy 381.645729 -377.134372) (xy 381.607782 -377.078786) (xy 381.57675 -377.019062)
			(xy 381.553078 -376.956058) (xy 381.537106 -376.890677) (xy 381.529062 -376.823855) (xy 381.529061 -376.756551)
			(xy 378.250997 -376.756551) (xy 378.250996 -376.823915) (xy 378.24292 -376.890853) (xy 378.226885 -376.956342)
			(xy 378.203121 -377.019439) (xy 378.171971 -377.079235) (xy 378.133884 -377.13487) (xy 378.11202 -377.160536)
			(xy 378.106228 -377.167685) (xy 378.09971 -377.184872) (xy 378.09932 -377.194064) (xy 378.09932 -377.35129)
			(xy 378.098864 -377.361421) (xy 378.091132 -377.38015) (xy 378.076836 -377.394508) (xy 378.058141 -377.40232)
			(xy 378.048012 -377.402852) (xy 377.331732 -377.402852) (xy 377.321586 -377.402353) (xy 377.302845 -377.394578)
			(xy 377.288522 -377.380206) (xy 377.280812 -377.361437) (xy 377.280424 -377.35129) (xy 377.280424 -377.194064)
			(xy 377.280026 -377.184876) (xy 377.273503 -377.167692) (xy 377.267724 -377.160536) (xy 377.245863 -377.134868)
			(xy 377.207773 -377.079234) (xy 377.17662 -377.019439) (xy 377.152855 -376.956342) (xy 377.136819 -376.890853)
			(xy 377.128742 -376.823915) (xy 347.450937 -376.823915) (xy 347.4429 -376.890678) (xy 347.426927 -376.95606)
			(xy 347.403255 -377.019065) (xy 347.372223 -377.078788) (xy 347.334275 -377.134376) (xy 347.312488 -377.160028)
			(xy 347.306696 -377.167176) (xy 347.300179 -377.184364) (xy 347.299788 -377.193556) (xy 347.299788 -377.35129)
			(xy 347.299259 -377.361444) (xy 347.291493 -377.380208) (xy 347.277138 -377.394573) (xy 347.25838 -377.402352)
			(xy 347.248226 -377.402852) (xy 346.531946 -377.402852) (xy 346.521776 -377.402398) (xy 346.502981 -377.394627)
			(xy 346.488594 -377.38025) (xy 346.480809 -377.36146) (xy 346.480384 -377.35129) (xy 346.480384 -377.193556)
			(xy 346.479999 -377.184366) (xy 346.473468 -377.167182) (xy 346.467684 -377.160028) (xy 346.445899 -377.134373)
			(xy 346.407947 -377.078788) (xy 346.376911 -377.019065) (xy 346.353236 -376.956061) (xy 346.337262 -376.890679)
			(xy 346.329216 -376.823856) (xy 343.051175 -376.823856) (xy 343.051175 -376.823915) (xy 343.043099 -376.890854)
			(xy 343.027063 -376.956343) (xy 343.003298 -377.01944) (xy 342.972146 -377.079236) (xy 342.934056 -377.134871)
			(xy 342.912192 -377.160536) (xy 342.906397 -377.167682) (xy 342.899882 -377.184872) (xy 342.899492 -377.194064)
			(xy 342.899492 -377.35129) (xy 342.898966 -377.361412) (xy 342.891248 -377.380127) (xy 342.876974 -377.394483)
			(xy 342.858303 -377.402308) (xy 342.848184 -377.402852) (xy 342.131904 -377.402852) (xy 342.121757 -377.402376)
			(xy 342.103014 -377.394592) (xy 342.088693 -377.380212) (xy 342.080984 -377.361439) (xy 342.080596 -377.35129)
			(xy 342.080596 -377.194064) (xy 342.080204 -377.184875) (xy 342.073678 -377.167691) (xy 342.067896 -377.160536)
			(xy 342.046036 -377.134867) (xy 342.007948 -377.079233) (xy 341.976797 -377.019438) (xy 341.953033 -376.956341)
			(xy 341.936997 -376.890852) (xy 341.928921 -376.823915) (xy 338.650849 -376.823915) (xy 338.642812 -376.890677)
			(xy 338.62684 -376.956059) (xy 338.603168 -377.019064) (xy 338.572137 -377.078788) (xy 338.534191 -377.134375)
			(xy 338.512404 -377.160028) (xy 338.506614 -377.167178) (xy 338.500095 -377.184365) (xy 338.499704 -377.193556)
			(xy 338.499704 -377.35129) (xy 338.49916 -377.361442) (xy 338.491396 -377.380203) (xy 338.477047 -377.394567)
			(xy 338.458293 -377.402349) (xy 338.448142 -377.402852) (xy 337.731862 -377.402852) (xy 337.721701 -377.402397)
			(xy 337.702929 -377.394609) (xy 337.688564 -377.380231) (xy 337.680793 -377.361452) (xy 337.6803 -377.35129)
			(xy 337.6803 -377.193556) (xy 337.679911 -377.184367) (xy 337.673383 -377.167182) (xy 337.6676 -377.160028)
			(xy 337.645817 -377.134372) (xy 337.607871 -377.078785) (xy 337.57684 -377.019062) (xy 337.553168 -376.956058)
			(xy 337.537196 -376.890677) (xy 337.529152 -376.823855) (xy 334.251087 -376.823855) (xy 334.251087 -376.823915)
			(xy 334.243011 -376.890853) (xy 334.226976 -376.956342) (xy 334.203211 -377.019439) (xy 334.172061 -377.079236)
			(xy 334.133972 -377.134871) (xy 334.112108 -377.160536) (xy 334.106315 -377.167684) (xy 334.099798 -377.184872)
			(xy 334.099408 -377.194064) (xy 334.099408 -377.35129) (xy 334.098867 -377.36141) (xy 334.091151 -377.380122)
			(xy 334.076882 -377.394477) (xy 334.058217 -377.402305) (xy 334.0481 -377.402852) (xy 333.33182 -377.402852)
			(xy 333.321674 -377.402363) (xy 333.302932 -377.394584) (xy 333.288609 -377.380209) (xy 333.2809 -377.361438)
			(xy 333.280512 -377.35129) (xy 333.280512 -377.194064) (xy 333.280117 -377.184875) (xy 333.273592 -377.167691)
			(xy 333.267812 -377.160536) (xy 333.245952 -377.134868) (xy 333.207862 -377.079234) (xy 333.17671 -377.019438)
			(xy 333.152945 -376.956342) (xy 333.136909 -376.890853) (xy 333.128833 -376.823915) (xy 303.451057 -376.823915)
			(xy 303.44298 -376.890854) (xy 303.426944 -376.956344) (xy 303.403178 -377.019441) (xy 303.372025 -377.079237)
			(xy 303.333933 -377.134871) (xy 303.312068 -377.160536) (xy 303.30627 -377.16768) (xy 303.299757 -377.184871)
			(xy 303.299368 -377.194064) (xy 303.299368 -377.35129) (xy 303.298865 -377.361415) (xy 303.291142 -377.380135)
			(xy 303.276861 -377.394491) (xy 303.258182 -377.402312) (xy 303.24806 -377.402852) (xy 302.53178 -377.402852)
			(xy 302.521631 -377.402396) (xy 302.502888 -377.394604) (xy 302.488567 -377.380218) (xy 302.480859 -377.361441)
			(xy 302.480472 -377.35129) (xy 302.480472 -377.194064) (xy 302.480085 -377.184874) (xy 302.473556 -377.16769)
			(xy 302.467772 -377.160536) (xy 302.445913 -377.134867) (xy 302.407826 -377.079232) (xy 302.376677 -377.019436)
			(xy 302.352913 -376.95634) (xy 302.336879 -376.890852) (xy 302.328803 -376.823914) (xy 302.328802 -376.756492)
			(xy 299.050731 -376.756492) (xy 299.050738 -376.756551) (xy 299.050738 -376.823856) (xy 299.042693 -376.890678)
			(xy 299.026721 -376.95606) (xy 299.003048 -377.019065) (xy 298.972016 -377.078789) (xy 298.934067 -377.134376)
			(xy 298.91228 -377.160028) (xy 298.906487 -377.167175) (xy 298.899971 -377.184364) (xy 298.89958 -377.193556)
			(xy 298.89958 -377.35129) (xy 298.899059 -377.361445) (xy 298.891291 -377.38021) (xy 298.876934 -377.394575)
			(xy 298.858173 -377.402353) (xy 298.848018 -377.402852) (xy 298.131738 -377.402852) (xy 298.121568 -377.402405)
			(xy 298.102772 -377.39463) (xy 298.088385 -377.380252) (xy 298.080601 -377.36146) (xy 298.080176 -377.35129)
			(xy 298.080176 -377.193556) (xy 298.079792 -377.184366) (xy 298.073261 -377.167182) (xy 298.067476 -377.160028)
			(xy 298.045691 -377.134373) (xy 298.00774 -377.078788) (xy 297.976704 -377.019065) (xy 297.95303 -376.956061)
			(xy 297.937055 -376.890679) (xy 297.92901 -376.823856) (xy 294.650969 -376.823856) (xy 294.650969 -376.823915)
			(xy 294.642893 -376.890854) (xy 294.626856 -376.956343) (xy 294.603091 -377.019441) (xy 294.571939 -377.079237)
			(xy 294.533849 -377.134871) (xy 294.511984 -377.160536) (xy 294.506188 -377.167681) (xy 294.499673 -377.184872)
			(xy 294.499284 -377.194064) (xy 294.499284 -377.35129) (xy 294.498766 -377.361413) (xy 294.491046 -377.38013)
			(xy 294.47677 -377.394485) (xy 294.458096 -377.402309) (xy 294.447976 -377.402852) (xy 293.731696 -377.402852)
			(xy 293.721593 -377.402319) (xy 293.702925 -377.39459) (xy 293.688632 -377.380308) (xy 293.680889 -377.361646)
			(xy 293.680388 -377.351544) (xy 293.680388 -377.194064) (xy 293.679998 -377.184875) (xy 293.673471 -377.16769)
			(xy 293.667688 -377.160536) (xy 293.645828 -377.134867) (xy 293.60774 -377.079233) (xy 293.57659 -377.019437)
			(xy 293.552826 -376.956341) (xy 293.536791 -376.890852) (xy 293.528715 -376.823915) (xy 290.250643 -376.823915)
			(xy 290.242606 -376.890678) (xy 290.226633 -376.95606) (xy 290.202962 -377.019064) (xy 290.17193 -377.078788)
			(xy 290.133983 -377.134375) (xy 290.112196 -377.160028) (xy 290.106405 -377.167177) (xy 290.099887 -377.184365)
			(xy 290.099496 -377.193556) (xy 290.099496 -377.35129) (xy 290.098959 -377.361443) (xy 290.091194 -377.380205)
			(xy 290.076842 -377.39457) (xy 290.058087 -377.402351) (xy 290.047934 -377.402852) (xy 289.331654 -377.402852)
			(xy 289.321492 -377.402404) (xy 289.30272 -377.394613) (xy 289.288356 -377.380233) (xy 289.280585 -377.361452)
			(xy 289.280092 -377.35129) (xy 289.280092 -377.193556) (xy 289.279705 -377.184366) (xy 289.273176 -377.167182)
			(xy 289.267392 -377.160028) (xy 289.245607 -377.134373) (xy 289.207654 -377.078788) (xy 289.176618 -377.019066)
			(xy 289.152942 -376.956061) (xy 289.136968 -376.890679) (xy 289.128922 -376.823856) (xy 273.068299 -376.823856)
			(xy 273.100384 -376.843252) (xy 273.210304 -376.919124) (xy 273.315441 -377.001494) (xy 273.415414 -377.090062)
			(xy 273.509856 -377.184504) (xy 273.598424 -377.284477) (xy 273.680794 -377.389614) (xy 273.756666 -377.499534)
			(xy 273.825762 -377.613833) (xy 273.887832 -377.732096) (xy 273.942647 -377.853891) (xy 273.990009 -377.978774)
			(xy 274.029744 -378.106288) (xy 274.061707 -378.235969) (xy 274.077801 -378.323794) (xy 286.928742 -378.323794)
			(xy 286.928744 -378.256367) (xy 286.936824 -378.189426) (xy 286.952863 -378.123935) (xy 286.976633 -378.060837)
			(xy 287.007789 -378.00104) (xy 287.045885 -377.945406) (xy 287.067752 -377.919742) (xy 287.073562 -377.912607)
			(xy 287.080067 -377.895408) (xy 287.080452 -377.886214) (xy 287.080452 -377.728734) (xy 287.080955 -377.718608)
			(xy 287.088674 -377.699885) (xy 287.102955 -377.685528) (xy 287.121637 -377.677709) (xy 287.13176 -377.677172)
			(xy 287.84804 -377.677172) (xy 287.858148 -377.677652) (xy 287.876822 -377.685397) (xy 287.891114 -377.699695)
			(xy 287.898852 -377.718372) (xy 287.899348 -377.72848) (xy 287.899348 -377.886214) (xy 287.899763 -377.8954)
			(xy 287.906275 -377.912584) (xy 287.912048 -377.919742) (xy 287.933888 -377.945427) (xy 287.971981 -378.001058)
			(xy 288.003136 -378.060851) (xy 288.026904 -378.123945) (xy 288.042943 -378.189432) (xy 288.051021 -378.256369)
			(xy 288.051024 -378.323734) (xy 291.329062 -378.323734) (xy 291.329064 -378.256427) (xy 291.337111 -378.189602)
			(xy 291.353086 -378.124219) (xy 291.376762 -378.061213) (xy 291.407799 -378.001489) (xy 291.445751 -377.945902)
			(xy 291.46754 -377.92025) (xy 291.473345 -377.913111) (xy 291.479854 -377.895916) (xy 291.48024 -377.886722)
			(xy 291.48024 -377.728734) (xy 291.480692 -377.718564) (xy 291.488466 -377.69977) (xy 291.502843 -377.685384)
			(xy 291.521633 -377.677598) (xy 291.531802 -377.677172) (xy 292.248082 -377.677172) (xy 292.258257 -377.677579)
			(xy 292.277058 -377.685365) (xy 292.291444 -377.699756) (xy 292.299224 -377.718559) (xy 292.299644 -377.728734)
			(xy 292.299644 -377.886722) (xy 292.300056 -377.895909) (xy 292.30657 -377.913092) (xy 292.312344 -377.92025)
			(xy 292.334107 -377.945923) (xy 292.372057 -378.001506) (xy 292.403093 -378.061227) (xy 292.426768 -378.124228)
			(xy 292.442743 -378.189608) (xy 292.450789 -378.256429) (xy 292.450792 -378.323732) (xy 292.450785 -378.323794)
			(xy 295.72883 -378.323794) (xy 295.728832 -378.256367) (xy 295.736911 -378.189427) (xy 295.752951 -378.123936)
			(xy 295.776719 -378.060837) (xy 295.807875 -378.001041) (xy 295.845969 -377.945407) (xy 295.867836 -377.919742)
			(xy 295.873644 -377.912605) (xy 295.880151 -377.895408) (xy 295.880536 -377.886214) (xy 295.880536 -377.728734)
			(xy 295.881055 -377.71861) (xy 295.88877 -377.69989) (xy 295.903047 -377.685533) (xy 295.921723 -377.677712)
			(xy 295.931844 -377.677172) (xy 296.648124 -377.677172) (xy 296.658276 -377.677601) (xy 296.677024 -377.6854)
			(xy 296.691345 -377.699793) (xy 296.699049 -377.71858) (xy 296.699432 -377.728734) (xy 296.699432 -377.886214)
			(xy 296.699851 -377.8954) (xy 296.70636 -377.912584) (xy 296.712132 -377.919742) (xy 296.733969 -377.945429)
			(xy 296.772057 -378.001061) (xy 296.803207 -378.060855) (xy 296.826971 -378.123949) (xy 296.843007 -378.189435)
			(xy 296.851085 -378.25637) (xy 296.851087 -378.323791) (xy 296.851087 -378.323794) (xy 300.128621 -378.323794)
			(xy 300.128623 -378.256367) (xy 300.136702 -378.189427) (xy 300.152741 -378.123936) (xy 300.176509 -378.060838)
			(xy 300.207664 -378.001041) (xy 300.245758 -377.945407) (xy 300.267624 -377.919742) (xy 300.27343 -377.912604)
			(xy 300.279938 -377.895408) (xy 300.280324 -377.886214) (xy 300.280324 -377.728734) (xy 300.280854 -377.718611)
			(xy 300.288568 -377.699894) (xy 300.302841 -377.685537) (xy 300.321512 -377.677714) (xy 300.331632 -377.677172)
			(xy 301.047912 -377.677172) (xy 301.058063 -377.677611) (xy 301.076811 -377.685405) (xy 301.091133 -377.699796)
			(xy 301.098837 -377.718581) (xy 301.09922 -377.728734) (xy 301.09922 -377.886214) (xy 301.099619 -377.895402)
			(xy 301.10614 -377.912587) (xy 301.11192 -377.919742) (xy 301.133758 -377.945429) (xy 301.171846 -378.001061)
			(xy 301.202997 -378.060854) (xy 301.226761 -378.123948) (xy 301.242798 -378.189434) (xy 301.250876 -378.25637)
			(xy 301.250878 -378.323734) (xy 330.92918 -378.323734) (xy 330.929182 -378.256427) (xy 330.937229 -378.189602)
			(xy 330.953206 -378.124218) (xy 330.976882 -378.061212) (xy 331.00792 -378.001488) (xy 331.045874 -377.945902)
			(xy 331.067664 -377.92025) (xy 331.073472 -377.913113) (xy 331.079978 -377.895916) (xy 331.080364 -377.886722)
			(xy 331.080364 -377.728734) (xy 331.080792 -377.718561) (xy 331.088571 -377.699763) (xy 331.102956 -377.685376)
			(xy 331.121753 -377.677594) (xy 331.131926 -377.677172) (xy 331.848206 -377.677172) (xy 331.858382 -377.67756)
			(xy 331.877184 -377.685353) (xy 331.891569 -377.69975) (xy 331.899348 -377.718557) (xy 331.899768 -377.728734)
			(xy 331.899768 -377.886722) (xy 331.900175 -377.895909) (xy 331.906692 -377.913093) (xy 331.912468 -377.92025)
			(xy 331.93423 -377.945923) (xy 331.972179 -378.001507) (xy 332.003213 -378.061228) (xy 332.026887 -378.124229)
			(xy 332.042861 -378.189609) (xy 332.050907 -378.256429) (xy 332.05091 -378.323732) (xy 332.050903 -378.323793)
			(xy 335.328973 -378.323793) (xy 335.328975 -378.256368) (xy 335.337053 -378.189429) (xy 335.35309 -378.123939)
			(xy 335.376855 -378.060841) (xy 335.408007 -378.001044) (xy 335.446096 -377.945408) (xy 335.46796 -377.919742)
			(xy 335.473771 -377.912607) (xy 335.480275 -377.895409) (xy 335.48066 -377.886214) (xy 335.48066 -377.728734)
			(xy 335.481155 -377.718607) (xy 335.488875 -377.699883) (xy 335.50316 -377.685525) (xy 335.521844 -377.677708)
			(xy 335.531968 -377.677172) (xy 336.248248 -377.677172) (xy 336.258402 -377.677582) (xy 336.27715 -377.685388)
			(xy 336.29147 -377.699787) (xy 336.299173 -377.718578) (xy 336.299556 -377.728734) (xy 336.299556 -377.886214)
			(xy 336.299969 -377.895401) (xy 336.306482 -377.912585) (xy 336.312256 -377.919742) (xy 336.334096 -377.945428)
			(xy 336.372188 -378.001058) (xy 336.403343 -378.060851) (xy 336.42711 -378.123945) (xy 336.443149 -378.189433)
			(xy 336.451227 -378.256369) (xy 336.45123 -378.323734) (xy 339.729268 -378.323734) (xy 339.72927 -378.256427)
			(xy 339.737317 -378.189602) (xy 339.753293 -378.124218) (xy 339.776969 -378.061213) (xy 339.808006 -378.001489)
			(xy 339.845958 -377.945902) (xy 339.867748 -377.92025) (xy 339.873554 -377.913112) (xy 339.880062 -377.895916)
			(xy 339.880448 -377.886722) (xy 339.880448 -377.728734) (xy 339.880892 -377.718563) (xy 339.888668 -377.699768)
			(xy 339.903047 -377.685381) (xy 339.92184 -377.677597) (xy 339.93201 -377.677172) (xy 340.64829 -377.677172)
			(xy 340.658465 -377.677573) (xy 340.677266 -377.685361) (xy 340.691653 -377.699754) (xy 340.699432 -377.718559)
			(xy 340.699852 -377.728734) (xy 340.699852 -377.886722) (xy 340.700262 -377.895909) (xy 340.706777 -377.913093)
			(xy 340.712552 -377.92025) (xy 340.734314 -377.945923) (xy 340.772264 -378.001506) (xy 340.803299 -378.061227)
			(xy 340.826974 -378.124229) (xy 340.842949 -378.189608) (xy 340.850995 -378.256429) (xy 340.850998 -378.323732)
			(xy 340.850998 -378.323734) (xy 344.129059 -378.323734) (xy 344.129061 -378.256427) (xy 344.137108 -378.189603)
			(xy 344.153083 -378.124219) (xy 344.176759 -378.061213) (xy 344.207795 -378.001489) (xy 344.245747 -377.945902)
			(xy 344.267536 -377.92025) (xy 344.273341 -377.913111) (xy 344.27985 -377.895916) (xy 344.280236 -377.886722)
			(xy 344.280236 -377.728734) (xy 344.280692 -377.718565) (xy 344.288465 -377.699771) (xy 344.302841 -377.685385)
			(xy 344.321629 -377.677599) (xy 344.331798 -377.677172) (xy 345.048078 -377.677172) (xy 345.058252 -377.677583)
			(xy 345.077053 -377.685367) (xy 345.09144 -377.699757) (xy 345.099219 -377.71856) (xy 345.09964 -377.728734)
			(xy 345.09964 -377.886722) (xy 345.100053 -377.895909) (xy 345.106566 -377.913092) (xy 345.11234 -377.92025)
			(xy 345.134103 -377.945923) (xy 345.172054 -378.001506) (xy 345.203089 -378.061226) (xy 345.226764 -378.124228)
			(xy 345.24274 -378.189608) (xy 345.250786 -378.256429) (xy 345.250789 -378.323732) (xy 345.250789 -378.323734)
			(xy 374.929089 -378.323734) (xy 374.929092 -378.256427) (xy 374.937139 -378.189602) (xy 374.953116 -378.124218)
			(xy 374.976793 -378.061212) (xy 375.007831 -378.001488) (xy 375.045786 -377.945902) (xy 375.067576 -377.92025)
			(xy 375.073374 -377.913105) (xy 375.079888 -377.895915) (xy 375.080276 -377.886722) (xy 375.080276 -377.728734)
			(xy 375.080693 -377.71856) (xy 375.088474 -377.699759) (xy 375.102862 -377.685371) (xy 375.121664 -377.677592)
			(xy 375.131838 -377.677172) (xy 375.848118 -377.677172) (xy 375.858295 -377.67755) (xy 375.877097 -377.685347)
			(xy 375.891482 -377.699747) (xy 375.89926 -377.718557) (xy 375.89968 -377.728734) (xy 375.89968 -377.886722)
			(xy 375.900084 -377.89591) (xy 375.906602 -377.913094) (xy 375.91238 -377.92025) (xy 375.934142 -377.945923)
			(xy 375.97209 -378.001507) (xy 376.003123 -378.061228) (xy 376.026797 -378.12423) (xy 376.042771 -378.189609)
			(xy 376.050817 -378.256429) (xy 376.050819 -378.323732) (xy 376.050812 -378.323793) (xy 379.328882 -378.323793)
			(xy 379.328884 -378.256368) (xy 379.336962 -378.189428) (xy 379.352999 -378.123938) (xy 379.376765 -378.06084)
			(xy 379.407917 -378.001043) (xy 379.446007 -377.945408) (xy 379.467872 -377.919742) (xy 379.473684 -377.912608)
			(xy 379.480188 -377.895409) (xy 379.480572 -377.886214) (xy 379.480572 -377.728734) (xy 379.481056 -377.718606)
			(xy 379.488778 -377.699879) (xy 379.503066 -377.685521) (xy 379.521754 -377.677706) (xy 379.53188 -377.677172)
			(xy 380.24816 -377.677172) (xy 380.258308 -377.677654) (xy 380.277054 -377.685431) (xy 380.291378 -377.699809)
			(xy 380.299084 -377.718584) (xy 380.299468 -377.728734) (xy 380.299468 -377.886214) (xy 380.299878 -377.895401)
			(xy 380.306393 -377.912585) (xy 380.312168 -377.919742) (xy 380.334008 -377.945428) (xy 380.372099 -378.001059)
			(xy 380.403253 -378.060852) (xy 380.42702 -378.123946) (xy 380.443058 -378.189433) (xy 380.451137 -378.256369)
			(xy 380.451139 -378.323734) (xy 383.729177 -378.323734) (xy 383.729179 -378.256427) (xy 383.737226 -378.189602)
			(xy 383.753202 -378.124218) (xy 383.776879 -378.061212) (xy 383.807917 -378.001488) (xy 383.84587 -377.945902)
			(xy 383.86766 -377.92025) (xy 383.873468 -377.913113) (xy 383.879974 -377.895916) (xy 383.88036 -377.886722)
			(xy 383.88036 -377.728734) (xy 383.880792 -377.718562) (xy 383.88857 -377.699764) (xy 383.902954 -377.685377)
			(xy 383.92175 -377.677595) (xy 383.931922 -377.677172) (xy 384.648202 -377.677172) (xy 384.658378 -377.677563)
			(xy 384.677179 -377.685355) (xy 384.691565 -377.699751) (xy 384.699344 -377.718558) (xy 384.699764 -377.728734)
			(xy 384.699764 -377.886722) (xy 384.700172 -377.895909) (xy 384.706688 -377.913093) (xy 384.712464 -377.92025)
			(xy 384.734226 -377.945923) (xy 384.772175 -378.001507) (xy 384.803209 -378.061228) (xy 384.826884 -378.124229)
			(xy 384.842858 -378.189609) (xy 384.850904 -378.256429) (xy 384.850907 -378.323732) (xy 384.850907 -378.323734)
			(xy 388.128968 -378.323734) (xy 388.12897 -378.256427) (xy 388.137017 -378.189602) (xy 388.152993 -378.124218)
			(xy 388.176669 -378.061213) (xy 388.207706 -378.001489) (xy 388.245658 -377.945902) (xy 388.267448 -377.92025)
			(xy 388.273254 -377.913112) (xy 388.279762 -377.895916) (xy 388.280148 -377.886722) (xy 388.280148 -377.728734)
			(xy 388.280592 -377.718563) (xy 388.288368 -377.699768) (xy 388.302747 -377.685381) (xy 388.32154 -377.677597)
			(xy 388.33171 -377.677172) (xy 389.04799 -377.677172) (xy 389.058165 -377.677573) (xy 389.076966 -377.685361)
			(xy 389.091353 -377.699754) (xy 389.099132 -377.718559) (xy 389.099552 -377.728734) (xy 389.099552 -377.886722)
			(xy 389.099962 -377.895909) (xy 389.106477 -377.913093) (xy 389.112252 -377.92025) (xy 389.134014 -377.945923)
			(xy 389.171964 -378.001506) (xy 389.202999 -378.061227) (xy 389.226674 -378.124229) (xy 389.242649 -378.189608)
			(xy 389.250695 -378.256429) (xy 389.250698 -378.323732) (xy 389.250698 -378.323734) (xy 418.928998 -378.323734)
			(xy 418.929001 -378.256426) (xy 418.937048 -378.189601) (xy 418.953025 -378.124217) (xy 418.976703 -378.061211)
			(xy 419.007742 -378.001487) (xy 419.045697 -377.945902) (xy 419.067488 -377.92025) (xy 419.073287 -377.913106)
			(xy 419.079801 -377.895915) (xy 419.080188 -377.886722) (xy 419.080188 -377.728734) (xy 419.080593 -377.718558)
			(xy 419.088376 -377.699755) (xy 419.102768 -377.685367) (xy 419.121574 -377.67759) (xy 419.13175 -377.677172)
			(xy 419.84803 -377.677172) (xy 419.858208 -377.67754) (xy 419.87701 -377.685341) (xy 419.891395 -377.699744)
			(xy 419.899173 -377.718556) (xy 419.899592 -377.728734) (xy 419.899592 -377.886722) (xy 419.899993 -377.89591)
			(xy 419.906513 -377.913094) (xy 419.912292 -377.92025) (xy 419.934053 -377.945924) (xy 419.972001 -378.001508)
			(xy 420.003034 -378.061229) (xy 420.026706 -378.12423) (xy 420.04268 -378.189609) (xy 420.050726 -378.256429)
			(xy 420.050728 -378.323732) (xy 420.050721 -378.323793) (xy 423.328791 -378.323793) (xy 423.328793 -378.256368)
			(xy 423.336871 -378.189428) (xy 423.352909 -378.123938) (xy 423.376675 -378.06084) (xy 423.407828 -378.001043)
			(xy 423.445919 -377.945408) (xy 423.467784 -377.919742) (xy 423.473586 -377.9126) (xy 423.480098 -377.895407)
			(xy 423.480484 -377.886214) (xy 423.480484 -377.728734) (xy 423.480956 -377.718604) (xy 423.488681 -377.699875)
			(xy 423.502972 -377.685516) (xy 423.521664 -377.677704) (xy 423.531792 -377.677172) (xy 424.248072 -377.677172)
			(xy 424.258189 -377.677638) (xy 424.276887 -377.685372) (xy 424.291201 -377.699673) (xy 424.298953 -377.718363)
			(xy 424.29938 -377.72848) (xy 424.29938 -377.886214) (xy 424.299788 -377.895401) (xy 424.306303 -377.912585)
			(xy 424.31208 -377.919742) (xy 424.333919 -377.945428) (xy 424.37201 -378.001059) (xy 424.403163 -378.060852)
			(xy 424.426929 -378.123946) (xy 424.442967 -378.189433) (xy 424.451046 -378.256369) (xy 424.451048 -378.323734)
			(xy 427.729086 -378.323734) (xy 427.729089 -378.256427) (xy 427.737136 -378.189602) (xy 427.753113 -378.124218)
			(xy 427.77679 -378.061212) (xy 427.807828 -378.001488) (xy 427.845782 -377.945902) (xy 427.867572 -377.92025)
			(xy 427.873381 -377.913114) (xy 427.879886 -377.895916) (xy 427.880272 -377.886722) (xy 427.880272 -377.728734)
			(xy 427.880693 -377.71856) (xy 427.888473 -377.69976) (xy 427.90286 -377.685373) (xy 427.92166 -377.677593)
			(xy 427.931834 -377.677172) (xy 428.648114 -377.677172) (xy 428.658291 -377.677553) (xy 428.677092 -377.685349)
			(xy 428.691478 -377.699748) (xy 428.699256 -377.718557) (xy 428.699676 -377.728734) (xy 428.699676 -377.886722)
			(xy 428.700081 -377.89591) (xy 428.706599 -377.913094) (xy 428.712376 -377.92025) (xy 428.734137 -377.945924)
			(xy 428.772086 -378.001507) (xy 428.80312 -378.061228) (xy 428.826793 -378.12423) (xy 428.842767 -378.189609)
			(xy 428.850813 -378.256429) (xy 428.850816 -378.323732) (xy 428.850816 -378.323734) (xy 432.128877 -378.323734)
			(xy 432.128879 -378.256427) (xy 432.136926 -378.189602) (xy 432.152902 -378.124218) (xy 432.176579 -378.061212)
			(xy 432.207617 -378.001488) (xy 432.24557 -377.945902) (xy 432.26736 -377.92025) (xy 432.273168 -377.913113)
			(xy 432.279674 -377.895916) (xy 432.28006 -377.886722) (xy 432.28006 -377.728734) (xy 432.280492 -377.718562)
			(xy 432.28827 -377.699764) (xy 432.302654 -377.685377) (xy 432.32145 -377.677595) (xy 432.331622 -377.677172)
			(xy 433.047902 -377.677172) (xy 433.058078 -377.677563) (xy 433.076879 -377.685355) (xy 433.091265 -377.699751)
			(xy 433.099044 -377.718558) (xy 433.099464 -377.728734) (xy 433.099464 -377.886722) (xy 433.099872 -377.895909)
			(xy 433.106388 -377.913093) (xy 433.112164 -377.92025) (xy 433.133926 -377.945923) (xy 433.171875 -378.001507)
			(xy 433.202909 -378.061228) (xy 433.226584 -378.124229) (xy 433.242558 -378.189609) (xy 433.250604 -378.256429)
			(xy 433.250607 -378.323732) (xy 433.242565 -378.390553) (xy 433.226595 -378.455933) (xy 433.202925 -378.518937)
			(xy 433.171895 -378.57866) (xy 433.13395 -378.634246) (xy 433.112164 -378.659898) (xy 433.106381 -378.667053)
			(xy 433.099859 -378.684236) (xy 433.099464 -378.693426) (xy 433.099464 -379.186694) (xy 433.099885 -379.19588)
			(xy 433.106392 -379.213064) (xy 433.112164 -379.220222) (xy 433.133997 -379.245837) (xy 433.171944 -379.301429)
			(xy 433.202975 -379.361158) (xy 433.226645 -379.424167) (xy 433.242615 -379.489554) (xy 433.250655 -379.55638)
			(xy 433.250651 -379.623689) (xy 433.242603 -379.690515) (xy 433.226625 -379.755899) (xy 433.202947 -379.818906)
			(xy 433.171909 -379.878631) (xy 433.133955 -379.934218) (xy 433.112164 -379.95987) (xy 433.106351 -379.967003)
			(xy 433.099847 -379.984203) (xy 433.099464 -379.993398) (xy 433.099464 -380.151386) (xy 433.099025 -380.161556)
			(xy 433.091245 -380.180351) (xy 433.076864 -380.194736) (xy 433.058072 -380.202522) (xy 433.047902 -380.202948)
			(xy 432.331622 -380.202948) (xy 432.32145 -380.202518) (xy 432.302653 -380.194737) (xy 432.288267 -380.180353)
			(xy 432.280484 -380.161558) (xy 432.28006 -380.151386) (xy 432.28006 -379.993398) (xy 432.279637 -379.984212)
			(xy 432.273131 -379.967029) (xy 432.26736 -379.95987) (xy 432.245617 -379.934181) (xy 432.207665 -379.8786)
			(xy 432.176629 -379.818882) (xy 432.152953 -379.755882) (xy 432.136976 -379.690504) (xy 432.128928 -379.623685)
			(xy 432.128924 -379.556384) (xy 432.136964 -379.489564) (xy 432.152932 -379.424184) (xy 432.176601 -379.361181)
			(xy 432.20763 -379.301459) (xy 432.245575 -379.245874) (xy 432.26736 -379.220222) (xy 432.27318 -379.213093)
			(xy 432.279679 -379.19589) (xy 432.28006 -379.186694) (xy 432.28006 -378.693426) (xy 432.279624 -378.684242)
			(xy 432.273127 -378.667058) (xy 432.26736 -378.659898) (xy 432.245546 -378.634267) (xy 432.207596 -378.578678)
			(xy 432.176563 -378.518952) (xy 432.152891 -378.455945) (xy 432.136919 -378.39056) (xy 432.128877 -378.323734)
			(xy 428.850816 -378.323734) (xy 428.842774 -378.390552) (xy 428.826805 -378.455933) (xy 428.803136 -378.518936)
			(xy 428.772106 -378.578659) (xy 428.734161 -378.634245) (xy 428.712376 -378.659898) (xy 428.706595 -378.667054)
			(xy 428.700072 -378.684236) (xy 428.699676 -378.693426) (xy 428.699676 -379.186694) (xy 428.700094 -379.19588)
			(xy 428.706603 -379.213064) (xy 428.712376 -379.220222) (xy 428.734209 -379.245837) (xy 428.772155 -379.301429)
			(xy 428.803185 -379.361158) (xy 428.826855 -379.424167) (xy 428.842824 -379.489554) (xy 428.850865 -379.55638)
			(xy 428.85086 -379.623689) (xy 428.842812 -379.690514) (xy 428.826835 -379.755899) (xy 428.803157 -379.818905)
			(xy 428.772119 -379.87863) (xy 428.734166 -379.934218) (xy 428.712376 -379.95987) (xy 428.706564 -379.967004)
			(xy 428.70006 -379.984203) (xy 428.699676 -379.993398) (xy 428.699676 -380.151386) (xy 428.699156 -380.161541)
			(xy 428.691388 -380.180307) (xy 428.677031 -380.194673) (xy 428.658269 -380.20245) (xy 428.648114 -380.202948)
			(xy 427.931834 -380.202948) (xy 427.921663 -380.202508) (xy 427.902866 -380.194731) (xy 427.88848 -380.180351)
			(xy 427.880696 -380.161557) (xy 427.880272 -380.151386) (xy 427.880272 -379.993398) (xy 427.879869 -379.98421)
			(xy 427.873351 -379.967025) (xy 427.867572 -379.95987) (xy 427.845829 -379.934181) (xy 427.807876 -379.878601)
			(xy 427.776839 -379.818882) (xy 427.753162 -379.755883) (xy 427.737185 -379.690505) (xy 427.729137 -379.623686)
			(xy 427.729133 -379.556384) (xy 427.737173 -379.489564) (xy 427.753142 -379.424183) (xy 427.776811 -379.361181)
			(xy 427.807841 -379.301459) (xy 427.845786 -379.245874) (xy 427.867572 -379.220222) (xy 427.873393 -379.213094)
			(xy 427.879891 -379.19589) (xy 427.880272 -379.186694) (xy 427.880272 -378.693426) (xy 427.879856 -378.684239)
			(xy 427.873347 -378.667055) (xy 427.867572 -378.659898) (xy 427.845758 -378.634267) (xy 427.807808 -378.578678)
			(xy 427.776774 -378.518952) (xy 427.753101 -378.455945) (xy 427.737129 -378.39056) (xy 427.729086 -378.323734)
			(xy 424.451048 -378.323734) (xy 424.451048 -378.323791) (xy 424.442974 -378.390728) (xy 424.426941 -378.456216)
			(xy 424.403179 -378.519312) (xy 424.37203 -378.579107) (xy 424.333943 -378.634741) (xy 424.31208 -378.660406)
			(xy 424.306296 -378.66756) (xy 424.299775 -378.684744) (xy 424.29938 -378.693934) (xy 424.29938 -379.186186)
			(xy 424.299802 -379.195372) (xy 424.306308 -379.212556) (xy 424.31208 -379.219714) (xy 424.33399 -379.245342)
			(xy 424.372079 -379.300981) (xy 424.403228 -379.360782) (xy 424.426991 -379.423884) (xy 424.443024 -379.489378)
			(xy 424.451096 -379.556321) (xy 424.451092 -379.623748) (xy 424.443011 -379.69069) (xy 424.42697 -379.756182)
			(xy 424.4032 -379.819281) (xy 424.372043 -379.879078) (xy 424.333947 -379.934713) (xy 424.31208 -379.960378)
			(xy 424.306266 -379.96751) (xy 424.299762 -379.984711) (xy 424.29938 -379.993906) (xy 424.29938 -380.151386)
			(xy 424.298863 -380.161509) (xy 424.291143 -380.180226) (xy 424.276866 -380.194583) (xy 424.258193 -380.202406)
			(xy 424.248072 -380.202948) (xy 423.531792 -380.202948) (xy 423.521689 -380.202422) (xy 423.50302 -380.194691)
			(xy 423.488727 -380.180407) (xy 423.480984 -380.161743) (xy 423.480484 -380.15164) (xy 423.480484 -379.993906)
			(xy 423.480075 -379.984719) (xy 423.473561 -379.967534) (xy 423.467784 -379.960378) (xy 423.445966 -379.934675)
			(xy 423.407877 -379.879046) (xy 423.376725 -379.819255) (xy 423.352959 -379.756163) (xy 423.336921 -379.690678)
			(xy 423.328841 -379.623744) (xy 423.328837 -379.556325) (xy 423.336908 -379.48939) (xy 423.352938 -379.423904)
			(xy 423.376697 -379.360809) (xy 423.407841 -379.301014) (xy 423.445923 -379.245379) (xy 423.467784 -379.219714)
			(xy 423.473598 -379.212581) (xy 423.480103 -379.195381) (xy 423.480484 -379.186186) (xy 423.480484 -378.693934)
			(xy 423.480061 -378.684748) (xy 423.473557 -378.667563) (xy 423.467784 -378.660406) (xy 423.445895 -378.634762)
			(xy 423.407808 -378.579124) (xy 423.376659 -378.519324) (xy 423.352897 -378.456225) (xy 423.336864 -378.390733)
			(xy 423.328791 -378.323793) (xy 420.050721 -378.323793) (xy 420.042687 -378.390552) (xy 420.026718 -378.455932)
			(xy 420.003049 -378.518936) (xy 419.972021 -378.578659) (xy 419.934077 -378.634245) (xy 419.912292 -378.659898)
			(xy 419.906513 -378.667056) (xy 419.899988 -378.684237) (xy 419.899592 -378.693426) (xy 419.899592 -379.186694)
			(xy 419.900007 -379.195881) (xy 419.906518 -379.213065) (xy 419.912292 -379.220222) (xy 419.934124 -379.245837)
			(xy 419.972069 -379.30143) (xy 420.003099 -379.361159) (xy 420.026768 -379.424168) (xy 420.042737 -379.489554)
			(xy 420.050777 -379.556381) (xy 420.050772 -379.623689) (xy 420.042724 -379.690514) (xy 420.026747 -379.755898)
			(xy 420.003071 -379.818905) (xy 419.972034 -379.87863) (xy 419.934082 -379.934217) (xy 419.912292 -379.95987)
			(xy 419.906482 -379.967006) (xy 419.899976 -379.984204) (xy 419.899592 -379.993398) (xy 419.899592 -380.151386)
			(xy 419.899056 -380.161539) (xy 419.891292 -380.180302) (xy 419.876939 -380.194667) (xy 419.858183 -380.202447)
			(xy 419.84803 -380.202948) (xy 419.13175 -380.202948) (xy 419.12158 -380.202495) (xy 419.102784 -380.194724)
			(xy 419.088396 -380.180347) (xy 419.080612 -380.161556) (xy 419.080188 -380.151386) (xy 419.080188 -379.993398)
			(xy 419.079781 -379.98421) (xy 419.073266 -379.967026) (xy 419.067488 -379.95987) (xy 419.045744 -379.934181)
			(xy 419.007791 -379.878601) (xy 418.976753 -379.818883) (xy 418.953075 -379.755883) (xy 418.937097 -379.690505)
			(xy 418.929049 -379.623686) (xy 418.929045 -379.556383) (xy 418.937085 -379.489563) (xy 418.953055 -379.424183)
			(xy 418.976724 -379.36118) (xy 419.007755 -379.301458) (xy 419.045702 -379.245873) (xy 419.067488 -379.220222)
			(xy 419.073299 -379.213087) (xy 419.079805 -379.195889) (xy 419.080188 -379.186694) (xy 419.080188 -378.693426)
			(xy 419.079768 -378.68424) (xy 419.073262 -378.667055) (xy 419.067488 -378.659898) (xy 419.045673 -378.634268)
			(xy 419.007722 -378.578679) (xy 418.976687 -378.518953) (xy 418.953014 -378.455946) (xy 418.937041 -378.39056)
			(xy 418.928998 -378.323734) (xy 389.250698 -378.323734) (xy 389.242656 -378.390553) (xy 389.226686 -378.455934)
			(xy 389.203015 -378.518937) (xy 389.171985 -378.57866) (xy 389.134038 -378.634246) (xy 389.112252 -378.659898)
			(xy 389.106468 -378.667052) (xy 389.099947 -378.684236) (xy 389.099552 -378.693426) (xy 389.099552 -379.186694)
			(xy 389.099976 -379.19588) (xy 389.106481 -379.213063) (xy 389.112252 -379.220222) (xy 389.134085 -379.245837)
			(xy 389.172033 -379.301428) (xy 389.203065 -379.361157) (xy 389.226736 -379.424166) (xy 389.242706 -379.489553)
			(xy 389.250746 -379.55638) (xy 389.250742 -379.623689) (xy 389.242693 -379.690515) (xy 389.226715 -379.7559)
			(xy 389.203037 -379.818906) (xy 389.171998 -379.878631) (xy 389.134043 -379.934218) (xy 389.112252 -379.95987)
			(xy 389.106437 -379.967002) (xy 389.099935 -379.984203) (xy 389.099552 -379.993398) (xy 389.099552 -380.151386)
			(xy 389.099125 -380.161558) (xy 389.091342 -380.180354) (xy 389.076958 -380.19474) (xy 389.058162 -380.202524)
			(xy 389.04799 -380.202948) (xy 388.33171 -380.202948) (xy 388.321537 -380.202528) (xy 388.30274 -380.194743)
			(xy 388.288354 -380.180357) (xy 388.280571 -380.161559) (xy 388.280148 -380.151386) (xy 388.280148 -379.993398)
			(xy 388.279728 -379.984212) (xy 388.27322 -379.967028) (xy 388.267448 -379.95987) (xy 388.245705 -379.934181)
			(xy 388.207755 -379.8786) (xy 388.176719 -379.818881) (xy 388.153043 -379.755882) (xy 388.137067 -379.690504)
			(xy 388.129019 -379.623685) (xy 388.129015 -379.556384) (xy 388.137054 -379.489564) (xy 388.153023 -379.424184)
			(xy 388.176691 -379.361182) (xy 388.207719 -379.30146) (xy 388.245663 -379.245874) (xy 388.267448 -379.220222)
			(xy 388.273266 -379.213092) (xy 388.279767 -379.19589) (xy 388.280148 -379.186694) (xy 388.280148 -378.693426)
			(xy 388.279715 -378.684241) (xy 388.273216 -378.667057) (xy 388.267448 -378.659898) (xy 388.245634 -378.634267)
			(xy 388.207686 -378.578678) (xy 388.176653 -378.518951) (xy 388.152981 -378.455944) (xy 388.13701 -378.390559)
			(xy 388.128968 -378.323734) (xy 384.850907 -378.323734) (xy 384.842865 -378.390553) (xy 384.826895 -378.455933)
			(xy 384.803225 -378.518937) (xy 384.772195 -378.57866) (xy 384.73425 -378.634246) (xy 384.712464 -378.659898)
			(xy 384.706681 -378.667053) (xy 384.700159 -378.684236) (xy 384.699764 -378.693426) (xy 384.699764 -379.186694)
			(xy 384.700185 -379.19588) (xy 384.706692 -379.213064) (xy 384.712464 -379.220222) (xy 384.734297 -379.245837)
			(xy 384.772244 -379.301429) (xy 384.803275 -379.361158) (xy 384.826945 -379.424167) (xy 384.842915 -379.489554)
			(xy 384.850955 -379.55638) (xy 384.850951 -379.623689) (xy 384.842903 -379.690515) (xy 384.826925 -379.755899)
			(xy 384.803247 -379.818906) (xy 384.772209 -379.878631) (xy 384.734255 -379.934218) (xy 384.712464 -379.95987)
			(xy 384.706651 -379.967003) (xy 384.700147 -379.984203) (xy 384.699764 -379.993398) (xy 384.699764 -380.151386)
			(xy 384.699325 -380.161556) (xy 384.691545 -380.180351) (xy 384.677164 -380.194736) (xy 384.658372 -380.202522)
			(xy 384.648202 -380.202948) (xy 383.931922 -380.202948) (xy 383.92175 -380.202518) (xy 383.902953 -380.194737)
			(xy 383.888567 -380.180353) (xy 383.880784 -380.161558) (xy 383.88036 -380.151386) (xy 383.88036 -379.993398)
			(xy 383.879937 -379.984212) (xy 383.873431 -379.967029) (xy 383.86766 -379.95987) (xy 383.845917 -379.934181)
			(xy 383.807965 -379.8786) (xy 383.776929 -379.818882) (xy 383.753253 -379.755882) (xy 383.737276 -379.690504)
			(xy 383.729228 -379.623685) (xy 383.729224 -379.556384) (xy 383.737264 -379.489564) (xy 383.753232 -379.424184)
			(xy 383.776901 -379.361181) (xy 383.80793 -379.301459) (xy 383.845875 -379.245874) (xy 383.86766 -379.220222)
			(xy 383.87348 -379.213093) (xy 383.879979 -379.19589) (xy 383.88036 -379.186694) (xy 383.88036 -378.693426)
			(xy 383.879924 -378.684242) (xy 383.873427 -378.667058) (xy 383.86766 -378.659898) (xy 383.845846 -378.634267)
			(xy 383.807896 -378.578678) (xy 383.776863 -378.518952) (xy 383.753191 -378.455945) (xy 383.737219 -378.39056)
			(xy 383.729177 -378.323734) (xy 380.451139 -378.323734) (xy 380.451139 -378.323792) (xy 380.443065 -378.390729)
			(xy 380.427031 -378.456217) (xy 380.403269 -378.519313) (xy 380.372119 -378.579108) (xy 380.334032 -378.634741)
			(xy 380.312168 -378.660406) (xy 380.306382 -378.667559) (xy 380.299862 -378.684744) (xy 380.299468 -378.693934)
			(xy 380.299468 -379.186186) (xy 380.299892 -379.195372) (xy 380.306397 -379.212556) (xy 380.312168 -379.219714)
			(xy 380.334078 -379.245341) (xy 380.372168 -379.300981) (xy 380.403318 -379.360782) (xy 380.427081 -379.423884)
			(xy 380.443114 -379.489378) (xy 380.451187 -379.556321) (xy 380.451183 -379.623749) (xy 380.443102 -379.69069)
			(xy 380.427061 -379.756182) (xy 380.40329 -379.819281) (xy 380.372132 -379.879079) (xy 380.334036 -379.934713)
			(xy 380.312168 -379.960378) (xy 380.306352 -379.967509) (xy 380.29985 -379.984711) (xy 380.299468 -379.993906)
			(xy 380.299468 -380.151386) (xy 380.298962 -380.161511) (xy 380.291241 -380.18023) (xy 380.27696 -380.194587)
			(xy 380.258282 -380.202408) (xy 380.24816 -380.202948) (xy 379.53188 -380.202948) (xy 379.521731 -380.202496)
			(xy 379.502987 -380.194703) (xy 379.488666 -380.180316) (xy 379.480958 -380.161537) (xy 379.480572 -380.151386)
			(xy 379.480572 -379.993906) (xy 379.480165 -379.984718) (xy 379.47365 -379.967534) (xy 379.467872 -379.960378)
			(xy 379.446054 -379.934675) (xy 379.407966 -379.879045) (xy 379.376815 -379.819254) (xy 379.353049 -379.756162)
			(xy 379.337011 -379.690678) (xy 379.328932 -379.623744) (xy 379.328928 -379.556325) (xy 379.336999 -379.48939)
			(xy 379.353029 -379.423904) (xy 379.376787 -379.360809) (xy 379.40793 -379.301014) (xy 379.446012 -379.24538)
			(xy 379.467872 -379.219714) (xy 379.473696 -379.212589) (xy 379.480192 -379.195383) (xy 379.480572 -379.186186)
			(xy 379.480572 -378.693934) (xy 379.480152 -378.684748) (xy 379.473646 -378.667563) (xy 379.467872 -378.660406)
			(xy 379.445983 -378.634761) (xy 379.407897 -378.579123) (xy 379.376749 -378.519324) (xy 379.352988 -378.456224)
			(xy 379.336955 -378.390733) (xy 379.328882 -378.323793) (xy 376.050812 -378.323793) (xy 376.042778 -378.390552)
			(xy 376.026808 -378.455933) (xy 376.003139 -378.518936) (xy 375.97211 -378.578659) (xy 375.934166 -378.634246)
			(xy 375.91238 -378.659898) (xy 375.906599 -378.667054) (xy 375.900076 -378.684236) (xy 375.89968 -378.693426)
			(xy 375.89968 -379.186694) (xy 375.900098 -379.19588) (xy 375.906607 -379.213064) (xy 375.91238 -379.220222)
			(xy 375.934212 -379.245837) (xy 375.972159 -379.301429) (xy 376.003189 -379.361158) (xy 376.026858 -379.424168)
			(xy 376.042827 -379.489554) (xy 376.050868 -379.55638) (xy 376.050863 -379.623689) (xy 376.042815 -379.690514)
			(xy 376.026838 -379.755899) (xy 376.003161 -379.818905) (xy 375.972123 -379.87863) (xy 375.93417 -379.934218)
			(xy 375.91238 -379.95987) (xy 375.906569 -379.967005) (xy 375.900064 -379.984203) (xy 375.89968 -379.993398)
			(xy 375.89968 -380.151386) (xy 375.899156 -380.161541) (xy 375.891389 -380.180306) (xy 375.877033 -380.194671)
			(xy 375.858272 -380.202449) (xy 375.848118 -380.202948) (xy 375.131838 -380.202948) (xy 375.121667 -380.202505)
			(xy 375.102871 -380.19473) (xy 375.088484 -380.18035) (xy 375.0807 -380.161557) (xy 375.080276 -380.151386)
			(xy 375.080276 -379.993398) (xy 375.079872 -379.98421) (xy 375.073355 -379.967025) (xy 375.067576 -379.95987)
			(xy 375.045832 -379.934181) (xy 375.00788 -379.878601) (xy 374.976842 -379.818883) (xy 374.953165 -379.755883)
			(xy 374.937188 -379.690505) (xy 374.92914 -379.623686) (xy 374.929136 -379.556384) (xy 374.937176 -379.489563)
			(xy 374.953145 -379.424183) (xy 374.976814 -379.361181) (xy 375.007844 -379.301459) (xy 375.04579 -379.245874)
			(xy 375.067576 -379.220222) (xy 375.073385 -379.213086) (xy 375.079893 -379.195889) (xy 375.080276 -379.186694)
			(xy 375.080276 -378.693426) (xy 375.079859 -378.684239) (xy 375.073351 -378.667055) (xy 375.067576 -378.659898)
			(xy 375.045762 -378.634267) (xy 375.007811 -378.578679) (xy 374.976777 -378.518952) (xy 374.953104 -378.455945)
			(xy 374.937132 -378.39056) (xy 374.929089 -378.323734) (xy 345.250789 -378.323734) (xy 345.242747 -378.390553)
			(xy 345.226776 -378.455934) (xy 345.203105 -378.518938) (xy 345.172074 -378.57866) (xy 345.134127 -378.634246)
			(xy 345.11234 -378.659898) (xy 345.106554 -378.667051) (xy 345.100035 -378.684236) (xy 345.09964 -378.693426)
			(xy 345.09964 -379.186694) (xy 345.100066 -379.195879) (xy 345.10657 -379.213063) (xy 345.11234 -379.220222)
			(xy 345.134174 -379.245837) (xy 345.172123 -379.301428) (xy 345.203155 -379.361156) (xy 345.226826 -379.424166)
			(xy 345.242797 -379.489553) (xy 345.250837 -379.55638) (xy 345.250833 -379.623689) (xy 345.242784 -379.690515)
			(xy 345.226806 -379.7559) (xy 345.203127 -379.818907) (xy 345.172087 -379.878632) (xy 345.134131 -379.934218)
			(xy 345.11234 -379.95987) (xy 345.106524 -379.967001) (xy 345.100023 -379.984203) (xy 345.09964 -379.993398)
			(xy 345.09964 -380.151386) (xy 345.099224 -380.161559) (xy 345.09144 -380.180358) (xy 345.077051 -380.194744)
			(xy 345.058252 -380.202526) (xy 345.048078 -380.202948) (xy 344.331798 -380.202948) (xy 344.321625 -380.202537)
			(xy 344.302827 -380.194749) (xy 344.288442 -380.180359) (xy 344.280659 -380.16156) (xy 344.280236 -380.151386)
			(xy 344.280236 -379.993398) (xy 344.279819 -379.984212) (xy 344.273309 -379.967028) (xy 344.267536 -379.95987)
			(xy 344.245794 -379.93418) (xy 344.207844 -379.878599) (xy 344.176809 -379.818881) (xy 344.153133 -379.755881)
			(xy 344.137157 -379.690504) (xy 344.12911 -379.623685) (xy 344.129106 -379.556384) (xy 344.137145 -379.489565)
			(xy 344.153113 -379.424185) (xy 344.17678 -379.361182) (xy 344.207808 -379.30146) (xy 344.245751 -379.245874)
			(xy 344.267536 -379.220222) (xy 344.273353 -379.213091) (xy 344.279855 -379.19589) (xy 344.280236 -379.186694)
			(xy 344.280236 -378.693426) (xy 344.279805 -378.684241) (xy 344.273305 -378.667057) (xy 344.267536 -378.659898)
			(xy 344.245723 -378.634267) (xy 344.207775 -378.578677) (xy 344.176743 -378.518951) (xy 344.153072 -378.455944)
			(xy 344.137101 -378.390559) (xy 344.129059 -378.323734) (xy 340.850998 -378.323734) (xy 340.842956 -378.390553)
			(xy 340.826986 -378.455934) (xy 340.803315 -378.518937) (xy 340.772285 -378.57866) (xy 340.734338 -378.634246)
			(xy 340.712552 -378.659898) (xy 340.706768 -378.667052) (xy 340.700247 -378.684236) (xy 340.699852 -378.693426)
			(xy 340.699852 -379.186694) (xy 340.700276 -379.19588) (xy 340.706781 -379.213063) (xy 340.712552 -379.220222)
			(xy 340.734385 -379.245837) (xy 340.772333 -379.301428) (xy 340.803365 -379.361157) (xy 340.827036 -379.424166)
			(xy 340.843006 -379.489553) (xy 340.851046 -379.55638) (xy 340.851042 -379.623689) (xy 340.842993 -379.690515)
			(xy 340.827015 -379.7559) (xy 340.803337 -379.818906) (xy 340.772298 -379.878631) (xy 340.734343 -379.934218)
			(xy 340.712552 -379.95987) (xy 340.706737 -379.967002) (xy 340.700235 -379.984203) (xy 340.699852 -379.993398)
			(xy 340.699852 -380.151386) (xy 340.699425 -380.161558) (xy 340.691642 -380.180354) (xy 340.677258 -380.19474)
			(xy 340.658462 -380.202524) (xy 340.64829 -380.202948) (xy 339.93201 -380.202948) (xy 339.921837 -380.202528)
			(xy 339.90304 -380.194743) (xy 339.888654 -380.180357) (xy 339.880871 -380.161559) (xy 339.880448 -380.151386)
			(xy 339.880448 -379.993398) (xy 339.880028 -379.984212) (xy 339.87352 -379.967028) (xy 339.867748 -379.95987)
			(xy 339.846005 -379.934181) (xy 339.808055 -379.8786) (xy 339.777019 -379.818881) (xy 339.753343 -379.755882)
			(xy 339.737367 -379.690504) (xy 339.729319 -379.623685) (xy 339.729315 -379.556384) (xy 339.737354 -379.489564)
			(xy 339.753323 -379.424184) (xy 339.776991 -379.361182) (xy 339.808019 -379.30146) (xy 339.845963 -379.245874)
			(xy 339.867748 -379.220222) (xy 339.873566 -379.213092) (xy 339.880067 -379.19589) (xy 339.880448 -379.186694)
			(xy 339.880448 -378.693426) (xy 339.880015 -378.684241) (xy 339.873516 -378.667057) (xy 339.867748 -378.659898)
			(xy 339.845934 -378.634267) (xy 339.807986 -378.578678) (xy 339.776953 -378.518951) (xy 339.753281 -378.455944)
			(xy 339.73731 -378.390559) (xy 339.729268 -378.323734) (xy 336.45123 -378.323734) (xy 336.45123 -378.323792)
			(xy 336.443156 -378.390729) (xy 336.427122 -378.456217) (xy 336.403359 -378.519313) (xy 336.372208 -378.579108)
			(xy 336.33412 -378.634742) (xy 336.312256 -378.660406) (xy 336.306469 -378.667558) (xy 336.29995 -378.684743)
			(xy 336.299556 -378.693934) (xy 336.299556 -379.186186) (xy 336.299983 -379.195371) (xy 336.306486 -379.212555)
			(xy 336.312256 -379.219714) (xy 336.334167 -379.245341) (xy 336.372257 -379.30098) (xy 336.403408 -379.360781)
			(xy 336.427172 -379.423883) (xy 336.443205 -379.489377) (xy 336.451278 -379.55632) (xy 336.451274 -379.623749)
			(xy 336.443193 -379.690691) (xy 336.427151 -379.756183) (xy 336.40338 -379.819282) (xy 336.372221 -379.879079)
			(xy 336.334124 -379.934713) (xy 336.312256 -379.960378) (xy 336.306438 -379.967508) (xy 336.299937 -379.98471)
			(xy 336.299556 -379.993906) (xy 336.299556 -380.151386) (xy 336.299062 -380.161512) (xy 336.291338 -380.180234)
			(xy 336.277054 -380.194591) (xy 336.258372 -380.20241) (xy 336.248248 -380.202948) (xy 335.531968 -380.202948)
			(xy 335.521818 -380.202506) (xy 335.503074 -380.194708) (xy 335.488753 -380.180319) (xy 335.481046 -380.161538)
			(xy 335.48066 -380.151386) (xy 335.48066 -379.993906) (xy 335.480234 -379.984721) (xy 335.47373 -379.967537)
			(xy 335.46796 -379.960378) (xy 335.446143 -379.934675) (xy 335.408055 -379.879045) (xy 335.376905 -379.819253)
			(xy 335.35314 -379.756162) (xy 335.337102 -379.690678) (xy 335.329023 -379.623744) (xy 335.329019 -379.556325)
			(xy 335.33709 -379.48939) (xy 335.353119 -379.423904) (xy 335.376876 -379.36081) (xy 335.40802 -379.301015)
			(xy 335.4461 -379.24538) (xy 335.46796 -379.219714) (xy 335.473783 -379.212588) (xy 335.48028 -379.195382)
			(xy 335.48066 -379.186186) (xy 335.48066 -378.693934) (xy 335.48022 -378.68475) (xy 335.473726 -378.667566)
			(xy 335.46796 -378.660406) (xy 335.446072 -378.634761) (xy 335.407987 -378.579123) (xy 335.376839 -378.519323)
			(xy 335.353078 -378.456224) (xy 335.337046 -378.390733) (xy 335.328973 -378.323793) (xy 332.050903 -378.323793)
			(xy 332.042868 -378.390553) (xy 332.026898 -378.455933) (xy 332.003229 -378.518937) (xy 331.972199 -378.578659)
			(xy 331.934254 -378.634246) (xy 331.912468 -378.659898) (xy 331.906686 -378.667053) (xy 331.900163 -378.684236)
			(xy 331.899768 -378.693426) (xy 331.899768 -379.186694) (xy 331.900188 -379.19588) (xy 331.906696 -379.213064)
			(xy 331.912468 -379.220222) (xy 331.934301 -379.245837) (xy 331.972248 -379.301429) (xy 332.003279 -379.361158)
			(xy 332.026949 -379.424167) (xy 332.042918 -379.489554) (xy 332.050958 -379.55638) (xy 332.050954 -379.623689)
			(xy 332.042906 -379.690514) (xy 332.026928 -379.755899) (xy 332.00325 -379.818906) (xy 331.972212 -379.878631)
			(xy 331.934258 -379.934218) (xy 331.912468 -379.95987) (xy 331.906655 -379.967003) (xy 331.900151 -379.984203)
			(xy 331.899768 -379.993398) (xy 331.899768 -380.151386) (xy 331.899325 -380.161556) (xy 331.891546 -380.180349)
			(xy 331.877166 -380.194734) (xy 331.858376 -380.202521) (xy 331.848206 -380.202948) (xy 331.131926 -380.202948)
			(xy 331.121754 -380.202514) (xy 331.102958 -380.194735) (xy 331.088571 -380.180352) (xy 331.080788 -380.161558)
			(xy 331.080364 -380.151386) (xy 331.080364 -379.993398) (xy 331.07994 -379.984213) (xy 331.073434 -379.967029)
			(xy 331.067664 -379.95987) (xy 331.045921 -379.934181) (xy 331.007969 -379.8786) (xy 330.976932 -379.818882)
			(xy 330.953256 -379.755882) (xy 330.937279 -379.690504) (xy 330.929231 -379.623686) (xy 330.929227 -379.556384)
			(xy 330.937267 -379.489564) (xy 330.953235 -379.424184) (xy 330.976904 -379.361181) (xy 331.007933 -379.301459)
			(xy 331.045878 -379.245874) (xy 331.067664 -379.220222) (xy 331.073484 -379.213094) (xy 331.079983 -379.19589)
			(xy 331.080364 -379.186694) (xy 331.080364 -378.693426) (xy 331.079927 -378.684242) (xy 331.07343 -378.667058)
			(xy 331.067664 -378.659898) (xy 331.04585 -378.634267) (xy 331.0079 -378.578678) (xy 330.976866 -378.518952)
			(xy 330.953194 -378.455945) (xy 330.937222 -378.39056) (xy 330.92918 -378.323734) (xy 301.250878 -378.323734)
			(xy 301.250878 -378.323791) (xy 301.242805 -378.390727) (xy 301.226773 -378.456215) (xy 301.203013 -378.51931)
			(xy 301.171866 -378.579106) (xy 301.133782 -378.63474) (xy 301.11192 -378.660406) (xy 301.106141 -378.667564)
			(xy 301.099615 -378.684745) (xy 301.09922 -378.693934) (xy 301.09922 -379.186186) (xy 301.099632 -379.195373)
			(xy 301.106144 -379.212558) (xy 301.11192 -379.219714) (xy 301.133828 -379.245342) (xy 301.171914 -379.300983)
			(xy 301.203062 -379.360784) (xy 301.226823 -379.423886) (xy 301.242854 -379.489379) (xy 301.250926 -379.556321)
			(xy 301.250922 -379.623748) (xy 301.242842 -379.690689) (xy 301.226802 -379.75618) (xy 301.203034 -379.819279)
			(xy 301.171879 -379.879077) (xy 301.133786 -379.934712) (xy 301.11192 -379.960378) (xy 301.10611 -379.967514)
			(xy 301.099603 -379.984711) (xy 301.09922 -379.993906) (xy 301.09922 -380.151386) (xy 301.098761 -380.161517)
			(xy 301.09103 -380.180245) (xy 301.076735 -380.194603) (xy 301.058041 -380.202416) (xy 301.047912 -380.202948)
			(xy 300.331632 -380.202948) (xy 300.321486 -380.202453) (xy 300.302743 -380.194677) (xy 300.28842 -380.180304)
			(xy 300.280711 -380.161534) (xy 300.280324 -380.151386) (xy 300.280324 -379.993906) (xy 300.279906 -379.98472)
			(xy 300.273397 -379.967536) (xy 300.267624 -379.960378) (xy 300.245804 -379.934676) (xy 300.207713 -379.879047)
			(xy 300.176559 -379.819256) (xy 300.152791 -379.756164) (xy 300.136751 -379.690679) (xy 300.128672 -379.623745)
			(xy 300.128667 -379.556324) (xy 300.136739 -379.489389) (xy 300.15277 -379.423902) (xy 300.17653 -379.360807)
			(xy 300.207677 -379.301012) (xy 300.245762 -379.245379) (xy 300.267624 -379.219714) (xy 300.273442 -379.212584)
			(xy 300.279943 -379.195382) (xy 300.280324 -379.186186) (xy 300.280324 -378.693934) (xy 300.279892 -378.684749)
			(xy 300.273393 -378.667565) (xy 300.267624 -378.660406) (xy 300.245734 -378.634762) (xy 300.207644 -378.579125)
			(xy 300.176493 -378.519326) (xy 300.152729 -378.456227) (xy 300.136695 -378.390735) (xy 300.128621 -378.323794)
			(xy 296.851087 -378.323794) (xy 296.843014 -378.390727) (xy 296.826983 -378.456214) (xy 296.803223 -378.51931)
			(xy 296.772077 -378.579105) (xy 296.733993 -378.63474) (xy 296.712132 -378.660406) (xy 296.706342 -378.667556)
			(xy 296.699825 -378.684743) (xy 296.699432 -378.693934) (xy 296.699432 -379.186186) (xy 296.699864 -379.195371)
			(xy 296.706364 -379.212554) (xy 296.712132 -379.219714) (xy 296.73404 -379.245342) (xy 296.772125 -379.300983)
			(xy 296.803272 -379.360785) (xy 296.827032 -379.423886) (xy 296.843064 -379.489379) (xy 296.851135 -379.556321)
			(xy 296.851131 -379.623748) (xy 296.843051 -379.690689) (xy 296.827012 -379.75618) (xy 296.803244 -379.819279)
			(xy 296.77209 -379.879076) (xy 296.733998 -379.934712) (xy 296.712132 -379.960378) (xy 296.706312 -379.967506)
			(xy 296.699813 -379.98471) (xy 296.699432 -379.993906) (xy 296.699432 -380.151386) (xy 296.698961 -380.161515)
			(xy 296.691233 -380.180241) (xy 296.676941 -380.194599) (xy 296.658251 -380.202414) (xy 296.648124 -380.202948)
			(xy 295.931844 -380.202948) (xy 295.921699 -380.202443) (xy 295.902957 -380.194671) (xy 295.888633 -380.1803)
			(xy 295.880924 -380.161533) (xy 295.880536 -380.151386) (xy 295.880536 -379.993906) (xy 295.880115 -379.98472)
			(xy 295.873608 -379.967536) (xy 295.867836 -379.960378) (xy 295.846016 -379.934676) (xy 295.807924 -379.879048)
			(xy 295.776769 -379.819257) (xy 295.753 -379.756165) (xy 295.736961 -379.69068) (xy 295.728881 -379.623745)
			(xy 295.728876 -379.556324) (xy 295.736948 -379.489388) (xy 295.75298 -379.423901) (xy 295.776741 -379.360806)
			(xy 295.807888 -379.301012) (xy 295.845974 -379.245379) (xy 295.867836 -379.219714) (xy 295.873656 -379.212586)
			(xy 295.880156 -379.195382) (xy 295.880536 -379.186186) (xy 295.880536 -378.693934) (xy 295.880101 -378.68475)
			(xy 295.873604 -378.667565) (xy 295.867836 -378.660406) (xy 295.845945 -378.634762) (xy 295.807855 -378.579126)
			(xy 295.776703 -378.519327) (xy 295.752939 -378.456227) (xy 295.736904 -378.390735) (xy 295.72883 -378.323794)
			(xy 292.450785 -378.323794) (xy 292.44275 -378.390553) (xy 292.426779 -378.455934) (xy 292.403109 -378.518938)
			(xy 292.372077 -378.57866) (xy 292.334131 -378.634246) (xy 292.312344 -378.659898) (xy 292.306559 -378.667051)
			(xy 292.300039 -378.684236) (xy 292.299644 -378.693426) (xy 292.299644 -379.186694) (xy 292.30007 -379.195879)
			(xy 292.306574 -379.213063) (xy 292.312344 -379.220222) (xy 292.334178 -379.245837) (xy 292.372126 -379.301428)
			(xy 292.403158 -379.361157) (xy 292.426829 -379.424166) (xy 292.4428 -379.489553) (xy 292.45084 -379.55638)
			(xy 292.450836 -379.623689) (xy 292.442787 -379.690515) (xy 292.426809 -379.7559) (xy 292.40313 -379.818907)
			(xy 292.372091 -379.878631) (xy 292.334135 -379.934218) (xy 292.312344 -379.95987) (xy 292.306528 -379.967001)
			(xy 292.300027 -379.984203) (xy 292.299644 -379.993398) (xy 292.299644 -380.151386) (xy 292.299224 -380.161559)
			(xy 292.291441 -380.180357) (xy 292.277054 -380.194743) (xy 292.258255 -380.202525) (xy 292.248082 -380.202948)
			(xy 291.531802 -380.202948) (xy 291.521629 -380.202534) (xy 291.502831 -380.194747) (xy 291.488446 -380.180358)
			(xy 291.480663 -380.161559) (xy 291.48024 -380.151386) (xy 291.48024 -379.993398) (xy 291.479822 -379.984212)
			(xy 291.473313 -379.967028) (xy 291.46754 -379.95987) (xy 291.445798 -379.934181) (xy 291.407847 -379.878599)
			(xy 291.376812 -379.818881) (xy 291.353137 -379.755881) (xy 291.337161 -379.690504) (xy 291.329113 -379.623685)
			(xy 291.329109 -379.556384) (xy 291.337148 -379.489564) (xy 291.353116 -379.424185) (xy 291.376784 -379.361182)
			(xy 291.407812 -379.30146) (xy 291.445755 -379.245874) (xy 291.46754 -379.220222) (xy 291.473357 -379.213092)
			(xy 291.479859 -379.19589) (xy 291.48024 -379.186694) (xy 291.48024 -378.693426) (xy 291.479809 -378.684241)
			(xy 291.473309 -378.667057) (xy 291.46754 -378.659898) (xy 291.445727 -378.634267) (xy 291.407778 -378.578678)
			(xy 291.376746 -378.518951) (xy 291.353075 -378.455944) (xy 291.337104 -378.390559) (xy 291.329062 -378.323734)
			(xy 288.051024 -378.323734) (xy 288.051024 -378.323792) (xy 288.04295 -378.390729) (xy 288.026915 -378.456218)
			(xy 288.003152 -378.519314) (xy 287.972001 -378.579109) (xy 287.933912 -378.634742) (xy 287.912048 -378.660406)
			(xy 287.90626 -378.667557) (xy 287.899742 -378.684743) (xy 287.899348 -378.693934) (xy 287.899348 -379.186186)
			(xy 287.899776 -379.195371) (xy 287.906279 -379.212555) (xy 287.912048 -379.219714) (xy 287.933959 -379.245341)
			(xy 287.97205 -379.30098) (xy 288.003201 -379.360781) (xy 288.026965 -379.423883) (xy 288.042999 -379.489377)
			(xy 288.051072 -379.55632) (xy 288.051068 -379.623749) (xy 288.042987 -379.690691) (xy 288.026945 -379.756183)
			(xy 288.003173 -379.819282) (xy 287.972014 -379.879079) (xy 287.933917 -379.934714) (xy 287.912048 -379.960378)
			(xy 287.906229 -379.967507) (xy 287.899729 -379.98471) (xy 287.899348 -379.993906) (xy 287.899348 -380.151386)
			(xy 287.898862 -380.161513) (xy 287.891136 -380.180236) (xy 287.87685 -380.194594) (xy 287.858165 -380.202411)
			(xy 287.84804 -380.202948) (xy 287.13176 -380.202948) (xy 287.121655 -380.202449) (xy 287.102985 -380.194707)
			(xy 287.088693 -380.180415) (xy 287.080951 -380.161745) (xy 287.080452 -380.15164) (xy 287.080452 -379.993906)
			(xy 287.080027 -379.984721) (xy 287.073523 -379.967537) (xy 287.067752 -379.960378) (xy 287.045931 -379.934676)
			(xy 287.007838 -379.879048) (xy 286.976682 -379.819258) (xy 286.952913 -379.756165) (xy 286.936873 -379.69068)
			(xy 286.928793 -379.623745) (xy 286.928788 -379.556324) (xy 286.936861 -379.489388) (xy 286.952893 -379.423901)
			(xy 286.976654 -379.360806) (xy 287.007802 -379.301011) (xy 287.045889 -379.245378) (xy 287.067752 -379.219714)
			(xy 287.073574 -379.212587) (xy 287.080072 -379.195382) (xy 287.080452 -379.186186) (xy 287.080452 -378.693934)
			(xy 287.080014 -378.68475) (xy 287.073519 -378.667566) (xy 287.067752 -378.660406) (xy 287.045861 -378.634763)
			(xy 287.007769 -378.579126) (xy 286.976617 -378.519328) (xy 286.952852 -378.456228) (xy 286.936817 -378.390735)
			(xy 286.928742 -378.323794) (xy 274.077801 -378.323794) (xy 274.085782 -378.367343) (xy 274.101882 -378.499931)
			(xy 274.109946 -378.633249) (xy 274.11045 -378.70003) (xy 274.109946 -378.766811) (xy 274.101882 -378.900129)
			(xy 274.085782 -379.032717) (xy 274.061707 -379.164091) (xy 274.029744 -379.293772) (xy 273.990009 -379.421286)
			(xy 273.942647 -379.546169) (xy 273.887832 -379.667964) (xy 273.825762 -379.786227) (xy 273.756666 -379.900526)
			(xy 273.680794 -380.010446) (xy 273.598424 -380.115583) (xy 273.509856 -380.215556) (xy 273.415414 -380.309998)
			(xy 273.315441 -380.398566) (xy 273.210304 -380.480936) (xy 273.100384 -380.556808) (xy 272.986085 -380.625904)
			(xy 272.92786 -380.656463) (xy 289.128932 -380.656463) (xy 289.136975 -380.589641) (xy 289.152947 -380.524259)
			(xy 289.17662 -380.461255) (xy 289.207654 -380.401532) (xy 289.245604 -380.345947) (xy 289.267392 -380.320296)
			(xy 289.273172 -380.313139) (xy 289.279697 -380.295958) (xy 289.280092 -380.286768) (xy 289.280092 -379.7935)
			(xy 289.279684 -379.784313) (xy 289.273169 -379.767128) (xy 289.267392 -379.759972) (xy 289.24565 -379.734282)
			(xy 289.207696 -379.678702) (xy 289.176658 -379.618984) (xy 289.15298 -379.555985) (xy 289.137002 -379.490606)
			(xy 289.128953 -379.423787) (xy 289.128949 -379.356485) (xy 289.136989 -379.289665) (xy 289.152959 -379.224284)
			(xy 289.176628 -379.161282) (xy 289.207659 -379.10156) (xy 289.245606 -379.045975) (xy 289.267392 -379.020324)
			(xy 289.273202 -379.013189) (xy 289.279709 -378.995991) (xy 289.280092 -378.986796) (xy 289.280092 -378.828554)
			(xy 289.280595 -378.818399) (xy 289.288376 -378.799638) (xy 289.302738 -378.785276) (xy 289.321499 -378.777495)
			(xy 289.331654 -378.776992) (xy 290.047934 -378.776992) (xy 290.058088 -378.777504) (xy 290.076849 -378.785281)
			(xy 290.091212 -378.799641) (xy 290.098993 -378.8184) (xy 290.099496 -378.828554) (xy 290.099496 -378.986796)
			(xy 290.099909 -378.995983) (xy 290.106421 -379.013167) (xy 290.112196 -379.020324) (xy 290.13403 -379.045938)
			(xy 290.171975 -379.101531) (xy 290.203004 -379.16126) (xy 290.226673 -379.224269) (xy 290.242641 -379.289656)
			(xy 290.250681 -379.356482) (xy 290.250677 -379.42379) (xy 290.242628 -379.490615) (xy 290.226651 -379.556)
			(xy 290.202975 -379.619006) (xy 290.171938 -379.678731) (xy 290.133986 -379.734319) (xy 290.112196 -379.759972)
			(xy 290.106386 -379.767108) (xy 290.099879 -379.784305) (xy 290.099496 -379.7935) (xy 290.099496 -380.286768)
			(xy 290.099922 -380.295953) (xy 290.106425 -380.313138) (xy 290.112196 -380.320296) (xy 290.134002 -380.345932)
			(xy 290.171948 -380.401522) (xy 290.202979 -380.461248) (xy 290.226649 -380.524255) (xy 290.242619 -380.589638)
			(xy 290.250654 -380.656404) (xy 293.528724 -380.656404) (xy 293.536798 -380.589467) (xy 293.552831 -380.52398)
			(xy 293.576592 -380.460884) (xy 293.60774 -380.401088) (xy 293.645826 -380.345453) (xy 293.667688 -380.319788)
			(xy 293.673471 -380.312633) (xy 293.679994 -380.29545) (xy 293.680388 -380.28626) (xy 293.680388 -379.794008)
			(xy 293.679977 -379.784821) (xy 293.673464 -379.767636) (xy 293.667688 -379.76048) (xy 293.645872 -379.734776)
			(xy 293.607782 -379.679146) (xy 293.57663 -379.619356) (xy 293.552864 -379.556264) (xy 293.536825 -379.49078)
			(xy 293.528746 -379.423846) (xy 293.528741 -379.356426) (xy 293.536812 -379.289491) (xy 293.552842 -379.224005)
			(xy 293.576601 -379.16091) (xy 293.607745 -379.101115) (xy 293.645827 -379.045481) (xy 293.667688 -379.019816)
			(xy 293.673501 -379.012683) (xy 293.680006 -378.995483) (xy 293.680388 -378.986288) (xy 293.680388 -378.828554)
			(xy 293.680887 -378.818431) (xy 293.688621 -378.799718) (xy 293.702902 -378.785366) (xy 293.721575 -378.777539)
			(xy 293.731696 -378.776992) (xy 294.447976 -378.776992) (xy 294.458096 -378.777435) (xy 294.476798 -378.785174)
			(xy 294.491112 -378.799482) (xy 294.49886 -378.81818) (xy 294.499284 -378.8283) (xy 294.499284 -378.986288)
			(xy 294.499704 -378.995474) (xy 294.506211 -379.012658) (xy 294.511984 -379.019816) (xy 294.533896 -379.045442)
			(xy 294.571984 -379.101082) (xy 294.603134 -379.160883) (xy 294.626896 -379.223985) (xy 294.642928 -379.289479)
			(xy 294.651001 -379.356422) (xy 294.650996 -379.42385) (xy 294.642915 -379.490792) (xy 294.626874 -379.556284)
			(xy 294.603104 -379.619383) (xy 294.571947 -379.67918) (xy 294.533851 -379.734815) (xy 294.511984 -379.76048)
			(xy 294.506169 -379.767612) (xy 294.499666 -379.784813) (xy 294.499284 -379.794008) (xy 294.499284 -380.28626)
			(xy 294.499717 -380.295445) (xy 294.506215 -380.312629) (xy 294.511984 -380.319788) (xy 294.533868 -380.345437)
			(xy 294.571957 -380.401073) (xy 294.603108 -380.460872) (xy 294.626872 -380.523971) (xy 294.642906 -380.589462)
			(xy 294.650981 -380.656402) (xy 294.650981 -380.656463) (xy 297.92902 -380.656463) (xy 297.937062 -380.589641)
			(xy 297.953034 -380.52426) (xy 297.976707 -380.461256) (xy 298.00774 -380.401533) (xy 298.045688 -380.345948)
			(xy 298.067476 -380.320296) (xy 298.073254 -380.313137) (xy 298.079781 -380.295957) (xy 298.080176 -380.286768)
			(xy 298.080176 -379.7935) (xy 298.079771 -379.784312) (xy 298.073254 -379.767128) (xy 298.067476 -379.759972)
			(xy 298.045734 -379.734282) (xy 298.007782 -379.678701) (xy 297.976744 -379.618984) (xy 297.953067 -379.555984)
			(xy 297.93709 -379.490606) (xy 297.929041 -379.423787) (xy 297.929037 -379.356485) (xy 297.937077 -379.289665)
			(xy 297.953046 -379.224285) (xy 297.976715 -379.161283) (xy 298.007745 -379.101561) (xy 298.04569 -379.045976)
			(xy 298.067476 -379.020324) (xy 298.073285 -379.013187) (xy 298.079793 -378.99599) (xy 298.080176 -378.986796)
			(xy 298.080176 -378.828554) (xy 298.080597 -378.818389) (xy 298.088393 -378.799611) (xy 298.102782 -378.785246)
			(xy 298.121572 -378.77748) (xy 298.131738 -378.776992) (xy 298.848018 -378.776992) (xy 298.858171 -378.777517)
			(xy 298.876932 -378.785289) (xy 298.891295 -378.799644) (xy 298.899077 -378.818401) (xy 298.89958 -378.828554)
			(xy 298.89958 -378.986796) (xy 298.899996 -378.995982) (xy 298.906506 -379.013167) (xy 298.91228 -379.020324)
			(xy 298.934114 -379.045938) (xy 298.972061 -379.10153) (xy 299.003091 -379.161259) (xy 299.02676 -379.224269)
			(xy 299.042729 -379.289655) (xy 299.050769 -379.356482) (xy 299.050765 -379.42379) (xy 299.042716 -379.490616)
			(xy 299.026739 -379.556) (xy 299.003061 -379.619007) (xy 298.972023 -379.678732) (xy 298.93407 -379.73432)
			(xy 298.91228 -379.759972) (xy 298.906468 -379.767106) (xy 298.899963 -379.784305) (xy 298.89958 -379.7935)
			(xy 298.89958 -380.286768) (xy 298.90001 -380.295953) (xy 298.90651 -380.313137) (xy 298.91228 -380.320296)
			(xy 298.934087 -380.345932) (xy 298.972034 -380.401521) (xy 299.003065 -380.461247) (xy 299.026736 -380.524254)
			(xy 299.042707 -380.589638) (xy 299.050742 -380.656404) (xy 302.328812 -380.656404) (xy 302.336886 -380.589468)
			(xy 302.352918 -380.52398) (xy 302.376679 -380.460884) (xy 302.407826 -380.401089) (xy 302.44591 -380.345454)
			(xy 302.467772 -380.319788) (xy 302.473565 -380.312641) (xy 302.48008 -380.295451) (xy 302.480472 -380.28626)
			(xy 302.480472 -379.794008) (xy 302.480064 -379.78482) (xy 302.47355 -379.767636) (xy 302.467772 -379.76048)
			(xy 302.445956 -379.734775) (xy 302.407868 -379.679146) (xy 302.376717 -379.619355) (xy 302.352951 -379.556263)
			(xy 302.336913 -379.490779) (xy 302.328834 -379.423846) (xy 302.328829 -379.356426) (xy 302.3369 -379.289492)
			(xy 302.35293 -379.224006) (xy 302.376687 -379.160911) (xy 302.407831 -379.101116) (xy 302.445912 -379.045482)
			(xy 302.467772 -379.019816) (xy 302.473595 -379.01269) (xy 302.480092 -378.995485) (xy 302.480472 -378.986288)
			(xy 302.480472 -378.828554) (xy 302.48089 -378.81842) (xy 302.488639 -378.799692) (xy 302.502946 -378.785336)
			(xy 302.521648 -378.777525) (xy 302.53178 -378.776992) (xy 303.24806 -378.776992) (xy 303.258211 -378.777454)
			(xy 303.27696 -378.785235) (xy 303.291285 -378.79962) (xy 303.298987 -378.818402) (xy 303.299368 -378.828554)
			(xy 303.299368 -378.986288) (xy 303.299791 -378.995474) (xy 303.306296 -379.012658) (xy 303.312068 -379.019816)
			(xy 303.33398 -379.045442) (xy 303.37207 -379.101081) (xy 303.40322 -379.160883) (xy 303.426983 -379.223985)
			(xy 303.443016 -379.289479) (xy 303.451089 -379.356422) (xy 303.451084 -379.42385) (xy 303.443003 -379.490792)
			(xy 303.426962 -379.556284) (xy 303.403191 -379.619383) (xy 303.372032 -379.679181) (xy 303.333936 -379.734815)
			(xy 303.312068 -379.76048) (xy 303.306251 -379.76761) (xy 303.299749 -379.784812) (xy 303.299368 -379.794008)
			(xy 303.299368 -380.28626) (xy 303.299805 -380.295444) (xy 303.306301 -380.312628) (xy 303.312068 -380.319788)
			(xy 303.333953 -380.345436) (xy 303.372043 -380.401073) (xy 303.403195 -380.460871) (xy 303.426959 -380.52397)
			(xy 303.442994 -380.589461) (xy 303.451069 -380.656402) (xy 303.451069 -380.656404) (xy 333.128842 -380.656404)
			(xy 333.136916 -380.589467) (xy 333.15295 -380.523979) (xy 333.176713 -380.460883) (xy 333.207862 -380.401087)
			(xy 333.245949 -380.345453) (xy 333.267812 -380.319788) (xy 333.273598 -380.312635) (xy 333.280118 -380.29545)
			(xy 333.280512 -380.28626) (xy 333.280512 -379.794008) (xy 333.280095 -379.784822) (xy 333.273586 -379.767637)
			(xy 333.267812 -379.76048) (xy 333.245995 -379.734776) (xy 333.207904 -379.679147) (xy 333.17675 -379.619357)
			(xy 333.152983 -379.556265) (xy 333.136944 -379.49078) (xy 333.128864 -379.423846) (xy 333.12886 -379.356426)
			(xy 333.136931 -379.289491) (xy 333.152962 -379.224004) (xy 333.176721 -379.160909) (xy 333.207867 -379.101115)
			(xy 333.24595 -379.045481) (xy 333.267812 -379.019816) (xy 333.273628 -379.012685) (xy 333.280131 -378.995483)
			(xy 333.280512 -378.986288) (xy 333.280512 -378.828554) (xy 333.280988 -378.818428) (xy 333.288726 -378.799711)
			(xy 333.303015 -378.785357) (xy 333.321696 -378.777535) (xy 333.33182 -378.776992) (xy 334.0481 -378.776992)
			(xy 334.058253 -378.777422) (xy 334.077004 -378.785216) (xy 334.091327 -378.79961) (xy 334.099028 -378.818399)
			(xy 334.099408 -378.828554) (xy 334.099408 -378.986288) (xy 334.099822 -378.995475) (xy 334.106333 -379.012659)
			(xy 334.112108 -379.019816) (xy 334.134019 -379.045442) (xy 334.172106 -379.101083) (xy 334.203254 -379.160884)
			(xy 334.227015 -379.223986) (xy 334.243047 -379.28948) (xy 334.251119 -379.356422) (xy 334.251114 -379.42385)
			(xy 334.243034 -379.490791) (xy 334.226994 -379.556283) (xy 334.203224 -379.619382) (xy 334.172068 -379.679179)
			(xy 334.133975 -379.734815) (xy 334.112108 -379.76048) (xy 334.106296 -379.767614) (xy 334.09979 -379.784813)
			(xy 334.099408 -379.794008) (xy 334.099408 -380.28626) (xy 334.099836 -380.295445) (xy 334.106337 -380.31263)
			(xy 334.112108 -380.319788) (xy 334.133991 -380.345437) (xy 334.172079 -380.401074) (xy 334.203228 -380.460873)
			(xy 334.226991 -380.523972) (xy 334.243025 -380.589463) (xy 334.251099 -380.656402) (xy 334.251099 -380.656464)
			(xy 337.529162 -380.656464) (xy 337.537203 -380.589643) (xy 337.553173 -380.524262) (xy 337.576842 -380.461259)
			(xy 337.607871 -380.401536) (xy 337.645815 -380.345949) (xy 337.6676 -380.320296) (xy 337.673381 -380.31314)
			(xy 337.679905 -380.295958) (xy 337.6803 -380.286768) (xy 337.6803 -379.7935) (xy 337.67989 -379.784313)
			(xy 337.673376 -379.767129) (xy 337.6676 -379.759972) (xy 337.645861 -379.734281) (xy 337.607913 -379.678699)
			(xy 337.57688 -379.61898) (xy 337.553206 -379.555981) (xy 337.537231 -379.490604) (xy 337.529183 -379.423786)
			(xy 337.529179 -379.356486) (xy 337.537218 -379.289667) (xy 337.553185 -379.224288) (xy 337.57685 -379.161286)
			(xy 337.607876 -379.101563) (xy 337.645816 -379.045977) (xy 337.6676 -379.020324) (xy 337.673411 -379.013189)
			(xy 337.679917 -378.995991) (xy 337.6803 -378.986796) (xy 337.6803 -378.828554) (xy 337.680795 -378.818398)
			(xy 337.688577 -378.799635) (xy 337.702942 -378.785273) (xy 337.721706 -378.777493) (xy 337.731862 -378.776992)
			(xy 338.448142 -378.776992) (xy 338.458297 -378.777498) (xy 338.477058 -378.785278) (xy 338.49142 -378.799639)
			(xy 338.499201 -378.818399) (xy 338.499704 -378.828554) (xy 338.499704 -378.986796) (xy 338.500115 -378.995983)
			(xy 338.506628 -379.013167) (xy 338.512404 -379.020324) (xy 338.534237 -379.045938) (xy 338.572182 -379.101531)
			(xy 338.603211 -379.16126) (xy 338.626879 -379.22427) (xy 338.642847 -379.289656) (xy 338.650887 -379.356482)
			(xy 338.650883 -379.42379) (xy 338.642834 -379.490615) (xy 338.626858 -379.556) (xy 338.603181 -379.619006)
			(xy 338.572145 -379.678731) (xy 338.534193 -379.734319) (xy 338.512404 -379.759972) (xy 338.506595 -379.767108)
			(xy 338.500088 -379.784306) (xy 338.499704 -379.7935) (xy 338.499704 -380.286768) (xy 338.500129 -380.295954)
			(xy 338.506632 -380.313138) (xy 338.512404 -380.320296) (xy 338.53421 -380.345933) (xy 338.572155 -380.401522)
			(xy 338.603185 -380.461248) (xy 338.626855 -380.524255) (xy 338.642826 -380.589639) (xy 338.65086 -380.656404)
			(xy 341.92893 -380.656404) (xy 341.937004 -380.589467) (xy 341.953037 -380.523979) (xy 341.976799 -380.460883)
			(xy 342.007947 -380.401088) (xy 342.046033 -380.345453) (xy 342.067896 -380.319788) (xy 342.07368 -380.312634)
			(xy 342.080202 -380.29545) (xy 342.080596 -380.28626) (xy 342.080596 -379.794008) (xy 342.080183 -379.784821)
			(xy 342.073671 -379.767637) (xy 342.067896 -379.76048) (xy 342.046079 -379.734776) (xy 342.007989 -379.679147)
			(xy 341.976837 -379.619356) (xy 341.95307 -379.556264) (xy 341.937032 -379.49078) (xy 341.928952 -379.423846)
			(xy 341.928948 -379.356426) (xy 341.937019 -379.289491) (xy 341.953049 -379.224005) (xy 341.976807 -379.16091)
			(xy 342.007952 -379.101115) (xy 342.046035 -379.045481) (xy 342.067896 -379.019816) (xy 342.07371 -379.012683)
			(xy 342.080215 -378.995483) (xy 342.080596 -378.986288) (xy 342.080596 -378.828554) (xy 342.081088 -378.81843)
			(xy 342.088822 -378.799716) (xy 342.103106 -378.785363) (xy 342.121782 -378.777538) (xy 342.131904 -378.776992)
			(xy 342.848184 -378.776992) (xy 342.858336 -378.777434) (xy 342.877087 -378.785223) (xy 342.89141 -378.799614)
			(xy 342.899112 -378.8184) (xy 342.899492 -378.828554) (xy 342.899492 -378.986288) (xy 342.89991 -378.995474)
			(xy 342.906418 -379.012659) (xy 342.912192 -379.019816) (xy 342.934103 -379.045442) (xy 342.972191 -379.101082)
			(xy 343.00334 -379.160884) (xy 343.027102 -379.223986) (xy 343.043135 -379.28948) (xy 343.051207 -379.356422)
			(xy 343.051202 -379.42385) (xy 343.043122 -379.490792) (xy 343.027081 -379.556283) (xy 343.003311 -379.619382)
			(xy 342.972154 -379.67918) (xy 342.934059 -379.734815) (xy 342.912192 -379.76048) (xy 342.906378 -379.767613)
			(xy 342.899874 -379.784813) (xy 342.899492 -379.794008) (xy 342.899492 -380.28626) (xy 342.899923 -380.295445)
			(xy 342.906422 -380.312629) (xy 342.912192 -380.319788) (xy 342.934076 -380.345437) (xy 342.972165 -380.401074)
			(xy 343.003315 -380.460872) (xy 343.027078 -380.523971) (xy 343.043113 -380.589462) (xy 343.051187 -380.656402)
			(xy 343.051187 -380.656463) (xy 346.329226 -380.656463) (xy 346.337269 -380.589641) (xy 346.353241 -380.524259)
			(xy 346.376913 -380.461255) (xy 346.407947 -380.401533) (xy 346.445896 -380.345948) (xy 346.467684 -380.320296)
			(xy 346.473463 -380.313138) (xy 346.479989 -380.295957) (xy 346.480384 -380.286768) (xy 346.480384 -379.7935)
			(xy 346.479977 -379.784312) (xy 346.473462 -379.767128) (xy 346.467684 -379.759972) (xy 346.445942 -379.734282)
			(xy 346.407989 -379.678702) (xy 346.376951 -379.618984) (xy 346.353274 -379.555984) (xy 346.337296 -379.490606)
			(xy 346.329247 -379.423787) (xy 346.329243 -379.356485) (xy 346.337283 -379.289665) (xy 346.353252 -379.224285)
			(xy 346.376922 -379.161282) (xy 346.407952 -379.10156) (xy 346.445898 -379.045976) (xy 346.467684 -379.020324)
			(xy 346.473493 -379.013188) (xy 346.480001 -378.99599) (xy 346.480384 -378.986796) (xy 346.480384 -378.828554)
			(xy 346.480797 -378.818388) (xy 346.488595 -378.799609) (xy 346.502986 -378.785243) (xy 346.521779 -378.777479)
			(xy 346.531946 -378.776992) (xy 347.248226 -378.776992) (xy 347.25838 -378.777511) (xy 347.277141 -378.785285)
			(xy 347.291504 -378.799642) (xy 347.299285 -378.8184) (xy 347.299788 -378.828554) (xy 347.299788 -378.986796)
			(xy 347.300203 -378.995983) (xy 347.306714 -379.013167) (xy 347.312488 -379.020324) (xy 347.334322 -379.045938)
			(xy 347.372268 -379.10153) (xy 347.403297 -379.161259) (xy 347.426966 -379.224269) (xy 347.442935 -379.289656)
			(xy 347.450975 -379.356482) (xy 347.450971 -379.42379) (xy 347.442922 -379.490616) (xy 347.426945 -379.556)
			(xy 347.403268 -379.619007) (xy 347.372231 -379.678732) (xy 347.334278 -379.734319) (xy 347.312488 -379.759972)
			(xy 347.306677 -379.767107) (xy 347.300171 -379.784305) (xy 347.299788 -379.7935) (xy 347.299788 -380.286768)
			(xy 347.300216 -380.295953) (xy 347.306718 -380.313138) (xy 347.312488 -380.320296) (xy 347.334295 -380.345932)
			(xy 347.372241 -380.401522) (xy 347.403272 -380.461248) (xy 347.426942 -380.524254) (xy 347.442913 -380.589638)
			(xy 347.450948 -380.656404) (xy 377.128751 -380.656404) (xy 377.136826 -380.589466) (xy 377.15286 -380.523978)
			(xy 377.176623 -380.460882) (xy 377.207772 -380.401087) (xy 377.24586 -380.345453) (xy 377.267724 -380.319788)
			(xy 377.273511 -380.312636) (xy 377.280031 -380.295451) (xy 377.280424 -380.28626) (xy 377.280424 -379.794008)
			(xy 377.280005 -379.784822) (xy 377.273497 -379.767638) (xy 377.267724 -379.76048) (xy 377.245906 -379.734776)
			(xy 377.207815 -379.679148) (xy 377.17666 -379.619357) (xy 377.152893 -379.556265) (xy 377.136853 -379.490781)
			(xy 377.128773 -379.423846) (xy 377.128769 -379.356426) (xy 377.13684 -379.28949) (xy 377.152871 -379.224004)
			(xy 377.176631 -379.160909) (xy 377.207777 -379.101114) (xy 377.245862 -379.045481) (xy 377.267724 -379.019816)
			(xy 377.273542 -379.012686) (xy 377.280043 -378.995484) (xy 377.280424 -378.986288) (xy 377.280424 -378.828554)
			(xy 377.280888 -378.818426) (xy 377.288628 -378.799707) (xy 377.302921 -378.785353) (xy 377.321607 -378.777533)
			(xy 377.331732 -378.776992) (xy 378.048012 -378.776992) (xy 378.058166 -378.777411) (xy 378.076917 -378.785209)
			(xy 378.09124 -378.799607) (xy 378.098941 -378.818398) (xy 378.09932 -378.828554) (xy 378.09932 -378.986288)
			(xy 378.099731 -378.995475) (xy 378.106244 -379.01266) (xy 378.11202 -379.019816) (xy 378.13393 -379.045443)
			(xy 378.172016 -379.101083) (xy 378.203164 -379.160885) (xy 378.226924 -379.223987) (xy 378.242956 -379.28948)
			(xy 378.251028 -379.356423) (xy 378.251023 -379.42385) (xy 378.242943 -379.490791) (xy 378.226903 -379.556282)
			(xy 378.203134 -379.619381) (xy 378.171979 -379.679179) (xy 378.133886 -379.734814) (xy 378.11202 -379.76048)
			(xy 378.106209 -379.767615) (xy 378.099702 -379.784813) (xy 378.09932 -379.794008) (xy 378.09932 -380.28626)
			(xy 378.099745 -380.295446) (xy 378.106248 -380.312631) (xy 378.11202 -380.319788) (xy 378.133903 -380.345437)
			(xy 378.17199 -380.401075) (xy 378.203138 -380.460873) (xy 378.226901 -380.523972) (xy 378.242934 -380.589463)
			(xy 378.251008 -380.656403) (xy 378.251008 -380.656464) (xy 381.529071 -380.656464) (xy 381.537113 -380.589643)
			(xy 381.553083 -380.524262) (xy 381.576752 -380.461258) (xy 381.607782 -380.401535) (xy 381.645726 -380.345948)
			(xy 381.667512 -380.320296) (xy 381.673294 -380.313141) (xy 381.679817 -380.295958) (xy 381.680212 -380.286768)
			(xy 381.680212 -379.7935) (xy 381.679799 -379.784313) (xy 381.673287 -379.767129) (xy 381.667512 -379.759972)
			(xy 381.645773 -379.73428) (xy 381.607824 -379.678699) (xy 381.57679 -379.618981) (xy 381.553116 -379.555981)
			(xy 381.537141 -379.490604) (xy 381.529093 -379.423786) (xy 381.529089 -379.356486) (xy 381.537128 -379.289667)
			(xy 381.553095 -379.224288) (xy 381.576761 -379.161285) (xy 381.607787 -379.101563) (xy 381.645728 -379.045977)
			(xy 381.667512 -379.020324) (xy 381.673325 -379.01319) (xy 381.679829 -378.995991) (xy 381.680212 -378.986796)
			(xy 381.680212 -378.828554) (xy 381.680695 -378.818397) (xy 381.68848 -378.799631) (xy 381.702848 -378.785269)
			(xy 381.721616 -378.777491) (xy 381.731774 -378.776992) (xy 382.448054 -378.776992) (xy 382.458203 -378.77757)
			(xy 382.476962 -378.785321) (xy 382.491328 -378.79966) (xy 382.499112 -378.818406) (xy 382.499616 -378.828554)
			(xy 382.499616 -378.986796) (xy 382.500025 -378.995983) (xy 382.506539 -379.013168) (xy 382.512316 -379.020324)
			(xy 382.534153 -379.045936) (xy 382.572103 -379.101528) (xy 382.603137 -379.161256) (xy 382.626809 -379.224266)
			(xy 382.64278 -379.289654) (xy 382.650821 -379.356481) (xy 382.650816 -379.423791) (xy 382.642767 -379.490618)
			(xy 382.626787 -379.556003) (xy 382.603107 -379.61901) (xy 382.572066 -379.678734) (xy 382.534108 -379.734321)
			(xy 382.512316 -379.759972) (xy 382.506508 -379.767109) (xy 382.5 -379.784306) (xy 382.499616 -379.7935)
			(xy 382.499616 -380.286768) (xy 382.500038 -380.295954) (xy 382.506543 -380.313139) (xy 382.512316 -380.320296)
			(xy 382.534125 -380.345931) (xy 382.572076 -380.401519) (xy 382.603111 -380.461245) (xy 382.626784 -380.524251)
			(xy 382.642757 -380.589636) (xy 382.650793 -380.656404) (xy 385.928839 -380.656404) (xy 385.936913 -380.589467)
			(xy 385.952947 -380.523979) (xy 385.976709 -380.460883) (xy 386.007858 -380.401087) (xy 386.045945 -380.345453)
			(xy 386.067808 -380.319788) (xy 386.073593 -380.312635) (xy 386.080114 -380.29545) (xy 386.080508 -380.28626)
			(xy 386.080508 -379.794008) (xy 386.080092 -379.784821) (xy 386.073582 -379.767637) (xy 386.067808 -379.76048)
			(xy 386.045991 -379.734776) (xy 386.0079 -379.679147) (xy 385.976747 -379.619356) (xy 385.95298 -379.556265)
			(xy 385.936941 -379.49078) (xy 385.928861 -379.423846) (xy 385.928857 -379.356426) (xy 385.936928 -379.289491)
			(xy 385.952958 -379.224004) (xy 385.976718 -379.160909) (xy 386.007863 -379.101115) (xy 386.045947 -379.045481)
			(xy 386.067808 -379.019816) (xy 386.073624 -379.012684) (xy 386.080127 -378.995483) (xy 386.080508 -378.986288)
			(xy 386.080508 -378.828554) (xy 386.080988 -378.818428) (xy 386.088725 -378.799712) (xy 386.103012 -378.785359)
			(xy 386.121693 -378.777535) (xy 386.131816 -378.776992) (xy 386.848096 -378.776992) (xy 386.858249 -378.777425)
			(xy 386.877 -378.785218) (xy 386.891323 -378.799611) (xy 386.899024 -378.818399) (xy 386.899404 -378.828554)
			(xy 386.899404 -378.986288) (xy 386.899819 -378.995475) (xy 386.906329 -379.012659) (xy 386.912104 -379.019816)
			(xy 386.934015 -379.045442) (xy 386.972102 -379.101083) (xy 387.00325 -379.160884) (xy 387.027012 -379.223986)
			(xy 387.043044 -379.28948) (xy 387.051116 -379.356422) (xy 387.051111 -379.42385) (xy 387.043031 -379.490791)
			(xy 387.02699 -379.556283) (xy 387.003221 -379.619382) (xy 386.972065 -379.679179) (xy 386.933971 -379.734815)
			(xy 386.912104 -379.76048) (xy 386.906291 -379.767614) (xy 386.899786 -379.784813) (xy 386.899404 -379.794008)
			(xy 386.899404 -380.28626) (xy 386.899832 -380.295445) (xy 386.906333 -380.31263) (xy 386.912104 -380.319788)
			(xy 386.933987 -380.345437) (xy 386.972075 -380.401074) (xy 387.003225 -380.460872) (xy 387.026988 -380.523971)
			(xy 387.043022 -380.589462) (xy 387.051096 -380.656402) (xy 387.051096 -380.656464) (xy 390.329159 -380.656464)
			(xy 390.3372 -380.589643) (xy 390.35317 -380.524263) (xy 390.376839 -380.461259) (xy 390.407867 -380.401536)
			(xy 390.445811 -380.345949) (xy 390.467596 -380.320296) (xy 390.473376 -380.313139) (xy 390.479901 -380.295958)
			(xy 390.480296 -380.286768) (xy 390.480296 -379.7935) (xy 390.479887 -379.784313) (xy 390.473372 -379.767128)
			(xy 390.467596 -379.759972) (xy 390.445857 -379.73428) (xy 390.407909 -379.678699) (xy 390.376876 -379.61898)
			(xy 390.353203 -379.555981) (xy 390.337228 -379.490604) (xy 390.32918 -379.423786) (xy 390.329176 -379.356486)
			(xy 390.337215 -379.289667) (xy 390.353181 -379.224288) (xy 390.376847 -379.161286) (xy 390.407872 -379.101563)
			(xy 390.445812 -379.045977) (xy 390.467596 -379.020324) (xy 390.473407 -379.013189) (xy 390.479913 -378.995991)
			(xy 390.480296 -378.986796) (xy 390.480296 -378.828554) (xy 390.480795 -378.818398) (xy 390.488576 -378.799636)
			(xy 390.50294 -378.785274) (xy 390.521702 -378.777494) (xy 390.531858 -378.776992) (xy 391.248138 -378.776992)
			(xy 391.258293 -378.777501) (xy 391.277054 -378.785279) (xy 391.291416 -378.79964) (xy 391.299197 -378.8184)
			(xy 391.2997 -378.828554) (xy 391.2997 -378.986796) (xy 391.300112 -378.995983) (xy 391.306625 -379.013167)
			(xy 391.3124 -379.020324) (xy 391.334234 -379.045938) (xy 391.372178 -379.101531) (xy 391.403207 -379.16126)
			(xy 391.426876 -379.224269) (xy 391.442844 -379.289656) (xy 391.450884 -379.356482) (xy 391.45088 -379.42379)
			(xy 391.442831 -379.490615) (xy 391.426855 -379.556) (xy 391.403178 -379.619006) (xy 391.372141 -379.678731)
			(xy 391.334189 -379.734319) (xy 391.3124 -379.759972) (xy 391.30659 -379.767108) (xy 391.300083 -379.784306)
			(xy 391.2997 -379.7935) (xy 391.2997 -380.286768) (xy 391.300126 -380.295954) (xy 391.306629 -380.313138)
			(xy 391.3124 -380.320296) (xy 391.334206 -380.345933) (xy 391.372152 -380.401522) (xy 391.403182 -380.461248)
			(xy 391.426852 -380.524255) (xy 391.442822 -380.589638) (xy 391.450857 -380.656404) (xy 421.12866 -380.656404)
			(xy 421.136735 -380.589466) (xy 421.152769 -380.523978) (xy 421.176533 -380.460881) (xy 421.207683 -380.401086)
			(xy 421.245772 -380.345453) (xy 421.267636 -380.319788) (xy 421.273425 -380.312637) (xy 421.279943 -380.295451)
			(xy 421.280336 -380.28626) (xy 421.280336 -379.794008) (xy 421.279914 -379.784822) (xy 421.273408 -379.767638)
			(xy 421.267636 -379.76048) (xy 421.245818 -379.734776) (xy 421.207725 -379.679148) (xy 421.176571 -379.619358)
			(xy 421.152802 -379.556266) (xy 421.136762 -379.490781) (xy 421.128682 -379.423846) (xy 421.128678 -379.356426)
			(xy 421.136749 -379.28949) (xy 421.152781 -379.224003) (xy 421.176541 -379.160908) (xy 421.207688 -379.101114)
			(xy 421.245774 -379.045481) (xy 421.267636 -379.019816) (xy 421.273455 -379.012687) (xy 421.279956 -378.995484)
			(xy 421.280336 -378.986288) (xy 421.280336 -378.828554) (xy 421.280789 -378.818425) (xy 421.288531 -378.799703)
			(xy 421.302827 -378.785349) (xy 421.321517 -378.777531) (xy 421.331644 -378.776992) (xy 422.047924 -378.776992)
			(xy 422.058033 -378.777465) (xy 422.076711 -378.785209) (xy 422.091004 -378.79951) (xy 422.09874 -378.81819)
			(xy 422.099232 -378.8283) (xy 422.099232 -378.986288) (xy 422.099663 -378.995473) (xy 422.106164 -379.012656)
			(xy 422.111932 -379.019816) (xy 422.133842 -379.045443) (xy 422.171927 -379.101084) (xy 422.203074 -379.160885)
			(xy 422.226834 -379.223987) (xy 422.242865 -379.289481) (xy 422.250937 -379.356423) (xy 422.250932 -379.423849)
			(xy 422.242852 -379.49079) (xy 422.226813 -379.556282) (xy 422.203045 -379.61938) (xy 422.17189 -379.679178)
			(xy 422.133798 -379.734814) (xy 422.111932 -379.76048) (xy 422.106111 -379.767607) (xy 422.099613 -379.784812)
			(xy 422.099232 -379.794008) (xy 422.099232 -380.28626) (xy 422.099677 -380.295443) (xy 422.106168 -380.312627)
			(xy 422.111932 -380.319788) (xy 422.133814 -380.345438) (xy 422.171901 -380.401075) (xy 422.203049 -380.460874)
			(xy 422.22681 -380.523973) (xy 422.242843 -380.589463) (xy 422.250917 -380.656403) (xy 422.250917 -380.656463)
			(xy 425.52898 -380.656463) (xy 425.537022 -380.589642) (xy 425.552992 -380.524262) (xy 425.576662 -380.461258)
			(xy 425.607692 -380.401535) (xy 425.645638 -380.345948) (xy 425.667424 -380.320296) (xy 425.673208 -380.313142)
			(xy 425.679729 -380.295958) (xy 425.680124 -380.286768) (xy 425.680124 -379.7935) (xy 425.679709 -379.784313)
			(xy 425.673198 -379.767129) (xy 425.667424 -379.759972) (xy 425.645684 -379.734281) (xy 425.607735 -379.678699)
			(xy 425.5767 -379.618981) (xy 425.553026 -379.555982) (xy 425.53705 -379.490605) (xy 425.529002 -379.423787)
			(xy 425.528998 -379.356486) (xy 425.537037 -379.289667) (xy 425.553004 -379.224287) (xy 425.576671 -379.161285)
			(xy 425.607698 -379.101563) (xy 425.64564 -379.045977) (xy 425.667424 -379.020324) (xy 425.673238 -379.013191)
			(xy 425.679742 -378.995991) (xy 425.680124 -378.986796) (xy 425.680124 -378.828554) (xy 425.680595 -378.818395)
			(xy 425.688382 -378.799628) (xy 425.702754 -378.785264) (xy 425.721527 -378.777489) (xy 425.731686 -378.776992)
			(xy 426.447966 -378.776992) (xy 426.458116 -378.77756) (xy 426.476875 -378.785315) (xy 426.49124 -378.799657)
			(xy 426.499024 -378.818405) (xy 426.499528 -378.828554) (xy 426.499528 -378.986796) (xy 426.499934 -378.995984)
			(xy 426.50645 -379.013168) (xy 426.512228 -379.020324) (xy 426.534064 -379.045937) (xy 426.572014 -379.101528)
			(xy 426.603047 -379.161257) (xy 426.626718 -379.224267) (xy 426.642689 -379.289654) (xy 426.65073 -379.356481)
			(xy 426.650725 -379.423791) (xy 426.642676 -379.490617) (xy 426.626697 -379.556003) (xy 426.603017 -379.619009)
			(xy 426.571977 -379.678734) (xy 426.53402 -379.73432) (xy 426.512228 -379.759972) (xy 426.50641 -379.767101)
			(xy 426.49991 -379.784304) (xy 426.499528 -379.7935) (xy 426.499528 -380.286768) (xy 426.499947 -380.295954)
			(xy 426.506454 -380.313139) (xy 426.512228 -380.320296) (xy 426.534036 -380.345932) (xy 426.571987 -380.40152)
			(xy 426.603021 -380.461245) (xy 426.626694 -380.524252) (xy 426.642667 -380.589636) (xy 426.650703 -380.656404)
			(xy 429.928748 -380.656404) (xy 429.936823 -380.589467) (xy 429.952857 -380.523978) (xy 429.976619 -380.460882)
			(xy 430.007769 -380.401087) (xy 430.045857 -380.345453) (xy 430.06772 -380.319788) (xy 430.073506 -380.312636)
			(xy 430.080027 -380.295451) (xy 430.08042 -380.28626) (xy 430.08042 -379.794008) (xy 430.080001 -379.784822)
			(xy 430.073493 -379.767638) (xy 430.06772 -379.76048) (xy 430.045902 -379.734776) (xy 430.007811 -379.679148)
			(xy 429.976657 -379.619357) (xy 429.952889 -379.556265) (xy 429.93685 -379.490781) (xy 429.92877 -379.423846)
			(xy 429.928766 -379.356426) (xy 429.936837 -379.289491) (xy 429.952868 -379.224004) (xy 429.976628 -379.160909)
			(xy 430.007774 -379.101114) (xy 430.045858 -379.045481) (xy 430.06772 -379.019816) (xy 430.073537 -379.012685)
			(xy 430.080039 -378.995484) (xy 430.08042 -378.986288) (xy 430.08042 -378.828554) (xy 430.080888 -378.818427)
			(xy 430.088628 -378.799708) (xy 430.102919 -378.785354) (xy 430.121603 -378.777533) (xy 430.131728 -378.776992)
			(xy 430.848008 -378.776992) (xy 430.858162 -378.777415) (xy 430.876913 -378.785212) (xy 430.891235 -378.799608)
			(xy 430.898936 -378.818398) (xy 430.899316 -378.828554) (xy 430.899316 -378.986288) (xy 430.899728 -378.995475)
			(xy 430.90624 -379.01266) (xy 430.912016 -379.019816) (xy 430.933927 -379.045443) (xy 430.972013 -379.101083)
			(xy 431.003161 -379.160885) (xy 431.026921 -379.223987) (xy 431.042953 -379.28948) (xy 431.051025 -379.356422)
			(xy 431.05102 -379.42385) (xy 431.04294 -379.490791) (xy 431.0269 -379.556282) (xy 431.003131 -379.619381)
			(xy 430.971976 -379.679179) (xy 430.933882 -379.734814) (xy 430.912016 -379.76048) (xy 430.906205 -379.767615)
			(xy 430.899698 -379.784813) (xy 430.899316 -379.794008) (xy 430.899316 -380.28626) (xy 430.899742 -380.295446)
			(xy 430.906244 -380.31263) (xy 430.912016 -380.319788) (xy 430.933899 -380.345437) (xy 430.971986 -380.401074)
			(xy 431.003135 -380.460873) (xy 431.026897 -380.523972) (xy 431.042931 -380.589463) (xy 431.051005 -380.656403)
			(xy 431.051005 -380.656464) (xy 434.329068 -380.656464) (xy 434.33711 -380.589643) (xy 434.35308 -380.524262)
			(xy 434.376749 -380.461259) (xy 434.407778 -380.401535) (xy 434.445722 -380.345949) (xy 434.467508 -380.320296)
			(xy 434.47329 -380.31314) (xy 434.479813 -380.295958) (xy 434.480208 -380.286768) (xy 434.480208 -379.7935)
			(xy 434.479796 -379.784313) (xy 434.473283 -379.767129) (xy 434.467508 -379.759972) (xy 434.445769 -379.73428)
			(xy 434.407821 -379.678699) (xy 434.376787 -379.61898) (xy 434.353113 -379.555981) (xy 434.337137 -379.490604)
			(xy 434.32909 -379.423786) (xy 434.329086 -379.356486) (xy 434.337125 -379.289667) (xy 434.353091 -379.224288)
			(xy 434.376757 -379.161286) (xy 434.407783 -379.101563) (xy 434.445724 -379.045977) (xy 434.467508 -379.020324)
			(xy 434.47332 -379.01319) (xy 434.479825 -378.995991) (xy 434.480208 -378.986796) (xy 434.480208 -378.828554)
			(xy 434.480695 -378.818397) (xy 434.488479 -378.799633) (xy 434.502846 -378.78527) (xy 434.521613 -378.777492)
			(xy 434.53177 -378.776992) (xy 435.24805 -378.776992) (xy 435.258213 -378.777504) (xy 435.276998 -378.785264)
			(xy 435.291383 -378.799622) (xy 435.299177 -378.818392) (xy 435.299612 -378.828554) (xy 435.299612 -378.986796)
			(xy 435.300021 -378.995983) (xy 435.306535 -379.013168) (xy 435.312312 -379.020324) (xy 435.334148 -379.045937)
			(xy 435.372099 -379.101528) (xy 435.403133 -379.161256) (xy 435.426805 -379.224266) (xy 435.442776 -379.289654)
			(xy 435.450817 -379.356481) (xy 435.450813 -379.423791) (xy 435.442763 -379.490618) (xy 435.426784 -379.556003)
			(xy 435.403103 -379.61901) (xy 435.372062 -379.678734) (xy 435.334104 -379.73432) (xy 435.312312 -379.759972)
			(xy 435.306504 -379.767109) (xy 435.299996 -379.784306) (xy 435.299612 -379.7935) (xy 435.299612 -380.286768)
			(xy 435.300035 -380.295954) (xy 435.306539 -380.313139) (xy 435.312312 -380.320296) (xy 435.334121 -380.345931)
			(xy 435.372072 -380.401519) (xy 435.403107 -380.461244) (xy 435.426781 -380.524251) (xy 435.442754 -380.589636)
			(xy 435.450797 -380.656461) (xy 435.450796 -380.723769) (xy 435.442749 -380.790594) (xy 435.426772 -380.855977)
			(xy 435.403095 -380.918983) (xy 435.372057 -380.978707) (xy 435.334102 -381.034292) (xy 435.312312 -381.059944)
			(xy 435.306516 -381.067089) (xy 435.3 -381.08428) (xy 435.299612 -381.093472) (xy 435.299612 -381.251206)
			(xy 435.29924 -381.261384) (xy 435.291444 -381.280189) (xy 435.277041 -381.294575) (xy 435.258229 -381.302351)
			(xy 435.24805 -381.302768) (xy 434.53177 -381.302768) (xy 434.521611 -381.302291) (xy 434.502842 -381.294508)
			(xy 434.488478 -381.280138) (xy 434.480704 -381.261365) (xy 434.480208 -381.251206) (xy 434.480208 -381.093472)
			(xy 434.47981 -381.084284) (xy 434.473288 -381.067099) (xy 434.467508 -381.059944) (xy 434.445741 -381.034275)
			(xy 434.407793 -380.97869) (xy 434.376761 -380.918969) (xy 434.353088 -380.855967) (xy 434.337115 -380.790587)
			(xy 434.32907 -380.723766) (xy 434.329068 -380.656464) (xy 431.051005 -380.656464) (xy 431.051003 -380.723827)
			(xy 431.042926 -380.790767) (xy 431.026889 -380.856257) (xy 431.003123 -380.919354) (xy 430.971971 -380.979151)
			(xy 430.933881 -381.034786) (xy 430.912016 -381.060452) (xy 430.906217 -381.067595) (xy 430.899703 -381.084787)
			(xy 430.899316 -381.09398) (xy 430.899316 -381.251206) (xy 430.898877 -381.261338) (xy 430.891139 -381.280068)
			(xy 430.876838 -381.294426) (xy 430.858138 -381.302237) (xy 430.848008 -381.302768) (xy 430.131728 -381.302768)
			(xy 430.121572 -381.302355) (xy 430.102814 -381.294563) (xy 430.088488 -381.280163) (xy 430.080793 -381.261364)
			(xy 430.08042 -381.251206) (xy 430.08042 -381.09398) (xy 430.080015 -381.084792) (xy 430.073497 -381.067608)
			(xy 430.06772 -381.060452) (xy 430.045875 -381.034771) (xy 430.007784 -380.979139) (xy 429.976632 -380.919345)
			(xy 429.952865 -380.85625) (xy 429.936828 -380.790763) (xy 429.92875 -380.723826) (xy 429.928748 -380.656404)
			(xy 426.650703 -380.656404) (xy 426.65071 -380.656461) (xy 426.650708 -380.723769) (xy 426.642661 -380.790593)
			(xy 426.626685 -380.855977) (xy 426.603009 -380.918982) (xy 426.571971 -380.978706) (xy 426.534018 -381.034292)
			(xy 426.512228 -381.059944) (xy 426.506422 -381.067082) (xy 426.499915 -381.084278) (xy 426.499528 -381.093472)
			(xy 426.499528 -381.251206) (xy 426.49914 -381.261382) (xy 426.491347 -381.280184) (xy 426.47695 -381.294569)
			(xy 426.458143 -381.302348) (xy 426.447966 -381.302768) (xy 425.731686 -381.302768) (xy 425.721528 -381.302278)
			(xy 425.70276 -381.2945) (xy 425.688395 -381.280133) (xy 425.68062 -381.261364) (xy 425.680124 -381.251206)
			(xy 425.680124 -381.093472) (xy 425.679722 -381.084284) (xy 425.673202 -381.0671) (xy 425.667424 -381.059944)
			(xy 425.645656 -381.034276) (xy 425.607708 -380.978691) (xy 425.576675 -380.91897) (xy 425.553001 -380.855967)
			(xy 425.537027 -380.790587) (xy 425.528982 -380.723767) (xy 425.52898 -380.656463) (xy 422.250917 -380.656463)
			(xy 422.250915 -380.723827) (xy 422.242838 -380.790766) (xy 422.226801 -380.856256) (xy 422.203036 -380.919354)
			(xy 422.171885 -380.979151) (xy 422.133796 -381.034786) (xy 422.111932 -381.060452) (xy 422.106123 -381.067588)
			(xy 422.099618 -381.084786) (xy 422.099232 -381.09398) (xy 422.099232 -381.251206) (xy 422.098777 -381.261337)
			(xy 422.091042 -381.280063) (xy 422.076746 -381.29442) (xy 422.058052 -381.302234) (xy 422.047924 -381.302768)
			(xy 421.331644 -381.302768) (xy 421.32152 -381.302347) (xy 421.302812 -381.294608) (xy 421.288495 -381.280292)
			(xy 421.280754 -381.261584) (xy 421.280336 -381.25146) (xy 421.280336 -381.09398) (xy 421.279927 -381.084793)
			(xy 421.273412 -381.067609) (xy 421.267636 -381.060452) (xy 421.24579 -381.034771) (xy 421.207699 -380.97914)
			(xy 421.176545 -380.919346) (xy 421.152778 -380.856251) (xy 421.13674 -380.790764) (xy 421.128662 -380.723826)
			(xy 421.12866 -380.656404) (xy 391.450857 -380.656404) (xy 391.450864 -380.656462) (xy 391.450863 -380.723768)
			(xy 391.442817 -380.790591) (xy 391.426843 -380.855974) (xy 391.40317 -380.918979) (xy 391.372136 -380.978704)
			(xy 391.334188 -381.034291) (xy 391.3124 -381.059944) (xy 391.306602 -381.067088) (xy 391.300088 -381.08428)
			(xy 391.2997 -381.093472) (xy 391.2997 -381.251206) (xy 391.299172 -381.261359) (xy 391.291403 -381.280121)
			(xy 391.277048 -381.294485) (xy 391.258291 -381.302266) (xy 391.248138 -381.302768) (xy 390.531858 -381.302768)
			(xy 390.521698 -381.302301) (xy 390.502929 -381.294514) (xy 390.488566 -381.28014) (xy 390.480792 -381.261366)
			(xy 390.480296 -381.251206) (xy 390.480296 -381.093472) (xy 390.4799 -381.084283) (xy 390.473377 -381.067099)
			(xy 390.467596 -381.059944) (xy 390.445829 -381.034275) (xy 390.407883 -380.97869) (xy 390.376851 -380.918968)
			(xy 390.353179 -380.855966) (xy 390.337206 -380.790586) (xy 390.329161 -380.723766) (xy 390.329159 -380.656464)
			(xy 387.051096 -380.656464) (xy 387.051094 -380.723828) (xy 387.043016 -380.790767) (xy 387.026979 -380.856257)
			(xy 387.003213 -380.919355) (xy 386.97206 -380.979152) (xy 386.933969 -381.034787) (xy 386.912104 -381.060452)
			(xy 386.906303 -381.067594) (xy 386.899791 -381.084787) (xy 386.899404 -381.09398) (xy 386.899404 -381.251206)
			(xy 386.89888 -381.261328) (xy 386.891158 -381.280041) (xy 386.876884 -381.294395) (xy 386.858215 -381.302222)
			(xy 386.848096 -381.302768) (xy 386.131816 -381.302768) (xy 386.121659 -381.302365) (xy 386.102901 -381.294568)
			(xy 386.088576 -381.280166) (xy 386.080881 -381.261365) (xy 386.080508 -381.251206) (xy 386.080508 -381.09398)
			(xy 386.080106 -381.084792) (xy 386.073587 -381.067608) (xy 386.067808 -381.060452) (xy 386.045963 -381.034771)
			(xy 386.007874 -380.979139) (xy 385.976722 -380.919345) (xy 385.952956 -380.85625) (xy 385.936919 -380.790763)
			(xy 385.928841 -380.723826) (xy 385.928839 -380.656404) (xy 382.650793 -380.656404) (xy 382.6508 -380.656461)
			(xy 382.650799 -380.723769) (xy 382.642752 -380.790593) (xy 382.626775 -380.855977) (xy 382.603098 -380.918983)
			(xy 382.57206 -380.978707) (xy 382.534106 -381.034292) (xy 382.512316 -381.059944) (xy 382.50652 -381.06709)
			(xy 382.500005 -381.08428) (xy 382.499616 -381.093472) (xy 382.499616 -381.251206) (xy 382.49924 -381.261384)
			(xy 382.491444 -381.280187) (xy 382.477044 -381.294574) (xy 382.458232 -381.30235) (xy 382.448054 -381.302768)
			(xy 381.731774 -381.302768) (xy 381.721615 -381.302288) (xy 381.702847 -381.294506) (xy 381.688482 -381.280137)
			(xy 381.680708 -381.261365) (xy 381.680212 -381.251206) (xy 381.680212 -381.093472) (xy 381.679813 -381.084284)
			(xy 381.673291 -381.0671) (xy 381.667512 -381.059944) (xy 381.645745 -381.034275) (xy 381.607797 -380.978691)
			(xy 381.576764 -380.918969) (xy 381.553092 -380.855967) (xy 381.537118 -380.790587) (xy 381.529073 -380.723767)
			(xy 381.529071 -380.656464) (xy 378.251008 -380.656464) (xy 378.251006 -380.723827) (xy 378.242929 -380.790767)
			(xy 378.226892 -380.856257) (xy 378.203126 -380.919354) (xy 378.171974 -380.979151) (xy 378.133884 -381.034786)
			(xy 378.11202 -381.060452) (xy 378.106221 -381.067596) (xy 378.099707 -381.084787) (xy 378.09932 -381.09398)
			(xy 378.09932 -381.251206) (xy 378.098877 -381.261338) (xy 378.09114 -381.280067) (xy 378.07684 -381.294424)
			(xy 378.058142 -381.302236) (xy 378.048012 -381.302768) (xy 377.331732 -381.302768) (xy 377.321576 -381.302352)
			(xy 377.302818 -381.294561) (xy 377.288492 -381.280162) (xy 377.280797 -381.261364) (xy 377.280424 -381.251206)
			(xy 377.280424 -381.09398) (xy 377.280018 -381.084792) (xy 377.273501 -381.067608) (xy 377.267724 -381.060452)
			(xy 377.245879 -381.034771) (xy 377.207788 -380.979139) (xy 377.176635 -380.919345) (xy 377.152869 -380.856251)
			(xy 377.136831 -380.790763) (xy 377.128753 -380.723826) (xy 377.128751 -380.656404) (xy 347.450948 -380.656404)
			(xy 347.450955 -380.656462) (xy 347.450954 -380.723768) (xy 347.442908 -380.790592) (xy 347.426934 -380.855975)
			(xy 347.40326 -380.91898) (xy 347.372226 -380.978704) (xy 347.334276 -381.034291) (xy 347.312488 -381.059944)
			(xy 347.306689 -381.067087) (xy 347.300176 -381.084279) (xy 347.299788 -381.093472) (xy 347.299788 -381.251206)
			(xy 347.299272 -381.261361) (xy 347.2915 -381.280125) (xy 347.277142 -381.294489) (xy 347.258381 -381.302268)
			(xy 347.248226 -381.302768) (xy 346.531946 -381.302768) (xy 346.521778 -381.302299) (xy 346.502986 -381.29453)
			(xy 346.488599 -381.280158) (xy 346.480812 -381.261373) (xy 346.480384 -381.251206) (xy 346.480384 -381.093472)
			(xy 346.479991 -381.084283) (xy 346.473466 -381.067099) (xy 346.467684 -381.059944) (xy 346.445915 -381.034276)
			(xy 346.407962 -380.978693) (xy 346.376926 -380.918972) (xy 346.35325 -380.85597) (xy 346.337274 -380.790589)
			(xy 346.329228 -380.723767) (xy 346.329226 -380.656463) (xy 343.051187 -380.656463) (xy 343.051185 -380.723828)
			(xy 343.043107 -380.790767) (xy 343.027069 -380.856258) (xy 343.003303 -380.919356) (xy 342.972149 -380.979152)
			(xy 342.934057 -381.034787) (xy 342.912192 -381.060452) (xy 342.90639 -381.067593) (xy 342.899879 -381.084787)
			(xy 342.899492 -381.09398) (xy 342.899492 -381.251206) (xy 342.898979 -381.261329) (xy 342.891255 -381.280044)
			(xy 342.876978 -381.294399) (xy 342.858304 -381.302224) (xy 342.848184 -381.302768) (xy 342.131904 -381.302768)
			(xy 342.121746 -381.302374) (xy 342.102988 -381.294574) (xy 342.088663 -381.280168) (xy 342.080969 -381.261366)
			(xy 342.080596 -381.251206) (xy 342.080596 -381.09398) (xy 342.080196 -381.084792) (xy 342.073675 -381.067608)
			(xy 342.067896 -381.060452) (xy 342.046052 -381.03477) (xy 342.007963 -380.979138) (xy 341.976811 -380.919344)
			(xy 341.953046 -380.856249) (xy 341.93701 -380.790762) (xy 341.928932 -380.723826) (xy 341.92893 -380.656404)
			(xy 338.65086 -380.656404) (xy 338.650867 -380.656462) (xy 338.650866 -380.723768) (xy 338.64282 -380.790591)
			(xy 338.626846 -380.855974) (xy 338.603173 -380.918979) (xy 338.57214 -380.978704) (xy 338.534192 -381.034291)
			(xy 338.512404 -381.059944) (xy 338.506607 -381.067089) (xy 338.500092 -381.08428) (xy 338.499704 -381.093472)
			(xy 338.499704 -381.251206) (xy 338.499172 -381.261359) (xy 338.491404 -381.28012) (xy 338.47705 -381.294484)
			(xy 338.458295 -381.302265) (xy 338.448142 -381.302768) (xy 337.731862 -381.302768) (xy 337.721703 -381.302298)
			(xy 337.702934 -381.294512) (xy 337.68857 -381.280139) (xy 337.680796 -381.261366) (xy 337.6803 -381.251206)
			(xy 337.6803 -381.093472) (xy 337.679904 -381.084283) (xy 337.67338 -381.067099) (xy 337.6676 -381.059944)
			(xy 337.645833 -381.034275) (xy 337.607886 -380.97869) (xy 337.576854 -380.918969) (xy 337.553182 -380.855966)
			(xy 337.537209 -380.790587) (xy 337.529164 -380.723766) (xy 337.529162 -380.656464) (xy 334.251099 -380.656464)
			(xy 334.251097 -380.723828) (xy 334.243019 -380.790767) (xy 334.226982 -380.856257) (xy 334.203216 -380.919355)
			(xy 334.172063 -380.979152) (xy 334.133973 -381.034787) (xy 334.112108 -381.060452) (xy 334.106308 -381.067595)
			(xy 334.099795 -381.084787) (xy 334.099408 -381.09398) (xy 334.099408 -381.251206) (xy 334.09888 -381.261327)
			(xy 334.091159 -381.280039) (xy 334.076886 -381.294394) (xy 334.058218 -381.302221) (xy 334.0481 -381.302768)
			(xy 333.33182 -381.302768) (xy 333.321663 -381.302362) (xy 333.302905 -381.294567) (xy 333.28858 -381.280165)
			(xy 333.280885 -381.261365) (xy 333.280512 -381.251206) (xy 333.280512 -381.09398) (xy 333.280109 -381.084792)
			(xy 333.27359 -381.067608) (xy 333.267812 -381.060452) (xy 333.245967 -381.034771) (xy 333.207877 -380.979139)
			(xy 333.176725 -380.919345) (xy 333.152959 -380.85625) (xy 333.136922 -380.790763) (xy 333.128844 -380.723826)
			(xy 333.128842 -380.656404) (xy 303.451069 -380.656404) (xy 303.451067 -380.723828) (xy 303.442989 -380.790768)
			(xy 303.42695 -380.856259) (xy 303.403182 -380.919357) (xy 303.372027 -380.979153) (xy 303.333934 -381.034787)
			(xy 303.312068 -381.060452) (xy 303.306263 -381.067591) (xy 303.299754 -381.084786) (xy 303.299368 -381.09398)
			(xy 303.299368 -381.251206) (xy 303.298878 -381.261332) (xy 303.29115 -381.280052) (xy 303.276865 -381.294408)
			(xy 303.258184 -381.302228) (xy 303.24806 -381.302768) (xy 302.53178 -381.302768) (xy 302.521621 -381.302394)
			(xy 302.502861 -381.294586) (xy 302.488538 -381.280174) (xy 302.480844 -381.261368) (xy 302.480472 -381.251206)
			(xy 302.480472 -381.09398) (xy 302.480078 -381.084791) (xy 302.473554 -381.067607) (xy 302.467772 -381.060452)
			(xy 302.445929 -381.03477) (xy 302.407841 -380.979137) (xy 302.376691 -380.919343) (xy 302.352927 -380.856248)
			(xy 302.336891 -380.790762) (xy 302.328814 -380.723826) (xy 302.328812 -380.656404) (xy 299.050742 -380.656404)
			(xy 299.050749 -380.656462) (xy 299.050747 -380.723768) (xy 299.042702 -380.790592) (xy 299.026727 -380.855975)
			(xy 299.003053 -380.91898) (xy 298.972018 -380.978704) (xy 298.934068 -381.034292) (xy 298.91228 -381.059944)
			(xy 298.90648 -381.067087) (xy 298.899968 -381.084279) (xy 298.89958 -381.093472) (xy 298.89958 -381.251206)
			(xy 298.899072 -381.261362) (xy 298.891299 -381.280128) (xy 298.876938 -381.294492) (xy 298.858174 -381.302269)
			(xy 298.848018 -381.302768) (xy 298.131738 -381.302768) (xy 298.12157 -381.302305) (xy 298.102777 -381.294534)
			(xy 298.088391 -381.28016) (xy 298.080604 -381.261374) (xy 298.080176 -381.251206) (xy 298.080176 -381.093472)
			(xy 298.079785 -381.084283) (xy 298.073258 -381.067098) (xy 298.067476 -381.059944) (xy 298.045707 -381.034276)
			(xy 298.007755 -380.978693) (xy 297.976719 -380.918972) (xy 297.953043 -380.855969) (xy 297.937068 -380.790589)
			(xy 297.929022 -380.723767) (xy 297.92902 -380.656463) (xy 294.650981 -380.656463) (xy 294.650979 -380.723828)
			(xy 294.642901 -380.790768) (xy 294.626863 -380.856258) (xy 294.603096 -380.919356) (xy 294.571942 -380.979153)
			(xy 294.53385 -381.034787) (xy 294.511984 -381.060452) (xy 294.506181 -381.067593) (xy 294.499671 -381.084787)
			(xy 294.499284 -381.09398) (xy 294.499284 -381.251206) (xy 294.498779 -381.26133) (xy 294.491054 -381.280047)
			(xy 294.476773 -381.294402) (xy 294.458097 -381.302225) (xy 294.447976 -381.302768) (xy 293.731696 -381.302768)
			(xy 293.721569 -381.302386) (xy 293.70286 -381.294631) (xy 293.688544 -381.280303) (xy 293.680805 -381.261587)
			(xy 293.680388 -381.25146) (xy 293.680388 -381.09398) (xy 293.67999 -381.084791) (xy 293.673468 -381.067607)
			(xy 293.667688 -381.060452) (xy 293.645844 -381.03477) (xy 293.607756 -380.979138) (xy 293.576605 -380.919344)
			(xy 293.55284 -380.856249) (xy 293.536803 -380.790762) (xy 293.528726 -380.723826) (xy 293.528724 -380.656404)
			(xy 290.250654 -380.656404) (xy 290.250661 -380.656462) (xy 290.25066 -380.723768) (xy 290.242614 -380.790591)
			(xy 290.22664 -380.855974) (xy 290.202966 -380.918979) (xy 290.171933 -380.978704) (xy 290.133984 -381.034291)
			(xy 290.112196 -381.059944) (xy 290.106398 -381.067088) (xy 290.099884 -381.084279) (xy 290.099496 -381.093472)
			(xy 290.099496 -381.251206) (xy 290.098972 -381.26136) (xy 290.091202 -381.280123) (xy 290.076846 -381.294486)
			(xy 290.058088 -381.302267) (xy 290.047934 -381.302768) (xy 289.331654 -381.302768) (xy 289.321494 -381.302304)
			(xy 289.302725 -381.294516) (xy 289.288362 -381.280141) (xy 289.280588 -381.261366) (xy 289.280092 -381.251206)
			(xy 289.280092 -381.093472) (xy 289.279697 -381.084283) (xy 289.273173 -381.067099) (xy 289.267392 -381.059944)
			(xy 289.245622 -381.034276) (xy 289.207669 -380.978693) (xy 289.176632 -380.918972) (xy 289.152956 -380.85597)
			(xy 289.13698 -380.790589) (xy 289.128934 -380.723767) (xy 289.128932 -380.656463) (xy 272.92786 -380.656463)
			(xy 272.867822 -380.687974) (xy 272.746027 -380.742789) (xy 272.621144 -380.790151) (xy 272.49363 -380.829886)
			(xy 272.363949 -380.861849) (xy 272.232575 -380.885924) (xy 272.099987 -380.902024) (xy 271.966669 -380.910088)
			(xy 271.833107 -380.910088) (xy 271.699789 -380.902024) (xy 271.567201 -380.885924) (xy 271.435827 -380.861849)
			(xy 271.306146 -380.829886) (xy 271.178632 -380.790151) (xy 271.053749 -380.742789) (xy 270.931954 -380.687974)
			(xy 270.813691 -380.625904) (xy 270.699392 -380.556808) (xy 270.589472 -380.480936) (xy 270.484335 -380.398566)
			(xy 270.384362 -380.309998) (xy 270.28992 -380.215556) (xy 270.201352 -380.115583) (xy 270.118982 -380.010446)
			(xy 270.04311 -379.900526) (xy 269.974014 -379.786227) (xy 269.911944 -379.667964) (xy 269.857129 -379.546169)
			(xy 269.809767 -379.421286) (xy 269.770032 -379.293772) (xy 269.738069 -379.164091) (xy 269.713994 -379.032717)
			(xy 269.697894 -378.900129) (xy 269.68983 -378.766811) (xy 262.508217 -378.766811) (xy 262.561832 -378.820426)
			(xy 262.579147 -378.8384) (xy 262.608475 -378.878779) (xy 262.631125 -378.92325) (xy 262.646539 -378.970716)
			(xy 262.654337 -379.020009) (xy 262.654796 -379.044962) (xy 262.654796 -382.223705) (xy 286.928753 -382.223705)
			(xy 286.928754 -382.15628) (xy 286.936832 -382.08934) (xy 286.95287 -382.02385) (xy 286.976638 -381.960752)
			(xy 287.007792 -381.900956) (xy 287.045886 -381.845322) (xy 287.067752 -381.819658) (xy 287.073555 -381.812518)
			(xy 287.080065 -381.795323) (xy 287.080452 -381.78613) (xy 287.080452 -381.628904) (xy 287.080987 -381.618801)
			(xy 287.088715 -381.600133) (xy 287.102996 -381.585839) (xy 287.121658 -381.578096) (xy 287.13176 -381.577596)
			(xy 287.84804 -381.577596) (xy 287.858151 -381.578052) (xy 287.876829 -381.585802) (xy 287.891122 -381.600108)
			(xy 287.898856 -381.618793) (xy 287.899348 -381.628904) (xy 287.899348 -381.78613) (xy 287.899755 -381.795317)
			(xy 287.906272 -381.812501) (xy 287.912048 -381.819658) (xy 287.933904 -381.84533) (xy 287.971996 -381.900963)
			(xy 288.00315 -381.960757) (xy 288.026917 -382.023853) (xy 288.042955 -382.089342) (xy 288.051033 -382.156281)
			(xy 288.051034 -382.223645) (xy 291.329073 -382.223645) (xy 291.329074 -382.15634) (xy 291.337119 -382.089516)
			(xy 291.353093 -382.024133) (xy 291.376767 -381.961128) (xy 291.407801 -381.901405) (xy 291.445751 -381.845818)
			(xy 291.46754 -381.820166) (xy 291.473339 -381.813022) (xy 291.479851 -381.795831) (xy 291.48024 -381.786638)
			(xy 291.48024 -381.628904) (xy 291.48062 -381.618777) (xy 291.488375 -381.600066) (xy 291.502703 -381.58575)
			(xy 291.52142 -381.578012) (xy 291.531548 -381.577596) (xy 292.248082 -381.577596) (xy 292.258202 -381.57814)
			(xy 292.276915 -381.585854) (xy 292.29127 -381.600122) (xy 292.299098 -381.618787) (xy 292.299644 -381.628904)
			(xy 292.299644 -381.786638) (xy 292.300049 -381.795826) (xy 292.306568 -381.813009) (xy 292.312344 -381.820166)
			(xy 292.334122 -381.845826) (xy 292.372072 -381.901411) (xy 292.403107 -381.961133) (xy 292.426781 -382.024137)
			(xy 292.442755 -382.089518) (xy 292.450801 -382.15634) (xy 292.450801 -382.223645) (xy 292.450794 -382.223705)
			(xy 295.728841 -382.223705) (xy 295.728842 -382.15628) (xy 295.73692 -382.08934) (xy 295.752957 -382.02385)
			(xy 295.776724 -381.960753) (xy 295.807878 -381.900957) (xy 295.84597 -381.845323) (xy 295.867836 -381.819658)
			(xy 295.873637 -381.812516) (xy 295.880148 -381.795323) (xy 295.880536 -381.78613) (xy 295.880536 -381.628904)
			(xy 295.88092 -381.618777) (xy 295.888674 -381.600067) (xy 295.903001 -381.585751) (xy 295.921717 -381.578012)
			(xy 295.931844 -381.577596) (xy 296.648124 -381.577596) (xy 296.658234 -381.578065) (xy 296.676912 -381.58581)
			(xy 296.691206 -381.600112) (xy 296.69894 -381.618794) (xy 296.699432 -381.628904) (xy 296.699432 -381.78613)
			(xy 296.699843 -381.795317) (xy 296.706358 -381.8125) (xy 296.712132 -381.819658) (xy 296.733985 -381.845332)
			(xy 296.772072 -381.900966) (xy 296.803221 -381.960761) (xy 296.826985 -382.023857) (xy 296.84302 -382.089345)
			(xy 296.851096 -382.156281) (xy 296.851097 -382.223704) (xy 296.851097 -382.223705) (xy 300.128632 -382.223705)
			(xy 300.128633 -382.15628) (xy 300.13671 -382.089341) (xy 300.152748 -382.023851) (xy 300.176514 -381.960753)
			(xy 300.207667 -381.900957) (xy 300.245759 -381.845323) (xy 300.267624 -381.819658) (xy 300.273424 -381.812515)
			(xy 300.279936 -381.795323) (xy 300.280324 -381.78613) (xy 300.280324 -381.628904) (xy 300.28072 -381.618779)
			(xy 300.288471 -381.600071) (xy 300.302794 -381.585755) (xy 300.321507 -381.578014) (xy 300.331632 -381.577596)
			(xy 301.047912 -381.577596) (xy 301.058021 -381.578075) (xy 301.076699 -381.585816) (xy 301.090993 -381.600115)
			(xy 301.098728 -381.618795) (xy 301.09922 -381.628904) (xy 301.09922 -381.78613) (xy 301.099611 -381.795319)
			(xy 301.106138 -381.812504) (xy 301.11192 -381.819658) (xy 301.133773 -381.845332) (xy 301.171861 -381.900965)
			(xy 301.203011 -381.960761) (xy 301.226775 -382.023856) (xy 301.242811 -382.089344) (xy 301.250887 -382.156281)
			(xy 301.250888 -382.223646) (xy 330.929191 -382.223646) (xy 330.929192 -382.156339) (xy 330.937238 -382.089516)
			(xy 330.953213 -382.024133) (xy 330.976888 -381.961128) (xy 331.007923 -381.901404) (xy 331.045875 -381.845818)
			(xy 331.067664 -381.820166) (xy 331.073465 -381.813025) (xy 331.079975 -381.795831) (xy 331.080364 -381.786638)
			(xy 331.080364 -381.628904) (xy 331.080824 -381.618755) (xy 331.088612 -381.600009) (xy 331.102996 -381.585687)
			(xy 331.121775 -381.577981) (xy 331.131926 -381.577596) (xy 331.848206 -381.577596) (xy 331.858328 -381.57812)
			(xy 331.877041 -381.585842) (xy 331.891395 -381.600116) (xy 331.899222 -381.618785) (xy 331.899768 -381.628904)
			(xy 331.899768 -381.786638) (xy 331.900167 -381.795826) (xy 331.906689 -381.81301) (xy 331.912468 -381.820166)
			(xy 331.934246 -381.845826) (xy 331.972195 -381.901412) (xy 332.003228 -381.961134) (xy 332.026901 -382.024138)
			(xy 332.042874 -382.089519) (xy 332.050919 -382.15634) (xy 332.05092 -382.223645) (xy 332.050913 -382.223704)
			(xy 335.328984 -382.223704) (xy 335.328985 -382.156281) (xy 335.337061 -382.089342) (xy 335.353096 -382.023853)
			(xy 335.37686 -381.960756) (xy 335.40801 -381.900959) (xy 335.446097 -381.845324) (xy 335.46796 -381.819658)
			(xy 335.473764 -381.812519) (xy 335.480273 -381.795323) (xy 335.48066 -381.78613) (xy 335.48066 -381.628904)
			(xy 335.481187 -381.6188) (xy 335.488916 -381.60013) (xy 335.5032 -381.585837) (xy 335.521865 -381.578095)
			(xy 335.531968 -381.577596) (xy 336.248248 -381.577596) (xy 336.258359 -381.578046) (xy 336.277038 -381.585799)
			(xy 336.291331 -381.600106) (xy 336.299064 -381.618792) (xy 336.299556 -381.628904) (xy 336.299556 -381.78613)
			(xy 336.299962 -381.795317) (xy 336.30648 -381.812501) (xy 336.312256 -381.819658) (xy 336.334112 -381.845331)
			(xy 336.372204 -381.900963) (xy 336.403357 -381.960758) (xy 336.427124 -382.023854) (xy 336.443161 -382.089342)
			(xy 336.451239 -382.156281) (xy 336.45124 -382.223645) (xy 339.729279 -382.223645) (xy 339.72928 -382.156339)
			(xy 339.737325 -382.089516) (xy 339.753299 -382.024133) (xy 339.776974 -381.961128) (xy 339.808009 -381.901404)
			(xy 339.845959 -381.845818) (xy 339.867748 -381.820166) (xy 339.873547 -381.813023) (xy 339.880059 -381.795831)
			(xy 339.880448 -381.786638) (xy 339.880448 -381.628904) (xy 339.880924 -381.618757) (xy 339.888708 -381.600014)
			(xy 339.903088 -381.585693) (xy 339.921861 -381.577984) (xy 339.93201 -381.577596) (xy 340.64829 -381.577596)
			(xy 340.658411 -381.578133) (xy 340.677123 -381.58585) (xy 340.691478 -381.60012) (xy 340.699306 -381.618786)
			(xy 340.699852 -381.628904) (xy 340.699852 -381.786638) (xy 340.700255 -381.795826) (xy 340.706775 -381.813009)
			(xy 340.712552 -381.820166) (xy 340.73433 -381.845826) (xy 340.77228 -381.901411) (xy 340.803314 -381.961134)
			(xy 340.826988 -382.024137) (xy 340.842962 -382.089518) (xy 340.851007 -382.15634) (xy 340.851007 -382.223645)
			(xy 344.12907 -382.223645) (xy 344.129071 -382.15634) (xy 344.137116 -382.089516) (xy 344.15309 -382.024134)
			(xy 344.176764 -381.961129) (xy 344.207798 -381.901405) (xy 344.245748 -381.845818) (xy 344.267536 -381.820166)
			(xy 344.273334 -381.813022) (xy 344.279847 -381.79583) (xy 344.280236 -381.786638) (xy 344.280236 -381.628904)
			(xy 344.280626 -381.618746) (xy 344.288427 -381.599986) (xy 344.302834 -381.585662) (xy 344.321637 -381.577968)
			(xy 344.331798 -381.577596) (xy 345.048078 -381.577596) (xy 345.058198 -381.578143) (xy 345.07691 -381.585856)
			(xy 345.091266 -381.600123) (xy 345.099094 -381.618787) (xy 345.09964 -381.628904) (xy 345.09964 -381.786638)
			(xy 345.100045 -381.795825) (xy 345.106564 -381.813009) (xy 345.11234 -381.820166) (xy 345.134118 -381.845826)
			(xy 345.172069 -381.901411) (xy 345.203104 -381.961133) (xy 345.226778 -382.024137) (xy 345.242752 -382.089518)
			(xy 345.250798 -382.15634) (xy 345.250798 -382.223645) (xy 345.250798 -382.223646) (xy 374.9291 -382.223646)
			(xy 374.929101 -382.156339) (xy 374.937147 -382.089515) (xy 374.953122 -382.024132) (xy 374.976798 -381.961127)
			(xy 375.007834 -381.901404) (xy 375.045787 -381.845818) (xy 375.067576 -381.820166) (xy 375.073367 -381.813016)
			(xy 375.079886 -381.795829) (xy 375.080276 -381.786638) (xy 375.080276 -381.628904) (xy 375.080724 -381.618753)
			(xy 375.088514 -381.600005) (xy 375.102902 -381.585683) (xy 375.121685 -381.577979) (xy 375.131838 -381.577596)
			(xy 375.848118 -381.577596) (xy 375.85824 -381.57811) (xy 375.876954 -381.585836) (xy 375.891308 -381.600113)
			(xy 375.899134 -381.618784) (xy 375.89968 -381.628904) (xy 375.89968 -381.786638) (xy 375.900076 -381.795827)
			(xy 375.9066 -381.813011) (xy 375.91238 -381.820166) (xy 375.934157 -381.845826) (xy 375.972105 -381.901412)
			(xy 376.003138 -381.961135) (xy 376.02681 -382.024138) (xy 376.042784 -382.089519) (xy 376.050828 -382.156341)
			(xy 376.050829 -382.223644) (xy 376.050822 -382.223704) (xy 379.328893 -382.223704) (xy 379.328894 -382.156281)
			(xy 379.33697 -382.089342) (xy 379.353006 -382.023853) (xy 379.37677 -381.960756) (xy 379.40792 -381.900959)
			(xy 379.446008 -381.845324) (xy 379.467872 -381.819658) (xy 379.473678 -381.81252) (xy 379.480185 -381.795324)
			(xy 379.480572 -381.78613) (xy 379.480572 -381.628904) (xy 379.481088 -381.618799) (xy 379.488819 -381.600126)
			(xy 379.503106 -381.585832) (xy 379.521775 -381.578092) (xy 379.53188 -381.577596) (xy 380.24816 -381.577596)
			(xy 380.258279 -381.578049) (xy 380.276981 -381.585783) (xy 380.291297 -381.600088) (xy 380.299044 -381.618785)
			(xy 380.299468 -381.628904) (xy 380.299468 -381.78613) (xy 380.299871 -381.795318) (xy 380.30639 -381.812502)
			(xy 380.312168 -381.819658) (xy 380.334023 -381.845331) (xy 380.372114 -381.900963) (xy 380.403267 -381.960758)
			(xy 380.427033 -382.023854) (xy 380.443071 -382.089343) (xy 380.451148 -382.156281) (xy 380.451149 -382.223646)
			(xy 383.729188 -382.223646) (xy 383.729189 -382.156339) (xy 383.737235 -382.089516) (xy 383.753209 -382.024133)
			(xy 383.776884 -381.961128) (xy 383.80792 -381.901404) (xy 383.845871 -381.845818) (xy 383.86766 -381.820166)
			(xy 383.873461 -381.813024) (xy 383.879971 -381.795831) (xy 383.88036 -381.786638) (xy 383.88036 -381.628904)
			(xy 383.880824 -381.618755) (xy 383.888611 -381.600011) (xy 383.902994 -381.585689) (xy 383.921771 -381.577981)
			(xy 383.931922 -381.577596) (xy 384.648202 -381.577596) (xy 384.658323 -381.578124) (xy 384.677036 -381.585844)
			(xy 384.691391 -381.600117) (xy 384.699218 -381.618786) (xy 384.699764 -381.628904) (xy 384.699764 -381.786638)
			(xy 384.700164 -381.795826) (xy 384.706686 -381.81301) (xy 384.712464 -381.820166) (xy 384.734242 -381.845826)
			(xy 384.772191 -381.901412) (xy 384.803224 -381.961134) (xy 384.826898 -382.024137) (xy 384.842871 -382.089519)
			(xy 384.850916 -382.15634) (xy 384.850917 -382.223645) (xy 388.128979 -382.223645) (xy 388.12898 -382.156339)
			(xy 388.137025 -382.089516) (xy 388.152999 -382.024133) (xy 388.176674 -381.961128) (xy 388.207709 -381.901404)
			(xy 388.245659 -381.845818) (xy 388.267448 -381.820166) (xy 388.273247 -381.813023) (xy 388.279759 -381.795831)
			(xy 388.280148 -381.786638) (xy 388.280148 -381.628904) (xy 388.280624 -381.618757) (xy 388.288408 -381.600014)
			(xy 388.302788 -381.585693) (xy 388.321561 -381.577984) (xy 388.33171 -381.577596) (xy 389.04799 -381.577596)
			(xy 389.058111 -381.578133) (xy 389.076823 -381.58585) (xy 389.091178 -381.60012) (xy 389.099006 -381.618786)
			(xy 389.099552 -381.628904) (xy 389.099552 -381.786638) (xy 389.099955 -381.795826) (xy 389.106475 -381.813009)
			(xy 389.112252 -381.820166) (xy 389.13403 -381.845826) (xy 389.17198 -381.901411) (xy 389.203014 -381.961134)
			(xy 389.226688 -382.024137) (xy 389.242662 -382.089518) (xy 389.250707 -382.15634) (xy 389.250707 -382.223645)
			(xy 389.250707 -382.223646) (xy 418.92901 -382.223646) (xy 418.92901 -382.156339) (xy 418.937056 -382.089515)
			(xy 418.953032 -382.024132) (xy 418.976708 -381.961127) (xy 419.007745 -381.901403) (xy 419.045698 -381.845818)
			(xy 419.067488 -381.820166) (xy 419.07328 -381.813018) (xy 419.079798 -381.79583) (xy 419.080188 -381.786638)
			(xy 419.080188 -381.628904) (xy 419.080688 -381.618797) (xy 419.088422 -381.600121) (xy 419.102714 -381.585827)
			(xy 419.121389 -381.57809) (xy 419.131496 -381.577596) (xy 419.84803 -381.577596) (xy 419.858153 -381.578101)
			(xy 419.876867 -381.58583) (xy 419.89122 -381.60011) (xy 419.899046 -381.618783) (xy 419.899592 -381.628904)
			(xy 419.899592 -381.786638) (xy 419.899986 -381.795827) (xy 419.906511 -381.813011) (xy 419.912292 -381.820166)
			(xy 419.934069 -381.845827) (xy 419.972016 -381.901413) (xy 420.003048 -381.961135) (xy 420.02672 -382.024139)
			(xy 420.042693 -382.089519) (xy 420.050737 -382.156341) (xy 420.050738 -382.223644) (xy 420.050731 -382.223705)
			(xy 423.328802 -382.223705) (xy 423.328803 -382.15628) (xy 423.33688 -382.089342) (xy 423.352916 -382.023852)
			(xy 423.37668 -381.960755) (xy 423.407831 -381.900959) (xy 423.44592 -381.845324) (xy 423.467784 -381.819658)
			(xy 423.473579 -381.812512) (xy 423.480095 -381.795322) (xy 423.480484 -381.78613) (xy 423.480484 -381.628904)
			(xy 423.480988 -381.618798) (xy 423.488721 -381.600122) (xy 423.503012 -381.585828) (xy 423.521686 -381.57809)
			(xy 423.531792 -381.577596) (xy 424.248072 -381.577596) (xy 424.258192 -381.578039) (xy 424.276895 -381.585777)
			(xy 424.29121 -381.600085) (xy 424.298957 -381.618784) (xy 424.29938 -381.628904) (xy 424.29938 -381.78613)
			(xy 424.29978 -381.795318) (xy 424.306301 -381.812502) (xy 424.31208 -381.819658) (xy 424.333935 -381.845331)
			(xy 424.372025 -381.900964) (xy 424.403177 -381.960759) (xy 424.426943 -382.023855) (xy 424.44298 -382.089343)
			(xy 424.451057 -382.156281) (xy 424.451058 -382.223646) (xy 427.729097 -382.223646) (xy 427.729098 -382.156339)
			(xy 427.737144 -382.089515) (xy 427.753119 -382.024132) (xy 427.776794 -381.961127) (xy 427.807831 -381.901404)
			(xy 427.845783 -381.845818) (xy 427.867572 -381.820166) (xy 427.873374 -381.813025) (xy 427.879883 -381.795831)
			(xy 427.880272 -381.786638) (xy 427.880272 -381.628904) (xy 427.880724 -381.618754) (xy 427.888513 -381.600007)
			(xy 427.9029 -381.585684) (xy 427.921682 -381.577979) (xy 427.931834 -381.577596) (xy 428.648114 -381.577596)
			(xy 428.658236 -381.578114) (xy 428.676949 -381.585838) (xy 428.691303 -381.600114) (xy 428.69913 -381.618785)
			(xy 428.699676 -381.628904) (xy 428.699676 -381.786638) (xy 428.700073 -381.795826) (xy 428.706596 -381.81301)
			(xy 428.712376 -381.820166) (xy 428.734154 -381.845826) (xy 428.772102 -381.901412) (xy 428.803135 -381.961135)
			(xy 428.826807 -382.024138) (xy 428.84278 -382.089519) (xy 428.850825 -382.15634) (xy 428.850826 -382.223644)
			(xy 428.850826 -382.223646) (xy 432.128888 -382.223646) (xy 432.128889 -382.156339) (xy 432.136935 -382.089516)
			(xy 432.152909 -382.024133) (xy 432.176584 -381.961128) (xy 432.20762 -381.901404) (xy 432.245571 -381.845818)
			(xy 432.26736 -381.820166) (xy 432.273161 -381.813024) (xy 432.279671 -381.795831) (xy 432.28006 -381.786638)
			(xy 432.28006 -381.628904) (xy 432.280524 -381.618755) (xy 432.288311 -381.600011) (xy 432.302694 -381.585689)
			(xy 432.321471 -381.577981) (xy 432.331622 -381.577596) (xy 433.047902 -381.577596) (xy 433.058023 -381.578124)
			(xy 433.076736 -381.585844) (xy 433.091091 -381.600117) (xy 433.098918 -381.618786) (xy 433.099464 -381.628904)
			(xy 433.099464 -381.786638) (xy 433.099864 -381.795826) (xy 433.106386 -381.81301) (xy 433.112164 -381.820166)
			(xy 433.133942 -381.845826) (xy 433.171891 -381.901412) (xy 433.202924 -381.961134) (xy 433.226598 -382.024137)
			(xy 433.242571 -382.089519) (xy 433.250616 -382.15634) (xy 433.250617 -382.223645) (xy 433.242574 -382.290466)
			(xy 433.226602 -382.355848) (xy 433.202931 -382.418852) (xy 433.171899 -382.478576) (xy 433.133951 -382.534162)
			(xy 433.112164 -382.559814) (xy 433.106374 -382.566964) (xy 433.099856 -382.584151) (xy 433.099464 -382.593342)
			(xy 433.099464 -383.086864) (xy 433.0999 -383.096048) (xy 433.106397 -383.113232) (xy 433.112164 -383.120392)
			(xy 433.133967 -383.146031) (xy 433.171916 -383.20162) (xy 433.202948 -383.261345) (xy 433.226386 -383.323727)
			(xy 434.32903 -383.323727) (xy 434.329034 -383.256419) (xy 434.337081 -383.189595) (xy 434.353057 -383.124211)
			(xy 434.376732 -383.061205) (xy 434.407768 -383.00148) (xy 434.445719 -382.945893) (xy 434.467508 -382.92024)
			(xy 434.473313 -382.913101) (xy 434.479823 -382.895906) (xy 434.480208 -382.886712) (xy 434.480208 -382.728724)
			(xy 434.480641 -382.71857) (xy 434.48843 -382.699817) (xy 434.502824 -382.685492) (xy 434.521614 -382.677793)
			(xy 434.53177 -382.677416) (xy 435.24805 -382.677416) (xy 435.258171 -382.677967) (xy 435.276886 -382.685674)
			(xy 435.291243 -382.69994) (xy 435.299068 -382.718607) (xy 435.299612 -382.728724) (xy 435.299612 -382.886712)
			(xy 435.300014 -382.8959) (xy 435.306533 -382.913084) (xy 435.312312 -382.92024) (xy 435.334066 -382.945921)
			(xy 435.372019 -383.001502) (xy 435.403056 -383.061221) (xy 435.426733 -383.124222) (xy 435.44271 -383.189601)
			(xy 435.450758 -383.256421) (xy 435.450761 -383.323724) (xy 435.44272 -383.390546) (xy 435.426749 -383.455926)
			(xy 435.403079 -383.518929) (xy 435.372047 -383.578652) (xy 435.334099 -383.634237) (xy 435.312312 -383.659888)
			(xy 435.306497 -383.66702) (xy 435.299993 -383.684221) (xy 435.299612 -383.693416) (xy 435.299612 -384.186684)
			(xy 435.300027 -384.195871) (xy 435.306537 -384.213055) (xy 435.312312 -384.220212) (xy 435.334137 -384.245834)
			(xy 435.372087 -384.301424) (xy 435.403122 -384.361151) (xy 435.426795 -384.42416) (xy 435.442767 -384.489546)
			(xy 435.450809 -384.556373) (xy 435.450805 -384.623681) (xy 435.442757 -384.690507) (xy 435.426779 -384.755892)
			(xy 435.4031 -384.818898) (xy 435.37206 -384.878623) (xy 435.334103 -384.934208) (xy 435.312312 -384.95986)
			(xy 435.306509 -384.967001) (xy 435.299998 -384.984195) (xy 435.299612 -384.993388) (xy 435.299612 -385.151376)
			(xy 435.299159 -385.161527) (xy 435.291374 -385.180277) (xy 435.276987 -385.194601) (xy 435.258203 -385.202303)
			(xy 435.24805 -385.202684) (xy 434.53177 -385.202684) (xy 434.521644 -385.202199) (xy 434.502927 -385.194466)
			(xy 434.488573 -385.180179) (xy 434.48075 -385.161499) (xy 434.480208 -385.151376) (xy 434.480208 -384.993388)
			(xy 434.479802 -384.9842) (xy 434.473285 -384.967016) (xy 434.467508 -384.95986) (xy 434.445757 -384.934178)
			(xy 434.407809 -384.878595) (xy 434.376776 -384.818876) (xy 434.353102 -384.755875) (xy 434.337128 -384.690497)
			(xy 434.329081 -384.623678) (xy 434.329078 -384.556376) (xy 434.337118 -384.489557) (xy 434.353086 -384.424177)
			(xy 434.376753 -384.361174) (xy 434.407781 -384.301451) (xy 434.445723 -384.245864) (xy 434.467508 -384.220212)
			(xy 434.473325 -384.213082) (xy 434.479827 -384.19588) (xy 434.480208 -384.186684) (xy 434.480208 -383.693416)
			(xy 434.479788 -383.68423) (xy 434.473281 -383.667046) (xy 434.467508 -383.659888) (xy 434.445686 -383.634265)
			(xy 434.40774 -383.578673) (xy 434.37671 -383.518945) (xy 434.353041 -383.455937) (xy 434.337071 -383.390552)
			(xy 434.32903 -383.323727) (xy 433.226386 -383.323727) (xy 433.22662 -383.324351) (xy 433.242592 -383.389735)
			(xy 433.250634 -383.456559) (xy 433.250633 -383.523865) (xy 433.242587 -383.590689) (xy 433.226613 -383.656072)
			(xy 433.202938 -383.719077) (xy 433.171903 -383.778801) (xy 433.133953 -383.834388) (xy 433.112164 -383.86004)
			(xy 433.106363 -383.867182) (xy 433.099852 -383.884375) (xy 433.099464 -383.893568) (xy 433.099464 -384.051556)
			(xy 433.099042 -384.061712) (xy 433.091254 -384.08047) (xy 433.076856 -384.094796) (xy 433.05806 -384.102491)
			(xy 433.047902 -384.102864) (xy 432.331622 -384.102864) (xy 432.321497 -384.102356) (xy 432.302777 -384.094636)
			(xy 432.28842 -384.080356) (xy 432.2806 -384.061678) (xy 432.28006 -384.051556) (xy 432.28006 -383.893568)
			(xy 432.279652 -383.884381) (xy 432.273135 -383.867197) (xy 432.26736 -383.86004) (xy 432.245587 -383.834375)
			(xy 432.207637 -383.778791) (xy 432.176602 -383.719069) (xy 432.152927 -383.656066) (xy 432.136952 -383.590686)
			(xy 432.128907 -383.523864) (xy 432.128905 -383.45656) (xy 432.136948 -383.389738) (xy 432.15292 -383.324357)
			(xy 432.176592 -383.261353) (xy 432.207624 -383.20163) (xy 432.245573 -383.146044) (xy 432.26736 -383.120392)
			(xy 432.27315 -383.113242) (xy 432.279667 -383.096055) (xy 432.28006 -383.086864) (xy 432.28006 -382.593342)
			(xy 432.279616 -382.584159) (xy 432.273125 -382.566975) (xy 432.26736 -382.559814) (xy 432.245562 -382.53417)
			(xy 432.207612 -382.478583) (xy 432.176578 -382.418858) (xy 432.152905 -382.355853) (xy 432.136932 -382.290469)
			(xy 432.128888 -382.223646) (xy 428.850826 -382.223646) (xy 428.842783 -382.290466) (xy 428.826812 -382.355848)
			(xy 428.803141 -382.418852) (xy 428.772109 -382.478575) (xy 428.734163 -382.534162) (xy 428.712376 -382.559814)
			(xy 428.706588 -382.566965) (xy 428.700069 -382.584151) (xy 428.699676 -382.593342) (xy 428.699676 -383.086864)
			(xy 428.700109 -383.096049) (xy 428.706607 -383.113233) (xy 428.712376 -383.120392) (xy 428.734179 -383.146031)
			(xy 428.772126 -383.20162) (xy 428.803158 -383.261345) (xy 428.826616 -383.323786) (xy 429.928711 -383.323786)
			(xy 429.928714 -383.25636) (xy 429.936794 -383.189418) (xy 429.952834 -383.123927) (xy 429.976603 -383.060829)
			(xy 430.007759 -383.001032) (xy 430.045853 -382.945397) (xy 430.06772 -382.919732) (xy 430.07353 -382.912597)
			(xy 430.080036 -382.895398) (xy 430.08042 -382.886204) (xy 430.08042 -382.728724) (xy 430.080836 -382.718601)
			(xy 430.08858 -382.699894) (xy 430.102897 -382.685578) (xy 430.121605 -382.677835) (xy 430.131728 -382.677416)
			(xy 430.848008 -382.677416) (xy 430.858133 -382.67781) (xy 430.87684 -382.685564) (xy 430.891154 -382.699887)
			(xy 430.898896 -382.718599) (xy 430.899316 -382.728724) (xy 430.899316 -382.886204) (xy 430.899721 -382.895392)
			(xy 430.906238 -382.912576) (xy 430.912016 -382.919732) (xy 430.933844 -382.945427) (xy 430.971933 -383.001057)
			(xy 431.003084 -383.06085) (xy 431.02685 -383.123943) (xy 431.042887 -383.189428) (xy 431.050966 -383.256363)
			(xy 431.050969 -383.323783) (xy 431.042897 -383.390719) (xy 431.026866 -383.456206) (xy 431.003106 -383.519301)
			(xy 430.971961 -383.579096) (xy 430.933877 -383.634731) (xy 430.912016 -383.660396) (xy 430.90624 -383.667556)
			(xy 430.899713 -383.684735) (xy 430.899316 -383.693924) (xy 430.899316 -384.186176) (xy 430.899734 -384.195362)
			(xy 430.906242 -384.212547) (xy 430.912016 -384.219704) (xy 430.933915 -384.24534) (xy 430.972001 -384.300979)
			(xy 431.00315 -384.36078) (xy 431.026911 -384.42388) (xy 431.042944 -384.489373) (xy 431.051016 -384.556314)
			(xy 431.051013 -384.62374) (xy 431.042934 -384.690681) (xy 431.026895 -384.756171) (xy 431.003128 -384.81927)
			(xy 430.971974 -384.879067) (xy 430.933882 -384.934702) (xy 430.912016 -384.960368) (xy 430.90621 -384.967507)
			(xy 430.8997 -384.984702) (xy 430.899316 -384.993896) (xy 430.899316 -385.151376) (xy 430.898865 -385.161495)
			(xy 430.891128 -385.180195) (xy 430.876822 -385.19451) (xy 430.858127 -385.202259) (xy 430.848008 -385.202684)
			(xy 430.131728 -385.202684) (xy 430.121605 -385.202261) (xy 430.102899 -385.194519) (xy 430.088583 -385.180204)
			(xy 430.08084 -385.161499) (xy 430.08042 -385.151376) (xy 430.08042 -384.993896) (xy 430.080008 -384.984709)
			(xy 430.073495 -384.967525) (xy 430.06772 -384.960368) (xy 430.045891 -384.934674) (xy 430.0078 -384.879044)
			(xy 429.976646 -384.819252) (xy 429.952879 -384.756159) (xy 429.936841 -384.690673) (xy 429.928761 -384.623738)
			(xy 429.928758 -384.556316) (xy 429.936831 -384.48938) (xy 429.952863 -384.423893) (xy 429.976624 -384.360797)
			(xy 430.007772 -384.301002) (xy 430.045857 -384.245369) (xy 430.06772 -384.219704) (xy 430.0735 -384.212547)
			(xy 430.080024 -384.195365) (xy 430.08042 -384.186176) (xy 430.08042 -383.693924) (xy 430.079994 -383.684739)
			(xy 430.073491 -383.667554) (xy 430.06772 -383.660396) (xy 430.04582 -383.63476) (xy 430.007731 -383.579122)
			(xy 429.976581 -383.519322) (xy 429.952818 -383.456221) (xy 429.936784 -383.390728) (xy 429.928711 -383.323786)
			(xy 428.826616 -383.323786) (xy 428.826829 -383.324352) (xy 428.842801 -383.389735) (xy 428.850843 -383.456559)
			(xy 428.850842 -383.523865) (xy 428.842797 -383.590688) (xy 428.826822 -383.656071) (xy 428.803148 -383.719077)
			(xy 428.772114 -383.778801) (xy 428.734164 -383.834388) (xy 428.712376 -383.86004) (xy 428.706577 -383.867183)
			(xy 428.700065 -383.884375) (xy 428.699676 -383.893568) (xy 428.699676 -384.051556) (xy 428.699242 -384.06171)
			(xy 428.691456 -384.080466) (xy 428.677063 -384.094792) (xy 428.65827 -384.102489) (xy 428.648114 -384.102864)
			(xy 427.931834 -384.102864) (xy 427.92171 -384.102345) (xy 427.90299 -384.09463) (xy 427.888633 -384.080353)
			(xy 427.880812 -384.061677) (xy 427.880272 -384.051556) (xy 427.880272 -383.893568) (xy 427.879883 -383.884378)
			(xy 427.873355 -383.867194) (xy 427.867572 -383.86004) (xy 427.845799 -383.834375) (xy 427.807848 -383.778791)
			(xy 427.776812 -383.71907) (xy 427.753137 -383.656067) (xy 427.737162 -383.590686) (xy 427.729116 -383.523864)
			(xy 427.729114 -383.45656) (xy 427.737157 -383.389738) (xy 427.75313 -383.324356) (xy 427.776802 -383.261352)
			(xy 427.807835 -383.201629) (xy 427.845784 -383.146044) (xy 427.867572 -383.120392) (xy 427.873363 -383.113243)
			(xy 427.879879 -383.096055) (xy 427.880272 -383.086864) (xy 427.880272 -382.593342) (xy 427.879848 -382.584156)
			(xy 427.873344 -382.566971) (xy 427.867572 -382.559814) (xy 427.845774 -382.53417) (xy 427.807823 -382.478583)
			(xy 427.776788 -382.418859) (xy 427.753115 -382.355853) (xy 427.737141 -382.29047) (xy 427.729097 -382.223646)
			(xy 424.451058 -382.223646) (xy 424.451058 -382.223704) (xy 424.442983 -382.290642) (xy 424.426948 -382.356131)
			(xy 424.403184 -382.419227) (xy 424.372033 -382.479023) (xy 424.333944 -382.534657) (xy 424.31208 -382.560322)
			(xy 424.306289 -382.567471) (xy 424.299772 -382.584659) (xy 424.29938 -382.59385) (xy 424.29938 -383.086356)
			(xy 424.299816 -383.09554) (xy 424.306312 -383.112725) (xy 424.31208 -383.119884) (xy 424.33396 -383.145536)
			(xy 424.37205 -383.201172) (xy 424.403201 -383.26097) (xy 424.426837 -383.323727) (xy 425.528942 -383.323727)
			(xy 425.528946 -383.256419) (xy 425.536993 -383.189594) (xy 425.55297 -383.12421) (xy 425.576646 -383.061204)
			(xy 425.607682 -383.00148) (xy 425.645635 -382.945892) (xy 425.667424 -382.92024) (xy 425.673231 -382.913103)
			(xy 425.679739 -382.895906) (xy 425.680124 -382.886712) (xy 425.680124 -382.728724) (xy 425.680536 -382.7186)
			(xy 425.688281 -382.699892) (xy 425.702599 -382.685576) (xy 425.721308 -382.677834) (xy 425.731432 -382.677416)
			(xy 426.447966 -382.677416) (xy 426.458088 -382.677954) (xy 426.476803 -382.685666) (xy 426.49116 -382.699937)
			(xy 426.498984 -382.718606) (xy 426.499528 -382.728724) (xy 426.499528 -382.886712) (xy 426.499926 -382.895901)
			(xy 426.506447 -382.913085) (xy 426.512228 -382.92024) (xy 426.533981 -382.945921) (xy 426.571933 -383.001502)
			(xy 426.60297 -383.061222) (xy 426.626646 -383.124223) (xy 426.642623 -383.189602) (xy 426.65067 -383.256422)
			(xy 426.650673 -383.323724) (xy 426.642632 -383.390545) (xy 426.626662 -383.455926) (xy 426.602992 -383.518929)
			(xy 426.571961 -383.578651) (xy 426.534014 -383.634236) (xy 426.512228 -383.659888) (xy 426.506403 -383.667013)
			(xy 426.499907 -383.684219) (xy 426.499528 -383.693416) (xy 426.499528 -384.186684) (xy 426.499939 -384.195871)
			(xy 426.506451 -384.213056) (xy 426.512228 -384.220212) (xy 426.534052 -384.245834) (xy 426.572002 -384.301424)
			(xy 426.603036 -384.361152) (xy 426.626708 -384.42416) (xy 426.64268 -384.489546) (xy 426.650721 -384.556373)
			(xy 426.650718 -384.623681) (xy 426.64267 -384.690507) (xy 426.626692 -384.755892) (xy 426.603014 -384.818898)
			(xy 426.571974 -384.878622) (xy 426.534019 -384.934208) (xy 426.512228 -384.95986) (xy 426.506415 -384.966993)
			(xy 426.499912 -384.984193) (xy 426.499528 -384.993388) (xy 426.499528 -385.151376) (xy 426.499065 -385.161494)
			(xy 426.49133 -385.180191) (xy 426.477028 -385.194505) (xy 426.458337 -385.202257) (xy 426.44822 -385.202684)
			(xy 425.731686 -385.202684) (xy 425.721561 -385.202185) (xy 425.702845 -385.194457) (xy 425.68849 -385.180175)
			(xy 425.680667 -385.161498) (xy 425.680124 -385.151376) (xy 425.680124 -384.993388) (xy 425.679714 -384.984201)
			(xy 425.6732 -384.967017) (xy 425.667424 -384.95986) (xy 425.645672 -384.934178) (xy 425.607723 -384.878596)
			(xy 425.576689 -384.818876) (xy 425.553015 -384.755876) (xy 425.53704 -384.690497) (xy 425.528994 -384.623678)
			(xy 425.52899 -384.556376) (xy 425.537031 -384.489556) (xy 425.552999 -384.424176) (xy 425.576667 -384.361173)
			(xy 425.607696 -384.301451) (xy 425.645639 -384.245865) (xy 425.667424 -384.220212) (xy 425.673243 -384.213083)
			(xy 425.679744 -384.19588) (xy 425.680124 -384.186684) (xy 425.680124 -383.693416) (xy 425.679701 -383.68423)
			(xy 425.673195 -383.667046) (xy 425.667424 -383.659888) (xy 425.645601 -383.634265) (xy 425.607655 -383.578674)
			(xy 425.576624 -383.518946) (xy 425.552954 -383.455938) (xy 425.536984 -383.390552) (xy 425.528942 -383.323727)
			(xy 424.426837 -383.323727) (xy 424.426965 -383.324068) (xy 424.443 -383.389559) (xy 424.451075 -383.456499)
			(xy 424.451074 -383.523925) (xy 424.442996 -383.590864) (xy 424.426958 -383.656355) (xy 424.403191 -383.719452)
			(xy 424.372038 -383.779249) (xy 424.333946 -383.834883) (xy 424.31208 -383.860548) (xy 424.306278 -383.867689)
			(xy 424.299767 -383.884883) (xy 424.29938 -383.894076) (xy 424.29938 -384.051556) (xy 424.298947 -384.061678)
			(xy 424.29121 -384.080385) (xy 424.276898 -384.094701) (xy 424.258194 -384.102444) (xy 424.248072 -384.102864)
			(xy 423.531792 -384.102864) (xy 423.521665 -384.10249) (xy 423.502954 -384.094732) (xy 423.488639 -384.080402)
			(xy 423.4809 -384.061684) (xy 423.480484 -384.051556) (xy 423.480484 -383.894076) (xy 423.480089 -383.884887)
			(xy 423.473565 -383.867703) (xy 423.467784 -383.860548) (xy 423.445936 -383.83487) (xy 423.407848 -383.779237)
			(xy 423.376698 -383.719442) (xy 423.352933 -383.656347) (xy 423.336897 -383.59086) (xy 423.32882 -383.523923)
			(xy 423.328819 -383.456501) (xy 423.336893 -383.389564) (xy 423.352926 -383.324076) (xy 423.376688 -383.26098)
			(xy 423.407836 -383.201184) (xy 423.445922 -383.145549) (xy 423.467784 -383.119884) (xy 423.473568 -383.11273)
			(xy 423.480091 -383.095546) (xy 423.480484 -383.086356) (xy 423.480484 -382.59385) (xy 423.480054 -382.584665)
			(xy 423.473554 -382.56748) (xy 423.467784 -382.560322) (xy 423.445911 -382.534665) (xy 423.407823 -382.479029)
			(xy 423.376674 -382.419231) (xy 423.352911 -382.356133) (xy 423.336877 -382.290643) (xy 423.328802 -382.223705)
			(xy 420.050731 -382.223705) (xy 420.042695 -382.290466) (xy 420.026725 -382.355847) (xy 420.003054 -382.418851)
			(xy 419.972024 -382.478574) (xy 419.934078 -382.534161) (xy 419.912292 -382.559814) (xy 419.906506 -382.566967)
			(xy 419.899985 -382.584151) (xy 419.899592 -382.593342) (xy 419.899592 -383.086864) (xy 419.900021 -383.096049)
			(xy 419.906522 -383.113234) (xy 419.912292 -383.120392) (xy 419.934094 -383.146032) (xy 419.972041 -383.201621)
			(xy 420.003072 -383.261346) (xy 420.02653 -383.323787) (xy 421.128623 -383.323787) (xy 421.128626 -383.256359)
			(xy 421.136706 -383.189418) (xy 421.152747 -383.123926) (xy 421.176516 -383.060828) (xy 421.207673 -383.001031)
			(xy 421.245769 -382.945397) (xy 421.267636 -382.919732) (xy 421.273449 -382.912598) (xy 421.279953 -382.895399)
			(xy 421.280336 -382.886204) (xy 421.280336 -382.728724) (xy 421.280736 -382.718599) (xy 421.288483 -382.699889)
			(xy 421.302805 -382.685572) (xy 421.321518 -382.677832) (xy 421.331644 -382.677416) (xy 422.047924 -382.677416)
			(xy 422.058036 -382.677866) (xy 422.076718 -382.685614) (xy 422.091013 -382.699922) (xy 422.098744 -382.718611)
			(xy 422.099232 -382.728724) (xy 422.099232 -382.886204) (xy 422.099656 -382.895389) (xy 422.106162 -382.912573)
			(xy 422.111932 -382.919732) (xy 422.133759 -382.945427) (xy 422.171847 -383.001058) (xy 422.202998 -383.06085)
			(xy 422.226762 -383.123943) (xy 422.242799 -383.189428) (xy 422.250878 -383.256363) (xy 422.250881 -383.323783)
			(xy 422.242809 -383.390718) (xy 422.226778 -383.456205) (xy 422.20302 -383.5193) (xy 422.171875 -383.579096)
			(xy 422.133793 -383.63473) (xy 422.111932 -383.660396) (xy 422.106146 -383.667549) (xy 422.099627 -383.684734)
			(xy 422.099232 -383.693924) (xy 422.099232 -384.186176) (xy 422.099669 -384.19536) (xy 422.106166 -384.212544)
			(xy 422.111932 -384.219704) (xy 422.13383 -384.245341) (xy 422.171916 -384.30098) (xy 422.203063 -384.36078)
			(xy 422.226824 -384.423881) (xy 422.242856 -384.489373) (xy 422.250928 -384.556314) (xy 422.250925 -384.62374)
			(xy 422.242846 -384.69068) (xy 422.226808 -384.756171) (xy 422.203041 -384.819269) (xy 422.171888 -384.879066)
			(xy 422.133797 -384.934702) (xy 422.111932 -384.960368) (xy 422.106116 -384.967499) (xy 422.099615 -384.984701)
			(xy 422.099232 -384.993896) (xy 422.099232 -385.151376) (xy 422.098696 -385.161479) (xy 422.090972 -385.180151)
			(xy 422.076691 -385.194445) (xy 422.058027 -385.202187) (xy 422.047924 -385.202684) (xy 421.331644 -385.202684)
			(xy 421.321522 -385.202247) (xy 421.302817 -385.194511) (xy 421.2885 -385.1802) (xy 421.280756 -385.161497)
			(xy 421.280336 -385.151376) (xy 421.280336 -384.993896) (xy 421.27992 -384.98471) (xy 421.27341 -384.967526)
			(xy 421.267636 -384.960368) (xy 421.245806 -384.934674) (xy 421.207714 -384.879045) (xy 421.17656 -384.819253)
			(xy 421.152792 -384.756159) (xy 421.136753 -384.690673) (xy 421.128674 -384.623738) (xy 421.12867 -384.556316)
			(xy 421.136743 -384.48938) (xy 421.152776 -384.423892) (xy 421.176538 -384.360797) (xy 421.207686 -384.301002)
			(xy 421.245773 -384.245369) (xy 421.267636 -384.219704) (xy 421.273418 -384.212549) (xy 421.27994 -384.195366)
			(xy 421.280336 -384.186176) (xy 421.280336 -383.693924) (xy 421.279906 -383.684739) (xy 421.273405 -383.667555)
			(xy 421.267636 -383.660396) (xy 421.245735 -383.634761) (xy 421.207645 -383.579123) (xy 421.176494 -383.519323)
			(xy 421.152731 -383.456222) (xy 421.136696 -383.390729) (xy 421.128623 -383.323787) (xy 420.02653 -383.323787)
			(xy 420.026742 -383.324352) (xy 420.042713 -383.389736) (xy 420.050756 -383.456559) (xy 420.050754 -383.523865)
			(xy 420.042709 -383.590688) (xy 420.026735 -383.656071) (xy 420.003062 -383.719076) (xy 419.972028 -383.7788)
			(xy 419.93408 -383.834387) (xy 419.912292 -383.86004) (xy 419.906495 -383.867185) (xy 419.899981 -383.884376)
			(xy 419.899592 -383.893568) (xy 419.899592 -384.051556) (xy 419.899148 -384.061677) (xy 419.891413 -384.080381)
			(xy 419.877104 -384.094697) (xy 419.858404 -384.102442) (xy 419.848284 -384.102864) (xy 419.13175 -384.102864)
			(xy 419.121627 -384.102333) (xy 419.102908 -384.094622) (xy 419.08855 -384.080349) (xy 419.080728 -384.061676)
			(xy 419.080188 -384.051556) (xy 419.080188 -383.893568) (xy 419.079796 -383.884379) (xy 419.07327 -383.867194)
			(xy 419.067488 -383.86004) (xy 419.045715 -383.834376) (xy 419.007762 -383.778792) (xy 418.976725 -383.719071)
			(xy 418.95305 -383.656068) (xy 418.937074 -383.590686) (xy 418.929028 -383.523864) (xy 418.929026 -383.45656)
			(xy 418.93707 -383.389737) (xy 418.953042 -383.324355) (xy 418.976716 -383.261351) (xy 419.00775 -383.201629)
			(xy 419.0457 -383.146043) (xy 419.067488 -383.120392) (xy 419.073269 -383.113236) (xy 419.079793 -383.096054)
			(xy 419.080188 -383.086864) (xy 419.080188 -382.593342) (xy 419.07976 -382.584157) (xy 419.073259 -382.566972)
			(xy 419.067488 -382.559814) (xy 419.045689 -382.534171) (xy 419.007737 -382.478584) (xy 418.976702 -382.41886)
			(xy 418.953027 -382.355854) (xy 418.937054 -382.29047) (xy 418.92901 -382.223646) (xy 389.250707 -382.223646)
			(xy 389.242664 -382.290467) (xy 389.226692 -382.355848) (xy 389.20302 -382.418853) (xy 389.171987 -382.478576)
			(xy 389.134039 -382.534162) (xy 389.112252 -382.559814) (xy 389.106461 -382.566963) (xy 389.099944 -382.584151)
			(xy 389.099552 -382.593342) (xy 389.099552 -383.086864) (xy 389.09999 -383.096048) (xy 389.106485 -383.113232)
			(xy 389.112252 -383.120392) (xy 389.134056 -383.146031) (xy 389.172005 -383.201619) (xy 389.203038 -383.261344)
			(xy 389.226475 -383.323726) (xy 390.329121 -383.323726) (xy 390.329125 -383.256419) (xy 390.337172 -383.189595)
			(xy 390.353147 -383.124211) (xy 390.376822 -383.061206) (xy 390.407857 -383.001481) (xy 390.445807 -382.945893)
			(xy 390.467596 -382.92024) (xy 390.4734 -382.9131) (xy 390.47991 -382.895906) (xy 390.480296 -382.886712)
			(xy 390.480296 -382.728724) (xy 390.480741 -382.718572) (xy 390.488528 -382.699821) (xy 390.502918 -382.685497)
			(xy 390.521704 -382.677795) (xy 390.531858 -382.677416) (xy 391.248138 -382.677416) (xy 391.258264 -382.677895)
			(xy 391.276982 -382.685631) (xy 391.291336 -382.699919) (xy 391.299158 -382.7186) (xy 391.2997 -382.728724)
			(xy 391.2997 -382.886712) (xy 391.300105 -382.8959) (xy 391.306622 -382.913084) (xy 391.3124 -382.92024)
			(xy 391.334151 -382.945922) (xy 391.372099 -383.001505) (xy 391.403131 -383.061225) (xy 391.426804 -383.124225)
			(xy 391.442779 -383.189603) (xy 391.450825 -383.256422) (xy 391.450828 -383.323724) (xy 391.442788 -383.390543)
			(xy 391.42682 -383.455923) (xy 391.403153 -383.518926) (xy 391.372126 -383.578649) (xy 391.334184 -383.634235)
			(xy 391.3124 -383.659888) (xy 391.306584 -383.667019) (xy 391.300081 -383.68422) (xy 391.2997 -383.693416)
			(xy 391.2997 -384.186684) (xy 391.300118 -384.19587) (xy 391.306626 -384.213055) (xy 391.3124 -384.220212)
			(xy 391.334222 -384.245836) (xy 391.372167 -384.301427) (xy 391.403197 -384.361155) (xy 391.426866 -384.424163)
			(xy 391.442835 -384.489548) (xy 391.450876 -384.556374) (xy 391.450872 -384.623681) (xy 391.442825 -384.690505)
			(xy 391.42685 -384.755889) (xy 391.403175 -384.818895) (xy 391.372139 -384.878619) (xy 391.334189 -384.934207)
			(xy 391.3124 -384.95986) (xy 391.306595 -384.967) (xy 391.300086 -384.984194) (xy 391.2997 -384.993388)
			(xy 391.2997 -385.151376) (xy 391.299259 -385.161529) (xy 391.291471 -385.180281) (xy 391.27708 -385.194605)
			(xy 391.258292 -385.202305) (xy 391.248138 -385.202684) (xy 390.531858 -385.202684) (xy 390.521732 -385.202209)
			(xy 390.503014 -385.194471) (xy 390.48866 -385.180182) (xy 390.480838 -385.1615) (xy 390.480296 -385.151376)
			(xy 390.480296 -384.993388) (xy 390.479892 -384.9842) (xy 390.473374 -384.967016) (xy 390.467596 -384.95986)
			(xy 390.445845 -384.934178) (xy 390.407898 -384.878595) (xy 390.376865 -384.818875) (xy 390.353192 -384.755875)
			(xy 390.337218 -384.690496) (xy 390.329172 -384.623678) (xy 390.329169 -384.556376) (xy 390.337209 -384.489557)
			(xy 390.353176 -384.424177) (xy 390.376843 -384.361174) (xy 390.40787 -384.301452) (xy 390.445812 -384.245865)
			(xy 390.467596 -384.220212) (xy 390.473412 -384.21308) (xy 390.479915 -384.19588) (xy 390.480296 -384.186684)
			(xy 390.480296 -383.693416) (xy 390.479879 -383.68423) (xy 390.47337 -383.667045) (xy 390.467596 -383.659888)
			(xy 390.445774 -383.634264) (xy 390.407829 -383.578673) (xy 390.3768 -383.518945) (xy 390.353131 -383.455937)
			(xy 390.337162 -383.390552) (xy 390.329121 -383.323726) (xy 389.226475 -383.323726) (xy 389.22671 -383.324351)
			(xy 389.242682 -383.389735) (xy 389.250725 -383.456559) (xy 389.250724 -383.523865) (xy 389.242678 -383.590689)
			(xy 389.226703 -383.656072) (xy 389.203028 -383.719078) (xy 389.171992 -383.778802) (xy 389.134041 -383.834388)
			(xy 389.112252 -383.86004) (xy 389.10645 -383.867181) (xy 389.09994 -383.884375) (xy 389.099552 -383.893568)
			(xy 389.099552 -384.051556) (xy 389.099043 -384.061701) (xy 389.091272 -384.080442) (xy 389.076902 -384.094765)
			(xy 389.058136 -384.102476) (xy 389.04799 -384.102864) (xy 388.33171 -384.102864) (xy 388.321584 -384.102365)
			(xy 388.302864 -384.094642) (xy 388.288508 -384.080359) (xy 388.280687 -384.061679) (xy 388.280148 -384.051556)
			(xy 388.280148 -383.893568) (xy 388.279742 -383.884381) (xy 388.273224 -383.867197) (xy 388.267448 -383.86004)
			(xy 388.245676 -383.834375) (xy 388.207726 -383.778791) (xy 388.176692 -383.719069) (xy 388.153018 -383.656066)
			(xy 388.137043 -383.590685) (xy 388.128998 -383.523864) (xy 388.128996 -383.45656) (xy 388.137039 -383.389738)
			(xy 388.15301 -383.324357) (xy 388.176682 -383.261353) (xy 388.207714 -383.20163) (xy 388.245661 -383.146044)
			(xy 388.267448 -383.120392) (xy 388.273236 -383.113241) (xy 388.279755 -383.096055) (xy 388.280148 -383.086864)
			(xy 388.280148 -382.593342) (xy 388.279707 -382.584158) (xy 388.273213 -382.566974) (xy 388.267448 -382.559814)
			(xy 388.24565 -382.53417) (xy 388.207701 -382.478583) (xy 388.176668 -382.418858) (xy 388.152995 -382.355852)
			(xy 388.137022 -382.290469) (xy 388.128979 -382.223645) (xy 384.850917 -382.223645) (xy 384.842874 -382.290466)
			(xy 384.826902 -382.355848) (xy 384.803231 -382.418852) (xy 384.772199 -382.478576) (xy 384.734251 -382.534162)
			(xy 384.712464 -382.559814) (xy 384.706674 -382.566964) (xy 384.700156 -382.584151) (xy 384.699764 -382.593342)
			(xy 384.699764 -383.086864) (xy 384.7002 -383.096048) (xy 384.706697 -383.113232) (xy 384.712464 -383.120392)
			(xy 384.734267 -383.146031) (xy 384.772216 -383.20162) (xy 384.803248 -383.261345) (xy 384.826708 -383.323786)
			(xy 385.928802 -383.323786) (xy 385.928805 -383.25636) (xy 385.936885 -383.189419) (xy 385.952924 -383.123928)
			(xy 385.976693 -383.060829) (xy 386.007848 -383.001032) (xy 386.045942 -382.945397) (xy 386.067808 -382.919732)
			(xy 386.073617 -382.912596) (xy 386.080124 -382.895398) (xy 386.080508 -382.886204) (xy 386.080508 -382.728724)
			(xy 386.080936 -382.718602) (xy 386.088677 -382.699897) (xy 386.102991 -382.685582) (xy 386.121694 -382.677837)
			(xy 386.131816 -382.677416) (xy 386.848096 -382.677416) (xy 386.85822 -382.67782) (xy 386.876927 -382.685569)
			(xy 386.891242 -382.69989) (xy 386.898984 -382.7186) (xy 386.899404 -382.728724) (xy 386.899404 -382.886204)
			(xy 386.899811 -382.895391) (xy 386.906327 -382.912576) (xy 386.912104 -382.919732) (xy 386.933932 -382.945426)
			(xy 386.972022 -383.001057) (xy 387.003174 -383.060849) (xy 387.02694 -383.123942) (xy 387.042978 -383.189428)
			(xy 387.051057 -383.256363) (xy 387.05106 -383.323783) (xy 387.042988 -383.390719) (xy 387.026956 -383.456206)
			(xy 387.003196 -383.519301) (xy 386.97205 -383.579097) (xy 386.933966 -383.634731) (xy 386.912104 -383.660396)
			(xy 386.906327 -383.667555) (xy 386.899801 -383.684735) (xy 386.899404 -383.693924) (xy 386.899404 -384.186176)
			(xy 386.899825 -384.195362) (xy 386.906331 -384.212547) (xy 386.912104 -384.219704) (xy 386.934003 -384.24534)
			(xy 386.972091 -384.300979) (xy 387.003239 -384.360779) (xy 387.027001 -384.42388) (xy 387.043034 -384.489372)
			(xy 387.051107 -384.556314) (xy 387.051104 -384.62374) (xy 387.043025 -384.690681) (xy 387.026985 -384.756172)
			(xy 387.003217 -384.81927) (xy 386.972063 -384.879068) (xy 386.93397 -384.934703) (xy 386.912104 -384.960368)
			(xy 386.906297 -384.967506) (xy 386.899788 -384.984702) (xy 386.899404 -384.993896) (xy 386.899404 -385.151376)
			(xy 386.898965 -385.161496) (xy 386.891225 -385.180199) (xy 386.876916 -385.194514) (xy 386.858216 -385.202261)
			(xy 386.848096 -385.202684) (xy 386.131816 -385.202684) (xy 386.121693 -385.202271) (xy 386.102986 -385.194525)
			(xy 386.088671 -385.180207) (xy 386.080928 -385.1615) (xy 386.080508 -385.151376) (xy 386.080508 -384.993896)
			(xy 386.080098 -384.984709) (xy 386.073584 -384.967525) (xy 386.067808 -384.960368) (xy 386.045979 -384.934674)
			(xy 386.007889 -384.879044) (xy 385.976736 -384.819251) (xy 385.95297 -384.756158) (xy 385.936931 -384.690673)
			(xy 385.928852 -384.623738) (xy 385.928849 -384.556317) (xy 385.936922 -384.489381) (xy 385.952954 -384.423893)
			(xy 385.976714 -384.360798) (xy 386.007861 -384.301003) (xy 386.045946 -384.245369) (xy 386.067808 -384.219704)
			(xy 386.073586 -384.212546) (xy 386.080112 -384.195365) (xy 386.080508 -384.186176) (xy 386.080508 -383.693924)
			(xy 386.080084 -383.684738) (xy 386.07358 -383.667554) (xy 386.067808 -383.660396) (xy 386.045908 -383.63476)
			(xy 386.00782 -383.579122) (xy 385.976671 -383.519321) (xy 385.952908 -383.456221) (xy 385.936875 -383.390728)
			(xy 385.928802 -383.323786) (xy 384.826708 -383.323786) (xy 384.82692 -383.324351) (xy 384.842892 -383.389735)
			(xy 384.850934 -383.456559) (xy 384.850933 -383.523865) (xy 384.842887 -383.590689) (xy 384.826913 -383.656072)
			(xy 384.803238 -383.719077) (xy 384.772203 -383.778801) (xy 384.734253 -383.834388) (xy 384.712464 -383.86004)
			(xy 384.706663 -383.867182) (xy 384.700152 -383.884375) (xy 384.699764 -383.893568) (xy 384.699764 -384.051556)
			(xy 384.699342 -384.061712) (xy 384.691554 -384.08047) (xy 384.677156 -384.094796) (xy 384.65836 -384.102491)
			(xy 384.648202 -384.102864) (xy 383.931922 -384.102864) (xy 383.921797 -384.102356) (xy 383.903077 -384.094636)
			(xy 383.88872 -384.080356) (xy 383.8809 -384.061678) (xy 383.88036 -384.051556) (xy 383.88036 -383.893568)
			(xy 383.879952 -383.884381) (xy 383.873435 -383.867197) (xy 383.86766 -383.86004) (xy 383.845887 -383.834375)
			(xy 383.807937 -383.778791) (xy 383.776902 -383.719069) (xy 383.753227 -383.656066) (xy 383.737252 -383.590686)
			(xy 383.729207 -383.523864) (xy 383.729205 -383.45656) (xy 383.737248 -383.389738) (xy 383.75322 -383.324357)
			(xy 383.776892 -383.261353) (xy 383.807924 -383.20163) (xy 383.845873 -383.146044) (xy 383.86766 -383.120392)
			(xy 383.87345 -383.113242) (xy 383.879967 -383.096055) (xy 383.88036 -383.086864) (xy 383.88036 -382.593342)
			(xy 383.879916 -382.584159) (xy 383.873425 -382.566975) (xy 383.86766 -382.559814) (xy 383.845862 -382.53417)
			(xy 383.807912 -382.478583) (xy 383.776878 -382.418858) (xy 383.753205 -382.355853) (xy 383.737232 -382.290469)
			(xy 383.729188 -382.223646) (xy 380.451149 -382.223646) (xy 380.451149 -382.223704) (xy 380.443073 -382.290642)
			(xy 380.427038 -382.356131) (xy 380.403273 -382.419228) (xy 380.372122 -382.479024) (xy 380.334032 -382.534657)
			(xy 380.312168 -382.560322) (xy 380.306375 -382.56747) (xy 380.299859 -382.584658) (xy 380.299468 -382.59385)
			(xy 380.299468 -383.086356) (xy 380.299907 -383.09554) (xy 380.306401 -383.112724) (xy 380.312168 -383.119884)
			(xy 380.334049 -383.145536) (xy 380.372139 -383.201171) (xy 380.403291 -383.260969) (xy 380.426928 -383.323727)
			(xy 381.529033 -383.323727) (xy 381.529037 -383.256419) (xy 381.537084 -383.189595) (xy 381.55306 -383.124211)
			(xy 381.576736 -383.061205) (xy 381.607772 -383.00148) (xy 381.645723 -382.945893) (xy 381.667512 -382.92024)
			(xy 381.673318 -382.913101) (xy 381.679827 -382.895906) (xy 381.680212 -382.886712) (xy 381.680212 -382.728724)
			(xy 381.680641 -382.71857) (xy 381.688431 -382.699816) (xy 381.702826 -382.685491) (xy 381.721618 -382.677793)
			(xy 381.731774 -382.677416) (xy 382.448054 -382.677416) (xy 382.458175 -382.677964) (xy 382.47689 -382.685672)
			(xy 382.491247 -382.699939) (xy 382.499072 -382.718606) (xy 382.499616 -382.728724) (xy 382.499616 -382.886712)
			(xy 382.500017 -382.8959) (xy 382.506537 -382.913085) (xy 382.512316 -382.92024) (xy 382.53407 -382.945921)
			(xy 382.572023 -383.001502) (xy 382.60306 -383.061221) (xy 382.626737 -383.124222) (xy 382.642713 -383.189601)
			(xy 382.650761 -383.256421) (xy 382.650764 -383.323724) (xy 382.642723 -383.390545) (xy 382.626753 -383.455926)
			(xy 382.603082 -383.518929) (xy 382.57205 -383.578652) (xy 382.534103 -383.634236) (xy 382.512316 -383.659888)
			(xy 382.506501 -383.667021) (xy 382.499997 -383.684221) (xy 382.499616 -383.693416) (xy 382.499616 -384.186684)
			(xy 382.50003 -384.195871) (xy 382.506541 -384.213055) (xy 382.512316 -384.220212) (xy 382.53414 -384.245834)
			(xy 382.572091 -384.301424) (xy 382.603125 -384.361151) (xy 382.626798 -384.42416) (xy 382.64277 -384.489546)
			(xy 382.650812 -384.556373) (xy 382.650808 -384.623681) (xy 382.64276 -384.690507) (xy 382.626782 -384.755892)
			(xy 382.603103 -384.818898) (xy 382.572063 -384.878622) (xy 382.534107 -384.934208) (xy 382.512316 -384.95986)
			(xy 382.506513 -384.967001) (xy 382.500002 -384.984195) (xy 382.499616 -384.993388) (xy 382.499616 -385.151376)
			(xy 382.499159 -385.161527) (xy 382.491375 -385.180275) (xy 382.476989 -385.194599) (xy 382.458206 -385.202303)
			(xy 382.448054 -385.202684) (xy 381.731774 -385.202684) (xy 381.721649 -385.202196) (xy 381.702931 -385.194464)
			(xy 381.688577 -385.180179) (xy 381.680754 -385.161499) (xy 381.680212 -385.151376) (xy 381.680212 -384.993388)
			(xy 381.679805 -384.984201) (xy 381.673289 -384.967016) (xy 381.667512 -384.95986) (xy 381.64576 -384.934178)
			(xy 381.607812 -384.878596) (xy 381.576779 -384.818876) (xy 381.553105 -384.755875) (xy 381.537131 -384.690497)
			(xy 381.529084 -384.623678) (xy 381.529081 -384.556376) (xy 381.537121 -384.489557) (xy 381.553089 -384.424177)
			(xy 381.576757 -384.361174) (xy 381.607784 -384.301451) (xy 381.645727 -384.245864) (xy 381.667512 -384.220212)
			(xy 381.67333 -384.213082) (xy 381.679831 -384.19588) (xy 381.680212 -384.186684) (xy 381.680212 -383.693416)
			(xy 381.679791 -383.68423) (xy 381.673285 -383.667046) (xy 381.667512 -383.659888) (xy 381.64569 -383.634265)
			(xy 381.607744 -383.578673) (xy 381.576714 -383.518946) (xy 381.553044 -383.455937) (xy 381.537074 -383.390552)
			(xy 381.529033 -383.323727) (xy 380.426928 -383.323727) (xy 380.427056 -383.324068) (xy 380.443091 -383.389559)
			(xy 380.451166 -383.456499) (xy 380.451165 -383.523925) (xy 380.443087 -383.590865) (xy 380.427049 -383.656355)
			(xy 380.403281 -383.719453) (xy 380.372127 -383.779249) (xy 380.334034 -383.834883) (xy 380.312168 -383.860548)
			(xy 380.306364 -383.867688) (xy 380.299855 -383.884883) (xy 380.299468 -383.894076) (xy 380.299468 -384.051556)
			(xy 380.299047 -384.06168) (xy 380.291308 -384.080388) (xy 380.276992 -384.094705) (xy 380.258284 -384.102446)
			(xy 380.24816 -384.102864) (xy 379.53188 -384.102864) (xy 379.521752 -384.1025) (xy 379.503041 -384.094738)
			(xy 379.488726 -384.080405) (xy 379.480988 -384.061685) (xy 379.480572 -384.051556) (xy 379.480572 -383.894076)
			(xy 379.48018 -383.884887) (xy 379.473654 -383.867702) (xy 379.467872 -383.860548) (xy 379.446025 -383.834869)
			(xy 379.407937 -383.779236) (xy 379.376788 -383.719441) (xy 379.353024 -383.656346) (xy 379.336988 -383.590859)
			(xy 379.328911 -383.523923) (xy 379.32891 -383.456501) (xy 379.336984 -383.389564) (xy 379.353017 -383.324077)
			(xy 379.376778 -383.260981) (xy 379.407925 -383.201185) (xy 379.44601 -383.14555) (xy 379.467872 -383.119884)
			(xy 379.473667 -383.112738) (xy 379.48018 -383.095548) (xy 379.480572 -383.086356) (xy 379.480572 -382.59385)
			(xy 379.480144 -382.584665) (xy 379.473643 -382.56748) (xy 379.467872 -382.560322) (xy 379.445999 -382.534664)
			(xy 379.407913 -382.479028) (xy 379.376764 -382.419231) (xy 379.353002 -382.356133) (xy 379.336968 -382.290643)
			(xy 379.328893 -382.223704) (xy 376.050822 -382.223704) (xy 376.042786 -382.290466) (xy 376.026815 -382.355847)
			(xy 376.003144 -382.418851) (xy 375.972113 -382.478575) (xy 375.934167 -382.534162) (xy 375.91238 -382.559814)
			(xy 375.906593 -382.566966) (xy 375.900073 -382.584151) (xy 375.89968 -382.593342) (xy 375.89968 -383.086864)
			(xy 375.900112 -383.096049) (xy 375.906611 -383.113233) (xy 375.91238 -383.120392) (xy 375.934183 -383.146031)
			(xy 375.97213 -383.20162) (xy 376.003162 -383.261346) (xy 376.02662 -383.323786) (xy 377.128714 -383.323786)
			(xy 377.128717 -383.256359) (xy 377.136797 -383.189418) (xy 377.152837 -383.123927) (xy 377.176606 -383.060828)
			(xy 377.207762 -383.001031) (xy 377.245857 -382.945397) (xy 377.267724 -382.919732) (xy 377.273535 -382.912597)
			(xy 377.28004 -382.895399) (xy 377.280424 -382.886204) (xy 377.280424 -382.728724) (xy 377.280836 -382.7186)
			(xy 377.288581 -382.699892) (xy 377.302899 -382.685576) (xy 377.321608 -382.677834) (xy 377.331732 -382.677416)
			(xy 378.048012 -382.677416) (xy 378.058137 -382.677806) (xy 378.076844 -382.685561) (xy 378.091159 -382.699886)
			(xy 378.098901 -382.718598) (xy 378.09932 -382.728724) (xy 378.09932 -382.886204) (xy 378.099724 -382.895392)
			(xy 378.106241 -382.912576) (xy 378.11202 -382.919732) (xy 378.133848 -382.945427) (xy 378.171936 -383.001058)
			(xy 378.203088 -383.06085) (xy 378.226853 -383.123943) (xy 378.24289 -383.189428) (xy 378.250969 -383.256363)
			(xy 378.250972 -383.323783) (xy 378.2429 -383.390719) (xy 378.226869 -383.456205) (xy 378.20311 -383.519301)
			(xy 378.171964 -383.579096) (xy 378.133881 -383.63473) (xy 378.11202 -383.660396) (xy 378.106245 -383.667557)
			(xy 378.099717 -383.684735) (xy 378.09932 -383.693924) (xy 378.09932 -384.186176) (xy 378.099737 -384.195363)
			(xy 378.106245 -384.212547) (xy 378.11202 -384.219704) (xy 378.133919 -384.24534) (xy 378.172005 -384.30098)
			(xy 378.203153 -384.36078) (xy 378.226914 -384.423881) (xy 378.242947 -384.489373) (xy 378.251019 -384.556314)
			(xy 378.251016 -384.62374) (xy 378.242937 -384.69068) (xy 378.226898 -384.756171) (xy 378.203131 -384.81927)
			(xy 378.171977 -384.879067) (xy 378.133885 -384.934702) (xy 378.11202 -384.960368) (xy 378.106214 -384.967507)
			(xy 378.099704 -384.984702) (xy 378.09932 -384.993896) (xy 378.09932 -385.151376) (xy 378.098865 -385.161494)
			(xy 378.091128 -385.180194) (xy 378.076824 -385.194508) (xy 378.05813 -385.202258) (xy 378.048012 -385.202684)
			(xy 377.331732 -385.202684) (xy 377.32161 -385.202258) (xy 377.302903 -385.194517) (xy 377.288587 -385.180203)
			(xy 377.280844 -385.161498) (xy 377.280424 -385.151376) (xy 377.280424 -384.993896) (xy 377.280011 -384.984709)
			(xy 377.273499 -384.967525) (xy 377.267724 -384.960368) (xy 377.245895 -384.934674) (xy 377.207803 -384.879044)
			(xy 377.17665 -384.819252) (xy 377.152882 -384.756159) (xy 377.136844 -384.690673) (xy 377.128765 -384.623738)
			(xy 377.128761 -384.556316) (xy 377.136834 -384.48938) (xy 377.152866 -384.423893) (xy 377.176627 -384.360797)
			(xy 377.207775 -384.301002) (xy 377.245861 -384.245369) (xy 377.267724 -384.219704) (xy 377.273504 -384.212547)
			(xy 377.280028 -384.195365) (xy 377.280424 -384.186176) (xy 377.280424 -383.693924) (xy 377.279997 -383.684739)
			(xy 377.273494 -383.667555) (xy 377.267724 -383.660396) (xy 377.245824 -383.63476) (xy 377.207735 -383.579122)
			(xy 377.176584 -383.519322) (xy 377.152821 -383.456221) (xy 377.136787 -383.390728) (xy 377.128714 -383.323786)
			(xy 376.02662 -383.323786) (xy 376.026833 -383.324352) (xy 376.042804 -383.389735) (xy 376.050846 -383.456559)
			(xy 376.050845 -383.523865) (xy 376.0428 -383.590688) (xy 376.026826 -383.656071) (xy 376.003152 -383.719076)
			(xy 375.972118 -383.778801) (xy 375.934168 -383.834388) (xy 375.91238 -383.86004) (xy 375.906582 -383.867184)
			(xy 375.900069 -383.884375) (xy 375.89968 -383.893568) (xy 375.89968 -384.051556) (xy 375.899242 -384.06171)
			(xy 375.891457 -384.080465) (xy 375.877065 -384.094791) (xy 375.858274 -384.102488) (xy 375.848118 -384.102864)
			(xy 375.131838 -384.102864) (xy 375.121714 -384.102342) (xy 375.102995 -384.094628) (xy 375.088637 -384.080352)
			(xy 375.080816 -384.061677) (xy 375.080276 -384.051556) (xy 375.080276 -383.893568) (xy 375.079886 -383.884379)
			(xy 375.073359 -383.867194) (xy 375.067576 -383.86004) (xy 375.045803 -383.834375) (xy 375.007851 -383.778792)
			(xy 374.976815 -383.71907) (xy 374.95314 -383.656067) (xy 374.937165 -383.590686) (xy 374.929119 -383.523864)
			(xy 374.929117 -383.45656) (xy 374.93716 -383.389738) (xy 374.953133 -383.324356) (xy 374.976805 -383.261352)
			(xy 375.007839 -383.201629) (xy 375.045788 -383.146044) (xy 375.067576 -383.120392) (xy 375.073356 -383.113235)
			(xy 375.079881 -383.096054) (xy 375.080276 -383.086864) (xy 375.080276 -382.593342) (xy 375.079851 -382.584156)
			(xy 375.073348 -382.566971) (xy 375.067576 -382.559814) (xy 375.045777 -382.53417) (xy 375.007826 -382.478584)
			(xy 374.976792 -382.418859) (xy 374.953118 -382.355853) (xy 374.937144 -382.29047) (xy 374.9291 -382.223646)
			(xy 345.250798 -382.223646) (xy 345.242755 -382.290467) (xy 345.226782 -382.355849) (xy 345.20311 -382.418853)
			(xy 345.172077 -382.478576) (xy 345.134128 -382.534162) (xy 345.11234 -382.559814) (xy 345.106548 -382.566962)
			(xy 345.100032 -382.584151) (xy 345.09964 -382.593342) (xy 345.09964 -383.086864) (xy 345.100081 -383.096048)
			(xy 345.106575 -383.113232) (xy 345.11234 -383.120392) (xy 345.134144 -383.146031) (xy 345.172094 -383.201619)
			(xy 345.203127 -383.261344) (xy 345.226566 -383.323727) (xy 346.329188 -383.323727) (xy 346.329192 -383.256419)
			(xy 346.33724 -383.189593) (xy 346.353218 -383.124208) (xy 346.376897 -383.061202) (xy 346.407937 -383.001478)
			(xy 346.445893 -382.945892) (xy 346.467684 -382.92024) (xy 346.473487 -382.913099) (xy 346.479998 -382.895905)
			(xy 346.480384 -382.886712) (xy 346.480384 -382.728724) (xy 346.480841 -382.718573) (xy 346.488625 -382.699825)
			(xy 346.503011 -382.685501) (xy 346.521794 -382.677797) (xy 346.531946 -382.677416) (xy 347.248226 -382.677416)
			(xy 347.258351 -382.677904) (xy 347.277069 -382.685636) (xy 347.291423 -382.699921) (xy 347.299246 -382.718601)
			(xy 347.299788 -382.728724) (xy 347.299788 -382.886712) (xy 347.300195 -382.895899) (xy 347.306711 -382.913084)
			(xy 347.312488 -382.92024) (xy 347.33424 -382.945922) (xy 347.372188 -383.001504) (xy 347.403221 -383.061224)
			(xy 347.426895 -383.124225) (xy 347.442869 -383.189603) (xy 347.450916 -383.256422) (xy 347.450919 -383.323724)
			(xy 347.442879 -383.390543) (xy 347.426911 -383.455923) (xy 347.403243 -383.518926) (xy 347.372216 -383.578649)
			(xy 347.334273 -383.634236) (xy 347.312488 -383.659888) (xy 347.30667 -383.667018) (xy 347.300169 -383.68422)
			(xy 347.299788 -383.693416) (xy 347.299788 -384.186684) (xy 347.300209 -384.19587) (xy 347.306715 -384.213054)
			(xy 347.312488 -384.220212) (xy 347.33431 -384.245835) (xy 347.372256 -384.301427) (xy 347.403286 -384.361154)
			(xy 347.426956 -384.424163) (xy 347.442926 -384.489548) (xy 347.450967 -384.556373) (xy 347.450963 -384.623681)
			(xy 347.442916 -384.690505) (xy 347.42694 -384.755889) (xy 347.403264 -384.818895) (xy 347.372228 -384.87862)
			(xy 347.334277 -384.934207) (xy 347.312488 -384.95986) (xy 347.306682 -384.966999) (xy 347.300173 -384.984194)
			(xy 347.299788 -384.993388) (xy 347.299788 -385.151376) (xy 347.299359 -385.16153) (xy 347.291569 -385.180284)
			(xy 347.277174 -385.194609) (xy 347.258382 -385.202307) (xy 347.248226 -385.202684) (xy 346.531946 -385.202684)
			(xy 346.521825 -385.202136) (xy 346.50311 -385.194428) (xy 346.488753 -385.180161) (xy 346.480928 -385.161494)
			(xy 346.480384 -385.151376) (xy 346.480384 -384.993388) (xy 346.479983 -384.9842) (xy 346.473463 -384.967015)
			(xy 346.467684 -384.95986) (xy 346.44593 -384.934179) (xy 346.407977 -384.878598) (xy 346.37694 -384.818879)
			(xy 346.353263 -384.755878) (xy 346.337287 -384.690499) (xy 346.329239 -384.623679) (xy 346.329236 -384.556376)
			(xy 346.337277 -384.489555) (xy 346.353247 -384.424174) (xy 346.376918 -384.361171) (xy 346.40795 -384.301448)
			(xy 346.445897 -384.245864) (xy 346.467684 -384.220212) (xy 346.473499 -384.213079) (xy 346.480003 -384.195879)
			(xy 346.480384 -384.186684) (xy 346.480384 -383.693416) (xy 346.47997 -383.684229) (xy 346.473459 -383.667045)
			(xy 346.467684 -383.659888) (xy 346.44586 -383.634266) (xy 346.407909 -383.578676) (xy 346.376875 -383.518949)
			(xy 346.353202 -383.45594) (xy 346.33723 -383.390554) (xy 346.329188 -383.323727) (xy 345.226566 -383.323727)
			(xy 345.2268 -383.32435) (xy 345.242773 -383.389734) (xy 345.250816 -383.456559) (xy 345.250814 -383.523865)
			(xy 345.242768 -383.590689) (xy 345.226793 -383.656073) (xy 345.203118 -383.719078) (xy 345.172081 -383.778802)
			(xy 345.134129 -383.834388) (xy 345.11234 -383.86004) (xy 345.106537 -383.86718) (xy 345.100028 -383.884375)
			(xy 345.09964 -383.893568) (xy 345.09964 -384.051556) (xy 345.099143 -384.061702) (xy 345.09137 -384.080446)
			(xy 345.076996 -384.094769) (xy 345.058226 -384.102478) (xy 345.048078 -384.102864) (xy 344.331798 -384.102864)
			(xy 344.321672 -384.102375) (xy 344.302951 -384.094647) (xy 344.288595 -384.080362) (xy 344.280775 -384.06168)
			(xy 344.280236 -384.051556) (xy 344.280236 -383.893568) (xy 344.279833 -383.88438) (xy 344.273313 -383.867196)
			(xy 344.267536 -383.86004) (xy 344.245764 -383.834375) (xy 344.207815 -383.77879) (xy 344.176781 -383.719068)
			(xy 344.153108 -383.656066) (xy 344.137134 -383.590685) (xy 344.129089 -383.523864) (xy 344.129087 -383.45656)
			(xy 344.13713 -383.389739) (xy 344.153101 -383.324358) (xy 344.176772 -383.261354) (xy 344.207803 -383.201631)
			(xy 344.24575 -383.146044) (xy 344.267536 -383.120392) (xy 344.273323 -383.11324) (xy 344.279843 -383.096055)
			(xy 344.280236 -383.086864) (xy 344.280236 -382.593342) (xy 344.279797 -382.584158) (xy 344.273303 -382.566974)
			(xy 344.267536 -382.559814) (xy 344.245738 -382.53417) (xy 344.20779 -382.478582) (xy 344.176757 -382.418858)
			(xy 344.153085 -382.355852) (xy 344.137113 -382.290469) (xy 344.12907 -382.223645) (xy 340.851007 -382.223645)
			(xy 340.842964 -382.290467) (xy 340.826992 -382.355848) (xy 340.80332 -382.418853) (xy 340.772287 -382.478576)
			(xy 340.734339 -382.534162) (xy 340.712552 -382.559814) (xy 340.706761 -382.566963) (xy 340.700244 -382.584151)
			(xy 340.699852 -382.593342) (xy 340.699852 -383.086864) (xy 340.70029 -383.096048) (xy 340.706785 -383.113232)
			(xy 340.712552 -383.120392) (xy 340.734356 -383.146031) (xy 340.772305 -383.201619) (xy 340.803338 -383.261344)
			(xy 340.826798 -383.323786) (xy 341.928893 -383.323786) (xy 341.928896 -383.25636) (xy 341.936975 -383.189419)
			(xy 341.953015 -383.123928) (xy 341.976783 -383.06083) (xy 342.007937 -383.001032) (xy 342.04603 -382.945397)
			(xy 342.067896 -382.919732) (xy 342.073703 -382.912594) (xy 342.080212 -382.895398) (xy 342.080596 -382.886204)
			(xy 342.080596 -382.728724) (xy 342.081035 -382.718604) (xy 342.088775 -382.699901) (xy 342.103084 -382.685586)
			(xy 342.121784 -382.677839) (xy 342.131904 -382.677416) (xy 342.848184 -382.677416) (xy 342.858307 -382.677829)
			(xy 342.877014 -382.685575) (xy 342.891329 -382.699893) (xy 342.899072 -382.7186) (xy 342.899492 -382.728724)
			(xy 342.899492 -382.886204) (xy 342.899902 -382.895391) (xy 342.906416 -382.912575) (xy 342.912192 -382.919732)
			(xy 342.934021 -382.945426) (xy 342.972111 -383.001056) (xy 343.003264 -383.060849) (xy 343.02703 -383.123942)
			(xy 343.043069 -383.189427) (xy 343.051148 -383.256362) (xy 343.051151 -383.323783) (xy 343.043078 -383.390719)
			(xy 343.027046 -383.456207) (xy 343.003286 -383.519302) (xy 342.972139 -383.579097) (xy 342.934054 -383.634731)
			(xy 342.912192 -383.660396) (xy 342.906414 -383.667554) (xy 342.899888 -383.684735) (xy 342.899492 -383.693924)
			(xy 342.899492 -384.186176) (xy 342.899916 -384.195362) (xy 342.90642 -384.212546) (xy 342.912192 -384.219704)
			(xy 342.934092 -384.24534) (xy 342.97218 -384.300978) (xy 343.003329 -384.360779) (xy 343.027092 -384.423879)
			(xy 343.043125 -384.489372) (xy 343.051198 -384.556314) (xy 343.051195 -384.62374) (xy 343.043115 -384.690681)
			(xy 343.027076 -384.756172) (xy 343.003307 -384.819271) (xy 342.972152 -384.879068) (xy 342.934058 -384.934703)
			(xy 342.912192 -384.960368) (xy 342.906383 -384.967504) (xy 342.899876 -384.984702) (xy 342.899492 -384.993896)
			(xy 342.899492 -385.151376) (xy 342.899064 -385.161498) (xy 342.891323 -385.180203) (xy 342.877009 -385.194518)
			(xy 342.858306 -385.202263) (xy 342.848184 -385.202684) (xy 342.131904 -385.202684) (xy 342.12178 -385.20228)
			(xy 342.103073 -385.194531) (xy 342.088758 -385.18021) (xy 342.081016 -385.1615) (xy 342.080596 -385.151376)
			(xy 342.080596 -384.993896) (xy 342.080189 -384.984709) (xy 342.073673 -384.967524) (xy 342.067896 -384.960368)
			(xy 342.046068 -384.934674) (xy 342.007978 -384.879043) (xy 341.976826 -384.819251) (xy 341.95306 -384.756158)
			(xy 341.937022 -384.690672) (xy 341.928943 -384.623737) (xy 341.92894 -384.556317) (xy 341.937012 -384.489381)
			(xy 341.953044 -384.423894) (xy 341.976804 -384.360799) (xy 342.00795 -384.301003) (xy 342.046034 -384.245369)
			(xy 342.067896 -384.219704) (xy 342.073673 -384.212545) (xy 342.080199 -384.195365) (xy 342.080596 -384.186176)
			(xy 342.080596 -383.693924) (xy 342.080175 -383.684738) (xy 342.073669 -383.667553) (xy 342.067896 -383.660396)
			(xy 342.045997 -383.63476) (xy 342.007909 -383.579121) (xy 341.976761 -383.519321) (xy 341.952999 -383.45622)
			(xy 341.936966 -383.390728) (xy 341.928893 -383.323786) (xy 340.826798 -383.323786) (xy 340.82701 -383.324351)
			(xy 340.842982 -383.389735) (xy 340.851025 -383.456559) (xy 340.851024 -383.523865) (xy 340.842978 -383.590689)
			(xy 340.827003 -383.656072) (xy 340.803328 -383.719078) (xy 340.772292 -383.778802) (xy 340.734341 -383.834388)
			(xy 340.712552 -383.86004) (xy 340.70675 -383.867181) (xy 340.70024 -383.884375) (xy 340.699852 -383.893568)
			(xy 340.699852 -384.051556) (xy 340.699343 -384.061701) (xy 340.691572 -384.080442) (xy 340.677202 -384.094765)
			(xy 340.658436 -384.102476) (xy 340.64829 -384.102864) (xy 339.93201 -384.102864) (xy 339.921884 -384.102365)
			(xy 339.903164 -384.094642) (xy 339.888808 -384.080359) (xy 339.880987 -384.061679) (xy 339.880448 -384.051556)
			(xy 339.880448 -383.893568) (xy 339.880042 -383.884381) (xy 339.873524 -383.867197) (xy 339.867748 -383.86004)
			(xy 339.845976 -383.834375) (xy 339.808026 -383.778791) (xy 339.776992 -383.719069) (xy 339.753318 -383.656066)
			(xy 339.737343 -383.590685) (xy 339.729298 -383.523864) (xy 339.729296 -383.45656) (xy 339.737339 -383.389738)
			(xy 339.75331 -383.324357) (xy 339.776982 -383.261353) (xy 339.808014 -383.20163) (xy 339.845961 -383.146044)
			(xy 339.867748 -383.120392) (xy 339.873536 -383.113241) (xy 339.880055 -383.096055) (xy 339.880448 -383.086864)
			(xy 339.880448 -382.593342) (xy 339.880007 -382.584158) (xy 339.873513 -382.566974) (xy 339.867748 -382.559814)
			(xy 339.84595 -382.53417) (xy 339.808001 -382.478583) (xy 339.776968 -382.418858) (xy 339.753295 -382.355852)
			(xy 339.737322 -382.290469) (xy 339.729279 -382.223645) (xy 336.45124 -382.223645) (xy 336.45124 -382.223704)
			(xy 336.443164 -382.290643) (xy 336.427128 -382.356132) (xy 336.403363 -382.419228) (xy 336.372211 -382.479024)
			(xy 336.334121 -382.534658) (xy 336.312256 -382.560322) (xy 336.306462 -382.567469) (xy 336.299947 -382.584658)
			(xy 336.299556 -382.59385) (xy 336.299556 -383.086356) (xy 336.299997 -383.09554) (xy 336.306491 -383.112724)
			(xy 336.312256 -383.119884) (xy 336.334137 -383.145536) (xy 336.372228 -383.201171) (xy 336.403381 -383.260969)
			(xy 336.427018 -383.323726) (xy 337.529124 -383.323726) (xy 337.529128 -383.256419) (xy 337.537175 -383.189595)
			(xy 337.55315 -383.124211) (xy 337.576825 -383.061205) (xy 337.607861 -383.001481) (xy 337.645811 -382.945893)
			(xy 337.6676 -382.92024) (xy 337.673405 -382.9131) (xy 337.679914 -382.895906) (xy 337.6803 -382.886712)
			(xy 337.6803 -382.728724) (xy 337.680741 -382.718571) (xy 337.688529 -382.699819) (xy 337.70292 -382.685495)
			(xy 337.721708 -382.677795) (xy 337.731862 -382.677416) (xy 338.448142 -382.677416) (xy 338.458268 -382.677891)
			(xy 338.476986 -382.685629) (xy 338.49134 -382.699918) (xy 338.499162 -382.7186) (xy 338.499704 -382.728724)
			(xy 338.499704 -382.886712) (xy 338.500108 -382.8959) (xy 338.506626 -382.913084) (xy 338.512404 -382.92024)
			(xy 338.534155 -382.945922) (xy 338.572102 -383.001505) (xy 338.603135 -383.061225) (xy 338.626808 -383.124225)
			(xy 338.642782 -383.189604) (xy 338.650828 -383.256422) (xy 338.650831 -383.323724) (xy 338.642791 -383.390543)
			(xy 338.626824 -383.455923) (xy 338.603157 -383.518926) (xy 338.57213 -383.578648) (xy 338.534188 -383.634235)
			(xy 338.512404 -383.659888) (xy 338.506588 -383.66702) (xy 338.500085 -383.68422) (xy 338.499704 -383.693416)
			(xy 338.499704 -384.186684) (xy 338.500121 -384.19587) (xy 338.50663 -384.213055) (xy 338.512404 -384.220212)
			(xy 338.534226 -384.245836) (xy 338.572171 -384.301427) (xy 338.6032 -384.361155) (xy 338.626869 -384.424163)
			(xy 338.642838 -384.489548) (xy 338.650879 -384.556374) (xy 338.650875 -384.623681) (xy 338.642828 -384.690505)
			(xy 338.626853 -384.755889) (xy 338.603178 -384.818894) (xy 338.572143 -384.878619) (xy 338.534193 -384.934207)
			(xy 338.512404 -384.95986) (xy 338.5066 -384.967) (xy 338.50009 -384.984194) (xy 338.499704 -384.993388)
			(xy 338.499704 -385.151376) (xy 338.499259 -385.161528) (xy 338.491472 -385.180279) (xy 338.477082 -385.194603)
			(xy 338.458296 -385.202305) (xy 338.448142 -385.202684) (xy 337.731862 -385.202684) (xy 337.721736 -385.202205)
			(xy 337.703018 -385.194469) (xy 337.688664 -385.180181) (xy 337.680842 -385.1615) (xy 337.6803 -385.151376)
			(xy 337.6803 -384.993388) (xy 337.679895 -384.9842) (xy 337.673378 -384.967016) (xy 337.6676 -384.95986)
			(xy 337.645849 -384.934178) (xy 337.607901 -384.878595) (xy 337.576869 -384.818875) (xy 337.553196 -384.755875)
			(xy 337.537221 -384.690497) (xy 337.529175 -384.623678) (xy 337.529172 -384.556376) (xy 337.537212 -384.489557)
			(xy 337.55318 -384.424177) (xy 337.576847 -384.361174) (xy 337.607874 -384.301451) (xy 337.645816 -384.245865)
			(xy 337.6676 -384.220212) (xy 337.673416 -384.213081) (xy 337.679919 -384.19588) (xy 337.6803 -384.186684)
			(xy 337.6803 -383.693416) (xy 337.679882 -383.68423) (xy 337.673374 -383.667045) (xy 337.6676 -383.659888)
			(xy 337.645778 -383.634264) (xy 337.607833 -383.578673) (xy 337.576803 -383.518945) (xy 337.553134 -383.455937)
			(xy 337.537165 -383.390552) (xy 337.529124 -383.323726) (xy 336.427018 -383.323726) (xy 336.427146 -383.324067)
			(xy 336.443182 -383.389559) (xy 336.451257 -383.456499) (xy 336.451256 -383.523925) (xy 336.443177 -383.590865)
			(xy 336.427139 -383.656356) (xy 336.403371 -383.719453) (xy 336.372216 -383.77925) (xy 336.334122 -383.834883)
			(xy 336.312256 -383.860548) (xy 336.306451 -383.867687) (xy 336.299943 -383.884882) (xy 336.299556 -383.894076)
			(xy 336.299556 -384.051556) (xy 336.29898 -384.061655) (xy 336.291267 -384.080321) (xy 336.276999 -384.094616)
			(xy 336.258346 -384.102362) (xy 336.248248 -384.102864) (xy 335.531968 -384.102864) (xy 335.521839 -384.102509)
			(xy 335.503128 -384.094744) (xy 335.488813 -384.080408) (xy 335.481076 -384.061686) (xy 335.48066 -384.051556)
			(xy 335.48066 -383.894076) (xy 335.480248 -383.884889) (xy 335.473734 -383.867706) (xy 335.46796 -383.860548)
			(xy 335.446113 -383.834869) (xy 335.408027 -383.779236) (xy 335.376877 -383.719441) (xy 335.353114 -383.656346)
			(xy 335.337079 -383.590859) (xy 335.329002 -383.523923) (xy 335.329001 -383.456501) (xy 335.337074 -383.389565)
			(xy 335.353107 -383.324077) (xy 335.376868 -383.260981) (xy 335.408014 -383.201185) (xy 335.446098 -383.14555)
			(xy 335.46796 -383.119884) (xy 335.473753 -383.112737) (xy 335.480268 -383.095548) (xy 335.48066 -383.086356)
			(xy 335.48066 -382.59385) (xy 335.480213 -382.584667) (xy 335.473723 -382.567483) (xy 335.46796 -382.560322)
			(xy 335.446088 -382.534664) (xy 335.408002 -382.479028) (xy 335.376854 -382.41923) (xy 335.353092 -382.356132)
			(xy 335.337058 -382.290643) (xy 335.328984 -382.223704) (xy 332.050913 -382.223704) (xy 332.042877 -382.290466)
			(xy 332.026905 -382.355848) (xy 332.003234 -382.418852) (xy 331.972202 -382.478575) (xy 331.934255 -382.534162)
			(xy 331.912468 -382.559814) (xy 331.906679 -382.566964) (xy 331.90016 -382.584151) (xy 331.899768 -382.593342)
			(xy 331.899768 -383.086864) (xy 331.900203 -383.096048) (xy 331.9067 -383.113233) (xy 331.912468 -383.120392)
			(xy 331.934271 -383.146031) (xy 331.972219 -383.20162) (xy 332.003251 -383.261345) (xy 332.026711 -383.323786)
			(xy 333.128805 -383.323786) (xy 333.128808 -383.25636) (xy 333.136888 -383.189419) (xy 333.152927 -383.123927)
			(xy 333.176696 -383.060829) (xy 333.207852 -383.001032) (xy 333.245945 -382.945397) (xy 333.267812 -382.919732)
			(xy 333.273621 -382.912596) (xy 333.280128 -382.895398) (xy 333.280512 -382.886204) (xy 333.280512 -382.728724)
			(xy 333.280936 -382.718602) (xy 333.288678 -382.699896) (xy 333.302993 -382.685581) (xy 333.321698 -382.677837)
			(xy 333.33182 -382.677416) (xy 334.0481 -382.677416) (xy 334.058224 -382.677816) (xy 334.076931 -382.685568)
			(xy 334.091246 -382.699889) (xy 334.098988 -382.718599) (xy 334.099408 -382.728724) (xy 334.099408 -382.886204)
			(xy 334.099815 -382.895392) (xy 334.106331 -382.912576) (xy 334.112108 -382.919732) (xy 334.133936 -382.945427)
			(xy 334.172026 -383.001057) (xy 334.203177 -383.060849) (xy 334.226943 -383.123942) (xy 334.242981 -383.189428)
			(xy 334.25106 -383.256363) (xy 334.251063 -383.323783) (xy 334.242991 -383.390719) (xy 334.226959 -383.456206)
			(xy 334.2032 -383.519301) (xy 334.172053 -383.579096) (xy 334.13397 -383.634731) (xy 334.112108 -383.660396)
			(xy 334.106332 -383.667556) (xy 334.099805 -383.684735) (xy 334.099408 -383.693924) (xy 334.099408 -384.186176)
			(xy 334.099828 -384.195362) (xy 334.106335 -384.212547) (xy 334.112108 -384.219704) (xy 334.134007 -384.24534)
			(xy 334.172094 -384.300979) (xy 334.203243 -384.360779) (xy 334.227005 -384.42388) (xy 334.243037 -384.489373)
			(xy 334.25111 -384.556314) (xy 334.251107 -384.62374) (xy 334.243028 -384.690681) (xy 334.226989 -384.756172)
			(xy 334.203221 -384.81927) (xy 334.172066 -384.879067) (xy 334.133974 -384.934703) (xy 334.112108 -384.960368)
			(xy 334.106301 -384.967506) (xy 334.099792 -384.984702) (xy 334.099408 -384.993896) (xy 334.099408 -385.151376)
			(xy 334.098965 -385.161496) (xy 334.091226 -385.180198) (xy 334.076918 -385.194512) (xy 334.05822 -385.20226)
			(xy 334.0481 -385.202684) (xy 333.33182 -385.202684) (xy 333.321697 -385.202267) (xy 333.302991 -385.194523)
			(xy 333.288675 -385.180206) (xy 333.280932 -385.161499) (xy 333.280512 -385.151376) (xy 333.280512 -384.993896)
			(xy 333.280101 -384.984709) (xy 333.273587 -384.967525) (xy 333.267812 -384.960368) (xy 333.245983 -384.934674)
			(xy 333.207892 -384.879044) (xy 333.176739 -384.819252) (xy 333.152973 -384.756158) (xy 333.136934 -384.690673)
			(xy 333.128855 -384.623738) (xy 333.128852 -384.556316) (xy 333.136925 -384.48938) (xy 333.152957 -384.423893)
			(xy 333.176717 -384.360798) (xy 333.207865 -384.301003) (xy 333.24595 -384.245369) (xy 333.267812 -384.219704)
			(xy 333.273591 -384.212546) (xy 333.280116 -384.195365) (xy 333.280512 -384.186176) (xy 333.280512 -383.693924)
			(xy 333.280088 -383.684738) (xy 333.273583 -383.667554) (xy 333.267812 -383.660396) (xy 333.245912 -383.63476)
			(xy 333.207824 -383.579122) (xy 333.176674 -383.519322) (xy 333.152911 -383.456221) (xy 333.136878 -383.390728)
			(xy 333.128805 -383.323786) (xy 332.026711 -383.323786) (xy 332.026923 -383.324351) (xy 332.042895 -383.389735)
			(xy 332.050937 -383.456559) (xy 332.050936 -383.523865) (xy 332.04289 -383.590689) (xy 332.026916 -383.656072)
			(xy 332.003242 -383.719077) (xy 331.972207 -383.778801) (xy 331.934257 -383.834388) (xy 331.912468 -383.86004)
			(xy 331.906668 -383.867183) (xy 331.900156 -383.884375) (xy 331.899768 -383.893568) (xy 331.899768 -384.051556)
			(xy 331.899342 -384.061711) (xy 331.891555 -384.080469) (xy 331.877159 -384.094795) (xy 331.858363 -384.10249)
			(xy 331.848206 -384.102864) (xy 331.131926 -384.102864) (xy 331.121801 -384.102352) (xy 331.103082 -384.094634)
			(xy 331.088724 -384.080355) (xy 331.080904 -384.061678) (xy 331.080364 -384.051556) (xy 331.080364 -383.893568)
			(xy 331.079955 -383.884381) (xy 331.073439 -383.867198) (xy 331.067664 -383.86004) (xy 331.045891 -383.834375)
			(xy 331.00794 -383.778791) (xy 330.976905 -383.71907) (xy 330.95323 -383.656067) (xy 330.937256 -383.590686)
			(xy 330.92921 -383.523864) (xy 330.929208 -383.45656) (xy 330.937251 -383.389738) (xy 330.953223 -383.324356)
			(xy 330.976895 -383.261352) (xy 331.007928 -383.20163) (xy 331.045877 -383.146044) (xy 331.067664 -383.120392)
			(xy 331.073454 -383.113243) (xy 331.079971 -383.096055) (xy 331.080364 -383.086864) (xy 331.080364 -382.593342)
			(xy 331.079919 -382.584159) (xy 331.073428 -382.566975) (xy 331.067664 -382.559814) (xy 331.045866 -382.53417)
			(xy 331.007916 -382.478583) (xy 330.976881 -382.418859) (xy 330.953208 -382.355853) (xy 330.937235 -382.29047)
			(xy 330.929191 -382.223646) (xy 301.250888 -382.223646) (xy 301.250888 -382.223704) (xy 301.242813 -382.290641)
			(xy 301.226779 -382.356129) (xy 301.203017 -382.419226) (xy 301.171869 -382.479022) (xy 301.133783 -382.534656)
			(xy 301.11192 -382.560322) (xy 301.106134 -382.567475) (xy 301.099612 -382.584659) (xy 301.09922 -382.59385)
			(xy 301.09922 -383.086356) (xy 301.099647 -383.095542) (xy 301.106148 -383.112726) (xy 301.11192 -383.119884)
			(xy 301.133799 -383.145537) (xy 301.171886 -383.201173) (xy 301.203035 -383.260972) (xy 301.22669 -383.323786)
			(xy 302.328775 -383.323786) (xy 302.328778 -383.25636) (xy 302.336857 -383.18942) (xy 302.352895 -383.123929)
			(xy 302.376662 -383.060831) (xy 302.407816 -383.001033) (xy 302.445907 -382.945398) (xy 302.467772 -382.919732)
			(xy 302.473589 -382.912601) (xy 302.480089 -382.895399) (xy 302.480472 -382.886204) (xy 302.480472 -382.728724)
			(xy 302.480935 -382.718606) (xy 302.48867 -382.699909) (xy 302.502972 -382.685595) (xy 302.521663 -382.677843)
			(xy 302.53178 -382.677416) (xy 303.24806 -382.677416) (xy 303.258182 -382.677849) (xy 303.276888 -382.685587)
			(xy 303.291204 -382.699899) (xy 303.298948 -382.718602) (xy 303.299368 -382.728724) (xy 303.299368 -382.886204)
			(xy 303.299783 -382.89539) (xy 303.306294 -382.912575) (xy 303.312068 -382.919732) (xy 303.333898 -382.945426)
			(xy 303.37199 -383.001056) (xy 303.403144 -383.060847) (xy 303.426911 -383.123941) (xy 303.44295 -383.189427)
			(xy 303.451029 -383.256362) (xy 303.451033 -383.323784) (xy 303.44296 -383.39072) (xy 303.426927 -383.456208)
			(xy 303.403166 -383.519303) (xy 303.372017 -383.579098) (xy 303.333931 -383.634731) (xy 303.312068 -383.660396)
			(xy 303.306286 -383.667552) (xy 303.299764 -383.684734) (xy 303.299368 -383.693924) (xy 303.299368 -384.186176)
			(xy 303.299797 -384.195361) (xy 303.306299 -384.212545) (xy 303.312068 -384.219704) (xy 303.333968 -384.24534)
			(xy 303.372058 -384.300978) (xy 303.403209 -384.360778) (xy 303.426973 -384.423878) (xy 303.443007 -384.489371)
			(xy 303.45108 -384.556313) (xy 303.451077 -384.623741) (xy 303.442997 -384.690682) (xy 303.426957 -384.756173)
			(xy 303.403187 -384.819272) (xy 303.37203 -384.879069) (xy 303.333935 -384.934703) (xy 303.312068 -384.960368)
			(xy 303.306256 -384.967502) (xy 303.299751 -384.984701) (xy 303.299368 -384.993896) (xy 303.299368 -385.151376)
			(xy 303.298964 -385.161501) (xy 303.291218 -385.18021) (xy 303.276897 -385.194527) (xy 303.258185 -385.202267)
			(xy 303.24806 -385.202684) (xy 302.53178 -385.202684) (xy 302.521654 -385.2023) (xy 302.502947 -385.194542)
			(xy 302.488633 -385.180216) (xy 302.480891 -385.161502) (xy 302.480472 -385.151376) (xy 302.480472 -384.993896)
			(xy 302.48007 -384.984708) (xy 302.473551 -384.967523) (xy 302.467772 -384.960368) (xy 302.445944 -384.934673)
			(xy 302.407856 -384.879042) (xy 302.376706 -384.81925) (xy 302.352941 -384.756157) (xy 302.336904 -384.690672)
			(xy 302.328825 -384.623737) (xy 302.328822 -384.556317) (xy 302.336894 -384.489382) (xy 302.352925 -384.423895)
			(xy 302.376684 -384.3608) (xy 302.407829 -384.301004) (xy 302.445911 -384.24537) (xy 302.467772 -384.219704)
			(xy 302.473558 -384.212552) (xy 302.480077 -384.195366) (xy 302.480472 -384.186176) (xy 302.480472 -383.693924)
			(xy 302.480057 -383.684737) (xy 302.473547 -383.667552) (xy 302.467772 -383.660396) (xy 302.445874 -383.634759)
			(xy 302.407788 -383.57912) (xy 302.37664 -383.51932) (xy 302.352879 -383.456219) (xy 302.336847 -383.390727)
			(xy 302.328775 -383.323786) (xy 301.22669 -383.323786) (xy 301.226797 -383.32407) (xy 301.242831 -383.38956)
			(xy 301.250905 -383.4565) (xy 301.250904 -383.523924) (xy 301.242827 -383.590863) (xy 301.22679 -383.656353)
			(xy 301.203025 -383.71945) (xy 301.171874 -383.779247) (xy 301.133784 -383.834882) (xy 301.11192 -383.860548)
			(xy 301.106123 -383.867693) (xy 301.099608 -383.884884) (xy 301.09922 -383.894076) (xy 301.09922 -384.051556)
			(xy 301.098748 -384.061673) (xy 301.091018 -384.080372) (xy 301.076719 -384.094687) (xy 301.058029 -384.102437)
			(xy 301.047912 -384.102864) (xy 300.331632 -384.102864) (xy 300.321507 -384.102457) (xy 300.302797 -384.094713)
			(xy 300.28848 -384.080393) (xy 300.28074 -384.061681) (xy 300.280324 -384.051556) (xy 300.280324 -383.894076)
			(xy 300.27992 -383.884888) (xy 300.273402 -383.867704) (xy 300.267624 -383.860548) (xy 300.245775 -383.83487)
			(xy 300.207684 -383.779238) (xy 300.176531 -383.719444) (xy 300.152765 -383.656349) (xy 300.136728 -383.590861)
			(xy 300.12865 -383.523923) (xy 300.128649 -383.456501) (xy 300.136724 -383.389563) (xy 300.152758 -383.324074)
			(xy 300.176522 -383.260978) (xy 300.207672 -383.201183) (xy 300.24576 -383.145549) (xy 300.267624 -383.119884)
			(xy 300.273413 -383.112733) (xy 300.279931 -383.095547) (xy 300.280324 -383.086356) (xy 300.280324 -382.59385)
			(xy 300.279884 -382.584666) (xy 300.273391 -382.567482) (xy 300.267624 -382.560322) (xy 300.245749 -382.534665)
			(xy 300.207659 -382.47903) (xy 300.176508 -382.419233) (xy 300.152743 -382.356135) (xy 300.136708 -382.290645)
			(xy 300.128632 -382.223705) (xy 296.851097 -382.223705) (xy 296.843022 -382.290641) (xy 296.826989 -382.356129)
			(xy 296.803227 -382.419225) (xy 296.77208 -382.479021) (xy 296.733994 -382.534656) (xy 296.712132 -382.560322)
			(xy 296.706335 -382.567467) (xy 296.699823 -382.584658) (xy 296.699432 -382.59385) (xy 296.699432 -383.086356)
			(xy 296.699878 -383.095539) (xy 296.706368 -383.112723) (xy 296.712132 -383.119884) (xy 296.734011 -383.145537)
			(xy 296.772097 -383.201174) (xy 296.803245 -383.260972) (xy 296.826877 -383.323727) (xy 297.928982 -383.323727)
			(xy 297.928985 -383.256419) (xy 297.937033 -383.189593) (xy 297.953011 -383.124208) (xy 297.97669 -383.061202)
			(xy 298.007729 -383.001478) (xy 298.045685 -382.945891) (xy 298.067476 -382.92024) (xy 298.073278 -382.913098)
			(xy 298.07979 -382.895905) (xy 298.080176 -382.886712) (xy 298.080176 -382.728724) (xy 298.080641 -382.718574)
			(xy 298.088424 -382.699827) (xy 298.102807 -382.685504) (xy 298.121587 -382.677799) (xy 298.131738 -382.677416)
			(xy 298.848018 -382.677416) (xy 298.858143 -382.677911) (xy 298.87686 -382.68564) (xy 298.891215 -382.699923)
			(xy 298.899038 -382.718602) (xy 298.89958 -382.728724) (xy 298.89958 -382.886712) (xy 298.899989 -382.895899)
			(xy 298.906504 -382.913083) (xy 298.91228 -382.92024) (xy 298.934031 -382.945922) (xy 298.97198 -383.001504)
			(xy 299.003014 -383.061224) (xy 299.026688 -383.124225) (xy 299.042663 -383.189603) (xy 299.050709 -383.256422)
			(xy 299.050713 -383.323724) (xy 299.042672 -383.390544) (xy 299.026704 -383.455924) (xy 299.003036 -383.518926)
			(xy 298.972008 -383.578649) (xy 298.934065 -383.634235) (xy 298.91228 -383.659888) (xy 298.906461 -383.667017)
			(xy 298.89996 -383.68422) (xy 298.89958 -383.693416) (xy 298.89958 -384.186684) (xy 298.900003 -384.19587)
			(xy 298.906508 -384.213054) (xy 298.91228 -384.220212) (xy 298.934103 -384.245835) (xy 298.972049 -384.301426)
			(xy 299.00308 -384.361154) (xy 299.02675 -384.424162) (xy 299.04272 -384.489548) (xy 299.050761 -384.556373)
			(xy 299.050757 -384.623681) (xy 299.04271 -384.690506) (xy 299.026734 -384.75589) (xy 299.003058 -384.818895)
			(xy 298.972021 -384.87862) (xy 298.934069 -384.934208) (xy 298.91228 -384.95986) (xy 298.906473 -384.966998)
			(xy 298.899965 -384.984194) (xy 298.89958 -384.993388) (xy 298.89958 -385.151376) (xy 298.899159 -385.161531)
			(xy 298.891367 -385.180287) (xy 298.87697 -385.194612) (xy 298.858175 -385.202309) (xy 298.848018 -385.202684)
			(xy 298.131738 -385.202684) (xy 298.121617 -385.202143) (xy 298.102901 -385.194432) (xy 298.088544 -385.180162)
			(xy 298.08072 -385.161494) (xy 298.080176 -385.151376) (xy 298.080176 -384.993388) (xy 298.079777 -384.9842)
			(xy 298.073256 -384.967015) (xy 298.067476 -384.95986) (xy 298.045723 -384.934179) (xy 298.00777 -384.878598)
			(xy 297.976733 -384.818878) (xy 297.953057 -384.755878) (xy 297.93708 -384.690499) (xy 297.929033 -384.623679)
			(xy 297.92903 -384.556376) (xy 297.937071 -384.489555) (xy 297.953041 -384.424174) (xy 297.976711 -384.361171)
			(xy 298.007742 -384.301449) (xy 298.045689 -384.245864) (xy 298.067476 -384.220212) (xy 298.07329 -384.213079)
			(xy 298.079795 -384.195879) (xy 298.080176 -384.186684) (xy 298.080176 -383.693416) (xy 298.079764 -383.684229)
			(xy 298.073252 -383.667044) (xy 298.067476 -383.659888) (xy 298.045651 -383.634266) (xy 298.007701 -383.578676)
			(xy 297.976668 -383.518948) (xy 297.952995 -383.45594) (xy 297.937024 -383.390554) (xy 297.928982 -383.323727)
			(xy 296.826877 -383.323727) (xy 296.827007 -383.324071) (xy 296.84304 -383.389561) (xy 296.851114 -383.4565)
			(xy 296.851113 -383.523924) (xy 296.843036 -383.590863) (xy 296.827 -383.656352) (xy 296.803235 -383.71945)
			(xy 296.772084 -383.779247) (xy 296.733996 -383.834882) (xy 296.712132 -383.860548) (xy 296.706324 -383.867685)
			(xy 296.699818 -383.884882) (xy 296.699432 -383.894076) (xy 296.699432 -384.051556) (xy 296.698949 -384.061672)
			(xy 296.691221 -384.080368) (xy 296.676925 -384.094683) (xy 296.658239 -384.102435) (xy 296.648124 -384.102864)
			(xy 295.931844 -384.102864) (xy 295.92172 -384.102447) (xy 295.90301 -384.094707) (xy 295.888693 -384.08039)
			(xy 295.880953 -384.06168) (xy 295.880536 -384.051556) (xy 295.880536 -383.894076) (xy 295.880129 -383.884889)
			(xy 295.873612 -383.867705) (xy 295.867836 -383.860548) (xy 295.845986 -383.83487) (xy 295.807895 -383.779238)
			(xy 295.776742 -383.719444) (xy 295.752975 -383.656349) (xy 295.736937 -383.590861) (xy 295.728859 -383.523924)
			(xy 295.728858 -383.4565) (xy 295.736933 -383.389563) (xy 295.752968 -383.324074) (xy 295.776732 -383.260978)
			(xy 295.807883 -383.201182) (xy 295.845972 -383.145549) (xy 295.867836 -383.119884) (xy 295.873626 -383.112735)
			(xy 295.880144 -383.095547) (xy 295.880536 -383.086356) (xy 295.880536 -382.59385) (xy 295.880094 -382.584666)
			(xy 295.873601 -382.567482) (xy 295.867836 -382.560322) (xy 295.845961 -382.534665) (xy 295.80787 -382.479031)
			(xy 295.776718 -382.419233) (xy 295.752953 -382.356135) (xy 295.736917 -382.290645) (xy 295.728841 -382.223705)
			(xy 292.450794 -382.223705) (xy 292.442758 -382.290467) (xy 292.426786 -382.355849) (xy 292.403113 -382.418853)
			(xy 292.37208 -382.478576) (xy 292.334131 -382.534162) (xy 292.312344 -382.559814) (xy 292.306552 -382.566962)
			(xy 292.300036 -382.584151) (xy 292.299644 -382.593342) (xy 292.299644 -383.086864) (xy 292.300084 -383.096048)
			(xy 292.306578 -383.113232) (xy 292.312344 -383.120392) (xy 292.334148 -383.146031) (xy 292.372098 -383.201619)
			(xy 292.403131 -383.261344) (xy 292.426592 -383.323786) (xy 293.528687 -383.323786) (xy 293.52869 -383.25636)
			(xy 293.536769 -383.189419) (xy 293.552808 -383.123928) (xy 293.576576 -383.06083) (xy 293.60773 -383.001033)
			(xy 293.645822 -382.945397) (xy 293.667688 -382.919732) (xy 293.673495 -382.912594) (xy 293.680004 -382.895398)
			(xy 293.680388 -382.886204) (xy 293.680388 -382.728724) (xy 293.680835 -382.718605) (xy 293.688573 -382.699904)
			(xy 293.70288 -382.685589) (xy 293.721577 -382.677841) (xy 293.731696 -382.677416) (xy 294.447976 -382.677416)
			(xy 294.458099 -382.677836) (xy 294.476805 -382.685579) (xy 294.491121 -382.699895) (xy 294.498864 -382.718601)
			(xy 294.499284 -382.728724) (xy 294.499284 -382.886204) (xy 294.499696 -382.895391) (xy 294.506209 -382.912575)
			(xy 294.511984 -382.919732) (xy 294.533813 -382.945426) (xy 294.571904 -383.001056) (xy 294.603057 -383.060848)
			(xy 294.626824 -383.123941) (xy 294.642863 -383.189427) (xy 294.650942 -383.256362) (xy 294.650945 -383.323784)
			(xy 294.642872 -383.39072) (xy 294.62684 -383.456207) (xy 294.603079 -383.519302) (xy 294.571932 -383.579097)
			(xy 294.533846 -383.634731) (xy 294.511984 -383.660396) (xy 294.506205 -383.667553) (xy 294.49968 -383.684735)
			(xy 294.499284 -383.693924) (xy 294.499284 -384.186176) (xy 294.499709 -384.195361) (xy 294.506213 -384.212546)
			(xy 294.511984 -384.219704) (xy 294.533884 -384.24534) (xy 294.571973 -384.300978) (xy 294.603123 -384.360778)
			(xy 294.626885 -384.423879) (xy 294.642919 -384.489372) (xy 294.650992 -384.556314) (xy 294.650989 -384.62374)
			(xy 294.642909 -384.690681) (xy 294.626869 -384.756173) (xy 294.603101 -384.819271) (xy 294.571945 -384.879068)
			(xy 294.533851 -384.934703) (xy 294.511984 -384.960368) (xy 294.506174 -384.967504) (xy 294.499668 -384.984702)
			(xy 294.499284 -384.993896) (xy 294.499284 -385.151376) (xy 294.498864 -385.161499) (xy 294.491121 -385.180205)
			(xy 294.476805 -385.194521) (xy 294.458099 -385.202264) (xy 294.447976 -385.202684) (xy 293.731696 -385.202684)
			(xy 293.721571 -385.202287) (xy 293.702865 -385.194534) (xy 293.68855 -385.180212) (xy 293.680808 -385.161501)
			(xy 293.680388 -385.151376) (xy 293.680388 -384.993896) (xy 293.679982 -384.984708) (xy 293.673466 -384.967524)
			(xy 293.667688 -384.960368) (xy 293.64586 -384.934673) (xy 293.607771 -384.879043) (xy 293.576619 -384.819251)
			(xy 293.552854 -384.756158) (xy 293.536816 -384.690672) (xy 293.528737 -384.623737) (xy 293.528734 -384.556317)
			(xy 293.536806 -384.489381) (xy 293.552838 -384.423894) (xy 293.576597 -384.360799) (xy 293.607743 -384.301004)
			(xy 293.645827 -384.245369) (xy 293.667688 -384.219704) (xy 293.673464 -384.212544) (xy 293.679991 -384.195365)
			(xy 293.680388 -384.186176) (xy 293.680388 -383.693924) (xy 293.679969 -383.684738) (xy 293.673462 -383.667553)
			(xy 293.667688 -383.660396) (xy 293.645789 -383.63476) (xy 293.607702 -383.579121) (xy 293.576554 -383.51932)
			(xy 293.552792 -383.45622) (xy 293.53676 -383.390727) (xy 293.528687 -383.323786) (xy 292.426592 -383.323786)
			(xy 292.426804 -383.32435) (xy 292.442776 -383.389734) (xy 292.450819 -383.456559) (xy 292.450818 -383.523865)
			(xy 292.442772 -383.590689) (xy 292.426797 -383.656073) (xy 292.403121 -383.719078) (xy 292.372085 -383.778802)
			(xy 292.334133 -383.834388) (xy 292.312344 -383.86004) (xy 292.306541 -383.86718) (xy 292.300032 -383.884375)
			(xy 292.299644 -383.893568) (xy 292.299644 -384.051556) (xy 292.299149 -384.06167) (xy 292.291423 -384.080364)
			(xy 292.277132 -384.094679) (xy 292.258449 -384.102433) (xy 292.248336 -384.102864) (xy 291.531802 -384.102864)
			(xy 291.521676 -384.102372) (xy 291.502956 -384.094645) (xy 291.488599 -384.080361) (xy 291.480779 -384.06168)
			(xy 291.48024 -384.051556) (xy 291.48024 -383.893568) (xy 291.479836 -383.88438) (xy 291.473317 -383.867197)
			(xy 291.46754 -383.86004) (xy 291.445768 -383.834375) (xy 291.407819 -383.77879) (xy 291.376785 -383.719068)
			(xy 291.353111 -383.656066) (xy 291.337137 -383.590685) (xy 291.329092 -383.523864) (xy 291.32909 -383.45656)
			(xy 291.337133 -383.389739) (xy 291.353104 -383.324357) (xy 291.376775 -383.261354) (xy 291.407806 -383.20163)
			(xy 291.445753 -383.146044) (xy 291.46754 -383.120392) (xy 291.473328 -383.113241) (xy 291.479847 -383.096055)
			(xy 291.48024 -383.086864) (xy 291.48024 -382.593342) (xy 291.4798 -382.584158) (xy 291.473306 -382.566974)
			(xy 291.46754 -382.559814) (xy 291.445742 -382.53417) (xy 291.407794 -382.478582) (xy 291.376761 -382.418858)
			(xy 291.353088 -382.355852) (xy 291.337116 -382.290469) (xy 291.329073 -382.223645) (xy 288.051034 -382.223645)
			(xy 288.051034 -382.223704) (xy 288.042958 -382.290643) (xy 288.026922 -382.356132) (xy 288.003157 -382.419229)
			(xy 287.972004 -382.479024) (xy 287.933913 -382.534658) (xy 287.912048 -382.560322) (xy 287.906253 -382.567468)
			(xy 287.899739 -382.584658) (xy 287.899348 -382.59385) (xy 287.899348 -383.086356) (xy 287.899791 -383.095539)
			(xy 287.906283 -383.112723) (xy 287.912048 -383.119884) (xy 287.93393 -383.145535) (xy 287.972021 -383.201171)
			(xy 288.003174 -383.260968) (xy 288.026812 -383.323727) (xy 289.128894 -383.323727) (xy 289.128898 -383.256418)
			(xy 289.136946 -383.189593) (xy 289.152924 -383.124208) (xy 289.176604 -383.061202) (xy 289.207644 -383.001477)
			(xy 289.245601 -382.945891) (xy 289.267392 -382.92024) (xy 289.273196 -382.9131) (xy 289.279706 -382.895905)
			(xy 289.280092 -382.886712) (xy 289.280092 -382.728724) (xy 289.280535 -382.718604) (xy 289.288274 -382.699902)
			(xy 289.302582 -382.685588) (xy 289.32128 -382.67784) (xy 289.3314 -382.677416) (xy 290.047934 -382.677416)
			(xy 290.05806 -382.677898) (xy 290.076777 -382.685632) (xy 290.091132 -382.69992) (xy 290.098954 -382.7186)
			(xy 290.099496 -382.728724) (xy 290.099496 -382.886712) (xy 290.099901 -382.8959) (xy 290.106419 -382.913084)
			(xy 290.112196 -382.92024) (xy 290.133947 -382.945922) (xy 290.171895 -383.001505) (xy 290.202928 -383.061225)
			(xy 290.226601 -383.124225) (xy 290.242576 -383.189603) (xy 290.250622 -383.256422) (xy 290.250625 -383.323724)
			(xy 290.242585 -383.390543) (xy 290.226617 -383.455923) (xy 290.20295 -383.518926) (xy 290.171923 -383.578649)
			(xy 290.133981 -383.634235) (xy 290.112196 -383.659888) (xy 290.106379 -383.667019) (xy 290.099877 -383.68422)
			(xy 290.099496 -383.693416) (xy 290.099496 -384.186684) (xy 290.099915 -384.19587) (xy 290.106423 -384.213055)
			(xy 290.112196 -384.220212) (xy 290.134018 -384.245836) (xy 290.171963 -384.301427) (xy 290.202993 -384.361155)
			(xy 290.226662 -384.424163) (xy 290.242632 -384.489548) (xy 290.250673 -384.556373) (xy 290.250669 -384.623681)
			(xy 290.242622 -384.690505) (xy 290.226646 -384.755889) (xy 290.202971 -384.818895) (xy 290.171936 -384.87862)
			(xy 290.133985 -384.934207) (xy 290.112196 -384.95986) (xy 290.106391 -384.966999) (xy 290.099881 -384.984194)
			(xy 290.099496 -384.993388) (xy 290.099496 -385.151376) (xy 290.099064 -385.161497) (xy 290.091323 -385.180201)
			(xy 290.077011 -385.194517) (xy 290.058309 -385.202262) (xy 290.048188 -385.202684) (xy 289.331654 -385.202684)
			(xy 289.321527 -385.202212) (xy 289.30281 -385.194473) (xy 289.288456 -385.180183) (xy 289.280634 -385.1615)
			(xy 289.280092 -385.151376) (xy 289.280092 -384.993388) (xy 289.279689 -384.9842) (xy 289.273171 -384.967016)
			(xy 289.267392 -384.95986) (xy 289.245638 -384.934179) (xy 289.207685 -384.878598) (xy 289.176647 -384.818879)
			(xy 289.15297 -384.755878) (xy 289.136993 -384.690499) (xy 289.128945 -384.623679) (xy 289.128942 -384.556375)
			(xy 289.136983 -384.489554) (xy 289.152954 -384.424174) (xy 289.176625 -384.36117) (xy 289.207657 -384.301448)
			(xy 289.245605 -384.245863) (xy 289.267392 -384.220212) (xy 289.273208 -384.21308) (xy 289.279711 -384.195879)
			(xy 289.280092 -384.186684) (xy 289.280092 -383.693416) (xy 289.279676 -383.684229) (xy 289.273167 -383.667045)
			(xy 289.267392 -383.659888) (xy 289.245567 -383.634266) (xy 289.207616 -383.578676) (xy 289.176581 -383.518949)
			(xy 289.152908 -383.45594) (xy 289.136936 -383.390554) (xy 289.128894 -383.323727) (xy 288.026812 -383.323727)
			(xy 288.02694 -383.324067) (xy 288.042976 -383.389558) (xy 288.051051 -383.456499) (xy 288.05105 -383.523925)
			(xy 288.042971 -383.590865) (xy 288.026933 -383.656356) (xy 288.003164 -383.719454) (xy 287.972009 -383.77925)
			(xy 287.933915 -383.834884) (xy 287.912048 -383.860548) (xy 287.906242 -383.867686) (xy 287.899734 -383.884882)
			(xy 287.899348 -383.894076) (xy 287.899348 -384.051556) (xy 287.898849 -384.06167) (xy 287.891124 -384.080363)
			(xy 287.876834 -384.094677) (xy 287.858153 -384.102432) (xy 287.84804 -384.102864) (xy 287.13176 -384.102864)
			(xy 287.12163 -384.102516) (xy 287.102919 -384.094748) (xy 287.088605 -384.08041) (xy 287.080868 -384.061686)
			(xy 287.080452 -384.051556) (xy 287.080452 -383.894076) (xy 287.080042 -383.884889) (xy 287.073527 -383.867705)
			(xy 287.067752 -383.860548) (xy 287.045902 -383.834871) (xy 287.007809 -383.779239) (xy 286.976655 -383.719445)
			(xy 286.952888 -383.65635) (xy 286.936849 -383.590862) (xy 286.928772 -383.523924) (xy 286.92877 -383.4565)
			(xy 286.936845 -383.389562) (xy 286.952881 -383.324073) (xy 286.976645 -383.260977) (xy 287.007797 -383.201182)
			(xy 287.045887 -383.145548) (xy 287.067752 -383.119884) (xy 287.073544 -383.112736) (xy 287.08006 -383.095547)
			(xy 287.080452 -383.086356) (xy 287.080452 -382.59385) (xy 287.080006 -382.584667) (xy 287.073516 -382.567483)
			(xy 287.067752 -382.560322) (xy 287.045876 -382.534666) (xy 287.007785 -382.479031) (xy 286.976631 -382.419234)
			(xy 286.952865 -382.356136) (xy 286.936829 -382.290645) (xy 286.928753 -382.223705) (xy 262.654796 -382.223705)
			(xy 262.654796 -385.608376) (xy 454.303373 -385.608376) (xy 454.303373 -385.479236) (xy 454.311323 -385.350341)
			(xy 454.327193 -385.222181) (xy 454.350922 -385.09524) (xy 454.382421 -384.970001) (xy 454.42157 -384.846938)
			(xy 454.468221 -384.726519) (xy 454.522196 -384.6092) (xy 454.583291 -384.495426) (xy 454.651274 -384.385629)
			(xy 454.725888 -384.280226) (xy 454.806849 -384.179616) (xy 454.893849 -384.084181) (xy 454.98656 -383.994282)
			(xy 455.08463 -383.910261) (xy 455.187685 -383.832437) (xy 455.295336 -383.761105) (xy 455.407175 -383.696535)
			(xy 455.522776 -383.638973) (xy 455.641701 -383.588636) (xy 455.7635 -383.545716) (xy 455.88771 -383.510375)
			(xy 456.013859 -383.482748) (xy 456.141471 -383.462939) (xy 456.27006 -383.451023) (xy 456.399138 -383.447047)
			(xy 456.528216 -383.451023) (xy 456.656805 -383.462939) (xy 456.784417 -383.482748) (xy 456.910566 -383.510375)
			(xy 457.034776 -383.545716) (xy 457.156575 -383.588636) (xy 457.2755 -383.638973) (xy 457.391101 -383.696535)
			(xy 457.50294 -383.761105) (xy 457.610591 -383.832437) (xy 457.713646 -383.910261) (xy 457.811716 -383.994282)
			(xy 457.904427 -384.084181) (xy 457.991427 -384.179616) (xy 458.072388 -384.280226) (xy 458.147002 -384.385629)
			(xy 458.214985 -384.495426) (xy 458.27608 -384.6092) (xy 458.330055 -384.726519) (xy 458.376706 -384.846938)
			(xy 458.415855 -384.970001) (xy 458.447354 -385.09524) (xy 458.471083 -385.222181) (xy 458.486953 -385.350341)
			(xy 458.494903 -385.479236) (xy 458.4954 -385.543806) (xy 458.494903 -385.608376) (xy 458.486953 -385.737271)
			(xy 458.471083 -385.865431) (xy 458.447354 -385.992372) (xy 458.415855 -386.117611) (xy 458.376706 -386.240674)
			(xy 458.330055 -386.361093) (xy 458.27608 -386.478412) (xy 458.214985 -386.592186) (xy 458.147002 -386.701983)
			(xy 458.072388 -386.807386) (xy 457.991427 -386.907996) (xy 457.904427 -387.003431) (xy 457.811716 -387.09333)
			(xy 457.713646 -387.177351) (xy 457.610591 -387.255175) (xy 457.50294 -387.326507) (xy 457.391101 -387.391077)
			(xy 457.2755 -387.448639) (xy 457.156575 -387.498976) (xy 457.034776 -387.541896) (xy 456.910566 -387.577237)
			(xy 456.784417 -387.604864) (xy 456.656805 -387.624673) (xy 456.528216 -387.636589) (xy 456.399138 -387.640566)
			(xy 456.27006 -387.636589) (xy 456.141471 -387.624673) (xy 456.013859 -387.604864) (xy 455.88771 -387.577237)
			(xy 455.7635 -387.541896) (xy 455.641701 -387.498976) (xy 455.522776 -387.448639) (xy 455.407175 -387.391077)
			(xy 455.295336 -387.326507) (xy 455.187685 -387.255175) (xy 455.08463 -387.177351) (xy 454.98656 -387.09333)
			(xy 454.893849 -387.003431) (xy 454.806849 -386.907996) (xy 454.725888 -386.807386) (xy 454.651274 -386.701983)
			(xy 454.583291 -386.592186) (xy 454.522196 -386.478412) (xy 454.468221 -386.361093) (xy 454.42157 -386.240674)
			(xy 454.382421 -386.117611) (xy 454.350922 -385.992372) (xy 454.327193 -385.865431) (xy 454.311323 -385.737271)
			(xy 454.303373 -385.608376) (xy 262.654796 -385.608376) (xy 262.654796 -387.940042) (xy 262.654324 -387.964992)
			(xy 262.646505 -388.014277) (xy 262.631083 -388.061734) (xy 262.608436 -388.1062) (xy 262.57912 -388.146581)
			(xy 262.561832 -388.164578) (xy 259.433314 -391.293096) (xy 259.415316 -391.310383) (xy 259.374941 -391.339708)
			(xy 259.330476 -391.362356) (xy 259.283016 -391.377771) (xy 259.233728 -391.385573) (xy 259.208778 -391.38606)
			(xy 245.30812 -391.38606) (xy 245.29805 -391.38648) (xy 245.279451 -391.394203) (xy 245.272052 -391.401046)
			(xy 244.461792 -392.211306) (xy 244.454956 -392.218709) (xy 244.447234 -392.237306) (xy 244.446806 -392.247374)
			(xy 244.446806 -397.823885) (xy 286.928734 -397.823885) (xy 286.928737 -397.756458) (xy 286.936817 -397.689516)
			(xy 286.952859 -397.624024) (xy 286.976629 -397.560925) (xy 287.007787 -397.501128) (xy 287.045884 -397.445494)
			(xy 287.067752 -397.41983) (xy 287.073567 -397.412698) (xy 287.080069 -397.395497) (xy 287.080452 -397.386302)
			(xy 287.080452 -396.89405) (xy 287.080006 -396.884867) (xy 287.073516 -396.867683) (xy 287.067752 -396.860522)
			(xy 287.045876 -396.834866) (xy 287.007785 -396.779231) (xy 286.976631 -396.719434) (xy 286.952865 -396.656336)
			(xy 286.936829 -396.590845) (xy 286.928753 -396.523905) (xy 286.928754 -396.45648) (xy 286.936832 -396.38954)
			(xy 286.95287 -396.32405) (xy 286.976638 -396.260952) (xy 287.007792 -396.201156) (xy 287.045886 -396.145522)
			(xy 287.067752 -396.119858) (xy 287.073555 -396.112718) (xy 287.080065 -396.095523) (xy 287.080452 -396.08633)
			(xy 287.080452 -395.92885) (xy 287.080968 -395.918725) (xy 287.088682 -395.900003) (xy 287.102959 -395.885644)
			(xy 287.121638 -395.877825) (xy 287.13176 -395.877288) (xy 287.84804 -395.877288) (xy 287.858195 -395.877689)
			(xy 287.876946 -395.885495) (xy 287.891268 -395.899898) (xy 287.898968 -395.918693) (xy 287.899348 -395.92885)
			(xy 287.899348 -396.08633) (xy 287.899755 -396.095517) (xy 287.906272 -396.112701) (xy 287.912048 -396.119858)
			(xy 287.933904 -396.14553) (xy 287.971996 -396.201163) (xy 288.00315 -396.260957) (xy 288.026917 -396.324053)
			(xy 288.042955 -396.389542) (xy 288.051033 -396.456481) (xy 288.051034 -396.523904) (xy 288.042958 -396.590843)
			(xy 288.026922 -396.656332) (xy 288.003157 -396.719429) (xy 287.972004 -396.779224) (xy 287.933913 -396.834858)
			(xy 287.912048 -396.860522) (xy 287.906253 -396.867668) (xy 287.899739 -396.884858) (xy 287.899348 -396.89405)
			(xy 287.899348 -397.386302) (xy 287.899769 -397.395488) (xy 287.906276 -397.412672) (xy 287.912048 -397.41983)
			(xy 287.933876 -397.445525) (xy 287.97197 -397.501154) (xy 288.000733 -397.556355) (xy 289.128926 -397.556355)
			(xy 289.13697 -397.489532) (xy 289.152943 -397.42415) (xy 289.176617 -397.361145) (xy 289.207652 -397.301423)
			(xy 289.245603 -397.245837) (xy 289.267392 -397.220186) (xy 289.273176 -397.213032) (xy 289.279698 -397.195848)
			(xy 289.280092 -397.186658) (xy 289.280092 -397.028924) (xy 289.280541 -397.018772) (xy 289.288327 -397.000022)
			(xy 289.302715 -396.985698) (xy 289.321501 -396.977996) (xy 289.331654 -396.977616) (xy 290.047934 -396.977616)
			(xy 290.05806 -396.978098) (xy 290.076777 -396.985832) (xy 290.091132 -397.00012) (xy 290.098954 -397.0188)
			(xy 290.099496 -397.028924) (xy 290.099496 -397.186658) (xy 290.099927 -397.195843) (xy 290.106426 -397.213027)
			(xy 290.112196 -397.220186) (xy 290.133992 -397.245831) (xy 290.171939 -397.301419) (xy 290.20297 -397.361144)
			(xy 290.22664 -397.424149) (xy 290.242612 -397.489532) (xy 290.250654 -397.556355) (xy 290.250653 -397.62366)
			(xy 290.242609 -397.690483) (xy 290.226636 -397.755865) (xy 290.202963 -397.81887) (xy 290.200388 -397.823825)
			(xy 291.329053 -397.823825) (xy 291.329057 -397.756517) (xy 291.337105 -397.689692) (xy 291.353082 -397.624308)
			(xy 291.376759 -397.561302) (xy 291.407796 -397.501577) (xy 291.44575 -397.44599) (xy 291.46754 -397.420338)
			(xy 291.47335 -397.413203) (xy 291.479856 -397.396004) (xy 291.48024 -397.38681) (xy 291.48024 -396.893542)
			(xy 291.4798 -396.884358) (xy 291.473306 -396.867174) (xy 291.46754 -396.860014) (xy 291.445742 -396.83437)
			(xy 291.407794 -396.778782) (xy 291.376761 -396.719058) (xy 291.353088 -396.656052) (xy 291.337116 -396.590669)
			(xy 291.329073 -396.523845) (xy 291.329074 -396.45654) (xy 291.337119 -396.389716) (xy 291.353093 -396.324333)
			(xy 291.376767 -396.261328) (xy 291.407801 -396.201605) (xy 291.445751 -396.146018) (xy 291.46754 -396.120366)
			(xy 291.473339 -396.113222) (xy 291.479851 -396.096031) (xy 291.48024 -396.086838) (xy 291.48024 -395.92885)
			(xy 291.480705 -395.918681) (xy 291.488474 -395.899887) (xy 291.502847 -395.885501) (xy 291.521634 -395.877714)
			(xy 291.531802 -395.877288) (xy 292.248082 -395.877288) (xy 292.258259 -395.87768) (xy 292.277063 -395.885468)
			(xy 292.29145 -395.899864) (xy 292.299227 -395.918673) (xy 292.299644 -395.92885) (xy 292.299644 -396.086838)
			(xy 292.300049 -396.096026) (xy 292.306568 -396.113209) (xy 292.312344 -396.120366) (xy 292.334122 -396.146026)
			(xy 292.372072 -396.201611) (xy 292.403107 -396.261333) (xy 292.426781 -396.324337) (xy 292.442755 -396.389718)
			(xy 292.450801 -396.45654) (xy 292.450801 -396.523845) (xy 292.442758 -396.590667) (xy 292.426786 -396.656049)
			(xy 292.403113 -396.719053) (xy 292.37208 -396.778776) (xy 292.334131 -396.834362) (xy 292.312344 -396.860014)
			(xy 292.306552 -396.867162) (xy 292.300036 -396.884351) (xy 292.299644 -396.893542) (xy 292.299644 -397.38681)
			(xy 292.300062 -397.395996) (xy 292.306572 -397.41318) (xy 292.312344 -397.420338) (xy 292.334095 -397.446021)
			(xy 292.372046 -397.501602) (xy 292.40047 -397.556296) (xy 293.528718 -397.556296) (xy 293.536793 -397.489359)
			(xy 293.552827 -397.42387) (xy 293.576589 -397.360774) (xy 293.607738 -397.300978) (xy 293.645825 -397.245343)
			(xy 293.667688 -397.219678) (xy 293.673475 -397.212526) (xy 293.679996 -397.195341) (xy 293.680388 -397.18615)
			(xy 293.680388 -397.028924) (xy 293.680835 -397.018805) (xy 293.688573 -397.000104) (xy 293.70288 -396.985789)
			(xy 293.721577 -396.978041) (xy 293.731696 -396.977616) (xy 294.447976 -396.977616) (xy 294.458099 -396.978036)
			(xy 294.476805 -396.985779) (xy 294.491121 -397.000095) (xy 294.498864 -397.018801) (xy 294.499284 -397.028924)
			(xy 294.499284 -397.18615) (xy 294.499722 -397.195334) (xy 294.506217 -397.212519) (xy 294.511984 -397.219678)
			(xy 294.533858 -397.245335) (xy 294.571948 -397.30097) (xy 294.603099 -397.360767) (xy 294.626863 -397.423865)
			(xy 294.642899 -397.489356) (xy 294.650974 -397.556295) (xy 294.650973 -397.62372) (xy 294.642896 -397.690659)
			(xy 294.626859 -397.756149) (xy 294.603093 -397.819246) (xy 294.600676 -397.823885) (xy 295.728821 -397.823885)
			(xy 295.728825 -397.756458) (xy 295.736905 -397.689516) (xy 295.752946 -397.624025) (xy 295.776716 -397.560926)
			(xy 295.807873 -397.501129) (xy 295.845969 -397.445495) (xy 295.867836 -397.41983) (xy 295.873649 -397.412697)
			(xy 295.880153 -397.395497) (xy 295.880536 -397.386302) (xy 295.880536 -396.89405) (xy 295.880094 -396.884866)
			(xy 295.873601 -396.867682) (xy 295.867836 -396.860522) (xy 295.845961 -396.834865) (xy 295.80787 -396.779231)
			(xy 295.776718 -396.719433) (xy 295.752953 -396.656335) (xy 295.736917 -396.590845) (xy 295.728841 -396.523905)
			(xy 295.728842 -396.45648) (xy 295.73692 -396.38954) (xy 295.752957 -396.32405) (xy 295.776724 -396.260953)
			(xy 295.807878 -396.201157) (xy 295.84597 -396.145523) (xy 295.867836 -396.119858) (xy 295.873637 -396.112716)
			(xy 295.880148 -396.095523) (xy 295.880536 -396.08633) (xy 295.880536 -395.92885) (xy 295.881067 -395.918727)
			(xy 295.888778 -395.900008) (xy 295.903051 -395.88565) (xy 295.921724 -395.877828) (xy 295.931844 -395.877288)
			(xy 296.648124 -395.877288) (xy 296.658278 -395.877702) (xy 296.677029 -395.885503) (xy 296.691351 -395.899902)
			(xy 296.699052 -395.918694) (xy 296.699432 -395.92885) (xy 296.699432 -396.08633) (xy 296.699843 -396.095517)
			(xy 296.706358 -396.1127) (xy 296.712132 -396.119858) (xy 296.733985 -396.145532) (xy 296.772072 -396.201166)
			(xy 296.803221 -396.260961) (xy 296.826985 -396.324057) (xy 296.84302 -396.389545) (xy 296.851096 -396.456481)
			(xy 296.851097 -396.523904) (xy 296.843022 -396.590841) (xy 296.826989 -396.656329) (xy 296.803227 -396.719425)
			(xy 296.77208 -396.779221) (xy 296.733994 -396.834856) (xy 296.712132 -396.860522) (xy 296.706335 -396.867667)
			(xy 296.699823 -396.884858) (xy 296.699432 -396.89405) (xy 296.699432 -397.386302) (xy 296.699856 -397.395487)
			(xy 296.706362 -397.412671) (xy 296.712132 -397.41983) (xy 296.733958 -397.445527) (xy 296.772045 -397.501157)
			(xy 296.800802 -397.556355) (xy 297.929014 -397.556355) (xy 297.937057 -397.489532) (xy 297.95303 -397.42415)
			(xy 297.976704 -397.361146) (xy 298.007738 -397.301423) (xy 298.045688 -397.245838) (xy 298.067476 -397.220186)
			(xy 298.073258 -397.21303) (xy 298.079782 -397.195848) (xy 298.080176 -397.186658) (xy 298.080176 -397.028924)
			(xy 298.080641 -397.018774) (xy 298.088424 -397.000027) (xy 298.102807 -396.985704) (xy 298.121587 -396.977999)
			(xy 298.131738 -396.977616) (xy 298.848018 -396.977616) (xy 298.858143 -396.978111) (xy 298.87686 -396.98584)
			(xy 298.891215 -397.000123) (xy 298.899038 -397.018802) (xy 298.89958 -397.028924) (xy 298.89958 -397.186658)
			(xy 298.900015 -397.195842) (xy 298.906512 -397.213027) (xy 298.91228 -397.220186) (xy 298.934077 -397.24583)
			(xy 298.972024 -397.301418) (xy 299.003056 -397.361143) (xy 299.026728 -397.424149) (xy 299.042699 -397.489532)
			(xy 299.050742 -397.556355) (xy 299.050741 -397.62366) (xy 299.042697 -397.690483) (xy 299.026723 -397.755866)
			(xy 299.00305 -397.818871) (xy 299.000445 -397.823885) (xy 300.128612 -397.823885) (xy 300.128616 -397.756458)
			(xy 300.136696 -397.689517) (xy 300.152736 -397.624025) (xy 300.176506 -397.560927) (xy 300.207662 -397.501129)
			(xy 300.245757 -397.445495) (xy 300.267624 -397.41983) (xy 300.273436 -397.412696) (xy 300.27994 -397.395497)
			(xy 300.280324 -397.386302) (xy 300.280324 -396.89405) (xy 300.279884 -396.884866) (xy 300.273391 -396.867682)
			(xy 300.267624 -396.860522) (xy 300.245749 -396.834865) (xy 300.207659 -396.77923) (xy 300.176508 -396.719433)
			(xy 300.152743 -396.656335) (xy 300.136708 -396.590845) (xy 300.128632 -396.523905) (xy 300.128633 -396.45648)
			(xy 300.13671 -396.389541) (xy 300.152748 -396.324051) (xy 300.176514 -396.260953) (xy 300.207667 -396.201157)
			(xy 300.245759 -396.145523) (xy 300.267624 -396.119858) (xy 300.273424 -396.112715) (xy 300.279936 -396.095523)
			(xy 300.280324 -396.08633) (xy 300.280324 -395.92885) (xy 300.280867 -395.918728) (xy 300.288576 -395.900011)
			(xy 300.302845 -395.885654) (xy 300.321514 -395.87783) (xy 300.331632 -395.877288) (xy 301.047912 -395.877288)
			(xy 301.058065 -395.877711) (xy 301.076816 -395.885509) (xy 301.091138 -395.899904) (xy 301.09884 -395.918694)
			(xy 301.09922 -395.92885) (xy 301.09922 -396.08633) (xy 301.099611 -396.095519) (xy 301.106138 -396.112704)
			(xy 301.11192 -396.119858) (xy 301.133773 -396.145532) (xy 301.171861 -396.201165) (xy 301.203011 -396.260961)
			(xy 301.226775 -396.324056) (xy 301.242811 -396.389544) (xy 301.250887 -396.456481) (xy 301.250888 -396.523904)
			(xy 301.242813 -396.590841) (xy 301.226779 -396.656329) (xy 301.203017 -396.719426) (xy 301.171869 -396.779222)
			(xy 301.133783 -396.834856) (xy 301.11192 -396.860522) (xy 301.106134 -396.867675) (xy 301.099612 -396.884859)
			(xy 301.09922 -396.89405) (xy 301.09922 -397.386302) (xy 301.099625 -397.39549) (xy 301.106142 -397.412674)
			(xy 301.11192 -397.41983) (xy 301.133746 -397.445526) (xy 301.171834 -397.501157) (xy 301.200562 -397.556296)
			(xy 302.328806 -397.556296) (xy 302.336881 -397.489359) (xy 302.352914 -397.423871) (xy 302.376676 -397.360775)
			(xy 302.407824 -397.300979) (xy 302.44591 -397.245344) (xy 302.467772 -397.219678) (xy 302.473569 -397.212534)
			(xy 302.480081 -397.195342) (xy 302.480472 -397.18615) (xy 302.480472 -397.028924) (xy 302.480935 -397.018806)
			(xy 302.48867 -397.000109) (xy 302.502972 -396.985795) (xy 302.521663 -396.978043) (xy 302.53178 -396.977616)
			(xy 303.24806 -396.977616) (xy 303.258182 -396.978049) (xy 303.276888 -396.985787) (xy 303.291204 -397.000099)
			(xy 303.298948 -397.018802) (xy 303.299368 -397.028924) (xy 303.299368 -397.18615) (xy 303.299809 -397.195334)
			(xy 303.306302 -397.212518) (xy 303.312068 -397.219678) (xy 303.333943 -397.245335) (xy 303.372033 -397.30097)
			(xy 303.403185 -397.360767) (xy 303.426951 -397.423865) (xy 303.442986 -397.489355) (xy 303.451062 -397.556295)
			(xy 303.451061 -397.62372) (xy 303.442984 -397.69066) (xy 303.426946 -397.75615) (xy 303.403179 -397.819247)
			(xy 303.372026 -397.879043) (xy 303.333934 -397.934677) (xy 303.312068 -397.960342) (xy 303.306267 -397.967484)
			(xy 303.299756 -397.984677) (xy 303.299368 -397.99387) (xy 303.299368 -398.486376) (xy 303.299797 -398.495561)
			(xy 303.306299 -398.512745) (xy 303.312068 -398.519904) (xy 303.333968 -398.54554) (xy 303.372058 -398.601178)
			(xy 303.403209 -398.660978) (xy 303.426973 -398.724078) (xy 303.443007 -398.789571) (xy 303.45108 -398.856513)
			(xy 303.451077 -398.923941) (xy 303.442997 -398.990882) (xy 303.426957 -399.056373) (xy 303.403187 -399.119472)
			(xy 303.37203 -399.179269) (xy 303.333935 -399.234903) (xy 303.312068 -399.260568) (xy 303.306256 -399.267702)
			(xy 303.299751 -399.284901) (xy 303.299368 -399.294096) (xy 303.299368 -399.451576) (xy 303.298964 -399.461701)
			(xy 303.291218 -399.48041) (xy 303.276897 -399.494727) (xy 303.258185 -399.502467) (xy 303.24806 -399.502884)
			(xy 302.53178 -399.502884) (xy 302.521654 -399.5025) (xy 302.502947 -399.494742) (xy 302.488633 -399.480416)
			(xy 302.480891 -399.461702) (xy 302.480472 -399.451576) (xy 302.480472 -399.294096) (xy 302.48007 -399.284908)
			(xy 302.473551 -399.267723) (xy 302.467772 -399.260568) (xy 302.445944 -399.234873) (xy 302.407856 -399.179242)
			(xy 302.376706 -399.11945) (xy 302.352941 -399.056357) (xy 302.336904 -398.990872) (xy 302.328825 -398.923937)
			(xy 302.328822 -398.856517) (xy 302.336894 -398.789582) (xy 302.352925 -398.724095) (xy 302.376684 -398.661)
			(xy 302.407829 -398.601204) (xy 302.445911 -398.54557) (xy 302.467772 -398.519904) (xy 302.473558 -398.512752)
			(xy 302.480077 -398.495566) (xy 302.480472 -398.486376) (xy 302.480472 -397.99387) (xy 302.480082 -397.98468)
			(xy 302.473555 -397.967496) (xy 302.467772 -397.960342) (xy 302.445919 -397.934668) (xy 302.407832 -397.879034)
			(xy 302.376682 -397.819239) (xy 302.352919 -397.756143) (xy 302.336883 -397.690656) (xy 302.328807 -397.623719)
			(xy 302.328806 -397.556296) (xy 301.200562 -397.556296) (xy 301.202986 -397.560949) (xy 301.226751 -397.624042)
			(xy 301.242789 -397.689527) (xy 301.250867 -397.756461) (xy 301.250871 -397.823882) (xy 301.242799 -397.890817)
			(xy 301.226768 -397.956304) (xy 301.203009 -398.019399) (xy 301.171864 -398.079194) (xy 301.133781 -398.134828)
			(xy 301.11192 -398.160494) (xy 301.106146 -398.167655) (xy 301.099617 -398.184833) (xy 301.09922 -398.194022)
			(xy 301.09922 -398.351502) (xy 301.098774 -398.361634) (xy 301.091038 -398.380362) (xy 301.076739 -398.39472)
			(xy 301.058042 -398.402532) (xy 301.047912 -398.403064) (xy 300.331632 -398.403064) (xy 300.321475 -398.402652)
			(xy 300.302717 -398.39486) (xy 300.288391 -398.38046) (xy 300.280696 -398.361661) (xy 300.280324 -398.351502)
			(xy 300.280324 -398.194022) (xy 300.279898 -398.184837) (xy 300.273395 -398.167652) (xy 300.267624 -398.160494)
			(xy 300.245722 -398.13486) (xy 300.207633 -398.079222) (xy 300.176482 -398.019421) (xy 300.152719 -397.95632)
			(xy 300.136686 -397.890827) (xy 300.128612 -397.823885) (xy 299.000445 -397.823885) (xy 298.972017 -397.878595)
			(xy 298.934068 -397.934182) (xy 298.91228 -397.959834) (xy 298.906484 -397.96698) (xy 298.89997 -397.98417)
			(xy 298.89958 -397.993362) (xy 298.89958 -398.486884) (xy 298.900003 -398.49607) (xy 298.906508 -398.513254)
			(xy 298.91228 -398.520412) (xy 298.934103 -398.546035) (xy 298.972049 -398.601626) (xy 299.00308 -398.661354)
			(xy 299.02675 -398.724362) (xy 299.04272 -398.789748) (xy 299.050761 -398.856573) (xy 299.050757 -398.923881)
			(xy 299.04271 -398.990706) (xy 299.026734 -399.05609) (xy 299.003058 -399.119095) (xy 298.972021 -399.17882)
			(xy 298.934069 -399.234408) (xy 298.91228 -399.26006) (xy 298.906473 -399.267198) (xy 298.899965 -399.284394)
			(xy 298.89958 -399.293588) (xy 298.89958 -399.451576) (xy 298.899159 -399.461731) (xy 298.891367 -399.480487)
			(xy 298.87697 -399.494812) (xy 298.858175 -399.502509) (xy 298.848018 -399.502884) (xy 298.131738 -399.502884)
			(xy 298.121617 -399.502343) (xy 298.102901 -399.494632) (xy 298.088544 -399.480362) (xy 298.08072 -399.461694)
			(xy 298.080176 -399.451576) (xy 298.080176 -399.293588) (xy 298.079777 -399.2844) (xy 298.073256 -399.267215)
			(xy 298.067476 -399.26006) (xy 298.045723 -399.234379) (xy 298.00777 -399.178798) (xy 297.976733 -399.119078)
			(xy 297.953057 -399.056078) (xy 297.93708 -398.990699) (xy 297.929033 -398.923879) (xy 297.92903 -398.856576)
			(xy 297.937071 -398.789755) (xy 297.953041 -398.724374) (xy 297.976711 -398.661371) (xy 298.007742 -398.601649)
			(xy 298.045689 -398.546064) (xy 298.067476 -398.520412) (xy 298.07329 -398.513279) (xy 298.079795 -398.496079)
			(xy 298.080176 -398.486884) (xy 298.080176 -397.993362) (xy 298.079789 -397.984172) (xy 298.07326 -397.966988)
			(xy 298.067476 -397.959834) (xy 298.045697 -397.934174) (xy 298.007746 -397.87859) (xy 297.97671 -397.818868)
			(xy 297.953035 -397.755864) (xy 297.93706 -397.690482) (xy 297.929015 -397.62366) (xy 297.929014 -397.556355)
			(xy 296.800802 -397.556355) (xy 296.803196 -397.56095) (xy 296.826961 -397.624042) (xy 296.842998 -397.689527)
			(xy 296.851076 -397.756461) (xy 296.85108 -397.823881) (xy 296.843008 -397.890817) (xy 296.826978 -397.956303)
			(xy 296.803219 -398.019398) (xy 296.772075 -398.079194) (xy 296.733993 -398.134828) (xy 296.712132 -398.160494)
			(xy 296.706347 -398.167647) (xy 296.699827 -398.184832) (xy 296.699432 -398.194022) (xy 296.699432 -398.351502)
			(xy 296.698974 -398.361632) (xy 296.691241 -398.380359) (xy 296.676945 -398.394716) (xy 296.658252 -398.40253)
			(xy 296.648124 -398.403064) (xy 295.931844 -398.403064) (xy 295.921688 -398.402642) (xy 295.90293 -398.394854)
			(xy 295.888604 -398.380456) (xy 295.880909 -398.36166) (xy 295.880536 -398.351502) (xy 295.880536 -398.194022)
			(xy 295.880107 -398.184837) (xy 295.873606 -398.167653) (xy 295.867836 -398.160494) (xy 295.845933 -398.13486)
			(xy 295.807843 -398.079222) (xy 295.776692 -398.019422) (xy 295.752929 -397.956321) (xy 295.736895 -397.890827)
			(xy 295.728821 -397.823885) (xy 294.600676 -397.823885) (xy 294.57194 -397.879043) (xy 294.533849 -397.934677)
			(xy 294.511984 -397.960342) (xy 294.506185 -397.967486) (xy 294.499672 -397.984677) (xy 294.499284 -397.99387)
			(xy 294.499284 -398.486376) (xy 294.499709 -398.495561) (xy 294.506213 -398.512746) (xy 294.511984 -398.519904)
			(xy 294.533884 -398.54554) (xy 294.571973 -398.601178) (xy 294.603123 -398.660978) (xy 294.626885 -398.724079)
			(xy 294.642919 -398.789572) (xy 294.650992 -398.856514) (xy 294.650989 -398.92394) (xy 294.642909 -398.990881)
			(xy 294.626869 -399.056373) (xy 294.603101 -399.119471) (xy 294.571945 -399.179268) (xy 294.533851 -399.234903)
			(xy 294.511984 -399.260568) (xy 294.506174 -399.267704) (xy 294.499668 -399.284902) (xy 294.499284 -399.294096)
			(xy 294.499284 -399.451576) (xy 294.498864 -399.461699) (xy 294.491121 -399.480405) (xy 294.476805 -399.494721)
			(xy 294.458099 -399.502464) (xy 294.447976 -399.502884) (xy 293.731696 -399.502884) (xy 293.721571 -399.502487)
			(xy 293.702865 -399.494734) (xy 293.68855 -399.480412) (xy 293.680808 -399.461701) (xy 293.680388 -399.451576)
			(xy 293.680388 -399.294096) (xy 293.679982 -399.284908) (xy 293.673466 -399.267724) (xy 293.667688 -399.260568)
			(xy 293.64586 -399.234873) (xy 293.607771 -399.179243) (xy 293.576619 -399.119451) (xy 293.552854 -399.056358)
			(xy 293.536816 -398.990872) (xy 293.528737 -398.923937) (xy 293.528734 -398.856517) (xy 293.536806 -398.789581)
			(xy 293.552838 -398.724094) (xy 293.576597 -398.660999) (xy 293.607743 -398.601204) (xy 293.645827 -398.545569)
			(xy 293.667688 -398.519904) (xy 293.673464 -398.512744) (xy 293.679991 -398.495565) (xy 293.680388 -398.486376)
			(xy 293.680388 -397.99387) (xy 293.679995 -397.984681) (xy 293.673469 -397.967497) (xy 293.667688 -397.960342)
			(xy 293.645834 -397.934668) (xy 293.607746 -397.879035) (xy 293.576596 -397.81924) (xy 293.552831 -397.756144)
			(xy 293.536796 -397.690656) (xy 293.528719 -397.623719) (xy 293.528718 -397.556296) (xy 292.40047 -397.556296)
			(xy 292.403082 -397.561322) (xy 292.426757 -397.624322) (xy 292.442733 -397.689701) (xy 292.450781 -397.75652)
			(xy 292.450784 -397.823823) (xy 292.442744 -397.890643) (xy 292.426774 -397.956023) (xy 292.403105 -398.019026)
			(xy 292.372075 -398.078748) (xy 292.33413 -398.134334) (xy 292.312344 -398.159986) (xy 292.306522 -398.167113)
			(xy 292.300024 -398.184318) (xy 292.299644 -398.193514) (xy 292.299644 -398.351502) (xy 292.299237 -398.361676)
			(xy 292.291448 -398.380474) (xy 292.277057 -398.39486) (xy 292.258256 -398.402641) (xy 292.248082 -398.403064)
			(xy 291.531802 -398.403064) (xy 291.521645 -398.402565) (xy 291.502876 -398.394792) (xy 291.488511 -398.380427)
			(xy 291.480736 -398.361659) (xy 291.48024 -398.351502) (xy 291.48024 -398.193514) (xy 291.479814 -398.184329)
			(xy 291.473311 -398.167145) (xy 291.46754 -398.159986) (xy 291.445715 -398.134365) (xy 291.407767 -398.078774)
			(xy 291.376735 -398.019046) (xy 291.353065 -397.956037) (xy 291.337094 -397.890651) (xy 291.329053 -397.823825)
			(xy 290.200388 -397.823825) (xy 290.171931 -397.878594) (xy 290.133983 -397.934181) (xy 290.112196 -397.959834)
			(xy 290.106402 -397.966981) (xy 290.099886 -397.98417) (xy 290.099496 -397.993362) (xy 290.099496 -398.486884)
			(xy 290.099915 -398.49607) (xy 290.106423 -398.513255) (xy 290.112196 -398.520412) (xy 290.134018 -398.546036)
			(xy 290.171963 -398.601627) (xy 290.202993 -398.661355) (xy 290.226662 -398.724363) (xy 290.242632 -398.789748)
			(xy 290.250673 -398.856573) (xy 290.250669 -398.923881) (xy 290.242622 -398.990705) (xy 290.226646 -399.056089)
			(xy 290.202971 -399.119095) (xy 290.171936 -399.17882) (xy 290.133985 -399.234407) (xy 290.112196 -399.26006)
			(xy 290.106391 -399.267199) (xy 290.099881 -399.284394) (xy 290.099496 -399.293588) (xy 290.099496 -399.451576)
			(xy 290.099059 -399.461729) (xy 290.09127 -399.480482) (xy 290.076878 -399.494806) (xy 290.058089 -399.502506)
			(xy 290.047934 -399.502884) (xy 289.331654 -399.502884) (xy 289.321527 -399.502412) (xy 289.30281 -399.494673)
			(xy 289.288456 -399.480383) (xy 289.280634 -399.4617) (xy 289.280092 -399.451576) (xy 289.280092 -399.293588)
			(xy 289.279689 -399.2844) (xy 289.273171 -399.267216) (xy 289.267392 -399.26006) (xy 289.245638 -399.234379)
			(xy 289.207685 -399.178798) (xy 289.176647 -399.119079) (xy 289.15297 -399.056078) (xy 289.136993 -398.990699)
			(xy 289.128945 -398.923879) (xy 289.128942 -398.856575) (xy 289.136983 -398.789754) (xy 289.152954 -398.724374)
			(xy 289.176625 -398.66137) (xy 289.207657 -398.601648) (xy 289.245605 -398.546063) (xy 289.267392 -398.520412)
			(xy 289.273208 -398.51328) (xy 289.279711 -398.496079) (xy 289.280092 -398.486884) (xy 289.280092 -397.993362)
			(xy 289.279702 -397.984173) (xy 289.273175 -397.966988) (xy 289.267392 -397.959834) (xy 289.245612 -397.934174)
			(xy 289.20766 -397.87859) (xy 289.176623 -397.818868) (xy 289.152948 -397.755865) (xy 289.136972 -397.690483)
			(xy 289.128927 -397.62366) (xy 289.128926 -397.556355) (xy 288.000733 -397.556355) (xy 288.003125 -397.560946)
			(xy 288.026894 -397.624039) (xy 288.042933 -397.689525) (xy 288.051013 -397.756461) (xy 288.051016 -397.823882)
			(xy 288.042944 -397.890819) (xy 288.026911 -397.956307) (xy 288.003148 -398.019402) (xy 287.971999 -398.079197)
			(xy 287.933912 -398.13483) (xy 287.912048 -398.160494) (xy 287.906265 -398.167649) (xy 287.899744 -398.184832)
			(xy 287.899348 -398.194022) (xy 287.899348 -398.351502) (xy 287.898875 -398.36163) (xy 287.891144 -398.380354)
			(xy 287.876853 -398.39471) (xy 287.858166 -398.402527) (xy 287.84804 -398.403064) (xy 287.13176 -398.403064)
			(xy 287.121599 -398.40271) (xy 287.102839 -398.394895) (xy 287.088515 -398.380477) (xy 287.080824 -398.361666)
			(xy 287.080452 -398.351502) (xy 287.080452 -398.194022) (xy 287.08002 -398.184837) (xy 287.07352 -398.167653)
			(xy 287.067752 -398.160494) (xy 287.045849 -398.13486) (xy 287.007758 -398.079223) (xy 286.976606 -398.019423)
			(xy 286.952842 -397.956321) (xy 286.936807 -397.890828) (xy 286.928734 -397.823885) (xy 244.446806 -397.823885)
			(xy 244.446806 -399.877788) (xy 244.446297 -399.902737) (xy 244.438487 -399.952019) (xy 244.423074 -399.999476)
			(xy 244.400434 -400.043943) (xy 244.371126 -400.084326) (xy 244.353842 -400.102324) (xy 243.288058 -401.168108)
			(xy 243.270087 -401.185424) (xy 243.229704 -401.214744) (xy 243.185232 -401.237387) (xy 243.137766 -401.252795)
			(xy 243.088474 -401.260589) (xy 243.063522 -401.261072) (xy 239.143794 -401.261072) (xy 239.133722 -401.261475)
			(xy 239.115123 -401.269209) (xy 239.107726 -401.276058) (xy 238.659987 -401.723797) (xy 286.928745 -401.723797)
			(xy 286.928747 -401.65637) (xy 286.936826 -401.58943) (xy 286.952865 -401.523939) (xy 286.976634 -401.460841)
			(xy 287.00779 -401.401044) (xy 287.045885 -401.34541) (xy 287.067752 -401.319746) (xy 287.07356 -401.312609)
			(xy 287.080067 -401.295412) (xy 287.080452 -401.286218) (xy 287.080452 -400.793966) (xy 287.080046 -400.784779)
			(xy 287.073528 -400.767595) (xy 287.067752 -400.760438) (xy 287.045892 -400.734769) (xy 287.0078 -400.679136)
			(xy 286.976646 -400.619341) (xy 286.952879 -400.556244) (xy 286.936842 -400.490755) (xy 286.928764 -400.423817)
			(xy 286.928764 -400.356392) (xy 286.93684 -400.289454) (xy 286.952876 -400.223964) (xy 286.976642 -400.160867)
			(xy 287.007795 -400.101072) (xy 287.045887 -400.045438) (xy 287.067752 -400.019774) (xy 287.073549 -400.012629)
			(xy 287.080062 -399.995438) (xy 287.080452 -399.986246) (xy 287.080452 -399.828766) (xy 287.080899 -399.818636)
			(xy 287.08864 -399.799911) (xy 287.102939 -399.785556) (xy 287.121632 -399.77774) (xy 287.13176 -399.777204)
			(xy 287.84804 -399.777204) (xy 287.858197 -399.777589) (xy 287.876951 -399.785399) (xy 287.891273 -399.799806)
			(xy 287.898971 -399.818606) (xy 287.899348 -399.828766) (xy 287.899348 -399.986246) (xy 287.899796 -399.995429)
			(xy 287.906285 -400.012613) (xy 287.912048 -400.019774) (xy 287.93392 -400.045433) (xy 287.972012 -400.101068)
			(xy 288.003165 -400.160864) (xy 288.026931 -400.223962) (xy 288.042968 -400.289452) (xy 288.051044 -400.356392)
			(xy 288.051043 -400.423817) (xy 288.042966 -400.490757) (xy 288.026928 -400.556247) (xy 288.003161 -400.619344)
			(xy 287.972007 -400.67914) (xy 287.933914 -400.734774) (xy 287.912048 -400.760438) (xy 287.906246 -400.767579)
			(xy 287.899736 -400.784773) (xy 287.899348 -400.793966) (xy 287.899348 -401.286218) (xy 287.899761 -401.295405)
			(xy 287.906274 -401.312588) (xy 287.912048 -401.319746) (xy 287.933892 -401.345428) (xy 287.971985 -401.401059)
			(xy 288.00314 -401.460852) (xy 288.026907 -401.523947) (xy 288.042946 -401.589435) (xy 288.051024 -401.656372)
			(xy 288.051026 -401.723795) (xy 288.042952 -401.790733) (xy 288.026917 -401.856221) (xy 288.003153 -401.919317)
			(xy 287.972002 -401.979113) (xy 287.933912 -402.034746) (xy 287.912048 -402.06041) (xy 287.906258 -402.06756)
			(xy 287.899741 -402.084747) (xy 287.899348 -402.093938) (xy 287.899348 -402.251418) (xy 287.898888 -402.261547)
			(xy 287.891152 -402.280271) (xy 287.876858 -402.294627) (xy 287.858167 -402.302444) (xy 287.84804 -402.30298)
			(xy 287.13176 -402.30298) (xy 287.121601 -402.302611) (xy 287.102844 -402.294798) (xy 287.088521 -402.280385)
			(xy 287.080826 -402.26158) (xy 287.080452 -402.251418) (xy 287.080452 -402.093938) (xy 287.080012 -402.084754)
			(xy 287.073518 -402.06757) (xy 287.067752 -402.06041) (xy 287.045865 -402.034763) (xy 287.007773 -401.979127)
			(xy 286.97662 -401.919329) (xy 286.952855 -401.85623) (xy 286.93682 -401.790738) (xy 286.928745 -401.723797)
			(xy 238.659987 -401.723797) (xy 237.559965 -402.823819) (xy 289.128886 -402.823819) (xy 289.12889 -402.756509)
			(xy 289.13694 -402.689682) (xy 289.15292 -402.624297) (xy 289.1766 -402.56129) (xy 289.207642 -402.501565)
			(xy 289.2456 -402.445979) (xy 289.267392 -402.420328) (xy 289.273201 -402.413191) (xy 289.279708 -402.395994)
			(xy 289.280092 -402.3868) (xy 289.280092 -401.893532) (xy 289.279668 -401.884346) (xy 289.273164 -401.867162)
			(xy 289.267392 -401.860004) (xy 289.245583 -401.834369) (xy 289.207631 -401.778781) (xy 289.176596 -401.719056)
			(xy 289.152922 -401.656049) (xy 289.136949 -401.590664) (xy 289.128906 -401.523839) (xy 289.128907 -401.456531)
			(xy 289.136954 -401.389706) (xy 289.152931 -401.324322) (xy 289.176608 -401.261317) (xy 289.207647 -401.201593)
			(xy 289.245601 -401.146007) (xy 289.267392 -401.120356) (xy 289.273189 -401.113211) (xy 289.279704 -401.09602)
			(xy 289.280092 -401.086828) (xy 289.280092 -400.92884) (xy 289.280554 -400.918689) (xy 289.288335 -400.89994)
			(xy 289.30272 -400.885615) (xy 289.321502 -400.877913) (xy 289.331654 -400.877532) (xy 290.047934 -400.877532)
			(xy 290.058062 -400.877998) (xy 290.076782 -400.885736) (xy 290.091137 -400.900028) (xy 290.098957 -400.918714)
			(xy 290.099496 -400.92884) (xy 290.099496 -401.086828) (xy 290.099893 -401.096017) (xy 290.106416 -401.113201)
			(xy 290.112196 -401.120356) (xy 290.133963 -401.146025) (xy 290.17191 -401.20161) (xy 290.202942 -401.261331)
			(xy 290.226615 -401.324334) (xy 290.242588 -401.389713) (xy 290.250633 -401.456534) (xy 290.250635 -401.523836)
			(xy 290.242593 -401.590657) (xy 290.226624 -401.656038) (xy 290.202955 -401.719041) (xy 290.200515 -401.723737)
			(xy 291.329064 -401.723737) (xy 291.329066 -401.65643) (xy 291.337113 -401.589606) (xy 291.353088 -401.524222)
			(xy 291.376763 -401.461217) (xy 291.407799 -401.401493) (xy 291.445751 -401.345906) (xy 291.46754 -401.320254)
			(xy 291.473344 -401.313114) (xy 291.479853 -401.295919) (xy 291.48024 -401.286726) (xy 291.48024 -400.793458)
			(xy 291.479841 -400.78427) (xy 291.473319 -400.767086) (xy 291.46754 -400.75993) (xy 291.445758 -400.734273)
			(xy 291.407809 -400.678687) (xy 291.376776 -400.618964) (xy 291.353103 -400.55596) (xy 291.337129 -400.490579)
			(xy 291.329085 -400.423757) (xy 291.329084 -400.356452) (xy 291.337128 -400.28963) (xy 291.3531 -400.224248)
			(xy 291.376772 -400.161244) (xy 291.407805 -400.101521) (xy 291.445753 -400.045934) (xy 291.46754 -400.020282)
			(xy 291.473332 -400.013134) (xy 291.479848 -399.995945) (xy 291.48024 -399.986754) (xy 291.48024 -399.828766)
			(xy 291.480706 -399.818606) (xy 291.488492 -399.799835) (xy 291.502866 -399.785471) (xy 291.521641 -399.777698)
			(xy 291.531802 -399.777204) (xy 292.248082 -399.777204) (xy 292.258234 -399.777747) (xy 292.276997 -399.785509)
			(xy 292.291361 -399.79986) (xy 292.299143 -399.818614) (xy 292.299644 -399.828766) (xy 292.299644 -399.986754)
			(xy 292.300089 -399.995937) (xy 292.30658 -400.013121) (xy 292.312344 -400.020282) (xy 292.334138 -400.045929)
			(xy 292.372088 -400.101516) (xy 292.403122 -400.16124) (xy 292.426795 -400.224245) (xy 292.442768 -400.289628)
			(xy 292.450812 -400.356452) (xy 292.450811 -400.423757) (xy 292.442766 -400.490581) (xy 292.426792 -400.555963)
			(xy 292.403118 -400.618968) (xy 292.372083 -400.678692) (xy 292.334132 -400.734278) (xy 292.312344 -400.75993)
			(xy 292.306545 -400.767073) (xy 292.300033 -400.784266) (xy 292.299644 -400.793458) (xy 292.299644 -401.286726)
			(xy 292.300054 -401.295913) (xy 292.306569 -401.313097) (xy 292.312344 -401.320254) (xy 292.33411 -401.345924)
			(xy 292.372061 -401.401507) (xy 292.403096 -401.461228) (xy 292.426771 -401.524231) (xy 292.442746 -401.589611)
			(xy 292.450792 -401.656432) (xy 292.450794 -401.723735) (xy 292.442752 -401.790557) (xy 292.426781 -401.855938)
			(xy 292.40311 -401.918941) (xy 292.372078 -401.978664) (xy 292.334131 -402.03425) (xy 292.312344 -402.059902)
			(xy 292.306557 -402.067054) (xy 292.300038 -402.084239) (xy 292.299644 -402.09343) (xy 292.299644 -402.251418)
			(xy 292.299181 -402.261579) (xy 292.291397 -402.280352) (xy 292.277022 -402.294718) (xy 292.258244 -402.302488)
			(xy 292.248082 -402.30298) (xy 291.531802 -402.30298) (xy 291.521647 -402.302465) (xy 291.502881 -402.294695)
			(xy 291.488516 -402.280336) (xy 291.480739 -402.261573) (xy 291.48024 -402.251418) (xy 291.48024 -402.09343)
			(xy 291.479806 -402.084246) (xy 291.473308 -402.067061) (xy 291.46754 -402.059902) (xy 291.44573 -402.034268)
			(xy 291.407782 -401.978679) (xy 291.37675 -401.918953) (xy 291.353078 -401.855946) (xy 291.337107 -401.790561)
			(xy 291.329064 -401.723737) (xy 290.200515 -401.723737) (xy 290.171926 -401.778764) (xy 290.133981 -401.834351)
			(xy 290.112196 -401.860004) (xy 290.106415 -401.86716) (xy 290.099891 -401.884342) (xy 290.099496 -401.893532)
			(xy 290.099496 -402.3868) (xy 290.099907 -402.395987) (xy 290.10642 -402.413171) (xy 290.112196 -402.420328)
			(xy 290.133935 -402.44602) (xy 290.171883 -402.501601) (xy 290.202916 -402.56132) (xy 290.22659 -402.624319)
			(xy 290.242566 -402.689696) (xy 290.250613 -402.756514) (xy 290.250617 -402.823814) (xy 290.250609 -402.823878)
			(xy 293.528678 -402.823878) (xy 293.528683 -402.75645) (xy 293.536763 -402.689509) (xy 293.552803 -402.624017)
			(xy 293.576572 -402.560919) (xy 293.607728 -402.501121) (xy 293.645822 -402.445485) (xy 293.667688 -402.41982)
			(xy 293.6735 -402.412685) (xy 293.680006 -402.395487) (xy 293.680388 -402.386292) (xy 293.680388 -401.89404)
			(xy 293.679961 -401.884854) (xy 293.67346 -401.86767) (xy 293.667688 -401.860512) (xy 293.645805 -401.834863)
			(xy 293.607717 -401.779226) (xy 293.576568 -401.719427) (xy 293.552806 -401.656328) (xy 293.536772 -401.590837)
			(xy 293.528698 -401.523897) (xy 293.5287 -401.456472) (xy 293.536777 -401.389533) (xy 293.552815 -401.324043)
			(xy 293.576581 -401.260945) (xy 293.607733 -401.201149) (xy 293.645823 -401.145513) (xy 293.667688 -401.119848)
			(xy 293.673488 -401.112705) (xy 293.680001 -401.095513) (xy 293.680388 -401.08632) (xy 293.680388 -400.92884)
			(xy 293.680849 -400.918722) (xy 293.688581 -400.900021) (xy 293.702884 -400.885706) (xy 293.721578 -400.877957)
			(xy 293.731696 -400.877532) (xy 294.447976 -400.877532) (xy 294.458101 -400.877936) (xy 294.47681 -400.885682)
			(xy 294.491127 -400.900003) (xy 294.498867 -400.918715) (xy 294.499284 -400.92884) (xy 294.499284 -401.08632)
			(xy 294.499688 -401.095508) (xy 294.506206 -401.112692) (xy 294.511984 -401.119848) (xy 294.533829 -401.145529)
			(xy 294.571919 -401.201161) (xy 294.603072 -401.260955) (xy 294.626838 -401.32405) (xy 294.642875 -401.389537)
			(xy 294.650953 -401.456474) (xy 294.650955 -401.523896) (xy 294.64288 -401.590833) (xy 294.626847 -401.656322)
			(xy 294.603084 -401.719418) (xy 294.600803 -401.723797) (xy 295.728833 -401.723797) (xy 295.728835 -401.65637)
			(xy 295.736913 -401.58943) (xy 295.752952 -401.523939) (xy 295.77672 -401.460841) (xy 295.807876 -401.401045)
			(xy 295.845969 -401.345411) (xy 295.867836 -401.319746) (xy 295.873643 -401.312608) (xy 295.88015 -401.295412)
			(xy 295.880536 -401.286218) (xy 295.880536 -400.793966) (xy 295.880134 -400.784778) (xy 295.873614 -400.767594)
			(xy 295.867836 -400.760438) (xy 295.845977 -400.734769) (xy 295.807885 -400.679135) (xy 295.776732 -400.61934)
			(xy 295.752966 -400.556244) (xy 295.736929 -400.490755) (xy 295.728852 -400.423816) (xy 295.728852 -400.356393)
			(xy 295.736928 -400.289454) (xy 295.752964 -400.223965) (xy 295.776729 -400.160868) (xy 295.807881 -400.101072)
			(xy 295.845971 -400.045439) (xy 295.867836 -400.019774) (xy 295.873631 -400.012628) (xy 295.880146 -399.995438)
			(xy 295.880536 -399.986246) (xy 295.880536 -399.828766) (xy 295.880999 -399.818638) (xy 295.888737 -399.799916)
			(xy 295.90303 -399.785561) (xy 295.921718 -399.777743) (xy 295.931844 -399.777204) (xy 296.648124 -399.777204)
			(xy 296.65828 -399.777602) (xy 296.677034 -399.785406) (xy 296.691357 -399.79981) (xy 296.699055 -399.818608)
			(xy 296.699432 -399.828766) (xy 296.699432 -399.986246) (xy 296.699883 -399.995429) (xy 296.70637 -400.012613)
			(xy 296.712132 -400.019774) (xy 296.734001 -400.045435) (xy 296.772087 -400.101071) (xy 296.803236 -400.160868)
			(xy 296.826998 -400.223965) (xy 296.843032 -400.289455) (xy 296.851107 -400.356393) (xy 296.851107 -400.423816)
			(xy 296.843031 -400.490754) (xy 296.826996 -400.556243) (xy 296.803232 -400.61934) (xy 296.772083 -400.679137)
			(xy 296.733995 -400.734772) (xy 296.712132 -400.760438) (xy 296.706329 -400.767578) (xy 296.69982 -400.784773)
			(xy 296.699432 -400.793966) (xy 296.699432 -401.286218) (xy 296.699849 -401.295404) (xy 296.70636 -401.312588)
			(xy 296.712132 -401.319746) (xy 296.733973 -401.34543) (xy 296.77206 -401.401062) (xy 296.80321 -401.460856)
			(xy 296.826974 -401.523951) (xy 296.84301 -401.589437) (xy 296.851088 -401.656373) (xy 296.85109 -401.723794)
			(xy 296.843016 -401.79073) (xy 296.826984 -401.856218) (xy 296.803224 -401.919314) (xy 296.772078 -401.979109)
			(xy 296.733994 -402.034744) (xy 296.712132 -402.06041) (xy 296.70634 -402.067558) (xy 296.699825 -402.084747)
			(xy 296.699432 -402.093938) (xy 296.699432 -402.251418) (xy 296.698988 -402.261549) (xy 296.691249 -402.280276)
			(xy 296.676949 -402.294633) (xy 296.658253 -402.302447) (xy 296.648124 -402.30298) (xy 295.931844 -402.30298)
			(xy 295.92169 -402.302542) (xy 295.902935 -402.294757) (xy 295.888609 -402.280365) (xy 295.880912 -402.261574)
			(xy 295.880536 -402.251418) (xy 295.880536 -402.093938) (xy 295.880099 -402.084754) (xy 295.873603 -402.06757)
			(xy 295.867836 -402.06041) (xy 295.845949 -402.034763) (xy 295.807859 -401.979127) (xy 295.776707 -401.919328)
			(xy 295.752942 -401.856229) (xy 295.736907 -401.790737) (xy 295.728833 -401.723797) (xy 294.600803 -401.723797)
			(xy 294.571935 -401.779213) (xy 294.533847 -401.834847) (xy 294.511984 -401.860512) (xy 294.506198 -401.867665)
			(xy 294.499678 -401.88485) (xy 294.499284 -401.89404) (xy 294.499284 -402.386292) (xy 294.499702 -402.395478)
			(xy 294.506211 -402.412662) (xy 294.511984 -402.41982) (xy 294.533801 -402.445524) (xy 294.571893 -402.501152)
			(xy 294.603046 -402.560943) (xy 294.626814 -402.624035) (xy 294.642853 -402.68952) (xy 294.650933 -402.756454)
			(xy 294.650937 -402.823819) (xy 297.928973 -402.823819) (xy 297.928978 -402.756509) (xy 297.937027 -402.689683)
			(xy 297.953006 -402.624297) (xy 297.976686 -402.561291) (xy 298.007727 -402.501566) (xy 298.045684 -402.445979)
			(xy 298.067476 -402.420328) (xy 298.073283 -402.41319) (xy 298.079792 -402.395994) (xy 298.080176 -402.3868)
			(xy 298.080176 -401.893532) (xy 298.079756 -401.884346) (xy 298.07325 -401.867161) (xy 298.067476 -401.860004)
			(xy 298.045668 -401.834368) (xy 298.007717 -401.77878) (xy 297.976683 -401.719055) (xy 297.953009 -401.656048)
			(xy 297.937037 -401.590664) (xy 297.928993 -401.523839) (xy 297.928995 -401.456531) (xy 297.937042 -401.389707)
			(xy 297.953018 -401.324323) (xy 297.976695 -401.261318) (xy 298.007732 -401.201594) (xy 298.045686 -401.146008)
			(xy 298.067476 -401.120356) (xy 298.073271 -401.113209) (xy 298.079787 -401.09602) (xy 298.080176 -401.086828)
			(xy 298.080176 -400.92884) (xy 298.080654 -400.918691) (xy 298.088432 -400.899945) (xy 298.102811 -400.885621)
			(xy 298.121588 -400.877915) (xy 298.131738 -400.877532) (xy 298.848018 -400.877532) (xy 298.858145 -400.878011)
			(xy 298.876865 -400.885744) (xy 298.89122 -400.900032) (xy 298.89904 -400.918716) (xy 298.89958 -400.92884)
			(xy 298.89958 -401.086828) (xy 298.899981 -401.096016) (xy 298.906502 -401.1132) (xy 298.91228 -401.120356)
			(xy 298.934048 -401.146024) (xy 298.971996 -401.201609) (xy 299.003029 -401.261331) (xy 299.026702 -401.324333)
			(xy 299.042676 -401.389713) (xy 299.050721 -401.456533) (xy 299.050723 -401.523837) (xy 299.042681 -401.590657)
			(xy 299.026711 -401.656038) (xy 299.003041 -401.719042) (xy 299.000571 -401.723796) (xy 300.128624 -401.723796)
			(xy 300.128626 -401.656371) (xy 300.136704 -401.58943) (xy 300.152743 -401.52394) (xy 300.17651 -401.460842)
			(xy 300.207665 -401.401045) (xy 300.245758 -401.345411) (xy 300.267624 -401.319746) (xy 300.273429 -401.312607)
			(xy 300.279938 -401.295412) (xy 300.280324 -401.286218) (xy 300.280324 -400.793966) (xy 300.279925 -400.784778)
			(xy 300.273403 -400.767594) (xy 300.267624 -400.760438) (xy 300.245765 -400.734768) (xy 300.207675 -400.679135)
			(xy 300.176522 -400.61934) (xy 300.152757 -400.556243) (xy 300.13672 -400.490755) (xy 300.128643 -400.423816)
			(xy 300.128643 -400.356393) (xy 300.136719 -400.289454) (xy 300.152754 -400.223965) (xy 300.176519 -400.160869)
			(xy 300.20767 -400.101073) (xy 300.24576 -400.045439) (xy 300.267624 -400.019774) (xy 300.273417 -400.012626)
			(xy 300.279933 -399.995438) (xy 300.280324 -399.986246) (xy 300.280324 -399.828766) (xy 300.280798 -399.818639)
			(xy 300.288534 -399.79992) (xy 300.302824 -399.785566) (xy 300.321507 -399.777745) (xy 300.331632 -399.777204)
			(xy 301.047912 -399.777204) (xy 301.058067 -399.777612) (xy 301.076821 -399.785412) (xy 301.091144 -399.799813)
			(xy 301.098843 -399.818608) (xy 301.09922 -399.828766) (xy 301.09922 -399.986246) (xy 301.099652 -399.995431)
			(xy 301.10615 -400.012616) (xy 301.11192 -400.019774) (xy 301.133789 -400.045435) (xy 301.171876 -400.10107)
			(xy 301.203026 -400.160867) (xy 301.226789 -400.223965) (xy 301.242823 -400.289454) (xy 301.250898 -400.356393)
			(xy 301.250898 -400.423816) (xy 301.242821 -400.490755) (xy 301.226786 -400.556244) (xy 301.203022 -400.619341)
			(xy 301.171872 -400.679137) (xy 301.133784 -400.734772) (xy 301.11192 -400.760438) (xy 301.106127 -400.767586)
			(xy 301.09961 -400.784774) (xy 301.09922 -400.793966) (xy 301.09922 -401.286218) (xy 301.099617 -401.295407)
			(xy 301.106139 -401.312591) (xy 301.11192 -401.319746) (xy 301.133762 -401.345429) (xy 301.17185 -401.401062)
			(xy 301.203 -401.460856) (xy 301.226765 -401.52395) (xy 301.242801 -401.589437) (xy 301.250878 -401.656373)
			(xy 301.25088 -401.723794) (xy 301.242807 -401.790731) (xy 301.226775 -401.856218) (xy 301.203014 -401.919314)
			(xy 301.171867 -401.97911) (xy 301.133782 -402.034744) (xy 301.11192 -402.06041) (xy 301.106139 -402.067566)
			(xy 301.099614 -402.084748) (xy 301.09922 -402.093938) (xy 301.09922 -402.251418) (xy 301.098787 -402.261551)
			(xy 301.091046 -402.28028) (xy 301.076743 -402.294637) (xy 301.058043 -402.302449) (xy 301.047912 -402.30298)
			(xy 300.331632 -402.30298) (xy 300.321477 -402.302552) (xy 300.302722 -402.294763) (xy 300.288396 -402.280368)
			(xy 300.280699 -402.261575) (xy 300.280324 -402.251418) (xy 300.280324 -402.093938) (xy 300.27989 -402.084753)
			(xy 300.273392 -402.067569) (xy 300.267624 -402.06041) (xy 300.245738 -402.034763) (xy 300.207648 -401.979126)
			(xy 300.176497 -401.919328) (xy 300.152733 -401.856229) (xy 300.136698 -401.790737) (xy 300.128624 -401.723796)
			(xy 299.000571 -401.723796) (xy 298.972011 -401.778765) (xy 298.934066 -401.834352) (xy 298.91228 -401.860004)
			(xy 298.906497 -401.867159) (xy 298.899975 -401.884342) (xy 298.89958 -401.893532) (xy 298.89958 -402.3868)
			(xy 298.899994 -402.395987) (xy 298.906505 -402.413171) (xy 298.91228 -402.420328) (xy 298.93402 -402.446019)
			(xy 298.971969 -402.501601) (xy 299.003003 -402.561319) (xy 299.026678 -402.624318) (xy 299.042653 -402.689696)
			(xy 299.050701 -402.756513) (xy 299.050705 -402.823814) (xy 299.050697 -402.823877) (xy 302.328766 -402.823877)
			(xy 302.328771 -402.75645) (xy 302.336851 -402.689509) (xy 302.35289 -402.624018) (xy 302.376659 -402.560919)
			(xy 302.407814 -402.501122) (xy 302.445906 -402.445486) (xy 302.467772 -402.41982) (xy 302.473594 -402.412693)
			(xy 302.480091 -402.395488) (xy 302.480472 -402.386292) (xy 302.480472 -401.89404) (xy 302.480049 -401.884854)
			(xy 302.473545 -401.867669) (xy 302.467772 -401.860512) (xy 302.445889 -401.834863) (xy 302.407803 -401.779225)
			(xy 302.376655 -401.719426) (xy 302.352893 -401.656328) (xy 302.33686 -401.590837) (xy 302.328786 -401.523897)
			(xy 302.328788 -401.456473) (xy 302.336865 -401.389534) (xy 302.352902 -401.324044) (xy 302.376667 -401.260946)
			(xy 302.407819 -401.201149) (xy 302.445908 -401.145514) (xy 302.467772 -401.119848) (xy 302.473582 -401.112713)
			(xy 302.480087 -401.095514) (xy 302.480472 -401.08632) (xy 302.480472 -400.92884) (xy 302.480948 -400.918724)
			(xy 302.488678 -400.900026) (xy 302.502976 -400.885712) (xy 302.521664 -400.87796) (xy 302.53178 -400.877532)
			(xy 303.24806 -400.877532) (xy 303.258184 -400.87795) (xy 303.276893 -400.885691) (xy 303.291209 -400.900007)
			(xy 303.29895 -400.918716) (xy 303.299368 -400.92884) (xy 303.299368 -401.08632) (xy 303.299776 -401.095507)
			(xy 303.306292 -401.112691) (xy 303.312068 -401.119848) (xy 303.333913 -401.145529) (xy 303.372005 -401.20116)
			(xy 303.403158 -401.260954) (xy 303.426925 -401.324049) (xy 303.442963 -401.389537) (xy 303.451041 -401.456474)
			(xy 303.451043 -401.523896) (xy 303.442968 -401.590834) (xy 303.426934 -401.656322) (xy 303.40317 -401.719418)
			(xy 303.37202 -401.779214) (xy 303.333932 -401.834847) (xy 303.312068 -401.860512) (xy 303.30628 -401.867663)
			(xy 303.299761 -401.884849) (xy 303.299368 -401.89404) (xy 303.299368 -402.386292) (xy 303.299789 -402.395478)
			(xy 303.306296 -402.412662) (xy 303.312068 -402.41982) (xy 303.333886 -402.445524) (xy 303.371978 -402.501152)
			(xy 303.403133 -402.560942) (xy 303.426901 -402.624034) (xy 303.442941 -402.689519) (xy 303.451021 -402.756454)
			(xy 303.451025 -402.823874) (xy 303.442954 -402.89081) (xy 303.426922 -402.956297) (xy 303.403162 -403.019392)
			(xy 303.372015 -403.079186) (xy 303.33393 -403.134819) (xy 303.312068 -403.160484) (xy 303.306249 -403.167613)
			(xy 303.299749 -403.184816) (xy 303.299368 -403.194012) (xy 303.299368 -403.351492) (xy 303.298977 -403.361618)
			(xy 303.291225 -403.380328) (xy 303.276901 -403.394643) (xy 303.258186 -403.402383) (xy 303.24806 -403.4028)
			(xy 302.53178 -403.4028) (xy 302.52167 -403.402331) (xy 302.502991 -403.394587) (xy 302.488697 -403.380285)
			(xy 302.480963 -403.361602) (xy 302.480472 -403.351492) (xy 302.480472 -403.194012) (xy 302.480062 -403.184825)
			(xy 302.473549 -403.16764) (xy 302.467772 -403.160484) (xy 302.445862 -403.134857) (xy 302.407776 -403.079216)
			(xy 302.376629 -403.019415) (xy 302.352869 -402.956313) (xy 302.336838 -402.890819) (xy 302.328766 -402.823877)
			(xy 299.050697 -402.823877) (xy 299.042666 -402.890633) (xy 299.026699 -402.956013) (xy 299.003032 -403.019015)
			(xy 298.972006 -403.078737) (xy 298.934064 -403.134323) (xy 298.91228 -403.159976) (xy 298.906466 -403.167109)
			(xy 298.899963 -403.184309) (xy 298.89958 -403.193504) (xy 298.89958 -403.351492) (xy 298.899171 -403.361648)
			(xy 298.891375 -403.380404) (xy 298.876974 -403.394729) (xy 298.858176 -403.402425) (xy 298.848018 -403.4028)
			(xy 298.131738 -403.4028) (xy 298.121619 -403.402243) (xy 298.102906 -403.394535) (xy 298.08855 -403.380271)
			(xy 298.080722 -403.361608) (xy 298.080176 -403.351492) (xy 298.080176 -403.193504) (xy 298.079769 -403.184316)
			(xy 298.073254 -403.167132) (xy 298.067476 -403.159976) (xy 298.04564 -403.134363) (xy 298.00769 -403.078772)
			(xy 297.976657 -403.019043) (xy 297.952985 -402.956034) (xy 297.937014 -402.890646) (xy 297.928973 -402.823819)
			(xy 294.650937 -402.823819) (xy 294.650937 -402.823874) (xy 294.642866 -402.890809) (xy 294.626835 -402.956296)
			(xy 294.603076 -403.019391) (xy 294.57193 -403.079186) (xy 294.533846 -403.134819) (xy 294.511984 -403.160484)
			(xy 294.506167 -403.167615) (xy 294.499665 -403.184816) (xy 294.499284 -403.194012) (xy 294.499284 -403.351492)
			(xy 294.498877 -403.361616) (xy 294.491129 -403.380322) (xy 294.476809 -403.394638) (xy 294.4581 -403.40238)
			(xy 294.447976 -403.4028) (xy 293.731696 -403.4028) (xy 293.721573 -403.402387) (xy 293.70287 -403.394638)
			(xy 293.688556 -403.38032) (xy 293.68081 -403.361615) (xy 293.680388 -403.351492) (xy 293.680388 -403.194012)
			(xy 293.679975 -403.184825) (xy 293.673464 -403.167641) (xy 293.667688 -403.160484) (xy 293.645777 -403.134857)
			(xy 293.607691 -403.079217) (xy 293.576543 -403.019415) (xy 293.552782 -402.956314) (xy 293.53675 -402.89082)
			(xy 293.528678 -402.823878) (xy 290.250609 -402.823878) (xy 290.242579 -402.890633) (xy 290.226612 -402.956012)
			(xy 290.202946 -403.019014) (xy 290.17192 -403.078737) (xy 290.133979 -403.134323) (xy 290.112196 -403.159976)
			(xy 290.106384 -403.16711) (xy 290.099879 -403.184309) (xy 290.099496 -403.193504) (xy 290.099496 -403.351492)
			(xy 290.099072 -403.361646) (xy 290.091278 -403.380399) (xy 290.076882 -403.394723) (xy 290.05809 -403.402422)
			(xy 290.047934 -403.4028) (xy 289.331654 -403.4028) (xy 289.321529 -403.402312) (xy 289.302815 -403.394577)
			(xy 289.288461 -403.380292) (xy 289.280637 -403.361614) (xy 289.280092 -403.351492) (xy 289.280092 -403.193504)
			(xy 289.279682 -403.184317) (xy 289.273168 -403.167132) (xy 289.267392 -403.159976) (xy 289.245556 -403.134363)
			(xy 289.207605 -403.078772) (xy 289.176571 -403.019044) (xy 289.152898 -402.956034) (xy 289.136927 -402.890647)
			(xy 289.128886 -402.823819) (xy 237.559965 -402.823819) (xy 237.421928 -402.961856) (xy 237.415119 -402.969281)
			(xy 237.40738 -402.987861) (xy 237.406942 -402.997924) (xy 237.406942 -405.623708) (xy 286.928756 -405.623708)
			(xy 286.928757 -405.556283) (xy 286.936834 -405.489343) (xy 286.952872 -405.423853) (xy 286.976639 -405.360756)
			(xy 287.007793 -405.30096) (xy 287.045886 -405.245326) (xy 287.067752 -405.219662) (xy 287.073554 -405.212521)
			(xy 287.080064 -405.195327) (xy 287.080452 -405.186134) (xy 287.080452 -404.693882) (xy 287.080039 -404.684695)
			(xy 287.073526 -404.667512) (xy 287.067752 -404.660354) (xy 287.045908 -404.634672) (xy 287.007815 -404.579041)
			(xy 286.97666 -404.519248) (xy 286.952893 -404.456153) (xy 286.936854 -404.390665) (xy 286.928776 -404.323728)
			(xy 286.928774 -404.256305) (xy 286.936848 -404.189367) (xy 286.952883 -404.123879) (xy 286.976647 -404.060783)
			(xy 287.007798 -404.000987) (xy 287.045888 -403.945354) (xy 287.067752 -403.91969) (xy 287.073542 -403.91254)
			(xy 287.080059 -403.895353) (xy 287.080452 -403.886162) (xy 287.080452 -403.728682) (xy 287.080912 -403.718553)
			(xy 287.088648 -403.699829) (xy 287.102942 -403.685473) (xy 287.121633 -403.677656) (xy 287.13176 -403.67712)
			(xy 287.84804 -403.67712) (xy 287.858199 -403.677489) (xy 287.876956 -403.685302) (xy 287.891279 -403.699715)
			(xy 287.898974 -403.71852) (xy 287.899348 -403.728682) (xy 287.899348 -403.886162) (xy 287.899788 -403.895346)
			(xy 287.906282 -403.91253) (xy 287.912048 -403.91969) (xy 287.933935 -403.945337) (xy 287.972027 -404.000973)
			(xy 288.00318 -404.060771) (xy 288.026945 -404.12387) (xy 288.04298 -404.189362) (xy 288.051055 -404.256303)
			(xy 288.051053 -404.32373) (xy 288.042974 -404.39067) (xy 288.026935 -404.456161) (xy 288.003166 -404.519259)
			(xy 287.97201 -404.579056) (xy 287.933915 -404.63469) (xy 287.912048 -404.660354) (xy 287.90624 -404.667491)
			(xy 287.899733 -404.684688) (xy 287.899348 -404.693882) (xy 287.899348 -405.186134) (xy 287.899754 -405.195321)
			(xy 287.906272 -405.212505) (xy 287.912048 -405.219662) (xy 287.933908 -405.245331) (xy 287.972 -405.300964)
			(xy 288.003154 -405.360759) (xy 288.026921 -405.423856) (xy 288.042958 -405.489345) (xy 288.051036 -405.556283)
			(xy 288.051036 -405.623708) (xy 288.04296 -405.690646) (xy 288.026924 -405.756136) (xy 288.003158 -405.819233)
			(xy 287.972005 -405.879028) (xy 287.933913 -405.934662) (xy 287.912048 -405.960326) (xy 287.906251 -405.967471)
			(xy 287.899738 -405.984662) (xy 287.899348 -405.993854) (xy 287.899348 -406.151334) (xy 287.898901 -406.161464)
			(xy 287.89116 -406.180189) (xy 287.876861 -406.194544) (xy 287.858168 -406.20236) (xy 287.84804 -406.202896)
			(xy 287.13176 -406.202896) (xy 287.121603 -406.202511) (xy 287.102849 -406.194701) (xy 287.088527 -406.180294)
			(xy 287.080829 -406.161494) (xy 287.080452 -406.151334) (xy 287.080452 -405.993854) (xy 287.080004 -405.984671)
			(xy 287.073515 -405.967487) (xy 287.067752 -405.960326) (xy 287.04588 -405.934667) (xy 287.007788 -405.879032)
			(xy 286.976635 -405.819236) (xy 286.952869 -405.756138) (xy 286.936832 -405.690648) (xy 286.928756 -405.623708)
			(xy 237.406942 -405.623708) (xy 237.406942 -406.72373) (xy 289.128897 -406.72373) (xy 289.1289 -406.656422)
			(xy 289.136948 -406.589596) (xy 289.152926 -406.524211) (xy 289.176605 -406.461205) (xy 289.207645 -406.401481)
			(xy 289.245601 -406.345895) (xy 289.267392 -406.320244) (xy 289.273194 -406.313103) (xy 289.279706 -406.295909)
			(xy 289.280092 -406.286716) (xy 289.280092 -405.793448) (xy 289.279661 -405.784263) (xy 289.273162 -405.767078)
			(xy 289.267392 -405.75992) (xy 289.245599 -405.734272) (xy 289.207647 -405.678686) (xy 289.176611 -405.618962)
			(xy 289.152936 -405.555957) (xy 289.136961 -405.490574) (xy 289.128917 -405.42375) (xy 289.128917 -405.356444)
			(xy 289.136962 -405.28962) (xy 289.152937 -405.224237) (xy 289.176613 -405.161232) (xy 289.20765 -405.101509)
			(xy 289.245602 -405.045923) (xy 289.267392 -405.020272) (xy 289.273182 -405.013122) (xy 289.279701 -404.995935)
			(xy 289.280092 -404.986744) (xy 289.280092 -404.828756) (xy 289.280486 -404.8186) (xy 289.288294 -404.799848)
			(xy 289.302699 -404.785527) (xy 289.321496 -404.777827) (xy 289.331654 -404.777448) (xy 290.047934 -404.777448)
			(xy 290.058064 -404.777899) (xy 290.076787 -404.785639) (xy 290.091143 -404.799936) (xy 290.098959 -404.818628)
			(xy 290.099496 -404.828756) (xy 290.099496 -404.986744) (xy 290.099886 -404.995933) (xy 290.106414 -405.013117)
			(xy 290.112196 -405.020272) (xy 290.133979 -405.045928) (xy 290.171925 -405.101515) (xy 290.202957 -405.161238)
			(xy 290.226628 -405.224242) (xy 290.242601 -405.289623) (xy 290.250644 -405.356445) (xy 290.250645 -405.423749)
			(xy 290.242602 -405.490571) (xy 290.22663 -405.555952) (xy 290.202959 -405.618957) (xy 290.200522 -405.623648)
			(xy 291.329076 -405.623648) (xy 291.329076 -405.556343) (xy 291.337121 -405.48952) (xy 291.353095 -405.424137)
			(xy 291.376768 -405.361132) (xy 291.407802 -405.301409) (xy 291.445752 -405.245822) (xy 291.46754 -405.22017)
			(xy 291.473337 -405.213025) (xy 291.47985 -405.195834) (xy 291.48024 -405.186642) (xy 291.48024 -404.693374)
			(xy 291.479833 -404.684187) (xy 291.473316 -404.667003) (xy 291.46754 -404.659846) (xy 291.445774 -404.634176)
			(xy 291.407825 -404.578592) (xy 291.37679 -404.518871) (xy 291.353116 -404.455869) (xy 291.337142 -404.390489)
			(xy 291.329096 -404.323668) (xy 291.329094 -404.256365) (xy 291.337136 -404.189544) (xy 291.353106 -404.124163)
			(xy 291.376777 -404.061159) (xy 291.407808 -404.001436) (xy 291.445754 -403.94585) (xy 291.46754 -403.920198)
			(xy 291.473325 -403.913045) (xy 291.479846 -403.89586) (xy 291.48024 -403.88667) (xy 291.48024 -403.728682)
			(xy 291.480718 -403.718523) (xy 291.488499 -403.699753) (xy 291.50287 -403.685388) (xy 291.521643 -403.677615)
			(xy 291.531802 -403.67712) (xy 292.248082 -403.67712) (xy 292.258236 -403.677648) (xy 292.277002 -403.685413)
			(xy 292.291367 -403.699768) (xy 292.299145 -403.718528) (xy 292.299644 -403.728682) (xy 292.299644 -403.88667)
			(xy 292.300081 -403.895854) (xy 292.306577 -403.913038) (xy 292.312344 -403.920198) (xy 292.334154 -403.945832)
			(xy 292.372103 -404.001421) (xy 292.403137 -404.061147) (xy 292.426809 -404.124153) (xy 292.442781 -404.189538)
			(xy 292.450824 -404.256363) (xy 292.450822 -404.32367) (xy 292.442775 -404.390495) (xy 292.426799 -404.455878)
			(xy 292.403123 -404.518884) (xy 292.372086 -404.578608) (xy 292.334134 -404.634194) (xy 292.312344 -404.659846)
			(xy 292.306539 -404.666985) (xy 292.300031 -404.68418) (xy 292.299644 -404.693374) (xy 292.299644 -405.186642)
			(xy 292.300047 -405.19583) (xy 292.306567 -405.213013) (xy 292.312344 -405.22017) (xy 292.334126 -405.245827)
			(xy 292.372076 -405.301412) (xy 292.403111 -405.361135) (xy 292.426785 -405.424139) (xy 292.442758 -405.489521)
			(xy 292.450803 -405.556343) (xy 292.450804 -405.623648) (xy 292.44276 -405.69047) (xy 292.426787 -405.755852)
			(xy 292.403114 -405.818857) (xy 292.372081 -405.87858) (xy 292.334132 -405.934166) (xy 292.312344 -405.959818)
			(xy 292.30655 -405.966965) (xy 292.300035 -405.984154) (xy 292.299644 -405.993346) (xy 292.299644 -406.151334)
			(xy 292.299194 -406.161496) (xy 292.291405 -406.18027) (xy 292.277026 -406.194634) (xy 292.258245 -406.202404)
			(xy 292.248082 -406.202896) (xy 291.531802 -406.202896) (xy 291.521649 -406.202366) (xy 291.502886 -406.194598)
			(xy 291.488522 -406.180244) (xy 291.480741 -406.161487) (xy 291.48024 -406.151334) (xy 291.48024 -405.993346)
			(xy 291.479799 -405.984162) (xy 291.473306 -405.966978) (xy 291.46754 -405.959818) (xy 291.445746 -405.934171)
			(xy 291.407797 -405.878584) (xy 291.376764 -405.818859) (xy 291.353092 -405.755854) (xy 291.337119 -405.690471)
			(xy 291.329076 -405.623648) (xy 290.200522 -405.623648) (xy 290.171928 -405.67868) (xy 290.133982 -405.734267)
			(xy 290.112196 -405.75992) (xy 290.106408 -405.767071) (xy 290.099888 -405.784257) (xy 290.099496 -405.793448)
			(xy 290.099496 -406.286716) (xy 290.099899 -406.295904) (xy 290.106418 -406.313088) (xy 290.112196 -406.320244)
			(xy 290.133951 -406.345922) (xy 290.171899 -406.401506) (xy 290.202931 -406.461226) (xy 290.226605 -406.524227)
			(xy 290.242579 -406.589606) (xy 290.250625 -406.656425) (xy 290.250628 -406.723727) (xy 290.250621 -406.723789)
			(xy 293.52869 -406.723789) (xy 293.528692 -406.656363) (xy 293.536771 -406.589423) (xy 293.55281 -406.523932)
			(xy 293.576577 -406.460834) (xy 293.607731 -406.401037) (xy 293.645823 -406.345401) (xy 293.667688 -406.319736)
			(xy 293.673493 -406.312597) (xy 293.680003 -406.295402) (xy 293.680388 -406.286208) (xy 293.680388 -405.793956)
			(xy 293.680002 -405.784766) (xy 293.673472 -405.767582) (xy 293.667688 -405.760428) (xy 293.645821 -405.734766)
			(xy 293.607733 -405.679131) (xy 293.576583 -405.619334) (xy 293.552819 -405.556237) (xy 293.536785 -405.490747)
			(xy 293.528709 -405.423809) (xy 293.52871 -405.356385) (xy 293.536786 -405.289447) (xy 293.552821 -405.223958)
			(xy 293.576585 -405.160861) (xy 293.607736 -405.101064) (xy 293.645824 -405.045429) (xy 293.667688 -405.019764)
			(xy 293.673481 -405.012616) (xy 293.679998 -404.995428) (xy 293.680388 -404.986236) (xy 293.680388 -404.828756)
			(xy 293.680849 -404.818646) (xy 293.688599 -404.799969) (xy 293.702903 -404.785676) (xy 293.721586 -404.777941)
			(xy 293.731696 -404.777448) (xy 294.447976 -404.777448) (xy 294.458077 -404.778003) (xy 294.476745 -404.785723)
			(xy 294.491038 -404.799998) (xy 294.498783 -404.818656) (xy 294.499284 -404.828756) (xy 294.499284 -404.986236)
			(xy 294.49968 -404.995425) (xy 294.506204 -405.012609) (xy 294.511984 -405.019764) (xy 294.533845 -405.045432)
			(xy 294.571934 -405.101066) (xy 294.603086 -405.160862) (xy 294.626851 -405.223958) (xy 294.642888 -405.289447)
			(xy 294.650964 -405.356385) (xy 294.650964 -405.423809) (xy 294.642889 -405.490747) (xy 294.626853 -405.556236)
			(xy 294.603089 -405.619333) (xy 294.60081 -405.623708) (xy 295.728844 -405.623708) (xy 295.728845 -405.556283)
			(xy 295.736922 -405.489344) (xy 295.752959 -405.423854) (xy 295.776725 -405.360757) (xy 295.807879 -405.30096)
			(xy 295.84597 -405.245327) (xy 295.867836 -405.219662) (xy 295.873636 -405.212519) (xy 295.880148 -405.195327)
			(xy 295.880536 -405.186134) (xy 295.880536 -404.693882) (xy 295.880126 -404.684695) (xy 295.873611 -404.667511)
			(xy 295.867836 -404.660354) (xy 295.845992 -404.634672) (xy 295.807901 -404.57904) (xy 295.776747 -404.519247)
			(xy 295.75298 -404.456152) (xy 295.736942 -404.390665) (xy 295.728864 -404.323728) (xy 295.728862 -404.256305)
			(xy 295.736936 -404.189368) (xy 295.75297 -404.123879) (xy 295.776733 -404.060783) (xy 295.807884 -404.000988)
			(xy 295.845972 -403.945355) (xy 295.867836 -403.91969) (xy 295.873624 -403.912539) (xy 295.880143 -403.895353)
			(xy 295.880536 -403.886162) (xy 295.880536 -403.728682) (xy 295.881011 -403.718555) (xy 295.888744 -403.699834)
			(xy 295.903034 -403.685478) (xy 295.921719 -403.677659) (xy 295.931844 -403.67712) (xy 296.648124 -403.67712)
			(xy 296.658282 -403.677502) (xy 296.677039 -403.685309) (xy 296.691362 -403.699718) (xy 296.699058 -403.718521)
			(xy 296.699432 -403.728682) (xy 296.699432 -403.886162) (xy 296.699876 -403.895345) (xy 296.706368 -403.912529)
			(xy 296.712132 -403.91969) (xy 296.734016 -403.945338) (xy 296.772102 -404.000976) (xy 296.80325 -404.060775)
			(xy 296.827012 -404.123874) (xy 296.843045 -404.189364) (xy 296.851118 -404.256304) (xy 296.851117 -404.323729)
			(xy 296.843039 -404.390668) (xy 296.827002 -404.456158) (xy 296.803237 -404.519256) (xy 296.772085 -404.579053)
			(xy 296.733996 -404.634688) (xy 296.712132 -404.660354) (xy 296.706322 -404.667489) (xy 296.699817 -404.684688)
			(xy 296.699432 -404.693882) (xy 296.699432 -405.186134) (xy 296.699841 -405.195321) (xy 296.706357 -405.212505)
			(xy 296.712132 -405.219662) (xy 296.733989 -405.245333) (xy 296.772076 -405.300967) (xy 296.803225 -405.360763)
			(xy 296.826988 -405.423859) (xy 296.843023 -405.489347) (xy 296.851099 -405.556284) (xy 296.851099 -405.623707)
			(xy 296.843025 -405.690644) (xy 296.826991 -405.756132) (xy 296.803229 -405.819229) (xy 296.77208 -405.879025)
			(xy 296.733994 -405.93466) (xy 296.712132 -405.960326) (xy 296.706334 -405.96747) (xy 296.699822 -405.984662)
			(xy 296.699432 -405.993854) (xy 296.699432 -406.151334) (xy 296.699001 -406.161466) (xy 296.691256 -406.180194)
			(xy 296.676953 -406.19455) (xy 296.658254 -406.202363) (xy 296.648124 -406.202896) (xy 295.931844 -406.202896)
			(xy 295.921692 -406.202442) (xy 295.90294 -406.19466) (xy 295.888615 -406.180273) (xy 295.880915 -406.161487)
			(xy 295.880536 -406.151334) (xy 295.880536 -405.993854) (xy 295.880092 -405.984671) (xy 295.873601 -405.967486)
			(xy 295.867836 -405.960326) (xy 295.845965 -405.934666) (xy 295.807874 -405.879032) (xy 295.776722 -405.819235)
			(xy 295.752956 -405.756137) (xy 295.73692 -405.690647) (xy 295.728844 -405.623708) (xy 294.60081 -405.623708)
			(xy 294.571938 -405.679129) (xy 294.533848 -405.734763) (xy 294.511984 -405.760428) (xy 294.506191 -405.767576)
			(xy 294.499675 -405.784764) (xy 294.499284 -405.793956) (xy 294.499284 -406.286208) (xy 294.499694 -406.295395)
			(xy 294.506208 -406.312579) (xy 294.511984 -406.319736) (xy 294.533817 -406.345427) (xy 294.571908 -406.401057)
			(xy 294.603061 -406.46085) (xy 294.626827 -406.523943) (xy 294.642866 -406.58943) (xy 294.650944 -406.656365)
			(xy 294.650947 -406.72373) (xy 297.928985 -406.72373) (xy 297.928988 -406.656422) (xy 297.937036 -406.589596)
			(xy 297.953013 -406.524212) (xy 297.976691 -406.461206) (xy 298.00773 -406.401482) (xy 298.045685 -406.345896)
			(xy 298.067476 -406.320244) (xy 298.073276 -406.313101) (xy 298.079789 -406.295909) (xy 298.080176 -406.286716)
			(xy 298.080176 -405.793448) (xy 298.079748 -405.784263) (xy 298.073247 -405.767078) (xy 298.067476 -405.75992)
			(xy 298.045683 -405.734272) (xy 298.007732 -405.678685) (xy 297.976697 -405.618962) (xy 297.953023 -405.555957)
			(xy 297.937049 -405.490574) (xy 297.929005 -405.42375) (xy 297.929005 -405.356444) (xy 297.93705 -405.28962)
			(xy 297.953025 -405.224238) (xy 297.9767 -405.161233) (xy 298.007735 -405.101509) (xy 298.045687 -405.045924)
			(xy 298.067476 -405.020272) (xy 298.073264 -405.013121) (xy 298.079785 -404.995935) (xy 298.080176 -404.986744)
			(xy 298.080176 -404.828756) (xy 298.080585 -404.818602) (xy 298.088391 -404.799853) (xy 298.102791 -404.785532)
			(xy 298.121582 -404.77783) (xy 298.131738 -404.777448) (xy 298.848018 -404.777448) (xy 298.858147 -404.777912)
			(xy 298.87687 -404.785647) (xy 298.891226 -404.79994) (xy 298.899043 -404.818629) (xy 298.89958 -404.828756)
			(xy 298.89958 -404.986744) (xy 298.899973 -404.995933) (xy 298.906499 -405.013117) (xy 298.91228 -405.020272)
			(xy 298.934063 -405.045928) (xy 298.972011 -405.101514) (xy 299.003043 -405.161237) (xy 299.026716 -405.224241)
			(xy 299.042688 -405.289623) (xy 299.050732 -405.356445) (xy 299.050733 -405.423749) (xy 299.042689 -405.490571)
			(xy 299.026717 -405.555953) (xy 299.003046 -405.618957) (xy 299.000577 -405.623708) (xy 300.128635 -405.623708)
			(xy 300.128635 -405.556283) (xy 300.136712 -405.489344) (xy 300.152749 -405.423854) (xy 300.176515 -405.360757)
			(xy 300.207668 -405.300961) (xy 300.245759 -405.245327) (xy 300.267624 -405.219662) (xy 300.273422 -405.212518)
			(xy 300.279935 -405.195326) (xy 300.280324 -405.186134) (xy 300.280324 -404.693882) (xy 300.279917 -404.684695)
			(xy 300.273401 -404.66751) (xy 300.267624 -404.660354) (xy 300.245781 -404.634671) (xy 300.20769 -404.57904)
			(xy 300.176537 -404.519246) (xy 300.15277 -404.456152) (xy 300.136733 -404.390664) (xy 300.128655 -404.323728)
			(xy 300.128653 -404.256305) (xy 300.136727 -404.189368) (xy 300.152761 -404.12388) (xy 300.176523 -404.060784)
			(xy 300.207673 -404.000989) (xy 300.245761 -403.945355) (xy 300.267624 -403.91969) (xy 300.27341 -403.912538)
			(xy 300.27993 -403.895352) (xy 300.280324 -403.886162) (xy 300.280324 -403.728682) (xy 300.280811 -403.718556)
			(xy 300.288542 -403.699837) (xy 300.302828 -403.685482) (xy 300.321509 -403.677661) (xy 300.331632 -403.67712)
			(xy 301.047912 -403.67712) (xy 301.058069 -403.677512) (xy 301.076826 -403.685315) (xy 301.09115 -403.699721)
			(xy 301.098846 -403.718522) (xy 301.09922 -403.728682) (xy 301.09922 -403.886162) (xy 301.099644 -403.895348)
			(xy 301.106147 -403.912533) (xy 301.11192 -403.91969) (xy 301.133805 -403.945338) (xy 301.171892 -404.000975)
			(xy 301.20304 -404.060774) (xy 301.226802 -404.123873) (xy 301.242836 -404.189364) (xy 301.250909 -404.256304)
			(xy 301.250907 -404.323729) (xy 301.24283 -404.390668) (xy 301.226793 -404.456158) (xy 301.203027 -404.519256)
			(xy 301.171875 -404.579053) (xy 301.133785 -404.634688) (xy 301.11192 -404.660354) (xy 301.10612 -404.667497)
			(xy 301.099607 -404.684689) (xy 301.09922 -404.693882) (xy 301.09922 -405.186134) (xy 301.099609 -405.195323)
			(xy 301.106137 -405.212508) (xy 301.11192 -405.219662) (xy 301.133777 -405.245332) (xy 301.171865 -405.300967)
			(xy 301.203015 -405.360762) (xy 301.226778 -405.423859) (xy 301.242814 -405.489347) (xy 301.25089 -405.556284)
			(xy 301.25089 -405.623707) (xy 301.242815 -405.690644) (xy 301.226781 -405.756133) (xy 301.203018 -405.819229)
			(xy 301.17187 -405.879026) (xy 301.133783 -405.93466) (xy 301.11192 -405.960326) (xy 301.106132 -405.967478)
			(xy 301.099612 -405.984663) (xy 301.09922 -405.993854) (xy 301.09922 -406.151334) (xy 301.0988 -406.161468)
			(xy 301.091054 -406.180197) (xy 301.076747 -406.194554) (xy 301.058044 -406.202365) (xy 301.047912 -406.202896)
			(xy 300.331632 -406.202896) (xy 300.321479 -406.202452) (xy 300.302727 -406.194667) (xy 300.288402 -406.180276)
			(xy 300.280702 -406.161488) (xy 300.280324 -406.151334) (xy 300.280324 -405.993854) (xy 300.279882 -405.98467)
			(xy 300.27339 -405.967486) (xy 300.267624 -405.960326) (xy 300.245753 -405.934666) (xy 300.207663 -405.879031)
			(xy 300.176511 -405.819235) (xy 300.152747 -405.756137) (xy 300.136711 -405.690647) (xy 300.128635 -405.623708)
			(xy 299.000577 -405.623708) (xy 298.972014 -405.678681) (xy 298.934067 -405.734268) (xy 298.91228 -405.75992)
			(xy 298.90649 -405.76707) (xy 298.899972 -405.784257) (xy 298.89958 -405.793448) (xy 298.89958 -406.286716)
			(xy 298.899987 -406.295903) (xy 298.906503 -406.313088) (xy 298.91228 -406.320244) (xy 298.934035 -406.345922)
			(xy 298.971984 -406.401506) (xy 299.003018 -406.461226) (xy 299.026691 -406.524227) (xy 299.042666 -406.589606)
			(xy 299.050712 -406.656425) (xy 299.050715 -406.723727) (xy 299.050708 -406.723789) (xy 302.328777 -406.723789)
			(xy 302.32878 -406.656363) (xy 302.336859 -406.589423) (xy 302.352897 -406.523933) (xy 302.376664 -406.460835)
			(xy 302.407816 -406.401037) (xy 302.445907 -406.345402) (xy 302.467772 -406.319736) (xy 302.473587 -406.312604)
			(xy 302.480089 -406.295403) (xy 302.480472 -406.286208) (xy 302.480472 -405.793956) (xy 302.480089 -405.784766)
			(xy 302.473557 -405.767581) (xy 302.467772 -405.760428) (xy 302.445905 -405.734766) (xy 302.407818 -405.67913)
			(xy 302.376669 -405.619333) (xy 302.352907 -405.556236) (xy 302.336872 -405.490747) (xy 302.328797 -405.423809)
			(xy 302.328798 -405.356385) (xy 302.336873 -405.289447) (xy 302.352908 -405.223958) (xy 302.376672 -405.160861)
			(xy 302.407821 -405.101065) (xy 302.445909 -405.04543) (xy 302.467772 -405.019764) (xy 302.473575 -405.012624)
			(xy 302.480084 -404.995429) (xy 302.480472 -404.986236) (xy 302.480472 -404.828756) (xy 302.480948 -404.818648)
			(xy 302.488695 -404.799974) (xy 302.502994 -404.785682) (xy 302.521672 -404.777944) (xy 302.53178 -404.777448)
			(xy 303.24806 -404.777448) (xy 303.25816 -404.778017) (xy 303.276827 -404.785732) (xy 303.291121 -404.800002)
			(xy 303.298867 -404.818657) (xy 303.299368 -404.828756) (xy 303.299368 -404.986236) (xy 303.299768 -404.995424)
			(xy 303.30629 -405.012608) (xy 303.312068 -405.019764) (xy 303.333929 -405.045432) (xy 303.37202 -405.101065)
			(xy 303.403173 -405.160861) (xy 303.426939 -405.223957) (xy 303.442975 -405.289447) (xy 303.451052 -405.356385)
			(xy 303.451052 -405.423809) (xy 303.442976 -405.490748) (xy 303.42694 -405.556237) (xy 303.403175 -405.619334)
			(xy 303.372023 -405.67913) (xy 303.333933 -405.734763) (xy 303.312068 -405.760428) (xy 303.306273 -405.767574)
			(xy 303.299758 -405.784764) (xy 303.299368 -405.793956) (xy 303.299368 -406.286208) (xy 303.299781 -406.295395)
			(xy 303.306294 -406.312579) (xy 303.312068 -406.319736) (xy 303.333902 -406.345427) (xy 303.371993 -406.401057)
			(xy 303.403147 -406.460849) (xy 303.426915 -406.523943) (xy 303.442953 -406.589429) (xy 303.451032 -406.656365)
			(xy 303.451035 -406.723787) (xy 303.442962 -406.790724) (xy 303.426929 -406.856211) (xy 303.403167 -406.919307)
			(xy 303.372018 -406.979102) (xy 303.333931 -407.034735) (xy 303.312068 -407.0604) (xy 303.306285 -407.067555)
			(xy 303.299763 -407.084738) (xy 303.299368 -407.093928) (xy 303.299368 -407.251408) (xy 303.29899 -407.261535)
			(xy 303.291233 -407.280245) (xy 303.276904 -407.29456) (xy 303.258187 -407.302299) (xy 303.24806 -407.302716)
			(xy 302.53178 -407.302716) (xy 302.521672 -407.302232) (xy 302.502996 -407.294491) (xy 302.488703 -407.280194)
			(xy 302.480966 -407.261516) (xy 302.480472 -407.251408) (xy 302.480472 -407.093928) (xy 302.480055 -407.084741)
			(xy 302.473547 -407.067557) (xy 302.467772 -407.0604) (xy 302.445878 -407.03476) (xy 302.407792 -406.979121)
			(xy 302.376644 -406.919321) (xy 302.352883 -406.856221) (xy 302.33685 -406.790729) (xy 302.328777 -406.723789)
			(xy 299.050708 -406.723789) (xy 299.042674 -406.790547) (xy 299.026705 -406.855927) (xy 299.003037 -406.91893)
			(xy 298.972009 -406.978653) (xy 298.934065 -407.034239) (xy 298.91228 -407.059892) (xy 298.906502 -407.06705)
			(xy 298.899977 -407.084231) (xy 298.89958 -407.09342) (xy 298.89958 -407.251408) (xy 298.899184 -407.261565)
			(xy 298.891382 -407.280321) (xy 298.876978 -407.294645) (xy 298.858177 -407.302341) (xy 298.848018 -407.302716)
			(xy 298.131738 -407.302716) (xy 298.121608 -407.302241) (xy 298.10288 -407.294517) (xy 298.088521 -407.280227)
			(xy 298.080708 -407.261535) (xy 298.080176 -407.251408) (xy 298.080176 -407.09342) (xy 298.079762 -407.084233)
			(xy 298.073252 -407.067048) (xy 298.067476 -407.059892) (xy 298.045656 -407.034266) (xy 298.007706 -406.978677)
			(xy 297.976672 -406.91895) (xy 297.952999 -406.855942) (xy 297.937027 -406.790556) (xy 297.928985 -406.72373)
			(xy 294.650947 -406.72373) (xy 294.650947 -406.723787) (xy 294.642874 -406.790723) (xy 294.626842 -406.856211)
			(xy 294.60308 -406.919306) (xy 294.571933 -406.979101) (xy 294.533847 -407.034735) (xy 294.511984 -407.0604)
			(xy 294.506203 -407.067556) (xy 294.49968 -407.084738) (xy 294.499284 -407.093928) (xy 294.499284 -407.251408)
			(xy 294.49889 -407.261533) (xy 294.491136 -407.28024) (xy 294.476813 -407.294554) (xy 294.458101 -407.302296)
			(xy 294.447976 -407.302716) (xy 293.731696 -407.302716) (xy 293.721589 -407.302218) (xy 293.702914 -407.294482)
			(xy 293.68862 -407.28019) (xy 293.680882 -407.261515) (xy 293.680388 -407.251408) (xy 293.680388 -407.093928)
			(xy 293.679967 -407.084742) (xy 293.673461 -407.067557) (xy 293.667688 -407.0604) (xy 293.645793 -407.03476)
			(xy 293.607706 -406.979122) (xy 293.576557 -406.919322) (xy 293.552796 -406.856222) (xy 293.536763 -406.79073)
			(xy 293.52869 -406.723789) (xy 290.250621 -406.723789) (xy 290.242587 -406.790547) (xy 290.226619 -406.855927)
			(xy 290.202951 -406.91893) (xy 290.171924 -406.978653) (xy 290.133981 -407.034239) (xy 290.112196 -407.059892)
			(xy 290.10642 -407.067052) (xy 290.099893 -407.084231) (xy 290.099496 -407.09342) (xy 290.099496 -407.251408)
			(xy 290.099085 -407.261563) (xy 290.091286 -407.280316) (xy 290.076886 -407.29464) (xy 290.058091 -407.302338)
			(xy 290.047934 -407.302716) (xy 289.331654 -407.302716) (xy 289.321519 -407.30231) (xy 289.302788 -407.294559)
			(xy 289.288432 -407.280248) (xy 289.280622 -407.261541) (xy 289.280092 -407.251408) (xy 289.280092 -407.09342)
			(xy 289.279674 -407.084234) (xy 289.273166 -407.067049) (xy 289.267392 -407.059892) (xy 289.245571 -407.034266)
			(xy 289.20762 -406.978677) (xy 289.176585 -406.918951) (xy 289.152912 -406.855943) (xy 289.136939 -406.790557)
			(xy 289.128897 -406.72373) (xy 237.406942 -406.72373) (xy 237.406942 -409.523887) (xy 286.928735 -409.523887)
			(xy 286.928738 -409.456459) (xy 286.936818 -409.389518) (xy 286.952859 -409.324026) (xy 286.97663 -409.260927)
			(xy 287.007788 -409.20113) (xy 287.045884 -409.145496) (xy 287.067752 -409.119832) (xy 287.073566 -409.1127)
			(xy 287.080069 -409.095499) (xy 287.080452 -409.086304) (xy 287.080452 -408.594052) (xy 287.080005 -408.584869)
			(xy 287.073516 -408.567685) (xy 287.067752 -408.560524) (xy 287.045878 -408.534866) (xy 287.007786 -408.479232)
			(xy 286.976633 -408.419435) (xy 286.952867 -408.356337) (xy 286.936831 -408.290847) (xy 286.928755 -408.223907)
			(xy 286.928755 -408.156481) (xy 286.936833 -408.089542) (xy 286.952871 -408.024051) (xy 286.976638 -407.960954)
			(xy 287.007793 -407.901158) (xy 287.045886 -407.845524) (xy 287.067752 -407.81986) (xy 287.073554 -407.812719)
			(xy 287.080064 -407.795525) (xy 287.080452 -407.786332) (xy 287.080452 -407.628852) (xy 287.080945 -407.618746)
			(xy 287.088689 -407.600076) (xy 287.102983 -407.585785) (xy 287.121654 -407.578043) (xy 287.13176 -407.577544)
			(xy 287.84804 -407.577544) (xy 287.858144 -407.578051) (xy 287.876813 -407.585791) (xy 287.891104 -407.600081)
			(xy 287.898847 -407.618748) (xy 287.899348 -407.628852) (xy 287.899348 -407.786332) (xy 287.899755 -407.795519)
			(xy 287.906272 -407.812703) (xy 287.912048 -407.81986) (xy 287.933906 -407.845531) (xy 287.971998 -407.901163)
			(xy 288.003152 -407.960958) (xy 288.026919 -408.024055) (xy 288.042957 -408.089543) (xy 288.051034 -408.156482)
			(xy 288.051035 -408.223906) (xy 288.042959 -408.290845) (xy 288.026923 -408.356334) (xy 288.003157 -408.419431)
			(xy 287.972004 -408.479226) (xy 287.933913 -408.53486) (xy 287.912048 -408.560524) (xy 287.906252 -408.56767)
			(xy 287.899739 -408.58486) (xy 287.899348 -408.594052) (xy 287.899348 -409.086304) (xy 287.899768 -409.09549)
			(xy 287.906276 -409.112674) (xy 287.912048 -409.119832) (xy 287.933878 -409.145526) (xy 287.971972 -409.201155)
			(xy 288.003127 -409.260947) (xy 288.026895 -409.32404) (xy 288.042935 -409.389526) (xy 288.051014 -409.456462)
			(xy 288.051018 -409.523884) (xy 288.042945 -409.590821) (xy 288.026911 -409.656308) (xy 288.003149 -409.719404)
			(xy 287.971999 -409.779199) (xy 287.933912 -409.834832) (xy 287.912048 -409.860496) (xy 287.906264 -409.86765)
			(xy 287.899743 -409.884834) (xy 287.899348 -409.894024) (xy 287.899348 -410.051504) (xy 287.898819 -410.061607)
			(xy 287.891089 -410.080276) (xy 287.876806 -410.094569) (xy 287.858143 -410.102312) (xy 287.84804 -410.102812)
			(xy 287.13176 -410.102812) (xy 287.12165 -410.102348) (xy 287.102973 -410.094599) (xy 287.08868 -410.080296)
			(xy 287.080945 -410.061614) (xy 287.080452 -410.051504) (xy 287.080452 -409.894024) (xy 287.080019 -409.884839)
			(xy 287.07352 -409.867655) (xy 287.067752 -409.860496) (xy 287.045851 -409.834861) (xy 287.00776 -409.779223)
			(xy 286.976608 -409.719423) (xy 286.952843 -409.656322) (xy 286.936809 -409.590829) (xy 286.928735 -409.523887)
			(xy 237.406942 -409.523887) (xy 237.406942 -410.623642) (xy 289.128908 -410.623642) (xy 289.12891 -410.556334)
			(xy 289.136956 -410.48951) (xy 289.152933 -410.424126) (xy 289.176609 -410.361121) (xy 289.207648 -410.301397)
			(xy 289.245602 -410.245811) (xy 289.267392 -410.22016) (xy 289.273187 -410.213014) (xy 289.279703 -410.195824)
			(xy 289.280092 -410.186632) (xy 289.280092 -409.693364) (xy 289.279701 -409.684175) (xy 289.273174 -409.66699)
			(xy 289.267392 -409.659836) (xy 289.245614 -409.634175) (xy 289.207662 -409.578591) (xy 289.176625 -409.518869)
			(xy 289.152949 -409.455866) (xy 289.136974 -409.390484) (xy 289.128928 -409.323662) (xy 289.128927 -409.256356)
			(xy 289.136971 -409.189534) (xy 289.152944 -409.124152) (xy 289.176618 -409.061147) (xy 289.207653 -409.001425)
			(xy 289.245603 -408.945839) (xy 289.267392 -408.920188) (xy 289.273175 -408.913033) (xy 289.279698 -408.89585)
			(xy 289.280092 -408.88666) (xy 289.280092 -408.728672) (xy 289.280498 -408.718517) (xy 289.288302 -408.699766)
			(xy 289.302703 -408.685443) (xy 289.321497 -408.677743) (xy 289.331654 -408.677364) (xy 290.047934 -408.677364)
			(xy 290.058066 -408.677799) (xy 290.076792 -408.685543) (xy 290.091148 -408.699845) (xy 290.098962 -408.718542)
			(xy 290.099496 -408.728672) (xy 290.099496 -408.88666) (xy 290.099926 -408.895845) (xy 290.106426 -408.91303)
			(xy 290.112196 -408.920188) (xy 290.133994 -408.945831) (xy 290.171941 -409.00142) (xy 290.202971 -409.061145)
			(xy 290.226642 -409.12415) (xy 290.242613 -409.189533) (xy 290.250656 -409.256356) (xy 290.250655 -409.323662)
			(xy 290.24261 -409.390484) (xy 290.226637 -409.455867) (xy 290.202964 -409.518872) (xy 290.200389 -409.523827)
			(xy 291.329055 -409.523827) (xy 291.329058 -409.456519) (xy 291.337106 -409.389694) (xy 291.353082 -409.32431)
			(xy 291.376759 -409.261304) (xy 291.407797 -409.201579) (xy 291.44575 -409.145992) (xy 291.46754 -409.12034)
			(xy 291.47335 -409.113204) (xy 291.479855 -409.096006) (xy 291.48024 -409.086812) (xy 291.48024 -408.593544)
			(xy 291.4798 -408.58436) (xy 291.473306 -408.567176) (xy 291.46754 -408.560016) (xy 291.445744 -408.53437)
			(xy 291.407796 -408.478783) (xy 291.376763 -408.419059) (xy 291.35309 -408.356053) (xy 291.337118 -408.29067)
			(xy 291.329074 -408.223847) (xy 291.329075 -408.156541) (xy 291.33712 -408.089718) (xy 291.353094 -408.024335)
			(xy 291.376767 -407.96133) (xy 291.407802 -407.901607) (xy 291.445752 -407.84602) (xy 291.46754 -407.820368)
			(xy 291.473338 -407.813224) (xy 291.479851 -407.796032) (xy 291.48024 -407.78684) (xy 291.48024 -407.628852)
			(xy 291.480583 -407.61869) (xy 291.488402 -407.599929) (xy 291.502823 -407.585606) (xy 291.521637 -407.577915)
			(xy 291.531802 -407.577544) (xy 292.248082 -407.577544) (xy 292.258208 -407.578041) (xy 292.27693 -407.585764)
			(xy 292.291287 -407.600047) (xy 292.299106 -407.618729) (xy 292.299644 -407.628852) (xy 292.299644 -407.78684)
			(xy 292.300048 -407.796028) (xy 292.306567 -407.813211) (xy 292.312344 -407.820368) (xy 292.334124 -407.846026)
			(xy 292.372074 -407.901612) (xy 292.403109 -407.961334) (xy 292.426783 -408.024338) (xy 292.442757 -408.089719)
			(xy 292.450802 -408.156542) (xy 292.450803 -408.223846) (xy 292.442759 -408.290669) (xy 292.426786 -408.356051)
			(xy 292.403114 -408.419055) (xy 292.372081 -408.478778) (xy 292.334132 -408.534364) (xy 292.312344 -408.560016)
			(xy 292.306551 -408.567164) (xy 292.300036 -408.584353) (xy 292.299644 -408.593544) (xy 292.299644 -409.086812)
			(xy 292.300061 -409.095998) (xy 292.306571 -409.113182) (xy 292.312344 -409.12034) (xy 292.334097 -409.146021)
			(xy 292.372048 -409.201603) (xy 292.403083 -409.261322) (xy 292.426759 -409.324323) (xy 292.442735 -409.389702)
			(xy 292.450782 -409.456522) (xy 292.450786 -409.523824) (xy 292.442745 -409.590645) (xy 292.426775 -409.656025)
			(xy 292.403106 -409.719028) (xy 292.372076 -409.77875) (xy 292.33413 -409.834336) (xy 292.312344 -409.859988)
			(xy 292.306521 -409.867114) (xy 292.300024 -409.884319) (xy 292.299644 -409.893516) (xy 292.299644 -410.051504)
			(xy 292.299182 -410.061653) (xy 292.291394 -410.080397) (xy 292.27701 -410.094718) (xy 292.258233 -410.102426)
			(xy 292.248082 -410.102812) (xy 291.531802 -410.102812) (xy 291.521682 -410.102273) (xy 291.502971 -410.094556)
			(xy 291.488616 -410.080286) (xy 291.480788 -410.061621) (xy 291.48024 -410.051504) (xy 291.48024 -409.893516)
			(xy 291.479813 -409.884331) (xy 291.47331 -409.867147) (xy 291.46754 -409.859988) (xy 291.445717 -409.834365)
			(xy 291.407769 -409.778774) (xy 291.376737 -409.719047) (xy 291.353066 -409.656039) (xy 291.337096 -409.590653)
			(xy 291.329055 -409.523827) (xy 290.200389 -409.523827) (xy 290.171931 -409.578596) (xy 290.133983 -409.634183)
			(xy 290.112196 -409.659836) (xy 290.106401 -409.666982) (xy 290.099886 -409.684172) (xy 290.099496 -409.693364)
			(xy 290.099496 -410.186632) (xy 290.099891 -410.195821) (xy 290.106415 -410.213005) (xy 290.112196 -410.22016)
			(xy 290.133967 -410.245826) (xy 290.171914 -410.301411) (xy 290.202946 -410.361133) (xy 290.226618 -410.424136)
			(xy 290.242591 -410.489516) (xy 290.250636 -410.556336) (xy 290.250638 -410.62364) (xy 290.250631 -410.6237)
			(xy 293.528701 -410.6237) (xy 293.528702 -410.556276) (xy 293.53678 -410.489336) (xy 293.552816 -410.423847)
			(xy 293.576582 -410.360749) (xy 293.607734 -410.300952) (xy 293.645824 -410.245317) (xy 293.667688 -410.219652)
			(xy 293.673486 -410.212508) (xy 293.68 -410.195317) (xy 293.680388 -410.186124) (xy 293.680388 -409.693872)
			(xy 293.679994 -409.684683) (xy 293.673469 -409.667499) (xy 293.667688 -409.660344) (xy 293.645836 -409.634669)
			(xy 293.607748 -409.579035) (xy 293.576597 -409.519241) (xy 293.552833 -409.456145) (xy 293.536797 -409.390657)
			(xy 293.52872 -409.32372) (xy 293.528719 -409.256298) (xy 293.536794 -409.189361) (xy 293.552828 -409.123872)
			(xy 293.57659 -409.060776) (xy 293.607739 -409.00098) (xy 293.645825 -408.945345) (xy 293.667688 -408.91968)
			(xy 293.673474 -408.912527) (xy 293.679995 -408.895343) (xy 293.680388 -408.886152) (xy 293.680388 -408.728672)
			(xy 293.680862 -408.718563) (xy 293.688606 -408.699886) (xy 293.702907 -408.685593) (xy 293.721587 -408.677857)
			(xy 293.731696 -408.677364) (xy 294.447976 -408.677364) (xy 294.458079 -408.677904) (xy 294.47675 -408.685627)
			(xy 294.491044 -408.699907) (xy 294.498786 -408.71857) (xy 294.499284 -408.728672) (xy 294.499284 -408.886152)
			(xy 294.499721 -408.895336) (xy 294.506216 -408.912521) (xy 294.511984 -408.91968) (xy 294.53386 -408.945335)
			(xy 294.57195 -409.000971) (xy 294.603101 -409.060768) (xy 294.626865 -409.123866) (xy 294.6429 -409.189357)
			(xy 294.650975 -409.256297) (xy 294.650974 -409.323721) (xy 294.642897 -409.390661) (xy 294.62686 -409.456151)
			(xy 294.603093 -409.519248) (xy 294.600676 -409.523887) (xy 295.728823 -409.523887) (xy 295.728826 -409.456459)
			(xy 295.736906 -409.389518) (xy 295.752947 -409.324026) (xy 295.776716 -409.260928) (xy 295.807873 -409.201131)
			(xy 295.845969 -409.145497) (xy 295.867836 -409.119832) (xy 295.873649 -409.112698) (xy 295.880153 -409.095499)
			(xy 295.880536 -409.086304) (xy 295.880536 -408.594052) (xy 295.880093 -408.584869) (xy 295.873601 -408.567684)
			(xy 295.867836 -408.560524) (xy 295.845963 -408.534866) (xy 295.807872 -408.479231) (xy 295.77672 -408.419434)
			(xy 295.752954 -408.356336) (xy 295.736918 -408.290846) (xy 295.728843 -408.223907) (xy 295.728843 -408.156481)
			(xy 295.736921 -408.089542) (xy 295.752958 -408.024052) (xy 295.776725 -407.960955) (xy 295.807878 -407.901159)
			(xy 295.84597 -407.845525) (xy 295.867836 -407.81986) (xy 295.873637 -407.812718) (xy 295.880148 -407.795525)
			(xy 295.880536 -407.786332) (xy 295.880536 -407.628852) (xy 295.880947 -407.618736) (xy 295.888707 -407.60005)
			(xy 295.903027 -407.585755) (xy 295.921727 -407.578029) (xy 295.931844 -407.577544) (xy 296.648124 -407.577544)
			(xy 296.658227 -407.578064) (xy 296.676895 -407.585799) (xy 296.691187 -407.600084) (xy 296.698931 -407.618749)
			(xy 296.699432 -407.628852) (xy 296.699432 -407.786332) (xy 296.699842 -407.795519) (xy 296.706357 -407.812703)
			(xy 296.712132 -407.81986) (xy 296.733987 -407.845532) (xy 296.772074 -407.901167) (xy 296.803223 -407.960962)
			(xy 296.826986 -408.024058) (xy 296.843021 -408.089546) (xy 296.851097 -408.156483) (xy 296.851098 -408.223905)
			(xy 296.843024 -408.290842) (xy 296.82699 -408.356331) (xy 296.803228 -408.419427) (xy 296.77208 -408.479223)
			(xy 296.733994 -408.534858) (xy 296.712132 -408.560524) (xy 296.706334 -408.567668) (xy 296.699822 -408.58486)
			(xy 296.699432 -408.594052) (xy 296.699432 -409.086304) (xy 296.699856 -409.095489) (xy 296.706362 -409.112673)
			(xy 296.712132 -409.119832) (xy 296.733959 -409.145527) (xy 296.772047 -409.201158) (xy 296.803198 -409.26095)
			(xy 296.826962 -409.324043) (xy 296.842999 -409.389528) (xy 296.851078 -409.456463) (xy 296.851081 -409.523883)
			(xy 296.843009 -409.590818) (xy 296.826978 -409.656305) (xy 296.80322 -409.7194) (xy 296.772075 -409.779196)
			(xy 296.733993 -409.83483) (xy 296.712132 -409.860496) (xy 296.706346 -409.867649) (xy 296.699827 -409.884834)
			(xy 296.699432 -409.894024) (xy 296.699432 -410.051504) (xy 296.698919 -410.061609) (xy 296.691186 -410.080281)
			(xy 296.676898 -410.094575) (xy 296.658229 -410.102315) (xy 296.648124 -410.102812) (xy 295.931844 -410.102812)
			(xy 295.921726 -410.102348) (xy 295.903026 -410.094617) (xy 295.88871 -410.080315) (xy 295.880961 -410.061622)
			(xy 295.880536 -410.051504) (xy 295.880536 -409.894024) (xy 295.880106 -409.884839) (xy 295.873605 -409.867655)
			(xy 295.867836 -409.860496) (xy 295.845935 -409.834861) (xy 295.807845 -409.779223) (xy 295.776694 -409.719423)
			(xy 295.752931 -409.656322) (xy 295.736896 -409.590829) (xy 295.728823 -409.523887) (xy 294.600676 -409.523887)
			(xy 294.57194 -409.579045) (xy 294.533849 -409.634679) (xy 294.511984 -409.660344) (xy 294.506184 -409.667487)
			(xy 294.499672 -409.684679) (xy 294.499284 -409.693872) (xy 294.499284 -410.186124) (xy 294.499686 -410.195312)
			(xy 294.506206 -410.212496) (xy 294.511984 -410.219652) (xy 294.533833 -410.24533) (xy 294.571923 -410.300962)
			(xy 294.603075 -410.360757) (xy 294.626841 -410.423852) (xy 294.642878 -410.489339) (xy 294.650956 -410.556277)
			(xy 294.650957 -410.623641) (xy 297.928996 -410.623641) (xy 297.928998 -410.556334) (xy 297.937044 -410.48951)
			(xy 297.95302 -410.424127) (xy 297.976696 -410.361121) (xy 298.007733 -410.301398) (xy 298.045686 -410.245812)
			(xy 298.067476 -410.22016) (xy 298.073269 -410.213012) (xy 298.079787 -410.195824) (xy 298.080176 -410.186632)
			(xy 298.080176 -409.693364) (xy 298.079788 -409.684174) (xy 298.07326 -409.66699) (xy 298.067476 -409.659836)
			(xy 298.045699 -409.634175) (xy 298.007747 -409.57859) (xy 297.976712 -409.518868) (xy 297.953037 -409.455865)
			(xy 297.937062 -409.390484) (xy 297.929016 -409.323661) (xy 297.929015 -409.256357) (xy 297.937058 -409.189534)
			(xy 297.953031 -409.124152) (xy 297.976704 -409.061148) (xy 298.007738 -409.001425) (xy 298.045688 -408.94584)
			(xy 298.067476 -408.920188) (xy 298.073257 -408.913032) (xy 298.079782 -408.89585) (xy 298.080176 -408.88666)
			(xy 298.080176 -408.728672) (xy 298.080598 -408.718519) (xy 298.088398 -408.699771) (xy 298.102794 -408.685449)
			(xy 298.121583 -408.677746) (xy 298.131738 -408.677364) (xy 298.848018 -408.677364) (xy 298.858149 -408.677812)
			(xy 298.876875 -408.68555) (xy 298.891232 -408.699849) (xy 298.899046 -408.718543) (xy 298.89958 -408.728672)
			(xy 298.89958 -408.88666) (xy 298.900014 -408.895845) (xy 298.906512 -408.913029) (xy 298.91228 -408.920188)
			(xy 298.934079 -408.945831) (xy 298.972026 -409.001419) (xy 299.003058 -409.061144) (xy 299.026729 -409.12415)
			(xy 299.042701 -409.189533) (xy 299.050744 -409.256356) (xy 299.050743 -409.323662) (xy 299.042698 -409.390485)
			(xy 299.026724 -409.455868) (xy 299.003051 -409.518873) (xy 299.000446 -409.523886) (xy 300.128614 -409.523886)
			(xy 300.128617 -409.456459) (xy 300.136697 -409.389518) (xy 300.152737 -409.324027) (xy 300.176506 -409.260928)
			(xy 300.207662 -409.201131) (xy 300.245757 -409.145497) (xy 300.267624 -409.119832) (xy 300.273435 -409.112697)
			(xy 300.27994 -409.095499) (xy 300.280324 -409.086304) (xy 300.280324 -408.594052) (xy 300.279883 -408.584868)
			(xy 300.27339 -408.567684) (xy 300.267624 -408.560524) (xy 300.245751 -408.534866) (xy 300.207661 -408.479231)
			(xy 300.17651 -408.419434) (xy 300.152745 -408.356336) (xy 300.136709 -408.290846) (xy 300.128634 -408.223906)
			(xy 300.128634 -408.156482) (xy 300.136711 -408.089542) (xy 300.152748 -408.024053) (xy 300.176514 -407.960955)
			(xy 300.207667 -407.901159) (xy 300.245759 -407.845525) (xy 300.267624 -407.81986) (xy 300.273423 -407.812717)
			(xy 300.279935 -407.795525) (xy 300.280324 -407.786332) (xy 300.280324 -407.628852) (xy 300.280747 -407.618737)
			(xy 300.288504 -407.600053) (xy 300.302821 -407.585759) (xy 300.321516 -407.578031) (xy 300.331632 -407.577544)
			(xy 301.047912 -407.577544) (xy 301.058015 -407.578074) (xy 301.076682 -407.585805) (xy 301.090975 -407.600088)
			(xy 301.098719 -407.61875) (xy 301.09922 -407.628852) (xy 301.09922 -407.786332) (xy 301.09961 -407.795521)
			(xy 301.106137 -407.812706) (xy 301.11192 -407.81986) (xy 301.133775 -407.845532) (xy 301.171863 -407.901166)
			(xy 301.203013 -407.960962) (xy 301.226777 -408.024057) (xy 301.242812 -408.089545) (xy 301.250888 -408.156483)
			(xy 301.250889 -408.223905) (xy 301.242814 -408.290843) (xy 301.22678 -408.356331) (xy 301.203018 -408.419427)
			(xy 301.171869 -408.479224) (xy 301.133783 -408.534858) (xy 301.11192 -408.560524) (xy 301.106133 -408.567676)
			(xy 301.099612 -408.584861) (xy 301.09922 -408.594052) (xy 301.09922 -409.086304) (xy 301.099624 -409.095492)
			(xy 301.106141 -409.112676) (xy 301.11192 -409.119832) (xy 301.133748 -409.145527) (xy 301.171836 -409.201158)
			(xy 301.202988 -409.26095) (xy 301.226753 -409.324043) (xy 301.24279 -409.389528) (xy 301.250869 -409.456463)
			(xy 301.250872 -409.523883) (xy 301.2428 -409.590819) (xy 301.226769 -409.656305) (xy 301.20301 -409.719401)
			(xy 301.171864 -409.779196) (xy 301.133781 -409.83483) (xy 301.11192 -409.860496) (xy 301.106145 -409.867657)
			(xy 301.099617 -409.884835) (xy 301.09922 -409.894024) (xy 301.09922 -410.051504) (xy 301.098719 -410.06161)
			(xy 301.090983 -410.080285) (xy 301.076692 -410.094579) (xy 301.058018 -410.102317) (xy 301.047912 -410.102812)
			(xy 300.331632 -410.102812) (xy 300.321513 -410.102358) (xy 300.302812 -410.094623) (xy 300.288497 -410.080318)
			(xy 300.280749 -410.061623) (xy 300.280324 -410.051504) (xy 300.280324 -409.894024) (xy 300.279897 -409.884839)
			(xy 300.273394 -409.867655) (xy 300.267624 -409.860496) (xy 300.245724 -409.83486) (xy 300.207635 -409.779222)
			(xy 300.176484 -409.719422) (xy 300.152721 -409.656321) (xy 300.136687 -409.590828) (xy 300.128614 -409.523886)
			(xy 299.000446 -409.523886) (xy 298.972017 -409.578597) (xy 298.934068 -409.634184) (xy 298.91228 -409.659836)
			(xy 298.906483 -409.666981) (xy 298.899969 -409.684172) (xy 298.89958 -409.693364) (xy 298.89958 -410.186632)
			(xy 298.899979 -410.19582) (xy 298.906501 -410.213004) (xy 298.91228 -410.22016) (xy 298.934052 -410.245825)
			(xy 298.972 -410.30141) (xy 299.003032 -410.361132) (xy 299.026705 -410.424135) (xy 299.042679 -410.489515)
			(xy 299.050724 -410.556336) (xy 299.050725 -410.62364) (xy 299.050718 -410.6237) (xy 302.328789 -410.6237)
			(xy 302.32879 -410.556276) (xy 302.336867 -410.489337) (xy 302.352904 -410.423847) (xy 302.376668 -410.36075)
			(xy 302.407819 -410.300953) (xy 302.445908 -410.245318) (xy 302.467772 -410.219652) (xy 302.47358 -410.212515)
			(xy 302.480086 -410.195318) (xy 302.480472 -410.186124) (xy 302.480472 -409.693872) (xy 302.480082 -409.684683)
			(xy 302.473555 -409.667498) (xy 302.467772 -409.660344) (xy 302.445921 -409.634669) (xy 302.407834 -409.579035)
			(xy 302.376684 -409.51924) (xy 302.35292 -409.456144) (xy 302.336885 -409.390657) (xy 302.328808 -409.32372)
			(xy 302.328807 -409.256298) (xy 302.336882 -409.189361) (xy 302.352915 -409.123873) (xy 302.376677 -409.060777)
			(xy 302.407824 -409.000981) (xy 302.44591 -408.945346) (xy 302.467772 -408.91968) (xy 302.473568 -408.912535)
			(xy 302.480081 -408.895344) (xy 302.480472 -408.886152) (xy 302.480472 -408.728672) (xy 302.480961 -408.718565)
			(xy 302.488703 -408.699891) (xy 302.502998 -408.685599) (xy 302.521673 -408.67786) (xy 302.53178 -408.677364)
			(xy 303.24806 -408.677364) (xy 303.258175 -408.677848) (xy 303.276871 -408.685576) (xy 303.291186 -408.699872)
			(xy 303.298939 -408.718557) (xy 303.299368 -408.728672) (xy 303.299368 -408.886152) (xy 303.299809 -408.895336)
			(xy 303.306302 -408.91252) (xy 303.312068 -408.91968) (xy 303.333945 -408.945335) (xy 303.372035 -409.00097)
			(xy 303.403187 -409.060768) (xy 303.426952 -409.123866) (xy 303.442988 -409.189356) (xy 303.451063 -409.256296)
			(xy 303.451062 -409.323722) (xy 303.442985 -409.390661) (xy 303.426947 -409.456151) (xy 303.40318 -409.519249)
			(xy 303.372026 -409.579045) (xy 303.333934 -409.634679) (xy 303.312068 -409.660344) (xy 303.306266 -409.667485)
			(xy 303.299755 -409.684679) (xy 303.299368 -409.693872) (xy 303.299368 -410.186124) (xy 303.299774 -410.195312)
			(xy 303.306291 -410.212495) (xy 303.312068 -410.219652) (xy 303.333917 -410.24533) (xy 303.372009 -410.300962)
			(xy 303.403162 -410.360756) (xy 303.426928 -410.423851) (xy 303.442966 -410.489339) (xy 303.451044 -410.556276)
			(xy 303.451045 -410.6237) (xy 303.44297 -410.690637) (xy 303.426935 -410.756126) (xy 303.403172 -410.819222)
			(xy 303.372021 -410.879018) (xy 303.333932 -410.934651) (xy 303.312068 -410.960316) (xy 303.306278 -410.967466)
			(xy 303.29976 -410.984653) (xy 303.299368 -410.993844) (xy 303.299368 -411.151324) (xy 303.299003 -411.161452)
			(xy 303.291241 -411.180162) (xy 303.276909 -411.194477) (xy 303.258189 -411.202216) (xy 303.24806 -411.202632)
			(xy 302.53178 -411.202632) (xy 302.521674 -411.202132) (xy 302.503001 -411.194394) (xy 302.488708 -411.180102)
			(xy 302.480969 -411.16143) (xy 302.480472 -411.151324) (xy 302.480472 -410.993844) (xy 302.480047 -410.984658)
			(xy 302.473544 -410.967474) (xy 302.467772 -410.960316) (xy 302.445893 -410.934663) (xy 302.407807 -410.879026)
			(xy 302.376658 -410.819228) (xy 302.352896 -410.75613) (xy 302.336863 -410.690639) (xy 302.328789 -410.6237)
			(xy 299.050718 -410.6237) (xy 299.042683 -410.690461) (xy 299.026712 -410.755842) (xy 299.003042 -410.818846)
			(xy 298.972012 -410.878569) (xy 298.934066 -410.934156) (xy 298.91228 -410.959808) (xy 298.906495 -410.966961)
			(xy 298.899974 -410.984146) (xy 298.89958 -410.993336) (xy 298.89958 -411.151324) (xy 298.899198 -411.161482)
			(xy 298.891391 -411.180239) (xy 298.876982 -411.194562) (xy 298.858179 -411.202258) (xy 298.848018 -411.202632)
			(xy 298.131738 -411.202632) (xy 298.12161 -411.202141) (xy 298.102885 -411.194421) (xy 298.088526 -411.180135)
			(xy 298.080711 -411.161449) (xy 298.080176 -411.151324) (xy 298.080176 -410.993336) (xy 298.079754 -410.98415)
			(xy 298.073249 -410.966965) (xy 298.067476 -410.959808) (xy 298.045672 -410.934169) (xy 298.007721 -410.878582)
			(xy 297.976686 -410.818857) (xy 297.953013 -410.75585) (xy 297.93704 -410.690466) (xy 297.928996 -410.623641)
			(xy 294.650957 -410.623641) (xy 294.650957 -410.623699) (xy 294.642883 -410.690637) (xy 294.626848 -410.756125)
			(xy 294.603085 -410.819221) (xy 294.571935 -410.879017) (xy 294.533848 -410.934651) (xy 294.511984 -410.960316)
			(xy 294.506196 -410.967467) (xy 294.499677 -410.984653) (xy 294.499284 -410.993844) (xy 294.499284 -411.151324)
			(xy 294.498834 -411.161436) (xy 294.491086 -411.180118) (xy 294.476778 -411.194413) (xy 294.458089 -411.202144)
			(xy 294.447976 -411.202632) (xy 293.731696 -411.202632) (xy 293.721591 -411.202119) (xy 293.702919 -411.194386)
			(xy 293.688625 -411.180098) (xy 293.680885 -411.161429) (xy 293.680388 -411.151324) (xy 293.680388 -410.993844)
			(xy 293.679959 -410.984659) (xy 293.673459 -410.967474) (xy 293.667688 -410.960316) (xy 293.645809 -410.934664)
			(xy 293.607721 -410.879027) (xy 293.576572 -410.819229) (xy 293.552809 -410.75613) (xy 293.536775 -410.69064)
			(xy 293.528701 -410.6237) (xy 290.250631 -410.6237) (xy 290.242595 -410.69046) (xy 290.226625 -410.755841)
			(xy 290.202956 -410.818845) (xy 290.171926 -410.878568) (xy 290.133982 -410.934155) (xy 290.112196 -410.959808)
			(xy 290.106413 -410.966963) (xy 290.09989 -410.984146) (xy 290.099496 -410.993336) (xy 290.099496 -411.151324)
			(xy 290.099098 -411.16148) (xy 290.091294 -411.180234) (xy 290.07689 -411.194557) (xy 290.058092 -411.202255)
			(xy 290.047934 -411.202632) (xy 289.331654 -411.202632) (xy 289.321521 -411.20221) (xy 289.302793 -411.194462)
			(xy 289.288438 -411.180156) (xy 289.280625 -411.161455) (xy 289.280092 -411.151324) (xy 289.280092 -410.993336)
			(xy 289.279666 -410.98415) (xy 289.273164 -410.966966) (xy 289.267392 -410.959808) (xy 289.245587 -410.934169)
			(xy 289.207635 -410.878582) (xy 289.1766 -410.818857) (xy 289.152925 -410.755851) (xy 289.136952 -410.690467)
			(xy 289.128908 -410.623642) (xy 237.406942 -410.623642) (xy 237.406942 -412.06928) (xy 237.406417 -412.094228)
			(xy 237.39861 -412.143509) (xy 237.383199 -412.190966) (xy 237.360564 -412.235432) (xy 237.33126 -412.275817)
			(xy 237.313978 -412.293816) (xy 235.9787 -413.629094) (xy 235.960708 -413.646388) (xy 235.920331 -413.675711)
			(xy 235.875865 -413.698359) (xy 235.828403 -413.713772) (xy 235.779115 -413.721572) (xy 235.754164 -413.722058)
			(xy 208.805526 -413.722058) (xy 208.780578 -413.721525) (xy 208.731298 -413.713719) (xy 208.683841 -413.69831)
			(xy 208.639375 -413.675677) (xy 208.59899 -413.646375) (xy 208.58099 -413.629094) (xy 207.025748 -412.073852)
			(xy 207.008419 -412.055891) (xy 206.979094 -412.015508) (xy 206.956447 -411.971034) (xy 206.941036 -411.923565)
			(xy 206.933241 -411.87427) (xy 206.932784 -411.849316) (xy 206.932784 -389.931402) (xy 206.932362 -389.921332)
			(xy 206.924639 -389.902734) (xy 206.917798 -389.895334) (xy 204.423264 -387.4008) (xy 204.405961 -387.382815)
			(xy 204.376631 -387.342439) (xy 204.353979 -387.297971) (xy 204.338563 -387.250507) (xy 204.330761 -387.201216)
			(xy 204.3303 -387.176264) (xy 204.3303 -378.650754) (xy 204.31379 -378.625608) (xy 204.299566 -378.619512)
			(xy 204.274196 -378.60805) (xy 204.226725 -378.578976) (xy 204.183985 -378.543309) (xy 204.146885 -378.501809)
			(xy 204.116211 -378.455355) (xy 204.092616 -378.404937) (xy 204.076601 -378.351623) (xy 204.068507 -378.296548)
			(xy 204.068504 -378.240882) (xy 197.862607 -378.240882) (xy 197.885782 -378.367343) (xy 197.901882 -378.499931)
			(xy 197.909946 -378.633249) (xy 197.91045 -378.70003) (xy 197.909946 -378.766811) (xy 197.901882 -378.900129)
			(xy 197.885782 -379.032717) (xy 197.861707 -379.164091) (xy 197.829744 -379.293772) (xy 197.790009 -379.421286)
			(xy 197.742647 -379.546169) (xy 197.687832 -379.667964) (xy 197.625762 -379.786227) (xy 197.556666 -379.900526)
			(xy 197.480794 -380.010446) (xy 197.398424 -380.115583) (xy 197.309856 -380.215556) (xy 197.215414 -380.309998)
			(xy 197.115441 -380.398566) (xy 197.010304 -380.480936) (xy 196.900384 -380.556808) (xy 196.786085 -380.625904)
			(xy 196.667822 -380.687974) (xy 196.546027 -380.742789) (xy 196.421144 -380.790151) (xy 196.29363 -380.829886)
			(xy 196.163949 -380.861849) (xy 196.032575 -380.885924) (xy 195.899987 -380.902024) (xy 195.766669 -380.910088)
			(xy 195.633107 -380.910088) (xy 195.499789 -380.902024) (xy 195.367201 -380.885924) (xy 195.235827 -380.861849)
			(xy 195.106146 -380.829886) (xy 194.978632 -380.790151) (xy 194.853749 -380.742789) (xy 194.731954 -380.687974)
			(xy 194.613691 -380.625904) (xy 194.499392 -380.556808) (xy 194.389472 -380.480936) (xy 194.284335 -380.398566)
			(xy 194.184362 -380.309998) (xy 194.08992 -380.215556) (xy 194.001352 -380.115583) (xy 193.918982 -380.010446)
			(xy 193.84311 -379.900526) (xy 193.774014 -379.786227) (xy 193.711944 -379.667964) (xy 193.657129 -379.546169)
			(xy 193.609767 -379.421286) (xy 193.570032 -379.293772) (xy 193.538069 -379.164091) (xy 193.513994 -379.032717)
			(xy 193.497894 -378.900129) (xy 193.48983 -378.766811) (xy 173.519592 -378.766811) (xy 173.519592 -379.186694)
			(xy 173.520007 -379.195881) (xy 173.526518 -379.213065) (xy 173.532292 -379.220222) (xy 173.554124 -379.245837)
			(xy 173.592069 -379.30143) (xy 173.623099 -379.361159) (xy 173.646768 -379.424168) (xy 173.662737 -379.489554)
			(xy 173.670777 -379.556381) (xy 173.670772 -379.623689) (xy 173.662724 -379.690514) (xy 173.646747 -379.755898)
			(xy 173.623071 -379.818905) (xy 173.592034 -379.87863) (xy 173.554082 -379.934217) (xy 173.532292 -379.95987)
			(xy 173.526482 -379.967006) (xy 173.519976 -379.984204) (xy 173.519592 -379.993398) (xy 173.519592 -380.151386)
			(xy 173.519056 -380.161539) (xy 173.511292 -380.180302) (xy 173.496939 -380.194667) (xy 173.478183 -380.202447)
			(xy 173.46803 -380.202948) (xy 172.75175 -380.202948) (xy 172.74158 -380.202495) (xy 172.722784 -380.194724)
			(xy 172.708396 -380.180347) (xy 172.700612 -380.161556) (xy 172.700188 -380.151386) (xy 172.700188 -379.993398)
			(xy 172.699781 -379.98421) (xy 172.693266 -379.967026) (xy 172.687488 -379.95987) (xy 172.665744 -379.934181)
			(xy 172.627791 -379.878601) (xy 172.596753 -379.818883) (xy 172.573075 -379.755883) (xy 172.557097 -379.690505)
			(xy 172.549049 -379.623686) (xy 172.549045 -379.556383) (xy 172.557085 -379.489563) (xy 172.573055 -379.424183)
			(xy 172.596724 -379.36118) (xy 172.627755 -379.301458) (xy 172.665702 -379.245873) (xy 172.687488 -379.220222)
			(xy 172.693299 -379.213087) (xy 172.699805 -379.195889) (xy 172.700188 -379.186694) (xy 172.700188 -378.693426)
			(xy 172.699768 -378.68424) (xy 172.693262 -378.667055) (xy 172.687488 -378.659898) (xy 172.665673 -378.634268)
			(xy 172.627722 -378.578679) (xy 172.596687 -378.518953) (xy 172.573014 -378.455946) (xy 172.557041 -378.39056)
			(xy 172.548998 -378.323734) (xy 169.270937 -378.323734) (xy 169.262897 -378.390552) (xy 169.246928 -378.455932)
			(xy 169.22326 -378.518935) (xy 169.192232 -378.578658) (xy 169.154289 -378.634245) (xy 169.132504 -378.659898)
			(xy 169.126726 -378.667057) (xy 169.1202 -378.684237) (xy 169.119804 -378.693426) (xy 169.119804 -379.186694)
			(xy 169.120216 -379.195881) (xy 169.126728 -379.213065) (xy 169.132504 -379.220222) (xy 169.154336 -379.245838)
			(xy 169.19228 -379.30143) (xy 169.223309 -379.361159) (xy 169.246977 -379.424169) (xy 169.262946 -379.489555)
			(xy 169.270986 -379.556381) (xy 169.270982 -379.623689) (xy 169.262933 -379.690513) (xy 169.246957 -379.755898)
			(xy 169.223281 -379.818904) (xy 169.192245 -379.878629) (xy 169.154293 -379.934217) (xy 169.132504 -379.95987)
			(xy 169.126696 -379.967007) (xy 169.120188 -379.984204) (xy 169.119804 -379.993398) (xy 169.119804 -380.151386)
			(xy 169.119256 -380.161538) (xy 169.111494 -380.180299) (xy 169.097146 -380.194663) (xy 169.078393 -380.202445)
			(xy 169.068242 -380.202948) (xy 168.351962 -380.202948) (xy 168.3418 -380.202497) (xy 168.323027 -380.194708)
			(xy 168.308663 -380.180329) (xy 168.300892 -380.161548) (xy 168.3004 -380.151386) (xy 168.3004 -379.993398)
			(xy 168.299991 -379.984211) (xy 168.293476 -379.967026) (xy 168.2877 -379.95987) (xy 168.265959 -379.93418)
			(xy 168.228011 -379.878598) (xy 168.196978 -379.818879) (xy 168.173304 -379.75588) (xy 168.157329 -379.690503)
			(xy 168.149282 -379.623685) (xy 168.149278 -379.556384) (xy 168.157317 -379.489565) (xy 168.173284 -379.424186)
			(xy 168.19695 -379.361184) (xy 168.227975 -379.301461) (xy 168.265916 -379.245875) (xy 168.2877 -379.220222)
			(xy 168.293512 -379.213088) (xy 168.300018 -379.195889) (xy 168.3004 -379.186694) (xy 168.3004 -378.693426)
			(xy 168.299977 -378.68424) (xy 168.293472 -378.667056) (xy 168.2877 -378.659898) (xy 168.265888 -378.634266)
			(xy 168.227942 -378.578676) (xy 168.196912 -378.518949) (xy 168.173243 -378.455942) (xy 168.157273 -378.390558)
			(xy 168.149231 -378.323734) (xy 164.871169 -378.323734) (xy 164.871169 -378.323791) (xy 164.863096 -378.390728)
			(xy 164.847063 -378.456215) (xy 164.823302 -378.519311) (xy 164.792155 -378.579106) (xy 164.75407 -378.634741)
			(xy 164.732208 -378.660406) (xy 164.726427 -378.667563) (xy 164.719903 -378.684744) (xy 164.719508 -378.693934)
			(xy 164.719508 -379.186186) (xy 164.719923 -379.195373) (xy 164.726433 -379.212557) (xy 164.732208 -379.219714)
			(xy 164.754117 -379.245342) (xy 164.792204 -379.300982) (xy 164.823352 -379.360784) (xy 164.847113 -379.423885)
			(xy 164.863145 -379.489379) (xy 164.871217 -379.556321) (xy 164.871213 -379.623748) (xy 164.863133 -379.690689)
			(xy 164.847093 -379.756181) (xy 164.823324 -379.81928) (xy 164.792168 -379.879077) (xy 164.754074 -379.934713)
			(xy 164.732208 -379.960378) (xy 164.726397 -379.967513) (xy 164.719891 -379.984711) (xy 164.719508 -379.993906)
			(xy 164.719508 -380.151386) (xy 164.718963 -380.161506) (xy 164.711249 -380.180218) (xy 164.696981 -380.194573)
			(xy 164.678317 -380.202401) (xy 164.6682 -380.202948) (xy 163.95192 -380.202948) (xy 163.941773 -380.202463)
			(xy 163.92303 -380.194683) (xy 163.908708 -380.180306) (xy 163.900999 -380.161534) (xy 163.900612 -380.151386)
			(xy 163.900612 -379.993906) (xy 163.900196 -379.98472) (xy 163.893686 -379.967535) (xy 163.887912 -379.960378)
			(xy 163.866093 -379.934676) (xy 163.828002 -379.879047) (xy 163.796849 -379.819256) (xy 163.773081 -379.756164)
			(xy 163.757042 -379.690679) (xy 163.748963 -379.623745) (xy 163.748958 -379.556324) (xy 163.75703 -379.489389)
			(xy 163.773061 -379.423902) (xy 163.79682 -379.360807) (xy 163.827966 -379.301013) (xy 163.86605 -379.245379)
			(xy 163.887912 -379.219714) (xy 163.893729 -379.212583) (xy 163.900231 -379.195382) (xy 163.900612 -379.186186)
			(xy 163.900612 -378.693934) (xy 163.900183 -378.684749) (xy 163.893682 -378.667565) (xy 163.887912 -378.660406)
			(xy 163.866022 -378.634762) (xy 163.827933 -378.579125) (xy 163.796783 -378.519326) (xy 163.77302 -378.456226)
			(xy 163.756986 -378.390734) (xy 163.748912 -378.323793) (xy 160.470867 -378.323793) (xy 160.462831 -378.390554)
			(xy 160.44686 -378.455935) (xy 160.423188 -378.518939) (xy 160.392156 -378.578661) (xy 160.354207 -378.634246)
			(xy 160.33242 -378.659898) (xy 160.326644 -378.667058) (xy 160.320116 -378.684237) (xy 160.31972 -378.693426)
			(xy 160.31972 -379.186694) (xy 160.320129 -379.195881) (xy 160.326643 -379.213066) (xy 160.33242 -379.220222)
			(xy 160.354254 -379.245836) (xy 160.392205 -379.301427) (xy 160.423238 -379.361156) (xy 160.44691 -379.424165)
			(xy 160.462881 -379.489552) (xy 160.470922 -379.55638) (xy 160.470918 -379.623689) (xy 160.462869 -379.690516)
			(xy 160.44689 -379.755901) (xy 160.42321 -379.818908) (xy 160.392169 -379.878632) (xy 160.354212 -379.934219)
			(xy 160.33242 -379.95987) (xy 160.326614 -379.967008) (xy 160.320104 -379.984204) (xy 160.31972 -379.993398)
			(xy 160.31972 -380.151386) (xy 160.319324 -380.161562) (xy 160.311536 -380.180364) (xy 160.297141 -380.194751)
			(xy 160.278334 -380.202529) (xy 160.268158 -380.202948) (xy 159.551878 -380.202948) (xy 159.541717 -380.202484)
			(xy 159.522945 -380.1947) (xy 159.50858 -380.180325) (xy 159.500808 -380.161547) (xy 159.500316 -380.151386)
			(xy 159.500316 -379.993398) (xy 159.499903 -379.984211) (xy 159.493391 -379.967027) (xy 159.487616 -379.95987)
			(xy 159.465874 -379.93418) (xy 159.427926 -379.878599) (xy 159.396892 -379.81888) (xy 159.373217 -379.75588)
			(xy 159.357242 -379.690503) (xy 159.349195 -379.623685) (xy 159.34919 -379.556384) (xy 159.35723 -379.489565)
			(xy 159.373197 -379.424186) (xy 159.396864 -379.361183) (xy 159.42789 -379.301461) (xy 159.465832 -379.245875)
			(xy 159.487616 -379.220222) (xy 159.49343 -379.213089) (xy 159.499934 -379.195889) (xy 159.500316 -379.186694)
			(xy 159.500316 -378.693426) (xy 159.49989 -378.684241) (xy 159.493387 -378.667056) (xy 159.487616 -378.659898)
			(xy 159.465803 -378.634267) (xy 159.427857 -378.578677) (xy 159.396826 -378.51895) (xy 159.373156 -378.455943)
			(xy 159.357185 -378.390558) (xy 159.349143 -378.323734) (xy 129.670819 -378.323734) (xy 129.662778 -378.390552)
			(xy 129.646808 -378.455933) (xy 129.623139 -378.518936) (xy 129.59211 -378.578659) (xy 129.554166 -378.634246)
			(xy 129.53238 -378.659898) (xy 129.526599 -378.667054) (xy 129.520076 -378.684236) (xy 129.51968 -378.693426)
			(xy 129.51968 -379.186694) (xy 129.520098 -379.19588) (xy 129.526607 -379.213064) (xy 129.53238 -379.220222)
			(xy 129.554212 -379.245837) (xy 129.592159 -379.301429) (xy 129.623189 -379.361158) (xy 129.646858 -379.424168)
			(xy 129.662827 -379.489554) (xy 129.670868 -379.55638) (xy 129.670863 -379.623689) (xy 129.662815 -379.690514)
			(xy 129.646838 -379.755899) (xy 129.623161 -379.818905) (xy 129.592123 -379.87863) (xy 129.55417 -379.934218)
			(xy 129.53238 -379.95987) (xy 129.526569 -379.967005) (xy 129.520064 -379.984203) (xy 129.51968 -379.993398)
			(xy 129.51968 -380.151386) (xy 129.519156 -380.161541) (xy 129.511389 -380.180306) (xy 129.497033 -380.194671)
			(xy 129.478272 -380.202449) (xy 129.468118 -380.202948) (xy 128.751838 -380.202948) (xy 128.741667 -380.202505)
			(xy 128.722871 -380.19473) (xy 128.708484 -380.18035) (xy 128.7007 -380.161557) (xy 128.700276 -380.151386)
			(xy 128.700276 -379.993398) (xy 128.699872 -379.98421) (xy 128.693355 -379.967025) (xy 128.687576 -379.95987)
			(xy 128.665832 -379.934181) (xy 128.62788 -379.878601) (xy 128.596842 -379.818883) (xy 128.573165 -379.755883)
			(xy 128.557188 -379.690505) (xy 128.54914 -379.623686) (xy 128.549136 -379.556384) (xy 128.557176 -379.489563)
			(xy 128.573145 -379.424183) (xy 128.596814 -379.361181) (xy 128.627844 -379.301459) (xy 128.66579 -379.245874)
			(xy 128.687576 -379.220222) (xy 128.693385 -379.213086) (xy 128.699893 -379.195889) (xy 128.700276 -379.186694)
			(xy 128.700276 -378.693426) (xy 128.699859 -378.684239) (xy 128.693351 -378.667055) (xy 128.687576 -378.659898)
			(xy 128.665762 -378.634267) (xy 128.627811 -378.578679) (xy 128.596777 -378.518952) (xy 128.573104 -378.455945)
			(xy 128.557132 -378.39056) (xy 128.549089 -378.323734) (xy 125.271028 -378.323734) (xy 125.262987 -378.390552)
			(xy 125.247018 -378.455932) (xy 125.223349 -378.518936) (xy 125.192321 -378.578659) (xy 125.154377 -378.634245)
			(xy 125.132592 -378.659898) (xy 125.126813 -378.667056) (xy 125.120288 -378.684237) (xy 125.119892 -378.693426)
			(xy 125.119892 -379.186694) (xy 125.120307 -379.195881) (xy 125.126818 -379.213065) (xy 125.132592 -379.220222)
			(xy 125.154424 -379.245837) (xy 125.192369 -379.30143) (xy 125.223399 -379.361159) (xy 125.247068 -379.424168)
			(xy 125.263037 -379.489554) (xy 125.271077 -379.556381) (xy 125.271072 -379.623689) (xy 125.263024 -379.690514)
			(xy 125.247047 -379.755898) (xy 125.223371 -379.818905) (xy 125.192334 -379.87863) (xy 125.154382 -379.934217)
			(xy 125.132592 -379.95987) (xy 125.126782 -379.967006) (xy 125.120276 -379.984204) (xy 125.119892 -379.993398)
			(xy 125.119892 -380.151386) (xy 125.119356 -380.161539) (xy 125.111592 -380.180302) (xy 125.097239 -380.194667)
			(xy 125.078483 -380.202447) (xy 125.06833 -380.202948) (xy 124.35205 -380.202948) (xy 124.34188 -380.202495)
			(xy 124.323084 -380.194724) (xy 124.308696 -380.180347) (xy 124.300912 -380.161556) (xy 124.300488 -380.151386)
			(xy 124.300488 -379.993398) (xy 124.300081 -379.98421) (xy 124.293566 -379.967026) (xy 124.287788 -379.95987)
			(xy 124.266044 -379.934181) (xy 124.228091 -379.878601) (xy 124.197053 -379.818883) (xy 124.173375 -379.755883)
			(xy 124.157397 -379.690505) (xy 124.149349 -379.623686) (xy 124.149345 -379.556383) (xy 124.157385 -379.489563)
			(xy 124.173355 -379.424183) (xy 124.197024 -379.36118) (xy 124.228055 -379.301458) (xy 124.266002 -379.245873)
			(xy 124.287788 -379.220222) (xy 124.293599 -379.213087) (xy 124.300105 -379.195889) (xy 124.300488 -379.186694)
			(xy 124.300488 -378.693426) (xy 124.300068 -378.68424) (xy 124.293562 -378.667055) (xy 124.287788 -378.659898)
			(xy 124.265973 -378.634268) (xy 124.228022 -378.578679) (xy 124.196987 -378.518953) (xy 124.173314 -378.455946)
			(xy 124.157341 -378.39056) (xy 124.149298 -378.323734) (xy 120.87126 -378.323734) (xy 120.87126 -378.323791)
			(xy 120.863187 -378.390728) (xy 120.847154 -378.456216) (xy 120.823392 -378.519311) (xy 120.792244 -378.579107)
			(xy 120.754159 -378.634741) (xy 120.732296 -378.660406) (xy 120.726514 -378.667561) (xy 120.719991 -378.684744)
			(xy 120.719596 -378.693934) (xy 120.719596 -379.186186) (xy 120.720014 -379.195372) (xy 120.726522 -379.212557)
			(xy 120.732296 -379.219714) (xy 120.754205 -379.245342) (xy 120.792293 -379.300982) (xy 120.823442 -379.360783)
			(xy 120.847204 -379.423885) (xy 120.863236 -379.489378) (xy 120.871308 -379.556321) (xy 120.871304 -379.623748)
			(xy 120.863224 -379.69069) (xy 120.847183 -379.756181) (xy 120.823414 -379.81928) (xy 120.792257 -379.879078)
			(xy 120.754163 -379.934713) (xy 120.732296 -379.960378) (xy 120.726483 -379.967512) (xy 120.719978 -379.984711)
			(xy 120.719596 -379.993906) (xy 120.719596 -380.151386) (xy 120.719063 -380.161507) (xy 120.711347 -380.180221)
			(xy 120.697075 -380.194577) (xy 120.678406 -380.202403) (xy 120.668288 -380.202948) (xy 119.952008 -380.202948)
			(xy 119.94186 -380.202473) (xy 119.923117 -380.194689) (xy 119.908795 -380.180309) (xy 119.901087 -380.161535)
			(xy 119.9007 -380.151386) (xy 119.9007 -379.993906) (xy 119.900287 -379.984719) (xy 119.893775 -379.967535)
			(xy 119.888 -379.960378) (xy 119.866181 -379.934675) (xy 119.828091 -379.879046) (xy 119.796938 -379.819255)
			(xy 119.773172 -379.756163) (xy 119.757133 -379.690679) (xy 119.749053 -379.623745) (xy 119.749049 -379.556325)
			(xy 119.757121 -379.489389) (xy 119.773151 -379.423903) (xy 119.79691 -379.360808) (xy 119.828056 -379.301013)
			(xy 119.866139 -379.245379) (xy 119.888 -379.219714) (xy 119.893816 -379.212582) (xy 119.900319 -379.195381)
			(xy 119.9007 -379.186186) (xy 119.9007 -378.693934) (xy 119.900273 -378.684749) (xy 119.893771 -378.667564)
			(xy 119.888 -378.660406) (xy 119.86611 -378.634762) (xy 119.828023 -378.579124) (xy 119.796873 -378.519325)
			(xy 119.77311 -378.456226) (xy 119.757077 -378.390734) (xy 119.749003 -378.323793) (xy 116.470957 -378.323793)
			(xy 116.462922 -378.390554) (xy 116.44695 -378.455936) (xy 116.423278 -378.518939) (xy 116.392245 -378.578662)
			(xy 116.354296 -378.634247) (xy 116.332508 -378.659898) (xy 116.326731 -378.667057) (xy 116.320204 -378.684237)
			(xy 116.319808 -378.693426) (xy 116.319808 -379.186694) (xy 116.320219 -379.195881) (xy 116.326732 -379.213066)
			(xy 116.332508 -379.220222) (xy 116.354343 -379.245836) (xy 116.392293 -379.301427) (xy 116.423328 -379.361155)
			(xy 116.447 -379.424165) (xy 116.462971 -379.489552) (xy 116.471013 -379.55638) (xy 116.471009 -379.623689)
			(xy 116.462959 -379.690516) (xy 116.44698 -379.755901) (xy 116.423299 -379.818908) (xy 116.392258 -379.878633)
			(xy 116.3543 -379.934219) (xy 116.332508 -379.95987) (xy 116.3267 -379.967007) (xy 116.320192 -379.984204)
			(xy 116.319808 -379.993398) (xy 116.319808 -380.151386) (xy 116.319256 -380.161537) (xy 116.311495 -380.180297)
			(xy 116.297148 -380.194661) (xy 116.278397 -380.202445) (xy 116.268246 -380.202948) (xy 115.551966 -380.202948)
			(xy 115.541804 -380.202494) (xy 115.523032 -380.194706) (xy 115.508667 -380.180328) (xy 115.500896 -380.161548)
			(xy 115.500404 -380.151386) (xy 115.500404 -379.993398) (xy 115.499994 -379.984211) (xy 115.49348 -379.967027)
			(xy 115.487704 -379.95987) (xy 115.465963 -379.93418) (xy 115.428015 -379.878598) (xy 115.396981 -379.81888)
			(xy 115.373307 -379.75588) (xy 115.357332 -379.690503) (xy 115.349285 -379.623685) (xy 115.349281 -379.556384)
			(xy 115.35732 -379.489565) (xy 115.373287 -379.424186) (xy 115.396953 -379.361184) (xy 115.427979 -379.301461)
			(xy 115.46592 -379.245875) (xy 115.487704 -379.220222) (xy 115.493517 -379.213088) (xy 115.500022 -379.195889)
			(xy 115.500404 -379.186694) (xy 115.500404 -378.693426) (xy 115.49998 -378.68424) (xy 115.493476 -378.667056)
			(xy 115.487704 -378.659898) (xy 115.465892 -378.634266) (xy 115.427946 -378.578676) (xy 115.396916 -378.518949)
			(xy 115.373246 -378.455942) (xy 115.357276 -378.390558) (xy 115.349234 -378.323734) (xy 85.670933 -378.323734)
			(xy 85.670933 -378.323792) (xy 85.662859 -378.390729) (xy 85.646825 -378.456217) (xy 85.623062 -378.519313)
			(xy 85.591912 -378.579108) (xy 85.553824 -378.634741) (xy 85.53196 -378.660406) (xy 85.526173 -378.667558)
			(xy 85.519654 -378.684743) (xy 85.51926 -378.693934) (xy 85.51926 -379.186186) (xy 85.519686 -379.195371)
			(xy 85.526189 -379.212555) (xy 85.53196 -379.219714) (xy 85.553871 -379.245341) (xy 85.591961 -379.30098)
			(xy 85.623111 -379.360781) (xy 85.646875 -379.423883) (xy 85.662908 -379.489377) (xy 85.670981 -379.55632)
			(xy 85.670977 -379.623749) (xy 85.662896 -379.690691) (xy 85.646854 -379.756183) (xy 85.623083 -379.819282)
			(xy 85.591925 -379.879079) (xy 85.553828 -379.934713) (xy 85.53196 -379.960378) (xy 85.526143 -379.967508)
			(xy 85.519641 -379.98471) (xy 85.51926 -379.993906) (xy 85.51926 -380.151386) (xy 85.518762 -380.161512)
			(xy 85.511039 -380.180233) (xy 85.496756 -380.194589) (xy 85.478075 -380.202409) (xy 85.467952 -380.202948)
			(xy 84.751672 -380.202948) (xy 84.741567 -380.202439) (xy 84.722898 -380.194701) (xy 84.708606 -380.180412)
			(xy 84.700863 -380.161744) (xy 84.700364 -380.15164) (xy 84.700364 -379.993906) (xy 84.699937 -379.984721)
			(xy 84.693433 -379.967537) (xy 84.687664 -379.960378) (xy 84.665846 -379.934675) (xy 84.627759 -379.879045)
			(xy 84.596608 -379.819254) (xy 84.572843 -379.756162) (xy 84.556805 -379.690678) (xy 84.548726 -379.623744)
			(xy 84.548722 -379.556325) (xy 84.556793 -379.48939) (xy 84.572822 -379.423904) (xy 84.59658 -379.36081)
			(xy 84.627723 -379.301014) (xy 84.665804 -379.24538) (xy 84.687664 -379.219714) (xy 84.693487 -379.212588)
			(xy 84.699984 -379.195383) (xy 84.700364 -379.186186) (xy 84.700364 -378.693934) (xy 84.699923 -378.68475)
			(xy 84.693429 -378.667566) (xy 84.687664 -378.660406) (xy 84.665776 -378.634761) (xy 84.62769 -378.579123)
			(xy 84.596543 -378.519324) (xy 84.572781 -378.456224) (xy 84.556749 -378.390733) (xy 84.548676 -378.323793)
			(xy 81.271142 -378.323793) (xy 81.263068 -378.390729) (xy 81.247035 -378.456217) (xy 81.223272 -378.519312)
			(xy 81.192123 -378.579108) (xy 81.154035 -378.634741) (xy 81.132172 -378.660406) (xy 81.126387 -378.667559)
			(xy 81.119866 -378.684744) (xy 81.119472 -378.693934) (xy 81.119472 -379.186186) (xy 81.119895 -379.195372)
			(xy 81.126401 -379.212556) (xy 81.132172 -379.219714) (xy 81.154082 -379.245341) (xy 81.192171 -379.300981)
			(xy 81.223322 -379.360782) (xy 81.247084 -379.423884) (xy 81.263118 -379.489378) (xy 81.27119 -379.556321)
			(xy 81.271186 -379.623748) (xy 81.263105 -379.69069) (xy 81.247064 -379.756182) (xy 81.223293 -379.819281)
			(xy 81.192136 -379.879079) (xy 81.15404 -379.934713) (xy 81.132172 -379.960378) (xy 81.126356 -379.967509)
			(xy 81.119854 -379.984711) (xy 81.119472 -379.993906) (xy 81.119472 -380.151386) (xy 81.118962 -380.16151)
			(xy 81.111241 -380.180229) (xy 81.096962 -380.194585) (xy 81.078286 -380.202407) (xy 81.068164 -380.202948)
			(xy 80.351884 -380.202948) (xy 80.34178 -380.202429) (xy 80.323111 -380.194695) (xy 80.308818 -380.180409)
			(xy 80.301076 -380.161744) (xy 80.300576 -380.15164) (xy 80.300576 -379.993906) (xy 80.300168 -379.984718)
			(xy 80.293654 -379.967534) (xy 80.287876 -379.960378) (xy 80.266058 -379.934675) (xy 80.22797 -379.879045)
			(xy 80.196818 -379.819254) (xy 80.173052 -379.756162) (xy 80.157015 -379.690678) (xy 80.148935 -379.623744)
			(xy 80.148931 -379.556325) (xy 80.157002 -379.48939) (xy 80.173032 -379.423904) (xy 80.19679 -379.360809)
			(xy 80.227934 -379.301014) (xy 80.266016 -379.24538) (xy 80.287876 -379.219714) (xy 80.293689 -379.21258)
			(xy 80.300195 -379.195381) (xy 80.300576 -379.186186) (xy 80.300576 -378.693934) (xy 80.300155 -378.684748)
			(xy 80.29365 -378.667563) (xy 80.287876 -378.660406) (xy 80.265987 -378.634761) (xy 80.227901 -378.579123)
			(xy 80.196753 -378.519324) (xy 80.172991 -378.456225) (xy 80.156958 -378.390733) (xy 80.148885 -378.323793)
			(xy 76.870815 -378.323793) (xy 76.862781 -378.390552) (xy 76.846812 -378.455933) (xy 76.823143 -378.518936)
			(xy 76.792114 -378.578659) (xy 76.75417 -378.634246) (xy 76.732384 -378.659898) (xy 76.726604 -378.667055)
			(xy 76.72008 -378.684236) (xy 76.719684 -378.693426) (xy 76.719684 -379.186694) (xy 76.720101 -379.19588)
			(xy 76.72661 -379.213065) (xy 76.732384 -379.220222) (xy 76.754216 -379.245837) (xy 76.792162 -379.30143)
			(xy 76.823192 -379.361158) (xy 76.846861 -379.424168) (xy 76.86283 -379.489554) (xy 76.870871 -379.55638)
			(xy 76.870866 -379.623689) (xy 76.862818 -379.690514) (xy 76.846841 -379.755899) (xy 76.823164 -379.818905)
			(xy 76.792127 -379.87863) (xy 76.754174 -379.934218) (xy 76.732384 -379.95987) (xy 76.726573 -379.967005)
			(xy 76.720068 -379.984203) (xy 76.719684 -379.993398) (xy 76.719684 -380.151386) (xy 76.719156 -380.16154)
			(xy 76.71139 -380.180305) (xy 76.697035 -380.19467) (xy 76.678276 -380.202449) (xy 76.668122 -380.202948)
			(xy 75.951842 -380.202948) (xy 75.941671 -380.202501) (xy 75.922875 -380.194728) (xy 75.908488 -380.180349)
			(xy 75.900704 -380.161556) (xy 75.90028 -380.151386) (xy 75.90028 -379.993398) (xy 75.899875 -379.98421)
			(xy 75.893358 -379.967026) (xy 75.88758 -379.95987) (xy 75.865836 -379.934181) (xy 75.827883 -379.878601)
			(xy 75.796846 -379.818883) (xy 75.773169 -379.755883) (xy 75.757191 -379.690505) (xy 75.749143 -379.623686)
			(xy 75.749139 -379.556383) (xy 75.757179 -379.489563) (xy 75.773148 -379.424183) (xy 75.796818 -379.36118)
			(xy 75.827848 -379.301458) (xy 75.865794 -379.245874) (xy 75.88758 -379.220222) (xy 75.89339 -379.213086)
			(xy 75.899897 -379.195889) (xy 75.90028 -379.186694) (xy 75.90028 -378.693426) (xy 75.899862 -378.68424)
			(xy 75.893354 -378.667055) (xy 75.88758 -378.659898) (xy 75.865766 -378.634267) (xy 75.827815 -378.578679)
			(xy 75.79678 -378.518953) (xy 75.773107 -378.455945) (xy 75.757135 -378.39056) (xy 75.749092 -378.323734)
			(xy 72.471054 -378.323734) (xy 72.471054 -378.323791) (xy 72.46298 -378.390728) (xy 72.446947 -378.456216)
			(xy 72.423186 -378.519312) (xy 72.392037 -378.579107) (xy 72.353951 -378.634741) (xy 72.332088 -378.660406)
			(xy 72.326305 -378.667561) (xy 72.319783 -378.684744) (xy 72.319388 -378.693934) (xy 72.319388 -379.186186)
			(xy 72.319808 -379.195372) (xy 72.326315 -379.212556) (xy 72.332088 -379.219714) (xy 72.353998 -379.245342)
			(xy 72.392086 -379.300981) (xy 72.423235 -379.360783) (xy 72.446997 -379.423884) (xy 72.46303 -379.489378)
			(xy 72.471102 -379.556321) (xy 72.471098 -379.623748) (xy 72.463017 -379.69069) (xy 72.446977 -379.756182)
			(xy 72.423207 -379.819281) (xy 72.39205 -379.879078) (xy 72.353955 -379.934713) (xy 72.332088 -379.960378)
			(xy 72.326274 -379.967511) (xy 72.31977 -379.984711) (xy 72.319388 -379.993906) (xy 72.319388 -380.151386)
			(xy 72.318863 -380.161508) (xy 72.311145 -380.180224) (xy 72.296871 -380.19458) (xy 72.278199 -380.202404)
			(xy 72.26808 -380.202948) (xy 71.5518 -380.202948) (xy 71.541652 -380.202479) (xy 71.522909 -380.194693)
			(xy 71.508587 -380.180311) (xy 71.500879 -380.161536) (xy 71.500492 -380.151386) (xy 71.500492 -379.993906)
			(xy 71.500081 -379.984719) (xy 71.493568 -379.967534) (xy 71.487792 -379.960378) (xy 71.465974 -379.934675)
			(xy 71.427884 -379.879046) (xy 71.396732 -379.819255) (xy 71.372965 -379.756163) (xy 71.356927 -379.690678)
			(xy 71.348847 -379.623744) (xy 71.348843 -379.556325) (xy 71.356914 -379.48939) (xy 71.372945 -379.423903)
			(xy 71.396703 -379.360808) (xy 71.427848 -379.301013) (xy 71.465931 -379.245379) (xy 71.487792 -379.219714)
			(xy 71.493607 -379.212582) (xy 71.500111 -379.195381) (xy 71.500492 -379.186186) (xy 71.500492 -378.693934)
			(xy 71.500067 -378.684748) (xy 71.493564 -378.667564) (xy 71.487792 -378.660406) (xy 71.465903 -378.634762)
			(xy 71.427815 -378.579124) (xy 71.396666 -378.519325) (xy 71.372904 -378.456225) (xy 71.35687 -378.390734)
			(xy 71.348797 -378.323793) (xy 41.671024 -378.323793) (xy 41.66295 -378.390729) (xy 41.646915 -378.456218)
			(xy 41.623152 -378.519314) (xy 41.592001 -378.579109) (xy 41.553912 -378.634742) (xy 41.532048 -378.660406)
			(xy 41.52626 -378.667557) (xy 41.519742 -378.684743) (xy 41.519348 -378.693934) (xy 41.519348 -379.186186)
			(xy 41.519776 -379.195371) (xy 41.526279 -379.212555) (xy 41.532048 -379.219714) (xy 41.553959 -379.245341)
			(xy 41.59205 -379.30098) (xy 41.623201 -379.360781) (xy 41.646965 -379.423883) (xy 41.662999 -379.489377)
			(xy 41.671072 -379.55632) (xy 41.671068 -379.623749) (xy 41.662987 -379.690691) (xy 41.646945 -379.756183)
			(xy 41.623173 -379.819282) (xy 41.592014 -379.879079) (xy 41.553917 -379.934714) (xy 41.532048 -379.960378)
			(xy 41.526229 -379.967507) (xy 41.519729 -379.98471) (xy 41.519348 -379.993906) (xy 41.519348 -380.151386)
			(xy 41.518862 -380.161513) (xy 41.511136 -380.180236) (xy 41.49685 -380.194594) (xy 41.478165 -380.202411)
			(xy 41.46804 -380.202948) (xy 40.75176 -380.202948) (xy 40.741609 -380.202512) (xy 40.722865 -380.194712)
			(xy 40.708545 -380.180321) (xy 40.700838 -380.161539) (xy 40.700452 -380.151386) (xy 40.700452 -379.993906)
			(xy 40.700027 -379.984721) (xy 40.693523 -379.967537) (xy 40.687752 -379.960378) (xy 40.665931 -379.934676)
			(xy 40.627838 -379.879048) (xy 40.596682 -379.819258) (xy 40.572913 -379.756165) (xy 40.556873 -379.69068)
			(xy 40.548793 -379.623745) (xy 40.548788 -379.556324) (xy 40.556861 -379.489388) (xy 40.572893 -379.423901)
			(xy 40.596654 -379.360806) (xy 40.627802 -379.301011) (xy 40.665889 -379.245378) (xy 40.687752 -379.219714)
			(xy 40.693574 -379.212587) (xy 40.700072 -379.195382) (xy 40.700452 -379.186186) (xy 40.700452 -378.693934)
			(xy 40.700014 -378.68475) (xy 40.693519 -378.667566) (xy 40.687752 -378.660406) (xy 40.665861 -378.634763)
			(xy 40.627769 -378.579126) (xy 40.596617 -378.519328) (xy 40.572852 -378.456228) (xy 40.556817 -378.390735)
			(xy 40.548742 -378.323794) (xy 37.271233 -378.323794) (xy 37.263159 -378.390729) (xy 37.247125 -378.456217)
			(xy 37.223362 -378.519313) (xy 37.192212 -378.579108) (xy 37.154124 -378.634741) (xy 37.13226 -378.660406)
			(xy 37.126473 -378.667558) (xy 37.119954 -378.684743) (xy 37.11956 -378.693934) (xy 37.11956 -379.186186)
			(xy 37.119986 -379.195371) (xy 37.126489 -379.212555) (xy 37.13226 -379.219714) (xy 37.154171 -379.245341)
			(xy 37.192261 -379.30098) (xy 37.223411 -379.360781) (xy 37.247175 -379.423883) (xy 37.263208 -379.489377)
			(xy 37.271281 -379.55632) (xy 37.271277 -379.623749) (xy 37.263196 -379.690691) (xy 37.247154 -379.756183)
			(xy 37.223383 -379.819282) (xy 37.192225 -379.879079) (xy 37.154128 -379.934713) (xy 37.13226 -379.960378)
			(xy 37.126443 -379.967508) (xy 37.119941 -379.98471) (xy 37.11956 -379.993906) (xy 37.11956 -380.151386)
			(xy 37.119062 -380.161512) (xy 37.111339 -380.180233) (xy 37.097056 -380.194589) (xy 37.078375 -380.202409)
			(xy 37.068252 -380.202948) (xy 36.351972 -380.202948) (xy 36.341822 -380.202502) (xy 36.323078 -380.194707)
			(xy 36.308758 -380.180318) (xy 36.30105 -380.161538) (xy 36.300664 -380.151386) (xy 36.300664 -379.993906)
			(xy 36.300237 -379.984721) (xy 36.293733 -379.967537) (xy 36.287964 -379.960378) (xy 36.266146 -379.934675)
			(xy 36.228059 -379.879045) (xy 36.196908 -379.819254) (xy 36.173143 -379.756162) (xy 36.157105 -379.690678)
			(xy 36.149026 -379.623744) (xy 36.149022 -379.556325) (xy 36.157093 -379.48939) (xy 36.173122 -379.423904)
			(xy 36.19688 -379.36081) (xy 36.228023 -379.301014) (xy 36.266104 -379.24538) (xy 36.287964 -379.219714)
			(xy 36.293787 -379.212588) (xy 36.300284 -379.195383) (xy 36.300664 -379.186186) (xy 36.300664 -378.693934)
			(xy 36.300223 -378.68475) (xy 36.293729 -378.667566) (xy 36.287964 -378.660406) (xy 36.266076 -378.634761)
			(xy 36.22799 -378.579123) (xy 36.196843 -378.519324) (xy 36.173081 -378.456224) (xy 36.157049 -378.390733)
			(xy 36.148976 -378.323793) (xy 32.870906 -378.323793) (xy 32.862871 -378.390552) (xy 32.846902 -378.455933)
			(xy 32.823232 -378.518936) (xy 32.792203 -378.578659) (xy 32.754258 -378.634246) (xy 32.732472 -378.659898)
			(xy 32.72669 -378.667053) (xy 32.720167 -378.684236) (xy 32.719772 -378.693426) (xy 32.719772 -379.186694)
			(xy 32.720191 -379.19588) (xy 32.726699 -379.213064) (xy 32.732472 -379.220222) (xy 32.754305 -379.245837)
			(xy 32.792251 -379.301429) (xy 32.823282 -379.361158) (xy 32.846952 -379.424167) (xy 32.862921 -379.489554)
			(xy 32.870962 -379.55638) (xy 32.870957 -379.623689) (xy 32.862909 -379.690514) (xy 32.846931 -379.755899)
			(xy 32.823254 -379.818905) (xy 32.792216 -379.87863) (xy 32.754262 -379.934218) (xy 32.732472 -379.95987)
			(xy 32.72666 -379.967004) (xy 32.720155 -379.984203) (xy 32.719772 -379.993398) (xy 32.719772 -380.151386)
			(xy 32.719325 -380.161556) (xy 32.711547 -380.180348) (xy 32.697168 -380.194733) (xy 32.678379 -380.20252)
			(xy 32.66821 -380.202948) (xy 31.95193 -380.202948) (xy 31.941759 -380.202511) (xy 31.922962 -380.194733)
			(xy 31.908576 -380.180351) (xy 31.900792 -380.161557) (xy 31.900368 -380.151386) (xy 31.900368 -379.993398)
			(xy 31.899944 -379.984213) (xy 31.893438 -379.967029) (xy 31.887668 -379.95987) (xy 31.865925 -379.934181)
			(xy 31.827973 -379.878601) (xy 31.796936 -379.818882) (xy 31.773259 -379.755883) (xy 31.757282 -379.690505)
			(xy 31.749234 -379.623686) (xy 31.74923 -379.556384) (xy 31.75727 -379.489564) (xy 31.773239 -379.424184)
			(xy 31.796908 -379.361181) (xy 31.827937 -379.301459) (xy 31.865882 -379.245874) (xy 31.887668 -379.220222)
			(xy 31.893488 -379.213094) (xy 31.899987 -379.19589) (xy 31.900368 -379.186694) (xy 31.900368 -378.693426)
			(xy 31.89993 -378.684242) (xy 31.893434 -378.667058) (xy 31.887668 -378.659898) (xy 31.865854 -378.634267)
			(xy 31.827904 -378.578678) (xy 31.79687 -378.518952) (xy 31.773198 -378.455945) (xy 31.757226 -378.39056)
			(xy 31.749183 -378.323734) (xy 28.471145 -378.323734) (xy 28.471145 -378.323792) (xy 28.463071 -378.390728)
			(xy 28.447038 -378.456216) (xy 28.423275 -378.519312) (xy 28.392126 -378.579108) (xy 28.354039 -378.634741)
			(xy 28.332176 -378.660406) (xy 28.326392 -378.66756) (xy 28.31987 -378.684744) (xy 28.319476 -378.693934)
			(xy 28.319476 -379.186186) (xy 28.319898 -379.195372) (xy 28.326404 -379.212556) (xy 28.332176 -379.219714)
			(xy 28.354036 -379.245382) (xy 28.392125 -379.301016) (xy 28.423276 -379.360812) (xy 28.447 -379.423801)
			(xy 29.549058 -379.423801) (xy 29.549059 -379.356496) (xy 29.557103 -379.289673) (xy 29.573076 -379.224291)
			(xy 29.596749 -379.161286) (xy 29.627783 -379.101562) (xy 29.665732 -379.045976) (xy 29.68752 -379.020324)
			(xy 29.693334 -379.013191) (xy 29.699837 -378.995991) (xy 29.70022 -378.986796) (xy 29.70022 -378.828554)
			(xy 29.700695 -378.818396) (xy 29.708482 -378.799629) (xy 29.722852 -378.785266) (xy 29.741623 -378.77749)
			(xy 29.751782 -378.776992) (xy 30.468062 -378.776992) (xy 30.478212 -378.777564) (xy 30.496971 -378.785317)
			(xy 30.511336 -378.799658) (xy 30.51912 -378.818405) (xy 30.519624 -378.828554) (xy 30.519624 -378.986796)
			(xy 30.520031 -378.995984) (xy 30.526546 -379.013168) (xy 30.532324 -379.020324) (xy 30.55411 -379.045978)
			(xy 30.592059 -379.101564) (xy 30.623093 -379.161287) (xy 30.646766 -379.224291) (xy 30.662739 -379.289673)
			(xy 30.670784 -379.356496) (xy 30.670784 -379.423801) (xy 30.66274 -379.490624) (xy 30.646767 -379.556006)
			(xy 30.623094 -379.61901) (xy 30.592061 -379.678734) (xy 30.554112 -379.73432) (xy 30.532324 -379.759972)
			(xy 30.526517 -379.76711) (xy 30.520008 -379.784306) (xy 30.519624 -379.7935) (xy 30.519624 -380.286768)
			(xy 30.520044 -380.295954) (xy 30.52655 -380.313139) (xy 30.532324 -380.320296) (xy 30.554132 -380.345932)
			(xy 30.592083 -380.40152) (xy 30.623117 -380.461245) (xy 30.646791 -380.524252) (xy 30.662763 -380.589636)
			(xy 30.6708 -380.656404) (xy 33.948845 -380.656404) (xy 33.95692 -380.589467) (xy 33.972953 -380.523978)
			(xy 33.996716 -380.460882) (xy 34.027865 -380.401087) (xy 34.065953 -380.345453) (xy 34.087816 -380.319788)
			(xy 34.093602 -380.312635) (xy 34.100122 -380.29545) (xy 34.100516 -380.28626) (xy 34.100516 -379.794008)
			(xy 34.100098 -379.784822) (xy 34.093589 -379.767638) (xy 34.087816 -379.76048) (xy 34.065999 -379.734776)
			(xy 34.027907 -379.679148) (xy 33.996754 -379.619357) (xy 33.972986 -379.556265) (xy 33.956947 -379.49078)
			(xy 33.948867 -379.423846) (xy 33.948863 -379.356426) (xy 33.956934 -379.289491) (xy 33.972965 -379.224004)
			(xy 33.996724 -379.160909) (xy 34.02787 -379.101114) (xy 34.065954 -379.045481) (xy 34.087816 -379.019816)
			(xy 34.093633 -379.012685) (xy 34.100135 -378.995484) (xy 34.100516 -378.986288) (xy 34.100516 -378.828554)
			(xy 34.100988 -378.818427) (xy 34.108727 -378.79971) (xy 34.123017 -378.785356) (xy 34.1417 -378.777534)
			(xy 34.151824 -378.776992) (xy 34.868104 -378.776992) (xy 34.878257 -378.777418) (xy 34.897008 -378.785214)
			(xy 34.911331 -378.799609) (xy 34.919032 -378.818399) (xy 34.919412 -378.828554) (xy 34.919412 -378.986288)
			(xy 34.919825 -378.995475) (xy 34.926336 -379.012659) (xy 34.932112 -379.019816) (xy 34.954023 -379.045443)
			(xy 34.992109 -379.101083) (xy 35.023257 -379.160885) (xy 35.047018 -379.223986) (xy 35.06305 -379.28948)
			(xy 35.071122 -379.356422) (xy 35.071117 -379.42385) (xy 35.063037 -379.490791) (xy 35.046997 -379.556283)
			(xy 35.023228 -379.619381) (xy 34.992072 -379.679179) (xy 34.953978 -379.734815) (xy 34.932112 -379.76048)
			(xy 34.9263 -379.767615) (xy 34.919794 -379.784813) (xy 34.919412 -379.794008) (xy 34.919412 -380.28626)
			(xy 34.919839 -380.295446) (xy 34.92634 -380.31263) (xy 34.932112 -380.319788) (xy 34.953995 -380.345437)
			(xy 34.992083 -380.401074) (xy 35.023232 -380.460873) (xy 35.046994 -380.523972) (xy 35.063028 -380.589463)
			(xy 35.071102 -380.656403) (xy 35.071102 -380.656464) (xy 38.349165 -380.656464) (xy 38.357207 -380.589643)
			(xy 38.373176 -380.524262) (xy 38.396845 -380.461259) (xy 38.427874 -380.401536) (xy 38.465819 -380.345949)
			(xy 38.487604 -380.320296) (xy 38.493385 -380.31314) (xy 38.499909 -380.295958) (xy 38.500304 -380.286768)
			(xy 38.500304 -379.7935) (xy 38.499893 -379.784313) (xy 38.49338 -379.767129) (xy 38.487604 -379.759972)
			(xy 38.465865 -379.73428) (xy 38.427917 -379.678699) (xy 38.396884 -379.61898) (xy 38.37321 -379.555981)
			(xy 38.357234 -379.490604) (xy 38.349187 -379.423786) (xy 38.349183 -379.356486) (xy 38.357221 -379.289667)
			(xy 38.373188 -379.224288) (xy 38.396854 -379.161286) (xy 38.42788 -379.101563) (xy 38.465821 -379.045977)
			(xy 38.487604 -379.020324) (xy 38.493416 -379.01319) (xy 38.499921 -378.995991) (xy 38.500304 -378.986796)
			(xy 38.500304 -378.828554) (xy 38.500795 -378.818397) (xy 38.508578 -378.799634) (xy 38.522944 -378.785271)
			(xy 38.541709 -378.777493) (xy 38.551866 -378.776992) (xy 39.268146 -378.776992) (xy 39.278301 -378.777495)
			(xy 39.297062 -378.785276) (xy 39.311424 -378.799638) (xy 39.319205 -378.818399) (xy 39.319708 -378.828554)
			(xy 39.319708 -378.986796) (xy 39.320118 -378.995983) (xy 39.326632 -379.013168) (xy 39.332408 -379.020324)
			(xy 39.354244 -379.045937) (xy 39.392195 -379.101528) (xy 39.423229 -379.161256) (xy 39.446902 -379.224266)
			(xy 39.462873 -379.289653) (xy 39.470914 -379.356481) (xy 39.47091 -379.423791) (xy 39.46286 -379.490618)
			(xy 39.44688 -379.556003) (xy 39.4232 -379.61901) (xy 39.392158 -379.678735) (xy 39.3542 -379.734321)
			(xy 39.332408 -379.759972) (xy 39.326599 -379.767109) (xy 39.320092 -379.784306) (xy 39.319708 -379.7935)
			(xy 39.319708 -380.286768) (xy 39.320132 -380.295954) (xy 39.326636 -380.313138) (xy 39.332408 -380.320296)
			(xy 39.354217 -380.345931) (xy 39.392169 -380.401519) (xy 39.423204 -380.461244) (xy 39.446878 -380.524251)
			(xy 39.462851 -380.589636) (xy 39.470887 -380.656404) (xy 42.748933 -380.656404) (xy 42.757007 -380.589467)
			(xy 42.773041 -380.523979) (xy 42.796803 -380.460883) (xy 42.827951 -380.401087) (xy 42.866037 -380.345453)
			(xy 42.8879 -380.319788) (xy 42.893684 -380.312634) (xy 42.900206 -380.29545) (xy 42.9006 -380.28626)
			(xy 42.9006 -379.794008) (xy 42.900186 -379.784821) (xy 42.893675 -379.767637) (xy 42.8879 -379.76048)
			(xy 42.866083 -379.734776) (xy 42.827993 -379.679147) (xy 42.79684 -379.619356) (xy 42.773073 -379.556264)
			(xy 42.757035 -379.49078) (xy 42.748955 -379.423846) (xy 42.748951 -379.356426) (xy 42.757022 -379.289491)
			(xy 42.773052 -379.224005) (xy 42.796811 -379.16091) (xy 42.827956 -379.101115) (xy 42.866039 -379.045481)
			(xy 42.8879 -379.019816) (xy 42.893715 -379.012684) (xy 42.900219 -378.995483) (xy 42.9006 -378.986288)
			(xy 42.9006 -378.828554) (xy 42.901088 -378.818429) (xy 42.908823 -378.799715) (xy 42.923108 -378.785361)
			(xy 42.941786 -378.777537) (xy 42.951908 -378.776992) (xy 43.668188 -378.776992) (xy 43.67834 -378.777431)
			(xy 43.697091 -378.785221) (xy 43.711414 -378.799613) (xy 43.719116 -378.8184) (xy 43.719496 -378.828554)
			(xy 43.719496 -378.986288) (xy 43.719913 -378.995474) (xy 43.726422 -379.012659) (xy 43.732196 -379.019816)
			(xy 43.754107 -379.045442) (xy 43.792195 -379.101082) (xy 43.823344 -379.160884) (xy 43.847105 -379.223986)
			(xy 43.863138 -379.28948) (xy 43.87121 -379.356422) (xy 43.871205 -379.42385) (xy 43.863125 -379.490791)
			(xy 43.847084 -379.556283) (xy 43.823314 -379.619382) (xy 43.792158 -379.67918) (xy 43.754063 -379.734815)
			(xy 43.732196 -379.76048) (xy 43.726382 -379.767613) (xy 43.719878 -379.784813) (xy 43.719496 -379.794008)
			(xy 43.719496 -380.28626) (xy 43.719926 -380.295445) (xy 43.726426 -380.31263) (xy 43.732196 -380.319788)
			(xy 43.75408 -380.345437) (xy 43.792168 -380.401074) (xy 43.823318 -380.460872) (xy 43.847081 -380.523971)
			(xy 43.863116 -380.589462) (xy 43.87119 -380.656402) (xy 43.87119 -380.656463) (xy 73.548987 -380.656463)
			(xy 73.557029 -380.589642) (xy 73.572999 -380.524261) (xy 73.596669 -380.461258) (xy 73.6277 -380.401535)
			(xy 73.665646 -380.345948) (xy 73.687432 -380.320296) (xy 73.693217 -380.313143) (xy 73.699738 -380.295958)
			(xy 73.700132 -380.286768) (xy 73.700132 -379.7935) (xy 73.699715 -379.784314) (xy 73.693205 -379.76713)
			(xy 73.687432 -379.759972) (xy 73.665692 -379.734281) (xy 73.627742 -379.6787) (xy 73.596707 -379.618982)
			(xy 73.573032 -379.555982) (xy 73.557056 -379.490605) (xy 73.549008 -379.423787) (xy 73.549004 -379.356486)
			(xy 73.557043 -379.289666) (xy 73.573011 -379.224287) (xy 73.596678 -379.161285) (xy 73.627705 -379.101562)
			(xy 73.665648 -379.045976) (xy 73.687432 -379.020324) (xy 73.693247 -379.013192) (xy 73.69975 -378.995991)
			(xy 73.700132 -378.986796) (xy 73.700132 -378.828554) (xy 73.700596 -378.818394) (xy 73.708384 -378.799625)
			(xy 73.722759 -378.785262) (xy 73.741534 -378.777488) (xy 73.751694 -378.776992) (xy 74.467974 -378.776992)
			(xy 74.478125 -378.777553) (xy 74.496884 -378.785311) (xy 74.511249 -378.799655) (xy 74.519032 -378.818404)
			(xy 74.519536 -378.828554) (xy 74.519536 -378.986796) (xy 74.519962 -378.995981) (xy 74.526466 -379.013165)
			(xy 74.532236 -379.020324) (xy 74.554072 -379.045937) (xy 74.592021 -379.101528) (xy 74.623053 -379.161257)
			(xy 74.646725 -379.224267) (xy 74.662695 -379.289654) (xy 74.670736 -379.356481) (xy 74.670731 -379.423791)
			(xy 74.662682 -379.490617) (xy 74.646703 -379.556002) (xy 74.623024 -379.619009) (xy 74.591984 -379.678734)
			(xy 74.554028 -379.73432) (xy 74.532236 -379.759972) (xy 74.526419 -379.767102) (xy 74.519918 -379.784304)
			(xy 74.519536 -379.7935) (xy 74.519536 -380.286768) (xy 74.519976 -380.295952) (xy 74.52647 -380.313136)
			(xy 74.532236 -380.320296) (xy 74.554044 -380.345932) (xy 74.591994 -380.40152) (xy 74.623028 -380.461246)
			(xy 74.6467 -380.524252) (xy 74.662673 -380.589637) (xy 74.670709 -380.656404) (xy 77.948754 -380.656404)
			(xy 77.956829 -380.589466) (xy 77.972863 -380.523978) (xy 77.996626 -380.460882) (xy 78.027776 -380.401086)
			(xy 78.065864 -380.345453) (xy 78.087728 -380.319788) (xy 78.093516 -380.312637) (xy 78.100035 -380.295451)
			(xy 78.100428 -380.28626) (xy 78.100428 -379.794008) (xy 78.100008 -379.784822) (xy 78.093501 -379.767638)
			(xy 78.087728 -379.76048) (xy 78.06591 -379.734776) (xy 78.027818 -379.679148) (xy 77.996664 -379.619357)
			(xy 77.972896 -379.556265) (xy 77.956856 -379.490781) (xy 77.948776 -379.423846) (xy 77.948772 -379.356426)
			(xy 77.956843 -379.28949) (xy 77.972874 -379.224004) (xy 77.996634 -379.160909) (xy 78.027781 -379.101114)
			(xy 78.065866 -379.045481) (xy 78.087728 -379.019816) (xy 78.093546 -379.012686) (xy 78.100047 -378.995484)
			(xy 78.100428 -378.986288) (xy 78.100428 -378.828554) (xy 78.100889 -378.818426) (xy 78.108629 -378.799706)
			(xy 78.122923 -378.785352) (xy 78.14161 -378.777532) (xy 78.151736 -378.776992) (xy 78.868016 -378.776992)
			(xy 78.878125 -378.777472) (xy 78.896802 -378.785213) (xy 78.911096 -378.799512) (xy 78.918831 -378.818191)
			(xy 78.919324 -378.8283) (xy 78.919324 -378.986288) (xy 78.919734 -378.995475) (xy 78.926247 -379.01266)
			(xy 78.932024 -379.019816) (xy 78.953934 -379.045443) (xy 78.99202 -379.101083) (xy 79.023167 -379.160885)
			(xy 79.046928 -379.223987) (xy 79.062959 -379.28948) (xy 79.071031 -379.356423) (xy 79.071026 -379.42385)
			(xy 79.062946 -379.490791) (xy 79.046906 -379.556282) (xy 79.023138 -379.619381) (xy 78.991983 -379.679179)
			(xy 78.95389 -379.734814) (xy 78.932024 -379.76048) (xy 78.926214 -379.767616) (xy 78.919706 -379.784813)
			(xy 78.919324 -379.794008) (xy 78.919324 -380.28626) (xy 78.919748 -380.295446) (xy 78.926251 -380.312631)
			(xy 78.932024 -380.319788) (xy 78.953907 -380.345437) (xy 78.991993 -380.401075) (xy 79.023142 -380.460873)
			(xy 79.046904 -380.523972) (xy 79.062937 -380.589463) (xy 79.071011 -380.656403) (xy 79.071011 -380.656464)
			(xy 82.349074 -380.656464) (xy 82.357116 -380.589643) (xy 82.373086 -380.524262) (xy 82.396755 -380.461258)
			(xy 82.427785 -380.401535) (xy 82.46573 -380.345948) (xy 82.487516 -380.320296) (xy 82.493299 -380.313141)
			(xy 82.499821 -380.295958) (xy 82.500216 -380.286768) (xy 82.500216 -379.7935) (xy 82.499803 -379.784313)
			(xy 82.493291 -379.767129) (xy 82.487516 -379.759972) (xy 82.465776 -379.734281) (xy 82.427828 -379.678699)
			(xy 82.396794 -379.618981) (xy 82.373119 -379.555982) (xy 82.357144 -379.490604) (xy 82.349096 -379.423786)
			(xy 82.349092 -379.356486) (xy 82.357131 -379.289667) (xy 82.373098 -379.224288) (xy 82.396764 -379.161285)
			(xy 82.427791 -379.101563) (xy 82.465732 -379.045977) (xy 82.487516 -379.020324) (xy 82.493329 -379.013191)
			(xy 82.499833 -378.995991) (xy 82.500216 -378.986796) (xy 82.500216 -378.828554) (xy 82.500695 -378.818396)
			(xy 82.508481 -378.79963) (xy 82.52285 -378.785267) (xy 82.54162 -378.777491) (xy 82.551778 -378.776992)
			(xy 83.268058 -378.776992) (xy 83.278207 -378.777567) (xy 83.296967 -378.785319) (xy 83.311332 -378.799659)
			(xy 83.319116 -378.818405) (xy 83.31962 -378.828554) (xy 83.31962 -378.986796) (xy 83.320028 -378.995984)
			(xy 83.326543 -379.013168) (xy 83.33232 -379.020324) (xy 83.354156 -379.045937) (xy 83.392107 -379.101528)
			(xy 83.42314 -379.161256) (xy 83.446812 -379.224266) (xy 83.462783 -379.289654) (xy 83.470824 -379.356481)
			(xy 83.470819 -379.423791) (xy 83.46277 -379.490618) (xy 83.446791 -379.556003) (xy 83.423111 -379.61901)
			(xy 83.392069 -379.678734) (xy 83.354112 -379.734321) (xy 83.33232 -379.759972) (xy 83.326513 -379.76711)
			(xy 83.320004 -379.784306) (xy 83.31962 -379.7935) (xy 83.31962 -380.286768) (xy 83.320041 -380.295954)
			(xy 83.326547 -380.313139) (xy 83.33232 -380.320296) (xy 83.354129 -380.345931) (xy 83.392079 -380.401519)
			(xy 83.423114 -380.461245) (xy 83.446788 -380.524252) (xy 83.46276 -380.589636) (xy 83.470797 -380.656404)
			(xy 86.748842 -380.656404) (xy 86.756916 -380.589467) (xy 86.77295 -380.523979) (xy 86.796713 -380.460883)
			(xy 86.827862 -380.401087) (xy 86.865949 -380.345453) (xy 86.887812 -380.319788) (xy 86.893598 -380.312635)
			(xy 86.900118 -380.29545) (xy 86.900512 -380.28626) (xy 86.900512 -379.794008) (xy 86.900095 -379.784822)
			(xy 86.893586 -379.767637) (xy 86.887812 -379.76048) (xy 86.865995 -379.734776) (xy 86.827904 -379.679147)
			(xy 86.79675 -379.619357) (xy 86.772983 -379.556265) (xy 86.756944 -379.49078) (xy 86.748864 -379.423846)
			(xy 86.74886 -379.356426) (xy 86.756931 -379.289491) (xy 86.772962 -379.224004) (xy 86.796721 -379.160909)
			(xy 86.827867 -379.101115) (xy 86.86595 -379.045481) (xy 86.887812 -379.019816) (xy 86.893628 -379.012685)
			(xy 86.900131 -378.995483) (xy 86.900512 -378.986288) (xy 86.900512 -378.828554) (xy 86.900988 -378.818428)
			(xy 86.908726 -378.799711) (xy 86.923015 -378.785357) (xy 86.941696 -378.777535) (xy 86.95182 -378.776992)
			(xy 87.6681 -378.776992) (xy 87.678208 -378.777485) (xy 87.696884 -378.785221) (xy 87.711179 -378.799516)
			(xy 87.718915 -378.818192) (xy 87.719408 -378.8283) (xy 87.719408 -378.986288) (xy 87.719822 -378.995475)
			(xy 87.726333 -379.012659) (xy 87.732108 -379.019816) (xy 87.754019 -379.045442) (xy 87.792106 -379.101083)
			(xy 87.823254 -379.160884) (xy 87.847015 -379.223986) (xy 87.863047 -379.28948) (xy 87.871119 -379.356422)
			(xy 87.871114 -379.42385) (xy 87.863034 -379.490791) (xy 87.846994 -379.556283) (xy 87.823224 -379.619382)
			(xy 87.792068 -379.679179) (xy 87.753975 -379.734815) (xy 87.732108 -379.76048) (xy 87.726296 -379.767614)
			(xy 87.71979 -379.784813) (xy 87.719408 -379.794008) (xy 87.719408 -380.28626) (xy 87.719836 -380.295445)
			(xy 87.726337 -380.31263) (xy 87.732108 -380.319788) (xy 87.753991 -380.345437) (xy 87.792079 -380.401074)
			(xy 87.823228 -380.460873) (xy 87.846991 -380.523972) (xy 87.863025 -380.589463) (xy 87.871099 -380.656402)
			(xy 87.871097 -380.723828) (xy 87.863019 -380.790767) (xy 87.846982 -380.856257) (xy 87.838954 -380.877572)
			(xy 105.0036 -380.877572) (xy 105.0036 -380.013972) (xy 105.00409 -379.983988) (xy 105.011918 -379.924532)
			(xy 105.027439 -379.866607) (xy 105.050388 -379.811203) (xy 105.080372 -379.759269) (xy 105.116878 -379.711693)
			(xy 105.159283 -379.669288) (xy 105.206859 -379.632782) (xy 105.258793 -379.602798) (xy 105.314197 -379.579849)
			(xy 105.372122 -379.564328) (xy 105.431578 -379.5565) (xy 105.491546 -379.5565) (xy 105.551002 -379.564328)
			(xy 105.608927 -379.579849) (xy 105.664331 -379.602798) (xy 105.716265 -379.632782) (xy 105.763841 -379.669288)
			(xy 105.806246 -379.711693) (xy 105.842752 -379.759269) (xy 105.872736 -379.811203) (xy 105.895685 -379.866607)
			(xy 105.911206 -379.924532) (xy 105.919034 -379.983988) (xy 105.919524 -380.013972) (xy 105.919524 -380.656403)
			(xy 117.548873 -380.656403) (xy 117.556947 -380.589466) (xy 117.572982 -380.523977) (xy 117.596746 -380.460881)
			(xy 117.627898 -380.401085) (xy 117.665987 -380.345452) (xy 117.687852 -380.319788) (xy 117.693643 -380.312639)
			(xy 117.700159 -380.295451) (xy 117.700552 -380.28626) (xy 117.700552 -379.794008) (xy 117.700126 -379.784823)
			(xy 117.693622 -379.767639) (xy 117.687852 -379.76048) (xy 117.666033 -379.734777) (xy 117.62794 -379.679149)
			(xy 117.596784 -379.619358) (xy 117.573015 -379.556266) (xy 117.556975 -379.490781) (xy 117.548894 -379.423846)
			(xy 117.54889 -379.356426) (xy 117.556962 -379.28949) (xy 117.572994 -379.224003) (xy 117.596755 -379.160908)
			(xy 117.627903 -379.101113) (xy 117.665989 -379.04548) (xy 117.687852 -379.019816) (xy 117.693673 -379.012688)
			(xy 117.700172 -378.995484) (xy 117.700552 -378.986288) (xy 117.700552 -378.828554) (xy 117.700989 -378.818423)
			(xy 117.708734 -378.799698) (xy 117.723036 -378.785343) (xy 117.741731 -378.777528) (xy 117.75186 -378.776992)
			(xy 118.46814 -378.776992) (xy 118.478296 -378.777389) (xy 118.497047 -378.785196) (xy 118.511369 -378.7996)
			(xy 118.519069 -378.818396) (xy 118.519448 -378.828554) (xy 118.519448 -378.986288) (xy 118.519875 -378.995473)
			(xy 118.526378 -379.012657) (xy 118.532148 -379.019816) (xy 118.554061 -379.045441) (xy 118.592152 -379.10108)
			(xy 118.623303 -379.160882) (xy 118.647067 -379.223984) (xy 118.663101 -379.289478) (xy 118.671174 -379.356422)
			(xy 118.671169 -379.42385) (xy 118.663088 -379.490793) (xy 118.647046 -379.556285) (xy 118.623274 -379.619384)
			(xy 118.592115 -379.679181) (xy 118.554017 -379.734816) (xy 118.532148 -379.76048) (xy 118.526329 -379.767609)
			(xy 118.519829 -379.784812) (xy 118.519448 -379.794008) (xy 118.519448 -380.28626) (xy 118.519889 -380.295444)
			(xy 118.526382 -380.312628) (xy 118.532148 -380.319788) (xy 118.554033 -380.345436) (xy 118.592125 -380.401072)
			(xy 118.623278 -380.46087) (xy 118.647043 -380.523969) (xy 118.663079 -380.589461) (xy 118.671154 -380.656402)
			(xy 118.671154 -380.656463) (xy 121.949193 -380.656463) (xy 121.957235 -380.589642) (xy 121.973206 -380.524261)
			(xy 121.996876 -380.461257) (xy 122.027907 -380.401534) (xy 122.065854 -380.345948) (xy 122.08764 -380.320296)
			(xy 122.093426 -380.313143) (xy 122.099946 -380.295958) (xy 122.10034 -380.286768) (xy 122.10034 -379.7935)
			(xy 122.099921 -379.784314) (xy 122.093413 -379.76713) (xy 122.08764 -379.759972) (xy 122.0659 -379.734281)
			(xy 122.027949 -379.6787) (xy 121.996914 -379.618982) (xy 121.973238 -379.555982) (xy 121.957262 -379.490605)
			(xy 121.949214 -379.423787) (xy 121.94921 -379.356485) (xy 121.957249 -379.289666) (xy 121.973217 -379.224287)
			(xy 121.996884 -379.161284) (xy 122.027912 -379.101562) (xy 122.065855 -379.045976) (xy 122.08764 -379.020324)
			(xy 122.093456 -379.013193) (xy 122.099958 -378.995991) (xy 122.10034 -378.986796) (xy 122.10034 -378.828554)
			(xy 122.100796 -378.818393) (xy 122.108586 -378.799623) (xy 122.122963 -378.785259) (xy 122.141741 -378.777486)
			(xy 122.151902 -378.776992) (xy 122.868182 -378.776992) (xy 122.878333 -378.777547) (xy 122.897093 -378.785307)
			(xy 122.911457 -378.799653) (xy 122.919241 -378.818404) (xy 122.919744 -378.828554) (xy 122.919744 -378.986796)
			(xy 122.920169 -378.995981) (xy 122.926674 -379.013165) (xy 122.932444 -379.020324) (xy 122.95428 -379.045937)
			(xy 122.992228 -379.101529) (xy 123.02326 -379.161257) (xy 123.046931 -379.224267) (xy 123.062901 -379.289654)
			(xy 123.070942 -379.356482) (xy 123.070937 -379.423791) (xy 123.062888 -379.490617) (xy 123.04691 -379.556002)
			(xy 123.023231 -379.619009) (xy 122.992191 -379.678733) (xy 122.954235 -379.73432) (xy 122.932444 -379.759972)
			(xy 122.926627 -379.767103) (xy 122.920126 -379.784305) (xy 122.919744 -379.7935) (xy 122.919744 -380.286768)
			(xy 122.920182 -380.295952) (xy 122.926678 -380.313136) (xy 122.932444 -380.320296) (xy 122.954252 -380.345932)
			(xy 122.992201 -380.40152) (xy 123.023235 -380.461246) (xy 123.046907 -380.524252) (xy 123.062879 -380.589637)
			(xy 123.070915 -380.656404) (xy 126.34896 -380.656404) (xy 126.357035 -380.589466) (xy 126.373069 -380.523978)
			(xy 126.396833 -380.460881) (xy 126.427983 -380.401086) (xy 126.466072 -380.345453) (xy 126.487936 -380.319788)
			(xy 126.493725 -380.312637) (xy 126.500243 -380.295451) (xy 126.500636 -380.28626) (xy 126.500636 -379.794008)
			(xy 126.500214 -379.784822) (xy 126.493708 -379.767638) (xy 126.487936 -379.76048) (xy 126.466118 -379.734776)
			(xy 126.428025 -379.679148) (xy 126.396871 -379.619358) (xy 126.373102 -379.556266) (xy 126.357062 -379.490781)
			(xy 126.348982 -379.423846) (xy 126.348978 -379.356426) (xy 126.357049 -379.28949) (xy 126.373081 -379.224003)
			(xy 126.396841 -379.160908) (xy 126.427988 -379.101114) (xy 126.466074 -379.045481) (xy 126.487936 -379.019816)
			(xy 126.493755 -379.012687) (xy 126.500256 -378.995484) (xy 126.500636 -378.986288) (xy 126.500636 -378.828554)
			(xy 126.501089 -378.818425) (xy 126.508831 -378.799703) (xy 126.523127 -378.785349) (xy 126.541817 -378.777531)
			(xy 126.551944 -378.776992) (xy 127.268224 -378.776992) (xy 127.278379 -378.777402) (xy 127.29713 -378.785204)
			(xy 127.311452 -378.799604) (xy 127.319153 -378.818397) (xy 127.319532 -378.828554) (xy 127.319532 -378.986288)
			(xy 127.319963 -378.995473) (xy 127.326464 -379.012656) (xy 127.332232 -379.019816) (xy 127.354142 -379.045443)
			(xy 127.392227 -379.101084) (xy 127.423374 -379.160885) (xy 127.447134 -379.223987) (xy 127.463165 -379.289481)
			(xy 127.471237 -379.356423) (xy 127.471232 -379.423849) (xy 127.463152 -379.49079) (xy 127.447113 -379.556282)
			(xy 127.423345 -379.61938) (xy 127.39219 -379.679178) (xy 127.354098 -379.734814) (xy 127.332232 -379.76048)
			(xy 127.326411 -379.767607) (xy 127.319913 -379.784812) (xy 127.319532 -379.794008) (xy 127.319532 -380.28626)
			(xy 127.319977 -380.295443) (xy 127.326468 -380.312627) (xy 127.332232 -380.319788) (xy 127.354114 -380.345438)
			(xy 127.392201 -380.401075) (xy 127.423349 -380.460874) (xy 127.44711 -380.523973) (xy 127.463143 -380.589463)
			(xy 127.471217 -380.656403) (xy 127.471217 -380.656463) (xy 130.74928 -380.656463) (xy 130.757322 -380.589642)
			(xy 130.773292 -380.524262) (xy 130.796962 -380.461258) (xy 130.827992 -380.401535) (xy 130.865938 -380.345948)
			(xy 130.887724 -380.320296) (xy 130.893508 -380.313142) (xy 130.900029 -380.295958) (xy 130.900424 -380.286768)
			(xy 130.900424 -379.7935) (xy 130.900009 -379.784313) (xy 130.893498 -379.767129) (xy 130.887724 -379.759972)
			(xy 130.865984 -379.734281) (xy 130.828035 -379.678699) (xy 130.797 -379.618981) (xy 130.773326 -379.555982)
			(xy 130.75735 -379.490605) (xy 130.749302 -379.423787) (xy 130.749298 -379.356486) (xy 130.757337 -379.289667)
			(xy 130.773304 -379.224287) (xy 130.796971 -379.161285) (xy 130.827998 -379.101563) (xy 130.86594 -379.045977)
			(xy 130.887724 -379.020324) (xy 130.893538 -379.013191) (xy 130.900042 -378.995991) (xy 130.900424 -378.986796)
			(xy 130.900424 -378.828554) (xy 130.900895 -378.818395) (xy 130.908682 -378.799628) (xy 130.923054 -378.785264)
			(xy 130.941827 -378.777489) (xy 130.951986 -378.776992) (xy 131.668266 -378.776992) (xy 131.678416 -378.77756)
			(xy 131.697175 -378.785315) (xy 131.71154 -378.799657) (xy 131.719324 -378.818405) (xy 131.719828 -378.828554)
			(xy 131.719828 -378.986796) (xy 131.720234 -378.995984) (xy 131.72675 -379.013168) (xy 131.732528 -379.020324)
			(xy 131.754364 -379.045937) (xy 131.792314 -379.101528) (xy 131.823347 -379.161257) (xy 131.847018 -379.224267)
			(xy 131.862989 -379.289654) (xy 131.87103 -379.356481) (xy 131.871025 -379.423791) (xy 131.862976 -379.490617)
			(xy 131.846997 -379.556003) (xy 131.823317 -379.619009) (xy 131.792277 -379.678734) (xy 131.75432 -379.73432)
			(xy 131.732528 -379.759972) (xy 131.72671 -379.767101) (xy 131.72021 -379.784304) (xy 131.719828 -379.7935)
			(xy 131.719828 -380.286768) (xy 131.720247 -380.295954) (xy 131.726754 -380.313139) (xy 131.732528 -380.320296)
			(xy 131.754336 -380.345932) (xy 131.792287 -380.40152) (xy 131.823321 -380.461245) (xy 131.846994 -380.524252)
			(xy 131.862967 -380.589636) (xy 131.871003 -380.656404) (xy 161.548806 -380.656404) (xy 161.55688 -380.589468)
			(xy 161.572912 -380.523981) (xy 161.596672 -380.460885) (xy 161.627819 -380.401089) (xy 161.665902 -380.345454)
			(xy 161.687764 -380.319788) (xy 161.693556 -380.31264) (xy 161.700072 -380.295451) (xy 161.700464 -380.28626)
			(xy 161.700464 -379.794008) (xy 161.700036 -379.784823) (xy 161.693533 -379.767639) (xy 161.687764 -379.76048)
			(xy 161.665948 -379.734775) (xy 161.627861 -379.679146) (xy 161.59671 -379.619354) (xy 161.572945 -379.556263)
			(xy 161.556907 -379.490779) (xy 161.548828 -379.423846) (xy 161.548823 -379.356426) (xy 161.556894 -379.289492)
			(xy 161.572923 -379.224006) (xy 161.59668 -379.160911) (xy 161.627824 -379.101116) (xy 161.665904 -379.045482)
			(xy 161.687764 -379.019816) (xy 161.693587 -379.01269) (xy 161.700084 -378.995484) (xy 161.700464 -378.986288)
			(xy 161.700464 -378.828554) (xy 161.70089 -378.818421) (xy 161.708637 -378.799695) (xy 161.722942 -378.785339)
			(xy 161.741641 -378.777526) (xy 161.751772 -378.776992) (xy 162.468052 -378.776992) (xy 162.47817 -378.777455)
			(xy 162.496871 -378.785186) (xy 162.511187 -378.799488) (xy 162.518935 -378.818182) (xy 162.51936 -378.8283)
			(xy 162.51936 -378.986288) (xy 162.519785 -378.995473) (xy 162.526289 -379.012658) (xy 162.53206 -379.019816)
			(xy 162.553973 -379.045442) (xy 162.592062 -379.101081) (xy 162.623213 -379.160882) (xy 162.646977 -379.223984)
			(xy 162.66301 -379.289479) (xy 162.671083 -379.356422) (xy 162.671078 -379.42385) (xy 162.662997 -379.490792)
			(xy 162.646955 -379.556285) (xy 162.623184 -379.619384) (xy 162.592025 -379.679181) (xy 162.553928 -379.734815)
			(xy 162.53206 -379.76048) (xy 162.526242 -379.76761) (xy 162.519741 -379.784812) (xy 162.51936 -379.794008)
			(xy 162.51936 -380.28626) (xy 162.519799 -380.295444) (xy 162.526294 -380.312628) (xy 162.53206 -380.319788)
			(xy 162.553945 -380.345436) (xy 162.592036 -380.401072) (xy 162.623188 -380.460871) (xy 162.646953 -380.52397)
			(xy 162.662988 -380.589461) (xy 162.671063 -380.656402) (xy 162.671063 -380.656463) (xy 165.949102 -380.656463)
			(xy 165.957144 -380.589642) (xy 165.973115 -380.524261) (xy 165.996786 -380.461257) (xy 166.027818 -380.401534)
			(xy 166.065765 -380.345948) (xy 166.087552 -380.320296) (xy 166.093339 -380.313144) (xy 166.099858 -380.295959)
			(xy 166.100252 -380.286768) (xy 166.100252 -379.7935) (xy 166.09983 -379.784314) (xy 166.093323 -379.76713)
			(xy 166.087552 -379.759972) (xy 166.065811 -379.734281) (xy 166.02786 -379.678701) (xy 165.996824 -379.618982)
			(xy 165.973148 -379.555983) (xy 165.957171 -379.490605) (xy 165.949123 -379.423787) (xy 165.949119 -379.356485)
			(xy 165.957158 -379.289666) (xy 165.973127 -379.224286) (xy 165.996795 -379.161284) (xy 166.027823 -379.101562)
			(xy 166.065767 -379.045976) (xy 166.087552 -379.020324) (xy 166.09337 -379.013194) (xy 166.09987 -378.995992)
			(xy 166.100252 -378.986796) (xy 166.100252 -378.828554) (xy 166.100696 -378.818392) (xy 166.108488 -378.799619)
			(xy 166.122869 -378.785255) (xy 166.141651 -378.777484) (xy 166.151814 -378.776992) (xy 166.868094 -378.776992)
			(xy 166.878246 -378.777537) (xy 166.897006 -378.785301) (xy 166.91137 -378.79965) (xy 166.919153 -378.818403)
			(xy 166.919656 -378.828554) (xy 166.919656 -378.986796) (xy 166.920078 -378.995982) (xy 166.926584 -379.013166)
			(xy 166.932356 -379.020324) (xy 166.954191 -379.045937) (xy 166.992139 -379.101529) (xy 167.02317 -379.161258)
			(xy 167.046841 -379.224268) (xy 167.06281 -379.289655) (xy 167.070851 -379.356482) (xy 167.070847 -379.423791)
			(xy 167.062798 -379.490617) (xy 167.046819 -379.556001) (xy 167.023141 -379.619008) (xy 166.992102 -379.678733)
			(xy 166.954147 -379.73432) (xy 166.932356 -379.759972) (xy 166.926541 -379.767104) (xy 166.920038 -379.784305)
			(xy 166.919656 -379.7935) (xy 166.919656 -380.286768) (xy 166.920091 -380.295952) (xy 166.926588 -380.313137)
			(xy 166.932356 -380.320296) (xy 166.954164 -380.345932) (xy 166.992112 -380.40152) (xy 167.023145 -380.461246)
			(xy 167.046817 -380.524253) (xy 167.062789 -380.589637) (xy 167.070824 -380.656403) (xy 170.34887 -380.656403)
			(xy 170.356944 -380.589466) (xy 170.372979 -380.523977) (xy 170.396743 -380.460881) (xy 170.427894 -380.401086)
			(xy 170.465984 -380.345452) (xy 170.487848 -380.319788) (xy 170.493638 -380.312638) (xy 170.500155 -380.295451)
			(xy 170.500548 -380.28626) (xy 170.500548 -379.794008) (xy 170.500123 -379.784823) (xy 170.493619 -379.767639)
			(xy 170.487848 -379.76048) (xy 170.46603 -379.734777) (xy 170.427936 -379.679149) (xy 170.396781 -379.619358)
			(xy 170.373012 -379.556266) (xy 170.356971 -379.490781) (xy 170.348891 -379.423846) (xy 170.348887 -379.356426)
			(xy 170.356959 -379.28949) (xy 170.37299 -379.224003) (xy 170.396751 -379.160908) (xy 170.427899 -379.101113)
			(xy 170.465985 -379.04548) (xy 170.487848 -379.019816) (xy 170.493669 -379.012688) (xy 170.500168 -378.995484)
			(xy 170.500548 -378.986288) (xy 170.500548 -378.828554) (xy 170.500989 -378.818423) (xy 170.508734 -378.7997)
			(xy 170.523034 -378.785345) (xy 170.541727 -378.777529) (xy 170.551856 -378.776992) (xy 171.268136 -378.776992)
			(xy 171.278291 -378.777392) (xy 171.297043 -378.785198) (xy 171.311365 -378.799601) (xy 171.319065 -378.818396)
			(xy 171.319444 -378.828554) (xy 171.319444 -378.986288) (xy 171.319872 -378.995473) (xy 171.326375 -379.012657)
			(xy 171.332144 -379.019816) (xy 171.354057 -379.045441) (xy 171.392148 -379.10108) (xy 171.4233 -379.160881)
			(xy 171.447064 -379.223984) (xy 171.463098 -379.289478) (xy 171.47117 -379.356422) (xy 171.471166 -379.42385)
			(xy 171.463085 -379.490793) (xy 171.447042 -379.556285) (xy 171.42327 -379.619384) (xy 171.392111 -379.679182)
			(xy 171.354013 -379.734816) (xy 171.332144 -379.76048) (xy 171.326324 -379.767608) (xy 171.319825 -379.784812)
			(xy 171.319444 -379.794008) (xy 171.319444 -380.28626) (xy 171.319886 -380.295444) (xy 171.326379 -380.312628)
			(xy 171.332144 -380.319788) (xy 171.35403 -380.345436) (xy 171.392121 -380.401072) (xy 171.423274 -380.46087)
			(xy 171.44704 -380.523969) (xy 171.463076 -380.589461) (xy 171.471151 -380.656402) (xy 171.471151 -380.656463)
			(xy 174.74919 -380.656463) (xy 174.757232 -380.589642) (xy 174.773202 -380.524261) (xy 174.796873 -380.461258)
			(xy 174.827904 -380.401535) (xy 174.86585 -380.345948) (xy 174.887636 -380.320296) (xy 174.893421 -380.313143)
			(xy 174.899942 -380.295958) (xy 174.900336 -380.286768) (xy 174.900336 -379.7935) (xy 174.899918 -379.784314)
			(xy 174.893409 -379.76713) (xy 174.887636 -379.759972) (xy 174.865896 -379.734281) (xy 174.827946 -379.6787)
			(xy 174.796911 -379.618982) (xy 174.773235 -379.555982) (xy 174.757259 -379.490605) (xy 174.749211 -379.423787)
			(xy 174.749207 -379.356486) (xy 174.757246 -379.289666) (xy 174.773214 -379.224287) (xy 174.796881 -379.161284)
			(xy 174.827909 -379.101562) (xy 174.865851 -379.045976) (xy 174.887636 -379.020324) (xy 174.893452 -379.013193)
			(xy 174.899954 -378.995991) (xy 174.900336 -378.986796) (xy 174.900336 -378.828554) (xy 174.900796 -378.818394)
			(xy 174.908585 -378.799624) (xy 174.922961 -378.78526) (xy 174.941737 -378.777487) (xy 174.951898 -378.776992)
			(xy 175.668178 -378.776992) (xy 175.678329 -378.77755) (xy 175.697089 -378.785309) (xy 175.711453 -378.799654)
			(xy 175.719237 -378.818404) (xy 175.71974 -378.828554) (xy 175.71974 -378.986796) (xy 175.720166 -378.995981)
			(xy 175.72667 -379.013165) (xy 175.73244 -379.020324) (xy 175.754276 -379.045937) (xy 175.792225 -379.101529)
			(xy 175.823257 -379.161257) (xy 175.846928 -379.224267) (xy 175.862898 -379.289654) (xy 175.870939 -379.356481)
			(xy 175.870934 -379.423791) (xy 175.862885 -379.490617) (xy 175.846907 -379.556002) (xy 175.823227 -379.619009)
			(xy 175.792187 -379.678734) (xy 175.754231 -379.73432) (xy 175.73244 -379.759972) (xy 175.726623 -379.767102)
			(xy 175.720122 -379.784305) (xy 175.71974 -379.7935) (xy 175.71974 -380.286768) (xy 175.720179 -380.295952)
			(xy 175.726674 -380.313136) (xy 175.73244 -380.320296) (xy 175.754248 -380.345932) (xy 175.792198 -380.40152)
			(xy 175.823231 -380.461246) (xy 175.846904 -380.524252) (xy 175.862876 -380.589637) (xy 175.870919 -380.656462)
			(xy 175.870917 -380.723769) (xy 175.862871 -380.790593) (xy 175.846895 -380.855977) (xy 175.823219 -380.918982)
			(xy 175.792182 -380.978706) (xy 175.75423 -381.034292) (xy 175.73244 -381.059944) (xy 175.726635 -381.067083)
			(xy 175.720127 -381.084278) (xy 175.71974 -381.093472) (xy 175.71974 -381.251206) (xy 175.71934 -381.261381)
			(xy 175.711549 -381.28018) (xy 175.697156 -381.294565) (xy 175.678353 -381.302346) (xy 175.668178 -381.302768)
			(xy 174.951898 -381.302768) (xy 174.941741 -381.302268) (xy 174.922973 -381.294494) (xy 174.908608 -381.280131)
			(xy 174.900832 -381.261363) (xy 174.900336 -381.251206) (xy 174.900336 -381.093472) (xy 174.899931 -381.084284)
			(xy 174.893413 -381.067101) (xy 174.887636 -381.059944) (xy 174.865868 -381.034275) (xy 174.827919 -380.978691)
			(xy 174.796885 -380.91897) (xy 174.773211 -380.855968) (xy 174.757237 -380.790587) (xy 174.749191 -380.723767)
			(xy 174.74919 -380.656463) (xy 171.471151 -380.656463) (xy 171.471149 -380.723828) (xy 171.46307 -380.790769)
			(xy 171.447031 -380.85626) (xy 171.423262 -380.919358) (xy 171.392106 -380.979154) (xy 171.354011 -381.034788)
			(xy 171.332144 -381.060452) (xy 171.326336 -381.067589) (xy 171.31983 -381.084786) (xy 171.319444 -381.09398)
			(xy 171.319444 -381.251206) (xy 171.318978 -381.261335) (xy 171.311245 -381.280059) (xy 171.296952 -381.294416)
			(xy 171.278263 -381.302232) (xy 171.268136 -381.302768) (xy 170.551856 -381.302768) (xy 170.541695 -381.302414)
			(xy 170.522936 -381.294598) (xy 170.508613 -381.28018) (xy 170.50092 -381.26137) (xy 170.500548 -381.251206)
			(xy 170.500548 -381.09398) (xy 170.500137 -381.084793) (xy 170.493623 -381.067609) (xy 170.487848 -381.060452)
			(xy 170.466002 -381.034771) (xy 170.42791 -380.97914) (xy 170.396755 -380.919347) (xy 170.372988 -380.856252)
			(xy 170.35695 -380.790764) (xy 170.348871 -380.723827) (xy 170.34887 -380.656403) (xy 167.070824 -380.656403)
			(xy 167.070831 -380.656462) (xy 167.070829 -380.723768) (xy 167.062783 -380.790592) (xy 167.046808 -380.855976)
			(xy 167.023133 -380.918981) (xy 166.992097 -380.978705) (xy 166.954145 -381.034292) (xy 166.932356 -381.059944)
			(xy 166.926553 -381.067084) (xy 166.920043 -381.084279) (xy 166.919656 -381.093472) (xy 166.919656 -381.251206)
			(xy 166.919171 -381.261365) (xy 166.911394 -381.280135) (xy 166.897025 -381.2945) (xy 166.878253 -381.302274)
			(xy 166.868094 -381.302768) (xy 166.151814 -381.302768) (xy 166.141644 -381.302325) (xy 166.122851 -381.294546)
			(xy 166.108466 -381.280166) (xy 166.100679 -381.261376) (xy 166.100252 -381.251206) (xy 166.100252 -381.093472)
			(xy 166.099844 -381.084285) (xy 166.093327 -381.067101) (xy 166.087552 -381.059944) (xy 166.065784 -381.034276)
			(xy 166.027833 -380.978692) (xy 165.996799 -380.918971) (xy 165.973124 -380.855968) (xy 165.957149 -380.790588)
			(xy 165.949103 -380.723767) (xy 165.949102 -380.656463) (xy 162.671063 -380.656463) (xy 162.671061 -380.723828)
			(xy 162.662983 -380.790768) (xy 162.646944 -380.856259) (xy 162.623176 -380.919357) (xy 162.59202 -380.979153)
			(xy 162.553927 -381.034787) (xy 162.53206 -381.060452) (xy 162.526254 -381.06759) (xy 162.519746 -381.084786)
			(xy 162.51936 -381.09398) (xy 162.51936 -381.251206) (xy 162.518878 -381.261333) (xy 162.511148 -381.280054)
			(xy 162.496861 -381.29441) (xy 162.478177 -381.302229) (xy 162.468052 -381.302768) (xy 161.751772 -381.302768)
			(xy 161.741644 -381.302406) (xy 161.722933 -381.294643) (xy 161.708619 -381.28031) (xy 161.70088 -381.261589)
			(xy 161.700464 -381.25146) (xy 161.700464 -381.09398) (xy 161.700049 -381.084794) (xy 161.693537 -381.06761)
			(xy 161.687764 -381.060452) (xy 161.665921 -381.03477) (xy 161.627834 -380.979137) (xy 161.596684 -380.919343)
			(xy 161.572921 -380.856248) (xy 161.556885 -380.790762) (xy 161.548808 -380.723826) (xy 161.548806 -380.656404)
			(xy 131.871003 -380.656404) (xy 131.87101 -380.656461) (xy 131.871008 -380.723769) (xy 131.862961 -380.790593)
			(xy 131.846985 -380.855977) (xy 131.823309 -380.918982) (xy 131.792271 -380.978706) (xy 131.754318 -381.034292)
			(xy 131.732528 -381.059944) (xy 131.726722 -381.067082) (xy 131.720215 -381.084278) (xy 131.719828 -381.093472)
			(xy 131.719828 -381.251206) (xy 131.71944 -381.261382) (xy 131.711647 -381.280184) (xy 131.69725 -381.294569)
			(xy 131.678443 -381.302348) (xy 131.668266 -381.302768) (xy 130.951986 -381.302768) (xy 130.941828 -381.302278)
			(xy 130.92306 -381.2945) (xy 130.908695 -381.280133) (xy 130.90092 -381.261364) (xy 130.900424 -381.251206)
			(xy 130.900424 -381.093472) (xy 130.900022 -381.084284) (xy 130.893502 -381.0671) (xy 130.887724 -381.059944)
			(xy 130.865956 -381.034276) (xy 130.828008 -380.978691) (xy 130.796975 -380.91897) (xy 130.773301 -380.855967)
			(xy 130.757327 -380.790587) (xy 130.749282 -380.723767) (xy 130.74928 -380.656463) (xy 127.471217 -380.656463)
			(xy 127.471215 -380.723827) (xy 127.463138 -380.790766) (xy 127.447101 -380.856256) (xy 127.423336 -380.919354)
			(xy 127.392185 -380.979151) (xy 127.354096 -381.034786) (xy 127.332232 -381.060452) (xy 127.326423 -381.067588)
			(xy 127.319918 -381.084786) (xy 127.319532 -381.09398) (xy 127.319532 -381.251206) (xy 127.319077 -381.261337)
			(xy 127.311342 -381.280063) (xy 127.297046 -381.29442) (xy 127.278352 -381.302234) (xy 127.268224 -381.302768)
			(xy 126.551944 -381.302768) (xy 126.541789 -381.302342) (xy 126.523031 -381.294555) (xy 126.508705 -381.280159)
			(xy 126.50101 -381.261363) (xy 126.500636 -381.251206) (xy 126.500636 -381.09398) (xy 126.500227 -381.084793)
			(xy 126.493712 -381.067609) (xy 126.487936 -381.060452) (xy 126.46609 -381.034771) (xy 126.427999 -380.97914)
			(xy 126.396845 -380.919346) (xy 126.373078 -380.856251) (xy 126.35704 -380.790764) (xy 126.348962 -380.723826)
			(xy 126.34896 -380.656404) (xy 123.070915 -380.656404) (xy 123.070922 -380.656462) (xy 123.07092 -380.723769)
			(xy 123.062874 -380.790593) (xy 123.046898 -380.855976) (xy 123.023223 -380.918982) (xy 122.992186 -380.978706)
			(xy 122.954234 -381.034292) (xy 122.932444 -381.059944) (xy 122.926639 -381.067083) (xy 122.920131 -381.084279)
			(xy 122.919744 -381.093472) (xy 122.919744 -381.251206) (xy 122.919341 -381.26138) (xy 122.91155 -381.280178)
			(xy 122.897158 -381.294564) (xy 122.878356 -381.302345) (xy 122.868182 -381.302768) (xy 122.151902 -381.302768)
			(xy 122.141745 -381.302265) (xy 122.122977 -381.294492) (xy 122.108612 -381.28013) (xy 122.100836 -381.261363)
			(xy 122.10034 -381.251206) (xy 122.10034 -381.093472) (xy 122.099934 -381.084285) (xy 122.093417 -381.067101)
			(xy 122.08764 -381.059944) (xy 122.065872 -381.034276) (xy 122.027923 -380.978691) (xy 121.996888 -380.91897)
			(xy 121.973215 -380.855968) (xy 121.95724 -380.790588) (xy 121.949194 -380.723767) (xy 121.949193 -380.656463)
			(xy 118.671154 -380.656463) (xy 118.671152 -380.723828) (xy 118.663073 -380.790769) (xy 118.647034 -380.85626)
			(xy 118.623265 -380.919357) (xy 118.592109 -380.979154) (xy 118.554015 -381.034788) (xy 118.532148 -381.060452)
			(xy 118.52634 -381.067589) (xy 118.519834 -381.084786) (xy 118.519448 -381.09398) (xy 118.519448 -381.251206)
			(xy 118.518978 -381.261335) (xy 118.511246 -381.280058) (xy 118.496954 -381.294415) (xy 118.478266 -381.302231)
			(xy 118.46814 -381.302768) (xy 117.75186 -381.302768) (xy 117.741699 -381.30241) (xy 117.72294 -381.294596)
			(xy 117.708617 -381.280179) (xy 117.700924 -381.261369) (xy 117.700552 -381.251206) (xy 117.700552 -381.09398)
			(xy 117.70014 -381.084793) (xy 117.693626 -381.06761) (xy 117.687852 -381.060452) (xy 117.666006 -381.034771)
			(xy 117.627913 -380.97914) (xy 117.596759 -380.919347) (xy 117.572991 -380.856252) (xy 117.556953 -380.790764)
			(xy 117.548874 -380.723827) (xy 117.548873 -380.656403) (xy 105.919524 -380.656403) (xy 105.919524 -380.877572)
			(xy 105.919034 -380.907556) (xy 105.911206 -380.967012) (xy 105.895685 -381.024937) (xy 105.872736 -381.080341)
			(xy 105.842752 -381.132275) (xy 105.806246 -381.179851) (xy 105.763841 -381.222256) (xy 105.716265 -381.258762)
			(xy 105.664331 -381.288746) (xy 105.608927 -381.311695) (xy 105.551002 -381.327216) (xy 105.491546 -381.335044)
			(xy 105.431578 -381.335044) (xy 105.372122 -381.327216) (xy 105.314197 -381.311695) (xy 105.258793 -381.288746)
			(xy 105.206859 -381.258762) (xy 105.159283 -381.222256) (xy 105.116878 -381.179851) (xy 105.080372 -381.132275)
			(xy 105.050388 -381.080341) (xy 105.027439 -381.024937) (xy 105.011918 -380.967012) (xy 105.00409 -380.907556)
			(xy 105.0036 -380.877572) (xy 87.838954 -380.877572) (xy 87.823216 -380.919355) (xy 87.792063 -380.979152)
			(xy 87.753973 -381.034787) (xy 87.732108 -381.060452) (xy 87.726308 -381.067595) (xy 87.719795 -381.084787)
			(xy 87.719408 -381.09398) (xy 87.719408 -381.251206) (xy 87.71888 -381.261327) (xy 87.711159 -381.280039)
			(xy 87.696886 -381.294394) (xy 87.678218 -381.302221) (xy 87.6681 -381.302768) (xy 86.95182 -381.302768)
			(xy 86.941695 -381.302367) (xy 86.922985 -381.294619) (xy 86.908669 -381.280298) (xy 86.900929 -381.261585)
			(xy 86.900512 -381.25146) (xy 86.900512 -381.09398) (xy 86.900109 -381.084792) (xy 86.89359 -381.067608)
			(xy 86.887812 -381.060452) (xy 86.865967 -381.034771) (xy 86.827877 -380.979139) (xy 86.796725 -380.919345)
			(xy 86.772959 -380.85625) (xy 86.756922 -380.790763) (xy 86.748844 -380.723826) (xy 86.748842 -380.656404)
			(xy 83.470797 -380.656404) (xy 83.470804 -380.656461) (xy 83.470802 -380.723769) (xy 83.462755 -380.790593)
			(xy 83.446779 -380.855977) (xy 83.423102 -380.918983) (xy 83.392064 -380.978706) (xy 83.35411 -381.034292)
			(xy 83.33232 -381.059944) (xy 83.326525 -381.06709) (xy 83.320009 -381.08428) (xy 83.31962 -381.093472)
			(xy 83.31962 -381.251206) (xy 83.31924 -381.261383) (xy 83.311445 -381.280186) (xy 83.297046 -381.294572)
			(xy 83.278236 -381.302349) (xy 83.268058 -381.302768) (xy 82.551778 -381.302768) (xy 82.54162 -381.302285)
			(xy 82.522851 -381.294504) (xy 82.508487 -381.280136) (xy 82.500712 -381.261365) (xy 82.500216 -381.251206)
			(xy 82.500216 -381.093472) (xy 82.499816 -381.084284) (xy 82.493295 -381.0671) (xy 82.487516 -381.059944)
			(xy 82.465749 -381.034275) (xy 82.427801 -380.978691) (xy 82.396768 -380.918969) (xy 82.373095 -380.855967)
			(xy 82.357121 -380.790587) (xy 82.349076 -380.723767) (xy 82.349074 -380.656464) (xy 79.071011 -380.656464)
			(xy 79.071009 -380.723827) (xy 79.062932 -380.790767) (xy 79.046895 -380.856256) (xy 79.02313 -380.919354)
			(xy 78.991978 -380.979151) (xy 78.953888 -381.034786) (xy 78.932024 -381.060452) (xy 78.926226 -381.067596)
			(xy 78.919711 -381.084787) (xy 78.919324 -381.09398) (xy 78.919324 -381.251206) (xy 78.918877 -381.261337)
			(xy 78.911141 -381.280066) (xy 78.896842 -381.294423) (xy 78.878145 -381.302235) (xy 78.868016 -381.302768)
			(xy 78.151736 -381.302768) (xy 78.141612 -381.302354) (xy 78.122903 -381.294611) (xy 78.108586 -381.280294)
			(xy 78.100846 -381.261584) (xy 78.100428 -381.25146) (xy 78.100428 -381.09398) (xy 78.100021 -381.084793)
			(xy 78.093505 -381.067609) (xy 78.087728 -381.060452) (xy 78.065883 -381.034771) (xy 78.027792 -380.979139)
			(xy 77.996638 -380.919346) (xy 77.972872 -380.856251) (xy 77.956834 -380.790763) (xy 77.948756 -380.723826)
			(xy 77.948754 -380.656404) (xy 74.670709 -380.656404) (xy 74.670716 -380.656462) (xy 74.670714 -380.723769)
			(xy 74.662667 -380.790593) (xy 74.646691 -380.855977) (xy 74.623015 -380.918982) (xy 74.591978 -380.978706)
			(xy 74.554026 -381.034292) (xy 74.532236 -381.059944) (xy 74.52643 -381.067082) (xy 74.519923 -381.084278)
			(xy 74.519536 -381.093472) (xy 74.519536 -381.251206) (xy 74.51914 -381.261381) (xy 74.511349 -381.280181)
			(xy 74.496954 -381.294567) (xy 74.478149 -381.302347) (xy 74.467974 -381.302768) (xy 73.751694 -381.302768)
			(xy 73.741537 -381.302272) (xy 73.722769 -381.294496) (xy 73.708404 -381.280131) (xy 73.700628 -381.261363)
			(xy 73.700132 -381.251206) (xy 73.700132 -381.093472) (xy 73.699728 -381.084284) (xy 73.693209 -381.0671)
			(xy 73.687432 -381.059944) (xy 73.665664 -381.034275) (xy 73.627715 -380.978691) (xy 73.596682 -380.91897)
			(xy 73.573008 -380.855967) (xy 73.557034 -380.790587) (xy 73.548988 -380.723767) (xy 73.548987 -380.656463)
			(xy 43.87119 -380.656463) (xy 43.871188 -380.723828) (xy 43.86311 -380.790767) (xy 43.847073 -380.856258)
			(xy 43.823306 -380.919355) (xy 43.792153 -380.979152) (xy 43.754061 -381.034787) (xy 43.732196 -381.060452)
			(xy 43.726394 -381.067594) (xy 43.719883 -381.084787) (xy 43.719496 -381.09398) (xy 43.719496 -381.251206)
			(xy 43.718979 -381.261329) (xy 43.711256 -381.280043) (xy 43.69698 -381.294398) (xy 43.678308 -381.302223)
			(xy 43.668188 -381.302768) (xy 42.951908 -381.302768) (xy 42.94175 -381.302371) (xy 42.922992 -381.294572)
			(xy 42.908667 -381.280167) (xy 42.900973 -381.261366) (xy 42.9006 -381.251206) (xy 42.9006 -381.09398)
			(xy 42.9002 -381.084792) (xy 42.893679 -381.067607) (xy 42.8879 -381.060452) (xy 42.866056 -381.034771)
			(xy 42.827966 -380.979138) (xy 42.796815 -380.919344) (xy 42.773049 -380.85625) (xy 42.757013 -380.790763)
			(xy 42.748935 -380.723826) (xy 42.748933 -380.656404) (xy 39.470887 -380.656404) (xy 39.470894 -380.656461)
			(xy 39.470893 -380.723769) (xy 39.462846 -380.790594) (xy 39.446869 -380.855978) (xy 39.423192 -380.918983)
			(xy 39.392153 -380.978707) (xy 39.354199 -381.034293) (xy 39.332408 -381.059944) (xy 39.326611 -381.067089)
			(xy 39.320096 -381.08428) (xy 39.319708 -381.093472) (xy 39.319708 -381.251206) (xy 39.319173 -381.261358)
			(xy 39.311405 -381.280119) (xy 39.297052 -381.294482) (xy 39.278298 -381.302265) (xy 39.268146 -381.302768)
			(xy 38.551866 -381.302768) (xy 38.541707 -381.302295) (xy 38.522938 -381.29451) (xy 38.508574 -381.280138)
			(xy 38.5008 -381.261365) (xy 38.500304 -381.251206) (xy 38.500304 -381.093472) (xy 38.499907 -381.084283)
			(xy 38.493384 -381.067099) (xy 38.487604 -381.059944) (xy 38.465837 -381.034275) (xy 38.42789 -380.97869)
			(xy 38.396858 -380.918969) (xy 38.373185 -380.855966) (xy 38.357212 -380.790587) (xy 38.349167 -380.723766)
			(xy 38.349165 -380.656464) (xy 35.071102 -380.656464) (xy 35.0711 -380.723828) (xy 35.063023 -380.790767)
			(xy 35.046985 -380.856257) (xy 35.023219 -380.919355) (xy 34.992067 -380.979151) (xy 34.953977 -381.034787)
			(xy 34.932112 -381.060452) (xy 34.926312 -381.067595) (xy 34.919799 -381.084787) (xy 34.919412 -381.09398)
			(xy 34.919412 -381.251206) (xy 34.91888 -381.261327) (xy 34.91116 -381.280038) (xy 34.896888 -381.294392)
			(xy 34.878222 -381.30222) (xy 34.868104 -381.302768) (xy 34.151824 -381.302768) (xy 34.141667 -381.302358)
			(xy 34.122909 -381.294565) (xy 34.108584 -381.280164) (xy 34.100889 -381.261365) (xy 34.100516 -381.251206)
			(xy 34.100516 -381.09398) (xy 34.100112 -381.084792) (xy 34.093594 -381.067608) (xy 34.087816 -381.060452)
			(xy 34.065971 -381.034771) (xy 34.027881 -380.979139) (xy 33.996728 -380.919345) (xy 33.972962 -380.85625)
			(xy 33.956925 -380.790763) (xy 33.948847 -380.723826) (xy 33.948845 -380.656404) (xy 30.6708 -380.656404)
			(xy 30.670807 -380.656461) (xy 30.670805 -380.723769) (xy 30.662758 -380.790593) (xy 30.646782 -380.855977)
			(xy 30.623105 -380.918982) (xy 30.592068 -380.978706) (xy 30.554114 -381.034292) (xy 30.532324 -381.059944)
			(xy 30.526529 -381.067091) (xy 30.520013 -381.08428) (xy 30.519624 -381.093472) (xy 30.519624 -381.251206)
			(xy 30.51924 -381.261383) (xy 30.511446 -381.280185) (xy 30.497048 -381.294571) (xy 30.478239 -381.302349)
			(xy 30.468062 -381.302768) (xy 29.751782 -381.302768) (xy 29.741624 -381.302282) (xy 29.722855 -381.294502)
			(xy 29.708491 -381.280135) (xy 29.700716 -381.261364) (xy 29.70022 -381.251206) (xy 29.70022 -381.093472)
			(xy 29.699819 -381.084284) (xy 29.693298 -381.0671) (xy 29.68752 -381.059944) (xy 29.665752 -381.034276)
			(xy 29.627804 -380.978691) (xy 29.596771 -380.918969) (xy 29.573098 -380.855967) (xy 29.557124 -380.790587)
			(xy 29.549079 -380.723767) (xy 29.549077 -380.656463) (xy 29.557119 -380.589643) (xy 29.573089 -380.524262)
			(xy 29.596759 -380.461258) (xy 29.627789 -380.401535) (xy 29.665734 -380.345948) (xy 29.68752 -380.320296)
			(xy 29.693303 -380.313141) (xy 29.699825 -380.295958) (xy 29.70022 -380.286768) (xy 29.70022 -379.7935)
			(xy 29.699806 -379.784313) (xy 29.693295 -379.767129) (xy 29.68752 -379.759972) (xy 29.66573 -379.734322)
			(xy 29.627781 -379.678735) (xy 29.596748 -379.619011) (xy 29.573075 -379.556006) (xy 29.557102 -379.490624)
			(xy 29.549058 -379.423801) (xy 28.447 -379.423801) (xy 28.447041 -379.423909) (xy 28.463077 -379.489397)
			(xy 28.471153 -379.556335) (xy 28.471153 -379.623759) (xy 28.463078 -379.690697) (xy 28.447043 -379.756186)
			(xy 28.423279 -379.819282) (xy 28.392128 -379.879078) (xy 28.35404 -379.934713) (xy 28.332176 -379.960378)
			(xy 28.326361 -379.96751) (xy 28.319858 -379.984711) (xy 28.319476 -379.993906) (xy 28.319476 -380.151386)
			(xy 28.318962 -380.16151) (xy 28.311242 -380.180228) (xy 28.296964 -380.194584) (xy 28.278289 -380.202406)
			(xy 28.268168 -380.202948) (xy 27.551888 -380.202948) (xy 27.541784 -380.202426) (xy 27.523115 -380.194693)
			(xy 27.508823 -380.180408) (xy 27.50108 -380.161743) (xy 27.50058 -380.15164) (xy 27.50058 -379.993906)
			(xy 27.500171 -379.984719) (xy 27.493657 -379.967534) (xy 27.48788 -379.960378) (xy 27.466012 -379.934716)
			(xy 27.427923 -379.879081) (xy 27.396771 -379.819285) (xy 27.373007 -379.756187) (xy 27.356972 -379.690698)
			(xy 27.348896 -379.623759) (xy 27.348896 -379.556335) (xy 27.356973 -379.489396) (xy 27.373009 -379.423907)
			(xy 27.396774 -379.36081) (xy 27.427926 -379.301013) (xy 27.466015 -379.245379) (xy 27.48788 -379.219714)
			(xy 27.493693 -379.21258) (xy 27.500199 -379.195381) (xy 27.50058 -379.186186) (xy 27.50058 -378.693934)
			(xy 27.500158 -378.684748) (xy 27.493653 -378.667563) (xy 27.48788 -378.660406) (xy 27.465991 -378.634761)
			(xy 27.427905 -378.579124) (xy 27.396756 -378.519324) (xy 27.372994 -378.456225) (xy 27.356961 -378.390733)
			(xy 27.348888 -378.323793) (xy 0.509016 -378.323793) (xy 0.509016 -382.223705) (xy 27.348899 -382.223705)
			(xy 27.3489 -382.15628) (xy 27.356976 -382.089342) (xy 27.373012 -382.023853) (xy 27.396777 -381.960755)
			(xy 27.427928 -381.900959) (xy 27.466016 -381.845324) (xy 27.48788 -381.819658) (xy 27.493675 -381.812511)
			(xy 27.500191 -381.795322) (xy 27.50058 -381.78613) (xy 27.50058 -381.628904) (xy 27.501088 -381.618798)
			(xy 27.508821 -381.600124) (xy 27.52311 -381.58583) (xy 27.541782 -381.578091) (xy 27.551888 -381.577596)
			(xy 28.268168 -381.577596) (xy 28.278288 -381.578042) (xy 28.29699 -381.585779) (xy 28.311306 -381.600086)
			(xy 28.319053 -381.618784) (xy 28.319476 -381.628904) (xy 28.319476 -381.78613) (xy 28.319877 -381.795318)
			(xy 28.326398 -381.812502) (xy 28.332176 -381.819658) (xy 28.354031 -381.845331) (xy 28.392122 -381.900964)
			(xy 28.423274 -381.960759) (xy 28.44704 -382.023855) (xy 28.463077 -382.089343) (xy 28.471154 -382.156281)
			(xy 28.471155 -382.223646) (xy 31.749194 -382.223646) (xy 31.749195 -382.156339) (xy 31.757241 -382.089516)
			(xy 31.773216 -382.024132) (xy 31.796891 -381.961127) (xy 31.827927 -381.901404) (xy 31.865879 -381.845818)
			(xy 31.887668 -381.820166) (xy 31.89347 -381.813025) (xy 31.899979 -381.795831) (xy 31.900368 -381.786638)
			(xy 31.900368 -381.628904) (xy 31.900824 -381.618754) (xy 31.908613 -381.600008) (xy 31.922998 -381.585686)
			(xy 31.941778 -381.57798) (xy 31.95193 -381.577596) (xy 32.66821 -381.577596) (xy 32.678332 -381.578117)
			(xy 32.697045 -381.58584) (xy 32.711399 -381.600115) (xy 32.719226 -381.618785) (xy 32.719772 -381.628904)
			(xy 32.719772 -381.786638) (xy 32.72017 -381.795826) (xy 32.726693 -381.81301) (xy 32.732472 -381.820166)
			(xy 32.75425 -381.845826) (xy 32.792198 -381.901412) (xy 32.823231 -381.961134) (xy 32.846904 -382.024138)
			(xy 32.862877 -382.089519) (xy 32.870922 -382.15634) (xy 32.870923 -382.223645) (xy 32.870916 -382.223704)
			(xy 36.148987 -382.223704) (xy 36.148988 -382.156281) (xy 36.157064 -382.089342) (xy 36.1731 -382.023853)
			(xy 36.196863 -381.960756) (xy 36.228013 -381.900959) (xy 36.266101 -381.845324) (xy 36.287964 -381.819658)
			(xy 36.293769 -381.812519) (xy 36.300277 -381.795323) (xy 36.300664 -381.78613) (xy 36.300664 -381.628904)
			(xy 36.301188 -381.6188) (xy 36.308917 -381.600129) (xy 36.323202 -381.585835) (xy 36.341868 -381.578094)
			(xy 36.351972 -381.577596) (xy 37.068252 -381.577596) (xy 37.078371 -381.578055) (xy 37.097073 -381.585787)
			(xy 37.111388 -381.60009) (xy 37.119136 -381.618786) (xy 37.11956 -381.628904) (xy 37.11956 -381.78613)
			(xy 37.119965 -381.795318) (xy 37.126483 -381.812501) (xy 37.13226 -381.819658) (xy 37.154116 -381.845331)
			(xy 37.192207 -381.900963) (xy 37.223361 -381.960758) (xy 37.247127 -382.023854) (xy 37.263164 -382.089343)
			(xy 37.271242 -382.156281) (xy 37.271243 -382.223704) (xy 37.271243 -382.223705) (xy 40.548753 -382.223705)
			(xy 40.548754 -382.15628) (xy 40.556832 -382.08934) (xy 40.57287 -382.02385) (xy 40.596638 -381.960752)
			(xy 40.627792 -381.900956) (xy 40.665886 -381.845322) (xy 40.687752 -381.819658) (xy 40.693555 -381.812518)
			(xy 40.700065 -381.795323) (xy 40.700452 -381.78613) (xy 40.700452 -381.628904) (xy 40.700987 -381.618801)
			(xy 40.708715 -381.600133) (xy 40.722996 -381.585839) (xy 40.741658 -381.578096) (xy 40.75176 -381.577596)
			(xy 41.46804 -381.577596) (xy 41.478151 -381.578052) (xy 41.496829 -381.585802) (xy 41.511122 -381.600108)
			(xy 41.518856 -381.618793) (xy 41.519348 -381.628904) (xy 41.519348 -381.78613) (xy 41.519755 -381.795317)
			(xy 41.526272 -381.812501) (xy 41.532048 -381.819658) (xy 41.553904 -381.84533) (xy 41.591996 -381.900963)
			(xy 41.62315 -381.960757) (xy 41.646917 -382.023853) (xy 41.662955 -382.089342) (xy 41.671033 -382.156281)
			(xy 41.671034 -382.223645) (xy 44.949073 -382.223645) (xy 44.949074 -382.15634) (xy 44.957119 -382.089516)
			(xy 44.973093 -382.024133) (xy 44.996767 -381.961128) (xy 45.027801 -381.901405) (xy 45.065751 -381.845818)
			(xy 45.08754 -381.820166) (xy 45.093339 -381.813022) (xy 45.099851 -381.795831) (xy 45.10024 -381.786638)
			(xy 45.10024 -381.628904) (xy 45.100626 -381.618745) (xy 45.108427 -381.599985) (xy 45.122836 -381.58566)
			(xy 45.141641 -381.577968) (xy 45.151802 -381.577596) (xy 45.868082 -381.577596) (xy 45.878202 -381.57814)
			(xy 45.896915 -381.585854) (xy 45.91127 -381.600122) (xy 45.919098 -381.618787) (xy 45.919644 -381.628904)
			(xy 45.919644 -381.786638) (xy 45.920049 -381.795826) (xy 45.926568 -381.813009) (xy 45.932344 -381.820166)
			(xy 45.954122 -381.845826) (xy 45.992072 -381.901411) (xy 46.023107 -381.961133) (xy 46.046781 -382.024137)
			(xy 46.062755 -382.089518) (xy 46.070801 -382.15634) (xy 46.070801 -382.223645) (xy 46.070794 -382.223705)
			(xy 71.348808 -382.223705) (xy 71.348809 -382.15628) (xy 71.356886 -382.089342) (xy 71.372922 -382.023852)
			(xy 71.396687 -381.960755) (xy 71.427838 -381.900958) (xy 71.465928 -381.845323) (xy 71.487792 -381.819658)
			(xy 71.493588 -381.812512) (xy 71.500103 -381.795322) (xy 71.500492 -381.78613) (xy 71.500492 -381.628904)
			(xy 71.500919 -381.618783) (xy 71.508664 -381.600081) (xy 71.522977 -381.585767) (xy 71.541679 -381.57802)
			(xy 71.5518 -381.577596) (xy 72.26808 -381.577596) (xy 72.278201 -381.578032) (xy 72.296903 -381.585773)
			(xy 72.311218 -381.600083) (xy 72.318965 -381.618783) (xy 72.319388 -381.628904) (xy 72.319388 -381.78613)
			(xy 72.319786 -381.795318) (xy 72.326308 -381.812503) (xy 72.332088 -381.819658) (xy 72.353943 -381.845331)
			(xy 72.392032 -381.900964) (xy 72.423184 -381.960759) (xy 72.446949 -382.023855) (xy 72.462986 -382.089343)
			(xy 72.471063 -382.156281) (xy 72.471064 -382.223646) (xy 75.749104 -382.223646) (xy 75.749104 -382.156339)
			(xy 75.75715 -382.089515) (xy 75.773125 -382.024132) (xy 75.796801 -381.961127) (xy 75.827838 -381.901403)
			(xy 75.86579 -381.845818) (xy 75.88758 -381.820166) (xy 75.893371 -381.813017) (xy 75.89989 -381.795829)
			(xy 75.90028 -381.786638) (xy 75.90028 -381.628904) (xy 75.900725 -381.618753) (xy 75.908515 -381.600004)
			(xy 75.922904 -381.585681) (xy 75.941689 -381.577978) (xy 75.951842 -381.577596) (xy 76.668122 -381.577596)
			(xy 76.678245 -381.578107) (xy 76.696958 -381.585834) (xy 76.711312 -381.600112) (xy 76.719138 -381.618784)
			(xy 76.719684 -381.628904) (xy 76.719684 -381.786638) (xy 76.720079 -381.795827) (xy 76.726604 -381.813011)
			(xy 76.732384 -381.820166) (xy 76.754161 -381.845826) (xy 76.792109 -381.901412) (xy 76.823141 -381.961135)
			(xy 76.846814 -382.024138) (xy 76.862787 -382.089519) (xy 76.870831 -382.156341) (xy 76.870832 -382.223644)
			(xy 76.870825 -382.223704) (xy 80.148896 -382.223704) (xy 80.148897 -382.15628) (xy 80.156973 -382.089342)
			(xy 80.173009 -382.023853) (xy 80.196773 -381.960755) (xy 80.227924 -381.900959) (xy 80.266012 -381.845324)
			(xy 80.287876 -381.819658) (xy 80.29367 -381.812511) (xy 80.300187 -381.795322) (xy 80.300576 -381.78613)
			(xy 80.300576 -381.628904) (xy 80.301088 -381.618798) (xy 80.30882 -381.600125) (xy 80.323108 -381.585831)
			(xy 80.341779 -381.578092) (xy 80.351884 -381.577596) (xy 81.068164 -381.577596) (xy 81.078284 -381.578046)
			(xy 81.096986 -381.585781) (xy 81.111301 -381.600087) (xy 81.119048 -381.618785) (xy 81.119472 -381.628904)
			(xy 81.119472 -381.78613) (xy 81.119874 -381.795318) (xy 81.126394 -381.812502) (xy 81.132172 -381.819658)
			(xy 81.154027 -381.845331) (xy 81.192118 -381.900964) (xy 81.223271 -381.960759) (xy 81.247037 -382.023854)
			(xy 81.263074 -382.089343) (xy 81.271151 -382.156281) (xy 81.271152 -382.223704) (xy 84.548687 -382.223704)
			(xy 84.548688 -382.156281) (xy 84.556764 -382.089342) (xy 84.5728 -382.023853) (xy 84.596563 -381.960756)
			(xy 84.627713 -381.900959) (xy 84.665801 -381.845324) (xy 84.687664 -381.819658) (xy 84.693469 -381.812519)
			(xy 84.699977 -381.795323) (xy 84.700364 -381.78613) (xy 84.700364 -381.628904) (xy 84.700888 -381.6188)
			(xy 84.708617 -381.600129) (xy 84.722902 -381.585835) (xy 84.741568 -381.578094) (xy 84.751672 -381.577596)
			(xy 85.467952 -381.577596) (xy 85.478071 -381.578055) (xy 85.496773 -381.585787) (xy 85.511088 -381.60009)
			(xy 85.518836 -381.618786) (xy 85.51926 -381.628904) (xy 85.51926 -381.78613) (xy 85.519665 -381.795318)
			(xy 85.526183 -381.812501) (xy 85.53196 -381.819658) (xy 85.553816 -381.845331) (xy 85.591907 -381.900963)
			(xy 85.623061 -381.960758) (xy 85.646827 -382.023854) (xy 85.662864 -382.089343) (xy 85.670942 -382.156281)
			(xy 85.670943 -382.223646) (xy 88.948982 -382.223646) (xy 88.948983 -382.156339) (xy 88.957028 -382.089516)
			(xy 88.973003 -382.024133) (xy 88.996677 -381.961128) (xy 89.027712 -381.901404) (xy 89.065663 -381.845818)
			(xy 89.087452 -381.820166) (xy 89.093252 -381.813023) (xy 89.099763 -381.795831) (xy 89.100152 -381.786638)
			(xy 89.100152 -381.628904) (xy 89.100624 -381.618756) (xy 89.108409 -381.600013) (xy 89.12279 -381.585691)
			(xy 89.141564 -381.577983) (xy 89.151714 -381.577596) (xy 89.867994 -381.577596) (xy 89.878115 -381.57813)
			(xy 89.896828 -381.585848) (xy 89.911183 -381.600119) (xy 89.91901 -381.618786) (xy 89.919556 -381.628904)
			(xy 89.919556 -381.786638) (xy 89.919958 -381.795826) (xy 89.926478 -381.81301) (xy 89.932256 -381.820166)
			(xy 89.954034 -381.845826) (xy 89.991983 -381.901411) (xy 90.023017 -381.961134) (xy 90.046691 -382.024137)
			(xy 90.062665 -382.089519) (xy 90.07071 -382.15634) (xy 90.070711 -382.223645) (xy 115.349246 -382.223645)
			(xy 115.349247 -382.15634) (xy 115.357291 -382.089517) (xy 115.373264 -382.024135) (xy 115.396937 -381.96113)
			(xy 115.427969 -381.901406) (xy 115.465917 -381.845819) (xy 115.487704 -381.820166) (xy 115.493498 -381.813019)
			(xy 115.500014 -381.79583) (xy 115.500404 -381.786638) (xy 115.500404 -381.628904) (xy 115.500825 -381.61875)
			(xy 115.50862 -381.599997) (xy 115.523017 -381.585673) (xy 115.54181 -381.577974) (xy 115.551966 -381.577596)
			(xy 116.268246 -381.577596) (xy 116.27837 -381.578088) (xy 116.297084 -381.585822) (xy 116.311437 -381.600106)
			(xy 116.319262 -381.618782) (xy 116.319808 -381.628904) (xy 116.319808 -381.786638) (xy 116.320198 -381.795827)
			(xy 116.326725 -381.813012) (xy 116.332508 -381.820166) (xy 116.354288 -381.845826) (xy 116.39224 -381.90141)
			(xy 116.423277 -381.961132) (xy 116.446952 -382.024135) (xy 116.462928 -382.089517) (xy 116.470973 -382.15634)
			(xy 116.470974 -382.223645) (xy 116.470967 -382.223705) (xy 119.749014 -382.223705) (xy 119.749015 -382.15628)
			(xy 119.757092 -382.089341) (xy 119.773128 -382.023852) (xy 119.796894 -381.960754) (xy 119.828046 -381.900958)
			(xy 119.866135 -381.845323) (xy 119.888 -381.819658) (xy 119.893797 -381.812513) (xy 119.900311 -381.795322)
			(xy 119.9007 -381.78613) (xy 119.9007 -381.628904) (xy 119.901119 -381.618782) (xy 119.908866 -381.600078)
			(xy 119.923182 -381.585764) (xy 119.941886 -381.578019) (xy 119.952008 -381.577596) (xy 120.668288 -381.577596)
			(xy 120.678409 -381.578026) (xy 120.697112 -381.585769) (xy 120.711426 -381.600081) (xy 120.719173 -381.618783)
			(xy 120.719596 -381.628904) (xy 120.719596 -381.78613) (xy 120.719992 -381.795319) (xy 120.726516 -381.812503)
			(xy 120.732296 -381.819658) (xy 120.75415 -381.845331) (xy 120.79224 -381.900965) (xy 120.823391 -381.96076)
			(xy 120.847156 -382.023855) (xy 120.863192 -382.089344) (xy 120.871269 -382.156281) (xy 120.87127 -382.223646)
			(xy 124.14931 -382.223646) (xy 124.14931 -382.156339) (xy 124.157356 -382.089515) (xy 124.173332 -382.024132)
			(xy 124.197008 -381.961127) (xy 124.228045 -381.901403) (xy 124.265998 -381.845818) (xy 124.287788 -381.820166)
			(xy 124.29358 -381.813018) (xy 124.300098 -381.79583) (xy 124.300488 -381.786638) (xy 124.300488 -381.628904)
			(xy 124.300925 -381.618752) (xy 124.308717 -381.600002) (xy 124.323109 -381.585679) (xy 124.341896 -381.577977)
			(xy 124.35205 -381.577596) (xy 125.06833 -381.577596) (xy 125.078453 -381.578101) (xy 125.097167 -381.58583)
			(xy 125.11152 -381.60011) (xy 125.119346 -381.618783) (xy 125.119892 -381.628904) (xy 125.119892 -381.786638)
			(xy 125.120286 -381.795827) (xy 125.126811 -381.813011) (xy 125.132592 -381.820166) (xy 125.154369 -381.845827)
			(xy 125.192316 -381.901413) (xy 125.223348 -381.961135) (xy 125.24702 -382.024139) (xy 125.262993 -382.089519)
			(xy 125.271037 -382.156341) (xy 125.271038 -382.223644) (xy 125.271038 -382.223646) (xy 128.5491 -382.223646)
			(xy 128.549101 -382.156339) (xy 128.557147 -382.089515) (xy 128.573122 -382.024132) (xy 128.596798 -381.961127)
			(xy 128.627834 -381.901404) (xy 128.665787 -381.845818) (xy 128.687576 -381.820166) (xy 128.693367 -381.813016)
			(xy 128.699886 -381.795829) (xy 128.700276 -381.786638) (xy 128.700276 -381.628904) (xy 128.700724 -381.618753)
			(xy 128.708514 -381.600005) (xy 128.722902 -381.585683) (xy 128.741685 -381.577979) (xy 128.751838 -381.577596)
			(xy 129.468118 -381.577596) (xy 129.47824 -381.57811) (xy 129.496954 -381.585836) (xy 129.511308 -381.600113)
			(xy 129.519134 -381.618784) (xy 129.51968 -381.628904) (xy 129.51968 -381.786638) (xy 129.520076 -381.795827)
			(xy 129.5266 -381.813011) (xy 129.53238 -381.820166) (xy 129.554157 -381.845826) (xy 129.592105 -381.901412)
			(xy 129.623138 -381.961135) (xy 129.64681 -382.024138) (xy 129.662784 -382.089519) (xy 129.670828 -382.156341)
			(xy 129.670829 -382.223644) (xy 129.670829 -382.223645) (xy 159.349155 -382.223645) (xy 159.349156 -382.15634)
			(xy 159.3572 -382.089517) (xy 159.373174 -382.024134) (xy 159.396847 -381.96113) (xy 159.42788 -381.901406)
			(xy 159.465828 -381.845818) (xy 159.487616 -381.820166) (xy 159.493411 -381.81302) (xy 159.499926 -381.79583)
			(xy 159.500316 -381.786638) (xy 159.500316 -381.628904) (xy 159.50072 -381.61878) (xy 159.508469 -381.600073)
			(xy 159.52279 -381.585758) (xy 159.5415 -381.578016) (xy 159.551624 -381.577596) (xy 160.268158 -381.577596)
			(xy 160.278277 -381.57816) (xy 160.296988 -381.585866) (xy 160.311345 -381.600128) (xy 160.319173 -381.618789)
			(xy 160.31972 -381.628904) (xy 160.31972 -381.786638) (xy 160.320108 -381.795828) (xy 160.326637 -381.813012)
			(xy 160.33242 -381.820166) (xy 160.354199 -381.845826) (xy 160.392151 -381.90141) (xy 160.423187 -381.961132)
			(xy 160.446862 -382.024136) (xy 160.462837 -382.089518) (xy 160.470882 -382.15634) (xy 160.470883 -382.223645)
			(xy 160.470876 -382.223705) (xy 163.748923 -382.223705) (xy 163.748924 -382.15628) (xy 163.757001 -382.089341)
			(xy 163.773038 -382.023851) (xy 163.796804 -381.960754) (xy 163.827956 -381.900957) (xy 163.866047 -381.845323)
			(xy 163.887912 -381.819658) (xy 163.89371 -381.812514) (xy 163.900224 -381.795323) (xy 163.900612 -381.78613)
			(xy 163.900612 -381.628904) (xy 163.90102 -381.61878) (xy 163.908769 -381.600074) (xy 163.923088 -381.58576)
			(xy 163.941796 -381.578016) (xy 163.95192 -381.577596) (xy 164.6682 -381.577596) (xy 164.678322 -381.578016)
			(xy 164.697025 -381.585763) (xy 164.711339 -381.600079) (xy 164.719085 -381.618782) (xy 164.719508 -381.628904)
			(xy 164.719508 -381.78613) (xy 164.719902 -381.795319) (xy 164.726426 -381.812503) (xy 164.732208 -381.819658)
			(xy 164.754062 -381.845331) (xy 164.79215 -381.900965) (xy 164.823301 -381.96076) (xy 164.847065 -382.023856)
			(xy 164.863101 -382.089344) (xy 164.871178 -382.156281) (xy 164.871179 -382.223645) (xy 168.149243 -382.223645)
			(xy 168.149244 -382.15634) (xy 168.157288 -382.089517) (xy 168.173261 -382.024135) (xy 168.196933 -381.96113)
			(xy 168.227965 -381.901406) (xy 168.265913 -381.845819) (xy 168.2877 -381.820166) (xy 168.293494 -381.813019)
			(xy 168.30001 -381.79583) (xy 168.3004 -381.786638) (xy 168.3004 -381.628904) (xy 168.300825 -381.61875)
			(xy 168.308619 -381.599998) (xy 168.323015 -381.585674) (xy 168.341806 -381.577975) (xy 168.351962 -381.577596)
			(xy 169.068242 -381.577596) (xy 169.078366 -381.578091) (xy 169.09708 -381.585824) (xy 169.111433 -381.600107)
			(xy 169.119258 -381.618783) (xy 169.119804 -381.628904) (xy 169.119804 -381.786638) (xy 169.120195 -381.795827)
			(xy 169.126722 -381.813012) (xy 169.132504 -381.820166) (xy 169.154281 -381.845827) (xy 169.192227 -381.901413)
			(xy 169.223258 -381.961136) (xy 169.24693 -382.024139) (xy 169.262902 -382.08952) (xy 169.270946 -382.156341)
			(xy 169.270947 -382.223644) (xy 169.270947 -382.223646) (xy 172.54901 -382.223646) (xy 172.54901 -382.156339)
			(xy 172.557056 -382.089515) (xy 172.573032 -382.024132) (xy 172.596708 -381.961127) (xy 172.627745 -381.901403)
			(xy 172.665698 -381.845818) (xy 172.687488 -381.820166) (xy 172.69328 -381.813018) (xy 172.699798 -381.79583)
			(xy 172.700188 -381.786638) (xy 172.700188 -381.628904) (xy 172.700625 -381.618752) (xy 172.708417 -381.600002)
			(xy 172.722809 -381.585679) (xy 172.741596 -381.577977) (xy 172.75175 -381.577596) (xy 173.46803 -381.577596)
			(xy 173.478153 -381.578101) (xy 173.496867 -381.58583) (xy 173.51122 -381.60011) (xy 173.519046 -381.618783)
			(xy 173.519592 -381.628904) (xy 173.519592 -381.786638) (xy 173.519986 -381.795827) (xy 173.526511 -381.813011)
			(xy 173.532292 -381.820166) (xy 173.554069 -381.845827) (xy 173.592016 -381.901413) (xy 173.623048 -381.961135)
			(xy 173.64672 -382.024139) (xy 173.662693 -382.089519) (xy 173.670737 -382.156341) (xy 173.670738 -382.223644)
			(xy 173.662695 -382.290466) (xy 173.646725 -382.355847) (xy 173.623054 -382.418851) (xy 173.592024 -382.478574)
			(xy 173.554078 -382.534161) (xy 173.532292 -382.559814) (xy 173.526506 -382.566967) (xy 173.519985 -382.584151)
			(xy 173.519592 -382.593342) (xy 173.519592 -383.086864) (xy 173.520021 -383.096049) (xy 173.526522 -383.113234)
			(xy 173.532292 -383.120392) (xy 173.554094 -383.146032) (xy 173.592041 -383.201621) (xy 173.623072 -383.261346)
			(xy 173.646507 -383.323727) (xy 174.749152 -383.323727) (xy 174.749155 -383.256419) (xy 174.757202 -383.189594)
			(xy 174.773179 -383.12421) (xy 174.796856 -383.061204) (xy 174.827893 -383.001479) (xy 174.865846 -382.945892)
			(xy 174.887636 -382.92024) (xy 174.893445 -382.913104) (xy 174.899951 -382.895906) (xy 174.900336 -382.886712)
			(xy 174.900336 -382.728724) (xy 174.900742 -382.718567) (xy 174.908536 -382.699808) (xy 174.922939 -382.685482)
			(xy 174.941739 -382.677788) (xy 174.951898 -382.677416) (xy 175.668178 -382.677416) (xy 175.6783 -382.677944)
			(xy 175.697017 -382.68566) (xy 175.711373 -382.699933) (xy 175.719197 -382.718605) (xy 175.71974 -382.728724)
			(xy 175.71974 -382.886712) (xy 175.720158 -382.895898) (xy 175.726668 -382.913082) (xy 175.73244 -382.92024)
			(xy 175.754193 -382.945921) (xy 175.792144 -383.001503) (xy 175.82318 -383.061222) (xy 175.846856 -383.124223)
			(xy 175.862832 -383.189602) (xy 175.870879 -383.256422) (xy 175.870883 -383.323724) (xy 175.862842 -383.390545)
			(xy 175.846872 -383.455925) (xy 175.823202 -383.518928) (xy 175.792172 -383.578651) (xy 175.754226 -383.634236)
			(xy 175.73244 -383.659888) (xy 175.726616 -383.667014) (xy 175.720119 -383.684219) (xy 175.71974 -383.693416)
			(xy 175.71974 -384.186684) (xy 175.720171 -384.195869) (xy 175.726672 -384.213053) (xy 175.73244 -384.220212)
			(xy 175.754264 -384.245835) (xy 175.792213 -384.301425) (xy 175.823246 -384.361152) (xy 175.846918 -384.424161)
			(xy 175.862889 -384.489547) (xy 175.87093 -384.556373) (xy 175.870927 -384.623681) (xy 175.862879 -384.690507)
			(xy 175.846902 -384.755891) (xy 175.823224 -384.818897) (xy 175.792185 -384.878622) (xy 175.754231 -384.934208)
			(xy 175.73244 -384.95986) (xy 175.726628 -384.966994) (xy 175.720124 -384.984193) (xy 175.71974 -384.993388)
			(xy 175.71974 -385.151376) (xy 175.71926 -385.161524) (xy 175.71148 -385.180268) (xy 175.697101 -385.194591)
			(xy 175.678327 -385.202298) (xy 175.668178 -385.202684) (xy 174.951898 -385.202684) (xy 174.941774 -385.202176)
			(xy 174.923058 -385.194452) (xy 174.908702 -385.180172) (xy 174.900879 -385.161497) (xy 174.900336 -385.151376)
			(xy 174.900336 -384.993388) (xy 174.899924 -384.984201) (xy 174.893411 -384.967017) (xy 174.887636 -384.95986)
			(xy 174.865884 -384.934179) (xy 174.827934 -384.878596) (xy 174.7969 -384.818877) (xy 174.773225 -384.755876)
			(xy 174.75725 -384.690497) (xy 174.749203 -384.623678) (xy 174.749199 -384.556376) (xy 174.75724 -384.489556)
			(xy 174.773209 -384.424176) (xy 174.796878 -384.361173) (xy 174.827906 -384.30145) (xy 174.865851 -384.245864)
			(xy 174.887636 -384.220212) (xy 174.893457 -384.213084) (xy 174.899956 -384.19588) (xy 174.900336 -384.186684)
			(xy 174.900336 -383.693416) (xy 174.89991 -383.684231) (xy 174.893407 -383.667046) (xy 174.887636 -383.659888)
			(xy 174.865813 -383.634265) (xy 174.827865 -383.578674) (xy 174.796834 -383.518947) (xy 174.773163 -383.455938)
			(xy 174.757193 -383.390553) (xy 174.749152 -383.323727) (xy 173.646507 -383.323727) (xy 173.646742 -383.324352)
			(xy 173.662713 -383.389736) (xy 173.670756 -383.456559) (xy 173.670754 -383.523865) (xy 173.662709 -383.590688)
			(xy 173.646735 -383.656071) (xy 173.623062 -383.719076) (xy 173.592028 -383.7788) (xy 173.55408 -383.834387)
			(xy 173.532292 -383.86004) (xy 173.526495 -383.867185) (xy 173.519981 -383.884376) (xy 173.519592 -383.893568)
			(xy 173.519592 -384.051556) (xy 173.519142 -384.061708) (xy 173.51136 -384.080461) (xy 173.496971 -384.094786)
			(xy 173.478184 -384.102486) (xy 173.46803 -384.102864) (xy 172.75175 -384.102864) (xy 172.741627 -384.102333)
			(xy 172.722908 -384.094622) (xy 172.70855 -384.080349) (xy 172.700728 -384.061676) (xy 172.700188 -384.051556)
			(xy 172.700188 -383.893568) (xy 172.699796 -383.884379) (xy 172.69327 -383.867194) (xy 172.687488 -383.86004)
			(xy 172.665715 -383.834376) (xy 172.627762 -383.778792) (xy 172.596725 -383.719071) (xy 172.57305 -383.656068)
			(xy 172.557074 -383.590686) (xy 172.549028 -383.523864) (xy 172.549026 -383.45656) (xy 172.55707 -383.389737)
			(xy 172.573042 -383.324355) (xy 172.596716 -383.261351) (xy 172.62775 -383.201629) (xy 172.6657 -383.146043)
			(xy 172.687488 -383.120392) (xy 172.693269 -383.113236) (xy 172.699793 -383.096054) (xy 172.700188 -383.086864)
			(xy 172.700188 -382.593342) (xy 172.69976 -382.584157) (xy 172.693259 -382.566972) (xy 172.687488 -382.559814)
			(xy 172.665689 -382.534171) (xy 172.627737 -382.478584) (xy 172.596702 -382.41886) (xy 172.573027 -382.355854)
			(xy 172.557054 -382.29047) (xy 172.54901 -382.223646) (xy 169.270947 -382.223646) (xy 169.262905 -382.290465)
			(xy 169.246934 -382.355847) (xy 169.223264 -382.41885) (xy 169.192235 -382.478574) (xy 169.15429 -382.534161)
			(xy 169.132504 -382.559814) (xy 169.126719 -382.566968) (xy 169.120197 -382.584152) (xy 169.119804 -382.593342)
			(xy 169.119804 -383.086864) (xy 169.120231 -383.096049) (xy 169.126733 -383.113234) (xy 169.132504 -383.120392)
			(xy 169.154306 -383.146032) (xy 169.192252 -383.201621) (xy 169.223282 -383.261347) (xy 169.246739 -383.323787)
			(xy 170.348832 -383.323787) (xy 170.348835 -383.256359) (xy 170.356915 -383.189418) (xy 170.372956 -383.123926)
			(xy 170.396726 -383.060827) (xy 170.427884 -383.001031) (xy 170.46598 -382.945396) (xy 170.487848 -382.919732)
			(xy 170.493662 -382.912599) (xy 170.500165 -382.895399) (xy 170.500548 -382.886204) (xy 170.500548 -382.728724)
			(xy 170.501103 -382.718623) (xy 170.508823 -382.699955) (xy 170.523098 -382.685662) (xy 170.541756 -382.677917)
			(xy 170.551856 -382.677416) (xy 171.268136 -382.677416) (xy 171.278249 -382.677856) (xy 171.296931 -382.685608)
			(xy 171.311225 -382.699919) (xy 171.318956 -382.71861) (xy 171.319444 -382.728724) (xy 171.319444 -382.886204)
			(xy 171.319865 -382.89539) (xy 171.326372 -382.912574) (xy 171.332144 -382.919732) (xy 171.353975 -382.945425)
			(xy 171.392068 -383.001055) (xy 171.423223 -383.060846) (xy 171.446992 -383.12394) (xy 171.463032 -383.189426)
			(xy 171.471111 -383.256362) (xy 171.471115 -383.323784) (xy 171.463041 -383.390721) (xy 171.447008 -383.456209)
			(xy 171.423246 -383.519304) (xy 171.392096 -383.579099) (xy 171.354008 -383.634732) (xy 171.332144 -383.660396)
			(xy 171.32636 -383.66755) (xy 171.319839 -383.684734) (xy 171.319444 -383.693924) (xy 171.319444 -384.186176)
			(xy 171.319878 -384.19536) (xy 171.326376 -384.212544) (xy 171.332144 -384.219704) (xy 171.354045 -384.245339)
			(xy 171.392137 -384.300977) (xy 171.423289 -384.360776) (xy 171.447054 -384.423877) (xy 171.463088 -384.489371)
			(xy 171.471162 -384.556313) (xy 171.471159 -384.623741) (xy 171.463078 -384.690683) (xy 171.447037 -384.756174)
			(xy 171.423267 -384.819273) (xy 171.392109 -384.87907) (xy 171.354012 -384.934704) (xy 171.332144 -384.960368)
			(xy 171.326329 -384.9675) (xy 171.319827 -384.984701) (xy 171.319444 -384.993896) (xy 171.319444 -385.151376)
			(xy 171.318896 -385.161478) (xy 171.311175 -385.180147) (xy 171.296897 -385.194441) (xy 171.278237 -385.202185)
			(xy 171.268136 -385.202684) (xy 170.551856 -385.202684) (xy 170.541742 -385.20225) (xy 170.52306 -385.194495)
			(xy 170.508766 -385.180183) (xy 170.501036 -385.16149) (xy 170.500548 -385.151376) (xy 170.500548 -384.993896)
			(xy 170.500129 -384.98471) (xy 170.49362 -384.967526) (xy 170.487848 -384.960368) (xy 170.466018 -384.934674)
			(xy 170.427925 -384.879045) (xy 170.39677 -384.819253) (xy 170.373001 -384.75616) (xy 170.356962 -384.690674)
			(xy 170.348883 -384.623738) (xy 170.348879 -384.556316) (xy 170.356952 -384.489379) (xy 170.372985 -384.423892)
			(xy 170.396748 -384.360796) (xy 170.427897 -384.301001) (xy 170.465984 -384.245368) (xy 170.487848 -384.219704)
			(xy 170.493631 -384.21255) (xy 170.500153 -384.195366) (xy 170.500548 -384.186176) (xy 170.500548 -383.693924)
			(xy 170.500116 -383.684739) (xy 170.493616 -383.667555) (xy 170.487848 -383.660396) (xy 170.465947 -383.634761)
			(xy 170.427856 -383.579123) (xy 170.396704 -383.519323) (xy 170.37294 -383.456222) (xy 170.356906 -383.390729)
			(xy 170.348832 -383.323787) (xy 169.246739 -383.323787) (xy 169.246952 -383.324353) (xy 169.262922 -383.389736)
			(xy 169.270965 -383.456559) (xy 169.270963 -383.523865) (xy 169.262918 -383.590688) (xy 169.246945 -383.65607)
			(xy 169.223272 -383.719075) (xy 169.192239 -383.7788) (xy 169.154291 -383.834387) (xy 169.132504 -383.86004)
			(xy 169.126708 -383.867186) (xy 169.120193 -383.884376) (xy 169.119804 -383.893568) (xy 169.119804 -384.051556)
			(xy 169.119342 -384.061707) (xy 169.111562 -384.080457) (xy 169.097177 -384.094782) (xy 169.078394 -384.102484)
			(xy 169.068242 -384.102864) (xy 168.351962 -384.102864) (xy 168.341833 -384.102405) (xy 168.323112 -384.094665)
			(xy 168.308757 -384.080371) (xy 168.300939 -384.061682) (xy 168.3004 -384.051556) (xy 168.3004 -383.893568)
			(xy 168.300005 -383.884379) (xy 168.293481 -383.867195) (xy 168.2877 -383.86004) (xy 168.265929 -383.834374)
			(xy 168.227982 -383.778789) (xy 168.196951 -383.719067) (xy 168.173279 -383.656064) (xy 168.157306 -383.590684)
			(xy 168.149261 -383.523864) (xy 168.149259 -383.456561) (xy 168.157301 -383.38974) (xy 168.173272 -383.324359)
			(xy 168.196941 -383.261355) (xy 168.22797 -383.201632) (xy 168.265914 -383.146045) (xy 168.2877 -383.120392)
			(xy 168.293482 -383.113237) (xy 168.300006 -383.096054) (xy 168.3004 -383.086864) (xy 168.3004 -382.593342)
			(xy 168.29997 -382.584157) (xy 168.29347 -382.566972) (xy 168.2877 -382.559814) (xy 168.265904 -382.534169)
			(xy 168.227958 -382.478581) (xy 168.196927 -382.418856) (xy 168.173256 -382.355851) (xy 168.157285 -382.290468)
			(xy 168.149243 -382.223645) (xy 164.871179 -382.223645) (xy 164.871179 -382.223704) (xy 164.863104 -382.290641)
			(xy 164.84707 -382.35613) (xy 164.823307 -382.419226) (xy 164.792158 -382.479022) (xy 164.754071 -382.534657)
			(xy 164.732208 -382.560322) (xy 164.726421 -382.567474) (xy 164.7199 -382.584659) (xy 164.719508 -382.59385)
			(xy 164.719508 -383.086356) (xy 164.719937 -383.095541) (xy 164.726437 -383.112726) (xy 164.732208 -383.119884)
			(xy 164.754087 -383.145536) (xy 164.792175 -383.201173) (xy 164.823325 -383.260971) (xy 164.846959 -383.323727)
			(xy 165.949064 -383.323727) (xy 165.949067 -383.256419) (xy 165.957115 -383.189594) (xy 165.973092 -383.124209)
			(xy 165.996769 -383.061203) (xy 166.027808 -383.001479) (xy 166.065762 -382.945892) (xy 166.087552 -382.92024)
			(xy 166.093363 -382.913105) (xy 166.099868 -382.895907) (xy 166.100252 -382.886712) (xy 166.100252 -382.728724)
			(xy 166.10074 -382.718577) (xy 166.108519 -382.699835) (xy 166.122895 -382.685512) (xy 166.141666 -382.677803)
			(xy 166.151814 -382.677416) (xy 166.868094 -382.677416) (xy 166.878217 -382.677931) (xy 166.896934 -382.685652)
			(xy 166.911289 -382.699929) (xy 166.919113 -382.718603) (xy 166.919656 -382.728724) (xy 166.919656 -382.886712)
			(xy 166.92007 -382.895899) (xy 166.926582 -382.913082) (xy 166.932356 -382.92024) (xy 166.954108 -382.945921)
			(xy 166.992059 -383.001503) (xy 167.023094 -383.061223) (xy 167.046769 -383.124224) (xy 167.062744 -383.189602)
			(xy 167.070791 -383.256422) (xy 167.070795 -383.323724) (xy 167.062754 -383.390544) (xy 167.046785 -383.455925)
			(xy 167.023116 -383.518928) (xy 166.992086 -383.57865) (xy 166.954142 -383.634236) (xy 166.932356 -383.659888)
			(xy 166.926534 -383.667015) (xy 166.920036 -383.68422) (xy 166.919656 -383.693416) (xy 166.919656 -384.186684)
			(xy 166.920084 -384.195869) (xy 166.926586 -384.213053) (xy 166.932356 -384.220212) (xy 166.954179 -384.245835)
			(xy 166.992127 -384.301425) (xy 167.023159 -384.361153) (xy 167.04683 -384.424161) (xy 167.062801 -384.489547)
			(xy 167.070842 -384.556373) (xy 167.070839 -384.623681) (xy 167.062791 -384.690506) (xy 167.046814 -384.75589)
			(xy 167.023137 -384.818897) (xy 166.9921 -384.878621) (xy 166.954146 -384.934208) (xy 166.932356 -384.95986)
			(xy 166.926546 -384.966995) (xy 166.92004 -384.984194) (xy 166.919656 -384.993388) (xy 166.919656 -385.151376)
			(xy 166.91916 -385.161522) (xy 166.911383 -385.180263) (xy 166.89701 -385.194585) (xy 166.878241 -385.202296)
			(xy 166.868094 -385.202684) (xy 166.151814 -385.202684) (xy 166.141691 -385.202163) (xy 166.122975 -385.194444)
			(xy 166.108619 -385.180169) (xy 166.100795 -385.161496) (xy 166.100252 -385.151376) (xy 166.100252 -384.993388)
			(xy 166.099836 -384.984202) (xy 166.093325 -384.967018) (xy 166.087552 -384.95986) (xy 166.065799 -384.934179)
			(xy 166.027849 -384.878597) (xy 165.996813 -384.818877) (xy 165.973138 -384.755877) (xy 165.957162 -384.690498)
			(xy 165.949115 -384.623678) (xy 165.949111 -384.556376) (xy 165.957152 -384.489555) (xy 165.973122 -384.424175)
			(xy 165.996791 -384.361172) (xy 166.027821 -384.30145) (xy 166.065766 -384.245864) (xy 166.087552 -384.220212)
			(xy 166.093375 -384.213086) (xy 166.099872 -384.19588) (xy 166.100252 -384.186684) (xy 166.100252 -383.693416)
			(xy 166.099823 -383.684231) (xy 166.093321 -383.667047) (xy 166.087552 -383.659888) (xy 166.065728 -383.634265)
			(xy 166.02778 -383.578675) (xy 165.996747 -383.518947) (xy 165.973076 -383.455939) (xy 165.957105 -383.390553)
			(xy 165.949064 -383.323727) (xy 164.846959 -383.323727) (xy 164.847088 -383.32407) (xy 164.863122 -383.38956)
			(xy 164.871196 -383.4565) (xy 164.871195 -383.523924) (xy 164.863117 -383.590864) (xy 164.84708 -383.656353)
			(xy 164.823315 -383.719451) (xy 164.792163 -383.779248) (xy 164.754073 -383.834883) (xy 164.732208 -383.860548)
			(xy 164.726409 -383.867692) (xy 164.719896 -383.884883) (xy 164.719508 -383.894076) (xy 164.719508 -384.051556)
			(xy 164.719048 -384.061675) (xy 164.711316 -384.080376) (xy 164.697013 -384.094691) (xy 164.678318 -384.102439)
			(xy 164.6682 -384.102864) (xy 163.95192 -384.102864) (xy 163.941794 -384.102467) (xy 163.923084 -384.094719)
			(xy 163.908768 -384.080396) (xy 163.901028 -384.061682) (xy 163.900612 -384.051556) (xy 163.900612 -383.894076)
			(xy 163.900211 -383.884888) (xy 163.893691 -383.867704) (xy 163.887912 -383.860548) (xy 163.866063 -383.83487)
			(xy 163.827973 -383.779238) (xy 163.796821 -383.719443) (xy 163.773056 -383.656348) (xy 163.757019 -383.59086)
			(xy 163.748941 -383.523923) (xy 163.74894 -383.456501) (xy 163.757014 -383.389563) (xy 163.773049 -383.324075)
			(xy 163.796811 -383.260979) (xy 163.827961 -383.201183) (xy 163.866049 -383.145549) (xy 163.887912 -383.119884)
			(xy 163.893699 -383.112732) (xy 163.900219 -383.095547) (xy 163.900612 -383.086356) (xy 163.900612 -382.59385)
			(xy 163.900175 -382.584666) (xy 163.89368 -382.567481) (xy 163.887912 -382.560322) (xy 163.866038 -382.534665)
			(xy 163.827949 -382.47903) (xy 163.796798 -382.419232) (xy 163.773034 -382.356134) (xy 163.756998 -382.290644)
			(xy 163.748923 -382.223705) (xy 160.470876 -382.223705) (xy 160.46284 -382.290468) (xy 160.446866 -382.35585)
			(xy 160.423193 -382.418854) (xy 160.392159 -382.478577) (xy 160.354208 -382.534162) (xy 160.33242 -382.559814)
			(xy 160.326637 -382.566969) (xy 160.320114 -382.584152) (xy 160.31972 -382.593342) (xy 160.31972 -383.086864)
			(xy 160.320143 -383.09605) (xy 160.326647 -383.113235) (xy 160.33242 -383.120392) (xy 160.354225 -383.146031)
			(xy 160.392176 -383.201618) (xy 160.42321 -383.261343) (xy 160.446672 -383.323786) (xy 161.548769 -383.323786)
			(xy 161.548772 -383.25636) (xy 161.556851 -383.18942) (xy 161.572889 -383.123929) (xy 161.596656 -383.060831)
			(xy 161.627809 -383.001034) (xy 161.665899 -382.945398) (xy 161.687764 -382.919732) (xy 161.69358 -382.912601)
			(xy 161.700081 -382.895399) (xy 161.700464 -382.886204) (xy 161.700464 -382.728724) (xy 161.701004 -382.718621)
			(xy 161.708727 -382.69995) (xy 161.723007 -382.685656) (xy 161.74167 -382.677914) (xy 161.751772 -382.677416)
			(xy 162.468052 -382.677416) (xy 162.478173 -382.677856) (xy 162.496879 -382.685591) (xy 162.511195 -382.699901)
			(xy 162.51894 -382.718603) (xy 162.51936 -382.728724) (xy 162.51936 -382.886204) (xy 162.519777 -382.89539)
			(xy 162.526287 -382.912574) (xy 162.53206 -382.919732) (xy 162.55389 -382.945426) (xy 162.591982 -383.001055)
			(xy 162.623137 -383.060847) (xy 162.646905 -383.12394) (xy 162.662944 -383.189426) (xy 162.671023 -383.256362)
			(xy 162.671027 -383.323784) (xy 162.662954 -383.39072) (xy 162.646921 -383.456208) (xy 162.623159 -383.519303)
			(xy 162.59201 -383.579098) (xy 162.553923 -383.634731) (xy 162.53206 -383.660396) (xy 162.526278 -383.667551)
			(xy 162.519755 -383.684734) (xy 162.51936 -383.693924) (xy 162.51936 -384.186176) (xy 162.51979 -384.195361)
			(xy 162.526291 -384.212545) (xy 162.53206 -384.219704) (xy 162.553961 -384.245339) (xy 162.592051 -384.300977)
			(xy 162.623202 -384.360777) (xy 162.646966 -384.423878) (xy 162.663 -384.489371) (xy 162.671074 -384.556313)
			(xy 162.671071 -384.623741) (xy 162.662991 -384.690682) (xy 162.64695 -384.756174) (xy 162.62318 -384.819272)
			(xy 162.592023 -384.879069) (xy 162.553928 -384.934703) (xy 162.53206 -384.960368) (xy 162.526247 -384.967501)
			(xy 162.519743 -384.984701) (xy 162.51936 -384.993896) (xy 162.51936 -385.151376) (xy 162.518964 -385.161502)
			(xy 162.511216 -385.180213) (xy 162.496893 -385.194529) (xy 162.478178 -385.202268) (xy 162.468052 -385.202684)
			(xy 161.751772 -385.202684) (xy 161.741659 -385.202238) (xy 161.722978 -385.194488) (xy 161.708683 -385.180179)
			(xy 161.700952 -385.161489) (xy 161.700464 -385.151376) (xy 161.700464 -384.993896) (xy 161.700041 -384.98471)
			(xy 161.693535 -384.967527) (xy 161.687764 -384.960368) (xy 161.665937 -384.934673) (xy 161.627849 -384.879042)
			(xy 161.596699 -384.819249) (xy 161.572934 -384.756157) (xy 161.556897 -384.690671) (xy 161.548819 -384.623737)
			(xy 161.548816 -384.556317) (xy 161.556888 -384.489382) (xy 161.572918 -384.423895) (xy 161.596677 -384.3608)
			(xy 161.627821 -384.301005) (xy 161.665903 -384.24537) (xy 161.687764 -384.219704) (xy 161.693549 -384.212551)
			(xy 161.700069 -384.195366) (xy 161.700464 -384.186176) (xy 161.700464 -383.693924) (xy 161.700028 -383.68474)
			(xy 161.693531 -383.667556) (xy 161.687764 -383.660396) (xy 161.665866 -383.634759) (xy 161.627781 -383.57912)
			(xy 161.596634 -383.519319) (xy 161.572873 -383.456219) (xy 161.556841 -383.390727) (xy 161.548769 -383.323786)
			(xy 160.446672 -383.323786) (xy 160.446884 -383.32435) (xy 160.462857 -383.389734) (xy 160.470901 -383.456558)
			(xy 160.470899 -383.523866) (xy 160.462853 -383.59069) (xy 160.446877 -383.656074) (xy 160.423201 -383.719079)
			(xy 160.392163 -383.778803) (xy 160.35421 -383.834388) (xy 160.33242 -383.86004) (xy 160.326626 -383.867187)
			(xy 160.320109 -383.884376) (xy 160.31972 -383.893568) (xy 160.31972 -384.051556) (xy 160.319248 -384.061673)
			(xy 160.311518 -384.080372) (xy 160.297219 -384.094687) (xy 160.278529 -384.102437) (xy 160.268412 -384.102864)
			(xy 159.551878 -384.102864) (xy 159.54175 -384.102392) (xy 159.523029 -384.094657) (xy 159.508674 -384.080367)
			(xy 159.500855 -384.061681) (xy 159.500316 -384.051556) (xy 159.500316 -383.893568) (xy 159.499918 -383.88438)
			(xy 159.493395 -383.867196) (xy 159.487616 -383.86004) (xy 159.465845 -383.834375) (xy 159.427897 -383.77879)
			(xy 159.396864 -383.719068) (xy 159.373191 -383.656065) (xy 159.357218 -383.590684) (xy 159.349173 -383.523864)
			(xy 159.349172 -383.45656) (xy 159.357214 -383.389739) (xy 159.373184 -383.324358) (xy 159.396854 -383.261354)
			(xy 159.427884 -383.201631) (xy 159.46583 -383.146044) (xy 159.487616 -383.120392) (xy 159.4934 -383.113238)
			(xy 159.499922 -383.096054) (xy 159.500316 -383.086864) (xy 159.500316 -382.593342) (xy 159.499882 -382.584157)
			(xy 159.493384 -382.566973) (xy 159.487616 -382.559814) (xy 159.465819 -382.53417) (xy 159.427872 -382.478582)
			(xy 159.396841 -382.418857) (xy 159.373169 -382.355851) (xy 159.357198 -382.290468) (xy 159.349155 -382.223645)
			(xy 129.670829 -382.223645) (xy 129.662786 -382.290466) (xy 129.646815 -382.355847) (xy 129.623144 -382.418851)
			(xy 129.592113 -382.478575) (xy 129.554167 -382.534162) (xy 129.53238 -382.559814) (xy 129.526593 -382.566966)
			(xy 129.520073 -382.584151) (xy 129.51968 -382.593342) (xy 129.51968 -383.086864) (xy 129.520112 -383.096049)
			(xy 129.526611 -383.113233) (xy 129.53238 -383.120392) (xy 129.554183 -383.146031) (xy 129.59213 -383.20162)
			(xy 129.623162 -383.261346) (xy 129.646598 -383.323727) (xy 130.749242 -383.323727) (xy 130.749246 -383.256419)
			(xy 130.757293 -383.189594) (xy 130.77327 -383.12421) (xy 130.796946 -383.061204) (xy 130.827982 -383.00148)
			(xy 130.865935 -382.945892) (xy 130.887724 -382.92024) (xy 130.893531 -382.913103) (xy 130.900039 -382.895906)
			(xy 130.900424 -382.886712) (xy 130.900424 -382.728724) (xy 130.900842 -382.718568) (xy 130.908634 -382.699812)
			(xy 130.923032 -382.685487) (xy 130.941828 -382.67779) (xy 130.951986 -382.677416) (xy 131.668266 -382.677416)
			(xy 131.678388 -382.677954) (xy 131.697103 -382.685666) (xy 131.71146 -382.699937) (xy 131.719284 -382.718606)
			(xy 131.719828 -382.728724) (xy 131.719828 -382.886712) (xy 131.720226 -382.895901) (xy 131.726747 -382.913085)
			(xy 131.732528 -382.92024) (xy 131.754281 -382.945921) (xy 131.792233 -383.001502) (xy 131.82327 -383.061222)
			(xy 131.846946 -383.124223) (xy 131.862923 -383.189602) (xy 131.87097 -383.256422) (xy 131.870973 -383.323724)
			(xy 131.862932 -383.390545) (xy 131.846962 -383.455926) (xy 131.823292 -383.518929) (xy 131.792261 -383.578651)
			(xy 131.754314 -383.634236) (xy 131.732528 -383.659888) (xy 131.726703 -383.667013) (xy 131.720207 -383.684219)
			(xy 131.719828 -383.693416) (xy 131.719828 -384.186684) (xy 131.720239 -384.195871) (xy 131.726751 -384.213056)
			(xy 131.732528 -384.220212) (xy 131.754352 -384.245834) (xy 131.792302 -384.301424) (xy 131.823336 -384.361152)
			(xy 131.847008 -384.42416) (xy 131.86298 -384.489546) (xy 131.871021 -384.556373) (xy 131.871018 -384.623681)
			(xy 131.86297 -384.690507) (xy 131.846992 -384.755892) (xy 131.823314 -384.818898) (xy 131.792274 -384.878622)
			(xy 131.754319 -384.934208) (xy 131.732528 -384.95986) (xy 131.726715 -384.966993) (xy 131.720212 -384.984193)
			(xy 131.719828 -384.993388) (xy 131.719828 -385.151376) (xy 131.719359 -385.161525) (xy 131.711577 -385.180272)
			(xy 131.697195 -385.194595) (xy 131.678417 -385.202301) (xy 131.668266 -385.202684) (xy 130.951986 -385.202684)
			(xy 130.941861 -385.202185) (xy 130.923145 -385.194457) (xy 130.90879 -385.180175) (xy 130.900967 -385.161498)
			(xy 130.900424 -385.151376) (xy 130.900424 -384.993388) (xy 130.900014 -384.984201) (xy 130.8935 -384.967017)
			(xy 130.887724 -384.95986) (xy 130.865972 -384.934178) (xy 130.828023 -384.878596) (xy 130.796989 -384.818876)
			(xy 130.773315 -384.755876) (xy 130.75734 -384.690497) (xy 130.749294 -384.623678) (xy 130.74929 -384.556376)
			(xy 130.757331 -384.489556) (xy 130.773299 -384.424176) (xy 130.796967 -384.361173) (xy 130.827996 -384.301451)
			(xy 130.865939 -384.245865) (xy 130.887724 -384.220212) (xy 130.893543 -384.213083) (xy 130.900044 -384.19588)
			(xy 130.900424 -384.186684) (xy 130.900424 -383.693416) (xy 130.900001 -383.68423) (xy 130.893495 -383.667046)
			(xy 130.887724 -383.659888) (xy 130.865901 -383.634265) (xy 130.827955 -383.578674) (xy 130.796924 -383.518946)
			(xy 130.773254 -383.455938) (xy 130.757284 -383.390552) (xy 130.749242 -383.323727) (xy 129.646598 -383.323727)
			(xy 129.646833 -383.324352) (xy 129.662804 -383.389735) (xy 129.670846 -383.456559) (xy 129.670845 -383.523865)
			(xy 129.6628 -383.590688) (xy 129.646826 -383.656071) (xy 129.623152 -383.719076) (xy 129.592118 -383.778801)
			(xy 129.554168 -383.834388) (xy 129.53238 -383.86004) (xy 129.526582 -383.867184) (xy 129.520069 -383.884375)
			(xy 129.51968 -383.893568) (xy 129.51968 -384.051556) (xy 129.519242 -384.06171) (xy 129.511457 -384.080465)
			(xy 129.497065 -384.094791) (xy 129.478274 -384.102488) (xy 129.468118 -384.102864) (xy 128.751838 -384.102864)
			(xy 128.741714 -384.102342) (xy 128.722995 -384.094628) (xy 128.708637 -384.080352) (xy 128.700816 -384.061677)
			(xy 128.700276 -384.051556) (xy 128.700276 -383.893568) (xy 128.699886 -383.884379) (xy 128.693359 -383.867194)
			(xy 128.687576 -383.86004) (xy 128.665803 -383.834375) (xy 128.627851 -383.778792) (xy 128.596815 -383.71907)
			(xy 128.57314 -383.656067) (xy 128.557165 -383.590686) (xy 128.549119 -383.523864) (xy 128.549117 -383.45656)
			(xy 128.55716 -383.389738) (xy 128.573133 -383.324356) (xy 128.596805 -383.261352) (xy 128.627839 -383.201629)
			(xy 128.665788 -383.146044) (xy 128.687576 -383.120392) (xy 128.693356 -383.113235) (xy 128.699881 -383.096054)
			(xy 128.700276 -383.086864) (xy 128.700276 -382.593342) (xy 128.699851 -382.584156) (xy 128.693348 -382.566971)
			(xy 128.687576 -382.559814) (xy 128.665777 -382.53417) (xy 128.627826 -382.478584) (xy 128.596792 -382.418859)
			(xy 128.573118 -382.355853) (xy 128.557144 -382.29047) (xy 128.5491 -382.223646) (xy 125.271038 -382.223646)
			(xy 125.262995 -382.290466) (xy 125.247025 -382.355847) (xy 125.223354 -382.418851) (xy 125.192324 -382.478574)
			(xy 125.154378 -382.534161) (xy 125.132592 -382.559814) (xy 125.126806 -382.566967) (xy 125.120285 -382.584151)
			(xy 125.119892 -382.593342) (xy 125.119892 -383.086864) (xy 125.120321 -383.096049) (xy 125.126822 -383.113234)
			(xy 125.132592 -383.120392) (xy 125.154394 -383.146032) (xy 125.192341 -383.201621) (xy 125.223372 -383.261346)
			(xy 125.24683 -383.323787) (xy 126.348923 -383.323787) (xy 126.348926 -383.256359) (xy 126.357006 -383.189418)
			(xy 126.373047 -383.123926) (xy 126.396816 -383.060828) (xy 126.427973 -383.001031) (xy 126.466069 -382.945397)
			(xy 126.487936 -382.919732) (xy 126.493749 -382.912598) (xy 126.500253 -382.895399) (xy 126.500636 -382.886204)
			(xy 126.500636 -382.728724) (xy 126.501036 -382.718599) (xy 126.508783 -382.699889) (xy 126.523105 -382.685572)
			(xy 126.541818 -382.677832) (xy 126.551944 -382.677416) (xy 127.268224 -382.677416) (xy 127.278336 -382.677866)
			(xy 127.297018 -382.685614) (xy 127.311313 -382.699922) (xy 127.319044 -382.718611) (xy 127.319532 -382.728724)
			(xy 127.319532 -382.886204) (xy 127.319956 -382.895389) (xy 127.326462 -382.912573) (xy 127.332232 -382.919732)
			(xy 127.354059 -382.945427) (xy 127.392147 -383.001058) (xy 127.423298 -383.06085) (xy 127.447062 -383.123943)
			(xy 127.463099 -383.189428) (xy 127.471178 -383.256363) (xy 127.471181 -383.323783) (xy 127.463109 -383.390718)
			(xy 127.447078 -383.456205) (xy 127.42332 -383.5193) (xy 127.392175 -383.579096) (xy 127.354093 -383.63473)
			(xy 127.332232 -383.660396) (xy 127.326446 -383.667549) (xy 127.319927 -383.684734) (xy 127.319532 -383.693924)
			(xy 127.319532 -384.186176) (xy 127.319969 -384.19536) (xy 127.326466 -384.212544) (xy 127.332232 -384.219704)
			(xy 127.35413 -384.245341) (xy 127.392216 -384.30098) (xy 127.423363 -384.36078) (xy 127.447124 -384.423881)
			(xy 127.463156 -384.489373) (xy 127.471228 -384.556314) (xy 127.471225 -384.62374) (xy 127.463146 -384.69068)
			(xy 127.447108 -384.756171) (xy 127.423341 -384.819269) (xy 127.392188 -384.879066) (xy 127.354097 -384.934702)
			(xy 127.332232 -384.960368) (xy 127.326416 -384.967499) (xy 127.319915 -384.984701) (xy 127.319532 -384.993896)
			(xy 127.319532 -385.151376) (xy 127.318996 -385.161479) (xy 127.311272 -385.180151) (xy 127.296991 -385.194445)
			(xy 127.278327 -385.202187) (xy 127.268224 -385.202684) (xy 126.551944 -385.202684) (xy 126.541822 -385.202247)
			(xy 126.523117 -385.194511) (xy 126.5088 -385.1802) (xy 126.501056 -385.161497) (xy 126.500636 -385.151376)
			(xy 126.500636 -384.993896) (xy 126.50022 -384.98471) (xy 126.49371 -384.967526) (xy 126.487936 -384.960368)
			(xy 126.466106 -384.934674) (xy 126.428014 -384.879045) (xy 126.39686 -384.819253) (xy 126.373092 -384.756159)
			(xy 126.357053 -384.690673) (xy 126.348974 -384.623738) (xy 126.34897 -384.556316) (xy 126.357043 -384.48938)
			(xy 126.373076 -384.423892) (xy 126.396838 -384.360797) (xy 126.427986 -384.301002) (xy 126.466073 -384.245369)
			(xy 126.487936 -384.219704) (xy 126.493718 -384.212549) (xy 126.50024 -384.195366) (xy 126.500636 -384.186176)
			(xy 126.500636 -383.693924) (xy 126.500206 -383.684739) (xy 126.493705 -383.667555) (xy 126.487936 -383.660396)
			(xy 126.466035 -383.634761) (xy 126.427945 -383.579123) (xy 126.396794 -383.519323) (xy 126.373031 -383.456222)
			(xy 126.356996 -383.390729) (xy 126.348923 -383.323787) (xy 125.24683 -383.323787) (xy 125.247042 -383.324352)
			(xy 125.263013 -383.389736) (xy 125.271056 -383.456559) (xy 125.271054 -383.523865) (xy 125.263009 -383.590688)
			(xy 125.247035 -383.656071) (xy 125.223362 -383.719076) (xy 125.192328 -383.7788) (xy 125.15438 -383.834387)
			(xy 125.132592 -383.86004) (xy 125.126795 -383.867185) (xy 125.120281 -383.884376) (xy 125.119892 -383.893568)
			(xy 125.119892 -384.051556) (xy 125.119442 -384.061708) (xy 125.11166 -384.080461) (xy 125.097271 -384.094786)
			(xy 125.078484 -384.102486) (xy 125.06833 -384.102864) (xy 124.35205 -384.102864) (xy 124.341927 -384.102333)
			(xy 124.323208 -384.094622) (xy 124.30885 -384.080349) (xy 124.301028 -384.061676) (xy 124.300488 -384.051556)
			(xy 124.300488 -383.893568) (xy 124.300096 -383.884379) (xy 124.29357 -383.867194) (xy 124.287788 -383.86004)
			(xy 124.266015 -383.834376) (xy 124.228062 -383.778792) (xy 124.197025 -383.719071) (xy 124.17335 -383.656068)
			(xy 124.157374 -383.590686) (xy 124.149328 -383.523864) (xy 124.149326 -383.45656) (xy 124.15737 -383.389737)
			(xy 124.173342 -383.324355) (xy 124.197016 -383.261351) (xy 124.22805 -383.201629) (xy 124.266 -383.146043)
			(xy 124.287788 -383.120392) (xy 124.293569 -383.113236) (xy 124.300093 -383.096054) (xy 124.300488 -383.086864)
			(xy 124.300488 -382.593342) (xy 124.30006 -382.584157) (xy 124.293559 -382.566972) (xy 124.287788 -382.559814)
			(xy 124.265989 -382.534171) (xy 124.228037 -382.478584) (xy 124.197002 -382.41886) (xy 124.173327 -382.355854)
			(xy 124.157354 -382.29047) (xy 124.14931 -382.223646) (xy 120.87127 -382.223646) (xy 120.87127 -382.223704)
			(xy 120.863195 -382.290642) (xy 120.84716 -382.35613) (xy 120.823397 -382.419227) (xy 120.792247 -382.479023)
			(xy 120.75416 -382.534657) (xy 120.732296 -382.560322) (xy 120.726507 -382.567473) (xy 120.719988 -382.584659)
			(xy 120.719596 -382.59385) (xy 120.719596 -383.086356) (xy 120.720028 -383.095541) (xy 120.726527 -383.112725)
			(xy 120.732296 -383.119884) (xy 120.754176 -383.145536) (xy 120.792264 -383.201173) (xy 120.823415 -383.26097)
			(xy 120.847049 -383.323727) (xy 121.949155 -383.323727) (xy 121.949158 -383.256419) (xy 121.957206 -383.189594)
			(xy 121.973182 -383.12421) (xy 121.996859 -383.061204) (xy 122.027897 -383.001479) (xy 122.06585 -382.945892)
			(xy 122.08764 -382.92024) (xy 122.09345 -382.913104) (xy 122.099955 -382.895906) (xy 122.10034 -382.886712)
			(xy 122.10034 -382.728724) (xy 122.100742 -382.718566) (xy 122.108537 -382.699807) (xy 122.122941 -382.685481)
			(xy 122.141742 -382.677788) (xy 122.151902 -382.677416) (xy 122.868182 -382.677416) (xy 122.878305 -382.677941)
			(xy 122.897021 -382.685658) (xy 122.911377 -382.699932) (xy 122.919201 -382.718604) (xy 122.919744 -382.728724)
			(xy 122.919744 -382.886712) (xy 122.920161 -382.895898) (xy 122.926671 -382.913082) (xy 122.932444 -382.92024)
			(xy 122.954197 -382.945921) (xy 122.992148 -383.001503) (xy 123.023183 -383.061222) (xy 123.046859 -383.124223)
			(xy 123.062835 -383.189602) (xy 123.070882 -383.256422) (xy 123.070886 -383.323724) (xy 123.062845 -383.390545)
			(xy 123.046875 -383.455925) (xy 123.023206 -383.518928) (xy 122.992176 -383.57865) (xy 122.95423 -383.634236)
			(xy 122.932444 -383.659888) (xy 122.926621 -383.667014) (xy 122.920124 -383.684219) (xy 122.919744 -383.693416)
			(xy 122.919744 -384.186684) (xy 122.920174 -384.195869) (xy 122.926675 -384.213053) (xy 122.932444 -384.220212)
			(xy 122.954268 -384.245835) (xy 122.992217 -384.301425) (xy 123.023249 -384.361152) (xy 123.046921 -384.424161)
			(xy 123.062892 -384.489547) (xy 123.070933 -384.556373) (xy 123.07093 -384.623681) (xy 123.062882 -384.690507)
			(xy 123.046905 -384.755891) (xy 123.023227 -384.818897) (xy 122.992189 -384.878622) (xy 122.954235 -384.934208)
			(xy 122.932444 -384.95986) (xy 122.926633 -384.966994) (xy 122.920128 -384.984193) (xy 122.919744 -384.993388)
			(xy 122.919744 -385.151376) (xy 122.91926 -385.161523) (xy 122.91148 -385.180267) (xy 122.897103 -385.194589)
			(xy 122.878331 -385.202298) (xy 122.868182 -385.202684) (xy 122.151902 -385.202684) (xy 122.141778 -385.202172)
			(xy 122.123062 -385.19445) (xy 122.108706 -385.180171) (xy 122.100883 -385.161497) (xy 122.10034 -385.151376)
			(xy 122.10034 -384.993388) (xy 122.099927 -384.984201) (xy 122.093414 -384.967017) (xy 122.08764 -384.95986)
			(xy 122.065888 -384.934179) (xy 122.027938 -384.878596) (xy 121.996903 -384.818877) (xy 121.973228 -384.755876)
			(xy 121.957253 -384.690498) (xy 121.949206 -384.623678) (xy 121.949202 -384.556376) (xy 121.957243 -384.489556)
			(xy 121.973212 -384.424176) (xy 121.996881 -384.361173) (xy 122.02791 -384.30145) (xy 122.065855 -384.245864)
			(xy 122.08764 -384.220212) (xy 122.093461 -384.213085) (xy 122.09996 -384.19588) (xy 122.10034 -384.186684)
			(xy 122.10034 -383.693416) (xy 122.099913 -383.684231) (xy 122.09341 -383.667047) (xy 122.08764 -383.659888)
			(xy 122.065817 -383.634265) (xy 122.027869 -383.578674) (xy 121.996837 -383.518947) (xy 121.973166 -383.455939)
			(xy 121.957196 -383.390553) (xy 121.949155 -383.323727) (xy 120.847049 -383.323727) (xy 120.847178 -383.324069)
			(xy 120.863212 -383.38956) (xy 120.871287 -383.4565) (xy 120.871286 -383.523925) (xy 120.863208 -383.590864)
			(xy 120.847171 -383.656354) (xy 120.823405 -383.719452) (xy 120.792252 -383.779248) (xy 120.754161 -383.834883)
			(xy 120.732296 -383.860548) (xy 120.726496 -383.867691) (xy 120.719984 -383.884883) (xy 120.719596 -383.894076)
			(xy 120.719596 -384.051556) (xy 120.719148 -384.061676) (xy 120.711413 -384.080379) (xy 120.697106 -384.094695)
			(xy 120.678408 -384.102441) (xy 120.668288 -384.102864) (xy 119.952008 -384.102864) (xy 119.941882 -384.102477)
			(xy 119.923171 -384.094724) (xy 119.908855 -384.080399) (xy 119.901116 -384.061683) (xy 119.9007 -384.051556)
			(xy 119.9007 -383.894076) (xy 119.900302 -383.884888) (xy 119.89378 -383.867703) (xy 119.888 -383.860548)
			(xy 119.866152 -383.83487) (xy 119.828063 -383.779237) (xy 119.796911 -383.719443) (xy 119.773146 -383.656348)
			(xy 119.75711 -383.59086) (xy 119.749032 -383.523923) (xy 119.749031 -383.456501) (xy 119.757105 -383.389564)
			(xy 119.773139 -383.324075) (xy 119.796901 -383.260979) (xy 119.82805 -383.201184) (xy 119.866137 -383.145549)
			(xy 119.888 -383.119884) (xy 119.893786 -383.112731) (xy 119.900307 -383.095547) (xy 119.9007 -383.086356)
			(xy 119.9007 -382.59385) (xy 119.900266 -382.584665) (xy 119.893769 -382.567481) (xy 119.888 -382.560322)
			(xy 119.866126 -382.534665) (xy 119.828038 -382.479029) (xy 119.796888 -382.419232) (xy 119.773124 -382.356134)
			(xy 119.757089 -382.290644) (xy 119.749014 -382.223705) (xy 116.470967 -382.223705) (xy 116.46293 -382.290468)
			(xy 116.446957 -382.35585) (xy 116.423283 -382.418855) (xy 116.392248 -382.478577) (xy 116.354297 -382.534163)
			(xy 116.332508 -382.559814) (xy 116.326724 -382.566968) (xy 116.320202 -382.584152) (xy 116.319808 -382.593342)
			(xy 116.319808 -383.086864) (xy 116.320234 -383.09605) (xy 116.326736 -383.113234) (xy 116.332508 -383.120392)
			(xy 116.354313 -383.146031) (xy 116.392265 -383.201618) (xy 116.4233 -383.261343) (xy 116.446764 -383.323787)
			(xy 117.548835 -383.323787) (xy 117.548838 -383.256359) (xy 117.556918 -383.189418) (xy 117.572959 -383.123926)
			(xy 117.59673 -383.060827) (xy 117.627888 -383.00103) (xy 117.665984 -382.945396) (xy 117.687852 -382.919732)
			(xy 117.693666 -382.9126) (xy 117.700169 -382.895399) (xy 117.700552 -382.886204) (xy 117.700552 -382.728724)
			(xy 117.701103 -382.718623) (xy 117.708824 -382.699954) (xy 117.7231 -382.68566) (xy 117.741759 -382.677916)
			(xy 117.75186 -382.677416) (xy 118.46814 -382.677416) (xy 118.478253 -382.677853) (xy 118.496935 -382.685607)
			(xy 118.511229 -382.699918) (xy 118.51896 -382.71861) (xy 118.519448 -382.728724) (xy 118.519448 -382.886204)
			(xy 118.519868 -382.89539) (xy 118.526376 -382.912574) (xy 118.532148 -382.919732) (xy 118.553978 -382.945426)
			(xy 118.592072 -383.001055) (xy 118.623227 -383.060847) (xy 118.646995 -383.12394) (xy 118.663035 -383.189426)
			(xy 118.671114 -383.256362) (xy 118.671118 -383.323784) (xy 118.663045 -383.390721) (xy 118.647011 -383.456208)
			(xy 118.623249 -383.519304) (xy 118.592099 -383.579099) (xy 118.554012 -383.634732) (xy 118.532148 -383.660396)
			(xy 118.526364 -383.66755) (xy 118.519843 -383.684734) (xy 118.519448 -383.693924) (xy 118.519448 -384.186176)
			(xy 118.519881 -384.195361) (xy 118.52638 -384.212545) (xy 118.532148 -384.219704) (xy 118.554049 -384.245339)
			(xy 118.59214 -384.300977) (xy 118.623292 -384.360777) (xy 118.647057 -384.423878) (xy 118.663091 -384.489371)
			(xy 118.671165 -384.556313) (xy 118.671162 -384.623741) (xy 118.663082 -384.690682) (xy 118.647041 -384.756174)
			(xy 118.62327 -384.819273) (xy 118.592112 -384.87907) (xy 118.554016 -384.934704) (xy 118.532148 -384.960368)
			(xy 118.526334 -384.9675) (xy 118.519831 -384.984701) (xy 118.519448 -384.993896) (xy 118.519448 -385.151376)
			(xy 118.518897 -385.161477) (xy 118.511176 -385.180146) (xy 118.4969 -385.19444) (xy 118.478241 -385.202184)
			(xy 118.46814 -385.202684) (xy 117.75186 -385.202684) (xy 117.741747 -385.202247) (xy 117.723065 -385.194493)
			(xy 117.708771 -385.180182) (xy 117.70104 -385.16149) (xy 117.700552 -385.151376) (xy 117.700552 -384.993896)
			(xy 117.700132 -384.98471) (xy 117.693624 -384.967526) (xy 117.687852 -384.960368) (xy 117.666022 -384.934674)
			(xy 117.627928 -384.879045) (xy 117.596773 -384.819253) (xy 117.573005 -384.75616) (xy 117.556965 -384.690674)
			(xy 117.548886 -384.623738) (xy 117.548882 -384.556316) (xy 117.556955 -384.489379) (xy 117.572989 -384.423892)
			(xy 117.596751 -384.360796) (xy 117.627901 -384.301001) (xy 117.665988 -384.245368) (xy 117.687852 -384.219704)
			(xy 117.693636 -384.21255) (xy 117.700157 -384.195366) (xy 117.700552 -384.186176) (xy 117.700552 -383.693924)
			(xy 117.700119 -383.684739) (xy 117.69362 -383.667555) (xy 117.687852 -383.660396) (xy 117.665951 -383.634761)
			(xy 117.62786 -383.579123) (xy 117.596708 -383.519323) (xy 117.572943 -383.456222) (xy 117.556909 -383.390729)
			(xy 117.548835 -383.323787) (xy 116.446764 -383.323787) (xy 116.446975 -383.324349) (xy 116.462948 -383.389733)
			(xy 116.470992 -383.456558) (xy 116.47099 -383.523866) (xy 116.462944 -383.59069) (xy 116.446967 -383.656074)
			(xy 116.423291 -383.719079) (xy 116.392252 -383.778803) (xy 116.354298 -383.834389) (xy 116.332508 -383.86004)
			(xy 116.326713 -383.867186) (xy 116.320197 -383.884376) (xy 116.319808 -383.893568) (xy 116.319808 -384.051556)
			(xy 116.319342 -384.061706) (xy 116.311563 -384.080456) (xy 116.297179 -384.094781) (xy 116.278398 -384.102483)
			(xy 116.268246 -384.102864) (xy 115.551966 -384.102864) (xy 115.541838 -384.102401) (xy 115.523116 -384.094663)
			(xy 115.508761 -384.08037) (xy 115.500943 -384.061682) (xy 115.500404 -384.051556) (xy 115.500404 -383.893568)
			(xy 115.500009 -383.884379) (xy 115.493485 -383.867195) (xy 115.487704 -383.86004) (xy 115.465933 -383.834374)
			(xy 115.427986 -383.778789) (xy 115.396954 -383.719067) (xy 115.373282 -383.656064) (xy 115.357309 -383.590684)
			(xy 115.349264 -383.523864) (xy 115.349262 -383.45656) (xy 115.357305 -383.38974) (xy 115.373275 -383.324359)
			(xy 115.396944 -383.261355) (xy 115.427974 -383.201632) (xy 115.465918 -383.146045) (xy 115.487704 -383.120392)
			(xy 115.493487 -383.113237) (xy 115.50001 -383.096054) (xy 115.500404 -383.086864) (xy 115.500404 -382.593342)
			(xy 115.499973 -382.584157) (xy 115.493474 -382.566973) (xy 115.487704 -382.559814) (xy 115.465908 -382.534169)
			(xy 115.427961 -382.478581) (xy 115.39693 -382.418856) (xy 115.37326 -382.355851) (xy 115.357288 -382.290468)
			(xy 115.349246 -382.223645) (xy 90.070711 -382.223645) (xy 90.062667 -382.290467) (xy 90.046695 -382.355848)
			(xy 90.023023 -382.418852) (xy 89.991991 -382.478576) (xy 89.954043 -382.534162) (xy 89.932256 -382.559814)
			(xy 89.926465 -382.566963) (xy 89.919948 -382.584151) (xy 89.919556 -382.593342) (xy 89.919556 -383.086864)
			(xy 89.919994 -383.096048) (xy 89.926489 -383.113232) (xy 89.932256 -383.120392) (xy 89.95406 -383.146031)
			(xy 89.992008 -383.201619) (xy 90.023041 -383.261345) (xy 90.046478 -383.323726) (xy 91.149124 -383.323726)
			(xy 91.149128 -383.256419) (xy 91.157175 -383.189595) (xy 91.17315 -383.124211) (xy 91.196825 -383.061205)
			(xy 91.227861 -383.001481) (xy 91.265811 -382.945893) (xy 91.2876 -382.92024) (xy 91.293405 -382.9131)
			(xy 91.299914 -382.895906) (xy 91.3003 -382.886712) (xy 91.3003 -382.728724) (xy 91.300741 -382.718571)
			(xy 91.308529 -382.699819) (xy 91.32292 -382.685495) (xy 91.341708 -382.677795) (xy 91.351862 -382.677416)
			(xy 92.068142 -382.677416) (xy 92.078268 -382.677891) (xy 92.096986 -382.685629) (xy 92.11134 -382.699918)
			(xy 92.119162 -382.7186) (xy 92.119704 -382.728724) (xy 92.119704 -382.886712) (xy 92.120108 -382.8959)
			(xy 92.126626 -382.913084) (xy 92.132404 -382.92024) (xy 92.154155 -382.945922) (xy 92.192102 -383.001505)
			(xy 92.223135 -383.061225) (xy 92.246808 -383.124225) (xy 92.262782 -383.189604) (xy 92.270828 -383.256422)
			(xy 92.270831 -383.323724) (xy 92.262791 -383.390543) (xy 92.246824 -383.455923) (xy 92.223157 -383.518926)
			(xy 92.19213 -383.578648) (xy 92.154188 -383.634235) (xy 92.132404 -383.659888) (xy 92.126588 -383.66702)
			(xy 92.120085 -383.68422) (xy 92.119704 -383.693416) (xy 92.119704 -384.186684) (xy 92.120121 -384.19587)
			(xy 92.12663 -384.213055) (xy 92.132404 -384.220212) (xy 92.154226 -384.245836) (xy 92.192171 -384.301427)
			(xy 92.2232 -384.361155) (xy 92.246869 -384.424163) (xy 92.262838 -384.489548) (xy 92.270879 -384.556374)
			(xy 92.270875 -384.623681) (xy 92.262828 -384.690505) (xy 92.246853 -384.755889) (xy 92.223178 -384.818894)
			(xy 92.192143 -384.878619) (xy 92.154193 -384.934207) (xy 92.132404 -384.95986) (xy 92.1266 -384.967)
			(xy 92.12009 -384.984194) (xy 92.119704 -384.993388) (xy 92.119704 -385.151376) (xy 92.119259 -385.161528)
			(xy 92.111472 -385.180279) (xy 92.097082 -385.194603) (xy 92.078296 -385.202305) (xy 92.068142 -385.202684)
			(xy 91.351862 -385.202684) (xy 91.341736 -385.202205) (xy 91.323018 -385.194469) (xy 91.308664 -385.180181)
			(xy 91.300842 -385.1615) (xy 91.3003 -385.151376) (xy 91.3003 -384.993388) (xy 91.299895 -384.9842)
			(xy 91.293378 -384.967016) (xy 91.2876 -384.95986) (xy 91.265849 -384.934178) (xy 91.227901 -384.878595)
			(xy 91.196869 -384.818875) (xy 91.173196 -384.755875) (xy 91.157221 -384.690497) (xy 91.149175 -384.623678)
			(xy 91.149172 -384.556376) (xy 91.157212 -384.489557) (xy 91.17318 -384.424177) (xy 91.196847 -384.361174)
			(xy 91.227874 -384.301451) (xy 91.265816 -384.245865) (xy 91.2876 -384.220212) (xy 91.293416 -384.213081)
			(xy 91.299919 -384.19588) (xy 91.3003 -384.186684) (xy 91.3003 -383.693416) (xy 91.299882 -383.68423)
			(xy 91.293374 -383.667045) (xy 91.2876 -383.659888) (xy 91.265778 -383.634264) (xy 91.227833 -383.578673)
			(xy 91.196803 -383.518945) (xy 91.173134 -383.455937) (xy 91.157165 -383.390552) (xy 91.149124 -383.323726)
			(xy 90.046478 -383.323726) (xy 90.046713 -383.324351) (xy 90.062685 -383.389735) (xy 90.070728 -383.456559)
			(xy 90.070727 -383.523865) (xy 90.062681 -383.590689) (xy 90.046706 -383.656072) (xy 90.023031 -383.719077)
			(xy 89.991996 -383.778801) (xy 89.954045 -383.834388) (xy 89.932256 -383.86004) (xy 89.926454 -383.867181)
			(xy 89.919944 -383.884375) (xy 89.919556 -383.893568) (xy 89.919556 -384.051556) (xy 89.919043 -384.0617)
			(xy 89.911273 -384.080441) (xy 89.896905 -384.094764) (xy 89.87814 -384.102475) (xy 89.867994 -384.102864)
			(xy 89.151714 -384.102864) (xy 89.141589 -384.102362) (xy 89.122869 -384.09464) (xy 89.108512 -384.080358)
			(xy 89.100692 -384.061679) (xy 89.100152 -384.051556) (xy 89.100152 -383.893568) (xy 89.099745 -383.884381)
			(xy 89.093228 -383.867197) (xy 89.087452 -383.86004) (xy 89.06568 -383.834375) (xy 89.02773 -383.778791)
			(xy 88.996695 -383.719069) (xy 88.973021 -383.656066) (xy 88.957046 -383.590685) (xy 88.949001 -383.523864)
			(xy 88.948999 -383.45656) (xy 88.957042 -383.389738) (xy 88.973014 -383.324357) (xy 88.996685 -383.261353)
			(xy 89.027717 -383.20163) (xy 89.065665 -383.146044) (xy 89.087452 -383.120392) (xy 89.093241 -383.113242)
			(xy 89.099759 -383.096055) (xy 89.100152 -383.086864) (xy 89.100152 -382.593342) (xy 89.09971 -382.584158)
			(xy 89.093217 -382.566975) (xy 89.087452 -382.559814) (xy 89.065654 -382.53417) (xy 89.027704 -382.478583)
			(xy 88.996671 -382.418858) (xy 88.972998 -382.355853) (xy 88.957025 -382.290469) (xy 88.948982 -382.223646)
			(xy 85.670943 -382.223646) (xy 85.670943 -382.223704) (xy 85.662867 -382.290643) (xy 85.646832 -382.356132)
			(xy 85.623067 -382.419228) (xy 85.591915 -382.479024) (xy 85.553825 -382.534657) (xy 85.53196 -382.560322)
			(xy 85.526167 -382.567469) (xy 85.519651 -382.584658) (xy 85.51926 -382.59385) (xy 85.51926 -383.086356)
			(xy 85.5197 -383.09554) (xy 85.526194 -383.112724) (xy 85.53196 -383.119884) (xy 85.553841 -383.145536)
			(xy 85.591932 -383.201171) (xy 85.623084 -383.260969) (xy 85.646743 -383.323786) (xy 86.748805 -383.323786)
			(xy 86.748808 -383.25636) (xy 86.756888 -383.189419) (xy 86.772927 -383.123927) (xy 86.796696 -383.060829)
			(xy 86.827852 -383.001032) (xy 86.865945 -382.945397) (xy 86.887812 -382.919732) (xy 86.893621 -382.912596)
			(xy 86.900128 -382.895398) (xy 86.900512 -382.886204) (xy 86.900512 -382.728724) (xy 86.900936 -382.718602)
			(xy 86.908678 -382.699896) (xy 86.922993 -382.685581) (xy 86.941698 -382.677837) (xy 86.95182 -382.677416)
			(xy 87.6681 -382.677416) (xy 87.678224 -382.677816) (xy 87.696931 -382.685568) (xy 87.711246 -382.699889)
			(xy 87.718988 -382.718599) (xy 87.719408 -382.728724) (xy 87.719408 -382.886204) (xy 87.719815 -382.895392)
			(xy 87.726331 -382.912576) (xy 87.732108 -382.919732) (xy 87.753936 -382.945427) (xy 87.792026 -383.001057)
			(xy 87.823177 -383.060849) (xy 87.846943 -383.123942) (xy 87.862981 -383.189428) (xy 87.87106 -383.256363)
			(xy 87.871063 -383.323783) (xy 87.862991 -383.390719) (xy 87.846959 -383.456206) (xy 87.8232 -383.519301)
			(xy 87.792053 -383.579096) (xy 87.75397 -383.634731) (xy 87.732108 -383.660396) (xy 87.726332 -383.667556)
			(xy 87.719805 -383.684735) (xy 87.719408 -383.693924) (xy 87.719408 -384.186176) (xy 87.719828 -384.195362)
			(xy 87.726335 -384.212547) (xy 87.732108 -384.219704) (xy 87.754007 -384.24534) (xy 87.792094 -384.300979)
			(xy 87.823243 -384.360779) (xy 87.847005 -384.42388) (xy 87.863037 -384.489373) (xy 87.87111 -384.556314)
			(xy 87.871107 -384.62374) (xy 87.863028 -384.690681) (xy 87.846989 -384.756172) (xy 87.823221 -384.81927)
			(xy 87.792066 -384.879067) (xy 87.753974 -384.934703) (xy 87.732108 -384.960368) (xy 87.726301 -384.967506)
			(xy 87.719792 -384.984702) (xy 87.719408 -384.993896) (xy 87.719408 -385.151376) (xy 87.718965 -385.161496)
			(xy 87.711226 -385.180198) (xy 87.696918 -385.194512) (xy 87.67822 -385.20226) (xy 87.6681 -385.202684)
			(xy 86.95182 -385.202684) (xy 86.941697 -385.202267) (xy 86.922991 -385.194523) (xy 86.908675 -385.180206)
			(xy 86.900932 -385.161499) (xy 86.900512 -385.151376) (xy 86.900512 -384.993896) (xy 86.900101 -384.984709)
			(xy 86.893587 -384.967525) (xy 86.887812 -384.960368) (xy 86.865983 -384.934674) (xy 86.827892 -384.879044)
			(xy 86.796739 -384.819252) (xy 86.772973 -384.756158) (xy 86.756934 -384.690673) (xy 86.748855 -384.623738)
			(xy 86.748852 -384.556316) (xy 86.756925 -384.48938) (xy 86.772957 -384.423893) (xy 86.796717 -384.360798)
			(xy 86.827865 -384.301003) (xy 86.86595 -384.245369) (xy 86.887812 -384.219704) (xy 86.893591 -384.212546)
			(xy 86.900116 -384.195365) (xy 86.900512 -384.186176) (xy 86.900512 -383.693924) (xy 86.900088 -383.684738)
			(xy 86.893583 -383.667554) (xy 86.887812 -383.660396) (xy 86.865912 -383.63476) (xy 86.827824 -383.579122)
			(xy 86.796674 -383.519322) (xy 86.772911 -383.456221) (xy 86.756878 -383.390728) (xy 86.748805 -383.323786)
			(xy 85.646743 -383.323786) (xy 85.646849 -383.324068) (xy 85.662885 -383.389559) (xy 85.67096 -383.456499)
			(xy 85.670959 -383.523925) (xy 85.662881 -383.590865) (xy 85.646842 -383.656355) (xy 85.623074 -383.719453)
			(xy 85.59192 -383.77925) (xy 85.553826 -383.834883) (xy 85.53196 -383.860548) (xy 85.526156 -383.867687)
			(xy 85.519647 -383.884883) (xy 85.51926 -383.894076) (xy 85.51926 -384.051556) (xy 85.518847 -384.061681)
			(xy 85.511106 -384.080391) (xy 85.496787 -384.094708) (xy 85.478077 -384.102448) (xy 85.467952 -384.102864)
			(xy 84.751672 -384.102864) (xy 84.741543 -384.102506) (xy 84.722832 -384.094742) (xy 84.708517 -384.080407)
			(xy 84.70078 -384.061685) (xy 84.700364 -384.051556) (xy 84.700364 -383.894076) (xy 84.699951 -383.884889)
			(xy 84.693438 -383.867706) (xy 84.687664 -383.860548) (xy 84.665817 -383.834869) (xy 84.62773 -383.779236)
			(xy 84.596581 -383.719441) (xy 84.572817 -383.656346) (xy 84.556782 -383.590859) (xy 84.548705 -383.523923)
			(xy 84.548704 -383.456501) (xy 84.556778 -383.389565) (xy 84.57281 -383.324077) (xy 84.596571 -383.260981)
			(xy 84.627718 -383.201185) (xy 84.665802 -383.14555) (xy 84.687664 -383.119884) (xy 84.693458 -383.112737)
			(xy 84.699972 -383.095548) (xy 84.700364 -383.086356) (xy 84.700364 -382.59385) (xy 84.699916 -382.584667)
			(xy 84.693427 -382.567483) (xy 84.687664 -382.560322) (xy 84.665791 -382.534664) (xy 84.627705 -382.479028)
			(xy 84.596557 -382.41923) (xy 84.572795 -382.356132) (xy 84.556761 -382.290643) (xy 84.548687 -382.223704)
			(xy 81.271152 -382.223704) (xy 81.263076 -382.290642) (xy 81.247041 -382.356131) (xy 81.223277 -382.419228)
			(xy 81.192126 -382.479023) (xy 81.154036 -382.534657) (xy 81.132172 -382.560322) (xy 81.12638 -382.56747)
			(xy 81.119863 -382.584659) (xy 81.119472 -382.59385) (xy 81.119472 -383.086356) (xy 81.11991 -383.09554)
			(xy 81.126405 -383.112724) (xy 81.132172 -383.119884) (xy 81.154053 -383.145536) (xy 81.192143 -383.201172)
			(xy 81.223294 -383.260969) (xy 81.246931 -383.323727) (xy 82.349036 -383.323727) (xy 82.34904 -383.256419)
			(xy 82.357087 -383.189595) (xy 82.373063 -383.124211) (xy 82.396739 -383.061205) (xy 82.427775 -383.00148)
			(xy 82.465727 -382.945892) (xy 82.487516 -382.92024) (xy 82.493322 -382.913102) (xy 82.499831 -382.895906)
			(xy 82.500216 -382.886712) (xy 82.500216 -382.728724) (xy 82.500636 -382.718601) (xy 82.508379 -382.699895)
			(xy 82.522695 -382.685579) (xy 82.541401 -382.677836) (xy 82.551524 -382.677416) (xy 83.268058 -382.677416)
			(xy 83.278179 -382.67796) (xy 83.296895 -382.68567) (xy 83.311252 -382.699938) (xy 83.319076 -382.718606)
			(xy 83.31962 -382.728724) (xy 83.31962 -382.886712) (xy 83.32002 -382.8959) (xy 83.32654 -382.913085)
			(xy 83.33232 -382.92024) (xy 83.354074 -382.945921) (xy 83.392026 -383.001502) (xy 83.423063 -383.061221)
			(xy 83.44674 -383.124222) (xy 83.462717 -383.189601) (xy 83.470764 -383.256421) (xy 83.470767 -383.323724)
			(xy 83.462726 -383.390545) (xy 83.446756 -383.455926) (xy 83.423085 -383.518929) (xy 83.392054 -383.578651)
			(xy 83.354107 -383.634236) (xy 83.33232 -383.659888) (xy 83.326506 -383.667021) (xy 83.320001 -383.684221)
			(xy 83.31962 -383.693416) (xy 83.31962 -384.186684) (xy 83.320033 -384.195871) (xy 83.326544 -384.213056)
			(xy 83.33232 -384.220212) (xy 83.354144 -384.245835) (xy 83.392095 -384.301424) (xy 83.423129 -384.361152)
			(xy 83.446801 -384.42416) (xy 83.462773 -384.489546) (xy 83.470815 -384.556373) (xy 83.470812 -384.623681)
			(xy 83.462763 -384.690507) (xy 83.446785 -384.755892) (xy 83.423107 -384.818898) (xy 83.392067 -384.878622)
			(xy 83.354111 -384.934208) (xy 83.33232 -384.95986) (xy 83.326518 -384.967001) (xy 83.320006 -384.984195)
			(xy 83.31962 -384.993388) (xy 83.31962 -385.151376) (xy 83.319165 -385.161494) (xy 83.311428 -385.180194)
			(xy 83.297124 -385.194508) (xy 83.27843 -385.202258) (xy 83.268312 -385.202684) (xy 82.551778 -385.202684)
			(xy 82.541653 -385.202192) (xy 82.522936 -385.194462) (xy 82.508581 -385.180178) (xy 82.500758 -385.161499)
			(xy 82.500216 -385.151376) (xy 82.500216 -384.993388) (xy 82.499808 -384.984201) (xy 82.493293 -384.967016)
			(xy 82.487516 -384.95986) (xy 82.465765 -384.934178) (xy 82.427816 -384.878595) (xy 82.396783 -384.818876)
			(xy 82.373109 -384.755875) (xy 82.357134 -384.690497) (xy 82.349088 -384.623678) (xy 82.349084 -384.556376)
			(xy 82.357125 -384.489556) (xy 82.373093 -384.424177) (xy 82.396761 -384.361174) (xy 82.427788 -384.301451)
			(xy 82.465731 -384.245865) (xy 82.487516 -384.220212) (xy 82.493334 -384.213082) (xy 82.499835 -384.19588)
			(xy 82.500216 -384.186684) (xy 82.500216 -383.693416) (xy 82.499794 -383.68423) (xy 82.493288 -383.667046)
			(xy 82.487516 -383.659888) (xy 82.465694 -383.634265) (xy 82.427747 -383.578674) (xy 82.396717 -383.518946)
			(xy 82.373047 -383.455938) (xy 82.357077 -383.390552) (xy 82.349036 -383.323727) (xy 81.246931 -383.323727)
			(xy 81.247059 -383.324068) (xy 81.263094 -383.389559) (xy 81.271169 -383.456499) (xy 81.271168 -383.523925)
			(xy 81.26309 -383.590865) (xy 81.247052 -383.656355) (xy 81.223285 -383.719453) (xy 81.19213 -383.779249)
			(xy 81.154038 -383.834883) (xy 81.132172 -383.860548) (xy 81.126369 -383.867688) (xy 81.119859 -383.884883)
			(xy 81.119472 -383.894076) (xy 81.119472 -384.051556) (xy 81.119047 -384.061679) (xy 81.111308 -384.080387)
			(xy 81.096994 -384.094704) (xy 81.078287 -384.102446) (xy 81.068164 -384.102864) (xy 80.351884 -384.102864)
			(xy 80.341756 -384.102496) (xy 80.323045 -384.094736) (xy 80.30873 -384.080405) (xy 80.300992 -384.061685)
			(xy 80.300576 -384.051556) (xy 80.300576 -383.894076) (xy 80.300183 -383.884887) (xy 80.293658 -383.867703)
			(xy 80.287876 -383.860548) (xy 80.266029 -383.834869) (xy 80.227941 -383.779236) (xy 80.196791 -383.719442)
			(xy 80.173027 -383.656347) (xy 80.156991 -383.590859) (xy 80.148914 -383.523923) (xy 80.148913 -383.456501)
			(xy 80.156987 -383.389564) (xy 80.17302 -383.324076) (xy 80.196781 -383.26098) (xy 80.227929 -383.201184)
			(xy 80.266014 -383.14555) (xy 80.287876 -383.119884) (xy 80.293659 -383.112729) (xy 80.300183 -383.095546)
			(xy 80.300576 -383.086356) (xy 80.300576 -382.59385) (xy 80.300147 -382.584665) (xy 80.293647 -382.56748)
			(xy 80.287876 -382.560322) (xy 80.266003 -382.534664) (xy 80.227916 -382.479028) (xy 80.196767 -382.419231)
			(xy 80.173005 -382.356133) (xy 80.156971 -382.290643) (xy 80.148896 -382.223704) (xy 76.870825 -382.223704)
			(xy 76.862789 -382.290466) (xy 76.846818 -382.355847) (xy 76.823147 -382.418851) (xy 76.792117 -382.478575)
			(xy 76.75417 -382.534162) (xy 76.732384 -382.559814) (xy 76.726597 -382.566966) (xy 76.720077 -382.584151)
			(xy 76.719684 -382.593342) (xy 76.719684 -383.086864) (xy 76.720115 -383.096049) (xy 76.726615 -383.113233)
			(xy 76.732384 -383.120392) (xy 76.754187 -383.146031) (xy 76.792134 -383.20162) (xy 76.823165 -383.261346)
			(xy 76.846624 -383.323787) (xy 77.948717 -383.323787) (xy 77.94872 -383.256359) (xy 77.9568 -383.189418)
			(xy 77.97284 -383.123927) (xy 77.99661 -383.060828) (xy 78.027766 -383.001031) (xy 78.065861 -382.945397)
			(xy 78.087728 -382.919732) (xy 78.09354 -382.912598) (xy 78.100045 -382.895399) (xy 78.100428 -382.886204)
			(xy 78.100428 -382.728724) (xy 78.100836 -382.7186) (xy 78.108582 -382.699891) (xy 78.122901 -382.685575)
			(xy 78.141611 -382.677834) (xy 78.151736 -382.677416) (xy 78.868016 -382.677416) (xy 78.878142 -382.677803)
			(xy 78.896849 -382.685559) (xy 78.911163 -382.699885) (xy 78.918905 -382.718598) (xy 78.919324 -382.728724)
			(xy 78.919324 -382.886204) (xy 78.919727 -382.895392) (xy 78.926245 -382.912577) (xy 78.932024 -382.919732)
			(xy 78.953852 -382.945427) (xy 78.99194 -383.001058) (xy 79.023091 -383.06085) (xy 79.046856 -383.123943)
			(xy 79.062893 -383.189428) (xy 79.070972 -383.256363) (xy 79.070975 -383.323783) (xy 79.062903 -383.390719)
			(xy 79.046872 -383.456205) (xy 79.023113 -383.519301) (xy 78.991968 -383.579096) (xy 78.953885 -383.63473)
			(xy 78.932024 -383.660396) (xy 78.926249 -383.667557) (xy 78.919721 -383.684735) (xy 78.919324 -383.693924)
			(xy 78.919324 -384.186176) (xy 78.91974 -384.195363) (xy 78.926249 -384.212547) (xy 78.932024 -384.219704)
			(xy 78.953922 -384.24534) (xy 78.992009 -384.30098) (xy 79.023156 -384.36078) (xy 79.046917 -384.423881)
			(xy 79.06295 -384.489373) (xy 79.071022 -384.556314) (xy 79.071019 -384.62374) (xy 79.06294 -384.69068)
			(xy 79.046901 -384.756171) (xy 79.023134 -384.819269) (xy 78.991981 -384.879067) (xy 78.953889 -384.934702)
			(xy 78.932024 -384.960368) (xy 78.926219 -384.967507) (xy 78.919709 -384.984702) (xy 78.919324 -384.993896)
			(xy 78.919324 -385.151376) (xy 78.918865 -385.161494) (xy 78.911129 -385.180193) (xy 78.896826 -385.194507)
			(xy 78.878134 -385.202257) (xy 78.868016 -385.202684) (xy 78.151736 -385.202684) (xy 78.141614 -385.202254)
			(xy 78.122908 -385.194515) (xy 78.108592 -385.180202) (xy 78.100848 -385.161498) (xy 78.100428 -385.151376)
			(xy 78.100428 -384.993896) (xy 78.100014 -384.984709) (xy 78.093502 -384.967525) (xy 78.087728 -384.960368)
			(xy 78.065898 -384.934674) (xy 78.027807 -384.879044) (xy 77.996653 -384.819252) (xy 77.972886 -384.756159)
			(xy 77.956847 -384.690673) (xy 77.948768 -384.623738) (xy 77.948764 -384.556316) (xy 77.956837 -384.48938)
			(xy 77.972869 -384.423893) (xy 77.996631 -384.360797) (xy 78.027779 -384.301002) (xy 78.065865 -384.245369)
			(xy 78.087728 -384.219704) (xy 78.093509 -384.212548) (xy 78.100032 -384.195366) (xy 78.100428 -384.186176)
			(xy 78.100428 -383.693924) (xy 78.1 -383.684739) (xy 78.093498 -383.667555) (xy 78.087728 -383.660396)
			(xy 78.065828 -383.63476) (xy 78.027738 -383.579122) (xy 77.996587 -383.519322) (xy 77.972824 -383.456221)
			(xy 77.95679 -383.390728) (xy 77.948717 -383.323787) (xy 76.846624 -383.323787) (xy 76.846836 -383.324352)
			(xy 76.862807 -383.389735) (xy 76.870849 -383.456559) (xy 76.870848 -383.523865) (xy 76.862803 -383.590688)
			(xy 76.846829 -383.656071) (xy 76.823155 -383.719076) (xy 76.792121 -383.7788) (xy 76.754172 -383.834388)
			(xy 76.732384 -383.86004) (xy 76.726586 -383.867184) (xy 76.720073 -383.884376) (xy 76.719684 -383.893568)
			(xy 76.719684 -384.051556) (xy 76.719242 -384.061709) (xy 76.711458 -384.080464) (xy 76.697067 -384.094789)
			(xy 76.678277 -384.102488) (xy 76.668122 -384.102864) (xy 75.951842 -384.102864) (xy 75.941718 -384.102339)
			(xy 75.922999 -384.094626) (xy 75.908642 -384.080351) (xy 75.90082 -384.061677) (xy 75.90028 -384.051556)
			(xy 75.90028 -383.893568) (xy 75.89989 -383.884379) (xy 75.893363 -383.867194) (xy 75.88758 -383.86004)
			(xy 75.865807 -383.834375) (xy 75.827855 -383.778792) (xy 75.796819 -383.71907) (xy 75.773143 -383.656067)
			(xy 75.757168 -383.590686) (xy 75.749122 -383.523864) (xy 75.74912 -383.45656) (xy 75.757164 -383.389738)
			(xy 75.773136 -383.324356) (xy 75.796809 -383.261352) (xy 75.827842 -383.201629) (xy 75.865792 -383.146044)
			(xy 75.88758 -383.120392) (xy 75.89336 -383.113235) (xy 75.899885 -383.096054) (xy 75.90028 -383.086864)
			(xy 75.90028 -382.593342) (xy 75.899854 -382.584156) (xy 75.893352 -382.566972) (xy 75.88758 -382.559814)
			(xy 75.865781 -382.53417) (xy 75.82783 -382.478584) (xy 75.796795 -382.418859) (xy 75.773121 -382.355854)
			(xy 75.757147 -382.29047) (xy 75.749104 -382.223646) (xy 72.471064 -382.223646) (xy 72.471064 -382.223704)
			(xy 72.462989 -382.290642) (xy 72.446954 -382.356131) (xy 72.42319 -382.419227) (xy 72.39204 -382.479023)
			(xy 72.353952 -382.534657) (xy 72.332088 -382.560322) (xy 72.326298 -382.567472) (xy 72.31978 -382.584659)
			(xy 72.319388 -382.59385) (xy 72.319388 -383.086356) (xy 72.319822 -383.095541) (xy 72.326319 -383.112725)
			(xy 72.332088 -383.119884) (xy 72.353968 -383.145536) (xy 72.392057 -383.201172) (xy 72.423208 -383.26097)
			(xy 72.446843 -383.323727) (xy 73.548949 -383.323727) (xy 73.548952 -383.256419) (xy 73.556999 -383.189594)
			(xy 73.572976 -383.12421) (xy 73.596652 -383.061204) (xy 73.62769 -383.001479) (xy 73.665642 -382.945892)
			(xy 73.687432 -382.92024) (xy 73.693241 -382.913103) (xy 73.699747 -382.895906) (xy 73.700132 -382.886712)
			(xy 73.700132 -382.728724) (xy 73.700542 -382.718567) (xy 73.708335 -382.699809) (xy 73.722736 -382.685484)
			(xy 73.741535 -382.677789) (xy 73.751694 -382.677416) (xy 74.467974 -382.677416) (xy 74.478096 -382.677947)
			(xy 74.496812 -382.685662) (xy 74.511169 -382.699934) (xy 74.518993 -382.718605) (xy 74.519536 -382.728724)
			(xy 74.519536 -382.886712) (xy 74.519955 -382.895898) (xy 74.526464 -382.913082) (xy 74.532236 -382.92024)
			(xy 74.553989 -382.945921) (xy 74.591941 -383.001503) (xy 74.622977 -383.061222) (xy 74.646653 -383.124223)
			(xy 74.662629 -383.189602) (xy 74.670676 -383.256422) (xy 74.670679 -383.323724) (xy 74.662639 -383.390545)
			(xy 74.646669 -383.455925) (xy 74.622999 -383.518928) (xy 74.591968 -383.578651) (xy 74.554022 -383.634236)
			(xy 74.532236 -383.659888) (xy 74.526412 -383.667013) (xy 74.519915 -383.684219) (xy 74.519536 -383.693416)
			(xy 74.519536 -384.186684) (xy 74.519968 -384.195869) (xy 74.526468 -384.213052) (xy 74.532236 -384.220212)
			(xy 74.55406 -384.245835) (xy 74.592009 -384.301425) (xy 74.623043 -384.361152) (xy 74.646714 -384.424161)
			(xy 74.662686 -384.489547) (xy 74.670727 -384.556373) (xy 74.670724 -384.623681) (xy 74.662676 -384.690507)
			(xy 74.646698 -384.755891) (xy 74.623021 -384.818897) (xy 74.591982 -384.878622) (xy 74.554027 -384.934208)
			(xy 74.532236 -384.95986) (xy 74.526424 -384.966994) (xy 74.51992 -384.984193) (xy 74.519536 -384.993388)
			(xy 74.519536 -385.151376) (xy 74.51906 -385.161524) (xy 74.511279 -385.180269) (xy 74.496899 -385.194592)
			(xy 74.478124 -385.202299) (xy 74.467974 -385.202684) (xy 73.751694 -385.202684) (xy 73.74157 -385.202179)
			(xy 73.722853 -385.194454) (xy 73.708498 -385.180173) (xy 73.700675 -385.161497) (xy 73.700132 -385.151376)
			(xy 73.700132 -384.993388) (xy 73.699721 -384.984201) (xy 73.693207 -384.967017) (xy 73.687432 -384.95986)
			(xy 73.66568 -384.934178) (xy 73.627731 -384.878596) (xy 73.596696 -384.818877) (xy 73.573022 -384.755876)
			(xy 73.557047 -384.690497) (xy 73.549 -384.623678) (xy 73.548996 -384.556376) (xy 73.557037 -384.489556)
			(xy 73.573006 -384.424176) (xy 73.596674 -384.361173) (xy 73.627703 -384.30145) (xy 73.665647 -384.245864)
			(xy 73.687432 -384.220212) (xy 73.693253 -384.213084) (xy 73.699752 -384.19588) (xy 73.700132 -384.186684)
			(xy 73.700132 -383.693416) (xy 73.699707 -383.684231) (xy 73.693203 -383.667046) (xy 73.687432 -383.659888)
			(xy 73.665609 -383.634265) (xy 73.627662 -383.578674) (xy 73.59663 -383.518946) (xy 73.57296 -383.455938)
			(xy 73.55699 -383.390553) (xy 73.548949 -383.323727) (xy 72.446843 -383.323727) (xy 72.446972 -383.324069)
			(xy 72.463006 -383.38956) (xy 72.471081 -383.456499) (xy 72.47108 -383.523925) (xy 72.463002 -383.590864)
			(xy 72.446964 -383.656354) (xy 72.423198 -383.719452) (xy 72.392045 -383.779248) (xy 72.353953 -383.834883)
			(xy 72.332088 -383.860548) (xy 72.326287 -383.86769) (xy 72.319775 -383.884883) (xy 72.319388 -383.894076)
			(xy 72.319388 -384.051556) (xy 72.318948 -384.061677) (xy 72.311212 -384.080382) (xy 72.296902 -384.094698)
			(xy 72.278201 -384.102443) (xy 72.26808 -384.102864) (xy 71.5518 -384.102864) (xy 71.541673 -384.102483)
			(xy 71.522963 -384.094728) (xy 71.508647 -384.0804) (xy 71.500908 -384.061683) (xy 71.500492 -384.051556)
			(xy 71.500492 -383.894076) (xy 71.500095 -383.884887) (xy 71.493572 -383.867703) (xy 71.487792 -383.860548)
			(xy 71.465944 -383.83487) (xy 71.427855 -383.779237) (xy 71.396704 -383.719442) (xy 71.37294 -383.656347)
			(xy 71.356903 -383.59086) (xy 71.348826 -383.523923) (xy 71.348825 -383.456501) (xy 71.356899 -383.389564)
			(xy 71.372933 -383.324076) (xy 71.396695 -383.26098) (xy 71.427843 -383.201184) (xy 71.465929 -383.145549)
			(xy 71.487792 -383.119884) (xy 71.493577 -383.11273) (xy 71.500099 -383.095546) (xy 71.500492 -383.086356)
			(xy 71.500492 -382.59385) (xy 71.50006 -382.584665) (xy 71.493562 -382.56748) (xy 71.487792 -382.560322)
			(xy 71.465918 -382.534665) (xy 71.427831 -382.479029) (xy 71.396681 -382.419231) (xy 71.372918 -382.356134)
			(xy 71.356883 -382.290644) (xy 71.348808 -382.223705) (xy 46.070794 -382.223705) (xy 46.062758 -382.290467)
			(xy 46.046786 -382.355849) (xy 46.023113 -382.418853) (xy 45.99208 -382.478576) (xy 45.954131 -382.534162)
			(xy 45.932344 -382.559814) (xy 45.926552 -382.566962) (xy 45.920036 -382.584151) (xy 45.919644 -382.593342)
			(xy 45.919644 -383.086864) (xy 45.920084 -383.096048) (xy 45.926578 -383.113232) (xy 45.932344 -383.120392)
			(xy 45.954148 -383.146031) (xy 45.992098 -383.201619) (xy 46.023131 -383.261344) (xy 46.04657 -383.323727)
			(xy 47.149191 -383.323727) (xy 47.149195 -383.256419) (xy 47.157243 -383.189593) (xy 47.173221 -383.124208)
			(xy 47.1969 -383.061202) (xy 47.22794 -383.001477) (xy 47.265897 -382.945892) (xy 47.287688 -382.92024)
			(xy 47.293491 -382.913099) (xy 47.300002 -382.895905) (xy 47.300388 -382.886712) (xy 47.300388 -382.728724)
			(xy 47.300841 -382.718573) (xy 47.308626 -382.699823) (xy 47.323013 -382.685499) (xy 47.341797 -382.677797)
			(xy 47.35195 -382.677416) (xy 48.06823 -382.677416) (xy 48.078356 -382.677901) (xy 48.097073 -382.685634)
			(xy 48.111427 -382.699921) (xy 48.11925 -382.718601) (xy 48.119792 -382.728724) (xy 48.119792 -382.886712)
			(xy 48.120198 -382.8959) (xy 48.126715 -382.913084) (xy 48.132492 -382.92024) (xy 48.154243 -382.945922)
			(xy 48.192191 -383.001505) (xy 48.223224 -383.061224) (xy 48.246898 -383.124225) (xy 48.262872 -383.189603)
			(xy 48.270919 -383.256422) (xy 48.270922 -383.323724) (xy 48.262882 -383.390543) (xy 48.246914 -383.455923)
			(xy 48.223247 -383.518926) (xy 48.192219 -383.578649) (xy 48.154277 -383.634236) (xy 48.132492 -383.659888)
			(xy 48.126675 -383.667018) (xy 48.120173 -383.68422) (xy 48.119792 -383.693416) (xy 48.119792 -384.186684)
			(xy 48.120212 -384.19587) (xy 48.126719 -384.213054) (xy 48.132492 -384.220212) (xy 48.154314 -384.245835)
			(xy 48.19226 -384.301427) (xy 48.22329 -384.361155) (xy 48.246959 -384.424163) (xy 48.262929 -384.489548)
			(xy 48.27097 -384.556373) (xy 48.270966 -384.623681) (xy 48.262919 -384.690505) (xy 48.246943 -384.755889)
			(xy 48.223268 -384.818895) (xy 48.192232 -384.87862) (xy 48.154281 -384.934207) (xy 48.132492 -384.95986)
			(xy 48.126687 -384.966999) (xy 48.120177 -384.984194) (xy 48.119792 -384.993388) (xy 48.119792 -385.151376)
			(xy 48.119359 -385.16153) (xy 48.11157 -385.180283) (xy 48.097176 -385.194608) (xy 48.078386 -385.202307)
			(xy 48.06823 -385.202684) (xy 47.35195 -385.202684) (xy 47.341829 -385.202133) (xy 47.323114 -385.194426)
			(xy 47.308757 -385.18016) (xy 47.300932 -385.161493) (xy 47.300388 -385.151376) (xy 47.300388 -384.993388)
			(xy 47.299986 -384.9842) (xy 47.293467 -384.967016) (xy 47.287688 -384.95986) (xy 47.265934 -384.934179)
			(xy 47.227981 -384.878598) (xy 47.196944 -384.818879) (xy 47.173267 -384.755878) (xy 47.15729 -384.690499)
			(xy 47.149242 -384.623679) (xy 47.149239 -384.556376) (xy 47.15728 -384.489554) (xy 47.173251 -384.424174)
			(xy 47.196921 -384.361171) (xy 47.227953 -384.301448) (xy 47.265901 -384.245863) (xy 47.287688 -384.220212)
			(xy 47.293503 -384.21308) (xy 47.300007 -384.195879) (xy 47.300388 -384.186684) (xy 47.300388 -383.693416)
			(xy 47.299973 -383.684229) (xy 47.293463 -383.667045) (xy 47.287688 -383.659888) (xy 47.265863 -383.634266)
			(xy 47.227913 -383.578676) (xy 47.196878 -383.518949) (xy 47.173205 -383.45594) (xy 47.157233 -383.390554)
			(xy 47.149191 -383.323727) (xy 46.04657 -383.323727) (xy 46.046804 -383.32435) (xy 46.062776 -383.389734)
			(xy 46.070819 -383.456559) (xy 46.070818 -383.523865) (xy 46.062772 -383.590689) (xy 46.046797 -383.656073)
			(xy 46.023121 -383.719078) (xy 45.992085 -383.778802) (xy 45.954133 -383.834388) (xy 45.932344 -383.86004)
			(xy 45.926541 -383.86718) (xy 45.920032 -383.884375) (xy 45.919644 -383.893568) (xy 45.919644 -384.051556)
			(xy 45.919143 -384.061702) (xy 45.91137 -384.080445) (xy 45.896998 -384.094768) (xy 45.878229 -384.102477)
			(xy 45.868082 -384.102864) (xy 45.151802 -384.102864) (xy 45.141676 -384.102372) (xy 45.122956 -384.094645)
			(xy 45.108599 -384.080361) (xy 45.100779 -384.06168) (xy 45.10024 -384.051556) (xy 45.10024 -383.893568)
			(xy 45.099836 -383.88438) (xy 45.093317 -383.867197) (xy 45.08754 -383.86004) (xy 45.065768 -383.834375)
			(xy 45.027819 -383.77879) (xy 44.996785 -383.719068) (xy 44.973111 -383.656066) (xy 44.957137 -383.590685)
			(xy 44.949092 -383.523864) (xy 44.94909 -383.45656) (xy 44.957133 -383.389739) (xy 44.973104 -383.324357)
			(xy 44.996775 -383.261354) (xy 45.027806 -383.20163) (xy 45.065753 -383.146044) (xy 45.08754 -383.120392)
			(xy 45.093328 -383.113241) (xy 45.099847 -383.096055) (xy 45.10024 -383.086864) (xy 45.10024 -382.593342)
			(xy 45.0998 -382.584158) (xy 45.093306 -382.566974) (xy 45.08754 -382.559814) (xy 45.065742 -382.53417)
			(xy 45.027794 -382.478582) (xy 44.996761 -382.418858) (xy 44.973088 -382.355852) (xy 44.957116 -382.290469)
			(xy 44.949073 -382.223645) (xy 41.671034 -382.223645) (xy 41.671034 -382.223704) (xy 41.662958 -382.290643)
			(xy 41.646922 -382.356132) (xy 41.623157 -382.419229) (xy 41.592004 -382.479024) (xy 41.553913 -382.534658)
			(xy 41.532048 -382.560322) (xy 41.526253 -382.567468) (xy 41.519739 -382.584658) (xy 41.519348 -382.59385)
			(xy 41.519348 -383.086356) (xy 41.519791 -383.095539) (xy 41.526283 -383.112723) (xy 41.532048 -383.119884)
			(xy 41.55393 -383.145535) (xy 41.592021 -383.201171) (xy 41.623174 -383.260968) (xy 41.646834 -383.323786)
			(xy 42.748896 -383.323786) (xy 42.748899 -383.25636) (xy 42.756978 -383.189419) (xy 42.773018 -383.123928)
			(xy 42.796786 -383.06083) (xy 42.827941 -383.001032) (xy 42.866034 -382.945397) (xy 42.8879 -382.919732)
			(xy 42.893708 -382.912595) (xy 42.900216 -382.895398) (xy 42.9006 -382.886204) (xy 42.9006 -382.728724)
			(xy 42.901035 -382.718603) (xy 42.908776 -382.6999) (xy 42.923086 -382.685585) (xy 42.941787 -382.677839)
			(xy 42.951908 -382.677416) (xy 43.668188 -382.677416) (xy 43.678312 -382.677826) (xy 43.697018 -382.685573)
			(xy 43.711333 -382.699892) (xy 43.719076 -382.7186) (xy 43.719496 -382.728724) (xy 43.719496 -382.886204)
			(xy 43.719905 -382.895391) (xy 43.72642 -382.912575) (xy 43.732196 -382.919732) (xy 43.754025 -382.945426)
			(xy 43.792115 -383.001057) (xy 43.823267 -383.060849) (xy 43.847034 -383.123942) (xy 43.863072 -383.189427)
			(xy 43.871151 -383.256363) (xy 43.871154 -383.323783) (xy 43.863081 -383.390719) (xy 43.84705 -383.456206)
			(xy 43.823289 -383.519302) (xy 43.792143 -383.579097) (xy 43.754058 -383.634731) (xy 43.732196 -383.660396)
			(xy 43.726418 -383.667554) (xy 43.719892 -383.684735) (xy 43.719496 -383.693924) (xy 43.719496 -384.186176)
			(xy 43.719919 -384.195362) (xy 43.726424 -384.212546) (xy 43.732196 -384.219704) (xy 43.754095 -384.24534)
			(xy 43.792183 -384.300979) (xy 43.823333 -384.360779) (xy 43.847095 -384.42388) (xy 43.863128 -384.489372)
			(xy 43.871201 -384.556314) (xy 43.871198 -384.62374) (xy 43.863118 -384.690681) (xy 43.847079 -384.756172)
			(xy 43.823311 -384.819271) (xy 43.792156 -384.879068) (xy 43.754062 -384.934703) (xy 43.732196 -384.960368)
			(xy 43.726388 -384.967505) (xy 43.71988 -384.984702) (xy 43.719496 -384.993896) (xy 43.719496 -385.151376)
			(xy 43.719064 -385.161497) (xy 43.711323 -385.180201) (xy 43.697011 -385.194517) (xy 43.678309 -385.202262)
			(xy 43.668188 -385.202684) (xy 42.951908 -385.202684) (xy 42.941784 -385.202277) (xy 42.923078 -385.194529)
			(xy 42.908762 -385.180209) (xy 42.90102 -385.1615) (xy 42.9006 -385.151376) (xy 42.9006 -384.993896)
			(xy 42.900192 -384.984709) (xy 42.893677 -384.967524) (xy 42.8879 -384.960368) (xy 42.866071 -384.934674)
			(xy 42.827982 -384.879043) (xy 42.796829 -384.819251) (xy 42.773063 -384.756158) (xy 42.757025 -384.690672)
			(xy 42.748946 -384.623737) (xy 42.748943 -384.556317) (xy 42.757015 -384.489381) (xy 42.773047 -384.423894)
			(xy 42.796807 -384.360798) (xy 42.827954 -384.301003) (xy 42.866038 -384.245369) (xy 42.8879 -384.219704)
			(xy 42.893677 -384.212545) (xy 42.900204 -384.195365) (xy 42.9006 -384.186176) (xy 42.9006 -383.693924)
			(xy 42.900178 -383.684738) (xy 42.893673 -383.667554) (xy 42.8879 -383.660396) (xy 42.866001 -383.63476)
			(xy 42.827913 -383.579121) (xy 42.796764 -383.519321) (xy 42.773002 -383.45622) (xy 42.756969 -383.390728)
			(xy 42.748896 -383.323786) (xy 41.646834 -383.323786) (xy 41.64694 -383.324067) (xy 41.662976 -383.389558)
			(xy 41.671051 -383.456499) (xy 41.67105 -383.523925) (xy 41.662971 -383.590865) (xy 41.646933 -383.656356)
			(xy 41.623164 -383.719454) (xy 41.592009 -383.77925) (xy 41.553915 -383.834884) (xy 41.532048 -383.860548)
			(xy 41.526242 -383.867686) (xy 41.519734 -383.884882) (xy 41.519348 -383.894076) (xy 41.519348 -384.051556)
			(xy 41.518849 -384.06167) (xy 41.511124 -384.080363) (xy 41.496834 -384.094677) (xy 41.478153 -384.102432)
			(xy 41.46804 -384.102864) (xy 40.75176 -384.102864) (xy 40.74163 -384.102516) (xy 40.722919 -384.094748)
			(xy 40.708605 -384.08041) (xy 40.700868 -384.061686) (xy 40.700452 -384.051556) (xy 40.700452 -383.894076)
			(xy 40.700042 -383.884889) (xy 40.693527 -383.867705) (xy 40.687752 -383.860548) (xy 40.665902 -383.834871)
			(xy 40.627809 -383.779239) (xy 40.596655 -383.719445) (xy 40.572888 -383.65635) (xy 40.556849 -383.590862)
			(xy 40.548772 -383.523924) (xy 40.54877 -383.4565) (xy 40.556845 -383.389562) (xy 40.572881 -383.324073)
			(xy 40.596645 -383.260977) (xy 40.627797 -383.201182) (xy 40.665887 -383.145548) (xy 40.687752 -383.119884)
			(xy 40.693544 -383.112736) (xy 40.70006 -383.095547) (xy 40.700452 -383.086356) (xy 40.700452 -382.59385)
			(xy 40.700006 -382.584667) (xy 40.693516 -382.567483) (xy 40.687752 -382.560322) (xy 40.665876 -382.534666)
			(xy 40.627785 -382.479031) (xy 40.596631 -382.419234) (xy 40.572865 -382.356136) (xy 40.556829 -382.290645)
			(xy 40.548753 -382.223705) (xy 37.271243 -382.223705) (xy 37.263167 -382.290643) (xy 37.247132 -382.356132)
			(xy 37.223367 -382.419228) (xy 37.192215 -382.479024) (xy 37.154125 -382.534657) (xy 37.13226 -382.560322)
			(xy 37.126467 -382.567469) (xy 37.119951 -382.584658) (xy 37.11956 -382.59385) (xy 37.11956 -383.086356)
			(xy 37.12 -383.09554) (xy 37.126494 -383.112724) (xy 37.13226 -383.119884) (xy 37.154141 -383.145536)
			(xy 37.192232 -383.201171) (xy 37.223384 -383.260969) (xy 37.247021 -383.323727) (xy 38.349127 -383.323727)
			(xy 38.349131 -383.256419) (xy 38.357178 -383.189595) (xy 38.373154 -383.124211) (xy 38.396829 -383.061205)
			(xy 38.427864 -383.00148) (xy 38.465815 -382.945893) (xy 38.487604 -382.92024) (xy 38.493409 -382.913101)
			(xy 38.499919 -382.895906) (xy 38.500304 -382.886712) (xy 38.500304 -382.728724) (xy 38.500741 -382.718571)
			(xy 38.50853 -382.699818) (xy 38.522922 -382.685494) (xy 38.541711 -382.677794) (xy 38.551866 -382.677416)
			(xy 39.268146 -382.677416) (xy 39.278273 -382.677888) (xy 39.29699 -382.685627) (xy 39.311344 -382.699917)
			(xy 39.319166 -382.7186) (xy 39.319708 -382.728724) (xy 39.319708 -382.886712) (xy 39.320111 -382.8959)
			(xy 39.326629 -382.913084) (xy 39.332408 -382.92024) (xy 39.354162 -382.945921) (xy 39.392115 -383.001502)
			(xy 39.423153 -383.061221) (xy 39.44683 -383.124222) (xy 39.462807 -383.189601) (xy 39.470855 -383.256421)
			(xy 39.470858 -383.323725) (xy 39.462817 -383.390546) (xy 39.446846 -383.455926) (xy 39.423175 -383.51893)
			(xy 39.392143 -383.578652) (xy 39.354195 -383.634237) (xy 39.332408 -383.659888) (xy 39.326592 -383.66702)
			(xy 39.320089 -383.684221) (xy 39.319708 -383.693416) (xy 39.319708 -384.186684) (xy 39.320124 -384.195871)
			(xy 39.326633 -384.213055) (xy 39.332408 -384.220212) (xy 39.354233 -384.245834) (xy 39.392184 -384.301424)
			(xy 39.423219 -384.361151) (xy 39.446892 -384.42416) (xy 39.462864 -384.489546) (xy 39.470906 -384.556373)
			(xy 39.470902 -384.623682) (xy 39.462854 -384.690507) (xy 39.446876 -384.755892) (xy 39.423196 -384.818898)
			(xy 39.392156 -384.878623) (xy 39.354199 -384.934209) (xy 39.332408 -384.95986) (xy 39.326604 -384.967)
			(xy 39.320094 -384.984195) (xy 39.319708 -384.993388) (xy 39.319708 -385.151376) (xy 39.319259 -385.161528)
			(xy 39.311473 -385.180278) (xy 39.297085 -385.194602) (xy 39.278299 -385.202304) (xy 39.268146 -385.202684)
			(xy 38.551866 -385.202684) (xy 38.54174 -385.202202) (xy 38.523023 -385.194468) (xy 38.508668 -385.18018)
			(xy 38.500846 -385.1615) (xy 38.500304 -385.151376) (xy 38.500304 -384.993388) (xy 38.499899 -384.9842)
			(xy 38.493381 -384.967016) (xy 38.487604 -384.95986) (xy 38.465853 -384.934178) (xy 38.427905 -384.878595)
			(xy 38.396872 -384.818875) (xy 38.373199 -384.755875) (xy 38.357224 -384.690497) (xy 38.349178 -384.623678)
			(xy 38.349175 -384.556376) (xy 38.357215 -384.489557) (xy 38.373183 -384.424177) (xy 38.39685 -384.361174)
			(xy 38.427877 -384.301451) (xy 38.465819 -384.245865) (xy 38.487604 -384.220212) (xy 38.493421 -384.213081)
			(xy 38.499923 -384.19588) (xy 38.500304 -384.186684) (xy 38.500304 -383.693416) (xy 38.499885 -383.68423)
			(xy 38.493377 -383.667045) (xy 38.487604 -383.659888) (xy 38.465782 -383.634264) (xy 38.427837 -383.578673)
			(xy 38.396807 -383.518945) (xy 38.373138 -383.455937) (xy 38.357168 -383.390552) (xy 38.349127 -383.323727)
			(xy 37.247021 -383.323727) (xy 37.247149 -383.324068) (xy 37.263185 -383.389559) (xy 37.27126 -383.456499)
			(xy 37.271259 -383.523925) (xy 37.263181 -383.590865) (xy 37.247142 -383.656355) (xy 37.223374 -383.719453)
			(xy 37.19222 -383.77925) (xy 37.154126 -383.834883) (xy 37.13226 -383.860548) (xy 37.126456 -383.867687)
			(xy 37.119947 -383.884883) (xy 37.11956 -383.894076) (xy 37.11956 -384.051556) (xy 37.119147 -384.061681)
			(xy 37.111406 -384.080391) (xy 37.097087 -384.094708) (xy 37.078377 -384.102448) (xy 37.068252 -384.102864)
			(xy 36.351972 -384.102864) (xy 36.341843 -384.102506) (xy 36.323132 -384.094742) (xy 36.308817 -384.080407)
			(xy 36.30108 -384.061685) (xy 36.300664 -384.051556) (xy 36.300664 -383.894076) (xy 36.300251 -383.884889)
			(xy 36.293738 -383.867706) (xy 36.287964 -383.860548) (xy 36.266117 -383.834869) (xy 36.22803 -383.779236)
			(xy 36.196881 -383.719441) (xy 36.173117 -383.656346) (xy 36.157082 -383.590859) (xy 36.149005 -383.523923)
			(xy 36.149004 -383.456501) (xy 36.157078 -383.389565) (xy 36.17311 -383.324077) (xy 36.196871 -383.260981)
			(xy 36.228018 -383.201185) (xy 36.266102 -383.14555) (xy 36.287964 -383.119884) (xy 36.293758 -383.112737)
			(xy 36.300272 -383.095548) (xy 36.300664 -383.086356) (xy 36.300664 -382.59385) (xy 36.300216 -382.584667)
			(xy 36.293727 -382.567483) (xy 36.287964 -382.560322) (xy 36.266091 -382.534664) (xy 36.228005 -382.479028)
			(xy 36.196857 -382.41923) (xy 36.173095 -382.356132) (xy 36.157061 -382.290643) (xy 36.148987 -382.223704)
			(xy 32.870916 -382.223704) (xy 32.86288 -382.290466) (xy 32.846909 -382.355848) (xy 32.823237 -382.418852)
			(xy 32.792206 -382.478575) (xy 32.754259 -382.534162) (xy 32.732472 -382.559814) (xy 32.726683 -382.566965)
			(xy 32.720165 -382.584151) (xy 32.719772 -382.593342) (xy 32.719772 -383.086864) (xy 32.720206 -383.096049)
			(xy 32.726704 -383.113233) (xy 32.732472 -383.120392) (xy 32.754275 -383.146031) (xy 32.792223 -383.20162)
			(xy 32.823255 -383.261345) (xy 32.846714 -383.323786) (xy 33.948808 -383.323786) (xy 33.948811 -383.25636)
			(xy 33.956891 -383.189419) (xy 33.972931 -383.123927) (xy 33.996699 -383.060829) (xy 34.027855 -383.001032)
			(xy 34.065949 -382.945397) (xy 34.087816 -382.919732) (xy 34.093626 -382.912596) (xy 34.100132 -382.895398)
			(xy 34.100516 -382.886204) (xy 34.100516 -382.728724) (xy 34.100936 -382.718601) (xy 34.108679 -382.699895)
			(xy 34.122995 -382.685579) (xy 34.141701 -382.677836) (xy 34.151824 -382.677416) (xy 34.868104 -382.677416)
			(xy 34.878229 -382.677813) (xy 34.896935 -382.685566) (xy 34.91125 -382.699888) (xy 34.918992 -382.718599)
			(xy 34.919412 -382.728724) (xy 34.919412 -382.886204) (xy 34.919818 -382.895392) (xy 34.926334 -382.912576)
			(xy 34.932112 -382.919732) (xy 34.95394 -382.945427) (xy 34.992029 -383.001057) (xy 35.023181 -383.060849)
			(xy 35.046946 -383.123942) (xy 35.062984 -383.189428) (xy 35.071063 -383.256363) (xy 35.071066 -383.323783)
			(xy 35.062994 -383.390719) (xy 35.046962 -383.456206) (xy 35.023203 -383.519301) (xy 34.992057 -383.579096)
			(xy 34.953973 -383.634731) (xy 34.932112 -383.660396) (xy 34.926336 -383.667556) (xy 34.919809 -383.684735)
			(xy 34.919412 -383.693924) (xy 34.919412 -384.186176) (xy 34.919831 -384.195362) (xy 34.926338 -384.212547)
			(xy 34.932112 -384.219704) (xy 34.954011 -384.24534) (xy 34.992098 -384.300979) (xy 35.023246 -384.36078)
			(xy 35.047008 -384.42388) (xy 35.06304 -384.489373) (xy 35.071113 -384.556314) (xy 35.07111 -384.62374)
			(xy 35.063031 -384.690681) (xy 35.046992 -384.756172) (xy 35.023224 -384.81927) (xy 34.99207 -384.879067)
			(xy 34.953978 -384.934703) (xy 34.932112 -384.960368) (xy 34.926305 -384.967506) (xy 34.919796 -384.984702)
			(xy 34.919412 -384.993896) (xy 34.919412 -385.151376) (xy 34.918965 -385.161495) (xy 34.911227 -385.180196)
			(xy 34.89692 -385.194511) (xy 34.878223 -385.202259) (xy 34.868104 -385.202684) (xy 34.151824 -385.202684)
			(xy 34.141701 -385.202264) (xy 34.122995 -385.194521) (xy 34.108679 -385.180205) (xy 34.100936 -385.161499)
			(xy 34.100516 -385.151376) (xy 34.100516 -384.993896) (xy 34.100104 -384.984709) (xy 34.093591 -384.967525)
			(xy 34.087816 -384.960368) (xy 34.065987 -384.934674) (xy 34.027896 -384.879044) (xy 33.996743 -384.819252)
			(xy 33.972976 -384.756159) (xy 33.956937 -384.690673) (xy 33.948858 -384.623738) (xy 33.948855 -384.556316)
			(xy 33.956928 -384.48938) (xy 33.97296 -384.423893) (xy 33.996721 -384.360798) (xy 34.027868 -384.301003)
			(xy 34.065954 -384.245369) (xy 34.087816 -384.219704) (xy 34.093595 -384.212547) (xy 34.10012 -384.195365)
			(xy 34.100516 -384.186176) (xy 34.100516 -383.693924) (xy 34.100091 -383.684739) (xy 34.093587 -383.667554)
			(xy 34.087816 -383.660396) (xy 34.065916 -383.63476) (xy 34.027827 -383.579122) (xy 33.996677 -383.519322)
			(xy 33.972915 -383.456221) (xy 33.956881 -383.390728) (xy 33.948808 -383.323786) (xy 32.846714 -383.323786)
			(xy 32.846926 -383.324351) (xy 32.862898 -383.389735) (xy 32.87094 -383.456559) (xy 32.870939 -383.523865)
			(xy 32.862893 -383.590689) (xy 32.846919 -383.656072) (xy 32.823245 -383.719077) (xy 32.79221 -383.778801)
			(xy 32.75426 -383.834388) (xy 32.732472 -383.86004) (xy 32.726672 -383.867183) (xy 32.72016 -383.884375)
			(xy 32.719772 -383.893568) (xy 32.719772 -384.051556) (xy 32.719342 -384.061711) (xy 32.711555 -384.080468)
			(xy 32.697161 -384.094793) (xy 32.678367 -384.10249) (xy 32.66821 -384.102864) (xy 31.95193 -384.102864)
			(xy 31.941806 -384.102349) (xy 31.923086 -384.094632) (xy 31.908729 -384.080354) (xy 31.900908 -384.061678)
			(xy 31.900368 -384.051556) (xy 31.900368 -383.893568) (xy 31.899958 -383.884381) (xy 31.893443 -383.867197)
			(xy 31.887668 -383.86004) (xy 31.865895 -383.834375) (xy 31.827944 -383.778791) (xy 31.796908 -383.71907)
			(xy 31.773234 -383.656067) (xy 31.757259 -383.590686) (xy 31.749213 -383.523864) (xy 31.749211 -383.45656)
			(xy 31.757254 -383.389738) (xy 31.773226 -383.324356) (xy 31.796899 -383.261352) (xy 31.827932 -383.201629)
			(xy 31.86588 -383.146044) (xy 31.887668 -383.120392) (xy 31.893459 -383.113243) (xy 31.899975 -383.096055)
			(xy 31.900368 -383.086864) (xy 31.900368 -382.593342) (xy 31.899923 -382.584159) (xy 31.893432 -382.566975)
			(xy 31.887668 -382.559814) (xy 31.86587 -382.53417) (xy 31.827919 -382.478583) (xy 31.796885 -382.418859)
			(xy 31.773211 -382.355853) (xy 31.757238 -382.29047) (xy 31.749194 -382.223646) (xy 28.471155 -382.223646)
			(xy 28.471155 -382.223704) (xy 28.463079 -382.290642) (xy 28.447044 -382.356131) (xy 28.42328 -382.419228)
			(xy 28.392129 -382.479023) (xy 28.35404 -382.534657) (xy 28.332176 -382.560322) (xy 28.326385 -382.567471)
			(xy 28.319868 -382.584659) (xy 28.319476 -382.59385) (xy 28.319476 -383.086356) (xy 28.319913 -383.09554)
			(xy 28.326409 -383.112725) (xy 28.332176 -383.119884) (xy 28.354057 -383.145536) (xy 28.392146 -383.201172)
			(xy 28.423298 -383.26097) (xy 28.446934 -383.323727) (xy 29.549039 -383.323727) (xy 29.549043 -383.256419)
			(xy 29.55709 -383.189594) (xy 29.573066 -383.12421) (xy 29.596742 -383.061205) (xy 29.627779 -383.00148)
			(xy 29.665731 -382.945892) (xy 29.68752 -382.92024) (xy 29.693327 -382.913102) (xy 29.699835 -382.895906)
			(xy 29.70022 -382.886712) (xy 29.70022 -382.728724) (xy 29.700636 -382.718601) (xy 29.70838 -382.699894)
			(xy 29.722697 -382.685578) (xy 29.741405 -382.677835) (xy 29.751528 -382.677416) (xy 30.468062 -382.677416)
			(xy 30.478183 -382.677957) (xy 30.496899 -382.685668) (xy 30.511256 -382.699938) (xy 30.51908 -382.718606)
			(xy 30.519624 -382.728724) (xy 30.519624 -382.886712) (xy 30.520023 -382.8959) (xy 30.526544 -382.913085)
			(xy 30.532324 -382.92024) (xy 30.554077 -382.945921) (xy 30.59203 -383.001502) (xy 30.623067 -383.061222)
			(xy 30.646743 -383.124222) (xy 30.66272 -383.189601) (xy 30.670767 -383.256421) (xy 30.67077 -383.323724)
			(xy 30.662729 -383.390545) (xy 30.646759 -383.455926) (xy 30.623089 -383.518929) (xy 30.592058 -383.578651)
			(xy 30.554111 -383.634236) (xy 30.532324 -383.659888) (xy 30.52651 -383.667021) (xy 30.520005 -383.684221)
			(xy 30.519624 -383.693416) (xy 30.519624 -384.186684) (xy 30.520036 -384.195871) (xy 30.526548 -384.213056)
			(xy 30.532324 -384.220212) (xy 30.554149 -384.245834) (xy 30.592099 -384.301424) (xy 30.623132 -384.361152)
			(xy 30.646805 -384.42416) (xy 30.662776 -384.489546) (xy 30.670818 -384.556373) (xy 30.670815 -384.623681)
			(xy 30.662767 -384.690507) (xy 30.646789 -384.755892) (xy 30.62311 -384.818898) (xy 30.592071 -384.878622)
			(xy 30.554115 -384.934209) (xy 30.532324 -384.95986) (xy 30.526522 -384.967002) (xy 30.52001 -384.984195)
			(xy 30.519624 -384.993388) (xy 30.519624 -385.151376) (xy 30.519165 -385.161494) (xy 30.511429 -385.180193)
			(xy 30.497126 -385.194507) (xy 30.478434 -385.202257) (xy 30.468316 -385.202684) (xy 29.751782 -385.202684)
			(xy 29.741657 -385.202189) (xy 29.72294 -385.19446) (xy 29.708585 -385.180177) (xy 29.700762 -385.161498)
			(xy 29.70022 -385.151376) (xy 29.70022 -384.993388) (xy 29.699811 -384.984201) (xy 29.693296 -384.967017)
			(xy 29.68752 -384.95986) (xy 29.665769 -384.934178) (xy 29.62782 -384.878596) (xy 29.596786 -384.818876)
			(xy 29.573112 -384.755875) (xy 29.557137 -384.690497) (xy 29.549091 -384.623678) (xy 29.549087 -384.556376)
			(xy 29.557128 -384.489556) (xy 29.573096 -384.424176) (xy 29.596764 -384.361174) (xy 29.627792 -384.301451)
			(xy 29.665735 -384.245865) (xy 29.68752 -384.220212) (xy 29.693339 -384.213083) (xy 29.69984 -384.19588)
			(xy 29.70022 -384.186684) (xy 29.70022 -383.693416) (xy 29.699797 -383.68423) (xy 29.693292 -383.667046)
			(xy 29.68752 -383.659888) (xy 29.665697 -383.634265) (xy 29.627751 -383.578674) (xy 29.59672 -383.518946)
			(xy 29.57305 -383.455938) (xy 29.55708 -383.390552) (xy 29.549039 -383.323727) (xy 28.446934 -383.323727)
			(xy 28.447062 -383.324068) (xy 28.463097 -383.389559) (xy 28.471172 -383.456499) (xy 28.471171 -383.523925)
			(xy 28.463093 -383.590865) (xy 28.447055 -383.656355) (xy 28.423288 -383.719452) (xy 28.392134 -383.779249)
			(xy 28.354042 -383.834883) (xy 28.332176 -383.860548) (xy 28.326374 -383.867689) (xy 28.319863 -383.884883)
			(xy 28.319476 -383.894076) (xy 28.319476 -384.051556) (xy 28.319047 -384.061679) (xy 28.311309 -384.080386)
			(xy 28.296996 -384.094702) (xy 28.27829 -384.102445) (xy 28.268168 -384.102864) (xy 27.551888 -384.102864)
			(xy 27.54176 -384.102493) (xy 27.523049 -384.094734) (xy 27.508734 -384.080404) (xy 27.500996 -384.061684)
			(xy 27.50058 -384.051556) (xy 27.50058 -383.894076) (xy 27.500186 -383.884887) (xy 27.493661 -383.867703)
			(xy 27.48788 -383.860548) (xy 27.466032 -383.834869) (xy 27.427945 -383.779236) (xy 27.396794 -383.719442)
			(xy 27.37303 -383.656347) (xy 27.356994 -383.59086) (xy 27.348917 -383.523923) (xy 27.348916 -383.456501)
			(xy 27.35699 -383.389564) (xy 27.373023 -383.324076) (xy 27.396784 -383.26098) (xy 27.427932 -383.201184)
			(xy 27.466018 -383.14555) (xy 27.48788 -383.119884) (xy 27.493664 -383.112729) (xy 27.500187 -383.095546)
			(xy 27.50058 -383.086356) (xy 27.50058 -382.59385) (xy 27.50015 -382.584665) (xy 27.49365 -382.56748)
			(xy 27.48788 -382.560322) (xy 27.466007 -382.534665) (xy 27.42792 -382.479028) (xy 27.396771 -382.419231)
			(xy 27.373008 -382.356133) (xy 27.356974 -382.290643) (xy 27.348899 -382.223705) (xy 0.509016 -382.223705)
			(xy 0.509016 -385.583938) (xy 100.447856 -385.583938) (xy 100.447856 -384.720338) (xy 100.448346 -384.690354)
			(xy 100.456174 -384.630898) (xy 100.471695 -384.572973) (xy 100.494644 -384.517569) (xy 100.524628 -384.465635)
			(xy 100.561134 -384.418059) (xy 100.603539 -384.375654) (xy 100.651115 -384.339148) (xy 100.703049 -384.309164)
			(xy 100.758453 -384.286215) (xy 100.816378 -384.270694) (xy 100.875834 -384.262866) (xy 100.935802 -384.262866)
			(xy 100.995258 -384.270694) (xy 101.053183 -384.286215) (xy 101.108587 -384.309164) (xy 101.160521 -384.339148)
			(xy 101.208097 -384.375654) (xy 101.250502 -384.418059) (xy 101.287008 -384.465635) (xy 101.316992 -384.517569)
			(xy 101.339941 -384.572973) (xy 101.355462 -384.630898) (xy 101.36329 -384.690354) (xy 101.36378 -384.720338)
			(xy 101.36378 -385.319283) (xy 104.635826 -385.319283) (xy 104.635826 -385.259317) (xy 104.643653 -385.199864)
			(xy 104.659172 -385.141942) (xy 104.682119 -385.08654) (xy 104.7121 -385.034608) (xy 104.748603 -384.987032)
			(xy 104.791004 -384.944628) (xy 104.838576 -384.908121) (xy 104.890506 -384.878136) (xy 104.945906 -384.855184)
			(xy 105.003827 -384.83966) (xy 105.063279 -384.831828) (xy 105.093262 -384.831336) (xy 105.956862 -384.831336)
			(xy 105.986849 -384.831807) (xy 106.046311 -384.83963) (xy 106.104243 -384.855149) (xy 106.159653 -384.878097)
			(xy 106.211594 -384.908081) (xy 106.259176 -384.944589) (xy 106.301586 -384.986995) (xy 106.338098 -385.034574)
			(xy 106.368087 -385.086513) (xy 106.391039 -385.141921) (xy 106.406562 -385.199852) (xy 106.414391 -385.259313)
			(xy 106.414391 -385.319287) (xy 106.406562 -385.378748) (xy 106.391039 -385.436679) (xy 106.368087 -385.492087)
			(xy 106.338098 -385.544026) (xy 106.301586 -385.591605) (xy 106.259176 -385.634011) (xy 106.211594 -385.670519)
			(xy 106.159653 -385.700503) (xy 106.104243 -385.723451) (xy 106.046311 -385.73897) (xy 105.986849 -385.746793)
			(xy 105.956862 -385.74726) (xy 105.093262 -385.74726) (xy 105.063279 -385.746772) (xy 105.003827 -385.73894)
			(xy 104.945906 -385.723416) (xy 104.890506 -385.700464) (xy 104.838576 -385.670479) (xy 104.791004 -385.633972)
			(xy 104.748603 -385.591568) (xy 104.7121 -385.543992) (xy 104.682119 -385.49206) (xy 104.659172 -385.436658)
			(xy 104.643653 -385.378736) (xy 104.635826 -385.319283) (xy 101.36378 -385.319283) (xy 101.36378 -385.583938)
			(xy 101.36329 -385.613922) (xy 101.355462 -385.673378) (xy 101.339941 -385.731303) (xy 101.316992 -385.786707)
			(xy 101.287008 -385.838641) (xy 101.250502 -385.886217) (xy 101.208097 -385.928622) (xy 101.160521 -385.965128)
			(xy 101.108587 -385.995112) (xy 101.053183 -386.018061) (xy 100.995258 -386.033582) (xy 100.935802 -386.04141)
			(xy 100.875834 -386.04141) (xy 100.816378 -386.033582) (xy 100.758453 -386.018061) (xy 100.703049 -385.995112)
			(xy 100.651115 -385.965128) (xy 100.603539 -385.928622) (xy 100.561134 -385.886217) (xy 100.524628 -385.838641)
			(xy 100.494644 -385.786707) (xy 100.471695 -385.731303) (xy 100.456174 -385.673378) (xy 100.448346 -385.613922)
			(xy 100.447856 -385.583938) (xy 0.509016 -385.583938) (xy 0.509016 -388.37489) (xy 1.56972 -388.37489)
			(xy 1.56972 -387.51129) (xy 1.57021 -387.481322) (xy 1.578033 -387.4219) (xy 1.593546 -387.364007)
			(xy 1.616482 -387.308634) (xy 1.646449 -387.256728) (xy 1.682936 -387.209178) (xy 1.725316 -387.166798)
			(xy 1.772866 -387.130311) (xy 1.824772 -387.100344) (xy 1.880145 -387.077408) (xy 1.938038 -387.061895)
			(xy 1.99746 -387.054072) (xy 2.057396 -387.054072) (xy 2.116818 -387.061895) (xy 2.174711 -387.077408)
			(xy 2.230084 -387.100344) (xy 2.28199 -387.130311) (xy 2.32954 -387.166798) (xy 2.37192 -387.209178)
			(xy 2.408407 -387.256728) (xy 2.438374 -387.308634) (xy 2.46131 -387.364007) (xy 2.476823 -387.4219)
			(xy 2.484646 -387.481322) (xy 2.485136 -387.51129) (xy 2.485136 -388.37489) (xy 2.484646 -388.404858)
			(xy 2.476823 -388.46428) (xy 2.46131 -388.522173) (xy 2.438374 -388.577546) (xy 2.408407 -388.629452)
			(xy 2.37192 -388.677002) (xy 2.32954 -388.719382) (xy 2.28199 -388.755869) (xy 2.230084 -388.785836)
			(xy 2.174711 -388.808772) (xy 2.116818 -388.824285) (xy 2.057396 -388.832108) (xy 1.99746 -388.832108)
			(xy 1.938038 -388.824285) (xy 1.880145 -388.808772) (xy 1.824772 -388.785836) (xy 1.772866 -388.755869)
			(xy 1.725316 -388.719382) (xy 1.682936 -388.677002) (xy 1.646449 -388.629452) (xy 1.616482 -388.577546)
			(xy 1.593546 -388.522173) (xy 1.578033 -388.46428) (xy 1.57021 -388.404858) (xy 1.56972 -388.37489)
			(xy 0.509016 -388.37489) (xy 0.509016 -398.164722) (xy 3.141726 -398.164722) (xy 3.141726 -398.035362)
			(xy 3.149849 -397.906256) (xy 3.166062 -397.777916) (xy 3.190302 -397.650846) (xy 3.222472 -397.52555)
			(xy 3.262447 -397.40252) (xy 3.310068 -397.282244) (xy 3.365147 -397.165195) (xy 3.427467 -397.051835)
			(xy 3.496782 -396.942612) (xy 3.572818 -396.837957) (xy 3.655276 -396.738283) (xy 3.743829 -396.643983)
			(xy 3.838129 -396.55543) (xy 3.937803 -396.472972) (xy 4.042458 -396.396936) (xy 4.151681 -396.327621)
			(xy 4.265041 -396.265301) (xy 4.38209 -396.210222) (xy 4.502366 -396.162601) (xy 4.625396 -396.122626)
			(xy 4.750692 -396.090456) (xy 4.877762 -396.066216) (xy 5.006102 -396.050003) (xy 5.135208 -396.04188)
			(xy 5.199888 -396.041372) (xy 6.800088 -396.041372) (xy 6.864769 -396.041866) (xy 6.993875 -396.049988)
			(xy 7.122217 -396.066201) (xy 7.249287 -396.090441) (xy 7.374584 -396.122612) (xy 7.497614 -396.162587)
			(xy 7.617892 -396.210208) (xy 7.734942 -396.265287) (xy 7.848302 -396.327608) (xy 7.957526 -396.396923)
			(xy 8.062181 -396.47296) (xy 8.161856 -396.555418) (xy 8.256157 -396.643972) (xy 8.344711 -396.738272)
			(xy 8.427169 -396.837947) (xy 8.503206 -396.942603) (xy 8.572521 -397.051826) (xy 8.634842 -397.165187)
			(xy 8.689921 -397.282236) (xy 8.737543 -397.402514) (xy 8.777518 -397.525544) (xy 8.809688 -397.650841)
			(xy 8.833928 -397.777911) (xy 8.839736 -397.823885) (xy 27.348879 -397.823885) (xy 27.348883 -397.756458)
			(xy 27.356962 -397.689518) (xy 27.373001 -397.624027) (xy 27.396769 -397.560929) (xy 27.427923 -397.501131)
			(xy 27.466014 -397.445496) (xy 27.48788 -397.41983) (xy 27.493686 -397.412692) (xy 27.500196 -397.395496)
			(xy 27.50058 -397.386302) (xy 27.50058 -396.89405) (xy 27.50015 -396.884865) (xy 27.49365 -396.86768)
			(xy 27.48788 -396.860522) (xy 27.466007 -396.834865) (xy 27.42792 -396.779228) (xy 27.396771 -396.719431)
			(xy 27.373008 -396.656333) (xy 27.356974 -396.590843) (xy 27.348899 -396.523905) (xy 27.3489 -396.45648)
			(xy 27.356976 -396.389542) (xy 27.373012 -396.324053) (xy 27.396777 -396.260955) (xy 27.427928 -396.201159)
			(xy 27.466016 -396.145524) (xy 27.48788 -396.119858) (xy 27.493675 -396.112711) (xy 27.500191 -396.095522)
			(xy 27.50058 -396.08633) (xy 27.50058 -395.92885) (xy 27.501069 -395.918722) (xy 27.508787 -395.899994)
			(xy 27.523074 -395.885635) (xy 27.541762 -395.877821) (xy 27.551888 -395.877288) (xy 28.268168 -395.877288)
			(xy 28.278319 -395.877747) (xy 28.297068 -395.88553) (xy 28.311392 -395.899915) (xy 28.319095 -395.918698)
			(xy 28.319476 -395.92885) (xy 28.319476 -396.08633) (xy 28.319877 -396.095518) (xy 28.326398 -396.112702)
			(xy 28.332176 -396.119858) (xy 28.354031 -396.145531) (xy 28.392122 -396.201164) (xy 28.423274 -396.260959)
			(xy 28.44704 -396.324055) (xy 28.463077 -396.389543) (xy 28.471154 -396.456481) (xy 28.471155 -396.523904)
			(xy 28.463079 -396.590842) (xy 28.447044 -396.656331) (xy 28.42328 -396.719428) (xy 28.392129 -396.779223)
			(xy 28.35404 -396.834857) (xy 28.332176 -396.860522) (xy 28.326385 -396.867671) (xy 28.319868 -396.884859)
			(xy 28.319476 -396.89405) (xy 28.319476 -397.386302) (xy 28.31989 -397.395489) (xy 28.326402 -397.412673)
			(xy 28.332176 -397.41983) (xy 28.354003 -397.445526) (xy 28.392095 -397.501155) (xy 28.420857 -397.556356)
			(xy 29.549071 -397.556356) (xy 29.557114 -397.489534) (xy 29.573085 -397.424153) (xy 29.596756 -397.361149)
			(xy 29.627787 -397.301425) (xy 29.665733 -397.245838) (xy 29.68752 -397.220186) (xy 29.693307 -397.213034)
			(xy 29.699827 -397.195849) (xy 29.70022 -397.186658) (xy 29.70022 -397.028924) (xy 29.700641 -397.018769)
			(xy 29.708433 -397.000013) (xy 29.72283 -396.985688) (xy 29.741625 -396.977991) (xy 29.751782 -396.977616)
			(xy 30.468062 -396.977616) (xy 30.478183 -396.978157) (xy 30.496899 -396.985868) (xy 30.511256 -397.000138)
			(xy 30.51908 -397.018806) (xy 30.519624 -397.028924) (xy 30.519624 -397.186658) (xy 30.520049 -397.195844)
			(xy 30.526552 -397.213029) (xy 30.532324 -397.220186) (xy 30.554123 -397.24583) (xy 30.592074 -397.301416)
			(xy 30.623108 -397.361141) (xy 30.646782 -397.424147) (xy 30.662756 -397.48953) (xy 30.6708 -397.556354)
			(xy 30.670799 -397.623661) (xy 30.662753 -397.690485) (xy 30.646778 -397.755868) (xy 30.623102 -397.818873)
			(xy 30.620528 -397.823826) (xy 31.749174 -397.823826) (xy 31.749178 -397.756517) (xy 31.757226 -397.689691)
			(xy 31.773204 -397.624307) (xy 31.796882 -397.5613) (xy 31.827922 -397.501576) (xy 31.865877 -397.44599)
			(xy 31.887668 -397.420338) (xy 31.893482 -397.413205) (xy 31.899984 -397.396005) (xy 31.900368 -397.38681)
			(xy 31.900368 -396.893542) (xy 31.899923 -396.884359) (xy 31.893432 -396.867175) (xy 31.887668 -396.860014)
			(xy 31.86587 -396.83437) (xy 31.827919 -396.778783) (xy 31.796885 -396.719059) (xy 31.773211 -396.656053)
			(xy 31.757238 -396.59067) (xy 31.749194 -396.523846) (xy 31.749195 -396.456539) (xy 31.757241 -396.389716)
			(xy 31.773216 -396.324332) (xy 31.796891 -396.261327) (xy 31.827927 -396.201604) (xy 31.865879 -396.146018)
			(xy 31.887668 -396.120366) (xy 31.89347 -396.113225) (xy 31.899979 -396.096031) (xy 31.900368 -396.086838)
			(xy 31.900368 -395.92885) (xy 31.900805 -395.918678) (xy 31.90858 -395.899879) (xy 31.922962 -395.885491)
			(xy 31.941758 -395.877709) (xy 31.95193 -395.877288) (xy 32.66821 -395.877288) (xy 32.678388 -395.877657)
			(xy 32.697193 -395.885455) (xy 32.711579 -395.899858) (xy 32.719355 -395.918671) (xy 32.719772 -395.92885)
			(xy 32.719772 -396.086838) (xy 32.72017 -396.096026) (xy 32.726693 -396.11321) (xy 32.732472 -396.120366)
			(xy 32.75425 -396.146026) (xy 32.792198 -396.201612) (xy 32.823231 -396.261334) (xy 32.846904 -396.324338)
			(xy 32.862877 -396.389719) (xy 32.870922 -396.45654) (xy 32.870923 -396.523845) (xy 32.86288 -396.590666)
			(xy 32.846909 -396.656048) (xy 32.823237 -396.719052) (xy 32.792206 -396.778775) (xy 32.754259 -396.834362)
			(xy 32.732472 -396.860014) (xy 32.726683 -396.867165) (xy 32.720165 -396.884351) (xy 32.719772 -396.893542)
			(xy 32.719772 -397.38681) (xy 32.720183 -397.395997) (xy 32.726697 -397.413181) (xy 32.732472 -397.420338)
			(xy 32.754222 -397.446021) (xy 32.792171 -397.501603) (xy 32.820593 -397.556296) (xy 33.948839 -397.556296)
			(xy 33.956914 -397.489358) (xy 33.972949 -397.423869) (xy 33.996713 -397.360773) (xy 34.027863 -397.300977)
			(xy 34.065952 -397.245343) (xy 34.087816 -397.219678) (xy 34.093606 -397.212528) (xy 34.100124 -397.195341)
			(xy 34.100516 -397.18615) (xy 34.100516 -397.028924) (xy 34.100936 -397.018801) (xy 34.108679 -397.000095)
			(xy 34.122995 -396.985779) (xy 34.141701 -396.978036) (xy 34.151824 -396.977616) (xy 34.868104 -396.977616)
			(xy 34.878229 -396.978013) (xy 34.896935 -396.985766) (xy 34.91125 -397.000088) (xy 34.918992 -397.018799)
			(xy 34.919412 -397.028924) (xy 34.919412 -397.18615) (xy 34.919843 -397.195335) (xy 34.926342 -397.21252)
			(xy 34.932112 -397.219678) (xy 34.953985 -397.245335) (xy 34.992073 -397.300971) (xy 35.023223 -397.360769)
			(xy 35.046986 -397.423867) (xy 35.06302 -397.489356) (xy 35.071095 -397.556295) (xy 35.071094 -397.62372)
			(xy 35.063017 -397.690658) (xy 35.046981 -397.756148) (xy 35.023216 -397.819245) (xy 35.020799 -397.823884)
			(xy 36.148967 -397.823884) (xy 36.148971 -397.756458) (xy 36.15705 -397.689518) (xy 36.173088 -397.624028)
			(xy 36.196855 -397.560929) (xy 36.228008 -397.501132) (xy 36.266099 -397.445496) (xy 36.287964 -397.41983)
			(xy 36.293781 -397.412699) (xy 36.300282 -397.395497) (xy 36.300664 -397.386302) (xy 36.300664 -396.89405)
			(xy 36.300216 -396.884867) (xy 36.293727 -396.867683) (xy 36.287964 -396.860522) (xy 36.266091 -396.834864)
			(xy 36.228005 -396.779228) (xy 36.196857 -396.71943) (xy 36.173095 -396.656332) (xy 36.157061 -396.590843)
			(xy 36.148987 -396.523904) (xy 36.148988 -396.456481) (xy 36.157064 -396.389542) (xy 36.1731 -396.324053)
			(xy 36.196863 -396.260956) (xy 36.228013 -396.201159) (xy 36.266101 -396.145524) (xy 36.287964 -396.119858)
			(xy 36.293769 -396.112719) (xy 36.300277 -396.095523) (xy 36.300664 -396.08633) (xy 36.300664 -395.92885)
			(xy 36.301168 -395.918724) (xy 36.308884 -395.899999) (xy 36.323166 -395.88564) (xy 36.341848 -395.877823)
			(xy 36.351972 -395.877288) (xy 37.068252 -395.877288) (xy 37.078402 -395.877761) (xy 37.097151 -395.885538)
			(xy 37.111475 -395.899919) (xy 37.119179 -395.918699) (xy 37.11956 -395.92885) (xy 37.11956 -396.08633)
			(xy 37.119965 -396.095518) (xy 37.126483 -396.112701) (xy 37.13226 -396.119858) (xy 37.154116 -396.145531)
			(xy 37.192207 -396.201163) (xy 37.223361 -396.260958) (xy 37.247127 -396.324054) (xy 37.263164 -396.389543)
			(xy 37.271242 -396.456481) (xy 37.271243 -396.523904) (xy 37.263167 -396.590843) (xy 37.247132 -396.656332)
			(xy 37.223367 -396.719428) (xy 37.192215 -396.779224) (xy 37.154125 -396.834857) (xy 37.13226 -396.860522)
			(xy 37.126467 -396.867669) (xy 37.119951 -396.884858) (xy 37.11956 -396.89405) (xy 37.11956 -397.386302)
			(xy 37.119978 -397.395488) (xy 37.126487 -397.412672) (xy 37.13226 -397.41983) (xy 37.154088 -397.445525)
			(xy 37.192181 -397.501155) (xy 37.220943 -397.556356) (xy 38.349159 -397.556356) (xy 38.357201 -397.489534)
			(xy 38.373172 -397.424153) (xy 38.396842 -397.361149) (xy 38.427873 -397.301426) (xy 38.465818 -397.245839)
			(xy 38.487604 -397.220186) (xy 38.493389 -397.213033) (xy 38.499911 -397.195848) (xy 38.500304 -397.186658)
			(xy 38.500304 -397.028924) (xy 38.500741 -397.018771) (xy 38.50853 -397.000018) (xy 38.522922 -396.985694)
			(xy 38.541711 -396.977994) (xy 38.551866 -396.977616) (xy 39.268146 -396.977616) (xy 39.278273 -396.978088)
			(xy 39.29699 -396.985827) (xy 39.311344 -397.000117) (xy 39.319166 -397.0188) (xy 39.319708 -397.028924)
			(xy 39.319708 -397.186658) (xy 39.320136 -397.195843) (xy 39.326637 -397.213028) (xy 39.332408 -397.220186)
			(xy 39.354207 -397.245829) (xy 39.392159 -397.301416) (xy 39.423195 -397.36114) (xy 39.446869 -397.424146)
			(xy 39.462843 -397.48953) (xy 39.470887 -397.556354) (xy 39.470887 -397.623661) (xy 39.462841 -397.690485)
			(xy 39.446865 -397.755869) (xy 39.423189 -397.818874) (xy 39.420585 -397.823885) (xy 40.548734 -397.823885)
			(xy 40.548737 -397.756458) (xy 40.556817 -397.689516) (xy 40.572859 -397.624024) (xy 40.596629 -397.560925)
			(xy 40.627787 -397.501128) (xy 40.665884 -397.445494) (xy 40.687752 -397.41983) (xy 40.693567 -397.412698)
			(xy 40.700069 -397.395497) (xy 40.700452 -397.386302) (xy 40.700452 -396.89405) (xy 40.700006 -396.884867)
			(xy 40.693516 -396.867683) (xy 40.687752 -396.860522) (xy 40.665876 -396.834866) (xy 40.627785 -396.779231)
			(xy 40.596631 -396.719434) (xy 40.572865 -396.656336) (xy 40.556829 -396.590845) (xy 40.548753 -396.523905)
			(xy 40.548754 -396.45648) (xy 40.556832 -396.38954) (xy 40.57287 -396.32405) (xy 40.596638 -396.260952)
			(xy 40.627792 -396.201156) (xy 40.665886 -396.145522) (xy 40.687752 -396.119858) (xy 40.693555 -396.112718)
			(xy 40.700065 -396.095523) (xy 40.700452 -396.08633) (xy 40.700452 -395.92885) (xy 40.700968 -395.918725)
			(xy 40.708682 -395.900003) (xy 40.722959 -395.885644) (xy 40.741638 -395.877825) (xy 40.75176 -395.877288)
			(xy 41.46804 -395.877288) (xy 41.478195 -395.877689) (xy 41.496946 -395.885495) (xy 41.511268 -395.899898)
			(xy 41.518968 -395.918693) (xy 41.519348 -395.92885) (xy 41.519348 -396.08633) (xy 41.519755 -396.095517)
			(xy 41.526272 -396.112701) (xy 41.532048 -396.119858) (xy 41.553904 -396.14553) (xy 41.591996 -396.201163)
			(xy 41.62315 -396.260957) (xy 41.646917 -396.324053) (xy 41.662955 -396.389542) (xy 41.671033 -396.456481)
			(xy 41.671034 -396.523904) (xy 41.662958 -396.590843) (xy 41.646922 -396.656332) (xy 41.623157 -396.719429)
			(xy 41.592004 -396.779224) (xy 41.553913 -396.834858) (xy 41.532048 -396.860522) (xy 41.526253 -396.867668)
			(xy 41.519739 -396.884858) (xy 41.519348 -396.89405) (xy 41.519348 -397.386302) (xy 41.519769 -397.395488)
			(xy 41.526276 -397.412672) (xy 41.532048 -397.41983) (xy 41.553876 -397.445525) (xy 41.59197 -397.501154)
			(xy 41.620702 -397.556296) (xy 42.748927 -397.556296) (xy 42.757002 -397.489358) (xy 42.773037 -397.42387)
			(xy 42.7968 -397.360774) (xy 42.827949 -397.300978) (xy 42.866037 -397.245343) (xy 42.8879 -397.219678)
			(xy 42.893688 -397.212527) (xy 42.900208 -397.195341) (xy 42.9006 -397.18615) (xy 42.9006 -397.028924)
			(xy 42.901035 -397.018803) (xy 42.908776 -397.0001) (xy 42.923086 -396.985785) (xy 42.941787 -396.978039)
			(xy 42.951908 -396.977616) (xy 43.668188 -396.977616) (xy 43.678312 -396.978026) (xy 43.697018 -396.985773)
			(xy 43.711333 -397.000092) (xy 43.719076 -397.0188) (xy 43.719496 -397.028924) (xy 43.719496 -397.18615)
			(xy 43.719931 -397.195335) (xy 43.726427 -397.212519) (xy 43.732196 -397.219678) (xy 43.75407 -397.245335)
			(xy 43.792159 -397.300971) (xy 43.823309 -397.360768) (xy 43.847073 -397.423866) (xy 43.863108 -397.489356)
			(xy 43.871183 -397.556295) (xy 43.871182 -397.62372) (xy 43.863105 -397.690659) (xy 43.847068 -397.756148)
			(xy 43.823303 -397.819246) (xy 43.820917 -397.823825) (xy 44.949053 -397.823825) (xy 44.949057 -397.756517)
			(xy 44.957105 -397.689692) (xy 44.973082 -397.624308) (xy 44.996759 -397.561302) (xy 45.027796 -397.501577)
			(xy 45.06575 -397.44599) (xy 45.08754 -397.420338) (xy 45.09335 -397.413203) (xy 45.099856 -397.396004)
			(xy 45.10024 -397.38681) (xy 45.10024 -396.893542) (xy 45.0998 -396.884358) (xy 45.093306 -396.867174)
			(xy 45.08754 -396.860014) (xy 45.065742 -396.83437) (xy 45.027794 -396.778782) (xy 44.996761 -396.719058)
			(xy 44.973088 -396.656052) (xy 44.957116 -396.590669) (xy 44.949073 -396.523845) (xy 44.949074 -396.45654)
			(xy 44.957119 -396.389716) (xy 44.973093 -396.324333) (xy 44.996767 -396.261328) (xy 45.027801 -396.201605)
			(xy 45.065751 -396.146018) (xy 45.08754 -396.120366) (xy 45.093339 -396.113222) (xy 45.099851 -396.096031)
			(xy 45.10024 -396.086838) (xy 45.10024 -395.92885) (xy 45.100705 -395.918681) (xy 45.108474 -395.899887)
			(xy 45.122847 -395.885501) (xy 45.141634 -395.877714) (xy 45.151802 -395.877288) (xy 45.868082 -395.877288)
			(xy 45.878259 -395.87768) (xy 45.897063 -395.885468) (xy 45.91145 -395.899864) (xy 45.919227 -395.918673)
			(xy 45.919644 -395.92885) (xy 45.919644 -396.086838) (xy 45.920049 -396.096026) (xy 45.926568 -396.113209)
			(xy 45.932344 -396.120366) (xy 45.954122 -396.146026) (xy 45.992072 -396.201611) (xy 46.023107 -396.261333)
			(xy 46.046781 -396.324337) (xy 46.062755 -396.389718) (xy 46.070801 -396.45654) (xy 46.070801 -396.523845)
			(xy 46.062758 -396.590667) (xy 46.046786 -396.656049) (xy 46.023113 -396.719053) (xy 45.99208 -396.778776)
			(xy 45.954131 -396.834362) (xy 45.932344 -396.860014) (xy 45.926552 -396.867162) (xy 45.920036 -396.884351)
			(xy 45.919644 -396.893542) (xy 45.919644 -397.38681) (xy 45.920062 -397.395996) (xy 45.926572 -397.41318)
			(xy 45.932344 -397.420338) (xy 45.954095 -397.446021) (xy 45.992046 -397.501602) (xy 46.020501 -397.556355)
			(xy 47.149223 -397.556355) (xy 47.157267 -397.489532) (xy 47.17324 -397.42415) (xy 47.196914 -397.361146)
			(xy 47.227949 -397.301423) (xy 47.265899 -397.245837) (xy 47.287688 -397.220186) (xy 47.293472 -397.213032)
			(xy 47.299994 -397.195848) (xy 47.300388 -397.186658) (xy 47.300388 -397.028924) (xy 47.300841 -397.018773)
			(xy 47.308626 -397.000023) (xy 47.323013 -396.985699) (xy 47.341797 -396.977997) (xy 47.35195 -396.977616)
			(xy 48.06823 -396.977616) (xy 48.078356 -396.978101) (xy 48.097073 -396.985834) (xy 48.111427 -397.000121)
			(xy 48.11925 -397.018801) (xy 48.119792 -397.028924) (xy 48.119792 -397.186658) (xy 48.120224 -397.195843)
			(xy 48.126723 -397.213027) (xy 48.132492 -397.220186) (xy 48.154289 -397.24583) (xy 48.192235 -397.301419)
			(xy 48.223266 -397.361144) (xy 48.246937 -397.424149) (xy 48.262908 -397.489532) (xy 48.270951 -397.556355)
			(xy 48.27095 -397.62366) (xy 48.262906 -397.690483) (xy 48.246933 -397.755865) (xy 48.22326 -397.81887)
			(xy 48.192227 -397.878594) (xy 48.154279 -397.934181) (xy 48.132492 -397.959834) (xy 48.126698 -397.966981)
			(xy 48.120182 -397.98417) (xy 48.119792 -397.993362) (xy 48.119792 -398.486884) (xy 48.120212 -398.49607)
			(xy 48.126719 -398.513254) (xy 48.132492 -398.520412) (xy 48.154314 -398.546035) (xy 48.19226 -398.601627)
			(xy 48.22329 -398.661355) (xy 48.246959 -398.724363) (xy 48.262929 -398.789748) (xy 48.27097 -398.856573)
			(xy 48.270966 -398.923881) (xy 48.262919 -398.990705) (xy 48.246943 -399.056089) (xy 48.223268 -399.119095)
			(xy 48.192232 -399.17882) (xy 48.154281 -399.234407) (xy 48.132492 -399.26006) (xy 48.126687 -399.267199)
			(xy 48.120177 -399.284394) (xy 48.119792 -399.293588) (xy 48.119792 -399.451576) (xy 48.119359 -399.46173)
			(xy 48.11157 -399.480483) (xy 48.097176 -399.494808) (xy 48.078386 -399.502507) (xy 48.06823 -399.502884)
			(xy 47.35195 -399.502884) (xy 47.341829 -399.502333) (xy 47.323114 -399.494626) (xy 47.308757 -399.48036)
			(xy 47.300932 -399.461693) (xy 47.300388 -399.451576) (xy 47.300388 -399.293588) (xy 47.299986 -399.2844)
			(xy 47.293467 -399.267216) (xy 47.287688 -399.26006) (xy 47.265934 -399.234379) (xy 47.227981 -399.178798)
			(xy 47.196944 -399.119079) (xy 47.173267 -399.056078) (xy 47.15729 -398.990699) (xy 47.149242 -398.923879)
			(xy 47.149239 -398.856576) (xy 47.15728 -398.789754) (xy 47.173251 -398.724374) (xy 47.196921 -398.661371)
			(xy 47.227953 -398.601648) (xy 47.265901 -398.546063) (xy 47.287688 -398.520412) (xy 47.293503 -398.51328)
			(xy 47.300007 -398.496079) (xy 47.300388 -398.486884) (xy 47.300388 -397.993362) (xy 47.299999 -397.984172)
			(xy 47.293471 -397.966988) (xy 47.287688 -397.959834) (xy 47.265909 -397.934174) (xy 47.227956 -397.87859)
			(xy 47.19692 -397.818868) (xy 47.173244 -397.755864) (xy 47.157269 -397.690483) (xy 47.149224 -397.62366)
			(xy 47.149223 -397.556355) (xy 46.020501 -397.556355) (xy 46.023082 -397.561322) (xy 46.046757 -397.624322)
			(xy 46.062733 -397.689701) (xy 46.070781 -397.75652) (xy 46.070784 -397.823823) (xy 46.062744 -397.890643)
			(xy 46.046774 -397.956023) (xy 46.023105 -398.019026) (xy 45.992075 -398.078748) (xy 45.95413 -398.134334)
			(xy 45.932344 -398.159986) (xy 45.926522 -398.167113) (xy 45.920024 -398.184318) (xy 45.919644 -398.193514)
			(xy 45.919644 -398.351502) (xy 45.919237 -398.361676) (xy 45.911448 -398.380474) (xy 45.897057 -398.39486)
			(xy 45.878256 -398.402641) (xy 45.868082 -398.403064) (xy 45.151802 -398.403064) (xy 45.141645 -398.402565)
			(xy 45.122876 -398.394792) (xy 45.108511 -398.380427) (xy 45.100736 -398.361659) (xy 45.10024 -398.351502)
			(xy 45.10024 -398.193514) (xy 45.099814 -398.184329) (xy 45.093311 -398.167145) (xy 45.08754 -398.159986)
			(xy 45.065715 -398.134365) (xy 45.027767 -398.078774) (xy 44.996735 -398.019046) (xy 44.973065 -397.956037)
			(xy 44.957094 -397.890651) (xy 44.949053 -397.823825) (xy 43.820917 -397.823825) (xy 43.792151 -397.879042)
			(xy 43.754061 -397.934677) (xy 43.732196 -397.960342) (xy 43.726399 -397.967487) (xy 43.719885 -397.984678)
			(xy 43.719496 -397.99387) (xy 43.719496 -398.486376) (xy 43.719919 -398.495562) (xy 43.726424 -398.512746)
			(xy 43.732196 -398.519904) (xy 43.754095 -398.54554) (xy 43.792183 -398.601179) (xy 43.823333 -398.660979)
			(xy 43.847095 -398.72408) (xy 43.863128 -398.789572) (xy 43.871201 -398.856514) (xy 43.871198 -398.92394)
			(xy 43.863118 -398.990881) (xy 43.847079 -399.056372) (xy 43.823311 -399.119471) (xy 43.792156 -399.179268)
			(xy 43.754062 -399.234903) (xy 43.732196 -399.260568) (xy 43.726388 -399.267705) (xy 43.71988 -399.284902)
			(xy 43.719496 -399.294096) (xy 43.719496 -399.451576) (xy 43.719064 -399.461697) (xy 43.711323 -399.480401)
			(xy 43.697011 -399.494717) (xy 43.678309 -399.502462) (xy 43.668188 -399.502884) (xy 42.951908 -399.502884)
			(xy 42.941784 -399.502477) (xy 42.923078 -399.494729) (xy 42.908762 -399.480409) (xy 42.90102 -399.4617)
			(xy 42.9006 -399.451576) (xy 42.9006 -399.294096) (xy 42.900192 -399.284909) (xy 42.893677 -399.267724)
			(xy 42.8879 -399.260568) (xy 42.866071 -399.234874) (xy 42.827982 -399.179243) (xy 42.796829 -399.119451)
			(xy 42.773063 -399.056358) (xy 42.757025 -398.990872) (xy 42.748946 -398.923937) (xy 42.748943 -398.856517)
			(xy 42.757015 -398.789581) (xy 42.773047 -398.724094) (xy 42.796807 -398.660998) (xy 42.827954 -398.601203)
			(xy 42.866038 -398.545569) (xy 42.8879 -398.519904) (xy 42.893677 -398.512745) (xy 42.900204 -398.495565)
			(xy 42.9006 -398.486376) (xy 42.9006 -397.99387) (xy 42.900204 -397.984681) (xy 42.893681 -397.967497)
			(xy 42.8879 -397.960342) (xy 42.866046 -397.934669) (xy 42.827957 -397.879035) (xy 42.796806 -397.81924)
			(xy 42.773041 -397.756144) (xy 42.757005 -397.690656) (xy 42.748928 -397.623719) (xy 42.748927 -397.556296)
			(xy 41.620702 -397.556296) (xy 41.623125 -397.560946) (xy 41.646894 -397.624039) (xy 41.662933 -397.689525)
			(xy 41.671013 -397.756461) (xy 41.671016 -397.823882) (xy 41.662944 -397.890819) (xy 41.646911 -397.956307)
			(xy 41.623148 -398.019402) (xy 41.591999 -398.079197) (xy 41.553912 -398.13483) (xy 41.532048 -398.160494)
			(xy 41.526265 -398.167649) (xy 41.519744 -398.184832) (xy 41.519348 -398.194022) (xy 41.519348 -398.351502)
			(xy 41.518875 -398.36163) (xy 41.511144 -398.380354) (xy 41.496853 -398.39471) (xy 41.478166 -398.402527)
			(xy 41.46804 -398.403064) (xy 40.75176 -398.403064) (xy 40.741599 -398.40271) (xy 40.722839 -398.394895)
			(xy 40.708515 -398.380477) (xy 40.700824 -398.361666) (xy 40.700452 -398.351502) (xy 40.700452 -398.194022)
			(xy 40.70002 -398.184837) (xy 40.69352 -398.167653) (xy 40.687752 -398.160494) (xy 40.665849 -398.13486)
			(xy 40.627758 -398.079223) (xy 40.596606 -398.019423) (xy 40.572842 -397.956321) (xy 40.556807 -397.890828)
			(xy 40.548734 -397.823885) (xy 39.420585 -397.823885) (xy 39.392151 -397.878597) (xy 39.354198 -397.934183)
			(xy 39.332408 -397.959834) (xy 39.326615 -397.966982) (xy 39.320098 -397.98417) (xy 39.319708 -397.993362)
			(xy 39.319708 -398.486884) (xy 39.320124 -398.496071) (xy 39.326633 -398.513255) (xy 39.332408 -398.520412)
			(xy 39.354233 -398.546034) (xy 39.392184 -398.601624) (xy 39.423219 -398.661351) (xy 39.446892 -398.72436)
			(xy 39.462864 -398.789746) (xy 39.470906 -398.856573) (xy 39.470902 -398.923882) (xy 39.462854 -398.990707)
			(xy 39.446876 -399.056092) (xy 39.423196 -399.119098) (xy 39.392156 -399.178823) (xy 39.354199 -399.234409)
			(xy 39.332408 -399.26006) (xy 39.326604 -399.2672) (xy 39.320094 -399.284395) (xy 39.319708 -399.293588)
			(xy 39.319708 -399.451576) (xy 39.319259 -399.461728) (xy 39.311473 -399.480478) (xy 39.297085 -399.494802)
			(xy 39.278299 -399.502504) (xy 39.268146 -399.502884) (xy 38.551866 -399.502884) (xy 38.54174 -399.502402)
			(xy 38.523023 -399.494668) (xy 38.508668 -399.48038) (xy 38.500846 -399.4617) (xy 38.500304 -399.451576)
			(xy 38.500304 -399.293588) (xy 38.499899 -399.2844) (xy 38.493381 -399.267216) (xy 38.487604 -399.26006)
			(xy 38.465853 -399.234378) (xy 38.427905 -399.178795) (xy 38.396872 -399.119075) (xy 38.373199 -399.056075)
			(xy 38.357224 -398.990697) (xy 38.349178 -398.923878) (xy 38.349175 -398.856576) (xy 38.357215 -398.789757)
			(xy 38.373183 -398.724377) (xy 38.39685 -398.661374) (xy 38.427877 -398.601651) (xy 38.465819 -398.546065)
			(xy 38.487604 -398.520412) (xy 38.493421 -398.513281) (xy 38.499923 -398.49608) (xy 38.500304 -398.486884)
			(xy 38.500304 -397.993362) (xy 38.499911 -397.984173) (xy 38.493385 -397.966989) (xy 38.487604 -397.959834)
			(xy 38.465827 -397.934173) (xy 38.42788 -397.878587) (xy 38.396849 -397.818865) (xy 38.373177 -397.755861)
			(xy 38.357204 -397.69048) (xy 38.34916 -397.623659) (xy 38.349159 -397.556356) (xy 37.220943 -397.556356)
			(xy 37.223335 -397.560946) (xy 37.247103 -397.624039) (xy 37.263142 -397.689525) (xy 37.271222 -397.756461)
			(xy 37.271225 -397.823882) (xy 37.263153 -397.890819) (xy 37.24712 -397.956306) (xy 37.223358 -398.019402)
			(xy 37.19221 -398.079196) (xy 37.154123 -398.134829) (xy 37.13226 -398.160494) (xy 37.126478 -398.16765)
			(xy 37.119956 -398.184832) (xy 37.11956 -398.194022) (xy 37.11956 -398.351502) (xy 37.119075 -398.361629)
			(xy 37.111347 -398.38035) (xy 37.09706 -398.394706) (xy 37.078376 -398.402525) (xy 37.068252 -398.403064)
			(xy 36.351972 -398.403064) (xy 36.341812 -398.402701) (xy 36.323052 -398.394889) (xy 36.308728 -398.380474)
			(xy 36.301036 -398.361665) (xy 36.300664 -398.351502) (xy 36.300664 -398.194022) (xy 36.300229 -398.184838)
			(xy 36.293731 -398.167654) (xy 36.287964 -398.160494) (xy 36.266064 -398.134859) (xy 36.227979 -398.079219)
			(xy 36.196832 -398.019419) (xy 36.173071 -397.956318) (xy 36.15704 -397.890825) (xy 36.148967 -397.823884)
			(xy 35.020799 -397.823884) (xy 34.992065 -397.879042) (xy 34.953976 -397.934677) (xy 34.932112 -397.960342)
			(xy 34.926316 -397.967488) (xy 34.919801 -397.984678) (xy 34.919412 -397.99387) (xy 34.919412 -398.486376)
			(xy 34.919831 -398.495562) (xy 34.926338 -398.512747) (xy 34.932112 -398.519904) (xy 34.954011 -398.54554)
			(xy 34.992098 -398.601179) (xy 35.023246 -398.66098) (xy 35.047008 -398.72408) (xy 35.06304 -398.789573)
			(xy 35.071113 -398.856514) (xy 35.07111 -398.92394) (xy 35.063031 -398.990881) (xy 35.046992 -399.056372)
			(xy 35.023224 -399.11947) (xy 34.99207 -399.179267) (xy 34.953978 -399.234903) (xy 34.932112 -399.260568)
			(xy 34.926305 -399.267706) (xy 34.919796 -399.284902) (xy 34.919412 -399.294096) (xy 34.919412 -399.451576)
			(xy 34.918965 -399.461695) (xy 34.911227 -399.480396) (xy 34.89692 -399.494711) (xy 34.878223 -399.502459)
			(xy 34.868104 -399.502884) (xy 34.151824 -399.502884) (xy 34.141701 -399.502464) (xy 34.122995 -399.494721)
			(xy 34.108679 -399.480405) (xy 34.100936 -399.461699) (xy 34.100516 -399.451576) (xy 34.100516 -399.294096)
			(xy 34.100104 -399.284909) (xy 34.093591 -399.267725) (xy 34.087816 -399.260568) (xy 34.065987 -399.234874)
			(xy 34.027896 -399.179244) (xy 33.996743 -399.119452) (xy 33.972976 -399.056359) (xy 33.956937 -398.990873)
			(xy 33.948858 -398.923938) (xy 33.948855 -398.856516) (xy 33.956928 -398.78958) (xy 33.97296 -398.724093)
			(xy 33.996721 -398.660998) (xy 34.027868 -398.601203) (xy 34.065954 -398.545569) (xy 34.087816 -398.519904)
			(xy 34.093595 -398.512747) (xy 34.10012 -398.495565) (xy 34.100516 -398.486376) (xy 34.100516 -397.99387)
			(xy 34.100117 -397.984682) (xy 34.093595 -397.967498) (xy 34.087816 -397.960342) (xy 34.065961 -397.934669)
			(xy 34.027871 -397.879036) (xy 33.996719 -397.819241) (xy 33.972954 -397.756145) (xy 33.956917 -397.690657)
			(xy 33.94884 -397.623719) (xy 33.948839 -397.556296) (xy 32.820593 -397.556296) (xy 32.823205 -397.561323)
			(xy 32.84688 -397.624323) (xy 32.862855 -397.689702) (xy 32.870902 -397.756521) (xy 32.870905 -397.823822)
			(xy 32.862865 -397.890642) (xy 32.846897 -397.956022) (xy 32.823229 -398.019025) (xy 32.7922 -398.078747)
			(xy 32.754257 -398.134334) (xy 32.732472 -398.159986) (xy 32.726653 -398.167115) (xy 32.720152 -398.184318)
			(xy 32.719772 -398.193514) (xy 32.719772 -398.351502) (xy 32.719268 -398.361659) (xy 32.711495 -398.380426)
			(xy 32.697133 -398.394791) (xy 32.678367 -398.402567) (xy 32.66821 -398.403064) (xy 31.95193 -398.403064)
			(xy 31.941761 -398.402611) (xy 31.922967 -398.394837) (xy 31.908581 -398.38046) (xy 31.900795 -398.361671)
			(xy 31.900368 -398.351502) (xy 31.900368 -398.193514) (xy 31.899936 -398.184329) (xy 31.893436 -398.167146)
			(xy 31.887668 -398.159986) (xy 31.865842 -398.134365) (xy 31.827892 -398.078775) (xy 31.796859 -398.019047)
			(xy 31.773187 -397.956039) (xy 31.757216 -397.890652) (xy 31.749174 -397.823826) (xy 30.620528 -397.823826)
			(xy 30.592066 -397.878596) (xy 30.554113 -397.934182) (xy 30.532324 -397.959834) (xy 30.526533 -397.966984)
			(xy 30.520014 -397.984171) (xy 30.519624 -397.993362) (xy 30.519624 -398.486884) (xy 30.520036 -398.496071)
			(xy 30.526548 -398.513256) (xy 30.532324 -398.520412) (xy 30.554149 -398.546034) (xy 30.592099 -398.601624)
			(xy 30.623132 -398.661352) (xy 30.646805 -398.72436) (xy 30.662776 -398.789746) (xy 30.670818 -398.856573)
			(xy 30.670815 -398.923881) (xy 30.662767 -398.990707) (xy 30.646789 -399.056092) (xy 30.62311 -399.119098)
			(xy 30.592071 -399.178822) (xy 30.554115 -399.234409) (xy 30.532324 -399.26006) (xy 30.526522 -399.267202)
			(xy 30.52001 -399.284395) (xy 30.519624 -399.293588) (xy 30.519624 -399.451576) (xy 30.519159 -399.461726)
			(xy 30.511376 -399.480473) (xy 30.496993 -399.494796) (xy 30.478213 -399.502501) (xy 30.468062 -399.502884)
			(xy 29.751782 -399.502884) (xy 29.741657 -399.502389) (xy 29.72294 -399.49466) (xy 29.708585 -399.480377)
			(xy 29.700762 -399.461698) (xy 29.70022 -399.451576) (xy 29.70022 -399.293588) (xy 29.699811 -399.284401)
			(xy 29.693296 -399.267217) (xy 29.68752 -399.26006) (xy 29.665769 -399.234378) (xy 29.62782 -399.178796)
			(xy 29.596786 -399.119076) (xy 29.573112 -399.056075) (xy 29.557137 -398.990697) (xy 29.549091 -398.923878)
			(xy 29.549087 -398.856576) (xy 29.557128 -398.789756) (xy 29.573096 -398.724376) (xy 29.596764 -398.661374)
			(xy 29.627792 -398.601651) (xy 29.665735 -398.546065) (xy 29.68752 -398.520412) (xy 29.693339 -398.513283)
			(xy 29.69984 -398.49608) (xy 29.70022 -398.486884) (xy 29.70022 -397.993362) (xy 29.699824 -397.984173)
			(xy 29.6933 -397.966989) (xy 29.68752 -397.959834) (xy 29.665743 -397.934174) (xy 29.627795 -397.878588)
			(xy 29.596762 -397.818865) (xy 29.57309 -397.755862) (xy 29.557116 -397.690481) (xy 29.549072 -397.623659)
			(xy 29.549071 -397.556356) (xy 28.420857 -397.556356) (xy 28.423249 -397.560947) (xy 28.447016 -397.62404)
			(xy 28.463055 -397.689526) (xy 28.471134 -397.756461) (xy 28.471138 -397.823882) (xy 28.463065 -397.890818)
			(xy 28.447033 -397.956305) (xy 28.423272 -398.019401) (xy 28.392124 -398.079196) (xy 28.354039 -398.134829)
			(xy 28.332176 -398.160494) (xy 28.326397 -398.167651) (xy 28.319873 -398.184833) (xy 28.319476 -398.194022)
			(xy 28.319476 -398.351502) (xy 28.318975 -398.361627) (xy 28.31125 -398.380345) (xy 28.296968 -398.394701)
			(xy 28.27829 -398.402523) (xy 28.268168 -398.403064) (xy 27.551888 -398.403064) (xy 27.541729 -398.402688)
			(xy 27.522969 -398.394881) (xy 27.508645 -398.38047) (xy 27.500952 -398.361664) (xy 27.50058 -398.351502)
			(xy 27.50058 -398.194022) (xy 27.500164 -398.184835) (xy 27.493655 -398.167651) (xy 27.48788 -398.160494)
			(xy 27.465979 -398.134859) (xy 27.427893 -398.07922) (xy 27.396745 -398.019419) (xy 27.372984 -397.956318)
			(xy 27.356952 -397.890826) (xy 27.348879 -397.823885) (xy 8.839736 -397.823885) (xy 8.850142 -397.906253)
			(xy 8.858264 -398.035359) (xy 8.858264 -398.164721) (xy 8.850142 -398.293827) (xy 8.833928 -398.422169)
			(xy 8.809688 -398.549239) (xy 8.777518 -398.674536) (xy 8.737543 -398.797566) (xy 8.689921 -398.917844)
			(xy 8.634842 -399.034893) (xy 8.572521 -399.148254) (xy 8.503206 -399.257477) (xy 8.427169 -399.362133)
			(xy 8.344711 -399.461808) (xy 8.256157 -399.556108) (xy 8.161856 -399.644662) (xy 8.062181 -399.72712)
			(xy 7.957526 -399.803157) (xy 7.848302 -399.872472) (xy 7.734942 -399.934793) (xy 7.617892 -399.989872)
			(xy 7.497614 -400.037493) (xy 7.374584 -400.077468) (xy 7.249287 -400.109639) (xy 7.122217 -400.133879)
			(xy 6.993875 -400.150092) (xy 6.864769 -400.158214) (xy 6.800088 -400.158712) (xy 5.199888 -400.158712)
			(xy 5.135208 -400.158204) (xy 5.006102 -400.150081) (xy 4.877762 -400.133868) (xy 4.750692 -400.109628)
			(xy 4.625396 -400.077458) (xy 4.502366 -400.037483) (xy 4.38209 -399.989862) (xy 4.265041 -399.934783)
			(xy 4.151681 -399.872463) (xy 4.042458 -399.803148) (xy 3.937803 -399.727112) (xy 3.838129 -399.644654)
			(xy 3.743829 -399.556101) (xy 3.655276 -399.461801) (xy 3.572818 -399.362127) (xy 3.496782 -399.257472)
			(xy 3.427467 -399.148249) (xy 3.365147 -399.034889) (xy 3.310068 -398.91784) (xy 3.262447 -398.797564)
			(xy 3.222472 -398.674534) (xy 3.190302 -398.549238) (xy 3.166062 -398.422168) (xy 3.149849 -398.293828)
			(xy 3.141726 -398.164722) (xy 0.509016 -398.164722) (xy 0.509016 -401.723796) (xy 27.348891 -401.723796)
			(xy 27.348893 -401.656371) (xy 27.35697 -401.589432) (xy 27.373007 -401.523942) (xy 27.396773 -401.460844)
			(xy 27.427925 -401.401047) (xy 27.466015 -401.345412) (xy 27.48788 -401.319746) (xy 27.49368 -401.312603)
			(xy 27.500193 -401.295411) (xy 27.50058 -401.286218) (xy 27.50058 -400.793966) (xy 27.500191 -400.784777)
			(xy 27.493663 -400.767592) (xy 27.48788 -400.760438) (xy 27.466023 -400.734768) (xy 27.427935 -400.679133)
			(xy 27.396785 -400.619338) (xy 27.373022 -400.556241) (xy 27.356986 -400.490753) (xy 27.34891 -400.423816)
			(xy 27.34891 -400.356393) (xy 27.356985 -400.289456) (xy 27.373019 -400.223967) (xy 27.396782 -400.160871)
			(xy 27.42793 -400.101074) (xy 27.466017 -400.04544) (xy 27.48788 -400.019774) (xy 27.493668 -400.012622)
			(xy 27.500188 -399.995437) (xy 27.50058 -399.986246) (xy 27.50058 -399.828766) (xy 27.501 -399.818632)
			(xy 27.508746 -399.799903) (xy 27.523053 -399.785546) (xy 27.541756 -399.777735) (xy 27.551888 -399.777204)
			(xy 28.268168 -399.777204) (xy 28.278321 -399.777648) (xy 28.297073 -399.785433) (xy 28.311398 -399.799824)
			(xy 28.319098 -399.818612) (xy 28.319476 -399.828766) (xy 28.319476 -399.986246) (xy 28.319918 -399.99543)
			(xy 28.32641 -400.012614) (xy 28.332176 -400.019774) (xy 28.354047 -400.045434) (xy 28.392137 -400.101069)
			(xy 28.423289 -400.160865) (xy 28.447053 -400.223963) (xy 28.463089 -400.289453) (xy 28.471165 -400.356392)
			(xy 28.471165 -400.423817) (xy 28.463088 -400.490756) (xy 28.447051 -400.556246) (xy 28.423285 -400.619343)
			(xy 28.392132 -400.679139) (xy 28.354041 -400.734773) (xy 28.332176 -400.760438) (xy 28.326378 -400.767582)
			(xy 28.319865 -400.784774) (xy 28.319476 -400.793966) (xy 28.319476 -401.286218) (xy 28.319883 -401.295405)
			(xy 28.326399 -401.31259) (xy 28.332176 -401.319746) (xy 28.354019 -401.345429) (xy 28.39211 -401.40106)
			(xy 28.423263 -401.460854) (xy 28.446989 -401.523838) (xy 29.549051 -401.523838) (xy 29.549053 -401.456532)
			(xy 29.557098 -401.389708) (xy 29.573073 -401.324325) (xy 29.596747 -401.26132) (xy 29.627782 -401.201596)
			(xy 29.665732 -401.146008) (xy 29.68752 -401.120356) (xy 29.69332 -401.113213) (xy 29.699832 -401.096021)
			(xy 29.70022 -401.086828) (xy 29.70022 -400.92884) (xy 29.700655 -400.918686) (xy 29.708441 -400.899931)
			(xy 29.722834 -400.885605) (xy 29.741626 -400.877908) (xy 29.751782 -400.877532) (xy 30.468062 -400.877532)
			(xy 30.478185 -400.878058) (xy 30.496904 -400.885771) (xy 30.511261 -400.900046) (xy 30.519083 -400.91872)
			(xy 30.519624 -400.92884) (xy 30.519624 -401.086828) (xy 30.520015 -401.096017) (xy 30.526542 -401.113202)
			(xy 30.532324 -401.120356) (xy 30.554093 -401.146024) (xy 30.592045 -401.201607) (xy 30.623081 -401.261328)
			(xy 30.646757 -401.324331) (xy 30.662732 -401.389711) (xy 30.670778 -401.456533) (xy 30.67078 -401.523837)
			(xy 30.662738 -401.590659) (xy 30.646766 -401.65604) (xy 30.623093 -401.719044) (xy 30.620654 -401.723737)
			(xy 31.749186 -401.723737) (xy 31.749188 -401.65643) (xy 31.757235 -401.589605) (xy 31.773211 -401.524221)
			(xy 31.796887 -401.461216) (xy 31.827925 -401.401492) (xy 31.865878 -401.345906) (xy 31.887668 -401.320254)
			(xy 31.893475 -401.313116) (xy 31.899981 -401.29592) (xy 31.900368 -401.286726) (xy 31.900368 -400.793458)
			(xy 31.899963 -400.784271) (xy 31.893444 -400.767087) (xy 31.887668 -400.75993) (xy 31.865885 -400.734273)
			(xy 31.827935 -400.678688) (xy 31.796899 -400.618966) (xy 31.773225 -400.555962) (xy 31.757251 -400.49058)
			(xy 31.749206 -400.423757) (xy 31.749205 -400.356452) (xy 31.757249 -400.289629) (xy 31.773222 -400.224247)
			(xy 31.796896 -400.161243) (xy 31.82793 -400.10152) (xy 31.86588 -400.045934) (xy 31.887668 -400.020282)
			(xy 31.893463 -400.013136) (xy 31.899977 -399.995946) (xy 31.900368 -399.986754) (xy 31.900368 -399.828766)
			(xy 31.900806 -399.818602) (xy 31.908597 -399.799827) (xy 31.92298 -399.785462) (xy 31.941766 -399.777694)
			(xy 31.95193 -399.777204) (xy 32.66821 -399.777204) (xy 32.678364 -399.777725) (xy 32.697127 -399.785496)
			(xy 32.711491 -399.799853) (xy 32.719271 -399.818612) (xy 32.719772 -399.828766) (xy 32.719772 -399.986754)
			(xy 32.720211 -399.995938) (xy 32.726705 -400.013122) (xy 32.732472 -400.020282) (xy 32.754265 -400.045929)
			(xy 32.792213 -400.101517) (xy 32.823246 -400.161241) (xy 32.846918 -400.224246) (xy 32.86289 -400.289629)
			(xy 32.870933 -400.356452) (xy 32.870933 -400.423757) (xy 32.862888 -400.49058) (xy 32.846915 -400.555962)
			(xy 32.823242 -400.618967) (xy 32.792209 -400.678691) (xy 32.75426 -400.734278) (xy 32.732472 -400.75993)
			(xy 32.726677 -400.767076) (xy 32.720162 -400.784266) (xy 32.719772 -400.793458) (xy 32.719772 -401.286726)
			(xy 32.720176 -401.295914) (xy 32.726695 -401.313098) (xy 32.732472 -401.320254) (xy 32.754237 -401.345924)
			(xy 32.792186 -401.401508) (xy 32.82322 -401.46123) (xy 32.846893 -401.524232) (xy 32.862868 -401.589612)
			(xy 32.870913 -401.656432) (xy 32.870915 -401.723735) (xy 32.862873 -401.790556) (xy 32.846903 -401.855937)
			(xy 32.823233 -401.91894) (xy 32.792203 -401.978663) (xy 32.754258 -402.03425) (xy 32.732472 -402.059902)
			(xy 32.726688 -402.067056) (xy 32.720167 -402.08424) (xy 32.719772 -402.09343) (xy 32.719772 -402.251418)
			(xy 32.719282 -402.261576) (xy 32.711503 -402.280343) (xy 32.697137 -402.294708) (xy 32.678368 -402.302483)
			(xy 32.66821 -402.30298) (xy 31.95193 -402.30298) (xy 31.941763 -402.302512) (xy 31.922972 -402.29474)
			(xy 31.908587 -402.280368) (xy 31.900798 -402.261585) (xy 31.900368 -402.251418) (xy 31.900368 -402.09343)
			(xy 31.899928 -402.084246) (xy 31.893434 -402.067062) (xy 31.887668 -402.059902) (xy 31.865858 -402.034268)
			(xy 31.827908 -401.97868) (xy 31.796874 -401.918954) (xy 31.773201 -401.855947) (xy 31.757229 -401.790562)
			(xy 31.749186 -401.723737) (xy 30.620654 -401.723737) (xy 30.59206 -401.778767) (xy 30.554112 -401.834352)
			(xy 30.532324 -401.860004) (xy 30.526546 -401.867163) (xy 30.520019 -401.884343) (xy 30.519624 -401.893532)
			(xy 30.519624 -402.3868) (xy 30.520029 -402.395988) (xy 30.526546 -402.413172) (xy 30.532324 -402.420328)
			(xy 30.554114 -402.445978) (xy 30.592063 -402.501565) (xy 30.623097 -402.561289) (xy 30.64677 -402.624293)
			(xy 30.662743 -402.689676) (xy 30.670787 -402.756499) (xy 30.670787 -402.823804) (xy 30.670778 -402.823878)
			(xy 33.948799 -402.823878) (xy 33.948804 -402.75645) (xy 33.956885 -402.689508) (xy 33.972926 -402.624016)
			(xy 33.996696 -402.560917) (xy 34.027853 -402.50112) (xy 34.065949 -402.445485) (xy 34.087816 -402.41982)
			(xy 34.093631 -402.412688) (xy 34.100134 -402.395487) (xy 34.100516 -402.386292) (xy 34.100516 -401.89404)
			(xy 34.100083 -401.884855) (xy 34.093585 -401.867671) (xy 34.087816 -401.860512) (xy 34.065932 -401.834863)
			(xy 34.027843 -401.779227) (xy 33.996692 -401.719428) (xy 33.972928 -401.656329) (xy 33.956894 -401.590838)
			(xy 33.948819 -401.523898) (xy 33.948821 -401.456472) (xy 33.956899 -401.389532) (xy 33.972937 -401.324042)
			(xy 33.996704 -401.260944) (xy 34.027858 -401.201147) (xy 34.06595 -401.145513) (xy 34.087816 -401.119848)
			(xy 34.093619 -401.112707) (xy 34.100129 -401.095513) (xy 34.100516 -401.08632) (xy 34.100516 -400.92884)
			(xy 34.100949 -400.918718) (xy 34.108687 -400.900012) (xy 34.122999 -400.885696) (xy 34.141702 -400.877952)
			(xy 34.151824 -400.877532) (xy 34.868104 -400.877532) (xy 34.878231 -400.877914) (xy 34.89694 -400.885669)
			(xy 34.911256 -400.899997) (xy 34.918995 -400.918713) (xy 34.919412 -400.92884) (xy 34.919412 -401.08632)
			(xy 34.91981 -401.095509) (xy 34.926332 -401.112693) (xy 34.932112 -401.119848) (xy 34.953956 -401.14553)
			(xy 34.992044 -401.201162) (xy 35.023195 -401.260956) (xy 35.04696 -401.324051) (xy 35.062997 -401.389538)
			(xy 35.071074 -401.456474) (xy 35.071076 -401.523896) (xy 35.063002 -401.590833) (xy 35.046969 -401.65632)
			(xy 35.023208 -401.719416) (xy 35.020926 -401.723796) (xy 36.148978 -401.723796) (xy 36.14898 -401.656371)
			(xy 36.157058 -401.589432) (xy 36.173095 -401.523942) (xy 36.19686 -401.460845) (xy 36.228011 -401.401047)
			(xy 36.2661 -401.345412) (xy 36.287964 -401.319746) (xy 36.293774 -401.312611) (xy 36.300279 -401.295412)
			(xy 36.300664 -401.286218) (xy 36.300664 -400.793966) (xy 36.300256 -400.784779) (xy 36.293739 -400.767595)
			(xy 36.287964 -400.760438) (xy 36.266107 -400.734767) (xy 36.228021 -400.679133) (xy 36.196872 -400.619337)
			(xy 36.173109 -400.556241) (xy 36.157074 -400.490753) (xy 36.148998 -400.423816) (xy 36.148998 -400.356393)
			(xy 36.157072 -400.289456) (xy 36.173106 -400.223968) (xy 36.196868 -400.160871) (xy 36.228016 -400.101075)
			(xy 36.266102 -400.04544) (xy 36.287964 -400.019774) (xy 36.293762 -400.01263) (xy 36.300274 -399.995438)
			(xy 36.300664 -399.986246) (xy 36.300664 -399.828766) (xy 36.301099 -399.818634) (xy 36.308843 -399.799908)
			(xy 36.323145 -399.785552) (xy 36.341842 -399.777738) (xy 36.351972 -399.777204) (xy 37.068252 -399.777204)
			(xy 37.078404 -399.777661) (xy 37.097156 -399.785442) (xy 37.111481 -399.799828) (xy 37.119181 -399.818613)
			(xy 37.11956 -399.828766) (xy 37.11956 -399.986246) (xy 37.120005 -399.995429) (xy 37.126496 -400.012613)
			(xy 37.13226 -400.019774) (xy 37.154131 -400.045434) (xy 37.192222 -400.101068) (xy 37.223375 -400.160865)
			(xy 37.247141 -400.223962) (xy 37.263177 -400.289453) (xy 37.271253 -400.356392) (xy 37.271252 -400.423817)
			(xy 37.263175 -400.490756) (xy 37.247138 -400.556246) (xy 37.223371 -400.619344) (xy 37.192218 -400.67914)
			(xy 37.154126 -400.734773) (xy 37.13226 -400.760438) (xy 37.12646 -400.76758) (xy 37.119948 -400.784773)
			(xy 37.11956 -400.793966) (xy 37.11956 -401.286218) (xy 37.11997 -401.295405) (xy 37.126485 -401.312589)
			(xy 37.13226 -401.319746) (xy 37.154104 -401.345428) (xy 37.192196 -401.40106) (xy 37.22335 -401.460853)
			(xy 37.247117 -401.523948) (xy 37.263155 -401.589435) (xy 37.271233 -401.656372) (xy 37.271235 -401.723795)
			(xy 37.263161 -401.790732) (xy 37.247127 -401.856221) (xy 37.223363 -401.919317) (xy 37.192213 -401.979112)
			(xy 37.154124 -402.034745) (xy 37.13226 -402.06041) (xy 37.126472 -402.067561) (xy 37.119953 -402.084747)
			(xy 37.11956 -402.093938) (xy 37.11956 -402.251418) (xy 37.119088 -402.261546) (xy 37.111355 -402.280268)
			(xy 37.097064 -402.294623) (xy 37.078378 -402.302442) (xy 37.068252 -402.30298) (xy 36.351972 -402.30298)
			(xy 36.341814 -402.302601) (xy 36.323057 -402.294792) (xy 36.308734 -402.280383) (xy 36.301038 -402.261579)
			(xy 36.300664 -402.251418) (xy 36.300664 -402.093938) (xy 36.300221 -402.084755) (xy 36.293729 -402.067571)
			(xy 36.287964 -402.06041) (xy 36.26608 -402.034762) (xy 36.227994 -401.979124) (xy 36.196846 -401.919325)
			(xy 36.173085 -401.856226) (xy 36.157052 -401.790735) (xy 36.148978 -401.723796) (xy 35.020926 -401.723796)
			(xy 34.99206 -401.779212) (xy 34.953974 -401.834847) (xy 34.932112 -401.860512) (xy 34.926329 -401.867667)
			(xy 34.919806 -401.88485) (xy 34.919412 -401.89404) (xy 34.919412 -402.386292) (xy 34.919823 -402.395479)
			(xy 34.926336 -402.412664) (xy 34.932112 -402.41982) (xy 34.953928 -402.445524) (xy 34.992018 -402.501154)
			(xy 35.02317 -402.560944) (xy 35.046936 -402.624036) (xy 35.062975 -402.68952) (xy 35.071054 -402.756454)
			(xy 35.071059 -402.823818) (xy 38.349119 -402.823818) (xy 38.349123 -402.75651) (xy 38.357172 -402.689685)
			(xy 38.373149 -402.6243) (xy 38.396825 -402.561294) (xy 38.427862 -402.501569) (xy 38.465814 -402.445981)
			(xy 38.487604 -402.420328) (xy 38.493414 -402.413192) (xy 38.499921 -402.395995) (xy 38.500304 -402.3868)
			(xy 38.500304 -401.893532) (xy 38.499878 -401.884347) (xy 38.493375 -401.867162) (xy 38.487604 -401.860004)
			(xy 38.465798 -401.834368) (xy 38.427852 -401.778778) (xy 38.396821 -401.719052) (xy 38.373151 -401.656045)
			(xy 38.357181 -401.590662) (xy 38.349139 -401.523838) (xy 38.34914 -401.456532) (xy 38.357186 -401.389709)
			(xy 38.37316 -401.324326) (xy 38.396834 -401.261321) (xy 38.427867 -401.201596) (xy 38.465816 -401.146009)
			(xy 38.487604 -401.120356) (xy 38.493402 -401.113212) (xy 38.499916 -401.096021) (xy 38.500304 -401.086828)
			(xy 38.500304 -400.92884) (xy 38.500755 -400.918688) (xy 38.508538 -400.899936) (xy 38.522926 -400.885611)
			(xy 38.541712 -400.87791) (xy 38.551866 -400.877532) (xy 39.268146 -400.877532) (xy 39.278275 -400.877989)
			(xy 39.296995 -400.88573) (xy 39.31135 -400.900025) (xy 39.319169 -400.918714) (xy 39.319708 -400.92884)
			(xy 39.319708 -401.086828) (xy 39.320103 -401.096017) (xy 39.326627 -401.113201) (xy 39.332408 -401.120356)
			(xy 39.354178 -401.146024) (xy 39.392131 -401.201607) (xy 39.423168 -401.261328) (xy 39.446844 -401.32433)
			(xy 39.46282 -401.389711) (xy 39.470866 -401.456533) (xy 39.470868 -401.523837) (xy 39.462825 -401.590659)
			(xy 39.446853 -401.656041) (xy 39.42318 -401.719045) (xy 39.420711 -401.723797) (xy 40.548745 -401.723797)
			(xy 40.548747 -401.65637) (xy 40.556826 -401.58943) (xy 40.572865 -401.523939) (xy 40.596634 -401.460841)
			(xy 40.62779 -401.401044) (xy 40.665885 -401.34541) (xy 40.687752 -401.319746) (xy 40.69356 -401.312609)
			(xy 40.700067 -401.295412) (xy 40.700452 -401.286218) (xy 40.700452 -400.793966) (xy 40.700046 -400.784779)
			(xy 40.693528 -400.767595) (xy 40.687752 -400.760438) (xy 40.665892 -400.734769) (xy 40.6278 -400.679136)
			(xy 40.596646 -400.619341) (xy 40.572879 -400.556244) (xy 40.556842 -400.490755) (xy 40.548764 -400.423817)
			(xy 40.548764 -400.356392) (xy 40.55684 -400.289454) (xy 40.572876 -400.223964) (xy 40.596642 -400.160867)
			(xy 40.627795 -400.101072) (xy 40.665887 -400.045438) (xy 40.687752 -400.019774) (xy 40.693549 -400.012629)
			(xy 40.700062 -399.995438) (xy 40.700452 -399.986246) (xy 40.700452 -399.828766) (xy 40.700899 -399.818636)
			(xy 40.70864 -399.799911) (xy 40.722939 -399.785556) (xy 40.741632 -399.77774) (xy 40.75176 -399.777204)
			(xy 41.46804 -399.777204) (xy 41.478197 -399.777589) (xy 41.496951 -399.785399) (xy 41.511273 -399.799806)
			(xy 41.518971 -399.818606) (xy 41.519348 -399.828766) (xy 41.519348 -399.986246) (xy 41.519796 -399.995429)
			(xy 41.526285 -400.012613) (xy 41.532048 -400.019774) (xy 41.55392 -400.045433) (xy 41.592012 -400.101068)
			(xy 41.623165 -400.160864) (xy 41.646931 -400.223962) (xy 41.662968 -400.289452) (xy 41.671044 -400.356392)
			(xy 41.671043 -400.423817) (xy 41.662966 -400.490757) (xy 41.646928 -400.556247) (xy 41.623161 -400.619344)
			(xy 41.592007 -400.67914) (xy 41.553914 -400.734774) (xy 41.532048 -400.760438) (xy 41.526246 -400.767579)
			(xy 41.519736 -400.784773) (xy 41.519348 -400.793966) (xy 41.519348 -401.286218) (xy 41.519761 -401.295405)
			(xy 41.526274 -401.312588) (xy 41.532048 -401.319746) (xy 41.553892 -401.345428) (xy 41.591985 -401.401059)
			(xy 41.62314 -401.460852) (xy 41.646907 -401.523947) (xy 41.662946 -401.589435) (xy 41.671024 -401.656372)
			(xy 41.671026 -401.723795) (xy 41.662952 -401.790733) (xy 41.646917 -401.856221) (xy 41.623153 -401.919317)
			(xy 41.592002 -401.979113) (xy 41.553912 -402.034746) (xy 41.532048 -402.06041) (xy 41.526258 -402.06756)
			(xy 41.519741 -402.084747) (xy 41.519348 -402.093938) (xy 41.519348 -402.251418) (xy 41.518888 -402.261547)
			(xy 41.511152 -402.280271) (xy 41.496858 -402.294627) (xy 41.478167 -402.302444) (xy 41.46804 -402.30298)
			(xy 40.75176 -402.30298) (xy 40.741601 -402.302611) (xy 40.722844 -402.294798) (xy 40.708521 -402.280385)
			(xy 40.700826 -402.26158) (xy 40.700452 -402.251418) (xy 40.700452 -402.093938) (xy 40.700012 -402.084754)
			(xy 40.693518 -402.06757) (xy 40.687752 -402.06041) (xy 40.665865 -402.034763) (xy 40.627773 -401.979127)
			(xy 40.59662 -401.919329) (xy 40.572855 -401.85623) (xy 40.55682 -401.790738) (xy 40.548745 -401.723797)
			(xy 39.420711 -401.723797) (xy 39.392146 -401.778768) (xy 39.354196 -401.834353) (xy 39.332408 -401.860004)
			(xy 39.326628 -401.867161) (xy 39.320103 -401.884342) (xy 39.319708 -401.893532) (xy 39.319708 -402.3868)
			(xy 39.320116 -402.395987) (xy 39.326631 -402.413172) (xy 39.332408 -402.420328) (xy 39.35415 -402.446018)
			(xy 39.392104 -402.501598) (xy 39.423142 -402.561316) (xy 39.44682 -402.624315) (xy 39.462798 -402.689694)
			(xy 39.470847 -402.756513) (xy 39.470851 -402.823815) (xy 39.470843 -402.823878) (xy 42.748887 -402.823878)
			(xy 42.748892 -402.75645) (xy 42.756972 -402.689509) (xy 42.773013 -402.624017) (xy 42.796782 -402.560918)
			(xy 42.827939 -402.501121) (xy 42.866033 -402.445485) (xy 42.8879 -402.41982) (xy 42.893713 -402.412686)
			(xy 42.900218 -402.395487) (xy 42.9006 -402.386292) (xy 42.9006 -401.89404) (xy 42.900171 -401.884855)
			(xy 42.89367 -401.86767) (xy 42.8879 -401.860512) (xy 42.866016 -401.834863) (xy 42.827928 -401.779226)
			(xy 42.796778 -401.719428) (xy 42.773015 -401.656329) (xy 42.756981 -401.590838) (xy 42.748907 -401.523898)
			(xy 42.748909 -401.456472) (xy 42.756987 -401.389533) (xy 42.773024 -401.324043) (xy 42.796791 -401.260945)
			(xy 42.827944 -401.201148) (xy 42.866035 -401.145513) (xy 42.8879 -401.119848) (xy 42.893701 -401.112706)
			(xy 42.900213 -401.095513) (xy 42.9006 -401.08632) (xy 42.9006 -400.92884) (xy 42.901049 -400.91872)
			(xy 42.908784 -400.900017) (xy 42.923091 -400.885702) (xy 42.941788 -400.877955) (xy 42.951908 -400.877532)
			(xy 43.668188 -400.877532) (xy 43.678314 -400.877927) (xy 43.697023 -400.885677) (xy 43.711339 -400.9)
			(xy 43.719079 -400.918714) (xy 43.719496 -400.92884) (xy 43.719496 -401.08632) (xy 43.719897 -401.095508)
			(xy 43.726417 -401.112692) (xy 43.732196 -401.119848) (xy 43.75404 -401.145529) (xy 43.79213 -401.201162)
			(xy 43.823282 -401.260955) (xy 43.847047 -401.32405) (xy 43.863084 -401.389537) (xy 43.871162 -401.456474)
			(xy 43.871164 -401.523896) (xy 43.86309 -401.590833) (xy 43.847056 -401.656321) (xy 43.823294 -401.719417)
			(xy 43.821044 -401.723737) (xy 44.949064 -401.723737) (xy 44.949066 -401.65643) (xy 44.957113 -401.589606)
			(xy 44.973088 -401.524222) (xy 44.996763 -401.461217) (xy 45.027799 -401.401493) (xy 45.065751 -401.345906)
			(xy 45.08754 -401.320254) (xy 45.093344 -401.313114) (xy 45.099853 -401.295919) (xy 45.10024 -401.286726)
			(xy 45.10024 -400.793458) (xy 45.099841 -400.78427) (xy 45.093319 -400.767086) (xy 45.08754 -400.75993)
			(xy 45.065758 -400.734273) (xy 45.027809 -400.678687) (xy 44.996776 -400.618964) (xy 44.973103 -400.55596)
			(xy 44.957129 -400.490579) (xy 44.949085 -400.423757) (xy 44.949084 -400.356452) (xy 44.957128 -400.28963)
			(xy 44.9731 -400.224248) (xy 44.996772 -400.161244) (xy 45.027805 -400.101521) (xy 45.065753 -400.045934)
			(xy 45.08754 -400.020282) (xy 45.093332 -400.013134) (xy 45.099848 -399.995945) (xy 45.10024 -399.986754)
			(xy 45.10024 -399.828766) (xy 45.100706 -399.818606) (xy 45.108492 -399.799835) (xy 45.122866 -399.785471)
			(xy 45.141641 -399.777698) (xy 45.151802 -399.777204) (xy 45.868082 -399.777204) (xy 45.878234 -399.777747)
			(xy 45.896997 -399.785509) (xy 45.911361 -399.79986) (xy 45.919143 -399.818614) (xy 45.919644 -399.828766)
			(xy 45.919644 -399.986754) (xy 45.920089 -399.995937) (xy 45.92658 -400.013121) (xy 45.932344 -400.020282)
			(xy 45.954138 -400.045929) (xy 45.992088 -400.101516) (xy 46.023122 -400.16124) (xy 46.046795 -400.224245)
			(xy 46.062768 -400.289628) (xy 46.070812 -400.356452) (xy 46.070811 -400.423757) (xy 46.062766 -400.490581)
			(xy 46.046792 -400.555963) (xy 46.023118 -400.618968) (xy 45.992083 -400.678692) (xy 45.954132 -400.734278)
			(xy 45.932344 -400.75993) (xy 45.926545 -400.767073) (xy 45.920033 -400.784266) (xy 45.919644 -400.793458)
			(xy 45.919644 -401.286726) (xy 45.920054 -401.295913) (xy 45.926569 -401.313097) (xy 45.932344 -401.320254)
			(xy 45.95411 -401.345924) (xy 45.992061 -401.401507) (xy 46.023096 -401.461228) (xy 46.046771 -401.524231)
			(xy 46.062746 -401.589611) (xy 46.070792 -401.656432) (xy 46.070794 -401.723735) (xy 46.062752 -401.790557)
			(xy 46.046781 -401.855938) (xy 46.02311 -401.918941) (xy 45.992078 -401.978664) (xy 45.954131 -402.03425)
			(xy 45.932344 -402.059902) (xy 45.926557 -402.067054) (xy 45.920038 -402.084239) (xy 45.919644 -402.09343)
			(xy 45.919644 -402.251418) (xy 45.919181 -402.261579) (xy 45.911397 -402.280352) (xy 45.897022 -402.294718)
			(xy 45.878244 -402.302488) (xy 45.868082 -402.30298) (xy 45.151802 -402.30298) (xy 45.141647 -402.302465)
			(xy 45.122881 -402.294695) (xy 45.108516 -402.280336) (xy 45.100739 -402.261573) (xy 45.10024 -402.251418)
			(xy 45.10024 -402.09343) (xy 45.099806 -402.084246) (xy 45.093308 -402.067061) (xy 45.08754 -402.059902)
			(xy 45.06573 -402.034268) (xy 45.027782 -401.978679) (xy 44.99675 -401.918953) (xy 44.973078 -401.855946)
			(xy 44.957107 -401.790561) (xy 44.949064 -401.723737) (xy 43.821044 -401.723737) (xy 43.792146 -401.779213)
			(xy 43.754059 -401.834847) (xy 43.732196 -401.860512) (xy 43.726411 -401.867666) (xy 43.71989 -401.88485)
			(xy 43.719496 -401.89404) (xy 43.719496 -402.386292) (xy 43.719911 -402.395479) (xy 43.726421 -402.412663)
			(xy 43.732196 -402.41982) (xy 43.754013 -402.445524) (xy 43.792103 -402.501153) (xy 43.823256 -402.560944)
			(xy 43.847023 -402.624036) (xy 43.863062 -402.68952) (xy 43.871142 -402.756454) (xy 43.871146 -402.823874)
			(xy 43.863075 -402.890809) (xy 43.847045 -402.956295) (xy 43.823286 -403.01939) (xy 43.792141 -403.079185)
			(xy 43.754057 -403.134819) (xy 43.732196 -403.160484) (xy 43.726381 -403.167616) (xy 43.719877 -403.184817)
			(xy 43.719496 -403.194012) (xy 43.719496 -403.351492) (xy 43.719077 -403.361614) (xy 43.711331 -403.380319)
			(xy 43.697015 -403.394633) (xy 43.67831 -403.402378) (xy 43.668188 -403.4028) (xy 42.951908 -403.4028)
			(xy 42.941786 -403.402377) (xy 42.923083 -403.394632) (xy 42.908768 -403.380317) (xy 42.901023 -403.361614)
			(xy 42.9006 -403.351492) (xy 42.9006 -403.194012) (xy 42.900184 -403.184825) (xy 42.893674 -403.167641)
			(xy 42.8879 -403.160484) (xy 42.865989 -403.134858) (xy 42.827902 -403.079218) (xy 42.796753 -403.019416)
			(xy 42.772992 -402.956314) (xy 42.756959 -402.89082) (xy 42.748887 -402.823878) (xy 39.470843 -402.823878)
			(xy 39.462811 -402.890635) (xy 39.446841 -402.956016) (xy 39.423172 -403.019018) (xy 39.392141 -403.07874)
			(xy 39.354194 -403.134325) (xy 39.332408 -403.159976) (xy 39.326598 -403.167111) (xy 39.320091 -403.184309)
			(xy 39.319708 -403.193504) (xy 39.319708 -403.351492) (xy 39.319272 -403.361645) (xy 39.311481 -403.380395)
			(xy 39.297088 -403.394719) (xy 39.278301 -403.40242) (xy 39.268146 -403.4028) (xy 38.551866 -403.4028)
			(xy 38.541742 -403.402303) (xy 38.523028 -403.394571) (xy 38.508674 -403.380289) (xy 38.500849 -403.361613)
			(xy 38.500304 -403.351492) (xy 38.500304 -403.193504) (xy 38.499891 -403.184317) (xy 38.493379 -403.167133)
			(xy 38.487604 -403.159976) (xy 38.46577 -403.134362) (xy 38.427825 -403.078769) (xy 38.396796 -403.01904)
			(xy 38.373127 -402.956031) (xy 38.357159 -402.890644) (xy 38.349119 -402.823818) (xy 35.071059 -402.823818)
			(xy 35.071059 -402.823874) (xy 35.062988 -402.890809) (xy 35.046958 -402.956295) (xy 35.023199 -403.01939)
			(xy 34.992055 -403.079185) (xy 34.953973 -403.134819) (xy 34.932112 -403.160484) (xy 34.926299 -403.167617)
			(xy 34.919794 -403.184817) (xy 34.919412 -403.194012) (xy 34.919412 -403.351492) (xy 34.918978 -403.361612)
			(xy 34.911234 -403.380314) (xy 34.896924 -403.394628) (xy 34.878224 -403.402375) (xy 34.868104 -403.4028)
			(xy 34.151824 -403.4028) (xy 34.141703 -403.402365) (xy 34.123 -403.394624) (xy 34.108685 -403.380314)
			(xy 34.100939 -403.361613) (xy 34.100516 -403.351492) (xy 34.100516 -403.194012) (xy 34.100096 -403.184826)
			(xy 34.093589 -403.167642) (xy 34.087816 -403.160484) (xy 34.065904 -403.134858) (xy 34.027816 -403.079218)
			(xy 33.996666 -403.019417) (xy 33.972904 -402.956315) (xy 33.956872 -402.890821) (xy 33.948799 -402.823878)
			(xy 30.670778 -402.823878) (xy 30.662742 -402.890627) (xy 30.646769 -402.956009) (xy 30.623096 -403.019014)
			(xy 30.592062 -403.078738) (xy 30.554112 -403.134324) (xy 30.532324 -403.159976) (xy 30.526515 -403.167113)
			(xy 30.520007 -403.18431) (xy 30.519624 -403.193504) (xy 30.519624 -403.351492) (xy 30.519172 -403.361643)
			(xy 30.511384 -403.38039) (xy 30.496997 -403.394713) (xy 30.478214 -403.402417) (xy 30.468062 -403.4028)
			(xy 29.751782 -403.4028) (xy 29.741659 -403.40229) (xy 29.722945 -403.394563) (xy 29.708591 -403.380285)
			(xy 29.700765 -403.361612) (xy 29.70022 -403.351492) (xy 29.70022 -403.193504) (xy 29.699804 -403.184318)
			(xy 29.693294 -403.167133) (xy 29.68752 -403.159976) (xy 29.665734 -403.134322) (xy 29.627785 -403.078736)
			(xy 29.596752 -403.019013) (xy 29.573079 -402.956008) (xy 29.557106 -402.890626) (xy 29.549061 -402.823804)
			(xy 29.549061 -402.756499) (xy 29.557105 -402.689677) (xy 29.573078 -402.624294) (xy 29.59675 -402.56129)
			(xy 29.627784 -402.501566) (xy 29.665732 -402.44598) (xy 29.68752 -402.420328) (xy 29.693332 -402.413194)
			(xy 29.699837 -402.395995) (xy 29.70022 -402.3868) (xy 29.70022 -401.893532) (xy 29.69979 -401.884347)
			(xy 29.69329 -401.867163) (xy 29.68752 -401.860004) (xy 29.665713 -401.834368) (xy 29.627766 -401.778779)
			(xy 29.596735 -401.719053) (xy 29.573064 -401.656046) (xy 29.557093 -401.590662) (xy 29.549051 -401.523838)
			(xy 28.446989 -401.523838) (xy 28.44703 -401.523948) (xy 28.463067 -401.589436) (xy 28.471145 -401.656372)
			(xy 28.471147 -401.723795) (xy 28.463073 -401.790732) (xy 28.447039 -401.85622) (xy 28.423277 -401.919316)
			(xy 28.392127 -401.979111) (xy 28.354039 -402.034745) (xy 28.332176 -402.06041) (xy 28.32639 -402.067562)
			(xy 28.31987 -402.084748) (xy 28.319476 -402.093938) (xy 28.319476 -402.251418) (xy 28.318989 -402.261544)
			(xy 28.311258 -402.280263) (xy 28.296972 -402.294618) (xy 28.278291 -402.302439) (xy 28.268168 -402.30298)
			(xy 27.551888 -402.30298) (xy 27.541731 -402.302588) (xy 27.522974 -402.294785) (xy 27.50865 -402.280379)
			(xy 27.500954 -402.261578) (xy 27.50058 -402.251418) (xy 27.50058 -402.093938) (xy 27.500156 -402.084752)
			(xy 27.493653 -402.067567) (xy 27.48788 -402.06041) (xy 27.465995 -402.034762) (xy 27.427908 -401.979125)
			(xy 27.39676 -401.919326) (xy 27.372998 -401.856227) (xy 27.356964 -401.790736) (xy 27.348891 -401.723796)
			(xy 0.509016 -401.723796) (xy 0.509016 -405.623707) (xy 27.348902 -405.623707) (xy 27.348902 -405.556284)
			(xy 27.356979 -405.489345) (xy 27.373014 -405.423856) (xy 27.396778 -405.360759) (xy 27.427928 -405.300963)
			(xy 27.466016 -405.245328) (xy 27.48788 -405.219662) (xy 27.493673 -405.212514) (xy 27.50019 -405.195326)
			(xy 27.50058 -405.186134) (xy 27.50058 -404.693882) (xy 27.500183 -404.684693) (xy 27.493661 -404.667509)
			(xy 27.48788 -404.660354) (xy 27.466038 -404.634671) (xy 27.42795 -404.579038) (xy 27.3968 -404.519244)
			(xy 27.373035 -404.45615) (xy 27.356999 -404.390663) (xy 27.348922 -404.323727) (xy 27.34892 -404.256306)
			(xy 27.356993 -404.189369) (xy 27.373025 -404.123882) (xy 27.396786 -404.060786) (xy 27.427933 -404.00099)
			(xy 27.466018 -403.945356) (xy 27.48788 -403.91969) (xy 27.493661 -403.912534) (xy 27.500186 -403.895352)
			(xy 27.50058 -403.886162) (xy 27.50058 -403.728682) (xy 27.501013 -403.718549) (xy 27.508754 -403.69982)
			(xy 27.523057 -403.685463) (xy 27.541757 -403.677651) (xy 27.551888 -403.67712) (xy 28.268168 -403.67712)
			(xy 28.278323 -403.677548) (xy 28.297078 -403.685337) (xy 28.311404 -403.699732) (xy 28.319101 -403.718525)
			(xy 28.319476 -403.728682) (xy 28.319476 -403.886162) (xy 28.31991 -403.895347) (xy 28.326408 -403.912531)
			(xy 28.332176 -403.91969) (xy 28.354062 -403.945337) (xy 28.392152 -404.000974) (xy 28.423303 -404.060772)
			(xy 28.447067 -404.123871) (xy 28.463102 -404.189363) (xy 28.471176 -404.256304) (xy 28.471174 -404.323729)
			(xy 28.463096 -404.39067) (xy 28.447057 -404.45616) (xy 28.42329 -404.519258) (xy 28.392135 -404.579055)
			(xy 28.354042 -404.634689) (xy 28.332176 -404.660354) (xy 28.326371 -404.667493) (xy 28.319862 -404.684688)
			(xy 28.319476 -404.693882) (xy 28.319476 -405.186134) (xy 28.319875 -405.195322) (xy 28.326397 -405.212506)
			(xy 28.332176 -405.219662) (xy 28.354035 -405.245332) (xy 28.392125 -405.300965) (xy 28.423278 -405.36076)
			(xy 28.447043 -405.423857) (xy 28.46308 -405.489345) (xy 28.471157 -405.556284) (xy 28.471157 -405.623707)
			(xy 28.463081 -405.690646) (xy 28.447046 -405.756135) (xy 28.423281 -405.819231) (xy 28.39213 -405.879027)
			(xy 28.35404 -405.934661) (xy 28.332176 -405.960326) (xy 28.326383 -405.967474) (xy 28.319867 -405.984662)
			(xy 28.319476 -405.993854) (xy 28.319476 -406.151334) (xy 28.319002 -406.161461) (xy 28.311266 -406.18018)
			(xy 28.296976 -406.194534) (xy 28.278293 -406.202355) (xy 28.268168 -406.202896) (xy 27.551888 -406.202896)
			(xy 27.541733 -406.202488) (xy 27.522979 -406.194688) (xy 27.508656 -406.180287) (xy 27.500957 -406.161492)
			(xy 27.50058 -406.151334) (xy 27.50058 -405.993854) (xy 27.500148 -405.984669) (xy 27.49365 -405.967484)
			(xy 27.48788 -405.960326) (xy 27.466011 -405.934665) (xy 27.427924 -405.87903) (xy 27.396774 -405.819233)
			(xy 27.373011 -405.756135) (xy 27.356977 -405.690646) (xy 27.348902 -405.623707) (xy 0.509016 -405.623707)
			(xy 0.509016 -406.72373) (xy 29.549042 -406.72373) (xy 29.549045 -406.656422) (xy 29.557092 -406.589598)
			(xy 29.573068 -406.524214) (xy 29.596744 -406.461208) (xy 29.627779 -406.401484) (xy 29.665731 -406.345896)
			(xy 29.68752 -406.320244) (xy 29.693325 -406.313105) (xy 29.699834 -406.29591) (xy 29.70022 -406.286716)
			(xy 29.70022 -405.793448) (xy 29.699782 -405.784264) (xy 29.693287 -405.767079) (xy 29.68752 -405.75992)
			(xy 29.665729 -405.734271) (xy 29.627781 -405.678684) (xy 29.596749 -405.618959) (xy 29.573078 -405.555955)
			(xy 29.557105 -405.490572) (xy 29.549062 -405.423749) (xy 29.549062 -405.356444) (xy 29.557107 -405.289622)
			(xy 29.573079 -405.22424) (xy 29.596752 -405.161235) (xy 29.627784 -405.101511) (xy 29.665733 -405.045924)
			(xy 29.68752 -405.020272) (xy 29.693313 -405.013125) (xy 29.699829 -404.995936) (xy 29.70022 -404.986744)
			(xy 29.70022 -404.828756) (xy 29.700586 -404.818597) (xy 29.7084 -404.799839) (xy 29.722814 -404.785517)
			(xy 29.74162 -404.777822) (xy 29.751782 -404.777448) (xy 30.468062 -404.777448) (xy 30.478187 -404.777958)
			(xy 30.496909 -404.785675) (xy 30.511267 -404.799954) (xy 30.519086 -404.818634) (xy 30.519624 -404.828756)
			(xy 30.519624 -404.986744) (xy 30.520008 -404.995934) (xy 30.526539 -405.013118) (xy 30.532324 -405.020272)
			(xy 30.554109 -405.045927) (xy 30.59206 -405.101512) (xy 30.623096 -405.161235) (xy 30.64677 -405.224239)
			(xy 30.662745 -405.289621) (xy 30.67079 -405.356444) (xy 30.67079 -405.42375) (xy 30.662746 -405.490573)
			(xy 30.646772 -405.555955) (xy 30.623098 -405.61896) (xy 30.620661 -405.623649) (xy 31.749197 -405.623649)
			(xy 31.749198 -405.556342) (xy 31.757243 -405.489519) (xy 31.773217 -405.424136) (xy 31.796892 -405.361131)
			(xy 31.827928 -405.301408) (xy 31.865879 -405.245822) (xy 31.887668 -405.22017) (xy 31.893468 -405.213028)
			(xy 31.899979 -405.195835) (xy 31.900368 -405.186642) (xy 31.900368 -404.693374) (xy 31.899955 -404.684187)
			(xy 31.893441 -404.667004) (xy 31.887668 -404.659846) (xy 31.865901 -404.634176) (xy 31.82795 -404.578593)
			(xy 31.796914 -404.518872) (xy 31.773239 -404.45587) (xy 31.757263 -404.39049) (xy 31.749217 -404.323668)
			(xy 31.749215 -404.256365) (xy 31.757257 -404.189543) (xy 31.773229 -404.124162) (xy 31.7969 -404.061158)
			(xy 31.827933 -404.001435) (xy 31.865881 -403.94585) (xy 31.887668 -403.920198) (xy 31.893456 -403.913047)
			(xy 31.899974 -403.895861) (xy 31.900368 -403.88667) (xy 31.900368 -403.728682) (xy 31.90075 -403.718506)
			(xy 31.908547 -403.699705) (xy 31.922945 -403.68532) (xy 31.941753 -403.677541) (xy 31.95193 -403.67712)
			(xy 32.66821 -403.67712) (xy 32.678366 -403.677625) (xy 32.697132 -403.685399) (xy 32.711496 -403.699761)
			(xy 32.719273 -403.718526) (xy 32.719772 -403.728682) (xy 32.719772 -403.88667) (xy 32.720203 -403.895855)
			(xy 32.726703 -403.913039) (xy 32.732472 -403.920198) (xy 32.754281 -403.945832) (xy 32.792229 -404.001422)
			(xy 32.82326 -404.061148) (xy 32.846931 -404.124155) (xy 32.862902 -404.189539) (xy 32.870945 -404.256363)
			(xy 32.870943 -404.32367) (xy 32.862897 -404.390494) (xy 32.846922 -404.455877) (xy 32.823247 -404.518882)
			(xy 32.792212 -404.578607) (xy 32.754261 -404.634194) (xy 32.732472 -404.659846) (xy 32.72667 -404.666987)
			(xy 32.720159 -404.684181) (xy 32.719772 -404.693374) (xy 32.719772 -405.186642) (xy 32.720168 -405.195831)
			(xy 32.726692 -405.213014) (xy 32.732472 -405.22017) (xy 32.754254 -405.245827) (xy 32.792202 -405.301413)
			(xy 32.823235 -405.361136) (xy 32.846907 -405.42414) (xy 32.862881 -405.489521) (xy 32.870925 -405.556343)
			(xy 32.870926 -405.623648) (xy 32.862882 -405.69047) (xy 32.84691 -405.755851) (xy 32.823239 -405.818856)
			(xy 32.792207 -405.878579) (xy 32.754259 -405.934166) (xy 32.732472 -405.959818) (xy 32.726682 -405.966967)
			(xy 32.720164 -405.984155) (xy 32.719772 -405.993346) (xy 32.719772 -406.151334) (xy 32.719295 -406.161493)
			(xy 32.711511 -406.180261) (xy 32.697141 -406.194624) (xy 32.678369 -406.202399) (xy 32.66821 -406.202896)
			(xy 31.95193 -406.202896) (xy 31.941778 -406.202343) (xy 31.923016 -406.194585) (xy 31.908651 -406.180237)
			(xy 31.900869 -406.161485) (xy 31.900368 -406.151334) (xy 31.900368 -405.993346) (xy 31.899921 -405.984163)
			(xy 31.893431 -405.966979) (xy 31.887668 -405.959818) (xy 31.865874 -405.934171) (xy 31.827923 -405.878584)
			(xy 31.796888 -405.81886) (xy 31.773215 -405.755855) (xy 31.757241 -405.690472) (xy 31.749197 -405.623649)
			(xy 30.620661 -405.623649) (xy 30.592063 -405.678683) (xy 30.554113 -405.734268) (xy 30.532324 -405.75992)
			(xy 30.526539 -405.767074) (xy 30.520017 -405.784258) (xy 30.519624 -405.793448) (xy 30.519624 -406.286716)
			(xy 30.520021 -406.295905) (xy 30.526543 -406.313089) (xy 30.532324 -406.320244) (xy 30.554081 -406.345922)
			(xy 30.592034 -406.401503) (xy 30.62307 -406.461223) (xy 30.646746 -406.524224) (xy 30.662723 -406.589604)
			(xy 30.67077 -406.656424) (xy 30.670773 -406.723728) (xy 30.670766 -406.723789) (xy 33.948811 -406.723789)
			(xy 33.948814 -406.656363) (xy 33.956893 -406.589422) (xy 33.972932 -406.523931) (xy 33.996701 -406.460833)
			(xy 34.027856 -406.401036) (xy 34.06595 -406.345401) (xy 34.087816 -406.319736) (xy 34.093624 -406.312599)
			(xy 34.100131 -406.295402) (xy 34.100516 -406.286208) (xy 34.100516 -405.793956) (xy 34.100123 -405.784767)
			(xy 34.093597 -405.767583) (xy 34.087816 -405.760428) (xy 34.065948 -405.734766) (xy 34.027858 -405.679132)
			(xy 33.996706 -405.619335) (xy 33.972942 -405.556238) (xy 33.956906 -405.490748) (xy 33.94883 -405.423809)
			(xy 33.948831 -405.356385) (xy 33.956907 -405.289446) (xy 33.972944 -405.223957) (xy 33.996709 -405.160859)
			(xy 34.027861 -405.101063) (xy 34.065951 -405.045429) (xy 34.087816 -405.019764) (xy 34.093612 -405.012619)
			(xy 34.100127 -404.995428) (xy 34.100516 -404.986236) (xy 34.100516 -404.828756) (xy 34.10095 -404.818642)
			(xy 34.108705 -404.79996) (xy 34.123017 -404.785666) (xy 34.14171 -404.777936) (xy 34.151824 -404.777448)
			(xy 34.868104 -404.777448) (xy 34.878207 -404.777981) (xy 34.896875 -404.78571) (xy 34.911168 -404.799992)
			(xy 34.918911 -404.818654) (xy 34.919412 -404.828756) (xy 34.919412 -404.986236) (xy 34.919802 -404.995425)
			(xy 34.926329 -405.01261) (xy 34.932112 -405.019764) (xy 34.953972 -405.045433) (xy 34.99206 -405.101067)
			(xy 35.02321 -405.160863) (xy 35.046974 -405.223959) (xy 35.063009 -405.289448) (xy 35.071085 -405.356385)
			(xy 35.071085 -405.423809) (xy 35.06301 -405.490746) (xy 35.046976 -405.556235) (xy 35.023212 -405.619332)
			(xy 35.020933 -405.623707) (xy 36.14899 -405.623707) (xy 36.14899 -405.556284) (xy 36.157066 -405.489346)
			(xy 36.173101 -405.423857) (xy 36.196864 -405.36076) (xy 36.228014 -405.300963) (xy 36.266101 -405.245328)
			(xy 36.287964 -405.219662) (xy 36.293767 -405.212522) (xy 36.300276 -405.195327) (xy 36.300664 -405.186134)
			(xy 36.300664 -404.693882) (xy 36.300248 -404.684696) (xy 36.293737 -404.667512) (xy 36.287964 -404.660354)
			(xy 36.266123 -404.63467) (xy 36.228036 -404.579038) (xy 36.196886 -404.519244) (xy 36.173122 -404.456149)
			(xy 36.157087 -404.390663) (xy 36.149009 -404.323727) (xy 36.149007 -404.256306) (xy 36.157081 -404.18937)
			(xy 36.173113 -404.123882) (xy 36.196873 -404.060787) (xy 36.228019 -404.000991) (xy 36.266103 -403.945356)
			(xy 36.287964 -403.91969) (xy 36.293755 -403.912541) (xy 36.300271 -403.895353) (xy 36.300664 -403.886162)
			(xy 36.300664 -403.728682) (xy 36.301112 -403.718551) (xy 36.30885 -403.699825) (xy 36.323149 -403.685468)
			(xy 36.341843 -403.677654) (xy 36.351972 -403.67712) (xy 37.068252 -403.67712) (xy 37.078405 -403.677561)
			(xy 37.097161 -403.685345) (xy 37.111486 -403.699736) (xy 37.119184 -403.718527) (xy 37.11956 -403.728682)
			(xy 37.11956 -403.886162) (xy 37.119998 -403.895346) (xy 37.126493 -403.91253) (xy 37.13226 -403.91969)
			(xy 37.154147 -403.945337) (xy 37.192238 -404.000973) (xy 37.22339 -404.060771) (xy 37.247154 -404.123871)
			(xy 37.26319 -404.189362) (xy 37.271264 -404.256303) (xy 37.271262 -404.32373) (xy 37.263184 -404.39067)
			(xy 37.247145 -404.456161) (xy 37.223376 -404.519259) (xy 37.192221 -404.579055) (xy 37.154127 -404.634689)
			(xy 37.13226 -404.660354) (xy 37.126453 -404.667492) (xy 37.119946 -404.684688) (xy 37.11956 -404.693882)
			(xy 37.11956 -405.186134) (xy 37.119963 -405.195322) (xy 37.126483 -405.212506) (xy 37.13226 -405.219662)
			(xy 37.154119 -405.245331) (xy 37.192211 -405.300964) (xy 37.223364 -405.36076) (xy 37.24713 -405.423856)
			(xy 37.263168 -405.489345) (xy 37.271245 -405.556284) (xy 37.271245 -405.623707) (xy 37.263169 -405.690646)
			(xy 37.247133 -405.756135) (xy 37.223368 -405.819232) (xy 37.192216 -405.879028) (xy 37.154125 -405.934661)
			(xy 37.13226 -405.960326) (xy 37.126465 -405.967472) (xy 37.11995 -405.984662) (xy 37.11956 -405.993854)
			(xy 37.11956 -406.151334) (xy 37.119101 -406.161463) (xy 37.111362 -406.180185) (xy 37.097068 -406.19454)
			(xy 37.078379 -406.202358) (xy 37.068252 -406.202896) (xy 36.351972 -406.202896) (xy 36.341816 -406.202501)
			(xy 36.323062 -406.194696) (xy 36.308739 -406.180291) (xy 36.301041 -406.161493) (xy 36.300664 -406.151334)
			(xy 36.300664 -405.993854) (xy 36.300214 -405.984671) (xy 36.293726 -405.967487) (xy 36.287964 -405.960326)
			(xy 36.266095 -405.934665) (xy 36.228009 -405.879029) (xy 36.196861 -405.819232) (xy 36.173099 -405.756135)
			(xy 36.157065 -405.690645) (xy 36.14899 -405.623707) (xy 35.020933 -405.623707) (xy 34.992063 -405.679128)
			(xy 34.953975 -405.734763) (xy 34.932112 -405.760428) (xy 34.926322 -405.767578) (xy 34.919803 -405.784765)
			(xy 34.919412 -405.793956) (xy 34.919412 -406.286208) (xy 34.919816 -406.295396) (xy 34.926334 -406.31258)
			(xy 34.932112 -406.319736) (xy 34.953944 -406.345427) (xy 34.992033 -406.401058) (xy 35.023184 -406.460851)
			(xy 35.04695 -406.523945) (xy 35.062987 -406.58943) (xy 35.071065 -406.656366) (xy 35.071068 -406.723729)
			(xy 38.34913 -406.723729) (xy 38.349133 -406.656422) (xy 38.35718 -406.589598) (xy 38.373155 -406.524215)
			(xy 38.39683 -406.461209) (xy 38.427865 -406.401484) (xy 38.465815 -406.345897) (xy 38.487604 -406.320244)
			(xy 38.493407 -406.313104) (xy 38.499918 -406.295909) (xy 38.500304 -406.286716) (xy 38.500304 -405.793448)
			(xy 38.49987 -405.784263) (xy 38.493373 -405.767079) (xy 38.487604 -405.75992) (xy 38.465813 -405.734271)
			(xy 38.427867 -405.678683) (xy 38.396836 -405.618959) (xy 38.373165 -405.555954) (xy 38.357193 -405.490572)
			(xy 38.34915 -405.423749) (xy 38.34915 -405.356445) (xy 38.357194 -405.289622) (xy 38.373167 -405.22424)
			(xy 38.396838 -405.161236) (xy 38.42787 -405.101512) (xy 38.465817 -405.045925) (xy 38.487604 -405.020272)
			(xy 38.493395 -405.013123) (xy 38.499913 -404.995935) (xy 38.500304 -404.986744) (xy 38.500304 -404.828756)
			(xy 38.500686 -404.818599) (xy 38.508497 -404.799844) (xy 38.522905 -404.785523) (xy 38.541706 -404.777825)
			(xy 38.551866 -404.777448) (xy 39.268146 -404.777448) (xy 39.278277 -404.777889) (xy 39.297 -404.785634)
			(xy 39.311355 -404.799934) (xy 39.319171 -404.818627) (xy 39.319708 -404.828756) (xy 39.319708 -404.986744)
			(xy 39.320095 -404.995934) (xy 39.326624 -405.013118) (xy 39.332408 -405.020272) (xy 39.354193 -405.045927)
			(xy 39.392146 -405.101512) (xy 39.423182 -405.161234) (xy 39.446858 -405.224239) (xy 39.462832 -405.289621)
			(xy 39.470878 -405.356444) (xy 39.470878 -405.42375) (xy 39.462833 -405.490573) (xy 39.446859 -405.555956)
			(xy 39.423185 -405.61896) (xy 39.420718 -405.623708) (xy 40.548756 -405.623708) (xy 40.548757 -405.556283)
			(xy 40.556834 -405.489343) (xy 40.572872 -405.423853) (xy 40.596639 -405.360756) (xy 40.627793 -405.30096)
			(xy 40.665886 -405.245326) (xy 40.687752 -405.219662) (xy 40.693554 -405.212521) (xy 40.700064 -405.195327)
			(xy 40.700452 -405.186134) (xy 40.700452 -404.693882) (xy 40.700039 -404.684695) (xy 40.693526 -404.667512)
			(xy 40.687752 -404.660354) (xy 40.665908 -404.634672) (xy 40.627815 -404.579041) (xy 40.59666 -404.519248)
			(xy 40.572893 -404.456153) (xy 40.556854 -404.390665) (xy 40.548776 -404.323728) (xy 40.548774 -404.256305)
			(xy 40.556848 -404.189367) (xy 40.572883 -404.123879) (xy 40.596647 -404.060783) (xy 40.627798 -404.000987)
			(xy 40.665888 -403.945354) (xy 40.687752 -403.91969) (xy 40.693542 -403.91254) (xy 40.700059 -403.895353)
			(xy 40.700452 -403.886162) (xy 40.700452 -403.728682) (xy 40.700912 -403.718553) (xy 40.708648 -403.699829)
			(xy 40.722942 -403.685473) (xy 40.741633 -403.677656) (xy 40.75176 -403.67712) (xy 41.46804 -403.67712)
			(xy 41.478199 -403.677489) (xy 41.496956 -403.685302) (xy 41.511279 -403.699715) (xy 41.518974 -403.71852)
			(xy 41.519348 -403.728682) (xy 41.519348 -403.886162) (xy 41.519788 -403.895346) (xy 41.526282 -403.91253)
			(xy 41.532048 -403.91969) (xy 41.553935 -403.945337) (xy 41.592027 -404.000973) (xy 41.62318 -404.060771)
			(xy 41.646945 -404.12387) (xy 41.66298 -404.189362) (xy 41.671055 -404.256303) (xy 41.671053 -404.32373)
			(xy 41.662974 -404.39067) (xy 41.646935 -404.456161) (xy 41.623166 -404.519259) (xy 41.59201 -404.579056)
			(xy 41.553915 -404.63469) (xy 41.532048 -404.660354) (xy 41.52624 -404.667491) (xy 41.519733 -404.684688)
			(xy 41.519348 -404.693882) (xy 41.519348 -405.186134) (xy 41.519754 -405.195321) (xy 41.526272 -405.212505)
			(xy 41.532048 -405.219662) (xy 41.553908 -405.245331) (xy 41.592 -405.300964) (xy 41.623154 -405.360759)
			(xy 41.646921 -405.423856) (xy 41.662958 -405.489345) (xy 41.671036 -405.556283) (xy 41.671036 -405.623708)
			(xy 41.66296 -405.690646) (xy 41.646924 -405.756136) (xy 41.623158 -405.819233) (xy 41.592005 -405.879028)
			(xy 41.553913 -405.934662) (xy 41.532048 -405.960326) (xy 41.526251 -405.967471) (xy 41.519738 -405.984662)
			(xy 41.519348 -405.993854) (xy 41.519348 -406.151334) (xy 41.518901 -406.161464) (xy 41.51116 -406.180189)
			(xy 41.496861 -406.194544) (xy 41.478168 -406.20236) (xy 41.46804 -406.202896) (xy 40.75176 -406.202896)
			(xy 40.741603 -406.202511) (xy 40.722849 -406.194701) (xy 40.708527 -406.180294) (xy 40.700829 -406.161494)
			(xy 40.700452 -406.151334) (xy 40.700452 -405.993854) (xy 40.700004 -405.984671) (xy 40.693515 -405.967487)
			(xy 40.687752 -405.960326) (xy 40.66588 -405.934667) (xy 40.627788 -405.879032) (xy 40.596635 -405.819236)
			(xy 40.572869 -405.756138) (xy 40.556832 -405.690648) (xy 40.548756 -405.623708) (xy 39.420718 -405.623708)
			(xy 39.392149 -405.678683) (xy 39.354197 -405.734269) (xy 39.332408 -405.75992) (xy 39.326621 -405.767072)
			(xy 39.3201 -405.784257) (xy 39.319708 -405.793448) (xy 39.319708 -406.286716) (xy 39.320109 -406.295904)
			(xy 39.326629 -406.313088) (xy 39.332408 -406.320244) (xy 39.354166 -406.345921) (xy 39.392119 -406.401503)
			(xy 39.423157 -406.461222) (xy 39.446834 -406.524224) (xy 39.46281 -406.589604) (xy 39.470858 -406.656424)
			(xy 39.470861 -406.723728) (xy 39.470854 -406.723789) (xy 42.748899 -406.723789) (xy 42.748901 -406.656363)
			(xy 42.756981 -406.589422) (xy 42.773019 -406.523932) (xy 42.796787 -406.460833) (xy 42.827942 -406.401036)
			(xy 42.866034 -406.345401) (xy 42.8879 -406.319736) (xy 42.893706 -406.312598) (xy 42.900215 -406.295402)
			(xy 42.9006 -406.286208) (xy 42.9006 -405.793956) (xy 42.900211 -405.784767) (xy 42.893683 -405.767582)
			(xy 42.8879 -405.760428) (xy 42.866032 -405.734766) (xy 42.827944 -405.679131) (xy 42.796793 -405.619334)
			(xy 42.773029 -405.556237) (xy 42.756994 -405.490748) (xy 42.748918 -405.423809) (xy 42.748919 -405.356385)
			(xy 42.756995 -405.289446) (xy 42.773031 -405.223957) (xy 42.796795 -405.16086) (xy 42.827947 -405.101064)
			(xy 42.866036 -405.045429) (xy 42.8879 -405.019764) (xy 42.893694 -405.012617) (xy 42.90021 -404.995428)
			(xy 42.9006 -404.986236) (xy 42.9006 -404.828756) (xy 42.901049 -404.818644) (xy 42.908801 -404.799965)
			(xy 42.923109 -404.785672) (xy 42.941796 -404.777939) (xy 42.951908 -404.777448) (xy 43.668188 -404.777448)
			(xy 43.67829 -404.777994) (xy 43.696958 -404.785718) (xy 43.711251 -404.799995) (xy 43.718995 -404.818655)
			(xy 43.719496 -404.828756) (xy 43.719496 -404.986236) (xy 43.71989 -404.995425) (xy 43.726415 -405.012609)
			(xy 43.732196 -405.019764) (xy 43.754056 -405.045432) (xy 43.792145 -405.101066) (xy 43.823296 -405.160862)
			(xy 43.847061 -405.223959) (xy 43.863097 -405.289447) (xy 43.871173 -405.356385) (xy 43.871173 -405.423809)
			(xy 43.863098 -405.490747) (xy 43.847063 -405.556236) (xy 43.823299 -405.619332) (xy 43.792148 -405.679128)
			(xy 43.75406 -405.734763) (xy 43.732196 -405.760428) (xy 43.726405 -405.767577) (xy 43.719887 -405.784765)
			(xy 43.719496 -405.793956) (xy 43.719496 -406.286208) (xy 43.719903 -406.295395) (xy 43.726419 -406.31258)
			(xy 43.732196 -406.319736) (xy 43.754029 -406.345427) (xy 43.792119 -406.401058) (xy 43.823271 -406.46085)
			(xy 43.847037 -406.523944) (xy 43.863075 -406.58943) (xy 43.871153 -406.656365) (xy 43.871156 -406.72373)
			(xy 47.149194 -406.72373) (xy 47.149197 -406.656422) (xy 47.157245 -406.589596) (xy 47.173223 -406.524212)
			(xy 47.196901 -406.461206) (xy 47.227941 -406.401481) (xy 47.265897 -406.345896) (xy 47.287688 -406.320244)
			(xy 47.293489 -406.313102) (xy 47.300002 -406.295909) (xy 47.300388 -406.286716) (xy 47.300388 -405.793448)
			(xy 47.299958 -405.784263) (xy 47.293458 -405.767078) (xy 47.287688 -405.75992) (xy 47.265895 -405.734272)
			(xy 47.227943 -405.678686) (xy 47.196907 -405.618962) (xy 47.173232 -405.555957) (xy 47.157258 -405.490574)
			(xy 47.149214 -405.42375) (xy 47.149214 -405.356444) (xy 47.157259 -405.28962) (xy 47.173234 -405.224237)
			(xy 47.19691 -405.161232) (xy 47.227946 -405.101509) (xy 47.265899 -405.045924) (xy 47.287688 -405.020272)
			(xy 47.293478 -405.013122) (xy 47.299997 -404.995935) (xy 47.300388 -404.986744) (xy 47.300388 -404.828756)
			(xy 47.300785 -404.818601) (xy 47.308593 -404.79985) (xy 47.322997 -404.785528) (xy 47.341792 -404.777828)
			(xy 47.35195 -404.777448) (xy 48.06823 -404.777448) (xy 48.07836 -404.777902) (xy 48.097083 -404.785641)
			(xy 48.111439 -404.799937) (xy 48.119255 -404.818629) (xy 48.119792 -404.828756) (xy 48.119792 -404.986744)
			(xy 48.120183 -404.995933) (xy 48.12671 -405.013117) (xy 48.132492 -405.020272) (xy 48.154275 -405.045928)
			(xy 48.192222 -405.101514) (xy 48.223254 -405.161238) (xy 48.246925 -405.224242) (xy 48.262897 -405.289623)
			(xy 48.270941 -405.356445) (xy 48.270942 -405.423749) (xy 48.262899 -405.490571) (xy 48.246927 -405.555952)
			(xy 48.223256 -405.618957) (xy 48.192225 -405.67868) (xy 48.154279 -405.734267) (xy 48.132492 -405.75992)
			(xy 48.126704 -405.767071) (xy 48.120184 -405.784257) (xy 48.119792 -405.793448) (xy 48.119792 -406.286716)
			(xy 48.120196 -406.295904) (xy 48.126714 -406.313088) (xy 48.132492 -406.320244) (xy 48.154247 -406.345922)
			(xy 48.192195 -406.401506) (xy 48.223228 -406.461226) (xy 48.246901 -406.524227) (xy 48.262876 -406.589606)
			(xy 48.270922 -406.656425) (xy 48.270925 -406.723727) (xy 48.262884 -406.790547) (xy 48.246916 -406.855927)
			(xy 48.223248 -406.91893) (xy 48.19222 -406.978653) (xy 48.154277 -407.034239) (xy 48.132492 -407.059892)
			(xy 48.126715 -407.067051) (xy 48.120189 -407.084231) (xy 48.119792 -407.09342) (xy 48.119792 -407.251408)
			(xy 48.119385 -407.261564) (xy 48.111585 -407.280318) (xy 48.097184 -407.294641) (xy 48.078388 -407.302339)
			(xy 48.06823 -407.302716) (xy 47.35195 -407.302716) (xy 47.341821 -407.302231) (xy 47.323093 -407.294512)
			(xy 47.308733 -407.280224) (xy 47.30092 -407.261534) (xy 47.300388 -407.251408) (xy 47.300388 -407.09342)
			(xy 47.299971 -407.084233) (xy 47.293462 -407.067049) (xy 47.287688 -407.059892) (xy 47.265867 -407.034266)
			(xy 47.227916 -406.978677) (xy 47.196882 -406.91895) (xy 47.173209 -406.855942) (xy 47.157236 -406.790556)
			(xy 47.149194 -406.72373) (xy 43.871156 -406.72373) (xy 43.871156 -406.723787) (xy 43.863084 -406.790723)
			(xy 43.847051 -406.85621) (xy 43.823291 -406.919306) (xy 43.792143 -406.979101) (xy 43.754058 -407.034735)
			(xy 43.732196 -407.0604) (xy 43.726416 -407.067557) (xy 43.719892 -407.084739) (xy 43.719496 -407.093928)
			(xy 43.719496 -407.251408) (xy 43.71909 -407.261531) (xy 43.711339 -407.280236) (xy 43.697019 -407.29455)
			(xy 43.678312 -407.302294) (xy 43.668188 -407.302716) (xy 42.951908 -407.302716) (xy 42.941802 -407.302209)
			(xy 42.923127 -407.294477) (xy 42.908832 -407.280187) (xy 42.901094 -407.261514) (xy 42.9006 -407.251408)
			(xy 42.9006 -407.093928) (xy 42.900176 -407.084742) (xy 42.893672 -407.067558) (xy 42.8879 -407.0604)
			(xy 42.866005 -407.034761) (xy 42.827917 -406.979122) (xy 42.796768 -406.919323) (xy 42.773005 -406.856222)
			(xy 42.756972 -406.79073) (xy 42.748899 -406.723789) (xy 39.470854 -406.723789) (xy 39.462819 -406.790549)
			(xy 39.446848 -406.85593) (xy 39.423176 -406.918933) (xy 39.392144 -406.978656) (xy 39.354195 -407.034241)
			(xy 39.332408 -407.059892) (xy 39.326633 -407.067053) (xy 39.320105 -407.084231) (xy 39.319708 -407.09342)
			(xy 39.319708 -407.251408) (xy 39.319285 -407.261562) (xy 39.311488 -407.280313) (xy 39.297092 -407.294635)
			(xy 39.278302 -407.302336) (xy 39.268146 -407.302716) (xy 38.551866 -407.302716) (xy 38.541732 -407.3023)
			(xy 38.523001 -407.294553) (xy 38.508645 -407.280245) (xy 38.500835 -407.261541) (xy 38.500304 -407.251408)
			(xy 38.500304 -407.09342) (xy 38.499883 -407.084234) (xy 38.493377 -407.06705) (xy 38.487604 -407.059892)
			(xy 38.465786 -407.034265) (xy 38.42784 -406.978674) (xy 38.39681 -406.918947) (xy 38.373141 -406.855939)
			(xy 38.357171 -406.790554) (xy 38.34913 -406.723729) (xy 35.071068 -406.723729) (xy 35.071068 -406.723786)
			(xy 35.062996 -406.790722) (xy 35.046964 -406.856209) (xy 35.023204 -406.919305) (xy 34.992058 -406.9791)
			(xy 34.953974 -407.034735) (xy 34.932112 -407.0604) (xy 34.926334 -407.067559) (xy 34.919808 -407.084739)
			(xy 34.919412 -407.093928) (xy 34.919412 -407.251408) (xy 34.918922 -407.261516) (xy 34.911184 -407.280192)
			(xy 34.896888 -407.294486) (xy 34.878212 -407.302222) (xy 34.868104 -407.302716) (xy 34.151824 -407.302716)
			(xy 34.141705 -407.302265) (xy 34.123005 -407.294528) (xy 34.10869 -407.280222) (xy 34.100941 -407.261527)
			(xy 34.100516 -407.251408) (xy 34.100516 -407.093928) (xy 34.100089 -407.084743) (xy 34.093586 -407.067558)
			(xy 34.087816 -407.0604) (xy 34.06592 -407.034761) (xy 34.027831 -406.979123) (xy 33.996681 -406.919323)
			(xy 33.972918 -406.856223) (xy 33.956884 -406.790731) (xy 33.948811 -406.723789) (xy 30.670766 -406.723789)
			(xy 30.662731 -406.790549) (xy 30.646761 -406.855929) (xy 30.62309 -406.918933) (xy 30.592058 -406.978655)
			(xy 30.554111 -407.03424) (xy 30.532324 -407.059892) (xy 30.526551 -407.067054) (xy 30.520022 -407.084232)
			(xy 30.519624 -407.09342) (xy 30.519624 -407.251408) (xy 30.519185 -407.26156) (xy 30.511392 -407.280307)
			(xy 30.497001 -407.29463) (xy 30.478216 -407.302333) (xy 30.468062 -407.302716) (xy 29.751782 -407.302716)
			(xy 29.741649 -407.302287) (xy 29.722919 -407.294545) (xy 29.708561 -407.280241) (xy 29.700751 -407.261539)
			(xy 29.70022 -407.251408) (xy 29.70022 -407.09342) (xy 29.699796 -407.084234) (xy 29.693291 -407.06705)
			(xy 29.68752 -407.059892) (xy 29.665701 -407.034265) (xy 29.627755 -406.978675) (xy 29.596724 -406.918948)
			(xy 29.573054 -406.85594) (xy 29.557084 -406.790555) (xy 29.549042 -406.72373) (xy 0.509016 -406.72373)
			(xy 0.509016 -409.523886) (xy 27.348881 -409.523886) (xy 27.348884 -409.45646) (xy 27.356963 -409.38952)
			(xy 27.373002 -409.324029) (xy 27.396769 -409.26093) (xy 27.427923 -409.201133) (xy 27.466015 -409.145498)
			(xy 27.48788 -409.119832) (xy 27.493686 -409.112693) (xy 27.500196 -409.095498) (xy 27.50058 -409.086304)
			(xy 27.50058 -408.594052) (xy 27.500149 -408.584867) (xy 27.49365 -408.567682) (xy 27.48788 -408.560524)
			(xy 27.466009 -408.534865) (xy 27.427922 -408.479229) (xy 27.396772 -408.419432) (xy 27.37301 -408.356334)
			(xy 27.356975 -408.290845) (xy 27.3489 -408.223906) (xy 27.348901 -408.156482) (xy 27.356977 -408.089544)
			(xy 27.373013 -408.024054) (xy 27.396777 -407.960957) (xy 27.427928 -407.901161) (xy 27.466016 -407.845526)
			(xy 27.48788 -407.81986) (xy 27.493674 -407.812713) (xy 27.500191 -407.795524) (xy 27.50058 -407.786332)
			(xy 27.50058 -407.628852) (xy 27.501045 -407.618743) (xy 27.508795 -407.600067) (xy 27.523098 -407.585775)
			(xy 27.541778 -407.578038) (xy 27.551888 -407.577544) (xy 28.268168 -407.577544) (xy 28.278268 -407.57811)
			(xy 28.296935 -407.585826) (xy 28.311229 -407.600098) (xy 28.318975 -407.618753) (xy 28.319476 -407.628852)
			(xy 28.319476 -407.786332) (xy 28.319876 -407.79552) (xy 28.326397 -407.812704) (xy 28.332176 -407.81986)
			(xy 28.354033 -407.845531) (xy 28.392123 -407.901164) (xy 28.423276 -407.96096) (xy 28.447042 -408.024056)
			(xy 28.463078 -408.089544) (xy 28.471155 -408.156482) (xy 28.471156 -408.223906) (xy 28.46308 -408.290844)
			(xy 28.447045 -408.356333) (xy 28.423281 -408.419429) (xy 28.39213 -408.479225) (xy 28.35404 -408.534859)
			(xy 28.332176 -408.560524) (xy 28.326384 -408.567672) (xy 28.319867 -408.584861) (xy 28.319476 -408.594052)
			(xy 28.319476 -409.086304) (xy 28.319889 -409.095491) (xy 28.326401 -409.112675) (xy 28.332176 -409.119832)
			(xy 28.354005 -409.145526) (xy 28.392097 -409.201156) (xy 28.42325 -409.260948) (xy 28.447018 -409.324041)
			(xy 28.463056 -409.389527) (xy 28.471135 -409.456462) (xy 28.471139 -409.523884) (xy 28.463066 -409.59082)
			(xy 28.447034 -409.656307) (xy 28.423273 -409.719403) (xy 28.392125 -409.779198) (xy 28.354039 -409.834831)
			(xy 28.332176 -409.860496) (xy 28.326396 -409.867653) (xy 28.319872 -409.884835) (xy 28.319476 -409.894024)
			(xy 28.319476 -410.051504) (xy 28.319087 -410.06163) (xy 28.311333 -410.080338) (xy 28.297008 -410.094653)
			(xy 28.278294 -410.102394) (xy 28.268168 -410.102812) (xy 27.551888 -410.102812) (xy 27.54178 -410.102325)
			(xy 27.523104 -410.094585) (xy 27.50881 -410.080289) (xy 27.501074 -410.061612) (xy 27.50058 -410.051504)
			(xy 27.50058 -409.894024) (xy 27.500163 -409.884837) (xy 27.493655 -409.867653) (xy 27.48788 -409.860496)
			(xy 27.465981 -409.83486) (xy 27.427895 -409.77922) (xy 27.396747 -409.71942) (xy 27.372986 -409.656319)
			(xy 27.356953 -409.590827) (xy 27.348881 -409.523886) (xy 0.509016 -409.523886) (xy 0.509016 -410.623641)
			(xy 29.549054 -410.623641) (xy 29.549055 -410.556335) (xy 29.5571 -410.489512) (xy 29.573074 -410.424129)
			(xy 29.596748 -410.361124) (xy 29.627782 -410.301399) (xy 29.665732 -410.245812) (xy 29.68752 -410.22016)
			(xy 29.693318 -410.213016) (xy 29.699831 -410.195825) (xy 29.70022 -410.186632) (xy 29.70022 -409.693364)
			(xy 29.699823 -409.684176) (xy 29.6933 -409.666992) (xy 29.68752 -409.659836) (xy 29.665745 -409.634174)
			(xy 29.627797 -409.578588) (xy 29.596764 -409.518866) (xy 29.573091 -409.455863) (xy 29.557118 -409.390482)
			(xy 29.549073 -409.323661) (xy 29.549072 -409.256357) (xy 29.557115 -409.189536) (xy 29.573086 -409.124154)
			(xy 29.596757 -409.06115) (xy 29.627787 -409.001427) (xy 29.665734 -408.94584) (xy 29.68752 -408.920188)
			(xy 29.693306 -408.913036) (xy 29.699827 -408.895851) (xy 29.70022 -408.88666) (xy 29.70022 -408.728672)
			(xy 29.700599 -408.718514) (xy 29.708408 -408.699757) (xy 29.722817 -408.685434) (xy 29.741621 -408.677738)
			(xy 29.751782 -408.677364) (xy 30.468062 -408.677364) (xy 30.478189 -408.677859) (xy 30.496914 -408.685578)
			(xy 30.511272 -408.699863) (xy 30.519089 -408.718547) (xy 30.519624 -408.728672) (xy 30.519624 -408.88666)
			(xy 30.520048 -408.895846) (xy 30.526551 -408.913031) (xy 30.532324 -408.920188) (xy 30.554125 -408.94583)
			(xy 30.592075 -409.001417) (xy 30.62311 -409.061142) (xy 30.646784 -409.124148) (xy 30.662757 -409.189531)
			(xy 30.670801 -409.256356) (xy 30.6708 -409.323662) (xy 30.662754 -409.390486) (xy 30.646779 -409.45587)
			(xy 30.623103 -409.518875) (xy 30.62053 -409.523827) (xy 31.749176 -409.523827) (xy 31.749179 -409.456519)
			(xy 31.757227 -409.389693) (xy 31.773205 -409.324309) (xy 31.796883 -409.261302) (xy 31.827922 -409.201578)
			(xy 31.865877 -409.145992) (xy 31.887668 -409.12034) (xy 31.893481 -409.113207) (xy 31.899984 -409.096007)
			(xy 31.900368 -409.086812) (xy 31.900368 -408.593544) (xy 31.899922 -408.584361) (xy 31.893432 -408.567177)
			(xy 31.887668 -408.560016) (xy 31.865872 -408.534371) (xy 31.827921 -408.478784) (xy 31.796887 -408.41906)
			(xy 31.773213 -408.356054) (xy 31.75724 -408.290671) (xy 31.749196 -408.223847) (xy 31.749197 -408.156541)
			(xy 31.757242 -408.089717) (xy 31.773217 -408.024334) (xy 31.796892 -407.961329) (xy 31.827927 -407.901606)
			(xy 31.865879 -407.84602) (xy 31.887668 -407.820368) (xy 31.893469 -407.813226) (xy 31.899979 -407.796033)
			(xy 31.900368 -407.78684) (xy 31.900368 -407.628852) (xy 31.900782 -407.618699) (xy 31.908587 -407.599952)
			(xy 31.922985 -407.585631) (xy 31.941775 -407.577927) (xy 31.95193 -407.577544) (xy 32.66821 -407.577544)
			(xy 32.678338 -407.578019) (xy 32.69706 -407.58575) (xy 32.711416 -407.60004) (xy 32.719234 -407.618727)
			(xy 32.719772 -407.628852) (xy 32.719772 -407.78684) (xy 32.720169 -407.796028) (xy 32.726693 -407.813212)
			(xy 32.732472 -407.820368) (xy 32.754252 -407.846027) (xy 32.7922 -407.901612) (xy 32.823233 -407.961335)
			(xy 32.846906 -408.024339) (xy 32.862879 -408.08972) (xy 32.870924 -408.156542) (xy 32.870924 -408.223846)
			(xy 32.862881 -408.290668) (xy 32.846909 -408.35605) (xy 32.823238 -408.419054) (xy 32.792206 -408.478777)
			(xy 32.754259 -408.534364) (xy 32.732472 -408.560016) (xy 32.726682 -408.567166) (xy 32.720164 -408.584353)
			(xy 32.719772 -408.593544) (xy 32.719772 -409.086812) (xy 32.720183 -409.095999) (xy 32.726697 -409.113183)
			(xy 32.732472 -409.12034) (xy 32.754224 -409.146022) (xy 32.792173 -409.201604) (xy 32.823207 -409.261324)
			(xy 32.846881 -409.324324) (xy 32.862857 -409.389703) (xy 32.870903 -409.456522) (xy 32.870907 -409.523824)
			(xy 32.862866 -409.590644) (xy 32.846897 -409.656024) (xy 32.823229 -409.719027) (xy 32.792201 -409.778749)
			(xy 32.754257 -409.834336) (xy 32.732472 -409.859988) (xy 32.726652 -409.867116) (xy 32.720152 -409.88432)
			(xy 32.719772 -409.893516) (xy 32.719772 -410.051504) (xy 32.719381 -410.061662) (xy 32.711579 -410.08042)
			(xy 32.697172 -410.094744) (xy 32.67837 -410.102438) (xy 32.66821 -410.102812) (xy 31.95193 -410.102812)
			(xy 31.941812 -410.102251) (xy 31.923101 -410.094542) (xy 31.908745 -410.080279) (xy 31.900916 -410.061619)
			(xy 31.900368 -410.051504) (xy 31.900368 -409.893516) (xy 31.899935 -409.884332) (xy 31.893436 -409.867148)
			(xy 31.887668 -409.859988) (xy 31.865844 -409.834366) (xy 31.827894 -409.778775) (xy 31.796861 -409.719048)
			(xy 31.773189 -409.65604) (xy 31.757217 -409.590654) (xy 31.749176 -409.523827) (xy 30.62053 -409.523827)
			(xy 30.592066 -409.578598) (xy 30.554113 -409.634184) (xy 30.532324 -409.659836) (xy 30.526532 -409.666985)
			(xy 30.520014 -409.684172) (xy 30.519624 -409.693364) (xy 30.519624 -410.186632) (xy 30.520014 -410.195821)
			(xy 30.526541 -410.213006) (xy 30.532324 -410.22016) (xy 30.554097 -410.245825) (xy 30.592049 -410.301408)
			(xy 30.623085 -410.36113) (xy 30.64676 -410.424133) (xy 30.662735 -410.489514) (xy 30.670781 -410.556336)
			(xy 30.670783 -410.62364) (xy 30.670776 -410.623701) (xy 33.948822 -410.623701) (xy 33.948823 -410.556275)
			(xy 33.956901 -410.489336) (xy 33.972939 -410.423846) (xy 33.996705 -410.360748) (xy 34.027859 -410.300951)
			(xy 34.065951 -410.245317) (xy 34.087816 -410.219652) (xy 34.093617 -410.21251) (xy 34.100129 -410.195317)
			(xy 34.100516 -410.186124) (xy 34.100516 -409.693872) (xy 34.100116 -409.684684) (xy 34.093595 -409.6675)
			(xy 34.087816 -409.660344) (xy 34.065963 -409.634669) (xy 34.027873 -409.579037) (xy 33.996721 -409.519242)
			(xy 33.972955 -409.456146) (xy 33.956919 -409.390658) (xy 33.948842 -409.323721) (xy 33.948841 -409.256297)
			(xy 33.956915 -409.18936) (xy 33.97295 -409.123871) (xy 33.996714 -409.060775) (xy 34.027864 -409.000979)
			(xy 34.065952 -408.945345) (xy 34.087816 -408.91968) (xy 34.093605 -408.91253) (xy 34.100124 -408.895343)
			(xy 34.100516 -408.886152) (xy 34.100516 -408.728672) (xy 34.100962 -408.718559) (xy 34.108712 -408.699878)
			(xy 34.123021 -408.685583) (xy 34.141711 -408.677852) (xy 34.151824 -408.677364) (xy 34.868104 -408.677364)
			(xy 34.878209 -408.677881) (xy 34.89688 -408.685613) (xy 34.911173 -408.6999) (xy 34.918914 -408.718568)
			(xy 34.919412 -408.728672) (xy 34.919412 -408.886152) (xy 34.919842 -408.895337) (xy 34.926342 -408.912522)
			(xy 34.932112 -408.91968) (xy 34.953987 -408.945336) (xy 34.992075 -409.000972) (xy 35.023224 -409.06077)
			(xy 35.046987 -409.123868) (xy 35.063022 -409.189358) (xy 35.071096 -409.256297) (xy 35.071095 -409.323721)
			(xy 35.063018 -409.39066) (xy 35.046982 -409.45615) (xy 35.023217 -409.519247) (xy 35.0208 -409.523886)
			(xy 36.148969 -409.523886) (xy 36.148972 -409.45646) (xy 36.157051 -409.38952) (xy 36.173089 -409.324029)
			(xy 36.196856 -409.260931) (xy 36.228009 -409.201134) (xy 36.266099 -409.145498) (xy 36.287964 -409.119832)
			(xy 36.29378 -409.112701) (xy 36.300281 -409.095499) (xy 36.300664 -409.086304) (xy 36.300664 -408.594052)
			(xy 36.300215 -408.584869) (xy 36.293727 -408.567685) (xy 36.287964 -408.560524) (xy 36.266093 -408.534865)
			(xy 36.228007 -408.479228) (xy 36.196859 -408.419431) (xy 36.173097 -408.356334) (xy 36.157063 -408.290844)
			(xy 36.148988 -408.223906) (xy 36.148989 -408.156482) (xy 36.157065 -408.089544) (xy 36.1731 -408.024055)
			(xy 36.196864 -407.960958) (xy 36.228014 -407.901161) (xy 36.266101 -407.845526) (xy 36.287964 -407.81986)
			(xy 36.293768 -407.81272) (xy 36.300276 -407.795525) (xy 36.300664 -407.786332) (xy 36.300664 -407.628852)
			(xy 36.301145 -407.618745) (xy 36.308892 -407.600072) (xy 36.323189 -407.585781) (xy 36.341864 -407.578041)
			(xy 36.351972 -407.577544) (xy 37.068252 -407.577544) (xy 37.078351 -407.578123) (xy 37.097017 -407.585835)
			(xy 37.111312 -407.600102) (xy 37.119058 -407.618754) (xy 37.11956 -407.628852) (xy 37.11956 -407.786332)
			(xy 37.119964 -407.79552) (xy 37.126483 -407.812703) (xy 37.13226 -407.81986) (xy 37.154118 -407.845531)
			(xy 37.192209 -407.901164) (xy 37.223362 -407.960959) (xy 37.247129 -408.024055) (xy 37.263166 -408.089544)
			(xy 37.271243 -408.156482) (xy 37.271244 -408.223906) (xy 37.263168 -408.290844) (xy 37.247132 -408.356333)
			(xy 37.223367 -408.41943) (xy 37.192215 -408.479226) (xy 37.154125 -408.534859) (xy 37.13226 -408.560524)
			(xy 37.126466 -408.567671) (xy 37.119951 -408.58486) (xy 37.11956 -408.594052) (xy 37.11956 -409.086304)
			(xy 37.119977 -409.09549) (xy 37.126487 -409.112674) (xy 37.13226 -409.119832) (xy 37.15409 -409.145526)
			(xy 37.192182 -409.201155) (xy 37.223337 -409.260947) (xy 37.247105 -409.32404) (xy 37.263144 -409.389526)
			(xy 37.271223 -409.456462) (xy 37.271227 -409.523884) (xy 37.263154 -409.59082) (xy 37.247121 -409.656308)
			(xy 37.223359 -409.719403) (xy 37.19221 -409.779198) (xy 37.154123 -409.834831) (xy 37.13226 -409.860496)
			(xy 37.126478 -409.867651) (xy 37.119955 -409.884834) (xy 37.11956 -409.894024) (xy 37.11956 -410.051504)
			(xy 37.119186 -410.061632) (xy 37.111429 -410.080343) (xy 37.097099 -410.094659) (xy 37.07838 -410.102396)
			(xy 37.068252 -410.102812) (xy 36.351972 -410.102812) (xy 36.341863 -410.102338) (xy 36.323186 -410.094594)
			(xy 36.308893 -410.080293) (xy 36.301157 -410.061613) (xy 36.300664 -410.051504) (xy 36.300664 -409.894024)
			(xy 36.300228 -409.88484) (xy 36.293731 -409.867656) (xy 36.287964 -409.860496) (xy 36.266066 -409.834859)
			(xy 36.227981 -409.77922) (xy 36.196834 -409.719419) (xy 36.173073 -409.656319) (xy 36.157041 -409.590827)
			(xy 36.148969 -409.523886) (xy 35.0208 -409.523886) (xy 34.992066 -409.579044) (xy 34.953976 -409.634679)
			(xy 34.932112 -409.660344) (xy 34.926316 -409.667489) (xy 34.9198 -409.68468) (xy 34.919412 -409.693872)
			(xy 34.919412 -410.186124) (xy 34.919808 -410.195313) (xy 34.926331 -410.212497) (xy 34.932112 -410.219652)
			(xy 34.95396 -410.24533) (xy 34.992048 -410.300963) (xy 35.023199 -410.360758) (xy 35.046964 -410.423853)
			(xy 35.063 -410.48934) (xy 35.071077 -410.556277) (xy 35.071078 -410.623641) (xy 38.349141 -410.623641)
			(xy 38.349143 -410.556335) (xy 38.357188 -410.489512) (xy 38.373162 -410.424129) (xy 38.396835 -410.361124)
			(xy 38.427868 -410.3014) (xy 38.465816 -410.245813) (xy 38.487604 -410.22016) (xy 38.493401 -410.213015)
			(xy 38.499915 -410.195824) (xy 38.500304 -410.186632) (xy 38.500304 -409.693364) (xy 38.49991 -409.684175)
			(xy 38.493385 -409.666991) (xy 38.487604 -409.659836) (xy 38.465829 -409.634174) (xy 38.427882 -409.578588)
			(xy 38.39685 -409.518865) (xy 38.373178 -409.455862) (xy 38.357206 -409.390482) (xy 38.349161 -409.323661)
			(xy 38.34916 -409.256357) (xy 38.357202 -409.189536) (xy 38.373173 -409.124155) (xy 38.396843 -409.061151)
			(xy 38.427873 -409.001428) (xy 38.465818 -408.945841) (xy 38.487604 -408.920188) (xy 38.493389 -408.913034)
			(xy 38.49991 -408.89585) (xy 38.500304 -408.88666) (xy 38.500304 -408.728672) (xy 38.500699 -408.718516)
			(xy 38.508504 -408.699762) (xy 38.522909 -408.685439) (xy 38.541707 -408.677741) (xy 38.551866 -408.677364)
			(xy 39.268146 -408.677364) (xy 39.278279 -408.67779) (xy 39.297005 -408.685537) (xy 39.311361 -408.699842)
			(xy 39.319174 -408.718541) (xy 39.319708 -408.728672) (xy 39.319708 -408.88666) (xy 39.320136 -408.895845)
			(xy 39.326637 -408.91303) (xy 39.332408 -408.920188) (xy 39.354209 -408.94583) (xy 39.392161 -409.001416)
			(xy 39.423197 -409.061141) (xy 39.446871 -409.124147) (xy 39.462845 -409.189531) (xy 39.470889 -409.256356)
			(xy 39.470888 -409.323663) (xy 39.462842 -409.390487) (xy 39.446866 -409.45587) (xy 39.423189 -409.518876)
			(xy 39.420585 -409.523887) (xy 40.548735 -409.523887) (xy 40.548738 -409.456459) (xy 40.556818 -409.389518)
			(xy 40.572859 -409.324026) (xy 40.59663 -409.260927) (xy 40.627788 -409.20113) (xy 40.665884 -409.145496)
			(xy 40.687752 -409.119832) (xy 40.693566 -409.1127) (xy 40.700069 -409.095499) (xy 40.700452 -409.086304)
			(xy 40.700452 -408.594052) (xy 40.700005 -408.584869) (xy 40.693516 -408.567685) (xy 40.687752 -408.560524)
			(xy 40.665878 -408.534866) (xy 40.627786 -408.479232) (xy 40.596633 -408.419435) (xy 40.572867 -408.356337)
			(xy 40.556831 -408.290847) (xy 40.548755 -408.223907) (xy 40.548755 -408.156481) (xy 40.556833 -408.089542)
			(xy 40.572871 -408.024051) (xy 40.596638 -407.960954) (xy 40.627793 -407.901158) (xy 40.665886 -407.845524)
			(xy 40.687752 -407.81986) (xy 40.693554 -407.812719) (xy 40.700064 -407.795525) (xy 40.700452 -407.786332)
			(xy 40.700452 -407.628852) (xy 40.700945 -407.618746) (xy 40.708689 -407.600076) (xy 40.722983 -407.585785)
			(xy 40.741654 -407.578043) (xy 40.75176 -407.577544) (xy 41.46804 -407.577544) (xy 41.478144 -407.578051)
			(xy 41.496813 -407.585791) (xy 41.511104 -407.600081) (xy 41.518847 -407.618748) (xy 41.519348 -407.628852)
			(xy 41.519348 -407.786332) (xy 41.519755 -407.795519) (xy 41.526272 -407.812703) (xy 41.532048 -407.81986)
			(xy 41.553906 -407.845531) (xy 41.591998 -407.901163) (xy 41.623152 -407.960958) (xy 41.646919 -408.024055)
			(xy 41.662957 -408.089543) (xy 41.671034 -408.156482) (xy 41.671035 -408.223906) (xy 41.662959 -408.290845)
			(xy 41.646923 -408.356334) (xy 41.623157 -408.419431) (xy 41.592004 -408.479226) (xy 41.553913 -408.53486)
			(xy 41.532048 -408.560524) (xy 41.526252 -408.56767) (xy 41.519739 -408.58486) (xy 41.519348 -408.594052)
			(xy 41.519348 -409.086304) (xy 41.519768 -409.09549) (xy 41.526276 -409.112674) (xy 41.532048 -409.119832)
			(xy 41.553878 -409.145526) (xy 41.591972 -409.201155) (xy 41.623127 -409.260947) (xy 41.646895 -409.32404)
			(xy 41.662935 -409.389526) (xy 41.671014 -409.456462) (xy 41.671018 -409.523884) (xy 41.662945 -409.590821)
			(xy 41.646911 -409.656308) (xy 41.623149 -409.719404) (xy 41.591999 -409.779199) (xy 41.553912 -409.834832)
			(xy 41.532048 -409.860496) (xy 41.526264 -409.86765) (xy 41.519743 -409.884834) (xy 41.519348 -409.894024)
			(xy 41.519348 -410.051504) (xy 41.518819 -410.061607) (xy 41.511089 -410.080276) (xy 41.496806 -410.094569)
			(xy 41.478143 -410.102312) (xy 41.46804 -410.102812) (xy 40.75176 -410.102812) (xy 40.74165 -410.102348)
			(xy 40.722973 -410.094599) (xy 40.70868 -410.080296) (xy 40.700945 -410.061614) (xy 40.700452 -410.051504)
			(xy 40.700452 -409.894024) (xy 40.700019 -409.884839) (xy 40.69352 -409.867655) (xy 40.687752 -409.860496)
			(xy 40.665851 -409.834861) (xy 40.62776 -409.779223) (xy 40.596608 -409.719423) (xy 40.572843 -409.656322)
			(xy 40.556809 -409.590829) (xy 40.548735 -409.523887) (xy 39.420585 -409.523887) (xy 39.392152 -409.578599)
			(xy 39.354198 -409.634185) (xy 39.332408 -409.659836) (xy 39.326615 -409.666984) (xy 39.320098 -409.684172)
			(xy 39.319708 -409.693364) (xy 39.319708 -410.186632) (xy 39.320101 -410.195821) (xy 39.326626 -410.213005)
			(xy 39.332408 -410.22016) (xy 39.354182 -410.245824) (xy 39.392134 -410.301408) (xy 39.423171 -410.361129)
			(xy 39.446847 -410.424132) (xy 39.462823 -410.489513) (xy 39.470869 -410.556336) (xy 39.470871 -410.62364)
			(xy 39.470864 -410.6237) (xy 42.74891 -410.6237) (xy 42.748911 -410.556276) (xy 42.756989 -410.489336)
			(xy 42.773026 -410.423846) (xy 42.796792 -410.360749) (xy 42.827944 -410.300952) (xy 42.866035 -410.245317)
			(xy 42.8879 -410.219652) (xy 42.893699 -410.212509) (xy 42.900212 -410.195317) (xy 42.9006 -410.186124)
			(xy 42.9006 -409.693872) (xy 42.900204 -409.684683) (xy 42.89368 -409.667499) (xy 42.8879 -409.660344)
			(xy 42.866048 -409.634669) (xy 42.827959 -409.579036) (xy 42.796808 -409.519241) (xy 42.773043 -409.456145)
			(xy 42.757006 -409.390658) (xy 42.74893 -409.32372) (xy 42.748928 -409.256298) (xy 42.757003 -409.18936)
			(xy 42.773037 -409.123872) (xy 42.7968 -409.060775) (xy 42.827949 -409.00098) (xy 42.866037 -408.945345)
			(xy 42.8879 -408.91968) (xy 42.893688 -408.912528) (xy 42.900208 -408.895343) (xy 42.9006 -408.886152)
			(xy 42.9006 -408.728672) (xy 42.901062 -408.718561) (xy 42.908809 -408.699883) (xy 42.923113 -408.685589)
			(xy 42.941797 -408.677855) (xy 42.951908 -408.677364) (xy 43.668188 -408.677364) (xy 43.678292 -408.677894)
			(xy 43.696963 -408.685621) (xy 43.711257 -408.699904) (xy 43.718998 -408.718569) (xy 43.719496 -408.728672)
			(xy 43.719496 -408.886152) (xy 43.71993 -408.895337) (xy 43.726427 -408.912521) (xy 43.732196 -408.91968)
			(xy 43.754072 -408.945335) (xy 43.792161 -409.000971) (xy 43.823311 -409.060769) (xy 43.847075 -409.123867)
			(xy 43.863109 -409.189357) (xy 43.871184 -409.256297) (xy 43.871183 -409.323721) (xy 43.863106 -409.390661)
			(xy 43.847069 -409.45615) (xy 43.823304 -409.519248) (xy 43.792151 -409.579044) (xy 43.754061 -409.634679)
			(xy 43.732196 -409.660344) (xy 43.726398 -409.667488) (xy 43.719884 -409.684679) (xy 43.719496 -409.693872)
			(xy 43.719496 -410.186124) (xy 43.719895 -410.195312) (xy 43.726417 -410.212497) (xy 43.732196 -410.219652)
			(xy 43.754044 -410.24533) (xy 43.792134 -410.300963) (xy 43.823285 -410.360757) (xy 43.847051 -410.423852)
			(xy 43.863087 -410.48934) (xy 43.871165 -410.556277) (xy 43.871166 -410.623642) (xy 47.149205 -410.623642)
			(xy 47.149207 -410.556334) (xy 47.157253 -410.48951) (xy 47.173229 -410.424126) (xy 47.196906 -410.361121)
			(xy 47.227944 -410.301397) (xy 47.265898 -410.245812) (xy 47.287688 -410.22016) (xy 47.293483 -410.213013)
			(xy 47.299999 -410.195824) (xy 47.300388 -410.186632) (xy 47.300388 -409.693364) (xy 47.299998 -409.684175)
			(xy 47.293471 -409.66699) (xy 47.287688 -409.659836) (xy 47.265911 -409.634175) (xy 47.227958 -409.578591)
			(xy 47.196922 -409.518869) (xy 47.173246 -409.455866) (xy 47.157271 -409.390484) (xy 47.149225 -409.323662)
			(xy 47.149224 -409.256357) (xy 47.157268 -409.189534) (xy 47.173241 -409.124152) (xy 47.196914 -409.061148)
			(xy 47.227949 -409.001425) (xy 47.2659 -408.945839) (xy 47.287688 -408.920188) (xy 47.293471 -408.913033)
			(xy 47.299994 -408.89585) (xy 47.300388 -408.88666) (xy 47.300388 -408.728672) (xy 47.300798 -408.718518)
			(xy 47.308601 -408.699767) (xy 47.323001 -408.685445) (xy 47.341793 -408.677744) (xy 47.35195 -408.677364)
			(xy 48.06823 -408.677364) (xy 48.078362 -408.677803) (xy 48.097088 -408.685545) (xy 48.111444 -408.699846)
			(xy 48.119258 -408.718542) (xy 48.119792 -408.728672) (xy 48.119792 -408.88666) (xy 48.120223 -408.895845)
			(xy 48.126722 -408.913029) (xy 48.132492 -408.920188) (xy 48.154291 -408.945831) (xy 48.192237 -409.001419)
			(xy 48.223268 -409.061145) (xy 48.246939 -409.12415) (xy 48.26291 -409.189533) (xy 48.270953 -409.256356)
			(xy 48.270952 -409.323662) (xy 48.262907 -409.390485) (xy 48.246933 -409.455867) (xy 48.223261 -409.518872)
			(xy 48.192228 -409.578596) (xy 48.15428 -409.634183) (xy 48.132492 -409.659836) (xy 48.126697 -409.666982)
			(xy 48.120182 -409.684172) (xy 48.119792 -409.693364) (xy 48.119792 -410.186632) (xy 48.120188 -410.195821)
			(xy 48.126712 -410.213005) (xy 48.132492 -410.22016) (xy 48.154263 -410.245825) (xy 48.19221 -410.301411)
			(xy 48.223243 -410.361133) (xy 48.246915 -410.424135) (xy 48.262888 -410.489516) (xy 48.270933 -410.556336)
			(xy 48.270934 -410.62364) (xy 48.262892 -410.690461) (xy 48.246922 -410.755842) (xy 48.223252 -410.818845)
			(xy 48.192223 -410.878569) (xy 48.154278 -410.934155) (xy 48.132492 -410.959808) (xy 48.126709 -410.966963)
			(xy 48.120186 -410.984146) (xy 48.119792 -410.993336) (xy 48.119792 -411.151324) (xy 48.119398 -411.161481)
			(xy 48.111593 -411.180235) (xy 48.097188 -411.194558) (xy 48.078389 -411.202255) (xy 48.06823 -411.202632)
			(xy 47.35195 -411.202632) (xy 47.341823 -411.202132) (xy 47.323098 -411.194415) (xy 47.308739 -411.180132)
			(xy 47.300923 -411.161448) (xy 47.300388 -411.151324) (xy 47.300388 -410.993336) (xy 47.299963 -410.98415)
			(xy 47.29346 -410.966966) (xy 47.287688 -410.959808) (xy 47.265883 -410.934169) (xy 47.227932 -410.878582)
			(xy 47.196896 -410.818857) (xy 47.173222 -410.755851) (xy 47.157249 -410.690466) (xy 47.149205 -410.623642)
			(xy 43.871166 -410.623642) (xy 43.871166 -410.623699) (xy 43.863092 -410.690636) (xy 43.847058 -410.756125)
			(xy 43.823295 -410.819221) (xy 43.792146 -410.879017) (xy 43.754059 -410.934651) (xy 43.732196 -410.960316)
			(xy 43.72641 -410.967468) (xy 43.719889 -410.984653) (xy 43.719496 -410.993844) (xy 43.719496 -411.151324)
			(xy 43.719035 -411.161435) (xy 43.711288 -411.180114) (xy 43.696984 -411.194408) (xy 43.678299 -411.202142)
			(xy 43.668188 -411.202632) (xy 42.951908 -411.202632) (xy 42.941804 -411.202109) (xy 42.923132 -411.19438)
			(xy 42.908838 -411.180095) (xy 42.901097 -411.161428) (xy 42.9006 -411.151324) (xy 42.9006 -410.993844)
			(xy 42.900169 -410.984659) (xy 42.89367 -410.967474) (xy 42.8879 -410.960316) (xy 42.86602 -410.934664)
			(xy 42.827932 -410.879027) (xy 42.796782 -410.819229) (xy 42.773019 -410.756131) (xy 42.756984 -410.69064)
			(xy 42.74891 -410.6237) (xy 39.470864 -410.6237) (xy 39.462827 -410.690463) (xy 39.446854 -410.755845)
			(xy 39.423181 -410.818849) (xy 39.392147 -410.878572) (xy 39.354196 -410.934157) (xy 39.332408 -410.959808)
			(xy 39.326626 -410.966964) (xy 39.320103 -410.984146) (xy 39.319708 -410.993336) (xy 39.319708 -411.151324)
			(xy 39.319298 -411.161479) (xy 39.311496 -411.18023) (xy 39.297096 -411.194552) (xy 39.278303 -411.202253)
			(xy 39.268146 -411.202632) (xy 38.551866 -411.202632) (xy 38.541734 -411.202201) (xy 38.523006 -411.194456)
			(xy 38.50865 -411.180153) (xy 38.500837 -411.161454) (xy 38.500304 -411.151324) (xy 38.500304 -410.993336)
			(xy 38.499876 -410.984151) (xy 38.493375 -410.966966) (xy 38.487604 -410.959808) (xy 38.465802 -410.934168)
			(xy 38.427856 -410.878579) (xy 38.396825 -410.818854) (xy 38.373155 -410.755848) (xy 38.357184 -410.690464)
			(xy 38.349141 -410.623641) (xy 35.071078 -410.623641) (xy 35.071078 -410.623699) (xy 35.063004 -410.690636)
			(xy 35.046971 -410.756124) (xy 35.023209 -410.81922) (xy 34.992061 -410.879016) (xy 34.953975 -410.934651)
			(xy 34.932112 -410.960316) (xy 34.926328 -410.96747) (xy 34.919805 -410.984654) (xy 34.919412 -410.993844)
			(xy 34.919412 -411.151324) (xy 34.918935 -411.161433) (xy 34.911192 -411.180109) (xy 34.896893 -411.194403)
			(xy 34.878213 -411.202139) (xy 34.868104 -411.202632) (xy 34.151824 -411.202632) (xy 34.141721 -411.202096)
			(xy 34.123049 -411.194372) (xy 34.108755 -411.180091) (xy 34.101013 -411.161427) (xy 34.100516 -411.151324)
			(xy 34.100516 -410.993844) (xy 34.100081 -410.98466) (xy 34.093584 -410.967475) (xy 34.087816 -410.960316)
			(xy 34.065936 -410.934664) (xy 34.027846 -410.879028) (xy 33.996696 -410.81923) (xy 33.972932 -410.756131)
			(xy 33.956897 -410.690641) (xy 33.948822 -410.623701) (xy 30.670776 -410.623701) (xy 30.66274 -410.690462)
			(xy 30.646767 -410.755844) (xy 30.623095 -410.818848) (xy 30.592061 -410.878571) (xy 30.554112 -410.934156)
			(xy 30.532324 -410.959808) (xy 30.526544 -410.966965) (xy 30.520019 -410.984146) (xy 30.519624 -410.993336)
			(xy 30.519624 -411.151324) (xy 30.519199 -411.161477) (xy 30.5114 -411.180225) (xy 30.497005 -411.194547)
			(xy 30.478217 -411.20225) (xy 30.468062 -411.202632) (xy 29.751782 -411.202632) (xy 29.741651 -411.202188)
			(xy 29.722924 -411.194449) (xy 29.708567 -411.180149) (xy 29.700753 -411.161453) (xy 29.70022 -411.151324)
			(xy 29.70022 -410.993336) (xy 29.699788 -410.984151) (xy 29.693289 -410.966967) (xy 29.68752 -410.959808)
			(xy 29.665717 -410.934169) (xy 29.62777 -410.87858) (xy 29.596738 -410.818854) (xy 29.573067 -410.755848)
			(xy 29.557096 -410.690465) (xy 29.549054 -410.623641) (xy 0.509016 -410.623641) (xy 0.509016 -416.589972)
			(xy 0.509537 -416.645741) (xy 0.517873 -416.756967) (xy 0.534497 -416.867259) (xy 0.559316 -416.976001)
			(xy 0.592193 -417.082584) (xy 0.632942 -417.186412) (xy 0.681337 -417.286904) (xy 0.682829 -417.289488)
			(xy 53.073808 -417.289488) (xy 53.073808 -394.27912) (xy 66.477388 -394.27912) (xy 66.525648 -394.32738)
			(xy 66.525648 -397.823885) (xy 71.348788 -397.823885) (xy 71.348792 -397.756458) (xy 71.356871 -397.689518)
			(xy 71.372911 -397.624026) (xy 71.396679 -397.560928) (xy 71.427833 -397.501131) (xy 71.465926 -397.445495)
			(xy 71.487792 -397.41983) (xy 71.4936 -397.412693) (xy 71.500108 -397.395496) (xy 71.500492 -397.386302)
			(xy 71.500492 -396.89405) (xy 71.50006 -396.884865) (xy 71.493562 -396.86768) (xy 71.487792 -396.860522)
			(xy 71.465918 -396.834865) (xy 71.427831 -396.779229) (xy 71.396681 -396.719431) (xy 71.372918 -396.656334)
			(xy 71.356883 -396.590844) (xy 71.348808 -396.523905) (xy 71.348809 -396.45648) (xy 71.356886 -396.389542)
			(xy 71.372922 -396.324052) (xy 71.396687 -396.260955) (xy 71.427838 -396.201158) (xy 71.465928 -396.145523)
			(xy 71.487792 -396.119858) (xy 71.493588 -396.112712) (xy 71.500103 -396.095522) (xy 71.500492 -396.08633)
			(xy 71.500492 -395.92885) (xy 71.501066 -395.918732) (xy 71.508769 -395.900021) (xy 71.523028 -395.885665)
			(xy 71.541686 -395.877836) (xy 71.5518 -395.877288) (xy 72.26808 -395.877288) (xy 72.278231 -395.877738)
			(xy 72.296981 -395.885524) (xy 72.311305 -395.899912) (xy 72.319007 -395.918697) (xy 72.319388 -395.92885)
			(xy 72.319388 -396.08633) (xy 72.319786 -396.095518) (xy 72.326308 -396.112703) (xy 72.332088 -396.119858)
			(xy 72.353943 -396.145531) (xy 72.392032 -396.201164) (xy 72.423184 -396.260959) (xy 72.446949 -396.324055)
			(xy 72.462986 -396.389543) (xy 72.471063 -396.456481) (xy 72.471064 -396.523904) (xy 72.462989 -396.590842)
			(xy 72.446954 -396.656331) (xy 72.42319 -396.719427) (xy 72.39204 -396.779223) (xy 72.353952 -396.834857)
			(xy 72.332088 -396.860522) (xy 72.326298 -396.867672) (xy 72.31978 -396.884859) (xy 72.319388 -396.89405)
			(xy 72.319388 -397.386302) (xy 72.3198 -397.395489) (xy 72.326313 -397.412673) (xy 72.332088 -397.41983)
			(xy 72.353915 -397.445526) (xy 72.392006 -397.501156) (xy 72.420766 -397.556355) (xy 73.54898 -397.556355)
			(xy 73.557023 -397.489534) (xy 73.572995 -397.424152) (xy 73.596666 -397.361148) (xy 73.627698 -397.301425)
			(xy 73.665645 -397.245838) (xy 73.687432 -397.220186) (xy 73.693221 -397.213036) (xy 73.69974 -397.195849)
			(xy 73.700132 -397.186658) (xy 73.700132 -397.028924) (xy 73.700542 -397.018767) (xy 73.708335 -397.000009)
			(xy 73.722736 -396.985684) (xy 73.741535 -396.977989) (xy 73.751694 -396.977616) (xy 74.467974 -396.977616)
			(xy 74.478096 -396.978147) (xy 74.496812 -396.985862) (xy 74.511169 -397.000134) (xy 74.518993 -397.018805)
			(xy 74.519536 -397.028924) (xy 74.519536 -397.186658) (xy 74.519981 -397.195841) (xy 74.526472 -397.213025)
			(xy 74.532236 -397.220186) (xy 74.554034 -397.24583) (xy 74.591984 -397.301417) (xy 74.623019 -397.361141)
			(xy 74.646692 -397.424147) (xy 74.662665 -397.48953) (xy 74.670709 -397.556354) (xy 74.670708 -397.623661)
			(xy 74.662662 -397.690484) (xy 74.646687 -397.755867) (xy 74.623012 -397.818872) (xy 74.620438 -397.823826)
			(xy 75.749084 -397.823826) (xy 75.749087 -397.756517) (xy 75.757136 -397.689691) (xy 75.773114 -397.624306)
			(xy 75.796793 -397.5613) (xy 75.827833 -397.501576) (xy 75.865789 -397.44599) (xy 75.88758 -397.420338)
			(xy 75.893383 -397.413197) (xy 75.899895 -397.396003) (xy 75.90028 -397.38681) (xy 75.90028 -396.893542)
			(xy 75.899854 -396.884356) (xy 75.893352 -396.867172) (xy 75.88758 -396.860014) (xy 75.865781 -396.83437)
			(xy 75.82783 -396.778784) (xy 75.796795 -396.719059) (xy 75.773121 -396.656054) (xy 75.757147 -396.59067)
			(xy 75.749104 -396.523846) (xy 75.749104 -396.456539) (xy 75.75715 -396.389715) (xy 75.773125 -396.324332)
			(xy 75.796801 -396.261327) (xy 75.827838 -396.201603) (xy 75.86579 -396.146018) (xy 75.88758 -396.120366)
			(xy 75.893371 -396.113217) (xy 75.89989 -396.096029) (xy 75.90028 -396.086838) (xy 75.90028 -395.92885)
			(xy 75.900706 -395.918676) (xy 75.908482 -395.899875) (xy 75.922868 -395.885487) (xy 75.941668 -395.877707)
			(xy 75.951842 -395.877288) (xy 76.668122 -395.877288) (xy 76.678301 -395.877647) (xy 76.697106 -395.885449)
			(xy 76.711492 -395.899855) (xy 76.719267 -395.91867) (xy 76.719684 -395.92885) (xy 76.719684 -396.086838)
			(xy 76.720079 -396.096027) (xy 76.726604 -396.113211) (xy 76.732384 -396.120366) (xy 76.754161 -396.146026)
			(xy 76.792109 -396.201612) (xy 76.823141 -396.261335) (xy 76.846814 -396.324338) (xy 76.862787 -396.389719)
			(xy 76.870831 -396.456541) (xy 76.870832 -396.523844) (xy 76.862789 -396.590666) (xy 76.846818 -396.656047)
			(xy 76.823147 -396.719051) (xy 76.792117 -396.778775) (xy 76.75417 -396.834362) (xy 76.732384 -396.860014)
			(xy 76.726597 -396.867166) (xy 76.720077 -396.884351) (xy 76.719684 -396.893542) (xy 76.719684 -397.38681)
			(xy 76.720093 -397.395997) (xy 76.726608 -397.413181) (xy 76.732384 -397.420338) (xy 76.754133 -397.446021)
			(xy 76.792082 -397.501604) (xy 76.820503 -397.556296) (xy 77.948748 -397.556296) (xy 77.956824 -397.489358)
			(xy 77.972859 -397.423869) (xy 77.996623 -397.360772) (xy 78.027774 -397.300977) (xy 78.065864 -397.245343)
			(xy 78.087728 -397.219678) (xy 78.09352 -397.21253) (xy 78.100037 -397.195341) (xy 78.100428 -397.18615)
			(xy 78.100428 -397.028924) (xy 78.100836 -397.0188) (xy 78.108582 -397.000091) (xy 78.122901 -396.985775)
			(xy 78.141611 -396.978034) (xy 78.151736 -396.977616) (xy 78.868016 -396.977616) (xy 78.878142 -396.978003)
			(xy 78.896849 -396.985759) (xy 78.911163 -397.000085) (xy 78.918905 -397.018798) (xy 78.919324 -397.028924)
			(xy 78.919324 -397.18615) (xy 78.919753 -397.195335) (xy 78.926253 -397.21252) (xy 78.932024 -397.219678)
			(xy 78.953897 -397.245336) (xy 78.991984 -397.300972) (xy 79.023133 -397.360769) (xy 79.046895 -397.423867)
			(xy 79.062929 -397.489357) (xy 79.071004 -397.556296) (xy 79.071003 -397.62372) (xy 79.062927 -397.690658)
			(xy 79.046891 -397.756147) (xy 79.023127 -397.819245) (xy 79.02071 -397.823885) (xy 80.148876 -397.823885)
			(xy 80.14888 -397.756458) (xy 80.156959 -397.689518) (xy 80.172998 -397.624027) (xy 80.196765 -397.560929)
			(xy 80.227919 -397.501131) (xy 80.266011 -397.445496) (xy 80.287876 -397.41983) (xy 80.293682 -397.412691)
			(xy 80.300192 -397.395496) (xy 80.300576 -397.386302) (xy 80.300576 -396.89405) (xy 80.300147 -396.884865)
			(xy 80.293647 -396.86768) (xy 80.287876 -396.860522) (xy 80.266003 -396.834864) (xy 80.227916 -396.779228)
			(xy 80.196767 -396.719431) (xy 80.173005 -396.656333) (xy 80.156971 -396.590843) (xy 80.148896 -396.523904)
			(xy 80.148897 -396.45648) (xy 80.156973 -396.389542) (xy 80.173009 -396.324053) (xy 80.196773 -396.260955)
			(xy 80.227924 -396.201159) (xy 80.266012 -396.145524) (xy 80.287876 -396.119858) (xy 80.29367 -396.112711)
			(xy 80.300187 -396.095522) (xy 80.300576 -396.08633) (xy 80.300576 -395.92885) (xy 80.301069 -395.918722)
			(xy 80.308787 -395.899995) (xy 80.323072 -395.885636) (xy 80.341759 -395.877821) (xy 80.351884 -395.877288)
			(xy 81.068164 -395.877288) (xy 81.078314 -395.877751) (xy 81.097063 -395.885532) (xy 81.111388 -395.899917)
			(xy 81.119091 -395.918698) (xy 81.119472 -395.92885) (xy 81.119472 -396.08633) (xy 81.119874 -396.095518)
			(xy 81.126394 -396.112702) (xy 81.132172 -396.119858) (xy 81.154027 -396.145531) (xy 81.192118 -396.201164)
			(xy 81.223271 -396.260959) (xy 81.247037 -396.324054) (xy 81.263074 -396.389543) (xy 81.271151 -396.456481)
			(xy 81.271152 -396.523904) (xy 81.263076 -396.590842) (xy 81.247041 -396.656331) (xy 81.223277 -396.719428)
			(xy 81.192126 -396.779223) (xy 81.154036 -396.834857) (xy 81.132172 -396.860522) (xy 81.12638 -396.86767)
			(xy 81.119863 -396.884859) (xy 81.119472 -396.89405) (xy 81.119472 -397.386302) (xy 81.119887 -397.395489)
			(xy 81.126398 -397.412673) (xy 81.132172 -397.41983) (xy 81.154 -397.445526) (xy 81.192091 -397.501155)
			(xy 81.220853 -397.556356) (xy 82.349068 -397.556356) (xy 82.357111 -397.489534) (xy 82.373082 -397.424153)
			(xy 82.396753 -397.361149) (xy 82.427783 -397.301425) (xy 82.46573 -397.245838) (xy 82.487516 -397.220186)
			(xy 82.493303 -397.213034) (xy 82.499823 -397.195849) (xy 82.500216 -397.186658) (xy 82.500216 -397.028924)
			(xy 82.500641 -397.018769) (xy 82.508432 -397.000014) (xy 82.522828 -396.98569) (xy 82.541621 -396.977992)
			(xy 82.551778 -396.977616) (xy 83.268058 -396.977616) (xy 83.278179 -396.97816) (xy 83.296895 -396.98587)
			(xy 83.311252 -397.000138) (xy 83.319076 -397.018806) (xy 83.31962 -397.028924) (xy 83.31962 -397.186658)
			(xy 83.320046 -397.195844) (xy 83.326548 -397.213028) (xy 83.33232 -397.220186) (xy 83.354119 -397.24583)
			(xy 83.39207 -397.301416) (xy 83.423105 -397.361141) (xy 83.446779 -397.424146) (xy 83.462753 -397.48953)
			(xy 83.470796 -397.556354) (xy 83.470796 -397.623661) (xy 83.46275 -397.690485) (xy 83.446775 -397.755868)
			(xy 83.423099 -397.818873) (xy 83.420495 -397.823884) (xy 84.548667 -397.823884) (xy 84.548671 -397.756458)
			(xy 84.55675 -397.689518) (xy 84.572788 -397.624028) (xy 84.596555 -397.560929) (xy 84.627708 -397.501132)
			(xy 84.665799 -397.445496) (xy 84.687664 -397.41983) (xy 84.693481 -397.412699) (xy 84.699982 -397.395497)
			(xy 84.700364 -397.386302) (xy 84.700364 -396.89405) (xy 84.699916 -396.884867) (xy 84.693427 -396.867683)
			(xy 84.687664 -396.860522) (xy 84.665791 -396.834864) (xy 84.627705 -396.779228) (xy 84.596557 -396.71943)
			(xy 84.572795 -396.656332) (xy 84.556761 -396.590843) (xy 84.548687 -396.523904) (xy 84.548688 -396.456481)
			(xy 84.556764 -396.389542) (xy 84.5728 -396.324053) (xy 84.596563 -396.260956) (xy 84.627713 -396.201159)
			(xy 84.665801 -396.145524) (xy 84.687664 -396.119858) (xy 84.693469 -396.112719) (xy 84.699977 -396.095523)
			(xy 84.700364 -396.08633) (xy 84.700364 -395.92885) (xy 84.700868 -395.918724) (xy 84.708584 -395.899999)
			(xy 84.722866 -395.88564) (xy 84.741548 -395.877823) (xy 84.751672 -395.877288) (xy 85.467952 -395.877288)
			(xy 85.478102 -395.877761) (xy 85.496851 -395.885538) (xy 85.511175 -395.899919) (xy 85.518879 -395.918699)
			(xy 85.51926 -395.92885) (xy 85.51926 -396.08633) (xy 85.519665 -396.095518) (xy 85.526183 -396.112701)
			(xy 85.53196 -396.119858) (xy 85.553816 -396.145531) (xy 85.591907 -396.201163) (xy 85.623061 -396.260958)
			(xy 85.646827 -396.324054) (xy 85.662864 -396.389543) (xy 85.670942 -396.456481) (xy 85.670943 -396.523904)
			(xy 85.662867 -396.590843) (xy 85.646832 -396.656332) (xy 85.623067 -396.719428) (xy 85.591915 -396.779224)
			(xy 85.553825 -396.834857) (xy 85.53196 -396.860522) (xy 85.526167 -396.867669) (xy 85.519651 -396.884858)
			(xy 85.51926 -396.89405) (xy 85.51926 -397.386302) (xy 85.519678 -397.395488) (xy 85.526187 -397.412672)
			(xy 85.53196 -397.41983) (xy 85.553788 -397.445525) (xy 85.591881 -397.501155) (xy 85.620612 -397.556296)
			(xy 86.748836 -397.556296) (xy 86.756911 -397.489358) (xy 86.772946 -397.423869) (xy 86.79671 -397.360773)
			(xy 86.82786 -397.300977) (xy 86.865948 -397.245343) (xy 86.887812 -397.219678) (xy 86.893602 -397.212528)
			(xy 86.90012 -397.195341) (xy 86.900512 -397.18615) (xy 86.900512 -397.028924) (xy 86.900936 -397.018802)
			(xy 86.908678 -397.000096) (xy 86.922993 -396.985781) (xy 86.941698 -396.978037) (xy 86.95182 -396.977616)
			(xy 87.6681 -396.977616) (xy 87.678224 -396.978016) (xy 87.696931 -396.985768) (xy 87.711246 -397.000089)
			(xy 87.718988 -397.018799) (xy 87.719408 -397.028924) (xy 87.719408 -397.18615) (xy 87.71984 -397.195335)
			(xy 87.726338 -397.21252) (xy 87.732108 -397.219678) (xy 87.753982 -397.245335) (xy 87.792069 -397.300971)
			(xy 87.823219 -397.360769) (xy 87.846982 -397.423866) (xy 87.863017 -397.489356) (xy 87.871092 -397.556295)
			(xy 87.871091 -397.62372) (xy 87.863014 -397.690658) (xy 87.846978 -397.756148) (xy 87.823213 -397.819245)
			(xy 87.820827 -397.823826) (xy 88.948962 -397.823826) (xy 88.948966 -397.756517) (xy 88.957014 -397.689692)
			(xy 88.972991 -397.624307) (xy 88.996669 -397.561301) (xy 89.027707 -397.501577) (xy 89.065661 -397.44599)
			(xy 89.087452 -397.420338) (xy 89.093264 -397.413204) (xy 89.099768 -397.396005) (xy 89.100152 -397.38681)
			(xy 89.100152 -396.893542) (xy 89.09971 -396.884358) (xy 89.093217 -396.867175) (xy 89.087452 -396.860014)
			(xy 89.065654 -396.83437) (xy 89.027704 -396.778783) (xy 88.996671 -396.719058) (xy 88.972998 -396.656053)
			(xy 88.957025 -396.590669) (xy 88.948982 -396.523846) (xy 88.948983 -396.456539) (xy 88.957028 -396.389716)
			(xy 88.973003 -396.324333) (xy 88.996677 -396.261328) (xy 89.027712 -396.201604) (xy 89.065663 -396.146018)
			(xy 89.087452 -396.120366) (xy 89.093252 -396.113223) (xy 89.099763 -396.096031) (xy 89.100152 -396.086838)
			(xy 89.100152 -395.92885) (xy 89.100605 -395.91868) (xy 89.108376 -395.899884) (xy 89.122753 -395.885496)
			(xy 89.141544 -395.877712) (xy 89.151714 -395.877288) (xy 89.867994 -395.877288) (xy 89.878171 -395.87767)
			(xy 89.896976 -395.885462) (xy 89.911362 -395.899861) (xy 89.919139 -395.918672) (xy 89.919556 -395.92885)
			(xy 89.919556 -396.086838) (xy 89.919958 -396.096026) (xy 89.926478 -396.11321) (xy 89.932256 -396.120366)
			(xy 89.954034 -396.146026) (xy 89.991983 -396.201611) (xy 90.023017 -396.261334) (xy 90.046691 -396.324337)
			(xy 90.062665 -396.389719) (xy 90.07071 -396.45654) (xy 90.070711 -396.523845) (xy 90.062667 -396.590667)
			(xy 90.046695 -396.656048) (xy 90.023023 -396.719052) (xy 89.991991 -396.778776) (xy 89.954043 -396.834362)
			(xy 89.932256 -396.860014) (xy 89.926465 -396.867163) (xy 89.919948 -396.884351) (xy 89.919556 -396.893542)
			(xy 89.919556 -397.38681) (xy 89.919971 -397.395996) (xy 89.926482 -397.41318) (xy 89.932256 -397.420338)
			(xy 89.954006 -397.446021) (xy 89.991957 -397.501603) (xy 90.020411 -397.556356) (xy 91.149156 -397.556356)
			(xy 91.157198 -397.489535) (xy 91.173169 -397.424153) (xy 91.196839 -397.361149) (xy 91.227869 -397.301426)
			(xy 91.265814 -397.245839) (xy 91.2876 -397.220186) (xy 91.293385 -397.213033) (xy 91.299907 -397.195848)
			(xy 91.3003 -397.186658) (xy 91.3003 -397.028924) (xy 91.300741 -397.018771) (xy 91.308529 -397.000019)
			(xy 91.32292 -396.985695) (xy 91.341708 -396.977995) (xy 91.351862 -396.977616) (xy 92.068142 -396.977616)
			(xy 92.078268 -396.978091) (xy 92.096986 -396.985829) (xy 92.11134 -397.000118) (xy 92.119162 -397.0188)
			(xy 92.119704 -397.028924) (xy 92.119704 -397.186658) (xy 92.120133 -397.195843) (xy 92.126634 -397.213028)
			(xy 92.132404 -397.220186) (xy 92.1542 -397.245831) (xy 92.192146 -397.301419) (xy 92.223176 -397.361144)
			(xy 92.246847 -397.42415) (xy 92.262818 -397.489532) (xy 92.27086 -397.556355) (xy 92.270859 -397.62366)
			(xy 92.262815 -397.690483) (xy 92.246842 -397.755865) (xy 92.22317 -397.81887) (xy 92.220595 -397.823825)
			(xy 115.349226 -397.823825) (xy 115.349229 -397.756518) (xy 115.357277 -397.689693) (xy 115.373253 -397.624309)
			(xy 115.396928 -397.561303) (xy 115.427964 -397.501578) (xy 115.465915 -397.445991) (xy 115.487704 -397.420338)
			(xy 115.49351 -397.413199) (xy 115.500019 -397.396004) (xy 115.500404 -397.38681) (xy 115.500404 -396.893542)
			(xy 115.499973 -396.884357) (xy 115.493474 -396.867173) (xy 115.487704 -396.860014) (xy 115.465908 -396.834369)
			(xy 115.427961 -396.778781) (xy 115.39693 -396.719056) (xy 115.37326 -396.656051) (xy 115.357288 -396.590668)
			(xy 115.349246 -396.523845) (xy 115.349247 -396.45654) (xy 115.357291 -396.389717) (xy 115.373264 -396.324335)
			(xy 115.396937 -396.26133) (xy 115.427969 -396.201606) (xy 115.465917 -396.146019) (xy 115.487704 -396.120366)
			(xy 115.493498 -396.113219) (xy 115.500014 -396.09603) (xy 115.500404 -396.086838) (xy 115.500404 -395.92885)
			(xy 115.500904 -395.918686) (xy 115.508666 -395.899899) (xy 115.523028 -395.885513) (xy 115.541803 -395.87772)
			(xy 115.551966 -395.877288) (xy 116.268246 -395.877288) (xy 116.278427 -395.877627) (xy 116.297232 -395.885437)
			(xy 116.311617 -395.899849) (xy 116.319392 -395.918668) (xy 116.319808 -395.92885) (xy 116.319808 -396.086838)
			(xy 116.320198 -396.096027) (xy 116.326725 -396.113212) (xy 116.332508 -396.120366) (xy 116.354288 -396.146026)
			(xy 116.39224 -396.20161) (xy 116.423277 -396.261332) (xy 116.446952 -396.324335) (xy 116.462928 -396.389717)
			(xy 116.470973 -396.45654) (xy 116.470974 -396.523845) (xy 116.46293 -396.590668) (xy 116.446957 -396.65605)
			(xy 116.423283 -396.719055) (xy 116.392248 -396.778777) (xy 116.354297 -396.834363) (xy 116.332508 -396.860014)
			(xy 116.326724 -396.867168) (xy 116.320202 -396.884352) (xy 116.319808 -396.893542) (xy 116.319808 -397.38681)
			(xy 116.320212 -397.395998) (xy 116.32673 -397.413182) (xy 116.332508 -397.420338) (xy 116.35426 -397.44602)
			(xy 116.392213 -397.501601) (xy 116.42064 -397.556296) (xy 117.548866 -397.556296) (xy 117.556942 -397.489357)
			(xy 117.572978 -397.423868) (xy 117.596743 -397.360771) (xy 117.627896 -397.300976) (xy 117.665987 -397.245342)
			(xy 117.687852 -397.219678) (xy 117.693647 -397.212532) (xy 117.700161 -397.195342) (xy 117.700552 -397.18615)
			(xy 117.700552 -397.028924) (xy 117.701103 -397.018823) (xy 117.708824 -397.000154) (xy 117.7231 -396.98586)
			(xy 117.741759 -396.978116) (xy 117.75186 -396.977616) (xy 118.46814 -396.977616) (xy 118.478253 -396.978053)
			(xy 118.496935 -396.985807) (xy 118.511229 -397.000118) (xy 118.51896 -397.01881) (xy 118.519448 -397.028924)
			(xy 118.519448 -397.18615) (xy 118.519894 -397.195333) (xy 118.526384 -397.212517) (xy 118.532148 -397.219678)
			(xy 118.554024 -397.245334) (xy 118.592115 -397.300969) (xy 118.623269 -397.360766) (xy 118.647035 -397.423864)
			(xy 118.663071 -397.489355) (xy 118.671147 -397.556295) (xy 118.671146 -397.62372) (xy 118.663068 -397.69066)
			(xy 118.64703 -397.75615) (xy 118.623262 -397.819248) (xy 118.620846 -397.823885) (xy 119.748994 -397.823885)
			(xy 119.748998 -397.756458) (xy 119.757077 -397.689517) (xy 119.773117 -397.624026) (xy 119.796885 -397.560928)
			(xy 119.828041 -397.50113) (xy 119.866134 -397.445495) (xy 119.888 -397.41983) (xy 119.893809 -397.412693)
			(xy 119.900316 -397.395496) (xy 119.9007 -397.386302) (xy 119.9007 -396.89405) (xy 119.900266 -396.884865)
			(xy 119.893769 -396.867681) (xy 119.888 -396.860522) (xy 119.866126 -396.834865) (xy 119.828038 -396.779229)
			(xy 119.796888 -396.719432) (xy 119.773124 -396.656334) (xy 119.757089 -396.590844) (xy 119.749014 -396.523905)
			(xy 119.749015 -396.45648) (xy 119.757092 -396.389541) (xy 119.773128 -396.324052) (xy 119.796894 -396.260954)
			(xy 119.828046 -396.201158) (xy 119.866135 -396.145523) (xy 119.888 -396.119858) (xy 119.893797 -396.112713)
			(xy 119.900311 -396.095522) (xy 119.9007 -396.08633) (xy 119.9007 -395.92885) (xy 119.901266 -395.918731)
			(xy 119.90897 -395.900019) (xy 119.923232 -395.885662) (xy 119.941893 -395.877834) (xy 119.952008 -395.877288)
			(xy 120.668288 -395.877288) (xy 120.678408 -395.877725) (xy 120.697109 -395.885467) (xy 120.711424 -395.899777)
			(xy 120.719171 -395.918476) (xy 120.719596 -395.928596) (xy 120.719596 -396.08633) (xy 120.719992 -396.095519)
			(xy 120.726516 -396.112703) (xy 120.732296 -396.119858) (xy 120.75415 -396.145531) (xy 120.79224 -396.201165)
			(xy 120.823391 -396.26096) (xy 120.847156 -396.324055) (xy 120.863192 -396.389544) (xy 120.871269 -396.456481)
			(xy 120.87127 -396.523904) (xy 120.863195 -396.590842) (xy 120.84716 -396.65633) (xy 120.823397 -396.719427)
			(xy 120.792247 -396.779223) (xy 120.75416 -396.834857) (xy 120.732296 -396.860522) (xy 120.726507 -396.867673)
			(xy 120.719988 -396.884859) (xy 120.719596 -396.89405) (xy 120.719596 -397.386302) (xy 120.720006 -397.395489)
			(xy 120.72652 -397.412673) (xy 120.732296 -397.41983) (xy 120.754123 -397.445526) (xy 120.792213 -397.501156)
			(xy 120.820972 -397.556355) (xy 121.949186 -397.556355) (xy 121.95723 -397.489533) (xy 121.973202 -397.424152)
			(xy 121.996873 -397.361148) (xy 122.027905 -397.301425) (xy 122.065853 -397.245838) (xy 122.08764 -397.220186)
			(xy 122.09343 -397.213036) (xy 122.099948 -397.195849) (xy 122.10034 -397.186658) (xy 122.10034 -397.028924)
			(xy 122.100736 -397.018798) (xy 122.108484 -397.000087) (xy 122.122807 -396.985771) (xy 122.141522 -396.978032)
			(xy 122.151648 -396.977616) (xy 122.868182 -396.977616) (xy 122.878305 -396.978141) (xy 122.897021 -396.985858)
			(xy 122.911377 -397.000132) (xy 122.919201 -397.018804) (xy 122.919744 -397.028924) (xy 122.919744 -397.186658)
			(xy 122.920187 -397.195841) (xy 122.926679 -397.213026) (xy 122.932444 -397.220186) (xy 122.954242 -397.24583)
			(xy 122.992192 -397.301417) (xy 123.023225 -397.361142) (xy 123.046898 -397.424147) (xy 123.062871 -397.489531)
			(xy 123.070915 -397.556354) (xy 123.070914 -397.623661) (xy 123.062868 -397.690484) (xy 123.046894 -397.755867)
			(xy 123.023219 -397.818872) (xy 123.020645 -397.823826) (xy 124.14929 -397.823826) (xy 124.149293 -397.756517)
			(xy 124.157342 -397.689691) (xy 124.17332 -397.624306) (xy 124.197 -397.5613) (xy 124.22804 -397.501575)
			(xy 124.265997 -397.44599) (xy 124.287788 -397.420338) (xy 124.293592 -397.413198) (xy 124.300103 -397.396004)
			(xy 124.300488 -397.38681) (xy 124.300488 -396.893542) (xy 124.30006 -396.884357) (xy 124.293559 -396.867172)
			(xy 124.287788 -396.860014) (xy 124.265989 -396.834371) (xy 124.228037 -396.778784) (xy 124.197002 -396.71906)
			(xy 124.173327 -396.656054) (xy 124.157354 -396.59067) (xy 124.14931 -396.523846) (xy 124.14931 -396.456539)
			(xy 124.157356 -396.389715) (xy 124.173332 -396.324332) (xy 124.197008 -396.261327) (xy 124.228045 -396.201603)
			(xy 124.265998 -396.146018) (xy 124.287788 -396.120366) (xy 124.29358 -396.113218) (xy 124.300098 -396.09603)
			(xy 124.300488 -396.086838) (xy 124.300488 -395.92885) (xy 124.300906 -395.918675) (xy 124.308684 -395.899872)
			(xy 124.323072 -395.885484) (xy 124.341875 -395.877706) (xy 124.35205 -395.877288) (xy 125.06833 -395.877288)
			(xy 125.07851 -395.87764) (xy 125.097315 -395.885445) (xy 125.1117 -395.899852) (xy 125.119475 -395.91867)
			(xy 125.119892 -395.92885) (xy 125.119892 -396.086838) (xy 125.120286 -396.096027) (xy 125.126811 -396.113211)
			(xy 125.132592 -396.120366) (xy 125.154369 -396.146027) (xy 125.192316 -396.201613) (xy 125.223348 -396.261335)
			(xy 125.24702 -396.324339) (xy 125.262993 -396.389719) (xy 125.271037 -396.456541) (xy 125.271038 -396.523844)
			(xy 125.262995 -396.590666) (xy 125.247025 -396.656047) (xy 125.223354 -396.719051) (xy 125.192324 -396.778774)
			(xy 125.154378 -396.834361) (xy 125.132592 -396.860014) (xy 125.126806 -396.867167) (xy 125.120285 -396.884351)
			(xy 125.119892 -396.893542) (xy 125.119892 -397.38681) (xy 125.120299 -397.395998) (xy 125.126815 -397.413182)
			(xy 125.132592 -397.420338) (xy 125.154341 -397.446021) (xy 125.192289 -397.501604) (xy 125.22071 -397.556296)
			(xy 126.348954 -397.556296) (xy 126.35703 -397.489357) (xy 126.373065 -397.423869) (xy 126.39683 -397.360772)
			(xy 126.427981 -397.300976) (xy 126.466071 -397.245343) (xy 126.487936 -397.219678) (xy 126.493729 -397.21253)
			(xy 126.500245 -397.195342) (xy 126.500636 -397.18615) (xy 126.500636 -397.028924) (xy 126.501036 -397.018799)
			(xy 126.508783 -397.000089) (xy 126.523105 -396.985772) (xy 126.541818 -396.978032) (xy 126.551944 -396.977616)
			(xy 127.268224 -396.977616) (xy 127.278336 -396.978066) (xy 127.297018 -396.985814) (xy 127.311313 -397.000122)
			(xy 127.319044 -397.018811) (xy 127.319532 -397.028924) (xy 127.319532 -397.18615) (xy 127.319981 -397.195333)
			(xy 127.326469 -397.212517) (xy 127.332232 -397.219678) (xy 127.354105 -397.245336) (xy 127.392191 -397.300972)
			(xy 127.423339 -397.36077) (xy 127.447102 -397.423867) (xy 127.463135 -397.489357) (xy 127.47121 -397.556296)
			(xy 127.471209 -397.623719) (xy 127.463133 -397.690658) (xy 127.447097 -397.756147) (xy 127.423333 -397.819244)
			(xy 127.420946 -397.823826) (xy 128.54908 -397.823826) (xy 128.549084 -397.756517) (xy 128.557132 -397.689691)
			(xy 128.57311 -397.624306) (xy 128.596789 -397.5613) (xy 128.627829 -397.501576) (xy 128.665785 -397.445989)
			(xy 128.687576 -397.420338) (xy 128.693379 -397.413197) (xy 128.69989 -397.396003) (xy 128.700276 -397.38681)
			(xy 128.700276 -396.893542) (xy 128.699851 -396.884356) (xy 128.693348 -396.867171) (xy 128.687576 -396.860014)
			(xy 128.665777 -396.83437) (xy 128.627826 -396.778784) (xy 128.596792 -396.719059) (xy 128.573118 -396.656053)
			(xy 128.557144 -396.59067) (xy 128.5491 -396.523846) (xy 128.549101 -396.456539) (xy 128.557147 -396.389715)
			(xy 128.573122 -396.324332) (xy 128.596798 -396.261327) (xy 128.627834 -396.201604) (xy 128.665787 -396.146018)
			(xy 128.687576 -396.120366) (xy 128.693367 -396.113216) (xy 128.699886 -396.096029) (xy 128.700276 -396.086838)
			(xy 128.700276 -395.92885) (xy 128.700706 -395.918677) (xy 128.708481 -395.899876) (xy 128.722866 -395.885488)
			(xy 128.741665 -395.877708) (xy 128.751838 -395.877288) (xy 129.468118 -395.877288) (xy 129.478297 -395.87765)
			(xy 129.497102 -395.885451) (xy 129.511487 -395.899856) (xy 129.519263 -395.91867) (xy 129.51968 -395.92885)
			(xy 129.51968 -396.086838) (xy 129.520076 -396.096027) (xy 129.5266 -396.113211) (xy 129.53238 -396.120366)
			(xy 129.554157 -396.146026) (xy 129.592105 -396.201612) (xy 129.623138 -396.261335) (xy 129.64681 -396.324338)
			(xy 129.662784 -396.389719) (xy 129.670828 -396.456541) (xy 129.670829 -396.523844) (xy 129.662786 -396.590666)
			(xy 129.646815 -396.656047) (xy 129.623144 -396.719051) (xy 129.592113 -396.778775) (xy 129.554167 -396.834362)
			(xy 129.53238 -396.860014) (xy 129.526593 -396.867166) (xy 129.520073 -396.884351) (xy 129.51968 -396.893542)
			(xy 129.51968 -397.38681) (xy 129.52009 -397.395997) (xy 129.526604 -397.413181) (xy 129.53238 -397.420338)
			(xy 129.55413 -397.446021) (xy 129.592078 -397.501604) (xy 129.620531 -397.556356) (xy 130.749274 -397.556356)
			(xy 130.757317 -397.489534) (xy 130.773288 -397.424152) (xy 130.796959 -397.361148) (xy 130.827991 -397.301425)
			(xy 130.865937 -397.245838) (xy 130.887724 -397.220186) (xy 130.893512 -397.213035) (xy 130.900031 -397.195849)
			(xy 130.900424 -397.186658) (xy 130.900424 -397.028924) (xy 130.900842 -397.018768) (xy 130.908634 -397.000012)
			(xy 130.923032 -396.985687) (xy 130.941828 -396.97799) (xy 130.951986 -396.977616) (xy 131.668266 -396.977616)
			(xy 131.678388 -396.978154) (xy 131.697103 -396.985866) (xy 131.71146 -397.000137) (xy 131.719284 -397.018806)
			(xy 131.719828 -397.028924) (xy 131.719828 -397.186658) (xy 131.720252 -397.195844) (xy 131.726756 -397.213029)
			(xy 131.732528 -397.220186) (xy 131.754326 -397.24583) (xy 131.792277 -397.301417) (xy 131.823312 -397.361141)
			(xy 131.846985 -397.424147) (xy 131.862959 -397.48953) (xy 131.871003 -397.556354) (xy 131.871002 -397.623661)
			(xy 131.862956 -397.690485) (xy 131.846981 -397.755868) (xy 131.823306 -397.818873) (xy 131.792269 -397.878596)
			(xy 131.754317 -397.934182) (xy 131.732528 -397.959834) (xy 131.726726 -397.966975) (xy 131.720217 -397.984169)
			(xy 131.719828 -397.993362) (xy 131.719828 -398.486884) (xy 131.720239 -398.496071) (xy 131.726751 -398.513256)
			(xy 131.732528 -398.520412) (xy 131.754352 -398.546034) (xy 131.792302 -398.601624) (xy 131.823336 -398.661352)
			(xy 131.847008 -398.72436) (xy 131.86298 -398.789746) (xy 131.871021 -398.856573) (xy 131.871018 -398.923881)
			(xy 131.86297 -398.990707) (xy 131.846992 -399.056092) (xy 131.823314 -399.119098) (xy 131.792274 -399.178822)
			(xy 131.754319 -399.234408) (xy 131.732528 -399.26006) (xy 131.726715 -399.267193) (xy 131.720212 -399.284393)
			(xy 131.719828 -399.293588) (xy 131.719828 -399.451576) (xy 131.719359 -399.461725) (xy 131.711577 -399.480472)
			(xy 131.697195 -399.494795) (xy 131.678417 -399.502501) (xy 131.668266 -399.502884) (xy 130.951986 -399.502884)
			(xy 130.941861 -399.502385) (xy 130.923145 -399.494657) (xy 130.90879 -399.480375) (xy 130.900967 -399.461698)
			(xy 130.900424 -399.451576) (xy 130.900424 -399.293588) (xy 130.900014 -399.284401) (xy 130.8935 -399.267217)
			(xy 130.887724 -399.26006) (xy 130.865972 -399.234378) (xy 130.828023 -399.178796) (xy 130.796989 -399.119076)
			(xy 130.773315 -399.056076) (xy 130.75734 -398.990697) (xy 130.749294 -398.923878) (xy 130.74929 -398.856576)
			(xy 130.757331 -398.789756) (xy 130.773299 -398.724376) (xy 130.796967 -398.661373) (xy 130.827996 -398.601651)
			(xy 130.865939 -398.546065) (xy 130.887724 -398.520412) (xy 130.893543 -398.513283) (xy 130.900044 -398.49608)
			(xy 130.900424 -398.486884) (xy 130.900424 -397.993362) (xy 130.900027 -397.984174) (xy 130.893504 -397.96699)
			(xy 130.887724 -397.959834) (xy 130.865946 -397.934174) (xy 130.827998 -397.878588) (xy 130.796965 -397.818865)
			(xy 130.773293 -397.755862) (xy 130.75732 -397.690481) (xy 130.749275 -397.62366) (xy 130.749274 -397.556356)
			(xy 129.620531 -397.556356) (xy 129.623112 -397.561323) (xy 129.646786 -397.624324) (xy 129.662761 -397.689702)
			(xy 129.670808 -397.756521) (xy 129.670811 -397.823822) (xy 129.662771 -397.890642) (xy 129.646803 -397.956022)
			(xy 129.623135 -398.019025) (xy 129.592108 -398.078747) (xy 129.554165 -398.134333) (xy 129.53238 -398.159986)
			(xy 129.526562 -398.167116) (xy 129.520061 -398.184318) (xy 129.51968 -398.193514) (xy 129.51968 -398.351502)
			(xy 129.519169 -398.361658) (xy 129.511397 -398.380423) (xy 129.497037 -398.394788) (xy 129.478274 -398.402565)
			(xy 129.468118 -398.403064) (xy 128.751838 -398.403064) (xy 128.741669 -398.402605) (xy 128.722876 -398.394833)
			(xy 128.70849 -398.380458) (xy 128.700703 -398.361671) (xy 128.700276 -398.351502) (xy 128.700276 -398.193514)
			(xy 128.699865 -398.184327) (xy 128.693352 -398.167142) (xy 128.687576 -398.159986) (xy 128.66575 -398.134365)
			(xy 128.627799 -398.078775) (xy 128.596766 -398.019048) (xy 128.573093 -397.956039) (xy 128.557122 -397.890652)
			(xy 128.54908 -397.823826) (xy 127.420946 -397.823826) (xy 127.392183 -397.879041) (xy 127.354095 -397.934676)
			(xy 127.332232 -397.960342) (xy 127.326427 -397.967481) (xy 127.319919 -397.984676) (xy 127.319532 -397.99387)
			(xy 127.319532 -398.486376) (xy 127.319969 -398.49556) (xy 127.326466 -398.512744) (xy 127.332232 -398.519904)
			(xy 127.35413 -398.545541) (xy 127.392216 -398.60118) (xy 127.423363 -398.66098) (xy 127.447124 -398.724081)
			(xy 127.463156 -398.789573) (xy 127.471228 -398.856514) (xy 127.471225 -398.92394) (xy 127.463146 -398.99088)
			(xy 127.447108 -399.056371) (xy 127.423341 -399.119469) (xy 127.392188 -399.179266) (xy 127.354097 -399.234902)
			(xy 127.332232 -399.260568) (xy 127.326416 -399.267699) (xy 127.319915 -399.284901) (xy 127.319532 -399.294096)
			(xy 127.319532 -399.451576) (xy 127.318996 -399.461679) (xy 127.311272 -399.480351) (xy 127.296991 -399.494645)
			(xy 127.278327 -399.502387) (xy 127.268224 -399.502884) (xy 126.551944 -399.502884) (xy 126.541822 -399.502447)
			(xy 126.523117 -399.494711) (xy 126.5088 -399.4804) (xy 126.501056 -399.461697) (xy 126.500636 -399.451576)
			(xy 126.500636 -399.294096) (xy 126.50022 -399.28491) (xy 126.49371 -399.267726) (xy 126.487936 -399.260568)
			(xy 126.466106 -399.234874) (xy 126.428014 -399.179245) (xy 126.39686 -399.119453) (xy 126.373092 -399.056359)
			(xy 126.357053 -398.990873) (xy 126.348974 -398.923938) (xy 126.34897 -398.856516) (xy 126.357043 -398.78958)
			(xy 126.373076 -398.724092) (xy 126.396838 -398.660997) (xy 126.427986 -398.601202) (xy 126.466073 -398.545569)
			(xy 126.487936 -398.519904) (xy 126.493718 -398.512749) (xy 126.50024 -398.495566) (xy 126.500636 -398.486376)
			(xy 126.500636 -397.99387) (xy 126.500232 -397.984682) (xy 126.493713 -397.967498) (xy 126.487936 -397.960342)
			(xy 126.466081 -397.934669) (xy 126.427989 -397.879037) (xy 126.396836 -397.819242) (xy 126.37307 -397.756146)
			(xy 126.357032 -397.690657) (xy 126.348955 -397.623719) (xy 126.348954 -397.556296) (xy 125.22071 -397.556296)
			(xy 125.223323 -397.561324) (xy 125.246996 -397.624324) (xy 125.262971 -397.689702) (xy 125.271018 -397.756521)
			(xy 125.271021 -397.823822) (xy 125.262981 -397.890642) (xy 125.247013 -397.956021) (xy 125.223346 -398.019024)
			(xy 125.192319 -398.078747) (xy 125.154377 -398.134334) (xy 125.132592 -398.159986) (xy 125.126775 -398.167117)
			(xy 125.120273 -398.184318) (xy 125.119892 -398.193514) (xy 125.119892 -398.351502) (xy 125.119369 -398.361656)
			(xy 125.111599 -398.38042) (xy 125.097243 -398.394784) (xy 125.078484 -398.402563) (xy 125.06833 -398.403064)
			(xy 124.35205 -398.403064) (xy 124.341882 -398.402595) (xy 124.323089 -398.394827) (xy 124.308702 -398.380455)
			(xy 124.300915 -398.36167) (xy 124.300488 -398.351502) (xy 124.300488 -398.193514) (xy 124.300074 -398.184327)
			(xy 124.293563 -398.167143) (xy 124.287788 -398.159986) (xy 124.265961 -398.134365) (xy 124.228011 -398.078775)
			(xy 124.196976 -398.019048) (xy 124.173304 -397.956039) (xy 124.157332 -397.890653) (xy 124.14929 -397.823826)
			(xy 123.020645 -397.823826) (xy 122.992184 -397.878596) (xy 122.954233 -397.934182) (xy 122.932444 -397.959834)
			(xy 122.926644 -397.966976) (xy 122.920133 -397.984169) (xy 122.919744 -397.993362) (xy 122.919744 -398.486884)
			(xy 122.920174 -398.496069) (xy 122.926675 -398.513253) (xy 122.932444 -398.520412) (xy 122.954268 -398.546035)
			(xy 122.992217 -398.601625) (xy 123.023249 -398.661352) (xy 123.046921 -398.724361) (xy 123.062892 -398.789747)
			(xy 123.070933 -398.856573) (xy 123.07093 -398.923881) (xy 123.062882 -398.990707) (xy 123.046905 -399.056091)
			(xy 123.023227 -399.119097) (xy 122.992189 -399.178822) (xy 122.954235 -399.234408) (xy 122.932444 -399.26006)
			(xy 122.926633 -399.267194) (xy 122.920128 -399.284393) (xy 122.919744 -399.293588) (xy 122.919744 -399.451576)
			(xy 122.919196 -399.461678) (xy 122.911475 -399.480347) (xy 122.897197 -399.494641) (xy 122.878537 -399.502385)
			(xy 122.868436 -399.502884) (xy 122.151902 -399.502884) (xy 122.141778 -399.502372) (xy 122.123062 -399.49465)
			(xy 122.108706 -399.480371) (xy 122.100883 -399.461697) (xy 122.10034 -399.451576) (xy 122.10034 -399.293588)
			(xy 122.099927 -399.284401) (xy 122.093414 -399.267217) (xy 122.08764 -399.26006) (xy 122.065888 -399.234379)
			(xy 122.027938 -399.178796) (xy 121.996903 -399.119077) (xy 121.973228 -399.056076) (xy 121.957253 -398.990698)
			(xy 121.949206 -398.923878) (xy 121.949202 -398.856576) (xy 121.957243 -398.789756) (xy 121.973212 -398.724376)
			(xy 121.996881 -398.661373) (xy 122.02791 -398.60165) (xy 122.065855 -398.546064) (xy 122.08764 -398.520412)
			(xy 122.093461 -398.513285) (xy 122.09996 -398.49608) (xy 122.10034 -398.486884) (xy 122.10034 -397.993362)
			(xy 122.099939 -397.984174) (xy 122.093418 -397.96699) (xy 122.08764 -397.959834) (xy 122.065862 -397.934174)
			(xy 122.027913 -397.878588) (xy 121.996879 -397.818866) (xy 121.973206 -397.755863) (xy 121.957232 -397.690481)
			(xy 121.949187 -397.62366) (xy 121.949186 -397.556355) (xy 120.820972 -397.556355) (xy 120.823365 -397.560948)
			(xy 120.847132 -397.624041) (xy 120.86317 -397.689526) (xy 120.871249 -397.756461) (xy 120.871253 -397.823882)
			(xy 120.86318 -397.890818) (xy 120.847149 -397.956305) (xy 120.823389 -398.0194) (xy 120.792242 -398.079195)
			(xy 120.754158 -398.134829) (xy 120.732296 -398.160494) (xy 120.726519 -398.167653) (xy 120.719993 -398.184833)
			(xy 120.719596 -398.194022) (xy 120.719596 -398.351502) (xy 120.719076 -398.361624) (xy 120.711354 -398.380339)
			(xy 120.697079 -398.394694) (xy 120.678408 -398.402519) (xy 120.668288 -398.403064) (xy 119.952008 -398.403064)
			(xy 119.941882 -398.402677) (xy 119.923171 -398.394924) (xy 119.908855 -398.380599) (xy 119.901116 -398.361883)
			(xy 119.9007 -398.351756) (xy 119.9007 -398.194022) (xy 119.900279 -398.184836) (xy 119.893773 -398.167651)
			(xy 119.888 -398.160494) (xy 119.866099 -398.13486) (xy 119.828011 -398.079221) (xy 119.796862 -398.01942)
			(xy 119.7731 -397.956319) (xy 119.757067 -397.890826) (xy 119.748994 -397.823885) (xy 118.620846 -397.823885)
			(xy 118.592108 -397.879044) (xy 118.554014 -397.934678) (xy 118.532148 -397.960342) (xy 118.526345 -397.967482)
			(xy 118.519835 -397.984677) (xy 118.519448 -397.99387) (xy 118.519448 -398.486376) (xy 118.519881 -398.495561)
			(xy 118.52638 -398.512745) (xy 118.532148 -398.519904) (xy 118.554049 -398.545539) (xy 118.59214 -398.601177)
			(xy 118.623292 -398.660977) (xy 118.647057 -398.724078) (xy 118.663091 -398.789571) (xy 118.671165 -398.856513)
			(xy 118.671162 -398.923941) (xy 118.663082 -398.990882) (xy 118.647041 -399.056374) (xy 118.62327 -399.119473)
			(xy 118.592112 -399.17927) (xy 118.554016 -399.234904) (xy 118.532148 -399.260568) (xy 118.526334 -399.2677)
			(xy 118.519831 -399.284901) (xy 118.519448 -399.294096) (xy 118.519448 -399.451576) (xy 118.518897 -399.461677)
			(xy 118.511176 -399.480346) (xy 118.4969 -399.49464) (xy 118.478241 -399.502384) (xy 118.46814 -399.502884)
			(xy 117.75186 -399.502884) (xy 117.741747 -399.502447) (xy 117.723065 -399.494693) (xy 117.708771 -399.480382)
			(xy 117.70104 -399.46169) (xy 117.700552 -399.451576) (xy 117.700552 -399.294096) (xy 117.700132 -399.28491)
			(xy 117.693624 -399.267726) (xy 117.687852 -399.260568) (xy 117.666022 -399.234874) (xy 117.627928 -399.179245)
			(xy 117.596773 -399.119453) (xy 117.573005 -399.05636) (xy 117.556965 -398.990874) (xy 117.548886 -398.923938)
			(xy 117.548882 -398.856516) (xy 117.556955 -398.789579) (xy 117.572989 -398.724092) (xy 117.596751 -398.660996)
			(xy 117.627901 -398.601201) (xy 117.665988 -398.545568) (xy 117.687852 -398.519904) (xy 117.693636 -398.51275)
			(xy 117.700157 -398.495566) (xy 117.700552 -398.486376) (xy 117.700552 -397.99387) (xy 117.700145 -397.984683)
			(xy 117.693628 -397.967499) (xy 117.687852 -397.960342) (xy 117.665996 -397.93467) (xy 117.627904 -397.879037)
			(xy 117.59675 -397.819243) (xy 117.572983 -397.756147) (xy 117.556945 -397.690658) (xy 117.548867 -397.623719)
			(xy 117.548866 -397.556296) (xy 116.42064 -397.556296) (xy 116.423251 -397.56132) (xy 116.446929 -397.624321)
			(xy 116.462906 -397.6897) (xy 116.470954 -397.75652) (xy 116.470957 -397.823823) (xy 116.462916 -397.890644)
			(xy 116.446945 -397.956025) (xy 116.423275 -398.019028) (xy 116.392243 -398.07875) (xy 116.354295 -398.134335)
			(xy 116.332508 -398.159986) (xy 116.326693 -398.167118) (xy 116.320189 -398.184319) (xy 116.319808 -398.193514)
			(xy 116.319808 -398.351502) (xy 116.319269 -398.361654) (xy 116.311503 -398.380415) (xy 116.297152 -398.394778)
			(xy 116.278398 -398.402561) (xy 116.268246 -398.403064) (xy 115.551966 -398.403064) (xy 115.541806 -398.402595)
			(xy 115.523037 -398.394809) (xy 115.508673 -398.380436) (xy 115.500899 -398.361662) (xy 115.500404 -398.351502)
			(xy 115.500404 -398.193514) (xy 115.499986 -398.184328) (xy 115.493478 -398.167143) (xy 115.487704 -398.159986)
			(xy 115.46588 -398.134364) (xy 115.427935 -398.078772) (xy 115.396905 -398.019044) (xy 115.373236 -397.956036)
			(xy 115.357267 -397.89065) (xy 115.349226 -397.823825) (xy 92.220595 -397.823825) (xy 92.192138 -397.878594)
			(xy 92.154191 -397.934181) (xy 92.132404 -397.959834) (xy 92.126611 -397.966982) (xy 92.120094 -397.98417)
			(xy 92.119704 -397.993362) (xy 92.119704 -398.486884) (xy 92.120121 -398.49607) (xy 92.12663 -398.513255)
			(xy 92.132404 -398.520412) (xy 92.154226 -398.546036) (xy 92.192171 -398.601627) (xy 92.2232 -398.661355)
			(xy 92.246869 -398.724363) (xy 92.262838 -398.789748) (xy 92.270879 -398.856574) (xy 92.270875 -398.923881)
			(xy 92.262828 -398.990705) (xy 92.246853 -399.056089) (xy 92.223178 -399.119094) (xy 92.192143 -399.178819)
			(xy 92.154193 -399.234407) (xy 92.132404 -399.26006) (xy 92.1266 -399.2672) (xy 92.12009 -399.284394)
			(xy 92.119704 -399.293588) (xy 92.119704 -399.451576) (xy 92.119259 -399.461728) (xy 92.111472 -399.480479)
			(xy 92.097082 -399.494803) (xy 92.078296 -399.502505) (xy 92.068142 -399.502884) (xy 91.351862 -399.502884)
			(xy 91.341736 -399.502405) (xy 91.323018 -399.494669) (xy 91.308664 -399.480381) (xy 91.300842 -399.4617)
			(xy 91.3003 -399.451576) (xy 91.3003 -399.293588) (xy 91.299895 -399.2844) (xy 91.293378 -399.267216)
			(xy 91.2876 -399.26006) (xy 91.265849 -399.234378) (xy 91.227901 -399.178795) (xy 91.196869 -399.119075)
			(xy 91.173196 -399.056075) (xy 91.157221 -398.990697) (xy 91.149175 -398.923878) (xy 91.149172 -398.856576)
			(xy 91.157212 -398.789757) (xy 91.17318 -398.724377) (xy 91.196847 -398.661374) (xy 91.227874 -398.601651)
			(xy 91.265816 -398.546065) (xy 91.2876 -398.520412) (xy 91.293416 -398.513281) (xy 91.299919 -398.49608)
			(xy 91.3003 -398.486884) (xy 91.3003 -397.993362) (xy 91.299908 -397.984173) (xy 91.293382 -397.966989)
			(xy 91.2876 -397.959834) (xy 91.265823 -397.934173) (xy 91.227877 -397.878587) (xy 91.196845 -397.818864)
			(xy 91.173174 -397.755861) (xy 91.157201 -397.69048) (xy 91.149157 -397.623659) (xy 91.149156 -397.556356)
			(xy 90.020411 -397.556356) (xy 90.022992 -397.561322) (xy 90.046667 -397.624323) (xy 90.062643 -397.689701)
			(xy 90.07069 -397.75652) (xy 90.070693 -397.823822) (xy 90.062653 -397.890643) (xy 90.046684 -397.956023)
			(xy 90.023015 -398.019026) (xy 89.991986 -398.078748) (xy 89.954041 -398.134334) (xy 89.932256 -398.159986)
			(xy 89.926435 -398.167114) (xy 89.919936 -398.184318) (xy 89.919556 -398.193514) (xy 89.919556 -398.351502)
			(xy 89.919138 -398.361674) (xy 89.911351 -398.38047) (xy 89.896964 -398.394855) (xy 89.878167 -398.402639)
			(xy 89.867994 -398.403064) (xy 89.151714 -398.403064) (xy 89.141544 -398.402625) (xy 89.122749 -398.394845)
			(xy 89.108364 -398.380464) (xy 89.100578 -398.361672) (xy 89.100152 -398.351502) (xy 89.100152 -398.193514)
			(xy 89.099724 -398.184329) (xy 89.093221 -398.167145) (xy 89.087452 -398.159986) (xy 89.065626 -398.134365)
			(xy 89.027678 -398.078774) (xy 88.996645 -398.019047) (xy 88.972974 -397.956038) (xy 88.957004 -397.890652)
			(xy 88.948962 -397.823826) (xy 87.820827 -397.823826) (xy 87.792062 -397.879042) (xy 87.753972 -397.934677)
			(xy 87.732108 -397.960342) (xy 87.726312 -397.967488) (xy 87.719797 -397.984678) (xy 87.719408 -397.99387)
			(xy 87.719408 -398.486376) (xy 87.719828 -398.495562) (xy 87.726335 -398.512747) (xy 87.732108 -398.519904)
			(xy 87.754007 -398.54554) (xy 87.792094 -398.601179) (xy 87.823243 -398.660979) (xy 87.847005 -398.72408)
			(xy 87.863037 -398.789573) (xy 87.87111 -398.856514) (xy 87.871107 -398.92394) (xy 87.863028 -398.990881)
			(xy 87.846989 -399.056372) (xy 87.823221 -399.11947) (xy 87.792066 -399.179267) (xy 87.753974 -399.234903)
			(xy 87.732108 -399.260568) (xy 87.726301 -399.267706) (xy 87.719792 -399.284902) (xy 87.719408 -399.294096)
			(xy 87.719408 -399.451576) (xy 87.718965 -399.461696) (xy 87.711226 -399.480398) (xy 87.696918 -399.494712)
			(xy 87.67822 -399.50246) (xy 87.6681 -399.502884) (xy 86.95182 -399.502884) (xy 86.941697 -399.502467)
			(xy 86.922991 -399.494723) (xy 86.908675 -399.480406) (xy 86.900932 -399.461699) (xy 86.900512 -399.451576)
			(xy 86.900512 -399.294096) (xy 86.900101 -399.284909) (xy 86.893587 -399.267725) (xy 86.887812 -399.260568)
			(xy 86.865983 -399.234874) (xy 86.827892 -399.179244) (xy 86.796739 -399.119452) (xy 86.772973 -399.056358)
			(xy 86.756934 -398.990873) (xy 86.748855 -398.923938) (xy 86.748852 -398.856516) (xy 86.756925 -398.78958)
			(xy 86.772957 -398.724093) (xy 86.796717 -398.660998) (xy 86.827865 -398.601203) (xy 86.86595 -398.545569)
			(xy 86.887812 -398.519904) (xy 86.893591 -398.512746) (xy 86.900116 -398.495565) (xy 86.900512 -398.486376)
			(xy 86.900512 -397.99387) (xy 86.900114 -397.984682) (xy 86.893592 -397.967497) (xy 86.887812 -397.960342)
			(xy 86.865957 -397.934669) (xy 86.827868 -397.879036) (xy 86.796716 -397.819241) (xy 86.772951 -397.756145)
			(xy 86.756914 -397.690657) (xy 86.748837 -397.623719) (xy 86.748836 -397.556296) (xy 85.620612 -397.556296)
			(xy 85.623035 -397.560946) (xy 85.646803 -397.624039) (xy 85.662842 -397.689525) (xy 85.670922 -397.756461)
			(xy 85.670925 -397.823882) (xy 85.662853 -397.890819) (xy 85.64682 -397.956306) (xy 85.623058 -398.019402)
			(xy 85.59191 -398.079196) (xy 85.553823 -398.134829) (xy 85.53196 -398.160494) (xy 85.526178 -398.16765)
			(xy 85.519656 -398.184832) (xy 85.51926 -398.194022) (xy 85.51926 -398.351502) (xy 85.518775 -398.361629)
			(xy 85.511047 -398.38035) (xy 85.49676 -398.394706) (xy 85.478076 -398.402525) (xy 85.467952 -398.403064)
			(xy 84.751672 -398.403064) (xy 84.741512 -398.402701) (xy 84.722752 -398.394889) (xy 84.708428 -398.380474)
			(xy 84.700736 -398.361665) (xy 84.700364 -398.351502) (xy 84.700364 -398.194022) (xy 84.699929 -398.184838)
			(xy 84.693431 -398.167654) (xy 84.687664 -398.160494) (xy 84.665764 -398.134859) (xy 84.627679 -398.079219)
			(xy 84.596532 -398.019419) (xy 84.572771 -397.956318) (xy 84.55674 -397.890825) (xy 84.548667 -397.823884)
			(xy 83.420495 -397.823884) (xy 83.392062 -397.878597) (xy 83.35411 -397.934182) (xy 83.33232 -397.959834)
			(xy 83.326529 -397.966983) (xy 83.32001 -397.984171) (xy 83.31962 -397.993362) (xy 83.31962 -398.486884)
			(xy 83.320033 -398.496071) (xy 83.326544 -398.513256) (xy 83.33232 -398.520412) (xy 83.354144 -398.546035)
			(xy 83.392095 -398.601624) (xy 83.423129 -398.661352) (xy 83.446801 -398.72436) (xy 83.462773 -398.789746)
			(xy 83.470815 -398.856573) (xy 83.470812 -398.923881) (xy 83.462763 -398.990707) (xy 83.446785 -399.056092)
			(xy 83.423107 -399.119098) (xy 83.392067 -399.178822) (xy 83.354111 -399.234408) (xy 83.33232 -399.26006)
			(xy 83.326518 -399.267201) (xy 83.320006 -399.284395) (xy 83.31962 -399.293588) (xy 83.31962 -399.451576)
			(xy 83.319159 -399.461726) (xy 83.311375 -399.480474) (xy 83.296991 -399.494798) (xy 83.27821 -399.502502)
			(xy 83.268058 -399.502884) (xy 82.551778 -399.502884) (xy 82.541653 -399.502392) (xy 82.522936 -399.494662)
			(xy 82.508581 -399.480378) (xy 82.500758 -399.461699) (xy 82.500216 -399.451576) (xy 82.500216 -399.293588)
			(xy 82.499808 -399.284401) (xy 82.493293 -399.267216) (xy 82.487516 -399.26006) (xy 82.465765 -399.234378)
			(xy 82.427816 -399.178795) (xy 82.396783 -399.119076) (xy 82.373109 -399.056075) (xy 82.357134 -398.990697)
			(xy 82.349088 -398.923878) (xy 82.349084 -398.856576) (xy 82.357125 -398.789756) (xy 82.373093 -398.724377)
			(xy 82.396761 -398.661374) (xy 82.427788 -398.601651) (xy 82.465731 -398.546065) (xy 82.487516 -398.520412)
			(xy 82.493334 -398.513282) (xy 82.499835 -398.49608) (xy 82.500216 -398.486884) (xy 82.500216 -397.993362)
			(xy 82.499821 -397.984173) (xy 82.493296 -397.966989) (xy 82.487516 -397.959834) (xy 82.465739 -397.934174)
			(xy 82.427791 -397.878588) (xy 82.396759 -397.818865) (xy 82.373086 -397.755862) (xy 82.357113 -397.690481)
			(xy 82.349069 -397.623659) (xy 82.349068 -397.556356) (xy 81.220853 -397.556356) (xy 81.223245 -397.560947)
			(xy 81.247013 -397.62404) (xy 81.263052 -397.689525) (xy 81.271131 -397.756461) (xy 81.271135 -397.823882)
			(xy 81.263062 -397.890818) (xy 81.24703 -397.956306) (xy 81.223269 -398.019401) (xy 81.192121 -398.079196)
			(xy 81.154035 -398.134829) (xy 81.132172 -398.160494) (xy 81.126392 -398.167651) (xy 81.119868 -398.184832)
			(xy 81.119472 -398.194022) (xy 81.119472 -398.351502) (xy 81.118975 -398.361627) (xy 81.111249 -398.380346)
			(xy 81.096966 -398.394702) (xy 81.078287 -398.402523) (xy 81.068164 -398.403064) (xy 80.351884 -398.403064)
			(xy 80.341724 -398.402691) (xy 80.322965 -398.394883) (xy 80.30864 -398.380471) (xy 80.300948 -398.361664)
			(xy 80.300576 -398.351502) (xy 80.300576 -398.194022) (xy 80.300161 -398.184835) (xy 80.293651 -398.16765)
			(xy 80.287876 -398.160494) (xy 80.265976 -398.134859) (xy 80.22789 -398.07922) (xy 80.196742 -398.019419)
			(xy 80.172981 -397.956318) (xy 80.156949 -397.890826) (xy 80.148876 -397.823885) (xy 79.02071 -397.823885)
			(xy 78.991976 -397.879041) (xy 78.953888 -397.934676) (xy 78.932024 -397.960342) (xy 78.92623 -397.967489)
			(xy 78.919713 -397.984678) (xy 78.919324 -397.99387) (xy 78.919324 -398.486376) (xy 78.91974 -398.495563)
			(xy 78.926249 -398.512747) (xy 78.932024 -398.519904) (xy 78.953922 -398.54554) (xy 78.992009 -398.60118)
			(xy 79.023156 -398.66098) (xy 79.046917 -398.724081) (xy 79.06295 -398.789573) (xy 79.071022 -398.856514)
			(xy 79.071019 -398.92394) (xy 79.06294 -398.99088) (xy 79.046901 -399.056371) (xy 79.023134 -399.119469)
			(xy 78.991981 -399.179267) (xy 78.953889 -399.234902) (xy 78.932024 -399.260568) (xy 78.926219 -399.267707)
			(xy 78.919709 -399.284902) (xy 78.919324 -399.294096) (xy 78.919324 -399.451576) (xy 78.918865 -399.461694)
			(xy 78.911129 -399.480393) (xy 78.896826 -399.494707) (xy 78.878134 -399.502457) (xy 78.868016 -399.502884)
			(xy 78.151736 -399.502884) (xy 78.141614 -399.502454) (xy 78.122908 -399.494715) (xy 78.108592 -399.480402)
			(xy 78.100848 -399.461698) (xy 78.100428 -399.451576) (xy 78.100428 -399.294096) (xy 78.100014 -399.284909)
			(xy 78.093502 -399.267725) (xy 78.087728 -399.260568) (xy 78.065898 -399.234874) (xy 78.027807 -399.179244)
			(xy 77.996653 -399.119452) (xy 77.972886 -399.056359) (xy 77.956847 -398.990873) (xy 77.948768 -398.923938)
			(xy 77.948764 -398.856516) (xy 77.956837 -398.78958) (xy 77.972869 -398.724093) (xy 77.996631 -398.660997)
			(xy 78.027779 -398.601202) (xy 78.065865 -398.545569) (xy 78.087728 -398.519904) (xy 78.093509 -398.512748)
			(xy 78.100032 -398.495566) (xy 78.100428 -398.486376) (xy 78.100428 -397.99387) (xy 78.100026 -397.984682)
			(xy 78.093506 -397.967498) (xy 78.087728 -397.960342) (xy 78.065873 -397.934669) (xy 78.027782 -397.879036)
			(xy 77.996629 -397.819241) (xy 77.972863 -397.756146) (xy 77.956826 -397.690657) (xy 77.948749 -397.623719)
			(xy 77.948748 -397.556296) (xy 76.820503 -397.556296) (xy 76.823115 -397.561323) (xy 76.846789 -397.624324)
			(xy 76.862764 -397.689702) (xy 76.870811 -397.756521) (xy 76.870814 -397.823822) (xy 76.862774 -397.890642)
			(xy 76.846806 -397.956022) (xy 76.823139 -398.019024) (xy 76.792111 -398.078747) (xy 76.754168 -398.134333)
			(xy 76.732384 -398.159986) (xy 76.726567 -398.167116) (xy 76.720065 -398.184318) (xy 76.719684 -398.193514)
			(xy 76.719684 -398.351502) (xy 76.719169 -398.361657) (xy 76.711398 -398.380422) (xy 76.697039 -398.394787)
			(xy 76.678277 -398.402565) (xy 76.668122 -398.403064) (xy 75.951842 -398.403064) (xy 75.941673 -398.402602)
			(xy 75.92288 -398.394831) (xy 75.908494 -398.380457) (xy 75.900707 -398.36167) (xy 75.90028 -398.351502)
			(xy 75.90028 -398.193514) (xy 75.899868 -398.184327) (xy 75.893356 -398.167142) (xy 75.88758 -398.159986)
			(xy 75.865754 -398.134365) (xy 75.827803 -398.078775) (xy 75.79677 -398.019048) (xy 75.773097 -397.956039)
			(xy 75.757126 -397.890653) (xy 75.749084 -397.823826) (xy 74.620438 -397.823826) (xy 74.591977 -397.878596)
			(xy 74.554025 -397.934182) (xy 74.532236 -397.959834) (xy 74.526435 -397.966975) (xy 74.519925 -397.984169)
			(xy 74.519536 -397.993362) (xy 74.519536 -398.486884) (xy 74.519968 -398.496069) (xy 74.526468 -398.513252)
			(xy 74.532236 -398.520412) (xy 74.55406 -398.546035) (xy 74.592009 -398.601625) (xy 74.623043 -398.661352)
			(xy 74.646714 -398.724361) (xy 74.662686 -398.789747) (xy 74.670727 -398.856573) (xy 74.670724 -398.923881)
			(xy 74.662676 -398.990707) (xy 74.646698 -399.056091) (xy 74.623021 -399.119097) (xy 74.591982 -399.178822)
			(xy 74.554027 -399.234408) (xy 74.532236 -399.26006) (xy 74.526424 -399.267194) (xy 74.51992 -399.284393)
			(xy 74.519536 -399.293588) (xy 74.519536 -399.451576) (xy 74.51906 -399.461724) (xy 74.511279 -399.480469)
			(xy 74.496899 -399.494792) (xy 74.478124 -399.502499) (xy 74.467974 -399.502884) (xy 73.751694 -399.502884)
			(xy 73.74157 -399.502379) (xy 73.722853 -399.494654) (xy 73.708498 -399.480373) (xy 73.700675 -399.461697)
			(xy 73.700132 -399.451576) (xy 73.700132 -399.293588) (xy 73.699721 -399.284401) (xy 73.693207 -399.267217)
			(xy 73.687432 -399.26006) (xy 73.66568 -399.234378) (xy 73.627731 -399.178796) (xy 73.596696 -399.119077)
			(xy 73.573022 -399.056076) (xy 73.557047 -398.990697) (xy 73.549 -398.923878) (xy 73.548996 -398.856576)
			(xy 73.557037 -398.789756) (xy 73.573006 -398.724376) (xy 73.596674 -398.661373) (xy 73.627703 -398.60165)
			(xy 73.665647 -398.546064) (xy 73.687432 -398.520412) (xy 73.693253 -398.513284) (xy 73.699752 -398.49608)
			(xy 73.700132 -398.486884) (xy 73.700132 -397.993362) (xy 73.699733 -397.984174) (xy 73.693211 -397.96699)
			(xy 73.687432 -397.959834) (xy 73.665654 -397.934174) (xy 73.627705 -397.878588) (xy 73.596672 -397.818866)
			(xy 73.572999 -397.755862) (xy 73.557026 -397.690481) (xy 73.548981 -397.62366) (xy 73.54898 -397.556355)
			(xy 72.420766 -397.556355) (xy 72.423159 -397.560948) (xy 72.446926 -397.62404) (xy 72.462964 -397.689526)
			(xy 72.471043 -397.756461) (xy 72.471047 -397.823882) (xy 72.462974 -397.890818) (xy 72.446942 -397.956305)
			(xy 72.423182 -398.0194) (xy 72.392035 -398.079195) (xy 72.35395 -398.134829) (xy 72.332088 -398.160494)
			(xy 72.32631 -398.167652) (xy 72.319785 -398.184833) (xy 72.319388 -398.194022) (xy 72.319388 -398.351502)
			(xy 72.318876 -398.361625) (xy 72.311153 -398.380341) (xy 72.296875 -398.394696) (xy 72.278201 -398.40252)
			(xy 72.26808 -398.403064) (xy 71.5518 -398.403064) (xy 71.541641 -398.402678) (xy 71.522882 -398.394875)
			(xy 71.508557 -398.380467) (xy 71.500864 -398.361663) (xy 71.500492 -398.351502) (xy 71.500492 -398.194022)
			(xy 71.500073 -398.184836) (xy 71.493566 -398.167651) (xy 71.487792 -398.160494) (xy 71.465891 -398.134859)
			(xy 71.427804 -398.07922) (xy 71.396655 -398.01942) (xy 71.372894 -397.956319) (xy 71.356861 -397.890826)
			(xy 71.348788 -397.823885) (xy 66.525648 -397.823885) (xy 66.525648 -401.723796) (xy 71.3488 -401.723796)
			(xy 71.348802 -401.656371) (xy 71.35688 -401.589431) (xy 71.372917 -401.523941) (xy 71.396683 -401.460843)
			(xy 71.427836 -401.401046) (xy 71.465927 -401.345411) (xy 71.487792 -401.319746) (xy 71.493593 -401.312604)
			(xy 71.500105 -401.295411) (xy 71.500492 -401.286218) (xy 71.500492 -400.793966) (xy 71.5001 -400.784777)
			(xy 71.493574 -400.767592) (xy 71.487792 -400.760438) (xy 71.465934 -400.734768) (xy 71.427846 -400.679134)
			(xy 71.396695 -400.619338) (xy 71.372931 -400.556242) (xy 71.356896 -400.490754) (xy 71.348819 -400.423816)
			(xy 71.348819 -400.356393) (xy 71.356894 -400.289455) (xy 71.372928 -400.223967) (xy 71.396692 -400.16087)
			(xy 71.427841 -400.101074) (xy 71.465929 -400.045439) (xy 71.487792 -400.019774) (xy 71.493581 -400.012623)
			(xy 71.500101 -399.995437) (xy 71.500492 -399.986246) (xy 71.500492 -399.828766) (xy 71.500997 -399.818643)
			(xy 71.508727 -399.79993) (xy 71.523007 -399.785577) (xy 71.54168 -399.77775) (xy 71.5518 -399.777204)
			(xy 72.26808 -399.777204) (xy 72.278233 -399.777638) (xy 72.296986 -399.785428) (xy 72.31131 -399.799821)
			(xy 72.31901 -399.818611) (xy 72.319388 -399.828766) (xy 72.319388 -399.986246) (xy 72.319827 -399.99543)
			(xy 72.326321 -400.012615) (xy 72.332088 -400.019774) (xy 72.353958 -400.045434) (xy 72.392048 -400.101069)
			(xy 72.423199 -400.160866) (xy 72.446963 -400.223963) (xy 72.462999 -400.289453) (xy 72.471074 -400.356392)
			(xy 72.471074 -400.423817) (xy 72.462997 -400.490756) (xy 72.44696 -400.556245) (xy 72.423195 -400.619342)
			(xy 72.392043 -400.679139) (xy 72.353953 -400.734773) (xy 72.332088 -400.760438) (xy 72.326291 -400.767583)
			(xy 72.319777 -400.784774) (xy 72.319388 -400.793966) (xy 72.319388 -401.286218) (xy 72.319792 -401.295406)
			(xy 72.32631 -401.31259) (xy 72.332088 -401.319746) (xy 72.353931 -401.345429) (xy 72.392021 -401.401061)
			(xy 72.423173 -401.460854) (xy 72.446939 -401.523949) (xy 72.462977 -401.589436) (xy 72.471054 -401.656372)
			(xy 72.471056 -401.723795) (xy 72.462982 -401.790732) (xy 72.446949 -401.85622) (xy 72.423187 -401.919316)
			(xy 72.392038 -401.979111) (xy 72.353951 -402.034745) (xy 72.332088 -402.06041) (xy 72.326303 -402.067564)
			(xy 72.319782 -402.084748) (xy 72.319388 -402.093938) (xy 72.319388 -402.251418) (xy 72.318889 -402.261542)
			(xy 72.311161 -402.280259) (xy 72.296879 -402.294614) (xy 72.278202 -402.302437) (xy 72.26808 -402.30298)
			(xy 71.5518 -402.30298) (xy 71.541643 -402.302578) (xy 71.522887 -402.294779) (xy 71.508563 -402.280376)
			(xy 71.500867 -402.261577) (xy 71.500492 -402.251418) (xy 71.500492 -402.093938) (xy 71.500065 -402.084753)
			(xy 71.493563 -402.067568) (xy 71.487792 -402.06041) (xy 71.465907 -402.034762) (xy 71.427819 -401.979125)
			(xy 71.39667 -401.919326) (xy 71.372907 -401.856227) (xy 71.356874 -401.790736) (xy 71.3488 -401.723796)
			(xy 66.525648 -401.723796) (xy 66.525648 -402.823818) (xy 73.54894 -402.823818) (xy 73.548944 -402.75651)
			(xy 73.556993 -402.689684) (xy 73.572971 -402.624299) (xy 73.596649 -402.561293) (xy 73.627687 -402.501568)
			(xy 73.665642 -402.44598) (xy 73.687432 -402.420328) (xy 73.693246 -402.413195) (xy 73.699749 -402.395995)
			(xy 73.700132 -402.3868) (xy 73.700132 -401.893532) (xy 73.699699 -401.884347) (xy 73.6932 -401.867163)
			(xy 73.687432 -401.860004) (xy 73.665625 -401.834368) (xy 73.627677 -401.778779) (xy 73.596645 -401.719053)
			(xy 73.572974 -401.656047) (xy 73.557002 -401.590662) (xy 73.54896 -401.523838) (xy 73.548962 -401.456532)
			(xy 73.557008 -401.389708) (xy 73.572982 -401.324325) (xy 73.596657 -401.261319) (xy 73.627692 -401.201595)
			(xy 73.665643 -401.146008) (xy 73.687432 -401.120356) (xy 73.693234 -401.113215) (xy 73.699745 -401.096021)
			(xy 73.700132 -401.086828) (xy 73.700132 -400.92884) (xy 73.700555 -400.918685) (xy 73.708343 -400.899927)
			(xy 73.722741 -400.885601) (xy 73.741537 -400.877906) (xy 73.751694 -400.877532) (xy 74.467974 -400.877532)
			(xy 74.478098 -400.878047) (xy 74.496817 -400.885765) (xy 74.511174 -400.900043) (xy 74.518996 -400.918719)
			(xy 74.519536 -400.92884) (xy 74.519536 -401.086828) (xy 74.519947 -401.096015) (xy 74.526462 -401.113198)
			(xy 74.532236 -401.120356) (xy 74.554005 -401.146024) (xy 74.591956 -401.201608) (xy 74.622991 -401.261329)
			(xy 74.646666 -401.324331) (xy 74.662641 -401.389712) (xy 74.670687 -401.456533) (xy 74.670689 -401.523837)
			(xy 74.662647 -401.590659) (xy 74.646675 -401.65604) (xy 74.623004 -401.719044) (xy 74.620565 -401.723737)
			(xy 75.749095 -401.723737) (xy 75.749097 -401.65643) (xy 75.757144 -401.589605) (xy 75.773121 -401.524221)
			(xy 75.796798 -401.461215) (xy 75.827836 -401.401492) (xy 75.86579 -401.345906) (xy 75.88758 -401.320254)
			(xy 75.893376 -401.313108) (xy 75.899892 -401.295918) (xy 75.90028 -401.286726) (xy 75.90028 -400.793458)
			(xy 75.899895 -400.784268) (xy 75.893364 -400.767084) (xy 75.88758 -400.75993) (xy 75.865797 -400.734274)
			(xy 75.827845 -400.678689) (xy 75.79681 -400.618966) (xy 75.773135 -400.555962) (xy 75.75716 -400.49058)
			(xy 75.749115 -400.423757) (xy 75.749114 -400.356452) (xy 75.757158 -400.289629) (xy 75.773132 -400.224247)
			(xy 75.796806 -400.161242) (xy 75.827841 -400.101519) (xy 75.865791 -400.045934) (xy 75.88758 -400.020282)
			(xy 75.893364 -400.013128) (xy 75.899887 -399.995944) (xy 75.90028 -399.986754) (xy 75.90028 -399.828766)
			(xy 75.900637 -399.818587) (xy 75.908441 -399.799783) (xy 75.922847 -399.785398) (xy 75.941662 -399.777622)
			(xy 75.951842 -399.777204) (xy 76.668122 -399.777204) (xy 76.678277 -399.777714) (xy 76.69704 -399.78549)
			(xy 76.711404 -399.79985) (xy 76.719183 -399.818611) (xy 76.719684 -399.828766) (xy 76.719684 -399.986754)
			(xy 76.72012 -399.995938) (xy 76.726616 -400.013123) (xy 76.732384 -400.020282) (xy 76.754177 -400.04593)
			(xy 76.792124 -400.101517) (xy 76.823156 -400.161242) (xy 76.846827 -400.224247) (xy 76.862799 -400.289629)
			(xy 76.870842 -400.356452) (xy 76.870842 -400.423757) (xy 76.862798 -400.49058) (xy 76.846825 -400.555962)
			(xy 76.823152 -400.618967) (xy 76.792119 -400.678691) (xy 76.754171 -400.734278) (xy 76.732384 -400.75993)
			(xy 76.72659 -400.767077) (xy 76.720074 -400.784266) (xy 76.719684 -400.793458) (xy 76.719684 -401.286726)
			(xy 76.720085 -401.295914) (xy 76.726605 -401.313098) (xy 76.732384 -401.320254) (xy 76.754149 -401.345924)
			(xy 76.792097 -401.401509) (xy 76.82313 -401.46123) (xy 76.846803 -401.524232) (xy 76.862777 -401.589612)
			(xy 76.870823 -401.656432) (xy 76.870825 -401.723735) (xy 76.862783 -401.790556) (xy 76.846813 -401.855936)
			(xy 76.823144 -401.91894) (xy 76.792114 -401.978663) (xy 76.75417 -402.03425) (xy 76.732384 -402.059902)
			(xy 76.726602 -402.067058) (xy 76.720079 -402.08424) (xy 76.719684 -402.09343) (xy 76.719684 -402.251418)
			(xy 76.719182 -402.261574) (xy 76.711406 -402.28034) (xy 76.697043 -402.294704) (xy 76.678278 -402.302481)
			(xy 76.668122 -402.30298) (xy 75.951842 -402.30298) (xy 75.941675 -402.302502) (xy 75.922885 -402.294734)
			(xy 75.908499 -402.280365) (xy 75.90071 -402.261584) (xy 75.90028 -402.251418) (xy 75.90028 -402.09343)
			(xy 75.89986 -402.084244) (xy 75.893354 -402.067059) (xy 75.88758 -402.059902) (xy 75.865769 -402.034268)
			(xy 75.827819 -401.97868) (xy 75.796784 -401.918954) (xy 75.773111 -401.855947) (xy 75.757138 -401.790562)
			(xy 75.749095 -401.723737) (xy 74.620565 -401.723737) (xy 74.591971 -401.778767) (xy 74.554023 -401.834352)
			(xy 74.532236 -401.860004) (xy 74.526447 -401.867155) (xy 74.51993 -401.884341) (xy 74.519536 -401.893532)
			(xy 74.519536 -402.3868) (xy 74.519961 -402.395985) (xy 74.526466 -402.413169) (xy 74.532236 -402.420328)
			(xy 74.553977 -402.446019) (xy 74.591929 -402.501599) (xy 74.622966 -402.561317) (xy 74.646642 -402.624317)
			(xy 74.662619 -402.689694) (xy 74.670668 -402.756513) (xy 74.670672 -402.823815) (xy 74.670664 -402.823878)
			(xy 77.948708 -402.823878) (xy 77.948713 -402.75645) (xy 77.956794 -402.689508) (xy 77.972835 -402.624016)
			(xy 77.996606 -402.560917) (xy 78.027764 -402.501119) (xy 78.06586 -402.445485) (xy 78.087728 -402.41982)
			(xy 78.093545 -402.412689) (xy 78.100047 -402.395488) (xy 78.100428 -402.386292) (xy 78.100428 -401.89404)
			(xy 78.099992 -401.884856) (xy 78.093496 -401.867671) (xy 78.087728 -401.860512) (xy 78.065843 -401.834863)
			(xy 78.027753 -401.779227) (xy 77.996602 -401.719429) (xy 77.972838 -401.65633) (xy 77.956803 -401.590838)
			(xy 77.948728 -401.523898) (xy 77.94873 -401.456472) (xy 77.956808 -401.389532) (xy 77.972847 -401.324041)
			(xy 77.996614 -401.260944) (xy 78.027769 -401.201147) (xy 78.065862 -401.145513) (xy 78.087728 -401.119848)
			(xy 78.093533 -401.112709) (xy 78.100042 -401.095514) (xy 78.100428 -401.08632) (xy 78.100428 -400.92884)
			(xy 78.10085 -400.918717) (xy 78.10859 -400.900009) (xy 78.122905 -400.885692) (xy 78.141613 -400.87795)
			(xy 78.151736 -400.877532) (xy 78.868016 -400.877532) (xy 78.878144 -400.877903) (xy 78.896854 -400.885663)
			(xy 78.911169 -400.899993) (xy 78.918908 -400.918712) (xy 78.919324 -400.92884) (xy 78.919324 -401.08632)
			(xy 78.919719 -401.095509) (xy 78.926243 -401.112693) (xy 78.932024 -401.119848) (xy 78.953867 -401.14553)
			(xy 78.991955 -401.201163) (xy 79.023105 -401.260957) (xy 79.04687 -401.324051) (xy 79.062906 -401.389538)
			(xy 79.070983 -401.456474) (xy 79.070985 -401.523896) (xy 79.062911 -401.590832) (xy 79.046879 -401.65632)
			(xy 79.023118 -401.719416) (xy 79.020837 -401.723796) (xy 80.148888 -401.723796) (xy 80.14889 -401.656371)
			(xy 80.156967 -401.589432) (xy 80.173004 -401.523942) (xy 80.19677 -401.460844) (xy 80.227922 -401.401047)
			(xy 80.266012 -401.345412) (xy 80.287876 -401.319746) (xy 80.293675 -401.312603) (xy 80.300189 -401.295411)
			(xy 80.300576 -401.286218) (xy 80.300576 -400.793966) (xy 80.300187 -400.784776) (xy 80.293659 -400.767592)
			(xy 80.287876 -400.760438) (xy 80.266019 -400.734767) (xy 80.227931 -400.679133) (xy 80.196782 -400.619337)
			(xy 80.173018 -400.556241) (xy 80.156983 -400.490753) (xy 80.148907 -400.423816) (xy 80.148907 -400.356393)
			(xy 80.156982 -400.289456) (xy 80.173016 -400.223967) (xy 80.196778 -400.160871) (xy 80.227927 -400.101075)
			(xy 80.266013 -400.04544) (xy 80.287876 -400.019774) (xy 80.293663 -400.012622) (xy 80.300184 -399.995437)
			(xy 80.300576 -399.986246) (xy 80.300576 -399.828766) (xy 80.301 -399.818633) (xy 80.308745 -399.799904)
			(xy 80.323051 -399.785548) (xy 80.341753 -399.777736) (xy 80.351884 -399.777204) (xy 81.068164 -399.777204)
			(xy 81.078316 -399.777651) (xy 81.097069 -399.785436) (xy 81.111393 -399.799825) (xy 81.119094 -399.818612)
			(xy 81.119472 -399.828766) (xy 81.119472 -399.986246) (xy 81.119914 -399.99543) (xy 81.126406 -400.012614)
			(xy 81.132172 -400.019774) (xy 81.154043 -400.045434) (xy 81.192133 -400.101069) (xy 81.223285 -400.160865)
			(xy 81.24705 -400.223963) (xy 81.263086 -400.289453) (xy 81.271162 -400.356392) (xy 81.271161 -400.423817)
			(xy 81.263085 -400.490756) (xy 81.247048 -400.556246) (xy 81.223282 -400.619343) (xy 81.192129 -400.679139)
			(xy 81.154037 -400.734773) (xy 81.132172 -400.760438) (xy 81.126373 -400.767581) (xy 81.11986 -400.784773)
			(xy 81.119472 -400.793966) (xy 81.119472 -401.286218) (xy 81.11988 -401.295405) (xy 81.126396 -401.312589)
			(xy 81.132172 -401.319746) (xy 81.154015 -401.345429) (xy 81.192107 -401.40106) (xy 81.22326 -401.460854)
			(xy 81.247026 -401.523948) (xy 81.263064 -401.589435) (xy 81.271142 -401.656372) (xy 81.271144 -401.723795)
			(xy 81.26307 -401.790732) (xy 81.247036 -401.85622) (xy 81.223273 -401.919316) (xy 81.192124 -401.979112)
			(xy 81.154036 -402.034745) (xy 81.132172 -402.06041) (xy 81.126385 -402.067562) (xy 81.119865 -402.084747)
			(xy 81.119472 -402.093938) (xy 81.119472 -402.251418) (xy 81.118989 -402.261544) (xy 81.111257 -402.280264)
			(xy 81.09697 -402.294619) (xy 81.078288 -402.30244) (xy 81.068164 -402.30298) (xy 80.351884 -402.30298)
			(xy 80.341726 -402.302591) (xy 80.32297 -402.294787) (xy 80.308646 -402.28038) (xy 80.30095 -402.261578)
			(xy 80.300576 -402.251418) (xy 80.300576 -402.093938) (xy 80.300153 -402.084752) (xy 80.293649 -402.067567)
			(xy 80.287876 -402.06041) (xy 80.265991 -402.034762) (xy 80.227905 -401.979125) (xy 80.196756 -401.919326)
			(xy 80.172994 -401.856227) (xy 80.156961 -401.790736) (xy 80.148888 -401.723796) (xy 79.020837 -401.723796)
			(xy 78.991971 -401.779212) (xy 78.953886 -401.834846) (xy 78.932024 -401.860512) (xy 78.926243 -401.867668)
			(xy 78.919718 -401.88485) (xy 78.919324 -401.89404) (xy 78.919324 -402.386292) (xy 78.919733 -402.395479)
			(xy 78.926247 -402.412664) (xy 78.932024 -402.41982) (xy 78.95384 -402.445525) (xy 78.991929 -402.501154)
			(xy 79.02308 -402.560945) (xy 79.046846 -402.624037) (xy 79.062884 -402.689521) (xy 79.070963 -402.756454)
			(xy 79.070968 -402.823818) (xy 82.349028 -402.823818) (xy 82.349032 -402.75651) (xy 82.357081 -402.689684)
			(xy 82.373058 -402.6243) (xy 82.396735 -402.561293) (xy 82.427773 -402.501568) (xy 82.465726 -402.44598)
			(xy 82.487516 -402.420328) (xy 82.493327 -402.413193) (xy 82.499833 -402.395995) (xy 82.500216 -402.3868)
			(xy 82.500216 -401.893532) (xy 82.499787 -401.884347) (xy 82.493286 -401.867163) (xy 82.487516 -401.860004)
			(xy 82.465709 -401.834368) (xy 82.427763 -401.778778) (xy 82.396731 -401.719052) (xy 82.373061 -401.656046)
			(xy 82.35709 -401.590662) (xy 82.349048 -401.523838) (xy 82.34905 -401.456532) (xy 82.357095 -401.389708)
			(xy 82.37307 -401.324325) (xy 82.396744 -401.26132) (xy 82.427778 -401.201596) (xy 82.465728 -401.146008)
			(xy 82.487516 -401.120356) (xy 82.493316 -401.113213) (xy 82.499828 -401.096021) (xy 82.500216 -401.086828)
			(xy 82.500216 -400.92884) (xy 82.500655 -400.918687) (xy 82.50844 -400.899932) (xy 82.522832 -400.885607)
			(xy 82.541623 -400.877908) (xy 82.551778 -400.877532) (xy 83.268058 -400.877532) (xy 83.278181 -400.878061)
			(xy 83.2969 -400.885773) (xy 83.311257 -400.900047) (xy 83.319079 -400.91872) (xy 83.31962 -400.92884)
			(xy 83.31962 -401.086828) (xy 83.320012 -401.096017) (xy 83.326538 -401.113202) (xy 83.33232 -401.120356)
			(xy 83.354089 -401.146024) (xy 83.392041 -401.201607) (xy 83.423078 -401.261328) (xy 83.446753 -401.324331)
			(xy 83.462729 -401.389711) (xy 83.470775 -401.456533) (xy 83.470777 -401.523837) (xy 83.462734 -401.590659)
			(xy 83.446762 -401.656041) (xy 83.42309 -401.719044) (xy 83.420621 -401.723796) (xy 84.548678 -401.723796)
			(xy 84.54868 -401.656371) (xy 84.556758 -401.589432) (xy 84.572795 -401.523942) (xy 84.59656 -401.460845)
			(xy 84.627711 -401.401047) (xy 84.6658 -401.345412) (xy 84.687664 -401.319746) (xy 84.693474 -401.312611)
			(xy 84.699979 -401.295412) (xy 84.700364 -401.286218) (xy 84.700364 -400.793966) (xy 84.699956 -400.784779)
			(xy 84.693439 -400.767595) (xy 84.687664 -400.760438) (xy 84.665807 -400.734767) (xy 84.627721 -400.679133)
			(xy 84.596572 -400.619337) (xy 84.572809 -400.556241) (xy 84.556774 -400.490753) (xy 84.548698 -400.423816)
			(xy 84.548698 -400.356393) (xy 84.556772 -400.289456) (xy 84.572806 -400.223968) (xy 84.596568 -400.160871)
			(xy 84.627716 -400.101075) (xy 84.665802 -400.04544) (xy 84.687664 -400.019774) (xy 84.693462 -400.01263)
			(xy 84.699974 -399.995438) (xy 84.700364 -399.986246) (xy 84.700364 -399.828766) (xy 84.700799 -399.818634)
			(xy 84.708543 -399.799908) (xy 84.722845 -399.785552) (xy 84.741542 -399.777738) (xy 84.751672 -399.777204)
			(xy 85.467952 -399.777204) (xy 85.478104 -399.777661) (xy 85.496856 -399.785442) (xy 85.511181 -399.799828)
			(xy 85.518881 -399.818613) (xy 85.51926 -399.828766) (xy 85.51926 -399.986246) (xy 85.519705 -399.995429)
			(xy 85.526196 -400.012613) (xy 85.53196 -400.019774) (xy 85.553831 -400.045434) (xy 85.591922 -400.101068)
			(xy 85.623075 -400.160865) (xy 85.646841 -400.223962) (xy 85.662877 -400.289453) (xy 85.670953 -400.356392)
			(xy 85.670952 -400.423817) (xy 85.662875 -400.490756) (xy 85.646838 -400.556246) (xy 85.623071 -400.619344)
			(xy 85.591918 -400.67914) (xy 85.553826 -400.734773) (xy 85.53196 -400.760438) (xy 85.52616 -400.76758)
			(xy 85.519648 -400.784773) (xy 85.51926 -400.793966) (xy 85.51926 -401.286218) (xy 85.51967 -401.295405)
			(xy 85.526185 -401.312589) (xy 85.53196 -401.319746) (xy 85.553804 -401.345428) (xy 85.591896 -401.40106)
			(xy 85.62305 -401.460853) (xy 85.646817 -401.523948) (xy 85.662855 -401.589435) (xy 85.670933 -401.656372)
			(xy 85.670935 -401.723795) (xy 85.662861 -401.790732) (xy 85.646827 -401.856221) (xy 85.623063 -401.919317)
			(xy 85.591913 -401.979112) (xy 85.553824 -402.034745) (xy 85.53196 -402.06041) (xy 85.526172 -402.067561)
			(xy 85.519653 -402.084747) (xy 85.51926 -402.093938) (xy 85.51926 -402.251418) (xy 85.518788 -402.261546)
			(xy 85.511055 -402.280268) (xy 85.496764 -402.294623) (xy 85.478078 -402.302442) (xy 85.467952 -402.30298)
			(xy 84.751672 -402.30298) (xy 84.741514 -402.302601) (xy 84.722757 -402.294792) (xy 84.708434 -402.280383)
			(xy 84.700738 -402.261579) (xy 84.700364 -402.251418) (xy 84.700364 -402.093938) (xy 84.699921 -402.084755)
			(xy 84.693429 -402.067571) (xy 84.687664 -402.06041) (xy 84.66578 -402.034762) (xy 84.627694 -401.979124)
			(xy 84.596546 -401.919325) (xy 84.572785 -401.856226) (xy 84.556752 -401.790735) (xy 84.548678 -401.723796)
			(xy 83.420621 -401.723796) (xy 83.392057 -401.778767) (xy 83.354108 -401.834352) (xy 83.33232 -401.860004)
			(xy 83.326542 -401.867162) (xy 83.320015 -401.884343) (xy 83.31962 -401.893532) (xy 83.31962 -402.3868)
			(xy 83.320026 -402.395988) (xy 83.326542 -402.413172) (xy 83.33232 -402.420328) (xy 83.354062 -402.446018)
			(xy 83.392015 -402.501598) (xy 83.423052 -402.561316) (xy 83.44673 -402.624316) (xy 83.462707 -402.689694)
			(xy 83.470756 -402.756513) (xy 83.47076 -402.823815) (xy 83.470752 -402.823878) (xy 86.748796 -402.823878)
			(xy 86.748801 -402.75645) (xy 86.756882 -402.689508) (xy 86.772922 -402.624016) (xy 86.796693 -402.560918)
			(xy 86.82785 -402.50112) (xy 86.865945 -402.445485) (xy 86.887812 -402.41982) (xy 86.893626 -402.412687)
			(xy 86.90013 -402.395487) (xy 86.900512 -402.386292) (xy 86.900512 -401.89404) (xy 86.90008 -401.884855)
			(xy 86.893581 -401.867671) (xy 86.887812 -401.860512) (xy 86.865928 -401.834863) (xy 86.827839 -401.779227)
			(xy 86.796689 -401.719428) (xy 86.772925 -401.656329) (xy 86.756891 -401.590838) (xy 86.748816 -401.523898)
			(xy 86.748818 -401.456472) (xy 86.756896 -401.389532) (xy 86.772934 -401.324042) (xy 86.796701 -401.260944)
			(xy 86.827855 -401.201148) (xy 86.865946 -401.145513) (xy 86.887812 -401.119848) (xy 86.893615 -401.112707)
			(xy 86.900125 -401.095513) (xy 86.900512 -401.08632) (xy 86.900512 -400.92884) (xy 86.900949 -400.918719)
			(xy 86.908686 -400.900014) (xy 86.922997 -400.885698) (xy 86.941699 -400.877953) (xy 86.95182 -400.877532)
			(xy 87.6681 -400.877532) (xy 87.678226 -400.877917) (xy 87.696936 -400.885671) (xy 87.711252 -400.899997)
			(xy 87.718991 -400.918713) (xy 87.719408 -400.92884) (xy 87.719408 -401.08632) (xy 87.719807 -401.095508)
			(xy 87.726328 -401.112693) (xy 87.732108 -401.119848) (xy 87.753952 -401.14553) (xy 87.792041 -401.201162)
			(xy 87.823192 -401.260956) (xy 87.846957 -401.324051) (xy 87.862994 -401.389538) (xy 87.871071 -401.456474)
			(xy 87.871073 -401.523896) (xy 87.862999 -401.590833) (xy 87.846966 -401.656321) (xy 87.823204 -401.719417)
			(xy 87.820954 -401.723737) (xy 115.349237 -401.723737) (xy 115.349239 -401.65643) (xy 115.357285 -401.589607)
			(xy 115.373259 -401.524224) (xy 115.396933 -401.461219) (xy 115.427967 -401.401494) (xy 115.465916 -401.345907)
			(xy 115.487704 -401.320254) (xy 115.493503 -401.313111) (xy 115.500016 -401.295919) (xy 115.500404 -401.286726)
			(xy 115.500404 -400.793458) (xy 115.500013 -400.784269) (xy 115.493486 -400.767085) (xy 115.487704 -400.75993)
			(xy 115.465923 -400.734273) (xy 115.427977 -400.678686) (xy 115.396945 -400.618963) (xy 115.373273 -400.555959)
			(xy 115.357301 -400.490578) (xy 115.349257 -400.423756) (xy 115.349256 -400.356453) (xy 115.357299 -400.289631)
			(xy 115.373271 -400.22425) (xy 115.396941 -400.161245) (xy 115.427972 -400.101522) (xy 115.465918 -400.045935)
			(xy 115.487704 -400.020282) (xy 115.493491 -400.01313) (xy 115.500011 -399.995945) (xy 115.500404 -399.986754)
			(xy 115.500404 -399.828766) (xy 115.500905 -399.81861) (xy 115.508684 -399.799847) (xy 115.523047 -399.785484)
			(xy 115.54181 -399.777705) (xy 115.551966 -399.777204) (xy 116.268246 -399.777204) (xy 116.278403 -399.777695)
			(xy 116.297166 -399.785478) (xy 116.311529 -399.799844) (xy 116.319307 -399.818609) (xy 116.319808 -399.828766)
			(xy 116.319808 -399.986754) (xy 116.320238 -399.995939) (xy 116.326738 -400.013124) (xy 116.332508 -400.020282)
			(xy 116.354303 -400.045929) (xy 116.392255 -400.101515) (xy 116.423291 -400.161238) (xy 116.446966 -400.224244)
			(xy 116.46294 -400.289627) (xy 116.470985 -400.356451) (xy 116.470984 -400.423758) (xy 116.462939 -400.490582)
			(xy 116.446963 -400.555965) (xy 116.423288 -400.61897) (xy 116.392251 -400.678693) (xy 116.354298 -400.734279)
			(xy 116.332508 -400.75993) (xy 116.326717 -400.767079) (xy 116.320199 -400.784267) (xy 116.319808 -400.793458)
			(xy 116.319808 -401.286726) (xy 116.320204 -401.295915) (xy 116.326727 -401.313099) (xy 116.332508 -401.320254)
			(xy 116.354276 -401.345923) (xy 116.392229 -401.401506) (xy 116.423266 -401.461227) (xy 116.446942 -401.524229)
			(xy 116.462918 -401.58961) (xy 116.470965 -401.656431) (xy 116.470967 -401.723736) (xy 116.462924 -401.790558)
			(xy 116.446952 -401.855939) (xy 116.423279 -401.918943) (xy 116.392246 -401.978666) (xy 116.354296 -402.034251)
			(xy 116.332508 -402.059902) (xy 116.326729 -402.06706) (xy 116.320204 -402.084241) (xy 116.319808 -402.09343)
			(xy 116.319808 -402.251418) (xy 116.319283 -402.261571) (xy 116.311511 -402.280332) (xy 116.297156 -402.294695)
			(xy 116.278399 -402.302477) (xy 116.268246 -402.30298) (xy 115.551966 -402.30298) (xy 115.541808 -402.302495)
			(xy 115.523042 -402.294713) (xy 115.508678 -402.280345) (xy 115.500902 -402.261576) (xy 115.500404 -402.251418)
			(xy 115.500404 -402.09343) (xy 115.499978 -402.084244) (xy 115.493475 -402.06706) (xy 115.487704 -402.059902)
			(xy 115.465896 -402.034267) (xy 115.42795 -401.978677) (xy 115.396919 -401.918951) (xy 115.373249 -401.855944)
			(xy 115.357279 -401.79056) (xy 115.349237 -401.723737) (xy 87.820954 -401.723737) (xy 87.792056 -401.779212)
			(xy 87.75397 -401.834847) (xy 87.732108 -401.860512) (xy 87.726325 -401.867667) (xy 87.719802 -401.88485)
			(xy 87.719408 -401.89404) (xy 87.719408 -402.386292) (xy 87.71982 -402.395479) (xy 87.726332 -402.412663)
			(xy 87.732108 -402.41982) (xy 87.753925 -402.445524) (xy 87.792014 -402.501153) (xy 87.823166 -402.560944)
			(xy 87.846933 -402.624036) (xy 87.862972 -402.68952) (xy 87.871051 -402.756454) (xy 87.871055 -402.823874)
			(xy 87.871055 -402.823878) (xy 117.548826 -402.823878) (xy 117.548831 -402.75645) (xy 117.556912 -402.689507)
			(xy 117.572954 -402.624015) (xy 117.596726 -402.560916) (xy 117.627885 -402.501119) (xy 117.665983 -402.445484)
			(xy 117.687852 -402.41982) (xy 117.693671 -402.412691) (xy 117.700171 -402.395488) (xy 117.700552 -402.386292)
			(xy 117.700552 -401.89404) (xy 117.700111 -401.884856) (xy 117.693618 -401.867672) (xy 117.687852 -401.860512)
			(xy 117.665967 -401.834864) (xy 117.627875 -401.779228) (xy 117.596722 -401.71943) (xy 117.572957 -401.656331)
			(xy 117.556921 -401.590839) (xy 117.548846 -401.523898) (xy 117.548848 -401.456472) (xy 117.556927 -401.389531)
			(xy 117.572966 -401.32404) (xy 117.596735 -401.260943) (xy 117.627891 -401.201146) (xy 117.665985 -401.145512)
			(xy 117.687852 -401.119848) (xy 117.69366 -401.112711) (xy 117.700166 -401.095514) (xy 117.700552 -401.08632)
			(xy 117.700552 -400.92884) (xy 117.701117 -400.91874) (xy 117.708832 -400.900072) (xy 117.723105 -400.885777)
			(xy 117.741761 -400.878033) (xy 117.75186 -400.877532) (xy 118.46814 -400.877532) (xy 118.478255 -400.877953)
			(xy 118.49694 -400.88571) (xy 118.511235 -400.900027) (xy 118.518963 -400.918724) (xy 118.519448 -400.92884)
			(xy 118.519448 -401.08632) (xy 118.51986 -401.095507) (xy 118.526374 -401.11269) (xy 118.532148 -401.119848)
			(xy 118.553994 -401.145529) (xy 118.592087 -401.20116) (xy 118.623241 -401.260953) (xy 118.647009 -401.324048)
			(xy 118.663047 -401.389536) (xy 118.671126 -401.456473) (xy 118.671127 -401.523897) (xy 118.663053 -401.590834)
			(xy 118.647018 -401.656323) (xy 118.623254 -401.719419) (xy 118.620974 -401.723796) (xy 119.749006 -401.723796)
			(xy 119.749008 -401.656371) (xy 119.757086 -401.589431) (xy 119.773123 -401.523941) (xy 119.79689 -401.460843)
			(xy 119.828043 -401.401046) (xy 119.866135 -401.345411) (xy 119.888 -401.319746) (xy 119.893802 -401.312605)
			(xy 119.900313 -401.295411) (xy 119.9007 -401.286218) (xy 119.9007 -400.793966) (xy 119.900306 -400.784777)
			(xy 119.893781 -400.767593) (xy 119.888 -400.760438) (xy 119.866142 -400.734768) (xy 119.828053 -400.679134)
			(xy 119.796902 -400.619339) (xy 119.773138 -400.556242) (xy 119.757102 -400.490754) (xy 119.749025 -400.423816)
			(xy 119.749025 -400.356393) (xy 119.7571 -400.289455) (xy 119.773135 -400.223966) (xy 119.796898 -400.16087)
			(xy 119.828048 -400.101074) (xy 119.866136 -400.045439) (xy 119.888 -400.019774) (xy 119.89379 -400.012624)
			(xy 119.900309 -399.995437) (xy 119.9007 -399.986246) (xy 119.9007 -399.828766) (xy 119.901197 -399.818642)
			(xy 119.908929 -399.799928) (xy 119.923211 -399.785574) (xy 119.941887 -399.777749) (xy 119.952008 -399.777204)
			(xy 120.668288 -399.777204) (xy 120.67841 -399.777626) (xy 120.697114 -399.785371) (xy 120.711429 -399.799686)
			(xy 120.719174 -399.81839) (xy 120.719596 -399.828512) (xy 120.719596 -399.986246) (xy 120.720033 -399.99543)
			(xy 120.726528 -400.012615) (xy 120.732296 -400.019774) (xy 120.754166 -400.045434) (xy 120.792255 -400.101069)
			(xy 120.823405 -400.160866) (xy 120.847169 -400.223964) (xy 120.863205 -400.289454) (xy 120.87128 -400.356392)
			(xy 120.87128 -400.423817) (xy 120.863203 -400.490755) (xy 120.847167 -400.556245) (xy 120.823402 -400.619342)
			(xy 120.79225 -400.679138) (xy 120.75416 -400.734773) (xy 120.732296 -400.760438) (xy 120.7265 -400.767584)
			(xy 120.719985 -400.784774) (xy 120.719596 -400.793966) (xy 120.719596 -401.286218) (xy 120.719998 -401.295406)
			(xy 120.726517 -401.31259) (xy 120.732296 -401.319746) (xy 120.754138 -401.345429) (xy 120.792228 -401.401061)
			(xy 120.82338 -401.460855) (xy 120.847146 -401.523949) (xy 120.863183 -401.589436) (xy 120.87126 -401.656372)
			(xy 120.871262 -401.723794) (xy 120.863189 -401.790731) (xy 120.847155 -401.856219) (xy 120.823394 -401.919315)
			(xy 120.792245 -401.979111) (xy 120.754159 -402.034745) (xy 120.732296 -402.06041) (xy 120.726512 -402.067564)
			(xy 120.71999 -402.084748) (xy 120.719596 -402.093938) (xy 120.719596 -402.251418) (xy 120.719089 -402.261541)
			(xy 120.711362 -402.280256) (xy 120.697083 -402.294611) (xy 120.678409 -402.302436) (xy 120.668288 -402.30298)
			(xy 119.952008 -402.30298) (xy 119.941884 -402.302577) (xy 119.923176 -402.294828) (xy 119.908861 -402.280507)
			(xy 119.901119 -402.261797) (xy 119.9007 -402.251672) (xy 119.9007 -402.093938) (xy 119.900272 -402.084753)
			(xy 119.893771 -402.067568) (xy 119.888 -402.06041) (xy 119.866114 -402.034763) (xy 119.828026 -401.979126)
			(xy 119.796877 -401.919327) (xy 119.773114 -401.856228) (xy 119.75708 -401.790736) (xy 119.749006 -401.723796)
			(xy 118.620974 -401.723796) (xy 118.592102 -401.779215) (xy 118.554013 -401.834848) (xy 118.532148 -401.860512)
			(xy 118.526357 -401.867661) (xy 118.519841 -401.884849) (xy 118.519448 -401.89404) (xy 118.519448 -402.386292)
			(xy 118.519874 -402.395477) (xy 118.526378 -402.412661) (xy 118.532148 -402.41982) (xy 118.553967 -402.445523)
			(xy 118.59206 -402.501151) (xy 118.623216 -402.560942) (xy 118.646985 -402.624034) (xy 118.663025 -402.689519)
			(xy 118.671106 -402.756454) (xy 118.67111 -402.823818) (xy 121.949146 -402.823818) (xy 121.94915 -402.756509)
			(xy 121.957199 -402.689684) (xy 121.973177 -402.624299) (xy 121.996856 -402.561292) (xy 122.027895 -402.501567)
			(xy 122.065849 -402.44598) (xy 122.08764 -402.420328) (xy 122.093455 -402.413196) (xy 122.099958 -402.395995)
			(xy 122.10034 -402.3868) (xy 122.10034 -401.893532) (xy 122.099905 -401.884348) (xy 122.093408 -401.867164)
			(xy 122.08764 -401.860004) (xy 122.065832 -401.834368) (xy 122.027884 -401.778779) (xy 121.996852 -401.719054)
			(xy 121.97318 -401.656047) (xy 121.957208 -401.590663) (xy 121.949166 -401.523838) (xy 121.949168 -401.456532)
			(xy 121.957214 -401.389708) (xy 121.973189 -401.324324) (xy 121.996864 -401.261319) (xy 122.0279 -401.201595)
			(xy 122.065851 -401.146008) (xy 122.08764 -401.120356) (xy 122.093443 -401.113215) (xy 122.099953 -401.096021)
			(xy 122.10034 -401.086828) (xy 122.10034 -400.92884) (xy 122.10075 -400.918715) (xy 122.108492 -400.900005)
			(xy 122.122812 -400.885688) (xy 122.141523 -400.877948) (xy 122.151648 -400.877532) (xy 122.868182 -400.877532)
			(xy 122.878307 -400.878041) (xy 122.897026 -400.885761) (xy 122.911383 -400.900041) (xy 122.919204 -400.918718)
			(xy 122.919744 -400.92884) (xy 122.919744 -401.086828) (xy 122.920153 -401.096015) (xy 122.926669 -401.113199)
			(xy 122.932444 -401.120356) (xy 122.954212 -401.146024) (xy 122.992163 -401.201608) (xy 123.023198 -401.261329)
			(xy 123.046873 -401.324332) (xy 123.062848 -401.389712) (xy 123.070894 -401.456533) (xy 123.070895 -401.523837)
			(xy 123.062853 -401.590658) (xy 123.046882 -401.65604) (xy 123.02321 -401.719043) (xy 123.020771 -401.723737)
			(xy 124.149301 -401.723737) (xy 124.149303 -401.65643) (xy 124.15735 -401.589605) (xy 124.173327 -401.524221)
			(xy 124.197004 -401.461215) (xy 124.228043 -401.401491) (xy 124.265997 -401.345906) (xy 124.287788 -401.320254)
			(xy 124.293585 -401.313109) (xy 124.3001 -401.295918) (xy 124.300488 -401.286726) (xy 124.300488 -400.793458)
			(xy 124.300101 -400.784268) (xy 124.293572 -400.767084) (xy 124.287788 -400.75993) (xy 124.266005 -400.734274)
			(xy 124.228052 -400.678689) (xy 124.197016 -400.618966) (xy 124.173341 -400.555962) (xy 124.157366 -400.49058)
			(xy 124.149321 -400.423757) (xy 124.14932 -400.356452) (xy 124.157365 -400.289629) (xy 124.173338 -400.224246)
			(xy 124.197013 -400.161242) (xy 124.228048 -400.101519) (xy 124.265999 -400.045933) (xy 124.287788 -400.020282)
			(xy 124.293573 -400.013129) (xy 124.300095 -399.995944) (xy 124.300488 -399.986754) (xy 124.300488 -399.828766)
			(xy 124.300837 -399.818586) (xy 124.308643 -399.799781) (xy 124.323052 -399.785395) (xy 124.341869 -399.777621)
			(xy 124.35205 -399.777204) (xy 125.06833 -399.777204) (xy 125.078486 -399.777708) (xy 125.097249 -399.785486)
			(xy 125.111612 -399.799848) (xy 125.119391 -399.818611) (xy 125.119892 -399.828766) (xy 125.119892 -399.986754)
			(xy 125.120326 -399.995939) (xy 125.126823 -400.013123) (xy 125.132592 -400.020282) (xy 125.154385 -400.04593)
			(xy 125.192331 -400.101518) (xy 125.223363 -400.161242) (xy 125.247034 -400.224247) (xy 125.263005 -400.289629)
			(xy 125.271049 -400.356452) (xy 125.271048 -400.423757) (xy 125.263004 -400.490579) (xy 125.247031 -400.555962)
			(xy 125.223359 -400.618966) (xy 125.192327 -400.67869) (xy 125.154379 -400.734277) (xy 125.132592 -400.75993)
			(xy 125.126799 -400.767078) (xy 125.120283 -400.784266) (xy 125.119892 -400.793458) (xy 125.119892 -401.286726)
			(xy 125.120291 -401.295914) (xy 125.126813 -401.313099) (xy 125.132592 -401.320254) (xy 125.154357 -401.345924)
			(xy 125.192305 -401.401509) (xy 125.223337 -401.46123) (xy 125.24701 -401.524232) (xy 125.262983 -401.589612)
			(xy 125.271029 -401.656432) (xy 125.271031 -401.723735) (xy 125.262989 -401.790555) (xy 125.24702 -401.855936)
			(xy 125.223351 -401.918939) (xy 125.192322 -401.978663) (xy 125.154377 -402.034249) (xy 125.132592 -402.059902)
			(xy 125.126811 -402.067058) (xy 125.120287 -402.08424) (xy 125.119892 -402.09343) (xy 125.119892 -402.251418)
			(xy 125.119382 -402.261573) (xy 125.111608 -402.280337) (xy 125.097247 -402.294701) (xy 125.078485 -402.30248)
			(xy 125.06833 -402.30298) (xy 124.35205 -402.30298) (xy 124.341884 -402.302496) (xy 124.323094 -402.29473)
			(xy 124.308708 -402.280363) (xy 124.300918 -402.261584) (xy 124.300488 -402.251418) (xy 124.300488 -402.09343)
			(xy 124.300066 -402.084244) (xy 124.293561 -402.067059) (xy 124.287788 -402.059902) (xy 124.265977 -402.034268)
			(xy 124.228026 -401.97868) (xy 124.196991 -401.918955) (xy 124.173317 -401.855948) (xy 124.157344 -401.790563)
			(xy 124.149301 -401.723737) (xy 123.020771 -401.723737) (xy 122.992178 -401.778766) (xy 122.954231 -401.834352)
			(xy 122.932444 -401.860004) (xy 122.926656 -401.867155) (xy 122.920138 -401.884341) (xy 122.919744 -401.893532)
			(xy 122.919744 -402.3868) (xy 122.920167 -402.395986) (xy 122.926673 -402.413169) (xy 122.932444 -402.420328)
			(xy 122.954185 -402.446019) (xy 122.992136 -402.501599) (xy 123.023173 -402.561317) (xy 123.046849 -402.624317)
			(xy 123.062826 -402.689695) (xy 123.070874 -402.756513) (xy 123.070878 -402.823815) (xy 123.07087 -402.823878)
			(xy 126.348914 -402.823878) (xy 126.348919 -402.75645) (xy 126.357 -402.689508) (xy 126.373042 -402.624016)
			(xy 126.396813 -402.560916) (xy 126.427971 -402.501119) (xy 126.466068 -402.445485) (xy 126.487936 -402.41982)
			(xy 126.493754 -402.41269) (xy 126.500255 -402.395488) (xy 126.500636 -402.386292) (xy 126.500636 -401.89404)
			(xy 126.500198 -401.884856) (xy 126.493703 -401.867672) (xy 126.487936 -401.860512) (xy 126.466051 -401.834864)
			(xy 126.427961 -401.779227) (xy 126.396809 -401.719429) (xy 126.373044 -401.65633) (xy 126.357009 -401.590839)
			(xy 126.348934 -401.523898) (xy 126.348936 -401.456472) (xy 126.357014 -401.389532) (xy 126.373053 -401.324041)
			(xy 126.396821 -401.260943) (xy 126.427976 -401.201147) (xy 126.46607 -401.145513) (xy 126.487936 -401.119848)
			(xy 126.493742 -401.112709) (xy 126.50025 -401.095514) (xy 126.500636 -401.08632) (xy 126.500636 -400.92884)
			(xy 126.50105 -400.918716) (xy 126.508791 -400.900006) (xy 126.523109 -400.885689) (xy 126.54182 -400.877949)
			(xy 126.551944 -400.877532) (xy 127.268224 -400.877532) (xy 127.278352 -400.877897) (xy 127.297062 -400.885659)
			(xy 127.311377 -400.899991) (xy 127.319116 -400.918711) (xy 127.319532 -400.92884) (xy 127.319532 -401.08632)
			(xy 127.319948 -401.095506) (xy 127.326459 -401.11269) (xy 127.332232 -401.119848) (xy 127.354075 -401.14553)
			(xy 127.392162 -401.201163) (xy 127.423312 -401.260957) (xy 127.447076 -401.324052) (xy 127.463112 -401.389538)
			(xy 127.471189 -401.456474) (xy 127.471191 -401.523896) (xy 127.463117 -401.590832) (xy 127.447085 -401.65632)
			(xy 127.423324 -401.719415) (xy 127.421073 -401.723737) (xy 128.549092 -401.723737) (xy 128.549094 -401.65643)
			(xy 128.557141 -401.589605) (xy 128.573117 -401.524221) (xy 128.596794 -401.461216) (xy 128.627832 -401.401492)
			(xy 128.665786 -401.345906) (xy 128.687576 -401.320254) (xy 128.693372 -401.313108) (xy 128.699888 -401.295918)
			(xy 128.700276 -401.286726) (xy 128.700276 -400.793458) (xy 128.699891 -400.784268) (xy 128.69336 -400.767084)
			(xy 128.687576 -400.75993) (xy 128.665793 -400.734273) (xy 128.627842 -400.678688) (xy 128.596806 -400.618966)
			(xy 128.573131 -400.555962) (xy 128.557157 -400.49058) (xy 128.549112 -400.423757) (xy 128.549111 -400.356452)
			(xy 128.557155 -400.289629) (xy 128.573129 -400.224247) (xy 128.596802 -400.161242) (xy 128.627837 -400.101519)
			(xy 128.665788 -400.045934) (xy 128.687576 -400.020282) (xy 128.69336 -400.013128) (xy 128.699883 -399.995944)
			(xy 128.700276 -399.986754) (xy 128.700276 -399.828766) (xy 128.700637 -399.818587) (xy 128.70844 -399.799785)
			(xy 128.722845 -399.7854) (xy 128.741659 -399.777623) (xy 128.751838 -399.777204) (xy 129.468118 -399.777204)
			(xy 129.478273 -399.777718) (xy 129.497036 -399.785492) (xy 129.511399 -399.799851) (xy 129.519179 -399.818611)
			(xy 129.51968 -399.828766) (xy 129.51968 -399.986754) (xy 129.520117 -399.995938) (xy 129.526612 -400.013123)
			(xy 129.53238 -400.020282) (xy 129.554173 -400.045929) (xy 129.592121 -400.101517) (xy 129.623152 -400.161241)
			(xy 129.646824 -400.224247) (xy 129.662796 -400.289629) (xy 129.670839 -400.356452) (xy 129.670839 -400.423757)
			(xy 129.662794 -400.49058) (xy 129.646821 -400.555962) (xy 129.623149 -400.618967) (xy 129.592116 -400.678691)
			(xy 129.554168 -400.734278) (xy 129.53238 -400.75993) (xy 129.526586 -400.767077) (xy 129.52007 -400.784266)
			(xy 129.51968 -400.793458) (xy 129.51968 -401.286726) (xy 129.520082 -401.295914) (xy 129.526602 -401.313098)
			(xy 129.53238 -401.320254) (xy 129.554146 -401.345924) (xy 129.592094 -401.401508) (xy 129.623127 -401.46123)
			(xy 129.6468 -401.524232) (xy 129.662774 -401.589612) (xy 129.67082 -401.656432) (xy 129.670822 -401.723735)
			(xy 129.66278 -401.790556) (xy 129.64681 -401.855937) (xy 129.623141 -401.91894) (xy 129.592111 -401.978663)
			(xy 129.554166 -402.03425) (xy 129.53238 -402.059902) (xy 129.526598 -402.067057) (xy 129.520075 -402.08424)
			(xy 129.51968 -402.09343) (xy 129.51968 -402.251418) (xy 129.519182 -402.261575) (xy 129.511405 -402.280341)
			(xy 129.497041 -402.294705) (xy 129.478275 -402.302482) (xy 129.468118 -402.30298) (xy 128.751838 -402.30298)
			(xy 128.741671 -402.302505) (xy 128.722881 -402.294736) (xy 128.708495 -402.280366) (xy 128.700706 -402.261584)
			(xy 128.700276 -402.251418) (xy 128.700276 -402.09343) (xy 128.699857 -402.084244) (xy 128.69335 -402.067059)
			(xy 128.687576 -402.059902) (xy 128.665766 -402.034268) (xy 128.627815 -401.97868) (xy 128.596781 -401.918954)
			(xy 128.573108 -401.855947) (xy 128.557135 -401.790562) (xy 128.549092 -401.723737) (xy 127.421073 -401.723737)
			(xy 127.392178 -401.779211) (xy 127.354094 -401.834846) (xy 127.332232 -401.860512) (xy 127.32644 -401.86766)
			(xy 127.319924 -401.884849) (xy 127.319532 -401.89404) (xy 127.319532 -402.386292) (xy 127.319961 -402.395477)
			(xy 127.326463 -402.412661) (xy 127.332232 -402.41982) (xy 127.354048 -402.445525) (xy 127.392136 -402.501154)
			(xy 127.423287 -402.560945) (xy 127.447052 -402.624037) (xy 127.46309 -402.689521) (xy 127.471169 -402.756454)
			(xy 127.471174 -402.823818) (xy 130.749234 -402.823818) (xy 130.749238 -402.75651) (xy 130.757287 -402.689684)
			(xy 130.773265 -402.624299) (xy 130.796942 -402.561293) (xy 130.82798 -402.501568) (xy 130.865934 -402.44598)
			(xy 130.887724 -402.420328) (xy 130.893536 -402.413194) (xy 130.900041 -402.395995) (xy 130.900424 -402.3868)
			(xy 130.900424 -401.893532) (xy 130.899993 -401.884347) (xy 130.893493 -401.867163) (xy 130.887724 -401.860004)
			(xy 130.865917 -401.834368) (xy 130.82797 -401.778779) (xy 130.796938 -401.719053) (xy 130.773267 -401.656046)
			(xy 130.757296 -401.590662) (xy 130.749254 -401.523838) (xy 130.749256 -401.456532) (xy 130.757301 -401.389708)
			(xy 130.773276 -401.324325) (xy 130.79695 -401.26132) (xy 130.827985 -401.201595) (xy 130.865935 -401.146008)
			(xy 130.887724 -401.120356) (xy 130.893525 -401.113214) (xy 130.900036 -401.096021) (xy 130.900424 -401.086828)
			(xy 130.900424 -400.92884) (xy 130.900855 -400.918686) (xy 130.908642 -400.899929) (xy 130.923036 -400.885604)
			(xy 130.94183 -400.877907) (xy 130.951986 -400.877532) (xy 131.668266 -400.877532) (xy 131.67839 -400.878054)
			(xy 131.697108 -400.88577) (xy 131.711465 -400.900045) (xy 131.719287 -400.918719) (xy 131.719828 -400.92884)
			(xy 131.719828 -401.086828) (xy 131.720218 -401.096017) (xy 131.726745 -401.113202) (xy 131.732528 -401.120356)
			(xy 131.754297 -401.146024) (xy 131.792249 -401.201607) (xy 131.823285 -401.261328) (xy 131.84696 -401.324331)
			(xy 131.862935 -401.389712) (xy 131.870981 -401.456533) (xy 131.870983 -401.523837) (xy 131.862941 -401.590659)
			(xy 131.846969 -401.65604) (xy 131.823297 -401.719044) (xy 131.792264 -401.778767) (xy 131.754315 -401.834352)
			(xy 131.732528 -401.860004) (xy 131.726738 -401.867154) (xy 131.720222 -401.884341) (xy 131.719828 -401.893532)
			(xy 131.719828 -402.3868) (xy 131.720232 -402.395988) (xy 131.726749 -402.413173) (xy 131.732528 -402.420328)
			(xy 131.75427 -402.446019) (xy 131.792222 -402.501599) (xy 131.823259 -402.561317) (xy 131.846936 -402.624316)
			(xy 131.862913 -402.689694) (xy 131.870962 -402.756513) (xy 131.870966 -402.823815) (xy 131.862926 -402.890635)
			(xy 131.846957 -402.956015) (xy 131.823289 -403.019017) (xy 131.792259 -403.078739) (xy 131.754314 -403.134324)
			(xy 131.732528 -403.159976) (xy 131.726708 -403.167104) (xy 131.720209 -403.184308) (xy 131.719828 -403.193504)
			(xy 131.719828 -403.351492) (xy 131.719372 -403.361642) (xy 131.711585 -403.380389) (xy 131.697199 -403.394712)
			(xy 131.678418 -403.402417) (xy 131.668266 -403.4028) (xy 130.951986 -403.4028) (xy 130.941863 -403.402286)
			(xy 130.92315 -403.394561) (xy 130.908795 -403.380284) (xy 130.90097 -403.361612) (xy 130.900424 -403.351492)
			(xy 130.900424 -403.193504) (xy 130.900007 -403.184318) (xy 130.893498 -403.167133) (xy 130.887724 -403.159976)
			(xy 130.86589 -403.134362) (xy 130.827943 -403.07877) (xy 130.796913 -403.019041) (xy 130.773243 -402.956032)
			(xy 130.757274 -402.890645) (xy 130.749234 -402.823818) (xy 127.471174 -402.823818) (xy 127.471174 -402.823874)
			(xy 127.463103 -402.890808) (xy 127.447074 -402.956294) (xy 127.423316 -403.019389) (xy 127.392173 -403.079184)
			(xy 127.354092 -403.134818) (xy 127.332232 -403.160484) (xy 127.326409 -403.16761) (xy 127.319912 -403.184816)
			(xy 127.319532 -403.194012) (xy 127.319532 -403.351492) (xy 127.319009 -403.361596) (xy 127.31128 -403.380268)
			(xy 127.296995 -403.394562) (xy 127.278328 -403.402303) (xy 127.268224 -403.4028) (xy 126.551944 -403.4028)
			(xy 126.541824 -403.402348) (xy 126.523122 -403.394614) (xy 126.508806 -403.380308) (xy 126.501059 -403.361611)
			(xy 126.500636 -403.351492) (xy 126.500636 -403.194012) (xy 126.500212 -403.184826) (xy 126.493707 -403.167642)
			(xy 126.487936 -403.160484) (xy 126.466024 -403.134858) (xy 126.427934 -403.079219) (xy 126.396783 -403.019418)
			(xy 126.37302 -402.956315) (xy 126.356987 -402.890821) (xy 126.348914 -402.823878) (xy 123.07087 -402.823878)
			(xy 123.062839 -402.890634) (xy 123.04687 -402.956014) (xy 123.023202 -403.019017) (xy 122.992173 -403.078739)
			(xy 122.954229 -403.134324) (xy 122.932444 -403.159976) (xy 122.926626 -403.167106) (xy 122.920126 -403.184308)
			(xy 122.919744 -403.193504) (xy 122.919744 -403.351492) (xy 122.919209 -403.361595) (xy 122.911483 -403.380264)
			(xy 122.897201 -403.394558) (xy 122.878538 -403.402301) (xy 122.868436 -403.4028) (xy 122.151902 -403.4028)
			(xy 122.14178 -403.402273) (xy 122.123067 -403.394553) (xy 122.108712 -403.38028) (xy 122.100886 -403.361611)
			(xy 122.10034 -403.351492) (xy 122.10034 -403.193504) (xy 122.099919 -403.184318) (xy 122.093412 -403.167134)
			(xy 122.08764 -403.159976) (xy 122.065805 -403.134363) (xy 122.027857 -403.078771) (xy 121.996826 -403.019042)
			(xy 121.973156 -402.956032) (xy 121.957186 -402.890645) (xy 121.949146 -402.823818) (xy 118.67111 -402.823818)
			(xy 118.67111 -402.823874) (xy 118.663038 -402.89081) (xy 118.647006 -402.956297) (xy 118.623245 -403.019392)
			(xy 118.592097 -403.079187) (xy 118.554011 -403.13482) (xy 118.532148 -403.160484) (xy 118.526327 -403.167612)
			(xy 118.519828 -403.184816) (xy 118.519448 -403.194012) (xy 118.519448 -403.351492) (xy 118.51891 -403.361594)
			(xy 118.511183 -403.380263) (xy 118.496903 -403.394557) (xy 118.478242 -403.4023) (xy 118.46814 -403.4028)
			(xy 117.75186 -403.4028) (xy 117.741749 -403.402348) (xy 117.72307 -403.394597) (xy 117.708776 -403.38029)
			(xy 117.701043 -403.361604) (xy 117.700552 -403.351492) (xy 117.700552 -403.194012) (xy 117.700125 -403.184827)
			(xy 117.693622 -403.167643) (xy 117.687852 -403.160484) (xy 117.665939 -403.134859) (xy 117.627848 -403.07922)
			(xy 117.596697 -403.019418) (xy 117.572933 -402.956316) (xy 117.556899 -402.890822) (xy 117.548826 -402.823878)
			(xy 87.871055 -402.823878) (xy 87.862984 -402.890809) (xy 87.846954 -402.956295) (xy 87.823196 -403.01939)
			(xy 87.792051 -403.079185) (xy 87.753969 -403.134819) (xy 87.732108 -403.160484) (xy 87.726294 -403.167617)
			(xy 87.71979 -403.184817) (xy 87.719408 -403.194012) (xy 87.719408 -403.351492) (xy 87.718978 -403.361613)
			(xy 87.711234 -403.380315) (xy 87.696922 -403.394629) (xy 87.678221 -403.402376) (xy 87.6681 -403.4028)
			(xy 86.95182 -403.4028) (xy 86.941699 -403.402368) (xy 86.922996 -403.394626) (xy 86.908681 -403.380315)
			(xy 86.900935 -403.361613) (xy 86.900512 -403.351492) (xy 86.900512 -403.194012) (xy 86.900093 -403.184826)
			(xy 86.893585 -403.167642) (xy 86.887812 -403.160484) (xy 86.8659 -403.134858) (xy 86.827812 -403.079218)
			(xy 86.796663 -403.019417) (xy 86.772901 -402.956315) (xy 86.756869 -402.890821) (xy 86.748796 -402.823878)
			(xy 83.470752 -402.823878) (xy 83.46272 -402.890635) (xy 83.446751 -402.956015) (xy 83.423082 -403.019018)
			(xy 83.392052 -403.07874) (xy 83.354106 -403.134324) (xy 83.33232 -403.159976) (xy 83.326511 -403.167113)
			(xy 83.320003 -403.18431) (xy 83.31962 -403.193504) (xy 83.31962 -403.351492) (xy 83.319172 -403.361643)
			(xy 83.311383 -403.380391) (xy 83.296995 -403.394714) (xy 83.278211 -403.402418) (xy 83.268058 -403.4028)
			(xy 82.551778 -403.4028) (xy 82.541655 -403.402293) (xy 82.522941 -403.394565) (xy 82.508586 -403.380286)
			(xy 82.500761 -403.361613) (xy 82.500216 -403.351492) (xy 82.500216 -403.193504) (xy 82.4998 -403.184318)
			(xy 82.49329 -403.167133) (xy 82.487516 -403.159976) (xy 82.465682 -403.134362) (xy 82.427736 -403.07877)
			(xy 82.396706 -403.019041) (xy 82.373037 -402.956031) (xy 82.357068 -402.890645) (xy 82.349028 -402.823818)
			(xy 79.070968 -402.823818) (xy 79.070968 -402.823874) (xy 79.062897 -402.890808) (xy 79.046867 -402.956294)
			(xy 79.023109 -403.019389) (xy 78.991966 -403.079184) (xy 78.953884 -403.134818) (xy 78.932024 -403.160484)
			(xy 78.926212 -403.167618) (xy 78.919706 -403.184817) (xy 78.919324 -403.194012) (xy 78.919324 -403.351492)
			(xy 78.918809 -403.361597) (xy 78.911078 -403.380271) (xy 78.896791 -403.394565) (xy 78.878121 -403.402304)
			(xy 78.868016 -403.4028) (xy 78.151736 -403.4028) (xy 78.141616 -403.402354) (xy 78.122913 -403.394618)
			(xy 78.108598 -403.38031) (xy 78.100851 -403.361612) (xy 78.100428 -403.351492) (xy 78.100428 -403.194012)
			(xy 78.100006 -403.184826) (xy 78.0935 -403.167642) (xy 78.087728 -403.160484) (xy 78.065816 -403.134858)
			(xy 78.027727 -403.079219) (xy 77.996577 -403.019417) (xy 77.972814 -402.956315) (xy 77.956781 -402.890821)
			(xy 77.948708 -402.823878) (xy 74.670664 -402.823878) (xy 74.662632 -402.890635) (xy 74.646664 -402.956014)
			(xy 74.622995 -403.019017) (xy 74.591966 -403.078739) (xy 74.554022 -403.134324) (xy 74.532236 -403.159976)
			(xy 74.526417 -403.167105) (xy 74.519917 -403.184308) (xy 74.519536 -403.193504) (xy 74.519536 -403.351492)
			(xy 74.519073 -403.361641) (xy 74.511286 -403.380386) (xy 74.496903 -403.394709) (xy 74.478125 -403.402415)
			(xy 74.467974 -403.4028) (xy 73.751694 -403.4028) (xy 73.741572 -403.402279) (xy 73.722858 -403.394557)
			(xy 73.708504 -403.380282) (xy 73.700678 -403.361611) (xy 73.700132 -403.351492) (xy 73.700132 -403.193504)
			(xy 73.699713 -403.184318) (xy 73.693205 -403.167134) (xy 73.687432 -403.159976) (xy 73.665597 -403.134363)
			(xy 73.62765 -403.07877) (xy 73.59662 -403.019041) (xy 73.57295 -402.956032) (xy 73.55698 -402.890645)
			(xy 73.54894 -402.823818) (xy 66.525648 -402.823818) (xy 66.525648 -405.623707) (xy 71.348811 -405.623707)
			(xy 71.348811 -405.556283) (xy 71.356888 -405.489345) (xy 71.372924 -405.423856) (xy 71.396688 -405.360759)
			(xy 71.427839 -405.300962) (xy 71.465928 -405.245327) (xy 71.487792 -405.219662) (xy 71.493586 -405.212515)
			(xy 71.500103 -405.195326) (xy 71.500492 -405.186134) (xy 71.500492 -404.693882) (xy 71.500092 -404.684694)
			(xy 71.493571 -404.667509) (xy 71.487792 -404.660354) (xy 71.46595 -404.634671) (xy 71.427861 -404.579039)
			(xy 71.39671 -404.519245) (xy 71.372945 -404.45615) (xy 71.356908 -404.390664) (xy 71.348831 -404.323727)
			(xy 71.348829 -404.256306) (xy 71.356902 -404.189369) (xy 71.372935 -404.123881) (xy 71.396696 -404.060785)
			(xy 71.427844 -404.00099) (xy 71.46593 -403.945355) (xy 71.487792 -403.91969) (xy 71.493574 -403.912535)
			(xy 71.500098 -403.895352) (xy 71.500492 -403.886162) (xy 71.500492 -403.728682) (xy 71.50101 -403.71856)
			(xy 71.508735 -403.699847) (xy 71.523011 -403.685493) (xy 71.541681 -403.677666) (xy 71.5518 -403.67712)
			(xy 72.26808 -403.67712) (xy 72.278235 -403.677538) (xy 72.296991 -403.685331) (xy 72.311316 -403.699729)
			(xy 72.319013 -403.718525) (xy 72.319388 -403.728682) (xy 72.319388 -403.886162) (xy 72.319819 -403.895347)
			(xy 72.326319 -403.912531) (xy 72.332088 -403.91969) (xy 72.353974 -403.945337) (xy 72.392063 -404.000974)
			(xy 72.423213 -404.060773) (xy 72.446977 -404.123872) (xy 72.463011 -404.189363) (xy 72.471085 -404.256304)
			(xy 72.471083 -404.323729) (xy 72.463005 -404.390669) (xy 72.446967 -404.45616) (xy 72.4232 -404.519258)
			(xy 72.392046 -404.579054) (xy 72.353954 -404.634689) (xy 72.332088 -404.660354) (xy 72.326285 -404.667494)
			(xy 72.319774 -404.684689) (xy 72.319388 -404.693882) (xy 72.319388 -405.186134) (xy 72.319784 -405.195323)
			(xy 72.326308 -405.212507) (xy 72.332088 -405.219662) (xy 72.353946 -405.245332) (xy 72.392036 -405.300965)
			(xy 72.423188 -405.360761) (xy 72.446953 -405.423857) (xy 72.462989 -405.489346) (xy 72.471066 -405.556284)
			(xy 72.471066 -405.623707) (xy 72.462991 -405.690645) (xy 72.446956 -405.756134) (xy 72.423191 -405.819231)
			(xy 72.392041 -405.879027) (xy 72.353952 -405.934661) (xy 72.332088 -405.960326) (xy 72.326297 -405.967475)
			(xy 72.319779 -405.984663) (xy 72.319388 -405.993854) (xy 72.319388 -406.151334) (xy 72.318902 -406.161459)
			(xy 72.311168 -406.180176) (xy 72.296883 -406.19453) (xy 72.278203 -406.202353) (xy 72.26808 -406.202896)
			(xy 71.5518 -406.202896) (xy 71.541645 -406.202478) (xy 71.522892 -406.194682) (xy 71.508569 -406.180284)
			(xy 71.50087 -406.161491) (xy 71.500492 -406.151334) (xy 71.500492 -405.993854) (xy 71.500058 -405.984669)
			(xy 71.493561 -405.967485) (xy 71.487792 -405.960326) (xy 71.465922 -405.934665) (xy 71.427834 -405.87903)
			(xy 71.396684 -405.819233) (xy 71.372921 -405.756136) (xy 71.356886 -405.690646) (xy 71.348811 -405.623707)
			(xy 66.525648 -405.623707) (xy 66.525648 -406.72373) (xy 73.548951 -406.72373) (xy 73.548954 -406.656422)
			(xy 73.557001 -406.589598) (xy 73.572978 -406.524214) (xy 73.596654 -406.461208) (xy 73.62769 -406.401483)
			(xy 73.665642 -406.345896) (xy 73.687432 -406.320244) (xy 73.693239 -406.313106) (xy 73.699747 -406.29591)
			(xy 73.700132 -406.286716) (xy 73.700132 -405.793448) (xy 73.699691 -405.784264) (xy 73.693198 -405.76708)
			(xy 73.687432 -405.75992) (xy 73.66564 -405.734271) (xy 73.627692 -405.678684) (xy 73.596659 -405.61896)
			(xy 73.572987 -405.555955) (xy 73.557015 -405.490572) (xy 73.548971 -405.42375) (xy 73.548971 -405.356444)
			(xy 73.557016 -405.289622) (xy 73.572989 -405.224239) (xy 73.596662 -405.161235) (xy 73.627695 -405.101511)
			(xy 73.665644 -405.045924) (xy 73.687432 -405.020272) (xy 73.693227 -405.013126) (xy 73.699742 -404.995936)
			(xy 73.700132 -404.986744) (xy 73.700132 -404.828756) (xy 73.700486 -404.818595) (xy 73.708302 -404.799836)
			(xy 73.72272 -404.785513) (xy 73.74153 -404.77782) (xy 73.751694 -404.777448) (xy 74.467974 -404.777448)
			(xy 74.4781 -404.777948) (xy 74.496822 -404.785669) (xy 74.51118 -404.799951) (xy 74.518998 -404.818633)
			(xy 74.519536 -404.828756) (xy 74.519536 -404.986744) (xy 74.519939 -404.995932) (xy 74.526459 -405.013115)
			(xy 74.532236 -405.020272) (xy 74.55402 -405.045927) (xy 74.591971 -405.101513) (xy 74.623006 -405.161235)
			(xy 74.64668 -405.22424) (xy 74.662654 -405.289622) (xy 74.670699 -405.356444) (xy 74.670699 -405.42375)
			(xy 74.662655 -405.490572) (xy 74.646682 -405.555955) (xy 74.623008 -405.618959) (xy 74.620571 -405.623649)
			(xy 75.749106 -405.623649) (xy 75.749107 -405.556342) (xy 75.757152 -405.489519) (xy 75.773127 -405.424136)
			(xy 75.796802 -405.361131) (xy 75.827839 -405.301407) (xy 75.865791 -405.245822) (xy 75.88758 -405.22017)
			(xy 75.893369 -405.21302) (xy 75.899889 -405.195833) (xy 75.90028 -405.186642) (xy 75.90028 -404.693374)
			(xy 75.899887 -404.684185) (xy 75.893362 -404.667001) (xy 75.88758 -404.659846) (xy 75.865813 -404.634177)
			(xy 75.827861 -404.578594) (xy 75.796824 -404.518873) (xy 75.773148 -404.45587) (xy 75.757173 -404.39049)
			(xy 75.749126 -404.323669) (xy 75.749124 -404.256365) (xy 75.757167 -404.189543) (xy 75.773138 -404.124161)
			(xy 75.796811 -404.061157) (xy 75.827844 -404.001435) (xy 75.865792 -403.94585) (xy 75.88758 -403.920198)
			(xy 75.893358 -403.913039) (xy 75.899884 -403.895859) (xy 75.90028 -403.88667) (xy 75.90028 -403.728682)
			(xy 75.90065 -403.718504) (xy 75.908449 -403.699701) (xy 75.922851 -403.685315) (xy 75.941664 -403.677538)
			(xy 75.951842 -403.67712) (xy 76.668122 -403.67712) (xy 76.678279 -403.677615) (xy 76.697045 -403.685393)
			(xy 76.711409 -403.699758) (xy 76.719186 -403.718525) (xy 76.719684 -403.728682) (xy 76.719684 -403.88667)
			(xy 76.720112 -403.895855) (xy 76.726614 -403.91304) (xy 76.732384 -403.920198) (xy 76.754193 -403.945833)
			(xy 76.792139 -404.001422) (xy 76.82317 -404.061148) (xy 76.846841 -404.124155) (xy 76.862812 -404.189539)
			(xy 76.870854 -404.256363) (xy 76.870852 -404.32367) (xy 76.862806 -404.390493) (xy 76.846831 -404.455877)
			(xy 76.823157 -404.518882) (xy 76.792122 -404.578606) (xy 76.754172 -404.634194) (xy 76.732384 -404.659846)
			(xy 76.726584 -404.666988) (xy 76.720072 -404.684181) (xy 76.719684 -404.693374) (xy 76.719684 -405.186642)
			(xy 76.720077 -405.195831) (xy 76.726603 -405.213015) (xy 76.732384 -405.22017) (xy 76.754165 -405.245827)
			(xy 76.792113 -405.301414) (xy 76.823145 -405.361137) (xy 76.846817 -405.42414) (xy 76.86279 -405.489522)
			(xy 76.870834 -405.556343) (xy 76.870835 -405.623648) (xy 76.862791 -405.690469) (xy 76.84682 -405.755851)
			(xy 76.823149 -405.818855) (xy 76.792117 -405.878579) (xy 76.754171 -405.934166) (xy 76.732384 -405.959818)
			(xy 76.726595 -405.966969) (xy 76.720077 -405.984155) (xy 76.719684 -405.993346) (xy 76.719684 -406.151334)
			(xy 76.719195 -406.161491) (xy 76.711414 -406.180257) (xy 76.697047 -406.19462) (xy 76.678279 -406.202397)
			(xy 76.668122 -406.202896) (xy 75.951842 -406.202896) (xy 75.941677 -406.202403) (xy 75.92289 -406.194638)
			(xy 75.908505 -406.180274) (xy 75.900712 -406.161498) (xy 75.90028 -406.151334) (xy 75.90028 -405.993346)
			(xy 75.899852 -405.984161) (xy 75.893351 -405.966976) (xy 75.88758 -405.959818) (xy 75.865785 -405.934171)
			(xy 75.827834 -405.878585) (xy 75.796799 -405.818861) (xy 75.773124 -405.755856) (xy 75.757151 -405.690472)
			(xy 75.749106 -405.623649) (xy 74.620571 -405.623649) (xy 74.591974 -405.678682) (xy 74.554024 -405.734268)
			(xy 74.532236 -405.75992) (xy 74.526441 -405.767066) (xy 74.519927 -405.784256) (xy 74.519536 -405.793448)
			(xy 74.519536 -406.286716) (xy 74.519953 -406.295902) (xy 74.526464 -406.313086) (xy 74.532236 -406.320244)
			(xy 74.553993 -406.345922) (xy 74.591944 -406.401504) (xy 74.62298 -406.461224) (xy 74.646656 -406.524225)
			(xy 74.662632 -406.589604) (xy 74.670679 -406.656424) (xy 74.670682 -406.723727) (xy 74.670675 -406.723789)
			(xy 77.94872 -406.723789) (xy 77.948723 -406.656363) (xy 77.956802 -406.589422) (xy 77.972842 -406.52393)
			(xy 77.996611 -406.460832) (xy 78.027767 -406.401035) (xy 78.065861 -406.345401) (xy 78.087728 -406.319736)
			(xy 78.093538 -406.3126) (xy 78.100044 -406.295402) (xy 78.100428 -406.286208) (xy 78.100428 -405.793956)
			(xy 78.100033 -405.784767) (xy 78.093508 -405.767584) (xy 78.087728 -405.760428) (xy 78.065859 -405.734766)
			(xy 78.027769 -405.679132) (xy 77.996617 -405.619336) (xy 77.972851 -405.556238) (xy 77.956815 -405.490748)
			(xy 77.948739 -405.423809) (xy 77.94874 -405.356385) (xy 77.956816 -405.289446) (xy 77.972853 -405.223956)
			(xy 77.996619 -405.160859) (xy 78.027772 -405.101063) (xy 78.065863 -405.045429) (xy 78.087728 -405.019764)
			(xy 78.093526 -405.01262) (xy 78.100039 -404.995428) (xy 78.100428 -404.986236) (xy 78.100428 -404.828756)
			(xy 78.10085 -404.818641) (xy 78.108607 -404.799956) (xy 78.122924 -404.785662) (xy 78.14162 -404.777934)
			(xy 78.151736 -404.777448) (xy 78.868016 -404.777448) (xy 78.878119 -404.777971) (xy 78.896788 -404.785704)
			(xy 78.91108 -404.799989) (xy 78.918823 -404.818653) (xy 78.919324 -404.828756) (xy 78.919324 -404.986236)
			(xy 78.919712 -404.995426) (xy 78.92624 -405.01261) (xy 78.932024 -405.019764) (xy 78.953883 -405.045433)
			(xy 78.99197 -405.101067) (xy 79.02312 -405.160863) (xy 79.046883 -405.22396) (xy 79.062918 -405.289448)
			(xy 79.070994 -405.356386) (xy 79.070995 -405.423808) (xy 79.062919 -405.490746) (xy 79.046885 -405.556235)
			(xy 79.023122 -405.619331) (xy 79.020843 -405.623707) (xy 80.148899 -405.623707) (xy 80.148899 -405.556284)
			(xy 80.156975 -405.489345) (xy 80.173011 -405.423856) (xy 80.196775 -405.360759) (xy 80.227925 -405.300963)
			(xy 80.266013 -405.245328) (xy 80.287876 -405.219662) (xy 80.293668 -405.212514) (xy 80.300186 -405.195326)
			(xy 80.300576 -405.186134) (xy 80.300576 -404.693882) (xy 80.30018 -404.684693) (xy 80.293657 -404.667509)
			(xy 80.287876 -404.660354) (xy 80.266034 -404.634671) (xy 80.227947 -404.579038) (xy 80.196796 -404.519244)
			(xy 80.173032 -404.45615) (xy 80.156996 -404.390663) (xy 80.148918 -404.323727) (xy 80.148917 -404.256306)
			(xy 80.15699 -404.189369) (xy 80.173022 -404.123882) (xy 80.196783 -404.060786) (xy 80.22793 -404.00099)
			(xy 80.266014 -403.945356) (xy 80.287876 -403.91969) (xy 80.293657 -403.912533) (xy 80.300182 -403.895352)
			(xy 80.300576 -403.886162) (xy 80.300576 -403.728682) (xy 80.301013 -403.71855) (xy 80.308753 -403.699821)
			(xy 80.323055 -403.685464) (xy 80.341754 -403.677652) (xy 80.351884 -403.67712) (xy 81.068164 -403.67712)
			(xy 81.078318 -403.677552) (xy 81.097074 -403.685339) (xy 81.111399 -403.699733) (xy 81.119096 -403.718526)
			(xy 81.119472 -403.728682) (xy 81.119472 -403.886162) (xy 81.119907 -403.895346) (xy 81.126404 -403.912531)
			(xy 81.132172 -403.91969) (xy 81.154059 -403.945337) (xy 81.192148 -404.000973) (xy 81.2233 -404.060772)
			(xy 81.247064 -404.123871) (xy 81.263099 -404.189363) (xy 81.271173 -404.256304) (xy 81.271171 -404.32373)
			(xy 81.263093 -404.39067) (xy 81.247054 -404.45616) (xy 81.223286 -404.519258) (xy 81.192131 -404.579055)
			(xy 81.154038 -404.634689) (xy 81.132172 -404.660354) (xy 81.126366 -404.667493) (xy 81.119858 -404.684688)
			(xy 81.119472 -404.693882) (xy 81.119472 -405.186134) (xy 81.119872 -405.195322) (xy 81.126393 -405.212506)
			(xy 81.132172 -405.219662) (xy 81.154031 -405.245332) (xy 81.192122 -405.300965) (xy 81.223274 -405.36076)
			(xy 81.24704 -405.423857) (xy 81.263077 -405.489345) (xy 81.271154 -405.556284) (xy 81.271154 -405.623707)
			(xy 81.263078 -405.690646) (xy 81.247043 -405.756135) (xy 81.223278 -405.819232) (xy 81.192126 -405.879027)
			(xy 81.154037 -405.934661) (xy 81.132172 -405.960326) (xy 81.126378 -405.967473) (xy 81.119862 -405.984662)
			(xy 81.119472 -405.993854) (xy 81.119472 -406.151334) (xy 81.119002 -406.161461) (xy 81.111265 -406.180181)
			(xy 81.096974 -406.194536) (xy 81.078289 -406.202356) (xy 81.068164 -406.202896) (xy 80.351884 -406.202896)
			(xy 80.341728 -406.202492) (xy 80.322975 -406.19469) (xy 80.308652 -406.180288) (xy 80.300953 -406.161492)
			(xy 80.300576 -406.151334) (xy 80.300576 -405.993854) (xy 80.300145 -405.984669) (xy 80.293646 -405.967484)
			(xy 80.287876 -405.960326) (xy 80.266007 -405.934665) (xy 80.22792 -405.879029) (xy 80.196771 -405.819232)
			(xy 80.173008 -405.756135) (xy 80.156974 -405.690646) (xy 80.148899 -405.623707) (xy 79.020843 -405.623707)
			(xy 78.991974 -405.679127) (xy 78.953887 -405.734762) (xy 78.932024 -405.760428) (xy 78.926236 -405.767579)
			(xy 78.919715 -405.784765) (xy 78.919324 -405.793956) (xy 78.919324 -406.286208) (xy 78.919725 -406.295396)
			(xy 78.926244 -406.312581) (xy 78.932024 -406.319736) (xy 78.953856 -406.345428) (xy 78.991944 -406.401059)
			(xy 79.023095 -406.460852) (xy 79.046859 -406.523945) (xy 79.062896 -406.589431) (xy 79.070974 -406.656366)
			(xy 79.070977 -406.72373) (xy 82.349039 -406.72373) (xy 82.349042 -406.656422) (xy 82.357089 -406.589598)
			(xy 82.373065 -406.524214) (xy 82.39674 -406.461209) (xy 82.427776 -406.401484) (xy 82.465727 -406.345896)
			(xy 82.487516 -406.320244) (xy 82.493321 -406.313105) (xy 82.49983 -406.29591) (xy 82.500216 -406.286716)
			(xy 82.500216 -405.793448) (xy 82.499779 -405.784264) (xy 82.493284 -405.767079) (xy 82.487516 -405.75992)
			(xy 82.465725 -405.734271) (xy 82.427778 -405.678683) (xy 82.396746 -405.618959) (xy 82.373074 -405.555954)
			(xy 82.357102 -405.490572) (xy 82.349059 -405.423749) (xy 82.349059 -405.356445) (xy 82.357103 -405.289622)
			(xy 82.373076 -405.22424) (xy 82.396748 -405.161235) (xy 82.427781 -405.101511) (xy 82.465729 -405.045924)
			(xy 82.487516 -405.020272) (xy 82.493309 -405.013124) (xy 82.499825 -404.995936) (xy 82.500216 -404.986744)
			(xy 82.500216 -404.828756) (xy 82.500586 -404.818597) (xy 82.508399 -404.799841) (xy 82.522811 -404.785518)
			(xy 82.541617 -404.777823) (xy 82.551778 -404.777448) (xy 83.268058 -404.777448) (xy 83.278183 -404.777961)
			(xy 83.296905 -404.785677) (xy 83.311263 -404.799955) (xy 83.319082 -404.818634) (xy 83.31962 -404.828756)
			(xy 83.31962 -404.986744) (xy 83.320004 -404.995934) (xy 83.326535 -405.013118) (xy 83.33232 -405.020272)
			(xy 83.354105 -405.045927) (xy 83.392057 -405.101512) (xy 83.423092 -405.161235) (xy 83.446767 -405.224239)
			(xy 83.462742 -405.289621) (xy 83.470787 -405.356444) (xy 83.470787 -405.42375) (xy 83.462743 -405.490573)
			(xy 83.446769 -405.555955) (xy 83.423095 -405.61896) (xy 83.420628 -405.623707) (xy 84.54869 -405.623707)
			(xy 84.54869 -405.556284) (xy 84.556766 -405.489346) (xy 84.572801 -405.423857) (xy 84.596564 -405.36076)
			(xy 84.627714 -405.300963) (xy 84.665801 -405.245328) (xy 84.687664 -405.219662) (xy 84.693467 -405.212522)
			(xy 84.699976 -405.195327) (xy 84.700364 -405.186134) (xy 84.700364 -404.693882) (xy 84.699948 -404.684696)
			(xy 84.693437 -404.667512) (xy 84.687664 -404.660354) (xy 84.665823 -404.63467) (xy 84.627736 -404.579038)
			(xy 84.596586 -404.519244) (xy 84.572822 -404.456149) (xy 84.556787 -404.390663) (xy 84.548709 -404.323727)
			(xy 84.548707 -404.256306) (xy 84.556781 -404.18937) (xy 84.572813 -404.123882) (xy 84.596573 -404.060787)
			(xy 84.627719 -404.000991) (xy 84.665803 -403.945356) (xy 84.687664 -403.91969) (xy 84.693455 -403.912541)
			(xy 84.699971 -403.895353) (xy 84.700364 -403.886162) (xy 84.700364 -403.728682) (xy 84.700812 -403.718551)
			(xy 84.70855 -403.699825) (xy 84.722849 -403.685468) (xy 84.741543 -403.677654) (xy 84.751672 -403.67712)
			(xy 85.467952 -403.67712) (xy 85.478105 -403.677561) (xy 85.496861 -403.685345) (xy 85.511186 -403.699736)
			(xy 85.518884 -403.718527) (xy 85.51926 -403.728682) (xy 85.51926 -403.886162) (xy 85.519698 -403.895346)
			(xy 85.526193 -403.91253) (xy 85.53196 -403.91969) (xy 85.553847 -403.945337) (xy 85.591938 -404.000973)
			(xy 85.62309 -404.060771) (xy 85.646854 -404.123871) (xy 85.66289 -404.189362) (xy 85.670964 -404.256303)
			(xy 85.670962 -404.32373) (xy 85.662884 -404.39067) (xy 85.646845 -404.456161) (xy 85.623076 -404.519259)
			(xy 85.591921 -404.579055) (xy 85.553827 -404.634689) (xy 85.53196 -404.660354) (xy 85.526153 -404.667492)
			(xy 85.519646 -404.684688) (xy 85.51926 -404.693882) (xy 85.51926 -405.186134) (xy 85.519663 -405.195322)
			(xy 85.526183 -405.212506) (xy 85.53196 -405.219662) (xy 85.553819 -405.245331) (xy 85.591911 -405.300964)
			(xy 85.623064 -405.36076) (xy 85.64683 -405.423856) (xy 85.662868 -405.489345) (xy 85.670945 -405.556284)
			(xy 85.670945 -405.623707) (xy 85.662869 -405.690646) (xy 85.646833 -405.756135) (xy 85.623068 -405.819232)
			(xy 85.591916 -405.879028) (xy 85.553825 -405.934661) (xy 85.53196 -405.960326) (xy 85.526165 -405.967472)
			(xy 85.51965 -405.984662) (xy 85.51926 -405.993854) (xy 85.51926 -406.151334) (xy 85.518801 -406.161463)
			(xy 85.511062 -406.180185) (xy 85.496768 -406.19454) (xy 85.478079 -406.202358) (xy 85.467952 -406.202896)
			(xy 84.751672 -406.202896) (xy 84.741516 -406.202501) (xy 84.722762 -406.194696) (xy 84.708439 -406.180291)
			(xy 84.700741 -406.161493) (xy 84.700364 -406.151334) (xy 84.700364 -405.993854) (xy 84.699914 -405.984671)
			(xy 84.693426 -405.967487) (xy 84.687664 -405.960326) (xy 84.665795 -405.934665) (xy 84.627709 -405.879029)
			(xy 84.596561 -405.819232) (xy 84.572799 -405.756135) (xy 84.556765 -405.690645) (xy 84.54869 -405.623707)
			(xy 83.420628 -405.623707) (xy 83.39206 -405.678683) (xy 83.354109 -405.734268) (xy 83.33232 -405.75992)
			(xy 83.326535 -405.767073) (xy 83.320013 -405.784258) (xy 83.31962 -405.793448) (xy 83.31962 -406.286716)
			(xy 83.320018 -406.295905) (xy 83.32654 -406.313089) (xy 83.33232 -406.320244) (xy 83.354077 -406.345921)
			(xy 83.39203 -406.401503) (xy 83.423067 -406.461223) (xy 83.446743 -406.524224) (xy 83.46272 -406.589604)
			(xy 83.470767 -406.656424) (xy 83.47077 -406.723728) (xy 83.470763 -406.723789) (xy 86.748808 -406.723789)
			(xy 86.748811 -406.656363) (xy 86.75689 -406.589422) (xy 86.772929 -406.523931) (xy 86.796697 -406.460833)
			(xy 86.827852 -406.401036) (xy 86.865946 -406.345401) (xy 86.887812 -406.319736) (xy 86.89362 -406.312599)
			(xy 86.900127 -406.295402) (xy 86.900512 -406.286208) (xy 86.900512 -405.793956) (xy 86.90012 -405.784767)
			(xy 86.893594 -405.767583) (xy 86.887812 -405.760428) (xy 86.865944 -405.734766) (xy 86.827854 -405.679131)
			(xy 86.796703 -405.619335) (xy 86.772939 -405.556238) (xy 86.756903 -405.490748) (xy 86.748827 -405.423809)
			(xy 86.748828 -405.356385) (xy 86.756904 -405.289446) (xy 86.77294 -405.223957) (xy 86.796706 -405.16086)
			(xy 86.827857 -405.101063) (xy 86.865947 -405.045429) (xy 86.887812 -405.019764) (xy 86.893608 -405.012618)
			(xy 86.900123 -404.995428) (xy 86.900512 -404.986236) (xy 86.900512 -404.828756) (xy 86.900949 -404.818643)
			(xy 86.908704 -404.799961) (xy 86.923015 -404.785668) (xy 86.941706 -404.777937) (xy 86.95182 -404.777448)
			(xy 87.6681 -404.777448) (xy 87.678202 -404.777984) (xy 87.696871 -404.785712) (xy 87.711163 -404.799993)
			(xy 87.718907 -404.818654) (xy 87.719408 -404.828756) (xy 87.719408 -404.986236) (xy 87.719799 -404.995425)
			(xy 87.726326 -405.01261) (xy 87.732108 -405.019764) (xy 87.753968 -405.045433) (xy 87.792056 -405.101067)
			(xy 87.823206 -405.160863) (xy 87.846971 -405.223959) (xy 87.863006 -405.289448) (xy 87.871082 -405.356385)
			(xy 87.871082 -405.423809) (xy 87.863007 -405.490746) (xy 87.846972 -405.556235) (xy 87.823209 -405.619332)
			(xy 87.792059 -405.679128) (xy 87.753971 -405.734763) (xy 87.732108 -405.760428) (xy 87.726318 -405.767578)
			(xy 87.719799 -405.784765) (xy 87.719408 -405.793956) (xy 87.719408 -406.286208) (xy 87.719813 -406.295396)
			(xy 87.72633 -406.31258) (xy 87.732108 -406.319736) (xy 87.75394 -406.345427) (xy 87.792029 -406.401058)
			(xy 87.823181 -406.460851) (xy 87.846947 -406.523944) (xy 87.862984 -406.58943) (xy 87.871062 -406.656365)
			(xy 87.871065 -406.723729) (xy 91.149127 -406.723729) (xy 91.14913 -406.656423) (xy 91.157177 -406.589598)
			(xy 91.173152 -406.524215) (xy 91.196827 -406.461209) (xy 91.227861 -406.401484) (xy 91.265812 -406.345897)
			(xy 91.2876 -406.320244) (xy 91.293403 -406.313103) (xy 91.299914 -406.295909) (xy 91.3003 -406.286716)
			(xy 91.3003 -405.793448) (xy 91.299867 -405.784263) (xy 91.293369 -405.767079) (xy 91.2876 -405.75992)
			(xy 91.26581 -405.734271) (xy 91.227863 -405.678683) (xy 91.196832 -405.618958) (xy 91.173162 -405.555954)
			(xy 91.15719 -405.490572) (xy 91.149147 -405.423749) (xy 91.149147 -405.356445) (xy 91.157191 -405.289622)
			(xy 91.173163 -405.224241) (xy 91.196835 -405.161236) (xy 91.227866 -405.101512) (xy 91.265813 -405.045925)
			(xy 91.2876 -405.020272) (xy 91.293391 -405.013123) (xy 91.299909 -404.995935) (xy 91.3003 -404.986744)
			(xy 91.3003 -404.828756) (xy 91.300686 -404.818599) (xy 91.308496 -404.799846) (xy 91.322903 -404.785524)
			(xy 91.341703 -404.777826) (xy 91.351862 -404.777448) (xy 92.068142 -404.777448) (xy 92.078272 -404.777892)
			(xy 92.096996 -404.785635) (xy 92.111351 -404.799934) (xy 92.119167 -404.818628) (xy 92.119704 -404.828756)
			(xy 92.119704 -404.986744) (xy 92.120092 -404.995934) (xy 92.126621 -405.013118) (xy 92.132404 -405.020272)
			(xy 92.154186 -405.045928) (xy 92.192133 -405.101515) (xy 92.223164 -405.161238) (xy 92.246835 -405.224242)
			(xy 92.262807 -405.289624) (xy 92.270851 -405.356445) (xy 92.270851 -405.423749) (xy 92.262808 -405.490571)
			(xy 92.246837 -405.555952) (xy 92.223166 -405.618956) (xy 92.220728 -405.623648) (xy 115.349248 -405.623648)
			(xy 115.349249 -405.556343) (xy 115.357293 -405.489521) (xy 115.373266 -405.424139) (xy 115.396938 -405.361134)
			(xy 115.42797 -405.30141) (xy 115.465917 -405.245823) (xy 115.487704 -405.22017) (xy 115.493496 -405.213022)
			(xy 115.500013 -405.195834) (xy 115.500404 -405.186642) (xy 115.500404 -404.693374) (xy 115.500006 -404.684186)
			(xy 115.493484 -404.667001) (xy 115.487704 -404.659846) (xy 115.465939 -404.634176) (xy 115.427992 -404.578591)
			(xy 115.396959 -404.51887) (xy 115.373287 -404.455868) (xy 115.357314 -404.390488) (xy 115.349268 -404.323668)
			(xy 115.349266 -404.256365) (xy 115.357308 -404.189545) (xy 115.373277 -404.124164) (xy 115.396946 -404.061161)
			(xy 115.427975 -404.001437) (xy 115.465919 -403.945851) (xy 115.487704 -403.920198) (xy 115.493484 -403.913041)
			(xy 115.500009 -403.89586) (xy 115.500404 -403.88667) (xy 115.500404 -403.728682) (xy 115.500918 -403.718527)
			(xy 115.508692 -403.699764) (xy 115.523051 -403.685401) (xy 115.541811 -403.677621) (xy 115.551966 -403.67712)
			(xy 116.268246 -403.67712) (xy 116.278404 -403.677595) (xy 116.297171 -403.685382) (xy 116.311534 -403.699752)
			(xy 116.31931 -403.718523) (xy 116.319808 -403.728682) (xy 116.319808 -403.88667) (xy 116.320231 -403.895856)
			(xy 116.326735 -403.91304) (xy 116.332508 -403.920198) (xy 116.354319 -403.945832) (xy 116.392271 -404.00142)
			(xy 116.423306 -404.061145) (xy 116.44698 -404.124152) (xy 116.462953 -404.189537) (xy 116.470996 -404.256363)
			(xy 116.470994 -404.32367) (xy 116.462947 -404.390495) (xy 116.44697 -404.455879) (xy 116.423292 -404.518885)
			(xy 116.392254 -404.578609) (xy 116.354299 -404.634195) (xy 116.332508 -404.659846) (xy 116.32671 -404.66699)
			(xy 116.320196 -404.684181) (xy 116.319808 -404.693374) (xy 116.319808 -405.186642) (xy 116.320196 -405.195832)
			(xy 116.326725 -405.213016) (xy 116.332508 -405.22017) (xy 116.354291 -405.245826) (xy 116.392244 -405.301411)
			(xy 116.42328 -405.361133) (xy 116.446956 -405.424137) (xy 116.462931 -405.48952) (xy 116.470976 -405.556343)
			(xy 116.470977 -405.623648) (xy 116.462932 -405.690471) (xy 116.446958 -405.755854) (xy 116.423284 -405.818858)
			(xy 116.392249 -405.878581) (xy 116.354297 -405.934167) (xy 116.332508 -405.959818) (xy 116.326722 -405.966971)
			(xy 116.320201 -405.984155) (xy 116.319808 -405.993346) (xy 116.319808 -406.151334) (xy 116.319296 -406.161488)
			(xy 116.311519 -406.180249) (xy 116.297159 -406.194612) (xy 116.2784 -406.202393) (xy 116.268246 -406.202896)
			(xy 115.551966 -406.202896) (xy 115.54181 -406.202395) (xy 115.523047 -406.194616) (xy 115.508684 -406.180253)
			(xy 115.500905 -406.16149) (xy 115.500404 -406.151334) (xy 115.500404 -405.993346) (xy 115.499971 -405.984161)
			(xy 115.493473 -405.966977) (xy 115.487704 -405.959818) (xy 115.465911 -405.93417) (xy 115.427965 -405.878582)
			(xy 115.396934 -405.818858) (xy 115.373263 -405.755853) (xy 115.357292 -405.69047) (xy 115.349248 -405.623648)
			(xy 92.220728 -405.623648) (xy 92.192136 -405.67868) (xy 92.15419 -405.734267) (xy 92.132404 -405.75992)
			(xy 92.126617 -405.767072) (xy 92.120096 -405.784257) (xy 92.119704 -405.793448) (xy 92.119704 -406.286716)
			(xy 92.120106 -406.295904) (xy 92.126625 -406.313088) (xy 92.132404 -406.320244) (xy 92.154159 -406.345923)
			(xy 92.192106 -406.401506) (xy 92.223138 -406.461227) (xy 92.246811 -406.524228) (xy 92.262785 -406.589606)
			(xy 92.270831 -406.656425) (xy 92.270834 -406.723727) (xy 92.270826 -406.72379) (xy 117.548838 -406.72379)
			(xy 117.548841 -406.656362) (xy 117.55692 -406.589421) (xy 117.572961 -406.523929) (xy 117.596731 -406.460831)
			(xy 117.627888 -406.401034) (xy 117.665984 -406.3454) (xy 117.687852 -406.319736) (xy 117.693665 -406.312602)
			(xy 117.700168 -406.295403) (xy 117.700552 -406.286208) (xy 117.700552 -405.793956) (xy 117.700151 -405.784768)
			(xy 117.69363 -405.767585) (xy 117.687852 -405.760428) (xy 117.665982 -405.734767) (xy 117.62789 -405.679133)
			(xy 117.596737 -405.619337) (xy 117.572971 -405.556239) (xy 117.556934 -405.490749) (xy 117.548857 -405.42381)
			(xy 117.548858 -405.356384) (xy 117.556935 -405.289445) (xy 117.572972 -405.223955) (xy 117.596739 -405.160858)
			(xy 117.627893 -405.101062) (xy 117.665986 -405.045428) (xy 117.687852 -405.019764) (xy 117.693653 -405.012622)
			(xy 117.700164 -404.995429) (xy 117.700552 -404.986236) (xy 117.700552 -404.828756) (xy 117.701048 -404.81865)
			(xy 117.708791 -404.79998) (xy 117.723084 -404.785689) (xy 117.741754 -404.777947) (xy 117.75186 -404.777448)
			(xy 118.46814 -404.777448) (xy 118.478245 -404.777951) (xy 118.496914 -404.785692) (xy 118.511206 -404.799983)
			(xy 118.518948 -404.818651) (xy 118.519448 -404.828756) (xy 118.519448 -404.986236) (xy 118.519853 -404.995424)
			(xy 118.526372 -405.012607) (xy 118.532148 -405.019764) (xy 118.55401 -405.045432) (xy 118.592102 -405.101065)
			(xy 118.623256 -405.16086) (xy 118.647023 -405.223957) (xy 118.66306 -405.289446) (xy 118.671137 -405.356385)
			(xy 118.671137 -405.423809) (xy 118.663061 -405.490748) (xy 118.647024 -405.556238) (xy 118.623258 -405.619335)
			(xy 118.62098 -405.623708) (xy 119.749017 -405.623708) (xy 119.749017 -405.556283) (xy 119.757094 -405.489345)
			(xy 119.77313 -405.423855) (xy 119.796895 -405.360758) (xy 119.828046 -405.300962) (xy 119.866136 -405.245327)
			(xy 119.888 -405.219662) (xy 119.893795 -405.212516) (xy 119.900311 -405.195326) (xy 119.9007 -405.186134)
			(xy 119.9007 -404.693882) (xy 119.900298 -404.684694) (xy 119.893779 -404.66751) (xy 119.888 -404.660354)
			(xy 119.866158 -404.634671) (xy 119.828068 -404.579039) (xy 119.796917 -404.519245) (xy 119.773151 -404.456151)
			(xy 119.757114 -404.390664) (xy 119.749037 -404.323727) (xy 119.749035 -404.256306) (xy 119.757108 -404.189369)
			(xy 119.773141 -404.123881) (xy 119.796903 -404.060785) (xy 119.828051 -404.000989) (xy 119.866137 -403.945355)
			(xy 119.888 -403.91969) (xy 119.893783 -403.912535) (xy 119.900306 -403.895352) (xy 119.9007 -403.886162)
			(xy 119.9007 -403.728682) (xy 119.90121 -403.718559) (xy 119.908937 -403.699845) (xy 119.923215 -403.685491)
			(xy 119.941888 -403.677665) (xy 119.952008 -403.67712) (xy 120.668288 -403.67712) (xy 120.678412 -403.677526)
			(xy 120.697119 -403.685274) (xy 120.711435 -403.699594) (xy 120.719177 -403.718304) (xy 120.719596 -403.728428)
			(xy 120.719596 -403.886162) (xy 120.720025 -403.895347) (xy 120.726526 -403.912532) (xy 120.732296 -403.91969)
			(xy 120.754182 -403.945337) (xy 120.79227 -404.000974) (xy 120.82342 -404.060773) (xy 120.847183 -404.123872)
			(xy 120.863217 -404.189363) (xy 120.871291 -404.256304) (xy 120.871289 -404.323729) (xy 120.863211 -404.390669)
			(xy 120.847173 -404.456159) (xy 120.823407 -404.519257) (xy 120.792253 -404.579054) (xy 120.754161 -404.634689)
			(xy 120.732296 -404.660354) (xy 120.726494 -404.667495) (xy 120.719983 -404.684689) (xy 120.719596 -404.693882)
			(xy 120.719596 -405.186134) (xy 120.719991 -405.195323) (xy 120.726515 -405.212507) (xy 120.732296 -405.219662)
			(xy 120.754154 -405.245332) (xy 120.792243 -405.300966) (xy 120.823395 -405.360761) (xy 120.847159 -405.423858)
			(xy 120.863195 -405.489346) (xy 120.871272 -405.556284) (xy 120.871272 -405.623707) (xy 120.863197 -405.690645)
			(xy 120.847162 -405.756134) (xy 120.823398 -405.81923) (xy 120.792248 -405.879026) (xy 120.75416 -405.934661)
			(xy 120.732296 -405.960326) (xy 120.726505 -405.967475) (xy 120.719987 -405.984663) (xy 120.719596 -405.993854)
			(xy 120.719596 -406.151334) (xy 120.719102 -406.161458) (xy 120.71137 -406.180174) (xy 120.697087 -406.194527)
			(xy 120.67841 -406.202352) (xy 120.668288 -406.202896) (xy 119.952008 -406.202896) (xy 119.941886 -406.202477)
			(xy 119.923181 -406.194731) (xy 119.908867 -406.180415) (xy 119.901122 -406.16171) (xy 119.9007 -406.151588)
			(xy 119.9007 -405.993854) (xy 119.900264 -405.98467) (xy 119.893768 -405.967485) (xy 119.888 -405.960326)
			(xy 119.86613 -405.934666) (xy 119.828042 -405.87903) (xy 119.796891 -405.819234) (xy 119.773127 -405.756136)
			(xy 119.757092 -405.690646) (xy 119.749017 -405.623708) (xy 118.62098 -405.623708) (xy 118.592105 -405.67913)
			(xy 118.554014 -405.734764) (xy 118.532148 -405.760428) (xy 118.526351 -405.767572) (xy 118.519838 -405.784764)
			(xy 118.519448 -405.793956) (xy 118.519448 -406.286208) (xy 118.519866 -406.295394) (xy 118.526375 -406.312578)
			(xy 118.532148 -406.319736) (xy 118.553982 -406.345426) (xy 118.592075 -406.401056) (xy 118.62323 -406.460848)
			(xy 118.646999 -406.523942) (xy 118.663038 -406.589429) (xy 118.671117 -406.656365) (xy 118.67112 -406.72373)
			(xy 121.949157 -406.72373) (xy 121.94916 -406.656422) (xy 121.957208 -406.589597) (xy 121.973184 -406.524213)
			(xy 121.99686 -406.461207) (xy 122.027897 -406.401483) (xy 122.06585 -406.345896) (xy 122.08764 -406.320244)
			(xy 122.093448 -406.313107) (xy 122.099955 -406.29591) (xy 122.10034 -406.286716) (xy 122.10034 -405.793448)
			(xy 122.099898 -405.784264) (xy 122.093405 -405.76708) (xy 122.08764 -405.75992) (xy 122.065848 -405.734271)
			(xy 122.027899 -405.678684) (xy 121.996866 -405.61896) (xy 121.973194 -405.555955) (xy 121.957221 -405.490573)
			(xy 121.949177 -405.42375) (xy 121.949177 -405.356444) (xy 121.957222 -405.289621) (xy 121.973195 -405.224239)
			(xy 121.996869 -405.161234) (xy 122.027902 -405.101511) (xy 122.065852 -405.045924) (xy 122.08764 -405.020272)
			(xy 122.093436 -405.013127) (xy 122.09995 -404.995936) (xy 122.10034 -404.986744) (xy 122.10034 -404.828756)
			(xy 122.100681 -404.818626) (xy 122.108451 -404.799913) (xy 122.122791 -404.785599) (xy 122.141517 -404.777863)
			(xy 122.151648 -404.777448) (xy 122.868182 -404.777448) (xy 122.878309 -404.777941) (xy 122.897031 -404.785665)
			(xy 122.911388 -404.799949) (xy 122.919207 -404.818632) (xy 122.919744 -404.828756) (xy 122.919744 -404.986744)
			(xy 122.920145 -404.995932) (xy 122.926666 -405.013116) (xy 122.932444 -405.020272) (xy 122.954228 -405.045927)
			(xy 122.992178 -405.101513) (xy 123.023213 -405.161236) (xy 123.046886 -405.22424) (xy 123.06286 -405.289622)
			(xy 123.070905 -405.356444) (xy 123.070905 -405.42375) (xy 123.062861 -405.490572) (xy 123.046888 -405.555954)
			(xy 123.023215 -405.618959) (xy 123.020778 -405.623649) (xy 124.149312 -405.623649) (xy 124.149313 -405.556342)
			(xy 124.157358 -405.489518) (xy 124.173333 -405.424135) (xy 124.197009 -405.36113) (xy 124.228046 -405.301407)
			(xy 124.265998 -405.245822) (xy 124.287788 -405.22017) (xy 124.293578 -405.21302) (xy 124.300097 -405.195833)
			(xy 124.300488 -405.186642) (xy 124.300488 -404.693374) (xy 124.300093 -404.684185) (xy 124.293569 -404.667001)
			(xy 124.287788 -404.659846) (xy 124.26602 -404.634177) (xy 124.228068 -404.578594) (xy 124.197031 -404.518873)
			(xy 124.173355 -404.455871) (xy 124.157379 -404.39049) (xy 124.149332 -404.323669) (xy 124.14933 -404.256364)
			(xy 124.157373 -404.189542) (xy 124.173345 -404.124161) (xy 124.197017 -404.061157) (xy 124.228051 -404.001435)
			(xy 124.266 -403.945849) (xy 124.287788 -403.920198) (xy 124.293567 -403.91304) (xy 124.300092 -403.895859)
			(xy 124.300488 -403.88667) (xy 124.300488 -403.728682) (xy 124.30085 -403.718503) (xy 124.308651 -403.699698)
			(xy 124.323056 -403.685313) (xy 124.34187 -403.677537) (xy 124.35205 -403.67712) (xy 125.06833 -403.67712)
			(xy 125.078487 -403.677608) (xy 125.097254 -403.685389) (xy 125.111617 -403.699756) (xy 125.119394 -403.718524)
			(xy 125.119892 -403.728682) (xy 125.119892 -403.88667) (xy 125.120318 -403.895855) (xy 125.126821 -403.91304)
			(xy 125.132592 -403.920198) (xy 125.1544 -403.945833) (xy 125.192347 -404.001422) (xy 125.223377 -404.061149)
			(xy 125.247047 -404.124155) (xy 125.263018 -404.189539) (xy 125.27106 -404.256363) (xy 125.271058 -404.32367)
			(xy 125.263012 -404.390493) (xy 125.247038 -404.455876) (xy 125.223364 -404.518882) (xy 125.19233 -404.578606)
			(xy 125.15438 -404.634193) (xy 125.132592 -404.659846) (xy 125.126792 -404.666989) (xy 125.12028 -404.684181)
			(xy 125.119892 -404.693374) (xy 125.119892 -405.186642) (xy 125.120284 -405.195831) (xy 125.12681 -405.213015)
			(xy 125.132592 -405.22017) (xy 125.154373 -405.245827) (xy 125.19232 -405.301414) (xy 125.223352 -405.361137)
			(xy 125.247023 -405.424141) (xy 125.262996 -405.489522) (xy 125.27104 -405.556343) (xy 125.271041 -405.623647)
			(xy 125.262998 -405.690469) (xy 125.247026 -405.755851) (xy 125.223355 -405.818855) (xy 125.192325 -405.878578)
			(xy 125.154378 -405.934165) (xy 125.132592 -405.959818) (xy 125.126804 -405.96697) (xy 125.120285 -405.984155)
			(xy 125.119892 -405.993346) (xy 125.119892 -406.151334) (xy 125.119395 -406.16149) (xy 125.111615 -406.180254)
			(xy 125.097251 -406.194617) (xy 125.078486 -406.202396) (xy 125.06833 -406.202896) (xy 124.35205 -406.202896)
			(xy 124.341886 -406.202396) (xy 124.323099 -406.194634) (xy 124.308713 -406.180272) (xy 124.30092 -406.161497)
			(xy 124.300488 -406.151334) (xy 124.300488 -405.993346) (xy 124.300059 -405.984161) (xy 124.293559 -405.966976)
			(xy 124.287788 -405.959818) (xy 124.265993 -405.934171) (xy 124.228041 -405.878585) (xy 124.197005 -405.818861)
			(xy 124.173331 -405.755856) (xy 124.157357 -405.690473) (xy 124.149312 -405.623649) (xy 123.020778 -405.623649)
			(xy 122.992181 -405.678682) (xy 122.954232 -405.734268) (xy 122.932444 -405.75992) (xy 122.92665 -405.767066)
			(xy 122.920135 -405.784256) (xy 122.919744 -405.793448) (xy 122.919744 -406.286716) (xy 122.920159 -406.295902)
			(xy 122.926671 -406.313086) (xy 122.932444 -406.320244) (xy 122.954201 -406.345922) (xy 122.992152 -406.401504)
			(xy 123.023187 -406.461224) (xy 123.046862 -406.524225) (xy 123.062838 -406.589605) (xy 123.070885 -406.656425)
			(xy 123.070888 -406.723727) (xy 123.070881 -406.723789) (xy 126.348926 -406.723789) (xy 126.348929 -406.656363)
			(xy 126.357008 -406.589421) (xy 126.373048 -406.52393) (xy 126.396818 -406.460832) (xy 126.427974 -406.401035)
			(xy 126.466069 -406.345401) (xy 126.487936 -406.319736) (xy 126.493747 -406.312601) (xy 126.500252 -406.295403)
			(xy 126.500636 -406.286208) (xy 126.500636 -405.793956) (xy 126.500239 -405.784768) (xy 126.493715 -405.767584)
			(xy 126.487936 -405.760428) (xy 126.466067 -405.734767) (xy 126.427976 -405.679132) (xy 126.396823 -405.619336)
			(xy 126.373058 -405.556239) (xy 126.357022 -405.490749) (xy 126.348945 -405.423809) (xy 126.348946 -405.356385)
			(xy 126.357023 -405.289445) (xy 126.37306 -405.223956) (xy 126.396826 -405.160859) (xy 126.427979 -405.101062)
			(xy 126.466071 -405.045429) (xy 126.487936 -405.019764) (xy 126.493735 -405.012621) (xy 126.500247 -404.995429)
			(xy 126.500636 -404.986236) (xy 126.500636 -404.828756) (xy 126.50105 -404.81864) (xy 126.508809 -404.799954)
			(xy 126.523128 -404.785659) (xy 126.541827 -404.777933) (xy 126.551944 -404.777448) (xy 127.268224 -404.777448)
			(xy 127.278328 -404.777964) (xy 127.296997 -404.7857) (xy 127.311289 -404.799986) (xy 127.319032 -404.818652)
			(xy 127.319532 -404.828756) (xy 127.319532 -404.986236) (xy 127.31994 -404.995423) (xy 127.326457 -405.012607)
			(xy 127.332232 -405.019764) (xy 127.354091 -405.045433) (xy 127.392178 -405.101068) (xy 127.423327 -405.160864)
			(xy 127.44709 -405.22396) (xy 127.463125 -405.289448) (xy 127.4712 -405.356386) (xy 127.471201 -405.423808)
			(xy 127.463126 -405.490746) (xy 127.447092 -405.556234) (xy 127.423329 -405.619331) (xy 127.42108 -405.623649)
			(xy 128.549103 -405.623649) (xy 128.549104 -405.556342) (xy 128.557149 -405.489519) (xy 128.573124 -405.424136)
			(xy 128.596799 -405.361131) (xy 128.627835 -405.301407) (xy 128.665787 -405.245822) (xy 128.687576 -405.22017)
			(xy 128.693365 -405.213019) (xy 128.699885 -405.195833) (xy 128.700276 -405.186642) (xy 128.700276 -404.693374)
			(xy 128.699884 -404.684185) (xy 128.693358 -404.667) (xy 128.687576 -404.659846) (xy 128.665809 -404.634177)
			(xy 128.627857 -404.578593) (xy 128.596821 -404.518873) (xy 128.573145 -404.45587) (xy 128.557169 -404.39049)
			(xy 128.549123 -404.323669) (xy 128.549121 -404.256365) (xy 128.557164 -404.189543) (xy 128.573135 -404.124161)
			(xy 128.596807 -404.061158) (xy 128.62784 -404.001435) (xy 128.665789 -403.94585) (xy 128.687576 -403.920198)
			(xy 128.693353 -403.913039) (xy 128.69988 -403.895859) (xy 128.700276 -403.88667) (xy 128.700276 -403.728682)
			(xy 128.70065 -403.718505) (xy 128.708448 -403.699702) (xy 128.722849 -403.685317) (xy 128.74166 -403.677539)
			(xy 128.751838 -403.67712) (xy 129.468118 -403.67712) (xy 129.478275 -403.677618) (xy 129.497041 -403.685395)
			(xy 129.511405 -403.699759) (xy 129.519182 -403.718525) (xy 129.51968 -403.728682) (xy 129.51968 -403.88667)
			(xy 129.520109 -403.895855) (xy 129.52661 -403.913039) (xy 129.53238 -403.920198) (xy 129.554189 -403.945833)
			(xy 129.592136 -404.001422) (xy 129.623167 -404.061148) (xy 129.646838 -404.124155) (xy 129.662809 -404.189539)
			(xy 129.670851 -404.256363) (xy 129.670849 -404.32367) (xy 129.662803 -404.390494) (xy 129.646828 -404.455877)
			(xy 129.623154 -404.518882) (xy 129.592119 -404.578606) (xy 129.554169 -404.634194) (xy 129.53238 -404.659846)
			(xy 129.526579 -404.666988) (xy 129.520068 -404.684181) (xy 129.51968 -404.693374) (xy 129.51968 -405.186642)
			(xy 129.520074 -405.195831) (xy 129.5266 -405.213015) (xy 129.53238 -405.22017) (xy 129.554161 -405.245827)
			(xy 129.592109 -405.301413) (xy 129.623142 -405.361136) (xy 129.646814 -405.42414) (xy 129.662787 -405.489522)
			(xy 129.670831 -405.556343) (xy 129.670832 -405.623648) (xy 129.662788 -405.690469) (xy 129.646817 -405.755851)
			(xy 129.623145 -405.818855) (xy 129.592114 -405.878579) (xy 129.554167 -405.934166) (xy 129.53238 -405.959818)
			(xy 129.526591 -405.966968) (xy 129.520072 -405.984155) (xy 129.51968 -405.993346) (xy 129.51968 -406.151334)
			(xy 129.519195 -406.161492) (xy 129.511413 -406.180258) (xy 129.497045 -406.194622) (xy 129.478276 -406.202398)
			(xy 129.468118 -406.202896) (xy 128.751838 -406.202896) (xy 128.741673 -406.202406) (xy 128.722886 -406.19464)
			(xy 128.708501 -406.180275) (xy 128.700708 -406.161498) (xy 128.700276 -406.151334) (xy 128.700276 -405.993346)
			(xy 128.699849 -405.984161) (xy 128.693347 -405.966976) (xy 128.687576 -405.959818) (xy 128.665781 -405.934171)
			(xy 128.62783 -405.878585) (xy 128.596795 -405.818861) (xy 128.573121 -405.755856) (xy 128.557148 -405.690472)
			(xy 128.549103 -405.623649) (xy 127.42108 -405.623649) (xy 127.392181 -405.679127) (xy 127.354095 -405.734762)
			(xy 127.332232 -405.760428) (xy 127.326433 -405.767571) (xy 127.319922 -405.784763) (xy 127.319532 -405.793956)
			(xy 127.319532 -406.286208) (xy 127.319954 -406.295394) (xy 127.326461 -406.312577) (xy 127.332232 -406.319736)
			(xy 127.354063 -406.345428) (xy 127.392151 -406.401059) (xy 127.423301 -406.460852) (xy 127.447066 -406.523945)
			(xy 127.463103 -406.589431) (xy 127.471181 -406.656366) (xy 127.471183 -406.72373) (xy 130.749245 -406.72373)
			(xy 130.749248 -406.656422) (xy 130.757295 -406.589598) (xy 130.773271 -406.524214) (xy 130.796947 -406.461208)
			(xy 130.827983 -406.401484) (xy 130.865935 -406.345896) (xy 130.887724 -406.320244) (xy 130.89353 -406.313105)
			(xy 130.900038 -406.29591) (xy 130.900424 -406.286716) (xy 130.900424 -405.793448) (xy 130.899985 -405.784264)
			(xy 130.893491 -405.76708) (xy 130.887724 -405.75992) (xy 130.865933 -405.734271) (xy 130.827985 -405.678684)
			(xy 130.796953 -405.61896) (xy 130.773281 -405.555955) (xy 130.757309 -405.490572) (xy 130.749265 -405.42375)
			(xy 130.749265 -405.356444) (xy 130.75731 -405.289622) (xy 130.773283 -405.22424) (xy 130.796955 -405.161235)
			(xy 130.827988 -405.101511) (xy 130.865936 -405.045924) (xy 130.887724 -405.020272) (xy 130.893518 -405.013125)
			(xy 130.900033 -404.995936) (xy 130.900424 -404.986744) (xy 130.900424 -404.828756) (xy 130.900786 -404.818596)
			(xy 130.908601 -404.799838) (xy 130.923016 -404.785515) (xy 130.941823 -404.777822) (xy 130.951986 -404.777448)
			(xy 131.668266 -404.777448) (xy 131.678391 -404.777955) (xy 131.697113 -404.785673) (xy 131.711471 -404.799953)
			(xy 131.71929 -404.818633) (xy 131.719828 -404.828756) (xy 131.719828 -404.986744) (xy 131.720211 -404.995934)
			(xy 131.726743 -405.013119) (xy 131.732528 -405.020272) (xy 131.754313 -405.045927) (xy 131.792264 -405.101512)
			(xy 131.823299 -405.161235) (xy 131.846974 -405.224239) (xy 131.862948 -405.289622) (xy 131.870993 -405.356444)
			(xy 131.870993 -405.42375) (xy 131.862949 -405.490573) (xy 131.846975 -405.555955) (xy 131.823302 -405.618959)
			(xy 131.792267 -405.678683) (xy 131.754316 -405.734268) (xy 131.732528 -405.75992) (xy 131.726732 -405.767065)
			(xy 131.720219 -405.784256) (xy 131.719828 -405.793448) (xy 131.719828 -406.286716) (xy 131.720224 -406.295905)
			(xy 131.726747 -406.313089) (xy 131.732528 -406.320244) (xy 131.754285 -406.345922) (xy 131.792237 -406.401504)
			(xy 131.823274 -406.461223) (xy 131.84695 -406.524225) (xy 131.862926 -406.589604) (xy 131.870973 -406.656424)
			(xy 131.870976 -406.723728) (xy 131.862934 -406.790548) (xy 131.846964 -406.855929) (xy 131.823293 -406.918933)
			(xy 131.792262 -406.978655) (xy 131.754315 -407.03424) (xy 131.732528 -407.059892) (xy 131.726744 -407.067045)
			(xy 131.720224 -407.08423) (xy 131.719828 -407.09342) (xy 131.719828 -407.251408) (xy 131.719385 -407.261559)
			(xy 131.711592 -407.280306) (xy 131.697203 -407.294628) (xy 131.678419 -407.302333) (xy 131.668266 -407.302716)
			(xy 130.951986 -407.302716) (xy 130.941853 -407.302283) (xy 130.923123 -407.294543) (xy 130.908766 -407.28024)
			(xy 130.900955 -407.261539) (xy 130.900424 -407.251408) (xy 130.900424 -407.09342) (xy 130.899999 -407.084235)
			(xy 130.893495 -407.06705) (xy 130.887724 -407.059892) (xy 130.865905 -407.034266) (xy 130.827958 -406.978675)
			(xy 130.796927 -406.918948) (xy 130.773257 -406.85594) (xy 130.757287 -406.790555) (xy 130.749245 -406.72373)
			(xy 127.471183 -406.72373) (xy 127.471183 -406.723786) (xy 127.463111 -406.790722) (xy 127.44708 -406.856209)
			(xy 127.423321 -406.919304) (xy 127.392176 -406.9791) (xy 127.354093 -407.034734) (xy 127.332232 -407.0604)
			(xy 127.326445 -407.067551) (xy 127.319926 -407.084737) (xy 127.319532 -407.093928) (xy 127.319532 -407.251408)
			(xy 127.319022 -407.261513) (xy 127.311288 -407.280185) (xy 127.296999 -407.294479) (xy 127.278329 -407.302219)
			(xy 127.268224 -407.302716) (xy 126.551944 -407.302716) (xy 126.541826 -407.302248) (xy 126.523127 -407.294518)
			(xy 126.508812 -407.280217) (xy 126.501062 -407.261525) (xy 126.500636 -407.251408) (xy 126.500636 -407.093928)
			(xy 126.500204 -407.084743) (xy 126.493705 -407.067559) (xy 126.487936 -407.0604) (xy 126.466039 -407.034761)
			(xy 126.427949 -406.979124) (xy 126.396798 -406.919324) (xy 126.373034 -406.856224) (xy 126.357 -406.790731)
			(xy 126.348926 -406.723789) (xy 123.070881 -406.723789) (xy 123.062847 -406.790548) (xy 123.046877 -406.855929)
			(xy 123.023207 -406.918932) (xy 122.992176 -406.978654) (xy 122.95423 -407.03424) (xy 122.932444 -407.059892)
			(xy 122.926661 -407.067047) (xy 122.92014 -407.08423) (xy 122.919744 -407.09342) (xy 122.919744 -407.251408)
			(xy 122.919222 -407.261512) (xy 122.91149 -407.280182) (xy 122.897205 -407.294475) (xy 122.878539 -407.302217)
			(xy 122.868436 -407.302716) (xy 122.151902 -407.302716) (xy 122.14177 -407.30227) (xy 122.123041 -407.294535)
			(xy 122.108683 -407.280236) (xy 122.100871 -407.261538) (xy 122.10034 -407.251408) (xy 122.10034 -407.09342)
			(xy 122.099911 -407.084235) (xy 122.09341 -407.067051) (xy 122.08764 -407.059892) (xy 122.065821 -407.034266)
			(xy 122.027873 -406.978676) (xy 121.996841 -406.918949) (xy 121.97317 -406.855941) (xy 121.957199 -406.790555)
			(xy 121.949157 -406.72373) (xy 118.67112 -406.72373) (xy 118.67112 -406.723787) (xy 118.663047 -406.790724)
			(xy 118.647013 -406.856212) (xy 118.62325 -406.919308) (xy 118.5921 -406.979103) (xy 118.554012 -407.034736)
			(xy 118.532148 -407.0604) (xy 118.526362 -407.067553) (xy 118.519843 -407.084738) (xy 118.519448 -407.093928)
			(xy 118.519448 -407.251408) (xy 118.518922 -407.261511) (xy 118.511191 -407.28018) (xy 118.496907 -407.294473)
			(xy 118.478243 -407.302216) (xy 118.46814 -407.302716) (xy 117.75186 -407.302716) (xy 117.741751 -407.302248)
			(xy 117.723075 -407.2945) (xy 117.708782 -407.280198) (xy 117.701046 -407.261518) (xy 117.700552 -407.251408)
			(xy 117.700552 -407.093928) (xy 117.700117 -407.084744) (xy 117.693619 -407.06756) (xy 117.687852 -407.0604)
			(xy 117.665955 -407.034762) (xy 117.627864 -406.979124) (xy 117.596711 -406.919325) (xy 117.572947 -406.856225)
			(xy 117.556912 -406.790732) (xy 117.548838 -406.72379) (xy 92.270826 -406.72379) (xy 92.262793 -406.790546)
			(xy 92.246825 -406.855926) (xy 92.223158 -406.918929) (xy 92.192131 -406.978652) (xy 92.154188 -407.034239)
			(xy 92.132404 -407.059892) (xy 92.126629 -407.067052) (xy 92.120101 -407.084231) (xy 92.119704 -407.09342)
			(xy 92.119704 -407.251408) (xy 92.119285 -407.261562) (xy 92.111487 -407.280314) (xy 92.09709 -407.294637)
			(xy 92.078298 -407.302337) (xy 92.068142 -407.302716) (xy 91.351862 -407.302716) (xy 91.341727 -407.302303)
			(xy 91.322997 -407.294555) (xy 91.308641 -407.280246) (xy 91.30083 -407.261541) (xy 91.3003 -407.251408)
			(xy 91.3003 -407.09342) (xy 91.29988 -407.084234) (xy 91.293373 -407.067049) (xy 91.2876 -407.059892)
			(xy 91.265782 -407.034265) (xy 91.227837 -406.978674) (xy 91.196807 -406.918947) (xy 91.173138 -406.855939)
			(xy 91.157168 -406.790554) (xy 91.149127 -406.723729) (xy 87.871065 -406.723729) (xy 87.871065 -406.723786)
			(xy 87.862993 -406.790722) (xy 87.846961 -406.85621) (xy 87.823201 -406.919305) (xy 87.792054 -406.9791)
			(xy 87.75397 -407.034735) (xy 87.732108 -407.0604) (xy 87.72633 -407.067558) (xy 87.719804 -407.084739)
			(xy 87.719408 -407.093928) (xy 87.719408 -407.251408) (xy 87.718921 -407.261516) (xy 87.711183 -407.280193)
			(xy 87.696886 -407.294487) (xy 87.678208 -407.302223) (xy 87.6681 -407.302716) (xy 86.95182 -407.302716)
			(xy 86.941701 -407.302268) (xy 86.923001 -407.29453) (xy 86.908686 -407.280223) (xy 86.900937 -407.261527)
			(xy 86.900512 -407.251408) (xy 86.900512 -407.093928) (xy 86.900086 -407.084743) (xy 86.893583 -407.067558)
			(xy 86.887812 -407.0604) (xy 86.865916 -407.034761) (xy 86.827828 -406.979123) (xy 86.796678 -406.919323)
			(xy 86.772915 -406.856223) (xy 86.756881 -406.790731) (xy 86.748808 -406.723789) (xy 83.470763 -406.723789)
			(xy 83.462728 -406.790549) (xy 83.446757 -406.85593) (xy 83.423086 -406.918933) (xy 83.392055 -406.978655)
			(xy 83.354107 -407.03424) (xy 83.33232 -407.059892) (xy 83.326547 -407.067054) (xy 83.320017 -407.084231)
			(xy 83.31962 -407.09342) (xy 83.31962 -407.251408) (xy 83.319185 -407.26156) (xy 83.311391 -407.280309)
			(xy 83.296998 -407.294631) (xy 83.278212 -407.302334) (xy 83.268058 -407.302716) (xy 82.551778 -407.302716)
			(xy 82.541644 -407.30229) (xy 82.522914 -407.294547) (xy 82.508557 -407.280242) (xy 82.500747 -407.26154)
			(xy 82.500216 -407.251408) (xy 82.500216 -407.09342) (xy 82.499792 -407.084234) (xy 82.493288 -407.06705)
			(xy 82.487516 -407.059892) (xy 82.465698 -407.034265) (xy 82.427751 -406.978675) (xy 82.396721 -406.918947)
			(xy 82.373051 -406.85594) (xy 82.35708 -406.790555) (xy 82.349039 -406.72373) (xy 79.070977 -406.72373)
			(xy 79.070977 -406.723786) (xy 79.062905 -406.790722) (xy 79.046874 -406.856209) (xy 79.023114 -406.919304)
			(xy 78.991969 -406.9791) (xy 78.953885 -407.034734) (xy 78.932024 -407.0604) (xy 78.926248 -407.06756)
			(xy 78.91972 -407.084739) (xy 78.919324 -407.093928) (xy 78.919324 -407.251408) (xy 78.918822 -407.261514)
			(xy 78.911086 -407.280188) (xy 78.896795 -407.294482) (xy 78.878122 -407.30222) (xy 78.868016 -407.302716)
			(xy 78.151736 -407.302716) (xy 78.141618 -407.302255) (xy 78.122918 -407.294521) (xy 78.108603 -407.280219)
			(xy 78.100854 -407.261526) (xy 78.100428 -407.251408) (xy 78.100428 -407.093928) (xy 78.099998 -407.084743)
			(xy 78.093497 -407.067559) (xy 78.087728 -407.0604) (xy 78.065832 -407.034761) (xy 78.027742 -406.979124)
			(xy 77.996591 -406.919324) (xy 77.972828 -406.856224) (xy 77.956793 -406.790731) (xy 77.94872 -406.723789)
			(xy 74.670675 -406.723789) (xy 74.662641 -406.790548) (xy 74.64667 -406.855929) (xy 74.623 -406.918932)
			(xy 74.591969 -406.978655) (xy 74.554022 -407.03424) (xy 74.532236 -407.059892) (xy 74.526453 -407.067046)
			(xy 74.519932 -407.08423) (xy 74.519536 -407.09342) (xy 74.519536 -407.251408) (xy 74.519085 -407.261558)
			(xy 74.511294 -407.280304) (xy 74.496907 -407.294625) (xy 74.478126 -407.302331) (xy 74.467974 -407.302716)
			(xy 73.751694 -407.302716) (xy 73.741562 -407.302277) (xy 73.722832 -407.294539) (xy 73.708474 -407.280238)
			(xy 73.700663 -407.261538) (xy 73.700132 -407.251408) (xy 73.700132 -407.09342) (xy 73.699705 -407.084235)
			(xy 73.693202 -407.067051) (xy 73.687432 -407.059892) (xy 73.665613 -407.034266) (xy 73.627666 -406.978675)
			(xy 73.596634 -406.918948) (xy 73.572963 -406.85594) (xy 73.556993 -406.790555) (xy 73.548951 -406.72373)
			(xy 66.525648 -406.72373) (xy 66.525648 -409.523886) (xy 71.34879 -409.523886) (xy 71.348793 -409.45646)
			(xy 71.356872 -409.389519) (xy 71.372911 -409.324028) (xy 71.396679 -409.26093) (xy 71.427834 -409.201133)
			(xy 71.465926 -409.145497) (xy 71.487792 -409.119832) (xy 71.493599 -409.112694) (xy 71.500108 -409.095498)
			(xy 71.500492 -409.086304) (xy 71.500492 -408.594052) (xy 71.500059 -408.584867) (xy 71.493561 -408.567682)
			(xy 71.487792 -408.560524) (xy 71.46592 -408.534865) (xy 71.427833 -408.479229) (xy 71.396683 -408.419432)
			(xy 71.372919 -408.356335) (xy 71.356885 -408.290845) (xy 71.348809 -408.223906) (xy 71.34881 -408.156482)
			(xy 71.356887 -408.089543) (xy 71.372923 -408.024054) (xy 71.396688 -407.960957) (xy 71.427839 -407.90116)
			(xy 71.465928 -407.845525) (xy 71.487792 -407.81986) (xy 71.493587 -407.812714) (xy 71.500103 -407.795524)
			(xy 71.500492 -407.786332) (xy 71.500492 -407.628852) (xy 71.500946 -407.618741) (xy 71.508698 -407.600063)
			(xy 71.523004 -407.585771) (xy 71.541689 -407.578036) (xy 71.5518 -407.577544) (xy 72.26808 -407.577544)
			(xy 72.278181 -407.5781) (xy 72.296848 -407.585821) (xy 72.311141 -407.600095) (xy 72.318887 -407.618752)
			(xy 72.319388 -407.628852) (xy 72.319388 -407.786332) (xy 72.319785 -407.795521) (xy 72.326308 -407.812705)
			(xy 72.332088 -407.81986) (xy 72.353945 -407.845532) (xy 72.392034 -407.901165) (xy 72.423186 -407.96096)
			(xy 72.446951 -408.024056) (xy 72.462988 -408.089545) (xy 72.471064 -408.156482) (xy 72.471065 -408.223906)
			(xy 72.46299 -408.290844) (xy 72.446955 -408.356332) (xy 72.423191 -408.419429) (xy 72.39204 -408.479225)
			(xy 72.353952 -408.534859) (xy 72.332088 -408.560524) (xy 72.326297 -408.567673) (xy 72.31978 -408.584861)
			(xy 72.319388 -408.594052) (xy 72.319388 -409.086304) (xy 72.319799 -409.095491) (xy 72.326313 -409.112675)
			(xy 72.332088 -409.119832) (xy 72.353917 -409.145526) (xy 72.392008 -409.201156) (xy 72.423161 -409.260948)
			(xy 72.446927 -409.324042) (xy 72.462966 -409.389527) (xy 72.471045 -409.456462) (xy 72.471048 -409.523884)
			(xy 72.462975 -409.59082) (xy 72.446943 -409.656307) (xy 72.423183 -409.719402) (xy 72.392035 -409.779197)
			(xy 72.35395 -409.834831) (xy 72.332088 -409.860496) (xy 72.326309 -409.867654) (xy 72.319784 -409.884835)
			(xy 72.319388 -409.894024) (xy 72.319388 -410.051504) (xy 72.318987 -410.061628) (xy 72.311235 -410.080334)
			(xy 72.296914 -410.094649) (xy 72.278204 -410.102392) (xy 72.26808 -410.102812) (xy 71.5518 -410.102812)
			(xy 71.541693 -410.102315) (xy 71.523017 -410.09458) (xy 71.508723 -410.080286) (xy 71.500986 -410.061611)
			(xy 71.500492 -410.051504) (xy 71.500492 -409.894024) (xy 71.500072 -409.884838) (xy 71.493565 -409.867653)
			(xy 71.487792 -409.860496) (xy 71.465893 -409.83486) (xy 71.427806 -409.779221) (xy 71.396657 -409.719421)
			(xy 71.372895 -409.65632) (xy 71.356863 -409.590827) (xy 71.34879 -409.523886) (xy 66.525648 -409.523886)
			(xy 66.525648 -410.623641) (xy 73.548963 -410.623641) (xy 73.548964 -410.556335) (xy 73.55701 -410.489511)
			(xy 73.572984 -410.424128) (xy 73.596658 -410.361123) (xy 73.627693 -410.301399) (xy 73.665643 -410.245812)
			(xy 73.687432 -410.22016) (xy 73.693232 -410.213017) (xy 73.699744 -410.195825) (xy 73.700132 -410.186632)
			(xy 73.700132 -409.693364) (xy 73.699732 -409.684176) (xy 73.69321 -409.666992) (xy 73.687432 -409.659836)
			(xy 73.665656 -409.634174) (xy 73.627707 -409.578589) (xy 73.596674 -409.518867) (xy 73.573001 -409.455863)
			(xy 73.557027 -409.390482) (xy 73.548982 -409.323661) (xy 73.548981 -409.256357) (xy 73.557024 -409.189535)
			(xy 73.572995 -409.124154) (xy 73.596667 -409.06115) (xy 73.627698 -409.001427) (xy 73.665645 -408.94584)
			(xy 73.687432 -408.920188) (xy 73.69322 -408.913037) (xy 73.699739 -408.895851) (xy 73.700132 -408.88666)
			(xy 73.700132 -408.728672) (xy 73.700499 -408.718512) (xy 73.70831 -408.699753) (xy 73.722724 -408.685429)
			(xy 73.741532 -408.677736) (xy 73.751694 -408.677364) (xy 74.467974 -408.677364) (xy 74.478102 -408.677848)
			(xy 74.496827 -408.685572) (xy 74.511185 -408.69986) (xy 74.519001 -408.718546) (xy 74.519536 -408.728672)
			(xy 74.519536 -408.88666) (xy 74.51998 -408.895843) (xy 74.526472 -408.913027) (xy 74.532236 -408.920188)
			(xy 74.554036 -408.94583) (xy 74.591986 -409.001418) (xy 74.62302 -409.061142) (xy 74.646694 -409.124148)
			(xy 74.662666 -409.189532) (xy 74.67071 -409.256356) (xy 74.670709 -409.323662) (xy 74.662663 -409.390486)
			(xy 74.646688 -409.455869) (xy 74.623013 -409.518874) (xy 74.620439 -409.523827) (xy 75.749085 -409.523827)
			(xy 75.749088 -409.456519) (xy 75.757137 -409.389693) (xy 75.773115 -409.324308) (xy 75.796793 -409.261302)
			(xy 75.827833 -409.201578) (xy 75.865789 -409.145992) (xy 75.88758 -409.12034) (xy 75.893382 -409.113199)
			(xy 75.899894 -409.096005) (xy 75.90028 -409.086812) (xy 75.90028 -408.593544) (xy 75.899853 -408.584358)
			(xy 75.893352 -408.567174) (xy 75.88758 -408.560016) (xy 75.865783 -408.534371) (xy 75.827832 -408.478784)
			(xy 75.796797 -408.41906) (xy 75.773123 -408.356055) (xy 75.757149 -408.290671) (xy 75.749105 -408.223847)
			(xy 75.749106 -408.156541) (xy 75.757151 -408.089717) (xy 75.773126 -408.024334) (xy 75.796802 -407.961329)
			(xy 75.827838 -407.901605) (xy 75.865791 -407.84602) (xy 75.88758 -407.820368) (xy 75.89337 -407.813218)
			(xy 75.899889 -407.796031) (xy 75.90028 -407.78684) (xy 75.90028 -407.628852) (xy 75.900682 -407.618697)
			(xy 75.90849 -407.599948) (xy 75.922892 -407.585627) (xy 75.941685 -407.577925) (xy 75.951842 -407.577544)
			(xy 76.668122 -407.577544) (xy 76.678251 -407.578008) (xy 76.696973 -407.585744) (xy 76.711329 -407.600037)
			(xy 76.719147 -407.618726) (xy 76.719684 -407.628852) (xy 76.719684 -407.78684) (xy 76.720078 -407.796029)
			(xy 76.726603 -407.813213) (xy 76.732384 -407.820368) (xy 76.754163 -407.846027) (xy 76.792111 -407.901613)
			(xy 76.823143 -407.961336) (xy 76.846815 -408.024339) (xy 76.862788 -408.08972) (xy 76.870833 -408.156542)
			(xy 76.870833 -408.223846) (xy 76.86279 -408.290668) (xy 76.846819 -408.356049) (xy 76.823148 -408.419053)
			(xy 76.792117 -408.478777) (xy 76.754171 -408.534364) (xy 76.732384 -408.560016) (xy 76.726596 -408.567167)
			(xy 76.720077 -408.584353) (xy 76.719684 -408.593544) (xy 76.719684 -409.086812) (xy 76.720092 -409.095999)
			(xy 76.726607 -409.113184) (xy 76.732384 -409.12034) (xy 76.754135 -409.146022) (xy 76.792084 -409.201605)
			(xy 76.823117 -409.261324) (xy 76.846791 -409.324325) (xy 76.862766 -409.389703) (xy 76.870812 -409.456522)
			(xy 76.870816 -409.523824) (xy 76.862775 -409.590644) (xy 76.846807 -409.656023) (xy 76.823139 -409.719026)
			(xy 76.792112 -409.778749) (xy 76.754169 -409.834335) (xy 76.732384 -409.859988) (xy 76.726566 -409.867118)
			(xy 76.720065 -409.88432) (xy 76.719684 -409.893516) (xy 76.719684 -410.051504) (xy 76.719281 -410.06166)
			(xy 76.711481 -410.080416) (xy 76.697079 -410.09474) (xy 76.678281 -410.102436) (xy 76.668122 -410.102812)
			(xy 75.951842 -410.102812) (xy 75.941724 -410.10224) (xy 75.923014 -410.094536) (xy 75.908658 -410.080276)
			(xy 75.900828 -410.061618) (xy 75.90028 -410.051504) (xy 75.90028 -409.893516) (xy 75.899867 -409.884329)
			(xy 75.893356 -409.867144) (xy 75.88758 -409.859988) (xy 75.865756 -409.834365) (xy 75.827805 -409.778776)
			(xy 75.796771 -409.719048) (xy 75.773099 -409.65604) (xy 75.757127 -409.590654) (xy 75.749085 -409.523827)
			(xy 74.620439 -409.523827) (xy 74.591977 -409.578598) (xy 74.554025 -409.634184) (xy 74.532236 -409.659836)
			(xy 74.526434 -409.666977) (xy 74.519924 -409.684171) (xy 74.519536 -409.693364) (xy 74.519536 -410.186632)
			(xy 74.519945 -410.195819) (xy 74.526461 -410.213002) (xy 74.532236 -410.22016) (xy 74.554009 -410.245825)
			(xy 74.59196 -410.301409) (xy 74.622995 -410.36113) (xy 74.64667 -410.424133) (xy 74.662644 -410.489514)
			(xy 74.67069 -410.556336) (xy 74.670692 -410.62364) (xy 74.670685 -410.623701) (xy 77.948731 -410.623701)
			(xy 77.948732 -410.556275) (xy 77.95681 -410.489335) (xy 77.972848 -410.423845) (xy 77.996615 -410.360747)
			(xy 78.02777 -410.300951) (xy 78.065862 -410.245317) (xy 78.087728 -410.219652) (xy 78.093531 -410.212512)
			(xy 78.100041 -410.195317) (xy 78.100428 -410.186124) (xy 78.100428 -409.693872) (xy 78.100025 -409.684684)
			(xy 78.093506 -409.6675) (xy 78.087728 -409.660344) (xy 78.065875 -409.63467) (xy 78.027784 -409.579037)
			(xy 77.996631 -409.519242) (xy 77.972865 -409.456147) (xy 77.956828 -409.390658) (xy 77.948751 -409.323721)
			(xy 77.94875 -409.256297) (xy 77.956825 -409.189359) (xy 77.97286 -409.123871) (xy 77.996624 -409.060774)
			(xy 78.027775 -409.000979) (xy 78.065864 -408.945345) (xy 78.087728 -408.91968) (xy 78.093519 -408.912531)
			(xy 78.100036 -408.895343) (xy 78.100428 -408.886152) (xy 78.100428 -408.728672) (xy 78.100794 -408.718544)
			(xy 78.108556 -408.699835) (xy 78.122888 -408.68552) (xy 78.141608 -408.677781) (xy 78.151736 -408.677364)
			(xy 78.868016 -408.677364) (xy 78.878121 -408.677871) (xy 78.896793 -408.685608) (xy 78.911086 -408.699897)
			(xy 78.918826 -408.718567) (xy 78.919324 -408.728672) (xy 78.919324 -408.886152) (xy 78.919752 -408.895337)
			(xy 78.926253 -408.912522) (xy 78.932024 -408.91968) (xy 78.953899 -408.945336) (xy 78.991986 -409.000972)
			(xy 79.023135 -409.06077) (xy 79.046897 -409.123868) (xy 79.062931 -409.189358) (xy 79.071005 -409.256297)
			(xy 79.071004 -409.323721) (xy 79.062928 -409.39066) (xy 79.046892 -409.456149) (xy 79.023127 -409.519246)
			(xy 79.02071 -409.523886) (xy 80.148878 -409.523886) (xy 80.148881 -409.45646) (xy 80.15696 -409.38952)
			(xy 80.172999 -409.324029) (xy 80.196766 -409.260931) (xy 80.227919 -409.201133) (xy 80.266011 -409.145498)
			(xy 80.287876 -409.119832) (xy 80.293681 -409.112693) (xy 80.300191 -409.095498) (xy 80.300576 -409.086304)
			(xy 80.300576 -408.594052) (xy 80.300146 -408.584867) (xy 80.293647 -408.567682) (xy 80.287876 -408.560524)
			(xy 80.266005 -408.534865) (xy 80.227918 -408.479229) (xy 80.196769 -408.419432) (xy 80.173006 -408.356334)
			(xy 80.156972 -408.290844) (xy 80.148897 -408.223906) (xy 80.148898 -408.156482) (xy 80.156974 -408.089544)
			(xy 80.17301 -408.024055) (xy 80.196774 -407.960957) (xy 80.227924 -407.901161) (xy 80.266012 -407.845526)
			(xy 80.287876 -407.81986) (xy 80.293669 -407.812712) (xy 80.300187 -407.795524) (xy 80.300576 -407.786332)
			(xy 80.300576 -407.628852) (xy 80.301045 -407.618743) (xy 80.308794 -407.600069) (xy 80.323095 -407.585776)
			(xy 80.341775 -407.578039) (xy 80.351884 -407.577544) (xy 81.068164 -407.577544) (xy 81.078264 -407.578113)
			(xy 81.09693 -407.585829) (xy 81.111224 -407.600099) (xy 81.11897 -407.618753) (xy 81.119472 -407.628852)
			(xy 81.119472 -407.786332) (xy 81.119873 -407.79552) (xy 81.126394 -407.812704) (xy 81.132172 -407.81986)
			(xy 81.154029 -407.845531) (xy 81.19212 -407.901164) (xy 81.223273 -407.960959) (xy 81.247038 -408.024056)
			(xy 81.263075 -408.089544) (xy 81.271152 -408.156482) (xy 81.271153 -408.223906) (xy 81.263077 -408.290844)
			(xy 81.247042 -408.356333) (xy 81.223277 -408.41943) (xy 81.192126 -408.479225) (xy 81.154036 -408.534859)
			(xy 81.132172 -408.560524) (xy 81.126379 -408.567672) (xy 81.119863 -408.58486) (xy 81.119472 -408.594052)
			(xy 81.119472 -409.086304) (xy 81.119886 -409.095491) (xy 81.126398 -409.112675) (xy 81.132172 -409.119832)
			(xy 81.154002 -409.145526) (xy 81.192093 -409.201156) (xy 81.223247 -409.260948) (xy 81.247014 -409.324041)
			(xy 81.263053 -409.389527) (xy 81.271132 -409.456462) (xy 81.271136 -409.523884) (xy 81.263063 -409.59082)
			(xy 81.247031 -409.656307) (xy 81.223269 -409.719403) (xy 81.192121 -409.779198) (xy 81.154035 -409.834831)
			(xy 81.132172 -409.860496) (xy 81.126391 -409.867652) (xy 81.119868 -409.884834) (xy 81.119472 -409.894024)
			(xy 81.119472 -410.051504) (xy 81.119086 -410.06163) (xy 81.111332 -410.080339) (xy 81.097006 -410.094654)
			(xy 81.078291 -410.102394) (xy 81.068164 -410.102812) (xy 80.351884 -410.102812) (xy 80.341776 -410.102328)
			(xy 80.3231 -410.094587) (xy 80.308806 -410.08029) (xy 80.30107 -410.061612) (xy 80.300576 -410.051504)
			(xy 80.300576 -409.894024) (xy 80.30016 -409.884837) (xy 80.293651 -409.867653) (xy 80.287876 -409.860496)
			(xy 80.265978 -409.83486) (xy 80.227891 -409.77922) (xy 80.196744 -409.71942) (xy 80.172983 -409.656319)
			(xy 80.15695 -409.590827) (xy 80.148878 -409.523886) (xy 79.02071 -409.523886) (xy 78.991976 -409.579043)
			(xy 78.953888 -409.634678) (xy 78.932024 -409.660344) (xy 78.926229 -409.667491) (xy 78.919713 -409.68468)
			(xy 78.919324 -409.693872) (xy 78.919324 -410.186124) (xy 78.919717 -410.195313) (xy 78.926242 -410.212497)
			(xy 78.932024 -410.219652) (xy 78.953871 -410.245331) (xy 78.991959 -410.300964) (xy 79.023109 -410.360758)
			(xy 79.046873 -410.423853) (xy 79.062909 -410.489341) (xy 79.070986 -410.556277) (xy 79.070987 -410.623641)
			(xy 82.349051 -410.623641) (xy 82.349052 -410.556335) (xy 82.357097 -410.489512) (xy 82.373071 -410.424129)
			(xy 82.396745 -410.361124) (xy 82.427779 -410.3014) (xy 82.465728 -410.245812) (xy 82.487516 -410.22016)
			(xy 82.493314 -410.213016) (xy 82.499827 -410.195824) (xy 82.500216 -410.186632) (xy 82.500216 -409.693364)
			(xy 82.49982 -409.684175) (xy 82.493296 -409.666991) (xy 82.487516 -409.659836) (xy 82.465741 -409.634174)
			(xy 82.427793 -409.578588) (xy 82.39676 -409.518866) (xy 82.373088 -409.455863) (xy 82.357115 -409.390482)
			(xy 82.34907 -409.323661) (xy 82.349069 -409.256357) (xy 82.357112 -409.189536) (xy 82.373083 -409.124155)
			(xy 82.396753 -409.061151) (xy 82.427784 -409.001427) (xy 82.46573 -408.94584) (xy 82.487516 -408.920188)
			(xy 82.493302 -408.913035) (xy 82.499822 -408.89585) (xy 82.500216 -408.88666) (xy 82.500216 -408.728672)
			(xy 82.500599 -408.718514) (xy 82.508407 -408.699758) (xy 82.522815 -408.685435) (xy 82.541618 -408.677739)
			(xy 82.551778 -408.677364) (xy 83.268058 -408.677364) (xy 83.278185 -408.677862) (xy 83.29691 -408.68558)
			(xy 83.311268 -408.699864) (xy 83.319085 -408.718548) (xy 83.31962 -408.728672) (xy 83.31962 -408.88666)
			(xy 83.320045 -408.895846) (xy 83.326548 -408.913031) (xy 83.33232 -408.920188) (xy 83.354121 -408.94583)
			(xy 83.392072 -409.001417) (xy 83.423107 -409.061141) (xy 83.446781 -409.124147) (xy 83.462754 -409.189531)
			(xy 83.470798 -409.256356) (xy 83.470797 -409.323662) (xy 83.462751 -409.390487) (xy 83.446775 -409.45587)
			(xy 83.423099 -409.518875) (xy 83.420495 -409.523886) (xy 84.548669 -409.523886) (xy 84.548672 -409.45646)
			(xy 84.556751 -409.38952) (xy 84.572789 -409.324029) (xy 84.596556 -409.260931) (xy 84.627709 -409.201134)
			(xy 84.665799 -409.145498) (xy 84.687664 -409.119832) (xy 84.69348 -409.112701) (xy 84.699981 -409.095499)
			(xy 84.700364 -409.086304) (xy 84.700364 -408.594052) (xy 84.699915 -408.584869) (xy 84.693427 -408.567685)
			(xy 84.687664 -408.560524) (xy 84.665793 -408.534865) (xy 84.627707 -408.479228) (xy 84.596559 -408.419431)
			(xy 84.572797 -408.356334) (xy 84.556763 -408.290844) (xy 84.548688 -408.223906) (xy 84.548689 -408.156482)
			(xy 84.556765 -408.089544) (xy 84.5728 -408.024055) (xy 84.596564 -407.960958) (xy 84.627714 -407.901161)
			(xy 84.665801 -407.845526) (xy 84.687664 -407.81986) (xy 84.693468 -407.81272) (xy 84.699976 -407.795525)
			(xy 84.700364 -407.786332) (xy 84.700364 -407.628852) (xy 84.700845 -407.618745) (xy 84.708592 -407.600072)
			(xy 84.722889 -407.585781) (xy 84.741564 -407.578041) (xy 84.751672 -407.577544) (xy 85.467952 -407.577544)
			(xy 85.478051 -407.578123) (xy 85.496717 -407.585835) (xy 85.511012 -407.600102) (xy 85.518758 -407.618754)
			(xy 85.51926 -407.628852) (xy 85.51926 -407.786332) (xy 85.519664 -407.79552) (xy 85.526183 -407.812703)
			(xy 85.53196 -407.81986) (xy 85.553818 -407.845531) (xy 85.591909 -407.901164) (xy 85.623062 -407.960959)
			(xy 85.646829 -408.024055) (xy 85.662866 -408.089544) (xy 85.670943 -408.156482) (xy 85.670944 -408.223906)
			(xy 85.662868 -408.290844) (xy 85.646832 -408.356333) (xy 85.623067 -408.41943) (xy 85.591915 -408.479226)
			(xy 85.553825 -408.534859) (xy 85.53196 -408.560524) (xy 85.526166 -408.567671) (xy 85.519651 -408.58486)
			(xy 85.51926 -408.594052) (xy 85.51926 -409.086304) (xy 85.519677 -409.09549) (xy 85.526187 -409.112674)
			(xy 85.53196 -409.119832) (xy 85.55379 -409.145526) (xy 85.591882 -409.201155) (xy 85.623037 -409.260947)
			(xy 85.646805 -409.32404) (xy 85.662844 -409.389526) (xy 85.670923 -409.456462) (xy 85.670927 -409.523884)
			(xy 85.662854 -409.59082) (xy 85.646821 -409.656308) (xy 85.623059 -409.719403) (xy 85.59191 -409.779198)
			(xy 85.553823 -409.834831) (xy 85.53196 -409.860496) (xy 85.526178 -409.867651) (xy 85.519655 -409.884834)
			(xy 85.51926 -409.894024) (xy 85.51926 -410.051504) (xy 85.518886 -410.061632) (xy 85.511129 -410.080343)
			(xy 85.496799 -410.094659) (xy 85.47808 -410.102396) (xy 85.467952 -410.102812) (xy 84.751672 -410.102812)
			(xy 84.741563 -410.102338) (xy 84.722886 -410.094594) (xy 84.708593 -410.080293) (xy 84.700857 -410.061613)
			(xy 84.700364 -410.051504) (xy 84.700364 -409.894024) (xy 84.699928 -409.88484) (xy 84.693431 -409.867656)
			(xy 84.687664 -409.860496) (xy 84.665766 -409.834859) (xy 84.627681 -409.77922) (xy 84.596534 -409.719419)
			(xy 84.572773 -409.656319) (xy 84.556741 -409.590827) (xy 84.548669 -409.523886) (xy 83.420495 -409.523886)
			(xy 83.392063 -409.578599) (xy 83.35411 -409.634184) (xy 83.33232 -409.659836) (xy 83.326528 -409.666985)
			(xy 83.32001 -409.684172) (xy 83.31962 -409.693364) (xy 83.31962 -410.186632) (xy 83.32001 -410.195821)
			(xy 83.326537 -410.213006) (xy 83.33232 -410.22016) (xy 83.354093 -410.245825) (xy 83.392045 -410.301408)
			(xy 83.423081 -410.36113) (xy 83.446757 -410.424133) (xy 83.462732 -410.489514) (xy 83.470778 -410.556336)
			(xy 83.47078 -410.62364) (xy 83.470773 -410.623701) (xy 86.748819 -410.623701) (xy 86.74882 -410.556275)
			(xy 86.756898 -410.489336) (xy 86.772936 -410.423846) (xy 86.796702 -410.360748) (xy 86.827855 -410.300952)
			(xy 86.865947 -410.245317) (xy 86.887812 -410.219652) (xy 86.893613 -410.21251) (xy 86.900125 -410.195317)
			(xy 86.900512 -410.186124) (xy 86.900512 -409.693872) (xy 86.900113 -409.684684) (xy 86.893591 -409.6675)
			(xy 86.887812 -409.660344) (xy 86.865959 -409.634669) (xy 86.82787 -409.579036) (xy 86.796718 -409.519242)
			(xy 86.772952 -409.456146) (xy 86.756916 -409.390658) (xy 86.748839 -409.32372) (xy 86.748837 -409.256298)
			(xy 86.756912 -409.18936) (xy 86.772947 -409.123871) (xy 86.79671 -409.060775) (xy 86.82786 -409.000979)
			(xy 86.865948 -408.945345) (xy 86.887812 -408.91968) (xy 86.893601 -408.912529) (xy 86.90012 -408.895343)
			(xy 86.900512 -408.886152) (xy 86.900512 -408.728672) (xy 86.900962 -408.71856) (xy 86.908711 -408.699879)
			(xy 86.923019 -408.685585) (xy 86.941708 -408.677853) (xy 86.95182 -408.677364) (xy 87.6681 -408.677364)
			(xy 87.678204 -408.677884) (xy 87.696876 -408.685615) (xy 87.711169 -408.699901) (xy 87.71891 -408.718568)
			(xy 87.719408 -408.728672) (xy 87.719408 -408.886152) (xy 87.719839 -408.895337) (xy 87.726338 -408.912522)
			(xy 87.732108 -408.91968) (xy 87.753983 -408.945336) (xy 87.792071 -409.000972) (xy 87.823221 -409.060769)
			(xy 87.846984 -409.123867) (xy 87.863019 -409.189358) (xy 87.871093 -409.256297) (xy 87.871092 -409.323721)
			(xy 87.863015 -409.39066) (xy 87.846979 -409.45615) (xy 87.823214 -409.519247) (xy 87.792062 -409.579044)
			(xy 87.753972 -409.634679) (xy 87.732108 -409.660344) (xy 87.726311 -409.667489) (xy 87.719796 -409.68468)
			(xy 87.719408 -409.693872) (xy 87.719408 -410.186124) (xy 87.719805 -410.195313) (xy 87.726328 -410.212497)
			(xy 87.732108 -410.219652) (xy 87.753956 -410.24533) (xy 87.792045 -410.300963) (xy 87.823196 -410.360758)
			(xy 87.84696 -410.423853) (xy 87.862997 -410.48934) (xy 87.871074 -410.556277) (xy 87.871075 -410.623641)
			(xy 91.149138 -410.623641) (xy 91.14914 -410.556335) (xy 91.157185 -410.489512) (xy 91.173158 -410.42413)
			(xy 91.196831 -410.361125) (xy 91.227864 -410.3014) (xy 91.265813 -410.245813) (xy 91.2876 -410.22016)
			(xy 91.293396 -410.213014) (xy 91.299911 -410.195824) (xy 91.3003 -410.186632) (xy 91.3003 -409.693364)
			(xy 91.299907 -409.684175) (xy 91.293382 -409.666991) (xy 91.2876 -409.659836) (xy 91.265825 -409.634174)
			(xy 91.227879 -409.578588) (xy 91.196847 -409.518865) (xy 91.173175 -409.455862) (xy 91.157203 -409.390482)
			(xy 91.149158 -409.323661) (xy 91.149157 -409.256357) (xy 91.157199 -409.189536) (xy 91.17317 -409.124155)
			(xy 91.19684 -409.061151) (xy 91.227869 -409.001428) (xy 91.265814 -408.945841) (xy 91.2876 -408.920188)
			(xy 91.293384 -408.913034) (xy 91.299906 -408.89585) (xy 91.3003 -408.88666) (xy 91.3003 -408.728672)
			(xy 91.300699 -408.718516) (xy 91.308503 -408.699763) (xy 91.322907 -408.685441) (xy 91.341704 -408.677742)
			(xy 91.351862 -408.677364) (xy 92.068142 -408.677364) (xy 92.078274 -408.677793) (xy 92.097001 -408.685539)
			(xy 92.111357 -408.699843) (xy 92.11917 -408.718542) (xy 92.119704 -408.728672) (xy 92.119704 -408.88666)
			(xy 92.120132 -408.895845) (xy 92.126633 -408.91303) (xy 92.132404 -408.920188) (xy 92.154202 -408.945831)
			(xy 92.192148 -409.00142) (xy 92.223178 -409.061145) (xy 92.246848 -409.124151) (xy 92.262819 -409.189534)
			(xy 92.270862 -409.256356) (xy 92.270861 -409.323662) (xy 92.262816 -409.390484) (xy 92.246843 -409.455867)
			(xy 92.223171 -409.518871) (xy 92.220596 -409.523827) (xy 115.349227 -409.523827) (xy 115.349231 -409.456519)
			(xy 115.357278 -409.389695) (xy 115.373254 -409.324311) (xy 115.396929 -409.261305) (xy 115.427964 -409.20158)
			(xy 115.465915 -409.145993) (xy 115.487704 -409.12034) (xy 115.493509 -409.113201) (xy 115.500019 -409.096006)
			(xy 115.500404 -409.086812) (xy 115.500404 -408.593544) (xy 115.499972 -408.584359) (xy 115.493473 -408.567175)
			(xy 115.487704 -408.560016) (xy 115.465909 -408.53437) (xy 115.427963 -408.478782) (xy 115.396932 -408.419057)
			(xy 115.373261 -408.356052) (xy 115.35729 -408.290669) (xy 115.349247 -408.223846) (xy 115.349248 -408.156541)
			(xy 115.357292 -408.089719) (xy 115.373265 -408.024337) (xy 115.396937 -407.961332) (xy 115.427969 -407.901608)
			(xy 115.465917 -407.846021) (xy 115.487704 -407.820368) (xy 115.493497 -407.81322) (xy 115.500014 -407.796032)
			(xy 115.500404 -407.78684) (xy 115.500404 -407.628852) (xy 115.500846 -407.61874) (xy 115.5086 -407.60006)
			(xy 115.52291 -407.585767) (xy 115.541599 -407.578034) (xy 115.551712 -407.577544) (xy 116.268246 -407.577544)
			(xy 116.278376 -407.577989) (xy 116.297099 -407.585733) (xy 116.311454 -407.600031) (xy 116.319271 -407.618724)
			(xy 116.319808 -407.628852) (xy 116.319808 -407.78684) (xy 116.320197 -407.79603) (xy 116.326725 -407.813214)
			(xy 116.332508 -407.820368) (xy 116.354289 -407.846026) (xy 116.392242 -407.90161) (xy 116.423279 -407.961333)
			(xy 116.446954 -408.024336) (xy 116.462929 -408.089718) (xy 116.470975 -408.156541) (xy 116.470976 -408.223847)
			(xy 116.462931 -408.29067) (xy 116.446958 -408.356052) (xy 116.423283 -408.419056) (xy 116.392248 -408.478779)
			(xy 116.354297 -408.534365) (xy 116.332508 -408.560016) (xy 116.326723 -408.56717) (xy 116.320201 -408.584354)
			(xy 116.319808 -408.593544) (xy 116.319808 -409.086812) (xy 116.320211 -409.096) (xy 116.326729 -409.113184)
			(xy 116.332508 -409.12034) (xy 116.354262 -409.146021) (xy 116.392215 -409.201602) (xy 116.423253 -409.261321)
			(xy 116.44693 -409.324322) (xy 116.462907 -409.389701) (xy 116.470955 -409.456521) (xy 116.470958 -409.523825)
			(xy 116.462917 -409.590646) (xy 116.446946 -409.656026) (xy 116.423275 -409.71903) (xy 116.392243 -409.778752)
			(xy 116.354295 -409.834337) (xy 116.332508 -409.859988) (xy 116.326692 -409.86712) (xy 116.320189 -409.884321)
			(xy 116.319808 -409.893516) (xy 116.319808 -410.051504) (xy 116.319318 -410.061612) (xy 116.311581 -410.080289)
			(xy 116.297285 -410.094583) (xy 116.278608 -410.102319) (xy 116.2685 -410.102812) (xy 115.551966 -410.102812)
			(xy 115.541844 -410.102303) (xy 115.523131 -410.094574) (xy 115.508778 -410.080295) (xy 115.500951 -410.061624)
			(xy 115.500404 -410.051504) (xy 115.500404 -409.893516) (xy 115.499985 -409.88433) (xy 115.493477 -409.867145)
			(xy 115.487704 -409.859988) (xy 115.465882 -409.834364) (xy 115.427937 -409.778773) (xy 115.396907 -409.719045)
			(xy 115.373238 -409.656037) (xy 115.357268 -409.590652) (xy 115.349227 -409.523827) (xy 92.220596 -409.523827)
			(xy 92.192139 -409.578596) (xy 92.154191 -409.634183) (xy 92.132404 -409.659836) (xy 92.12661 -409.666983)
			(xy 92.120094 -409.684172) (xy 92.119704 -409.693364) (xy 92.119704 -410.186632) (xy 92.120098 -410.195821)
			(xy 92.126623 -410.213005) (xy 92.132404 -410.22016) (xy 92.154175 -410.245826) (xy 92.192121 -410.301411)
			(xy 92.223153 -410.361133) (xy 92.246825 -410.424136) (xy 92.262797 -410.489516) (xy 92.270842 -410.556336)
			(xy 92.270844 -410.623639) (xy 92.270837 -410.623701) (xy 117.548849 -410.623701) (xy 117.54885 -410.556275)
			(xy 117.556929 -410.489335) (xy 117.572967 -410.423844) (xy 117.596736 -410.360746) (xy 117.627891 -410.30095)
			(xy 117.665985 -410.245316) (xy 117.687852 -410.219652) (xy 117.693658 -410.212514) (xy 117.700166 -410.195318)
			(xy 117.700552 -410.186124) (xy 117.700552 -409.693872) (xy 117.700144 -409.684685) (xy 117.693627 -409.667501)
			(xy 117.687852 -409.660344) (xy 117.665998 -409.63467) (xy 117.627906 -409.579038) (xy 117.596751 -409.519243)
			(xy 117.572984 -409.456148) (xy 117.556946 -409.390659) (xy 117.548869 -409.323721) (xy 117.548868 -409.256297)
			(xy 117.556943 -409.189359) (xy 117.572979 -409.12387) (xy 117.596744 -409.060773) (xy 117.627896 -409.000978)
			(xy 117.665987 -408.945344) (xy 117.687852 -408.91968) (xy 117.693646 -408.912533) (xy 117.700161 -408.895344)
			(xy 117.700552 -408.886152) (xy 117.700552 -408.728672) (xy 117.701061 -408.718567) (xy 117.708799 -408.699898)
			(xy 117.723088 -408.685606) (xy 117.741756 -408.677863) (xy 117.75186 -408.677364) (xy 118.46814 -408.677364)
			(xy 118.478247 -408.677852) (xy 118.496919 -408.685596) (xy 118.511211 -408.699891) (xy 118.518951 -408.718565)
			(xy 118.519448 -408.728672) (xy 118.519448 -408.886152) (xy 118.519893 -408.895335) (xy 118.526384 -408.912519)
			(xy 118.532148 -408.91968) (xy 118.554026 -408.945335) (xy 118.592117 -409.000969) (xy 118.62327 -409.060767)
			(xy 118.647036 -409.123865) (xy 118.663072 -409.189356) (xy 118.671148 -409.256296) (xy 118.671147 -409.323722)
			(xy 118.663069 -409.390662) (xy 118.647031 -409.456152) (xy 118.623263 -409.51925) (xy 118.620848 -409.523886)
			(xy 119.748996 -409.523886) (xy 119.748999 -409.45646) (xy 119.757078 -409.389519) (xy 119.773118 -409.324028)
			(xy 119.796886 -409.26093) (xy 119.828041 -409.201132) (xy 119.866134 -409.145497) (xy 119.888 -409.119832)
			(xy 119.893808 -409.112695) (xy 119.900316 -409.095498) (xy 119.9007 -409.086304) (xy 119.9007 -408.594052)
			(xy 119.900265 -408.584867) (xy 119.893769 -408.567683) (xy 119.888 -408.560524) (xy 119.866128 -408.534865)
			(xy 119.82804 -408.47923) (xy 119.796889 -408.419433) (xy 119.773126 -408.356335) (xy 119.757091 -408.290845)
			(xy 119.749015 -408.223906) (xy 119.749016 -408.156482) (xy 119.757093 -408.089543) (xy 119.773129 -408.024054)
			(xy 119.796894 -407.960956) (xy 119.828046 -407.90116) (xy 119.866136 -407.845525) (xy 119.888 -407.81986)
			(xy 119.893796 -407.812714) (xy 119.900311 -407.795524) (xy 119.9007 -407.786332) (xy 119.9007 -407.628852)
			(xy 119.901146 -407.61874) (xy 119.908899 -407.600061) (xy 119.923208 -407.585768) (xy 119.941896 -407.578035)
			(xy 119.952008 -407.577544) (xy 120.668288 -407.577544) (xy 120.678389 -407.578094) (xy 120.697056 -407.585817)
			(xy 120.71135 -407.600093) (xy 120.719095 -407.618752) (xy 120.719596 -407.628852) (xy 120.719596 -407.786332)
			(xy 120.719991 -407.795521) (xy 120.726515 -407.812705) (xy 120.732296 -407.81986) (xy 120.754152 -407.845532)
			(xy 120.792241 -407.901165) (xy 120.823393 -407.96096) (xy 120.847158 -408.024056) (xy 120.863194 -408.089545)
			(xy 120.87127 -408.156482) (xy 120.871271 -408.223906) (xy 120.863196 -408.290843) (xy 120.847161 -408.356332)
			(xy 120.823398 -408.419429) (xy 120.792248 -408.479225) (xy 120.75416 -408.534859) (xy 120.732296 -408.560524)
			(xy 120.726506 -408.567674) (xy 120.719988 -408.584861) (xy 120.719596 -408.594052) (xy 120.719596 -409.086304)
			(xy 120.720005 -409.095491) (xy 120.72652 -409.112675) (xy 120.732296 -409.119832) (xy 120.754125 -409.145526)
			(xy 120.792215 -409.201157) (xy 120.823367 -409.260949) (xy 120.847134 -409.324042) (xy 120.863172 -409.389527)
			(xy 120.871251 -409.456463) (xy 120.871254 -409.523883) (xy 120.863181 -409.590819) (xy 120.84715 -409.656306)
			(xy 120.823389 -409.719402) (xy 120.792243 -409.779197) (xy 120.754158 -409.834831) (xy 120.732296 -409.860496)
			(xy 120.726518 -409.867654) (xy 120.719992 -409.884835) (xy 120.719596 -409.894024) (xy 120.719596 -410.051504)
			(xy 120.719187 -410.061627) (xy 120.711437 -410.080332) (xy 120.697118 -410.094646) (xy 120.678411 -410.10239)
			(xy 120.668288 -410.102812) (xy 119.952008 -410.102812) (xy 119.941888 -410.102378) (xy 119.923186 -410.094634)
			(xy 119.908872 -410.080324) (xy 119.901125 -410.061624) (xy 119.9007 -410.051504) (xy 119.9007 -409.894024)
			(xy 119.900278 -409.884838) (xy 119.893773 -409.867654) (xy 119.888 -409.860496) (xy 119.866101 -409.83486)
			(xy 119.828013 -409.779221) (xy 119.796864 -409.719421) (xy 119.773102 -409.65632) (xy 119.757069 -409.590828)
			(xy 119.748996 -409.523886) (xy 118.620848 -409.523886) (xy 118.592108 -409.579046) (xy 118.554015 -409.63468)
			(xy 118.532148 -409.660344) (xy 118.526344 -409.667484) (xy 118.519835 -409.684679) (xy 118.519448 -409.693872)
			(xy 118.519448 -410.186124) (xy 118.519858 -410.195311) (xy 118.526373 -410.212495) (xy 118.532148 -410.219652)
			(xy 118.553998 -410.245329) (xy 118.592091 -410.300961) (xy 118.623245 -410.360755) (xy 118.647012 -410.42385)
			(xy 118.663051 -410.489338) (xy 118.671128 -410.556276) (xy 118.67113 -410.623641) (xy 121.949169 -410.623641)
			(xy 121.94917 -410.556335) (xy 121.957216 -410.489511) (xy 121.97319 -410.424128) (xy 121.996865 -410.361123)
			(xy 122.0279 -410.301399) (xy 122.065851 -410.245812) (xy 122.08764 -410.22016) (xy 122.093441 -410.213018)
			(xy 122.099952 -410.195825) (xy 122.10034 -410.186632) (xy 122.10034 -409.693364) (xy 122.099938 -409.684176)
			(xy 122.093418 -409.666992) (xy 122.08764 -409.659836) (xy 122.065864 -409.634174) (xy 122.027915 -409.578589)
			(xy 121.996881 -409.518867) (xy 121.973208 -409.455864) (xy 121.957234 -409.390483) (xy 121.949189 -409.323661)
			(xy 121.949188 -409.256357) (xy 121.957231 -409.189535) (xy 121.973202 -409.124154) (xy 121.996874 -409.06115)
			(xy 122.027906 -409.001427) (xy 122.065853 -408.94584) (xy 122.08764 -408.920188) (xy 122.093429 -408.913038)
			(xy 122.099947 -408.895851) (xy 122.10034 -408.88666) (xy 122.10034 -408.728672) (xy 122.100694 -408.718543)
			(xy 122.108459 -408.699831) (xy 122.122795 -408.685516) (xy 122.141518 -408.677779) (xy 122.151648 -408.677364)
			(xy 122.868182 -408.677364) (xy 122.878311 -408.677842) (xy 122.897036 -408.685568) (xy 122.911394 -408.699858)
			(xy 122.919209 -408.718546) (xy 122.919744 -408.728672) (xy 122.919744 -408.88666) (xy 122.920186 -408.895844)
			(xy 122.926679 -408.913028) (xy 122.932444 -408.920188) (xy 122.954244 -408.94583) (xy 122.992193 -409.001418)
			(xy 123.023227 -409.061143) (xy 123.0469 -409.124148) (xy 123.062873 -409.189532) (xy 123.070916 -409.256356)
			(xy 123.070915 -409.323662) (xy 123.062869 -409.390486) (xy 123.046895 -409.455869) (xy 123.02322 -409.518874)
			(xy 123.020646 -409.523827) (xy 124.149291 -409.523827) (xy 124.149295 -409.456519) (xy 124.157343 -409.389693)
			(xy 124.173321 -409.324308) (xy 124.197 -409.261302) (xy 124.22804 -409.201577) (xy 124.265997 -409.145992)
			(xy 124.287788 -409.12034) (xy 124.293591 -409.113199) (xy 124.300102 -409.096005) (xy 124.300488 -409.086812)
			(xy 124.300488 -408.593544) (xy 124.300059 -408.584359) (xy 124.293559 -408.567174) (xy 124.287788 -408.560016)
			(xy 124.265991 -408.534371) (xy 124.228039 -408.478785) (xy 124.197004 -408.419061) (xy 124.173329 -408.356055)
			(xy 124.157355 -408.290671) (xy 124.149311 -408.223847) (xy 124.149312 -408.156541) (xy 124.157357 -408.089717)
			(xy 124.173333 -408.024333) (xy 124.197008 -407.961328) (xy 124.228045 -407.901605) (xy 124.265998 -407.84602)
			(xy 124.287788 -407.820368) (xy 124.293579 -407.813219) (xy 124.300097 -407.796031) (xy 124.300488 -407.78684)
			(xy 124.300488 -407.628852) (xy 124.300946 -407.618742) (xy 124.308697 -407.600065) (xy 124.323002 -407.585772)
			(xy 124.341685 -407.578037) (xy 124.351796 -407.577544) (xy 125.06833 -407.577544) (xy 125.078459 -407.578002)
			(xy 125.097182 -407.58574) (xy 125.111537 -407.600035) (xy 125.119355 -407.618725) (xy 125.119892 -407.628852)
			(xy 125.119892 -407.78684) (xy 125.120285 -407.796029) (xy 125.126811 -407.813213) (xy 125.132592 -407.820368)
			(xy 125.154371 -407.846027) (xy 125.192318 -407.901613) (xy 125.22335 -407.961336) (xy 125.247022 -408.02434)
			(xy 125.262994 -408.089721) (xy 125.271039 -408.156542) (xy 125.271039 -408.223846) (xy 125.262997 -408.290667)
			(xy 125.247025 -408.356049) (xy 125.223355 -408.419053) (xy 125.192324 -408.478776) (xy 125.154378 -408.534363)
			(xy 125.132592 -408.560016) (xy 125.126805 -408.567168) (xy 125.120285 -408.584353) (xy 125.119892 -408.593544)
			(xy 125.119892 -409.086812) (xy 125.120298 -409.096) (xy 125.126815 -409.113184) (xy 125.132592 -409.12034)
			(xy 125.154343 -409.146022) (xy 125.192291 -409.201605) (xy 125.223324 -409.261324) (xy 125.246998 -409.324325)
			(xy 125.262972 -409.389703) (xy 125.271019 -409.456522) (xy 125.271022 -409.523824) (xy 125.262982 -409.590643)
			(xy 125.247014 -409.656023) (xy 125.223347 -409.719026) (xy 125.192319 -409.778749) (xy 125.154377 -409.834336)
			(xy 125.132592 -409.859988) (xy 125.126775 -409.867118) (xy 125.120273 -409.88432) (xy 125.119892 -409.893516)
			(xy 125.119892 -410.051504) (xy 125.119487 -410.061628) (xy 125.111736 -410.080333) (xy 125.097416 -410.094647)
			(xy 125.078708 -410.102391) (xy 125.068584 -410.102812) (xy 124.35205 -410.102812) (xy 124.341933 -410.102234)
			(xy 124.323223 -410.094532) (xy 124.308867 -410.080274) (xy 124.301036 -410.061618) (xy 124.300488 -410.051504)
			(xy 124.300488 -409.893516) (xy 124.300073 -409.884329) (xy 124.293563 -409.867145) (xy 124.287788 -409.859988)
			(xy 124.265963 -409.834366) (xy 124.228013 -409.778776) (xy 124.196978 -409.719049) (xy 124.173305 -409.65604)
			(xy 124.157333 -409.590654) (xy 124.149291 -409.523827) (xy 123.020646 -409.523827) (xy 122.992184 -409.578598)
			(xy 122.954233 -409.634184) (xy 122.932444 -409.659836) (xy 122.926643 -409.666978) (xy 122.920132 -409.684171)
			(xy 122.919744 -409.693364) (xy 122.919744 -410.186632) (xy 122.920151 -410.195819) (xy 122.926668 -410.213003)
			(xy 122.932444 -410.22016) (xy 122.954216 -410.245825) (xy 122.992167 -410.301409) (xy 123.023202 -410.361131)
			(xy 123.046876 -410.424134) (xy 123.062851 -410.489514) (xy 123.070896 -410.556336) (xy 123.070898 -410.62364)
			(xy 123.070891 -410.623701) (xy 126.348937 -410.623701) (xy 126.348938 -410.556275) (xy 126.357016 -410.489335)
			(xy 126.373055 -410.423845) (xy 126.396822 -410.360747) (xy 126.427977 -410.300951) (xy 126.46607 -410.245317)
			(xy 126.487936 -410.219652) (xy 126.49374 -410.212512) (xy 126.500249 -410.195317) (xy 126.500636 -410.186124)
			(xy 126.500636 -409.693872) (xy 126.500231 -409.684684) (xy 126.493713 -409.667501) (xy 126.487936 -409.660344)
			(xy 126.466083 -409.63467) (xy 126.427991 -409.579037) (xy 126.396838 -409.519243) (xy 126.373071 -409.456147)
			(xy 126.357034 -409.390659) (xy 126.348957 -409.323721) (xy 126.348956 -409.256297) (xy 126.357031 -409.189359)
			(xy 126.373066 -409.12387) (xy 126.396831 -409.060774) (xy 126.427982 -409.000978) (xy 126.466071 -408.945345)
			(xy 126.487936 -408.91968) (xy 126.493728 -408.912532) (xy 126.500245 -408.895343) (xy 126.500636 -408.886152)
			(xy 126.500636 -408.728672) (xy 126.500994 -408.718543) (xy 126.508758 -408.699832) (xy 126.523093 -408.685517)
			(xy 126.541815 -408.67778) (xy 126.551944 -408.677364) (xy 127.268224 -408.677364) (xy 127.27833 -408.677864)
			(xy 127.297002 -408.685603) (xy 127.311294 -408.699895) (xy 127.319035 -408.718566) (xy 127.319532 -408.728672)
			(xy 127.319532 -408.886152) (xy 127.31998 -408.895335) (xy 127.326469 -408.912519) (xy 127.332232 -408.91968)
			(xy 127.354107 -408.945336) (xy 127.392193 -409.000973) (xy 127.423341 -409.06077) (xy 127.447103 -409.123868)
			(xy 127.463137 -409.189358) (xy 127.471211 -409.256297) (xy 127.47121 -409.323721) (xy 127.463134 -409.39066)
			(xy 127.447098 -409.456149) (xy 127.423334 -409.519246) (xy 127.420948 -409.523827) (xy 128.549082 -409.523827)
			(xy 128.549085 -409.456519) (xy 128.557133 -409.389693) (xy 128.573111 -409.324308) (xy 128.59679 -409.261302)
			(xy 128.627829 -409.201578) (xy 128.665785 -409.145991) (xy 128.687576 -409.12034) (xy 128.693378 -409.113198)
			(xy 128.69989 -409.096005) (xy 128.700276 -409.086812) (xy 128.700276 -408.593544) (xy 128.69985 -408.584358)
			(xy 128.693348 -408.567174) (xy 128.687576 -408.560016) (xy 128.665779 -408.534371) (xy 128.627828 -408.478784)
			(xy 128.596793 -408.41906) (xy 128.573119 -408.356055) (xy 128.557146 -408.290671) (xy 128.549102 -408.223847)
			(xy 128.549103 -408.156541) (xy 128.557148 -408.089717) (xy 128.573123 -408.024334) (xy 128.596798 -407.961329)
			(xy 128.627835 -407.901605) (xy 128.665787 -407.84602) (xy 128.687576 -407.820368) (xy 128.693366 -407.813218)
			(xy 128.699885 -407.796031) (xy 128.700276 -407.78684) (xy 128.700276 -407.628852) (xy 128.700745 -407.618743)
			(xy 128.708494 -407.600069) (xy 128.722795 -407.585776) (xy 128.741475 -407.578039) (xy 128.751584 -407.577544)
			(xy 129.468118 -407.577544) (xy 129.478246 -407.578012) (xy 129.496969 -407.585746) (xy 129.511325 -407.600038)
			(xy 129.519143 -407.618726) (xy 129.51968 -407.628852) (xy 129.51968 -407.78684) (xy 129.520075 -407.796029)
			(xy 129.5266 -407.813213) (xy 129.53238 -407.820368) (xy 129.554159 -407.846027) (xy 129.592107 -407.901613)
			(xy 129.62314 -407.961336) (xy 129.646812 -408.024339) (xy 129.662785 -408.08972) (xy 129.67083 -408.156542)
			(xy 129.67083 -408.223846) (xy 129.662787 -408.290668) (xy 129.646816 -408.356049) (xy 129.623145 -408.419053)
			(xy 129.592113 -408.478777) (xy 129.554167 -408.534364) (xy 129.53238 -408.560016) (xy 129.526592 -408.567167)
			(xy 129.520073 -408.584353) (xy 129.51968 -408.593544) (xy 129.51968 -409.086812) (xy 129.520089 -409.095999)
			(xy 129.526604 -409.113183) (xy 129.53238 -409.12034) (xy 129.554131 -409.146022) (xy 129.59208 -409.201604)
			(xy 129.623114 -409.261324) (xy 129.646788 -409.324325) (xy 129.662763 -409.389703) (xy 129.670809 -409.456522)
			(xy 129.670813 -409.523824) (xy 129.662772 -409.590644) (xy 129.646804 -409.656024) (xy 129.623136 -409.719026)
			(xy 129.592108 -409.778749) (xy 129.554165 -409.834335) (xy 129.53238 -409.859988) (xy 129.526561 -409.867117)
			(xy 129.52006 -409.88432) (xy 129.51968 -409.893516) (xy 129.51968 -410.051504) (xy 129.519287 -410.061629)
			(xy 129.511534 -410.080337) (xy 129.49721 -410.094651) (xy 129.478497 -410.102393) (xy 129.468372 -410.102812)
			(xy 128.751838 -410.102812) (xy 128.74172 -410.102244) (xy 128.72301 -410.094538) (xy 128.708654 -410.080277)
			(xy 128.700824 -410.061618) (xy 128.700276 -410.051504) (xy 128.700276 -409.893516) (xy 128.699864 -409.884329)
			(xy 128.693352 -409.867144) (xy 128.687576 -409.859988) (xy 128.665751 -409.834366) (xy 128.627801 -409.778776)
			(xy 128.596768 -409.719048) (xy 128.573095 -409.65604) (xy 128.557124 -409.590654) (xy 128.549082 -409.523827)
			(xy 127.420948 -409.523827) (xy 127.392184 -409.579043) (xy 127.354096 -409.634678) (xy 127.332232 -409.660344)
			(xy 127.326426 -409.667482) (xy 127.319919 -409.684678) (xy 127.319532 -409.693872) (xy 127.319532 -410.186124)
			(xy 127.319946 -410.19531) (xy 127.326459 -410.212494) (xy 127.332232 -410.219652) (xy 127.354079 -410.245331)
			(xy 127.392166 -410.300964) (xy 127.423316 -410.360759) (xy 127.44708 -410.423854) (xy 127.463115 -410.489341)
			(xy 127.471192 -410.556277) (xy 127.471193 -410.623641) (xy 130.749257 -410.623641) (xy 130.749258 -410.556335)
			(xy 130.757303 -410.489512) (xy 130.773278 -410.424129) (xy 130.796952 -410.361123) (xy 130.827986 -410.301399)
			(xy 130.865936 -410.245812) (xy 130.887724 -410.22016) (xy 130.893523 -410.213017) (xy 130.900035 -410.195825)
			(xy 130.900424 -410.186632) (xy 130.900424 -409.693364) (xy 130.900026 -409.684176) (xy 130.893503 -409.666992)
			(xy 130.887724 -409.659836) (xy 130.865948 -409.634174) (xy 130.828 -409.578589) (xy 130.796967 -409.518866)
			(xy 130.773294 -409.455863) (xy 130.757321 -409.390482) (xy 130.749276 -409.323661) (xy 130.749275 -409.256357)
			(xy 130.757318 -409.189536) (xy 130.773289 -409.124154) (xy 130.79696 -409.06115) (xy 130.827991 -409.001427)
			(xy 130.865937 -408.94584) (xy 130.887724 -408.920188) (xy 130.893511 -408.913036) (xy 130.900031 -408.895851)
			(xy 130.900424 -408.88666) (xy 130.900424 -408.728672) (xy 130.900799 -408.718513) (xy 130.908608 -408.699755)
			(xy 130.92302 -408.685432) (xy 130.941825 -408.677738) (xy 130.951986 -408.677364) (xy 131.668266 -408.677364)
			(xy 131.678393 -408.677855) (xy 131.697118 -408.685576) (xy 131.711477 -408.699862) (xy 131.719293 -408.718547)
			(xy 131.719828 -408.728672) (xy 131.719828 -408.88666) (xy 131.720251 -408.895846) (xy 131.726755 -408.913031)
			(xy 131.732528 -408.920188) (xy 131.754328 -408.94583) (xy 131.792279 -409.001417) (xy 131.823314 -409.061142)
			(xy 131.846987 -409.124148) (xy 131.86296 -409.189532) (xy 131.871004 -409.256356) (xy 131.871003 -409.323662)
			(xy 131.862957 -409.390486) (xy 131.846982 -409.45587) (xy 131.823306 -409.518875) (xy 131.79227 -409.578598)
			(xy 131.754317 -409.634184) (xy 131.732528 -409.659836) (xy 131.726725 -409.666976) (xy 131.720216 -409.684171)
			(xy 131.719828 -409.693364) (xy 131.719828 -410.186632) (xy 131.720217 -410.195822) (xy 131.726745 -410.213006)
			(xy 131.732528 -410.22016) (xy 131.754301 -410.245825) (xy 131.792252 -410.301409) (xy 131.823288 -410.36113)
			(xy 131.846963 -410.424133) (xy 131.862938 -410.489514) (xy 131.870984 -410.556336) (xy 131.870986 -410.62364)
			(xy 131.862943 -410.690462) (xy 131.84697 -410.755844) (xy 131.823298 -410.818848) (xy 131.792265 -410.878571)
			(xy 131.754316 -410.934156) (xy 131.732528 -410.959808) (xy 131.726737 -410.966957) (xy 131.720221 -410.984145)
			(xy 131.719828 -410.993336) (xy 131.719828 -411.151324) (xy 131.719399 -411.161476) (xy 131.7116 -411.180224)
			(xy 131.697207 -411.194545) (xy 131.67842 -411.202249) (xy 131.668266 -411.202632) (xy 130.951986 -411.202632)
			(xy 130.941855 -411.202184) (xy 130.923128 -411.194446) (xy 130.908772 -411.180148) (xy 130.900958 -411.161453)
			(xy 130.900424 -411.151324) (xy 130.900424 -410.993336) (xy 130.899991 -410.984151) (xy 130.893493 -410.966967)
			(xy 130.887724 -410.959808) (xy 130.865921 -410.934169) (xy 130.827974 -410.87858) (xy 130.796942 -410.818855)
			(xy 130.773271 -410.755848) (xy 130.757299 -410.690465) (xy 130.749257 -410.623641) (xy 127.471193 -410.623641)
			(xy 127.471193 -410.623699) (xy 127.463119 -410.690635) (xy 127.447087 -410.756123) (xy 127.423326 -410.819219)
			(xy 127.392179 -410.879015) (xy 127.354094 -410.93465) (xy 127.332232 -410.960316) (xy 127.326438 -410.967463)
			(xy 127.319924 -410.984652) (xy 127.319532 -410.993844) (xy 127.319532 -411.151324) (xy 127.319035 -411.16143)
			(xy 127.311296 -411.180103) (xy 127.297003 -411.194396) (xy 127.27833 -411.202135) (xy 127.268224 -411.202632)
			(xy 126.551944 -411.202632) (xy 126.541828 -411.202149) (xy 126.523132 -411.194421) (xy 126.508817 -411.180125)
			(xy 126.501065 -411.161439) (xy 126.500636 -411.151324) (xy 126.500636 -410.993844) (xy 126.500196 -410.98466)
			(xy 126.493702 -410.967476) (xy 126.487936 -410.960316) (xy 126.466055 -410.934664) (xy 126.427964 -410.879029)
			(xy 126.396812 -410.819231) (xy 126.373048 -410.756132) (xy 126.357012 -410.690641) (xy 126.348937 -410.623701)
			(xy 123.070891 -410.623701) (xy 123.062855 -410.690462) (xy 123.046883 -410.755843) (xy 123.023211 -410.818847)
			(xy 122.992179 -410.87857) (xy 122.954231 -410.934156) (xy 122.932444 -410.959808) (xy 122.926655 -410.966958)
			(xy 122.920137 -410.984145) (xy 122.919744 -410.993336) (xy 122.919744 -411.151324) (xy 122.919236 -411.161429)
			(xy 122.911498 -411.180099) (xy 122.897209 -411.194392) (xy 122.878541 -411.202133) (xy 122.868436 -411.202632)
			(xy 122.151902 -411.202632) (xy 122.141772 -411.202171) (xy 122.123046 -411.194439) (xy 122.108688 -411.180144)
			(xy 122.100874 -411.161452) (xy 122.10034 -411.151324) (xy 122.10034 -410.993336) (xy 122.099903 -410.984152)
			(xy 122.093407 -410.966968) (xy 122.08764 -410.959808) (xy 122.065836 -410.934169) (xy 122.027888 -410.878581)
			(xy 121.996855 -410.818855) (xy 121.973183 -410.755849) (xy 121.957211 -410.690465) (xy 121.949169 -410.623641)
			(xy 118.67113 -410.623641) (xy 118.67113 -410.6237) (xy 118.663055 -410.690638) (xy 118.647019 -410.756127)
			(xy 118.623255 -410.819223) (xy 118.592103 -410.879018) (xy 118.554013 -410.934652) (xy 118.532148 -410.960316)
			(xy 118.526356 -410.967464) (xy 118.51984 -410.984653) (xy 118.519448 -410.993844) (xy 118.519448 -411.151324)
			(xy 118.518936 -411.161428) (xy 118.511199 -411.180098) (xy 118.496911 -411.19439) (xy 118.478244 -411.202133)
			(xy 118.46814 -411.202632) (xy 117.75186 -411.202632) (xy 117.741753 -411.202148) (xy 117.72308 -411.194404)
			(xy 117.708787 -411.180107) (xy 117.701048 -411.161431) (xy 117.700552 -411.151324) (xy 117.700552 -410.993844)
			(xy 117.700109 -410.984661) (xy 117.693617 -410.967477) (xy 117.687852 -410.960316) (xy 117.66597 -410.934665)
			(xy 117.627879 -410.879029) (xy 117.596726 -410.819232) (xy 117.57296 -410.756133) (xy 117.556924 -410.690642)
			(xy 117.548849 -410.623701) (xy 92.270837 -410.623701) (xy 92.262802 -410.69046) (xy 92.246832 -410.755841)
			(xy 92.223163 -410.818845) (xy 92.192134 -410.878568) (xy 92.154189 -410.934155) (xy 92.132404 -410.959808)
			(xy 92.126622 -410.966964) (xy 92.120098 -410.984146) (xy 92.119704 -410.993336) (xy 92.119704 -411.151324)
			(xy 92.119298 -411.161479) (xy 92.111495 -411.180231) (xy 92.097094 -411.194554) (xy 92.078299 -411.202253)
			(xy 92.068142 -411.202632) (xy 91.351862 -411.202632) (xy 91.341729 -411.202204) (xy 91.323002 -411.194458)
			(xy 91.308646 -411.180154) (xy 91.300833 -411.161455) (xy 91.3003 -411.151324) (xy 91.3003 -410.993336)
			(xy 91.299873 -410.984151) (xy 91.293371 -410.966966) (xy 91.2876 -410.959808) (xy 91.265798 -410.934168)
			(xy 91.227852 -410.878579) (xy 91.196822 -410.818853) (xy 91.173151 -410.755847) (xy 91.157181 -410.690464)
			(xy 91.149138 -410.623641) (xy 87.871075 -410.623641) (xy 87.871075 -410.623699) (xy 87.863001 -410.690636)
			(xy 87.846967 -410.756124) (xy 87.823205 -410.81922) (xy 87.792057 -410.879016) (xy 87.753971 -410.934651)
			(xy 87.732108 -410.960316) (xy 87.726323 -410.96747) (xy 87.719801 -410.984654) (xy 87.719408 -410.993844)
			(xy 87.719408 -411.151324) (xy 87.718935 -411.161433) (xy 87.711191 -411.180111) (xy 87.69689 -411.194404)
			(xy 87.67821 -411.20214) (xy 87.6681 -411.202632) (xy 86.95182 -411.202632) (xy 86.941716 -411.202099)
			(xy 86.923045 -411.194374) (xy 86.90875 -411.180092) (xy 86.901009 -411.161427) (xy 86.900512 -411.151324)
			(xy 86.900512 -410.993844) (xy 86.900078 -410.984659) (xy 86.893581 -410.967475) (xy 86.887812 -410.960316)
			(xy 86.865932 -410.934664) (xy 86.827843 -410.879028) (xy 86.796692 -410.81923) (xy 86.772928 -410.756131)
			(xy 86.756894 -410.69064) (xy 86.748819 -410.623701) (xy 83.470773 -410.623701) (xy 83.462736 -410.690462)
			(xy 83.446764 -410.755844) (xy 83.423091 -410.818848) (xy 83.392058 -410.878571) (xy 83.354108 -410.934156)
			(xy 83.33232 -410.959808) (xy 83.32654 -410.966965) (xy 83.320015 -410.984146) (xy 83.31962 -410.993336)
			(xy 83.31962 -411.151324) (xy 83.319199 -411.161477) (xy 83.311399 -411.180226) (xy 83.297003 -411.194548)
			(xy 83.278213 -411.202251) (xy 83.268058 -411.202632) (xy 82.551778 -411.202632) (xy 82.541646 -411.202191)
			(xy 82.522919 -411.194451) (xy 82.508563 -411.18015) (xy 82.500749 -411.161454) (xy 82.500216 -411.151324)
			(xy 82.500216 -410.993336) (xy 82.499785 -410.984151) (xy 82.493285 -410.966967) (xy 82.487516 -410.959808)
			(xy 82.465713 -410.934169) (xy 82.427766 -410.87858) (xy 82.396735 -410.818854) (xy 82.373064 -410.755848)
			(xy 82.357093 -410.690465) (xy 82.349051 -410.623641) (xy 79.070987 -410.623641) (xy 79.070987 -410.623699)
			(xy 79.062913 -410.690636) (xy 79.04688 -410.756124) (xy 79.023119 -410.81922) (xy 78.991971 -410.879016)
			(xy 78.953886 -410.93465) (xy 78.932024 -410.960316) (xy 78.926241 -410.967471) (xy 78.919717 -410.984654)
			(xy 78.919324 -410.993844) (xy 78.919324 -411.151324) (xy 78.918835 -411.161431) (xy 78.911094 -411.180106)
			(xy 78.896799 -411.194399) (xy 78.878123 -411.202137) (xy 78.868016 -411.202632) (xy 78.151736 -411.202632)
			(xy 78.14162 -411.202155) (xy 78.122923 -411.194425) (xy 78.108609 -411.180127) (xy 78.100857 -411.16144)
			(xy 78.100428 -411.151324) (xy 78.100428 -410.993844) (xy 78.09999 -410.98466) (xy 78.093495 -410.967476)
			(xy 78.087728 -410.960316) (xy 78.065847 -410.934664) (xy 78.027757 -410.879028) (xy 77.996606 -410.819231)
			(xy 77.972841 -410.756132) (xy 77.956806 -410.690641) (xy 77.948731 -410.623701) (xy 74.670685 -410.623701)
			(xy 74.662649 -410.690462) (xy 74.646677 -410.755844) (xy 74.623005 -410.818848) (xy 74.591972 -410.87857)
			(xy 74.554023 -410.934156) (xy 74.532236 -410.959808) (xy 74.526446 -410.966957) (xy 74.519929 -410.984145)
			(xy 74.519536 -410.993336) (xy 74.519536 -411.151324) (xy 74.519099 -411.161475) (xy 74.511302 -411.180221)
			(xy 74.496911 -411.194542) (xy 74.478127 -411.202248) (xy 74.467974 -411.202632) (xy 73.751694 -411.202632)
			(xy 73.741563 -411.202177) (xy 73.722837 -411.194442) (xy 73.70848 -411.180146) (xy 73.700666 -411.161452)
			(xy 73.700132 -411.151324) (xy 73.700132 -410.993336) (xy 73.699697 -410.984152) (xy 73.6932 -410.966967)
			(xy 73.687432 -410.959808) (xy 73.665629 -410.934169) (xy 73.627681 -410.87858) (xy 73.596649 -410.818855)
			(xy 73.572977 -410.755849) (xy 73.557005 -410.690465) (xy 73.548963 -410.623641) (xy 66.525648 -410.623641)
			(xy 66.525648 -417.289488) (xy 66.525648 -417.371276) (xy 141.02334 -417.371276) (xy 141.02334 -394.305282)
			(xy 141.023796 -394.293166) (xy 141.031289 -394.270122) (xy 141.045535 -394.25052) (xy 141.06514 -394.23628)
			(xy 141.088186 -394.228793) (xy 141.100302 -394.22832) (xy 154.426158 -394.22832) (xy 154.57678 -394.378688)
			(xy 154.57678 -397.823825) (xy 159.349135 -397.823825) (xy 159.349138 -397.756518) (xy 159.357186 -397.689693)
			(xy 159.373162 -397.624309) (xy 159.396838 -397.561303) (xy 159.427875 -397.501578) (xy 159.465827 -397.44599)
			(xy 159.487616 -397.420338) (xy 159.493423 -397.4132) (xy 159.499931 -397.396004) (xy 159.500316 -397.38681)
			(xy 159.500316 -396.893542) (xy 159.499882 -396.884357) (xy 159.493384 -396.867173) (xy 159.487616 -396.860014)
			(xy 159.465819 -396.83437) (xy 159.427872 -396.778782) (xy 159.396841 -396.719057) (xy 159.373169 -396.656051)
			(xy 159.357198 -396.590668) (xy 159.349155 -396.523845) (xy 159.349156 -396.45654) (xy 159.3572 -396.389717)
			(xy 159.373174 -396.324334) (xy 159.396847 -396.26133) (xy 159.42788 -396.201606) (xy 159.465828 -396.146018)
			(xy 159.487616 -396.120366) (xy 159.493411 -396.11322) (xy 159.499926 -396.09603) (xy 159.500316 -396.086838)
			(xy 159.500316 -395.92885) (xy 159.500804 -395.918684) (xy 159.508569 -395.899895) (xy 159.522934 -395.885509)
			(xy 159.541713 -395.877718) (xy 159.551878 -395.877288) (xy 160.268158 -395.877288) (xy 160.278333 -395.877699)
			(xy 160.297136 -395.88548) (xy 160.311525 -395.89987) (xy 160.319302 -395.918675) (xy 160.31972 -395.92885)
			(xy 160.31972 -396.086838) (xy 160.320108 -396.096028) (xy 160.326637 -396.113212) (xy 160.33242 -396.120366)
			(xy 160.354199 -396.146026) (xy 160.392151 -396.20161) (xy 160.423187 -396.261332) (xy 160.446862 -396.324336)
			(xy 160.462837 -396.389718) (xy 160.470882 -396.45654) (xy 160.470883 -396.523845) (xy 160.46284 -396.590668)
			(xy 160.446866 -396.65605) (xy 160.423193 -396.719054) (xy 160.392159 -396.778777) (xy 160.354208 -396.834362)
			(xy 160.33242 -396.860014) (xy 160.326637 -396.867169) (xy 160.320114 -396.884352) (xy 160.31972 -396.893542)
			(xy 160.31972 -397.38681) (xy 160.320121 -397.395998) (xy 160.326641 -397.413183) (xy 160.33242 -397.420338)
			(xy 160.354172 -397.44602) (xy 160.392124 -397.501601) (xy 160.420549 -397.556296) (xy 161.5488 -397.556296)
			(xy 161.556874 -397.489359) (xy 161.572908 -397.423871) (xy 161.596669 -397.360775) (xy 161.627817 -397.300979)
			(xy 161.665902 -397.245344) (xy 161.687764 -397.219678) (xy 161.69356 -397.212533) (xy 161.700073 -397.195342)
			(xy 161.700464 -397.18615) (xy 161.700464 -397.028924) (xy 161.701004 -397.018821) (xy 161.708727 -397.00015)
			(xy 161.723007 -396.985856) (xy 161.74167 -396.978114) (xy 161.751772 -396.977616) (xy 162.468052 -396.977616)
			(xy 162.478173 -396.978056) (xy 162.496879 -396.985791) (xy 162.511195 -397.000101) (xy 162.51894 -397.018803)
			(xy 162.51936 -397.028924) (xy 162.51936 -397.18615) (xy 162.519803 -397.195333) (xy 162.526295 -397.212518)
			(xy 162.53206 -397.219678) (xy 162.553935 -397.245334) (xy 162.592026 -397.300969) (xy 162.623179 -397.360766)
			(xy 162.646944 -397.423864) (xy 162.66298 -397.489355) (xy 162.671056 -397.556295) (xy 162.671055 -397.62372)
			(xy 162.662977 -397.69066) (xy 162.64694 -397.75615) (xy 162.623173 -397.819247) (xy 162.620757 -397.823885)
			(xy 163.748903 -397.823885) (xy 163.748907 -397.756458) (xy 163.756987 -397.689517) (xy 163.773027 -397.624026)
			(xy 163.796796 -397.560927) (xy 163.827951 -397.50113) (xy 163.866045 -397.445495) (xy 163.887912 -397.41983)
			(xy 163.893722 -397.412694) (xy 163.900228 -397.395497) (xy 163.900612 -397.386302) (xy 163.900612 -396.89405)
			(xy 163.900175 -396.884866) (xy 163.89368 -396.867681) (xy 163.887912 -396.860522) (xy 163.866038 -396.834865)
			(xy 163.827949 -396.77923) (xy 163.796798 -396.719432) (xy 163.773034 -396.656334) (xy 163.756998 -396.590844)
			(xy 163.748923 -396.523905) (xy 163.748924 -396.45648) (xy 163.757001 -396.389541) (xy 163.773038 -396.324051)
			(xy 163.796804 -396.260954) (xy 163.827956 -396.201157) (xy 163.866047 -396.145523) (xy 163.887912 -396.119858)
			(xy 163.89371 -396.112714) (xy 163.900224 -396.095523) (xy 163.900612 -396.08633) (xy 163.900612 -395.92885)
			(xy 163.901167 -395.91873) (xy 163.908873 -395.900015) (xy 163.923138 -395.885658) (xy 163.941803 -395.877832)
			(xy 163.95192 -395.877288) (xy 164.6682 -395.877288) (xy 164.678353 -395.877721) (xy 164.697103 -395.885515)
			(xy 164.711426 -395.899908) (xy 164.719127 -395.918695) (xy 164.719508 -395.92885) (xy 164.719508 -396.08633)
			(xy 164.719902 -396.095519) (xy 164.726426 -396.112703) (xy 164.732208 -396.119858) (xy 164.754062 -396.145531)
			(xy 164.79215 -396.201165) (xy 164.823301 -396.26096) (xy 164.847065 -396.324056) (xy 164.863101 -396.389544)
			(xy 164.871178 -396.456481) (xy 164.871179 -396.523904) (xy 164.863104 -396.590841) (xy 164.84707 -396.65633)
			(xy 164.823307 -396.719426) (xy 164.792158 -396.779222) (xy 164.754071 -396.834857) (xy 164.732208 -396.860522)
			(xy 164.726421 -396.867674) (xy 164.7199 -396.884859) (xy 164.719508 -396.89405) (xy 164.719508 -397.386302)
			(xy 164.719915 -397.395489) (xy 164.726431 -397.412674) (xy 164.732208 -397.41983) (xy 164.754034 -397.445526)
			(xy 164.792124 -397.501156) (xy 164.823276 -397.560948) (xy 164.846898 -397.62366) (xy 165.949096 -397.62366)
			(xy 165.949096 -397.556355) (xy 165.957139 -397.489533) (xy 165.973111 -397.424151) (xy 165.996783 -397.361147)
			(xy 166.027816 -397.301424) (xy 166.065765 -397.245838) (xy 166.087552 -397.220186) (xy 166.093343 -397.213037)
			(xy 166.09986 -397.195849) (xy 166.100252 -397.186658) (xy 166.100252 -397.028924) (xy 166.10074 -397.018777)
			(xy 166.108519 -397.000035) (xy 166.122895 -396.985712) (xy 166.141666 -396.978003) (xy 166.151814 -396.977616)
			(xy 166.868094 -396.977616) (xy 166.878217 -396.978131) (xy 166.896934 -396.985852) (xy 166.911289 -397.000129)
			(xy 166.919113 -397.018803) (xy 166.919656 -397.028924) (xy 166.919656 -397.186658) (xy 166.920096 -397.195842)
			(xy 166.92659 -397.213026) (xy 166.932356 -397.220186) (xy 166.954154 -397.24583) (xy 166.992103 -397.301417)
			(xy 167.023136 -397.361142) (xy 167.046808 -397.424148) (xy 167.062781 -397.489531) (xy 167.070824 -397.556355)
			(xy 167.070823 -397.62366) (xy 167.062778 -397.690484) (xy 167.046804 -397.755867) (xy 167.02313 -397.818872)
			(xy 167.020556 -397.823825) (xy 168.149223 -397.823825) (xy 168.149226 -397.756518) (xy 168.157274 -397.689693)
			(xy 168.17325 -397.624309) (xy 168.196925 -397.561304) (xy 168.22796 -397.501579) (xy 168.265911 -397.445991)
			(xy 168.2877 -397.420338) (xy 168.293505 -397.413199) (xy 168.300015 -397.396004) (xy 168.3004 -397.38681)
			(xy 168.3004 -396.893542) (xy 168.29997 -396.884357) (xy 168.29347 -396.867172) (xy 168.2877 -396.860014)
			(xy 168.265904 -396.834369) (xy 168.227958 -396.778781) (xy 168.196927 -396.719056) (xy 168.173256 -396.656051)
			(xy 168.157285 -396.590668) (xy 168.149243 -396.523845) (xy 168.149244 -396.45654) (xy 168.157288 -396.389717)
			(xy 168.173261 -396.324335) (xy 168.196933 -396.26133) (xy 168.227965 -396.201606) (xy 168.265913 -396.146019)
			(xy 168.2877 -396.120366) (xy 168.293494 -396.113219) (xy 168.30001 -396.09603) (xy 168.3004 -396.086838)
			(xy 168.3004 -395.92885) (xy 168.300904 -395.918686) (xy 168.308665 -395.8999) (xy 168.323026 -395.885515)
			(xy 168.341799 -395.877721) (xy 168.351962 -395.877288) (xy 169.068242 -395.877288) (xy 169.078423 -395.877631)
			(xy 169.097228 -395.885439) (xy 169.111613 -395.89985) (xy 169.119388 -395.918669) (xy 169.119804 -395.92885)
			(xy 169.119804 -396.086838) (xy 169.120195 -396.096027) (xy 169.126722 -396.113212) (xy 169.132504 -396.120366)
			(xy 169.154281 -396.146027) (xy 169.192227 -396.201613) (xy 169.223258 -396.261336) (xy 169.24693 -396.324339)
			(xy 169.262902 -396.38972) (xy 169.270946 -396.456541) (xy 169.270947 -396.523844) (xy 169.262905 -396.590665)
			(xy 169.246934 -396.656047) (xy 169.223264 -396.71905) (xy 169.192235 -396.778774) (xy 169.15429 -396.834361)
			(xy 169.132504 -396.860014) (xy 169.126719 -396.867168) (xy 169.120197 -396.884352) (xy 169.119804 -396.893542)
			(xy 169.119804 -397.38681) (xy 169.120209 -397.395998) (xy 169.126726 -397.413182) (xy 169.132504 -397.420338)
			(xy 169.154253 -397.446021) (xy 169.1922 -397.501604) (xy 169.22062 -397.556296) (xy 170.348863 -397.556296)
			(xy 170.356939 -397.489357) (xy 170.372975 -397.423868) (xy 170.39674 -397.360771) (xy 170.427892 -397.300976)
			(xy 170.465983 -397.245342) (xy 170.487848 -397.219678) (xy 170.493642 -397.212531) (xy 170.500157 -397.195342)
			(xy 170.500548 -397.18615) (xy 170.500548 -397.028924) (xy 170.501103 -397.018823) (xy 170.508823 -397.000155)
			(xy 170.523098 -396.985862) (xy 170.541756 -396.978117) (xy 170.551856 -396.977616) (xy 171.268136 -396.977616)
			(xy 171.278249 -396.978056) (xy 171.296931 -396.985808) (xy 171.311225 -397.000119) (xy 171.318956 -397.01881)
			(xy 171.319444 -397.028924) (xy 171.319444 -397.18615) (xy 171.319891 -397.195333) (xy 171.326381 -397.212517)
			(xy 171.332144 -397.219678) (xy 171.35402 -397.245334) (xy 171.392112 -397.300969) (xy 171.423265 -397.360766)
			(xy 171.447031 -397.423864) (xy 171.463068 -397.489355) (xy 171.471144 -397.556295) (xy 171.471143 -397.62372)
			(xy 171.463065 -397.69066) (xy 171.447027 -397.756151) (xy 171.423259 -397.819248) (xy 171.420874 -397.823826)
			(xy 172.54899 -397.823826) (xy 172.548993 -397.756517) (xy 172.557042 -397.689691) (xy 172.57302 -397.624306)
			(xy 172.5967 -397.5613) (xy 172.62774 -397.501575) (xy 172.665697 -397.44599) (xy 172.687488 -397.420338)
			(xy 172.693292 -397.413198) (xy 172.699803 -397.396004) (xy 172.700188 -397.38681) (xy 172.700188 -396.893542)
			(xy 172.69976 -396.884357) (xy 172.693259 -396.867172) (xy 172.687488 -396.860014) (xy 172.665689 -396.834371)
			(xy 172.627737 -396.778784) (xy 172.596702 -396.71906) (xy 172.573027 -396.656054) (xy 172.557054 -396.59067)
			(xy 172.54901 -396.523846) (xy 172.54901 -396.456539) (xy 172.557056 -396.389715) (xy 172.573032 -396.324332)
			(xy 172.596708 -396.261327) (xy 172.627745 -396.201603) (xy 172.665698 -396.146018) (xy 172.687488 -396.120366)
			(xy 172.69328 -396.113218) (xy 172.699798 -396.09603) (xy 172.700188 -396.086838) (xy 172.700188 -395.92885)
			(xy 172.700606 -395.918675) (xy 172.708384 -395.899872) (xy 172.722772 -395.885484) (xy 172.741575 -395.877706)
			(xy 172.75175 -395.877288) (xy 173.46803 -395.877288) (xy 173.47821 -395.87764) (xy 173.497015 -395.885445)
			(xy 173.5114 -395.899852) (xy 173.519175 -395.91867) (xy 173.519592 -395.92885) (xy 173.519592 -396.086838)
			(xy 173.519986 -396.096027) (xy 173.526511 -396.113211) (xy 173.532292 -396.120366) (xy 173.554069 -396.146027)
			(xy 173.592016 -396.201613) (xy 173.623048 -396.261335) (xy 173.64672 -396.324339) (xy 173.662693 -396.389719)
			(xy 173.670737 -396.456541) (xy 173.670738 -396.523844) (xy 173.662695 -396.590666) (xy 173.646725 -396.656047)
			(xy 173.623054 -396.719051) (xy 173.592024 -396.778774) (xy 173.554078 -396.834361) (xy 173.532292 -396.860014)
			(xy 173.526506 -396.867167) (xy 173.519985 -396.884351) (xy 173.519592 -396.893542) (xy 173.519592 -397.38681)
			(xy 173.519999 -397.395998) (xy 173.526515 -397.413182) (xy 173.532292 -397.420338) (xy 173.554041 -397.446021)
			(xy 173.591989 -397.501604) (xy 173.620441 -397.556355) (xy 174.749183 -397.556355) (xy 174.757226 -397.489534)
			(xy 174.773198 -397.424152) (xy 174.796869 -397.361148) (xy 174.827901 -397.301424) (xy 174.865849 -397.245838)
			(xy 174.887636 -397.220186) (xy 174.893426 -397.213036) (xy 174.899944 -397.195849) (xy 174.900336 -397.186658)
			(xy 174.900336 -397.028924) (xy 174.900742 -397.018767) (xy 174.908536 -397.000008) (xy 174.922939 -396.985682)
			(xy 174.941739 -396.977988) (xy 174.951898 -396.977616) (xy 175.668178 -396.977616) (xy 175.6783 -396.978144)
			(xy 175.697017 -396.98586) (xy 175.711373 -397.000133) (xy 175.719197 -397.018805) (xy 175.71974 -397.028924)
			(xy 175.71974 -397.186658) (xy 175.720184 -397.195841) (xy 175.726675 -397.213025) (xy 175.73244 -397.220186)
			(xy 175.754238 -397.24583) (xy 175.792188 -397.301417) (xy 175.823222 -397.361142) (xy 175.846895 -397.424147)
			(xy 175.862868 -397.489531) (xy 175.870912 -397.556354) (xy 175.870911 -397.623661) (xy 175.862865 -397.690484)
			(xy 175.846891 -397.755867) (xy 175.823216 -397.818872) (xy 175.79218 -397.878596) (xy 175.754229 -397.934182)
			(xy 175.73244 -397.959834) (xy 175.726639 -397.966976) (xy 175.720129 -397.984169) (xy 175.71974 -397.993362)
			(xy 175.71974 -398.486884) (xy 175.720171 -398.496069) (xy 175.726672 -398.513253) (xy 175.73244 -398.520412)
			(xy 175.754264 -398.546035) (xy 175.792213 -398.601625) (xy 175.823246 -398.661352) (xy 175.846918 -398.724361)
			(xy 175.862889 -398.789747) (xy 175.87093 -398.856573) (xy 175.870927 -398.923881) (xy 175.862879 -398.990707)
			(xy 175.846902 -399.056091) (xy 175.823224 -399.119097) (xy 175.792185 -399.178822) (xy 175.754231 -399.234408)
			(xy 175.73244 -399.26006) (xy 175.726628 -399.267194) (xy 175.720124 -399.284393) (xy 175.71974 -399.293588)
			(xy 175.71974 -399.451576) (xy 175.71926 -399.461724) (xy 175.71148 -399.480468) (xy 175.697101 -399.494791)
			(xy 175.678327 -399.502498) (xy 175.668178 -399.502884) (xy 174.951898 -399.502884) (xy 174.941774 -399.502376)
			(xy 174.923058 -399.494652) (xy 174.908702 -399.480372) (xy 174.900879 -399.461697) (xy 174.900336 -399.451576)
			(xy 174.900336 -399.293588) (xy 174.899924 -399.284401) (xy 174.893411 -399.267217) (xy 174.887636 -399.26006)
			(xy 174.865884 -399.234379) (xy 174.827934 -399.178796) (xy 174.7969 -399.119077) (xy 174.773225 -399.056076)
			(xy 174.75725 -398.990697) (xy 174.749203 -398.923878) (xy 174.749199 -398.856576) (xy 174.75724 -398.789756)
			(xy 174.773209 -398.724376) (xy 174.796878 -398.661373) (xy 174.827906 -398.60165) (xy 174.865851 -398.546064)
			(xy 174.887636 -398.520412) (xy 174.893457 -398.513284) (xy 174.899956 -398.49608) (xy 174.900336 -398.486884)
			(xy 174.900336 -397.993362) (xy 174.899936 -397.984174) (xy 174.893414 -397.96699) (xy 174.887636 -397.959834)
			(xy 174.865858 -397.934174) (xy 174.827909 -397.878588) (xy 174.796876 -397.818866) (xy 174.773202 -397.755863)
			(xy 174.757229 -397.690481) (xy 174.749184 -397.62366) (xy 174.749183 -397.556355) (xy 173.620441 -397.556355)
			(xy 173.623023 -397.561324) (xy 173.646696 -397.624324) (xy 173.662671 -397.689702) (xy 173.670718 -397.756521)
			(xy 173.670721 -397.823822) (xy 173.662681 -397.890642) (xy 173.646713 -397.956021) (xy 173.623046 -398.019024)
			(xy 173.592019 -398.078747) (xy 173.554077 -398.134334) (xy 173.532292 -398.159986) (xy 173.526475 -398.167117)
			(xy 173.519973 -398.184318) (xy 173.519592 -398.193514) (xy 173.519592 -398.351502) (xy 173.519069 -398.361656)
			(xy 173.511299 -398.38042) (xy 173.496943 -398.394784) (xy 173.478184 -398.402563) (xy 173.46803 -398.403064)
			(xy 172.75175 -398.403064) (xy 172.741582 -398.402595) (xy 172.722789 -398.394827) (xy 172.708402 -398.380455)
			(xy 172.700615 -398.36167) (xy 172.700188 -398.351502) (xy 172.700188 -398.193514) (xy 172.699774 -398.184327)
			(xy 172.693263 -398.167143) (xy 172.687488 -398.159986) (xy 172.665661 -398.134365) (xy 172.627711 -398.078775)
			(xy 172.596676 -398.019048) (xy 172.573004 -397.956039) (xy 172.557032 -397.890653) (xy 172.54899 -397.823826)
			(xy 171.420874 -397.823826) (xy 171.392104 -397.879044) (xy 171.354011 -397.934678) (xy 171.332144 -397.960342)
			(xy 171.32634 -397.967482) (xy 171.319831 -397.984677) (xy 171.319444 -397.99387) (xy 171.319444 -398.486376)
			(xy 171.319878 -398.49556) (xy 171.326376 -398.512744) (xy 171.332144 -398.519904) (xy 171.354045 -398.545539)
			(xy 171.392137 -398.601177) (xy 171.423289 -398.660976) (xy 171.447054 -398.724077) (xy 171.463088 -398.789571)
			(xy 171.471162 -398.856513) (xy 171.471159 -398.923941) (xy 171.463078 -398.990883) (xy 171.447037 -399.056374)
			(xy 171.423267 -399.119473) (xy 171.392109 -399.17927) (xy 171.354012 -399.234904) (xy 171.332144 -399.260568)
			(xy 171.326329 -399.2677) (xy 171.319827 -399.284901) (xy 171.319444 -399.294096) (xy 171.319444 -399.451576)
			(xy 171.318896 -399.461678) (xy 171.311175 -399.480347) (xy 171.296897 -399.494641) (xy 171.278237 -399.502385)
			(xy 171.268136 -399.502884) (xy 170.551856 -399.502884) (xy 170.541742 -399.50245) (xy 170.52306 -399.494695)
			(xy 170.508766 -399.480383) (xy 170.501036 -399.46169) (xy 170.500548 -399.451576) (xy 170.500548 -399.294096)
			(xy 170.500129 -399.28491) (xy 170.49362 -399.267726) (xy 170.487848 -399.260568) (xy 170.466018 -399.234874)
			(xy 170.427925 -399.179245) (xy 170.39677 -399.119453) (xy 170.373001 -399.05636) (xy 170.356962 -398.990874)
			(xy 170.348883 -398.923938) (xy 170.348879 -398.856516) (xy 170.356952 -398.789579) (xy 170.372985 -398.724092)
			(xy 170.396748 -398.660996) (xy 170.427897 -398.601201) (xy 170.465984 -398.545568) (xy 170.487848 -398.519904)
			(xy 170.493631 -398.51275) (xy 170.500153 -398.495566) (xy 170.500548 -398.486376) (xy 170.500548 -397.99387)
			(xy 170.500141 -397.984683) (xy 170.493624 -397.967499) (xy 170.487848 -397.960342) (xy 170.465992 -397.934669)
			(xy 170.4279 -397.879037) (xy 170.396746 -397.819242) (xy 170.372979 -397.756146) (xy 170.356942 -397.690658)
			(xy 170.348864 -397.623719) (xy 170.348863 -397.556296) (xy 169.22062 -397.556296) (xy 169.223233 -397.561324)
			(xy 169.246906 -397.624324) (xy 169.26288 -397.689702) (xy 169.270927 -397.756521) (xy 169.27093 -397.823822)
			(xy 169.26289 -397.890641) (xy 169.246923 -397.956021) (xy 169.223256 -398.019024) (xy 169.19223 -398.078746)
			(xy 169.154288 -398.134333) (xy 169.132504 -398.159986) (xy 169.126689 -398.167118) (xy 169.120185 -398.184319)
			(xy 169.119804 -398.193514) (xy 169.119804 -398.351502) (xy 169.119269 -398.361655) (xy 169.111502 -398.380416)
			(xy 169.097149 -398.394779) (xy 169.078394 -398.402561) (xy 169.068242 -398.403064) (xy 168.351962 -398.403064)
			(xy 168.341802 -398.402598) (xy 168.323032 -398.394811) (xy 168.308669 -398.380437) (xy 168.300895 -398.361662)
			(xy 168.3004 -398.351502) (xy 168.3004 -398.193514) (xy 168.299983 -398.184328) (xy 168.293474 -398.167143)
			(xy 168.2877 -398.159986) (xy 168.265876 -398.134364) (xy 168.227931 -398.078772) (xy 168.196902 -398.019044)
			(xy 168.173233 -397.956036) (xy 168.157263 -397.89065) (xy 168.149223 -397.823825) (xy 167.020556 -397.823825)
			(xy 166.992095 -397.878596) (xy 166.954145 -397.934182) (xy 166.932356 -397.959834) (xy 166.926557 -397.966977)
			(xy 166.920045 -397.984169) (xy 166.919656 -397.993362) (xy 166.919656 -398.486884) (xy 166.920084 -398.496069)
			(xy 166.926586 -398.513253) (xy 166.932356 -398.520412) (xy 166.954179 -398.546035) (xy 166.992127 -398.601625)
			(xy 167.023159 -398.661353) (xy 167.04683 -398.724361) (xy 167.062801 -398.789747) (xy 167.070842 -398.856573)
			(xy 167.070839 -398.923881) (xy 167.062791 -398.990706) (xy 167.046814 -399.05609) (xy 167.023137 -399.119097)
			(xy 166.9921 -399.178821) (xy 166.954146 -399.234408) (xy 166.932356 -399.26006) (xy 166.926546 -399.267195)
			(xy 166.92004 -399.284394) (xy 166.919656 -399.293588) (xy 166.919656 -399.451576) (xy 166.91916 -399.461722)
			(xy 166.911383 -399.480463) (xy 166.89701 -399.494785) (xy 166.878241 -399.502496) (xy 166.868094 -399.502884)
			(xy 166.151814 -399.502884) (xy 166.141691 -399.502363) (xy 166.122975 -399.494644) (xy 166.108619 -399.480369)
			(xy 166.100795 -399.461696) (xy 166.100252 -399.451576) (xy 166.100252 -399.293588) (xy 166.099836 -399.284402)
			(xy 166.093325 -399.267218) (xy 166.087552 -399.26006) (xy 166.065799 -399.234379) (xy 166.027849 -399.178797)
			(xy 165.996813 -399.119077) (xy 165.973138 -399.056077) (xy 165.957162 -398.990698) (xy 165.949115 -398.923878)
			(xy 165.949111 -398.856576) (xy 165.957152 -398.789755) (xy 165.973122 -398.724375) (xy 165.996791 -398.661372)
			(xy 166.027821 -398.60165) (xy 166.065766 -398.546064) (xy 166.087552 -398.520412) (xy 166.093375 -398.513286)
			(xy 166.099872 -398.49608) (xy 166.100252 -398.486884) (xy 166.100252 -397.993362) (xy 166.099848 -397.984174)
			(xy 166.093329 -397.966991) (xy 166.087552 -397.959834) (xy 166.065774 -397.934174) (xy 166.027824 -397.878589)
			(xy 165.99679 -397.818866) (xy 165.973116 -397.755863) (xy 165.957142 -397.690482) (xy 165.949096 -397.62366)
			(xy 164.846898 -397.62366) (xy 164.847042 -397.624041) (xy 164.863079 -397.689526) (xy 164.871158 -397.756461)
			(xy 164.871162 -397.823882) (xy 164.86309 -397.890817) (xy 164.847058 -397.956304) (xy 164.823299 -398.019399)
			(xy 164.792153 -398.079195) (xy 164.754069 -398.134829) (xy 164.732208 -398.160494) (xy 164.726432 -398.167654)
			(xy 164.719905 -398.184833) (xy 164.719508 -398.194022) (xy 164.719508 -398.351502) (xy 164.718976 -398.361623)
			(xy 164.711257 -398.380335) (xy 164.696985 -398.394689) (xy 164.678318 -398.402517) (xy 164.6682 -398.403064)
			(xy 163.95192 -398.403064) (xy 163.941763 -398.402661) (xy 163.923004 -398.394866) (xy 163.908678 -398.380462)
			(xy 163.900984 -398.361662) (xy 163.900612 -398.351502) (xy 163.900612 -398.194022) (xy 163.900188 -398.184836)
			(xy 163.893684 -398.167652) (xy 163.887912 -398.160494) (xy 163.86601 -398.13486) (xy 163.827922 -398.079221)
			(xy 163.796772 -398.019421) (xy 163.77301 -397.95632) (xy 163.756976 -397.890827) (xy 163.748903 -397.823885)
			(xy 162.620757 -397.823885) (xy 162.592019 -397.879044) (xy 162.553926 -397.934677) (xy 162.53206 -397.960342)
			(xy 162.526258 -397.967483) (xy 162.519748 -397.984677) (xy 162.51936 -397.99387) (xy 162.51936 -398.486376)
			(xy 162.51979 -398.495561) (xy 162.526291 -398.512745) (xy 162.53206 -398.519904) (xy 162.553961 -398.545539)
			(xy 162.592051 -398.601177) (xy 162.623202 -398.660977) (xy 162.646966 -398.724078) (xy 162.663 -398.789571)
			(xy 162.671074 -398.856513) (xy 162.671071 -398.923941) (xy 162.662991 -398.990882) (xy 162.64695 -399.056374)
			(xy 162.62318 -399.119472) (xy 162.592023 -399.179269) (xy 162.553928 -399.234903) (xy 162.53206 -399.260568)
			(xy 162.526247 -399.267701) (xy 162.519743 -399.284901) (xy 162.51936 -399.294096) (xy 162.51936 -399.451576)
			(xy 162.518964 -399.461702) (xy 162.511216 -399.480413) (xy 162.496893 -399.494729) (xy 162.478178 -399.502468)
			(xy 162.468052 -399.502884) (xy 161.751772 -399.502884) (xy 161.741659 -399.502438) (xy 161.722978 -399.494688)
			(xy 161.708683 -399.480379) (xy 161.700952 -399.461689) (xy 161.700464 -399.451576) (xy 161.700464 -399.294096)
			(xy 161.700041 -399.28491) (xy 161.693535 -399.267727) (xy 161.687764 -399.260568) (xy 161.665937 -399.234873)
			(xy 161.627849 -399.179242) (xy 161.596699 -399.119449) (xy 161.572934 -399.056357) (xy 161.556897 -398.990871)
			(xy 161.548819 -398.923937) (xy 161.548816 -398.856517) (xy 161.556888 -398.789582) (xy 161.572918 -398.724095)
			(xy 161.596677 -398.661) (xy 161.627821 -398.601205) (xy 161.665903 -398.54557) (xy 161.687764 -398.519904)
			(xy 161.693549 -398.512751) (xy 161.700069 -398.495566) (xy 161.700464 -398.486376) (xy 161.700464 -397.99387)
			(xy 161.700054 -397.984683) (xy 161.693538 -397.9675) (xy 161.687764 -397.960342) (xy 161.665911 -397.934668)
			(xy 161.627824 -397.879034) (xy 161.596675 -397.819239) (xy 161.572912 -397.756143) (xy 161.556877 -397.690655)
			(xy 161.548801 -397.623719) (xy 161.5488 -397.556296) (xy 160.420549 -397.556296) (xy 160.423161 -397.561321)
			(xy 160.446838 -397.624321) (xy 160.462815 -397.6897) (xy 160.470863 -397.75652) (xy 160.470866 -397.823823)
			(xy 160.462825 -397.890644) (xy 160.446855 -397.956024) (xy 160.423185 -398.019027) (xy 160.392154 -398.078749)
			(xy 160.354207 -398.134334) (xy 160.33242 -398.159986) (xy 160.326607 -398.16712) (xy 160.320101 -398.184319)
			(xy 160.31972 -398.193514) (xy 160.31972 -398.351502) (xy 160.319337 -398.361679) (xy 160.311543 -398.380482)
			(xy 160.297145 -398.394868) (xy 160.278335 -398.402645) (xy 160.268158 -398.403064) (xy 159.551878 -398.403064)
			(xy 159.541719 -398.402585) (xy 159.52295 -398.394804) (xy 159.508585 -398.380433) (xy 159.500811 -398.361661)
			(xy 159.500316 -398.351502) (xy 159.500316 -398.193514) (xy 159.499895 -398.184328) (xy 159.493388 -398.167144)
			(xy 159.487616 -398.159986) (xy 159.465792 -398.134364) (xy 159.427845 -398.078773) (xy 159.396815 -398.019045)
			(xy 159.373145 -397.956036) (xy 159.357176 -397.890651) (xy 159.349135 -397.823825) (xy 154.57678 -397.823825)
			(xy 154.57678 -401.723737) (xy 159.349146 -401.723737) (xy 159.349148 -401.65643) (xy 159.357194 -401.589607)
			(xy 159.373169 -401.524223) (xy 159.396843 -401.461218) (xy 159.427878 -401.401494) (xy 159.465828 -401.345906)
			(xy 159.487616 -401.320254) (xy 159.493416 -401.313112) (xy 159.499928 -401.295919) (xy 159.500316 -401.286726)
			(xy 159.500316 -400.793458) (xy 159.499923 -400.784269) (xy 159.493397 -400.767085) (xy 159.487616 -400.75993)
			(xy 159.465835 -400.734273) (xy 159.427887 -400.678686) (xy 159.396855 -400.618963) (xy 159.373183 -400.55596)
			(xy 159.35721 -400.490578) (xy 159.349166 -400.423757) (xy 159.349165 -400.356452) (xy 159.357209 -400.289631)
			(xy 159.37318 -400.224249) (xy 159.396851 -400.161245) (xy 159.427883 -400.101521) (xy 159.465829 -400.045934)
			(xy 159.487616 -400.020282) (xy 159.493405 -400.013131) (xy 159.499923 -399.995945) (xy 159.500316 -399.986754)
			(xy 159.500316 -399.828766) (xy 159.500805 -399.818609) (xy 159.508586 -399.799843) (xy 159.522953 -399.78548)
			(xy 159.541721 -399.777703) (xy 159.551878 -399.777204) (xy 160.268158 -399.777204) (xy 160.278323 -399.777697)
			(xy 160.29711 -399.785462) (xy 160.311495 -399.799826) (xy 160.319288 -399.818602) (xy 160.31972 -399.828766)
			(xy 160.31972 -399.986754) (xy 160.320148 -399.995939) (xy 160.326649 -400.013124) (xy 160.33242 -400.020282)
			(xy 160.354215 -400.045929) (xy 160.392166 -400.101515) (xy 160.423201 -400.161239) (xy 160.446876 -400.224244)
			(xy 160.462849 -400.289628) (xy 160.470894 -400.356451) (xy 160.470893 -400.423758) (xy 160.462848 -400.490581)
			(xy 160.446873 -400.555964) (xy 160.423198 -400.618969) (xy 160.392161 -400.678693) (xy 160.354209 -400.734278)
			(xy 160.33242 -400.75993) (xy 160.326631 -400.76708) (xy 160.320111 -400.784267) (xy 160.31972 -400.793458)
			(xy 160.31972 -401.286726) (xy 160.320113 -401.295915) (xy 160.326638 -401.313099) (xy 160.33242 -401.320254)
			(xy 160.354187 -401.345923) (xy 160.392139 -401.401506) (xy 160.423176 -401.461227) (xy 160.446852 -401.52423)
			(xy 160.462827 -401.58961) (xy 160.470874 -401.656431) (xy 160.470876 -401.723735) (xy 160.462833 -401.790557)
			(xy 160.446862 -401.855939) (xy 160.423189 -401.918943) (xy 160.392156 -401.978665) (xy 160.354208 -402.03425)
			(xy 160.33242 -402.059902) (xy 160.326642 -402.067061) (xy 160.320116 -402.084241) (xy 160.31972 -402.09343)
			(xy 160.31972 -402.251418) (xy 160.31935 -402.261596) (xy 160.311551 -402.280399) (xy 160.297149 -402.294785)
			(xy 160.278336 -402.302562) (xy 160.268158 -402.30298) (xy 159.551878 -402.30298) (xy 159.541721 -402.302485)
			(xy 159.522955 -402.294707) (xy 159.508591 -402.280342) (xy 159.500814 -402.261575) (xy 159.500316 -402.251418)
			(xy 159.500316 -402.09343) (xy 159.499888 -402.084245) (xy 159.493386 -402.06706) (xy 159.487616 -402.059902)
			(xy 159.465807 -402.034267) (xy 159.427861 -401.978678) (xy 159.39683 -401.918952) (xy 159.373159 -401.855945)
			(xy 159.357188 -401.790561) (xy 159.349146 -401.723737) (xy 154.57678 -401.723737) (xy 154.57678 -402.823877)
			(xy 161.54876 -402.823877) (xy 161.548765 -402.756451) (xy 161.556845 -402.68951) (xy 161.572884 -402.624018)
			(xy 161.596652 -402.56092) (xy 161.627806 -402.501122) (xy 161.665898 -402.445486) (xy 161.687764 -402.41982)
			(xy 161.693585 -402.412692) (xy 161.700083 -402.395488) (xy 161.700464 -402.386292) (xy 161.700464 -401.89404)
			(xy 161.70002 -401.884857) (xy 161.693528 -401.867673) (xy 161.687764 -401.860512) (xy 161.665882 -401.834862)
			(xy 161.627796 -401.779225) (xy 161.596648 -401.719426) (xy 161.572887 -401.656327) (xy 161.556854 -401.590837)
			(xy 161.54878 -401.523897) (xy 161.548782 -401.456473) (xy 161.556859 -401.389534) (xy 161.572896 -401.324044)
			(xy 161.59666 -401.260946) (xy 161.627811 -401.201149) (xy 161.6659 -401.145514) (xy 161.687764 -401.119848)
			(xy 161.693573 -401.112712) (xy 161.700078 -401.095514) (xy 161.700464 -401.08632) (xy 161.700464 -400.92884)
			(xy 161.700948 -400.918725) (xy 161.708676 -400.900029) (xy 161.722972 -400.885714) (xy 161.741657 -400.877961)
			(xy 161.751772 -400.877532) (xy 162.468052 -400.877532) (xy 162.478175 -400.877956) (xy 162.496884 -400.885694)
			(xy 162.511201 -400.900009) (xy 162.518942 -400.918717) (xy 162.51936 -400.92884) (xy 162.51936 -401.08632)
			(xy 162.519769 -401.095507) (xy 162.526285 -401.112691) (xy 162.53206 -401.119848) (xy 162.553906 -401.145529)
			(xy 162.591998 -401.20116) (xy 162.623151 -401.260954) (xy 162.646919 -401.324049) (xy 162.662957 -401.389536)
			(xy 162.671035 -401.456474) (xy 162.671037 -401.523896) (xy 162.662962 -401.590834) (xy 162.646927 -401.656323)
			(xy 162.623164 -401.719419) (xy 162.620884 -401.723796) (xy 163.748915 -401.723796) (xy 163.748917 -401.656371)
			(xy 163.756995 -401.589431) (xy 163.773033 -401.52394) (xy 163.7968 -401.460842) (xy 163.827954 -401.401046)
			(xy 163.866046 -401.345411) (xy 163.887912 -401.319746) (xy 163.893715 -401.312606) (xy 163.900226 -401.295411)
			(xy 163.900612 -401.286218) (xy 163.900612 -400.793966) (xy 163.900216 -400.784777) (xy 163.893692 -400.767593)
			(xy 163.887912 -400.760438) (xy 163.866054 -400.734768) (xy 163.827964 -400.679135) (xy 163.796812 -400.619339)
			(xy 163.773047 -400.556243) (xy 163.757011 -400.490754) (xy 163.748934 -400.423816) (xy 163.748934 -400.356393)
			(xy 163.757009 -400.289455) (xy 163.773044 -400.223966) (xy 163.796809 -400.160869) (xy 163.827959 -400.101073)
			(xy 163.866048 -400.045439) (xy 163.887912 -400.019774) (xy 163.893703 -400.012625) (xy 163.900221 -399.995437)
			(xy 163.900612 -399.986246) (xy 163.900612 -399.828766) (xy 163.901098 -399.818641) (xy 163.908832 -399.799924)
			(xy 163.923117 -399.78557) (xy 163.941797 -399.777747) (xy 163.95192 -399.777204) (xy 164.6682 -399.777204)
			(xy 164.678355 -399.777622) (xy 164.697108 -399.785418) (xy 164.711431 -399.799816) (xy 164.71913 -399.818609)
			(xy 164.719508 -399.828766) (xy 164.719508 -399.986246) (xy 164.719942 -399.995431) (xy 164.726439 -400.012615)
			(xy 164.732208 -400.019774) (xy 164.754078 -400.045435) (xy 164.792166 -400.10107) (xy 164.823316 -400.160867)
			(xy 164.847079 -400.223964) (xy 164.863114 -400.289454) (xy 164.871189 -400.356393) (xy 164.871189 -400.423817)
			(xy 164.863112 -400.490755) (xy 164.847076 -400.556244) (xy 164.823312 -400.619341) (xy 164.792161 -400.679138)
			(xy 164.754072 -400.734773) (xy 164.732208 -400.760438) (xy 164.726414 -400.767585) (xy 164.719897 -400.784774)
			(xy 164.719508 -400.793966) (xy 164.719508 -401.286218) (xy 164.719908 -401.295406) (xy 164.726429 -401.312591)
			(xy 164.732208 -401.319746) (xy 164.75405 -401.345429) (xy 164.792139 -401.401061) (xy 164.82329 -401.460855)
			(xy 164.847055 -401.52395) (xy 164.863092 -401.589436) (xy 164.871169 -401.656373) (xy 164.871171 -401.723794)
			(xy 164.863098 -401.790731) (xy 164.847065 -401.856219) (xy 164.823304 -401.919315) (xy 164.792156 -401.97911)
			(xy 164.75407 -402.034745) (xy 164.732208 -402.06041) (xy 164.726426 -402.067565) (xy 164.719902 -402.084748)
			(xy 164.719508 -402.093938) (xy 164.719508 -402.251418) (xy 164.71899 -402.26154) (xy 164.711265 -402.280253)
			(xy 164.696989 -402.294607) (xy 164.678319 -402.302434) (xy 164.6682 -402.30298) (xy 163.95192 -402.30298)
			(xy 163.941765 -402.302562) (xy 163.923009 -402.294769) (xy 163.908684 -402.280371) (xy 163.900987 -402.261575)
			(xy 163.900612 -402.251418) (xy 163.900612 -402.093938) (xy 163.900181 -402.084753) (xy 163.893681 -402.067569)
			(xy 163.887912 -402.06041) (xy 163.866026 -402.034763) (xy 163.827937 -401.979126) (xy 163.796787 -401.919327)
			(xy 163.773023 -401.856228) (xy 163.756989 -401.790737) (xy 163.748915 -401.723796) (xy 162.620884 -401.723796)
			(xy 162.592013 -401.779214) (xy 162.553924 -401.834847) (xy 162.53206 -401.860512) (xy 162.526271 -401.867662)
			(xy 162.519753 -401.884849) (xy 162.51936 -401.89404) (xy 162.51936 -402.386292) (xy 162.519783 -402.395478)
			(xy 162.526289 -402.412662) (xy 162.53206 -402.41982) (xy 162.553878 -402.445523) (xy 162.591971 -402.501152)
			(xy 162.623126 -402.560942) (xy 162.646895 -402.624034) (xy 162.662935 -402.689519) (xy 162.671015 -402.756454)
			(xy 162.671019 -402.823818) (xy 165.949055 -402.823818) (xy 165.94906 -402.756509) (xy 165.957109 -402.689683)
			(xy 165.973087 -402.624298) (xy 165.996766 -402.561292) (xy 166.027805 -402.501567) (xy 166.065761 -402.44598)
			(xy 166.087552 -402.420328) (xy 166.093368 -402.413197) (xy 166.09987 -402.395995) (xy 166.100252 -402.3868)
			(xy 166.100252 -401.893532) (xy 166.099815 -401.884348) (xy 166.093319 -401.867164) (xy 166.087552 -401.860004)
			(xy 166.065744 -401.834368) (xy 166.027795 -401.77878) (xy 165.996762 -401.719054) (xy 165.97309 -401.656047)
			(xy 165.957118 -401.590663) (xy 165.949075 -401.523838) (xy 165.949077 -401.456532) (xy 165.957123 -401.389707)
			(xy 165.973098 -401.324324) (xy 165.996774 -401.261318) (xy 166.02781 -401.201594) (xy 166.065762 -401.146008)
			(xy 166.087552 -401.120356) (xy 166.093356 -401.113216) (xy 166.099865 -401.096021) (xy 166.100252 -401.086828)
			(xy 166.100252 -400.92884) (xy 166.100754 -400.918694) (xy 166.108527 -400.899952) (xy 166.122899 -400.885629)
			(xy 166.141667 -400.87792) (xy 166.151814 -400.877532) (xy 166.868094 -400.877532) (xy 166.878219 -400.878031)
			(xy 166.896939 -400.885756) (xy 166.911295 -400.900038) (xy 166.919116 -400.918717) (xy 166.919656 -400.92884)
			(xy 166.919656 -401.086828) (xy 166.920063 -401.096015) (xy 166.92658 -401.113199) (xy 166.932356 -401.120356)
			(xy 166.954124 -401.146024) (xy 166.992074 -401.201608) (xy 167.023108 -401.26133) (xy 167.046782 -401.324332)
			(xy 167.062757 -401.389712) (xy 167.070803 -401.456533) (xy 167.070804 -401.523837) (xy 167.062762 -401.590658)
			(xy 167.046791 -401.656039) (xy 167.02312 -401.719043) (xy 167.020682 -401.723736) (xy 168.149234 -401.723736)
			(xy 168.149236 -401.65643) (xy 168.157282 -401.589607) (xy 168.173256 -401.524224) (xy 168.19693 -401.461219)
			(xy 168.227963 -401.401494) (xy 168.265912 -401.345907) (xy 168.2877 -401.320254) (xy 168.293499 -401.31311)
			(xy 168.300012 -401.295919) (xy 168.3004 -401.286726) (xy 168.3004 -400.793458) (xy 168.30001 -400.784269)
			(xy 168.293482 -400.767084) (xy 168.2877 -400.75993) (xy 168.265919 -400.734272) (xy 168.227973 -400.678686)
			(xy 168.196942 -400.618963) (xy 168.17327 -400.555959) (xy 168.157298 -400.490578) (xy 168.149254 -400.423756)
			(xy 168.149253 -400.356453) (xy 168.157296 -400.289631) (xy 168.173267 -400.22425) (xy 168.196938 -400.161246)
			(xy 168.227968 -400.101522) (xy 168.265914 -400.045935) (xy 168.2877 -400.020282) (xy 168.293487 -400.01313)
			(xy 168.300007 -399.995945) (xy 168.3004 -399.986754) (xy 168.3004 -399.828766) (xy 168.300905 -399.818611)
			(xy 168.308683 -399.799848) (xy 168.323045 -399.785485) (xy 168.341807 -399.777705) (xy 168.351962 -399.777204)
			(xy 169.068242 -399.777204) (xy 169.078398 -399.777698) (xy 169.097162 -399.78548) (xy 169.111524 -399.799845)
			(xy 169.119303 -399.81861) (xy 169.119804 -399.828766) (xy 169.119804 -399.986754) (xy 169.120235 -399.995939)
			(xy 169.126734 -400.013124) (xy 169.132504 -400.020282) (xy 169.154296 -400.04593) (xy 169.192242 -400.101518)
			(xy 169.223273 -400.161243) (xy 169.246943 -400.224248) (xy 169.262915 -400.28963) (xy 169.270958 -400.356452)
			(xy 169.270957 -400.423757) (xy 169.262913 -400.490579) (xy 169.246941 -400.555961) (xy 169.223269 -400.618966)
			(xy 169.192237 -400.67869) (xy 169.154291 -400.734277) (xy 169.132504 -400.75993) (xy 169.126713 -400.767079)
			(xy 169.120195 -400.784267) (xy 169.119804 -400.793458) (xy 169.119804 -401.286726) (xy 169.1202 -401.295915)
			(xy 169.126723 -401.313099) (xy 169.132504 -401.320254) (xy 169.154269 -401.345925) (xy 169.192215 -401.401509)
			(xy 169.223247 -401.461231) (xy 169.246919 -401.524233) (xy 169.262893 -401.589612) (xy 169.270938 -401.656432)
			(xy 169.27094 -401.723735) (xy 169.262899 -401.790555) (xy 169.246929 -401.855936) (xy 169.223261 -401.918939)
			(xy 169.192232 -401.978662) (xy 169.154289 -402.034249) (xy 169.132504 -402.059902) (xy 169.126725 -402.067059)
			(xy 169.1202 -402.084241) (xy 169.119804 -402.09343) (xy 169.119804 -402.251418) (xy 169.119283 -402.261572)
			(xy 169.11151 -402.280333) (xy 169.097154 -402.294697) (xy 169.078396 -402.302478) (xy 169.068242 -402.30298)
			(xy 168.351962 -402.30298) (xy 168.341804 -402.302498) (xy 168.323037 -402.294715) (xy 168.308674 -402.280346)
			(xy 168.300898 -402.261576) (xy 168.3004 -402.251418) (xy 168.3004 -402.09343) (xy 168.299975 -402.084244)
			(xy 168.293472 -402.06706) (xy 168.2877 -402.059902) (xy 168.265892 -402.034267) (xy 168.227946 -401.978677)
			(xy 168.196916 -401.918951) (xy 168.173246 -401.855944) (xy 168.157276 -401.79056) (xy 168.149234 -401.723736)
			(xy 167.020682 -401.723736) (xy 166.992089 -401.778766) (xy 166.954142 -401.834352) (xy 166.932356 -401.860004)
			(xy 166.92657 -401.867156) (xy 166.92005 -401.884342) (xy 166.919656 -401.893532) (xy 166.919656 -402.3868)
			(xy 166.920076 -402.395986) (xy 166.926584 -402.41317) (xy 166.932356 -402.420328) (xy 166.954097 -402.446019)
			(xy 166.992047 -402.5016) (xy 167.023083 -402.561318) (xy 167.046758 -402.624317) (xy 167.062735 -402.689695)
			(xy 167.070783 -402.756513) (xy 167.070787 -402.823815) (xy 167.070779 -402.823878) (xy 170.348823 -402.823878)
			(xy 170.348828 -402.75645) (xy 170.356909 -402.689507) (xy 170.372951 -402.624015) (xy 170.396723 -402.560916)
			(xy 170.427882 -402.501119) (xy 170.465979 -402.445484) (xy 170.487848 -402.41982) (xy 170.493667 -402.412691)
			(xy 170.500167 -402.395488) (xy 170.500548 -402.386292) (xy 170.500548 -401.89404) (xy 170.500108 -401.884856)
			(xy 170.493614 -401.867672) (xy 170.487848 -401.860512) (xy 170.465963 -401.834864) (xy 170.427871 -401.779228)
			(xy 170.396719 -401.71943) (xy 170.372954 -401.656331) (xy 170.356918 -401.590839) (xy 170.348843 -401.523898)
			(xy 170.348845 -401.456472) (xy 170.356924 -401.389531) (xy 170.372963 -401.324041) (xy 170.396731 -401.260943)
			(xy 170.427887 -401.201146) (xy 170.465981 -401.145512) (xy 170.487848 -401.119848) (xy 170.493655 -401.112711)
			(xy 170.500162 -401.095514) (xy 170.500548 -401.08632) (xy 170.500548 -400.92884) (xy 170.501117 -400.91874)
			(xy 170.508832 -400.900073) (xy 170.523102 -400.885779) (xy 170.541757 -400.878033) (xy 170.551856 -400.877532)
			(xy 171.268136 -400.877532) (xy 171.278265 -400.877887) (xy 171.296975 -400.885653) (xy 171.311289 -400.899989)
			(xy 171.319028 -400.918711) (xy 171.319444 -400.92884) (xy 171.319444 -401.08632) (xy 171.319857 -401.095507)
			(xy 171.32637 -401.11269) (xy 171.332144 -401.119848) (xy 171.35399 -401.145528) (xy 171.392083 -401.20116)
			(xy 171.423238 -401.260953) (xy 171.447006 -401.324048) (xy 171.463044 -401.389536) (xy 171.471123 -401.456473)
			(xy 171.471124 -401.523897) (xy 171.46305 -401.590834) (xy 171.447015 -401.656323) (xy 171.42325 -401.719419)
			(xy 171.421001 -401.723737) (xy 172.549001 -401.723737) (xy 172.549003 -401.65643) (xy 172.55705 -401.589605)
			(xy 172.573027 -401.524221) (xy 172.596704 -401.461215) (xy 172.627743 -401.401491) (xy 172.665697 -401.345906)
			(xy 172.687488 -401.320254) (xy 172.693285 -401.313109) (xy 172.6998 -401.295918) (xy 172.700188 -401.286726)
			(xy 172.700188 -400.793458) (xy 172.699801 -400.784268) (xy 172.693272 -400.767084) (xy 172.687488 -400.75993)
			(xy 172.665705 -400.734274) (xy 172.627752 -400.678689) (xy 172.596716 -400.618966) (xy 172.573041 -400.555962)
			(xy 172.557066 -400.49058) (xy 172.549021 -400.423757) (xy 172.54902 -400.356452) (xy 172.557065 -400.289629)
			(xy 172.573038 -400.224246) (xy 172.596713 -400.161242) (xy 172.627748 -400.101519) (xy 172.665699 -400.045933)
			(xy 172.687488 -400.020282) (xy 172.693273 -400.013129) (xy 172.699795 -399.995944) (xy 172.700188 -399.986754)
			(xy 172.700188 -399.828766) (xy 172.700537 -399.818586) (xy 172.708343 -399.799781) (xy 172.722752 -399.785395)
			(xy 172.741569 -399.777621) (xy 172.75175 -399.777204) (xy 173.46803 -399.777204) (xy 173.478186 -399.777708)
			(xy 173.496949 -399.785486) (xy 173.511312 -399.799848) (xy 173.519091 -399.818611) (xy 173.519592 -399.828766)
			(xy 173.519592 -399.986754) (xy 173.520026 -399.995939) (xy 173.526523 -400.013123) (xy 173.532292 -400.020282)
			(xy 173.554085 -400.04593) (xy 173.592031 -400.101518) (xy 173.623063 -400.161242) (xy 173.646734 -400.224247)
			(xy 173.662705 -400.289629) (xy 173.670749 -400.356452) (xy 173.670748 -400.423757) (xy 173.662704 -400.490579)
			(xy 173.646731 -400.555962) (xy 173.623059 -400.618966) (xy 173.592027 -400.67869) (xy 173.554079 -400.734277)
			(xy 173.532292 -400.75993) (xy 173.526499 -400.767078) (xy 173.519983 -400.784266) (xy 173.519592 -400.793458)
			(xy 173.519592 -401.286726) (xy 173.519991 -401.295914) (xy 173.526513 -401.313099) (xy 173.532292 -401.320254)
			(xy 173.554057 -401.345924) (xy 173.592005 -401.401509) (xy 173.623037 -401.46123) (xy 173.64671 -401.524232)
			(xy 173.662683 -401.589612) (xy 173.670729 -401.656432) (xy 173.670731 -401.723735) (xy 173.662689 -401.790555)
			(xy 173.64672 -401.855936) (xy 173.623051 -401.918939) (xy 173.592022 -401.978663) (xy 173.554077 -402.034249)
			(xy 173.532292 -402.059902) (xy 173.526511 -402.067058) (xy 173.519987 -402.08424) (xy 173.519592 -402.09343)
			(xy 173.519592 -402.251418) (xy 173.519082 -402.261573) (xy 173.511308 -402.280337) (xy 173.496947 -402.294701)
			(xy 173.478185 -402.30248) (xy 173.46803 -402.30298) (xy 172.75175 -402.30298) (xy 172.741584 -402.302496)
			(xy 172.722794 -402.29473) (xy 172.708408 -402.280363) (xy 172.700618 -402.261584) (xy 172.700188 -402.251418)
			(xy 172.700188 -402.09343) (xy 172.699766 -402.084244) (xy 172.693261 -402.067059) (xy 172.687488 -402.059902)
			(xy 172.665677 -402.034268) (xy 172.627726 -401.97868) (xy 172.596691 -401.918955) (xy 172.573017 -401.855948)
			(xy 172.557044 -401.790563) (xy 172.549001 -401.723737) (xy 171.421001 -401.723737) (xy 171.392099 -401.779215)
			(xy 171.354009 -401.834848) (xy 171.332144 -401.860512) (xy 171.326353 -401.867661) (xy 171.319836 -401.884849)
			(xy 171.319444 -401.89404) (xy 171.319444 -402.386292) (xy 171.31987 -402.395477) (xy 171.326374 -402.412661)
			(xy 171.332144 -402.41982) (xy 171.353963 -402.445523) (xy 171.392057 -402.501151) (xy 171.423213 -402.560941)
			(xy 171.446982 -402.624033) (xy 171.463022 -402.689518) (xy 171.471103 -402.756453) (xy 171.471107 -402.823818)
			(xy 174.749143 -402.823818) (xy 174.749147 -402.75651) (xy 174.757196 -402.689684) (xy 174.773174 -402.624299)
			(xy 174.796852 -402.561292) (xy 174.827891 -402.501567) (xy 174.865845 -402.44598) (xy 174.887636 -402.420328)
			(xy 174.89345 -402.413195) (xy 174.899953 -402.395995) (xy 174.900336 -402.3868) (xy 174.900336 -401.893532)
			(xy 174.899902 -401.884348) (xy 174.893404 -401.867163) (xy 174.887636 -401.860004) (xy 174.865829 -401.834368)
			(xy 174.827881 -401.778779) (xy 174.796848 -401.719053) (xy 174.773177 -401.656047) (xy 174.757205 -401.590663)
			(xy 174.749163 -401.523838) (xy 174.749165 -401.456532) (xy 174.757211 -401.389708) (xy 174.773186 -401.324324)
			(xy 174.796861 -401.261319) (xy 174.827896 -401.201595) (xy 174.865847 -401.146008) (xy 174.887636 -401.120356)
			(xy 174.893438 -401.113215) (xy 174.899949 -401.096021) (xy 174.900336 -401.086828) (xy 174.900336 -400.92884)
			(xy 174.900755 -400.918684) (xy 174.908544 -400.899926) (xy 174.922943 -400.8856) (xy 174.94174 -400.877905)
			(xy 174.951898 -400.877532) (xy 175.668178 -400.877532) (xy 175.678302 -400.878044) (xy 175.697022 -400.885763)
			(xy 175.711378 -400.900042) (xy 175.7192 -400.918718) (xy 175.71974 -400.92884) (xy 175.71974 -401.086828)
			(xy 175.72015 -401.096015) (xy 175.726665 -401.113198) (xy 175.73244 -401.120356) (xy 175.754209 -401.146024)
			(xy 175.792159 -401.201608) (xy 175.823195 -401.261329) (xy 175.846869 -401.324331) (xy 175.862844 -401.389712)
			(xy 175.870891 -401.456533) (xy 175.870892 -401.523837) (xy 175.86285 -401.590658) (xy 175.846878 -401.65604)
			(xy 175.823207 -401.719044) (xy 175.792175 -401.778766) (xy 175.754227 -401.834352) (xy 175.73244 -401.860004)
			(xy 175.726652 -401.867155) (xy 175.720134 -401.884341) (xy 175.71974 -401.893532) (xy 175.71974 -402.3868)
			(xy 175.720164 -402.395985) (xy 175.726669 -402.413169) (xy 175.73244 -402.420328) (xy 175.754181 -402.446019)
			(xy 175.792133 -402.501599) (xy 175.823169 -402.561317) (xy 175.846846 -402.624317) (xy 175.862823 -402.689694)
			(xy 175.870871 -402.756513) (xy 175.870875 -402.823815) (xy 175.862835 -402.890634) (xy 175.846867 -402.956014)
			(xy 175.823199 -403.019017) (xy 175.79217 -403.078739) (xy 175.754225 -403.134324) (xy 175.73244 -403.159976)
			(xy 175.726621 -403.167105) (xy 175.720122 -403.184308) (xy 175.71974 -403.193504) (xy 175.71974 -403.351492)
			(xy 175.719273 -403.361641) (xy 175.711487 -403.380385) (xy 175.697105 -403.394707) (xy 175.678328 -403.402415)
			(xy 175.668178 -403.4028) (xy 174.951898 -403.4028) (xy 174.941776 -403.402276) (xy 174.923063 -403.394555)
			(xy 174.908708 -403.380281) (xy 174.900882 -403.361611) (xy 174.900336 -403.351492) (xy 174.900336 -403.193504)
			(xy 174.899916 -403.184318) (xy 174.893408 -403.167134) (xy 174.887636 -403.159976) (xy 174.865801 -403.134363)
			(xy 174.827854 -403.078771) (xy 174.796823 -403.019042) (xy 174.773153 -402.956032) (xy 174.757183 -402.890645)
			(xy 174.749143 -402.823818) (xy 171.471107 -402.823818) (xy 171.471107 -402.823874) (xy 171.463035 -402.89081)
			(xy 171.447003 -402.956298) (xy 171.423242 -403.019393) (xy 171.392094 -403.079187) (xy 171.354007 -403.13482)
			(xy 171.332144 -403.160484) (xy 171.326322 -403.167611) (xy 171.319824 -403.184816) (xy 171.319444 -403.194012)
			(xy 171.319444 -403.351492) (xy 171.318909 -403.361595) (xy 171.311183 -403.380264) (xy 171.296901 -403.394558)
			(xy 171.278238 -403.402301) (xy 171.268136 -403.4028) (xy 170.551856 -403.4028) (xy 170.541744 -403.402351)
			(xy 170.523065 -403.394599) (xy 170.508772 -403.380291) (xy 170.501039 -403.361604) (xy 170.500548 -403.351492)
			(xy 170.500548 -403.194012) (xy 170.500121 -403.184827) (xy 170.493618 -403.167643) (xy 170.487848 -403.160484)
			(xy 170.465935 -403.134858) (xy 170.427845 -403.079219) (xy 170.396693 -403.019418) (xy 170.37293 -402.956316)
			(xy 170.356896 -402.890822) (xy 170.348823 -402.823878) (xy 167.070779 -402.823878) (xy 167.062748 -402.890634)
			(xy 167.04678 -402.956014) (xy 167.023112 -403.019016) (xy 166.992084 -403.078738) (xy 166.954141 -403.134324)
			(xy 166.932356 -403.159976) (xy 166.926539 -403.167107) (xy 166.920038 -403.184308) (xy 166.919656 -403.193504)
			(xy 166.919656 -403.351492) (xy 166.919173 -403.361639) (xy 166.911391 -403.38038) (xy 166.897014 -403.394702)
			(xy 166.878242 -403.402412) (xy 166.868094 -403.4028) (xy 166.151814 -403.4028) (xy 166.141693 -403.402263)
			(xy 166.12298 -403.394547) (xy 166.108624 -403.380277) (xy 166.100798 -403.36161) (xy 166.100252 -403.351492)
			(xy 166.100252 -403.193504) (xy 166.099828 -403.184318) (xy 166.093323 -403.167135) (xy 166.087552 -403.159976)
			(xy 166.065717 -403.134363) (xy 166.027768 -403.078771) (xy 165.996736 -403.019042) (xy 165.973066 -402.956033)
			(xy 165.957096 -402.890646) (xy 165.949055 -402.823818) (xy 162.671019 -402.823818) (xy 162.671019 -402.823874)
			(xy 162.662948 -402.89081) (xy 162.646916 -402.956297) (xy 162.623155 -403.019392) (xy 162.592008 -403.079187)
			(xy 162.553923 -403.13482) (xy 162.53206 -403.160484) (xy 162.52624 -403.167613) (xy 162.51974 -403.184816)
			(xy 162.51936 -403.194012) (xy 162.51936 -403.351492) (xy 162.518976 -403.361619) (xy 162.511224 -403.38033)
			(xy 162.496896 -403.394646) (xy 162.478179 -403.402384) (xy 162.468052 -403.4028) (xy 161.751772 -403.4028)
			(xy 161.741661 -403.402338) (xy 161.722983 -403.394591) (xy 161.708689 -403.380287) (xy 161.700955 -403.361603)
			(xy 161.700464 -403.351492) (xy 161.700464 -403.194012) (xy 161.700034 -403.184827) (xy 161.693532 -403.167643)
			(xy 161.687764 -403.160484) (xy 161.665854 -403.134857) (xy 161.627769 -403.079216) (xy 161.596623 -403.019414)
			(xy 161.572863 -402.956313) (xy 161.556832 -402.890819) (xy 161.54876 -402.823877) (xy 154.57678 -402.823877)
			(xy 154.57678 -405.623648) (xy 159.349158 -405.623648) (xy 159.349158 -405.556343) (xy 159.357202 -405.48952)
			(xy 159.373175 -405.424138) (xy 159.396848 -405.361133) (xy 159.427881 -405.301409) (xy 159.465829 -405.245822)
			(xy 159.487616 -405.22017) (xy 159.49341 -405.213023) (xy 159.499926 -405.195834) (xy 159.500316 -405.186642)
			(xy 159.500316 -404.693374) (xy 159.499915 -404.684186) (xy 159.493395 -404.667002) (xy 159.487616 -404.659846)
			(xy 159.465851 -404.634176) (xy 159.427903 -404.578591) (xy 159.39687 -404.51887) (xy 159.373197 -404.455868)
			(xy 159.357223 -404.390488) (xy 159.349177 -404.323668) (xy 159.349175 -404.256365) (xy 159.357217 -404.189544)
			(xy 159.373187 -404.124164) (xy 159.396856 -404.06116) (xy 159.427886 -404.001437) (xy 159.46583 -403.94585)
			(xy 159.487616 -403.920198) (xy 159.493398 -403.913042) (xy 159.499921 -403.89586) (xy 159.500316 -403.88667)
			(xy 159.500316 -403.728682) (xy 159.500818 -403.718526) (xy 159.508594 -403.69976) (xy 159.522957 -403.685396)
			(xy 159.541722 -403.677619) (xy 159.551878 -403.67712) (xy 160.268158 -403.67712) (xy 160.278325 -403.677598)
			(xy 160.297115 -403.685366) (xy 160.311501 -403.699735) (xy 160.31929 -403.718516) (xy 160.31972 -403.728682)
			(xy 160.31972 -403.88667) (xy 160.32014 -403.895856) (xy 160.326646 -403.913041) (xy 160.33242 -403.920198)
			(xy 160.354231 -403.945832) (xy 160.392181 -404.00142) (xy 160.423216 -404.061146) (xy 160.446889 -404.124153)
			(xy 160.462862 -404.189538) (xy 160.470905 -404.256363) (xy 160.470903 -404.32367) (xy 160.462856 -404.390495)
			(xy 160.446879 -404.455879) (xy 160.423202 -404.518885) (xy 160.392164 -404.578608) (xy 160.35421 -404.634194)
			(xy 160.33242 -404.659846) (xy 160.326624 -404.666992) (xy 160.320108 -404.684182) (xy 160.31972 -404.693374)
			(xy 160.31972 -405.186642) (xy 160.320105 -405.195832) (xy 160.326636 -405.213016) (xy 160.33242 -405.22017)
			(xy 160.354203 -405.245826) (xy 160.392155 -405.301411) (xy 160.42319 -405.361134) (xy 160.446865 -405.424138)
			(xy 160.46284 -405.48952) (xy 160.470885 -405.556343) (xy 160.470886 -405.623648) (xy 160.462842 -405.690471)
			(xy 160.446868 -405.755853) (xy 160.423194 -405.818858) (xy 160.392159 -405.878581) (xy 160.354209 -405.934166)
			(xy 160.33242 -405.959818) (xy 160.326636 -405.966972) (xy 160.320113 -405.984156) (xy 160.31972 -405.993346)
			(xy 160.31972 -406.151334) (xy 160.319363 -406.161513) (xy 160.311559 -406.180317) (xy 160.297153 -406.194702)
			(xy 160.278338 -406.202478) (xy 160.268158 -406.202896) (xy 159.551878 -406.202896) (xy 159.541723 -406.202386)
			(xy 159.52296 -406.19461) (xy 159.508596 -406.18025) (xy 159.500817 -406.161489) (xy 159.500316 -406.151334)
			(xy 159.500316 -405.993346) (xy 159.49988 -405.984162) (xy 159.493384 -405.966977) (xy 159.487616 -405.959818)
			(xy 159.465823 -405.93417) (xy 159.427876 -405.878583) (xy 159.396844 -405.818858) (xy 159.373173 -405.755853)
			(xy 159.357201 -405.690471) (xy 159.349158 -405.623648) (xy 154.57678 -405.623648) (xy 154.57678 -406.723789)
			(xy 161.548771 -406.723789) (xy 161.548774 -406.656363) (xy 161.556853 -406.589423) (xy 161.572891 -406.523933)
			(xy 161.596657 -406.460835) (xy 161.627809 -406.401038) (xy 161.665899 -406.345402) (xy 161.687764 -406.319736)
			(xy 161.693578 -406.312604) (xy 161.70008 -406.295403) (xy 161.700464 -406.286208) (xy 161.700464 -405.793956)
			(xy 161.700061 -405.784768) (xy 161.693541 -405.767585) (xy 161.687764 -405.760428) (xy 161.665897 -405.734765)
			(xy 161.627811 -405.67913) (xy 161.596663 -405.619333) (xy 161.5729 -405.556236) (xy 161.556866 -405.490747)
			(xy 161.548791 -405.423809) (xy 161.548792 -405.356385) (xy 161.556867 -405.289447) (xy 161.572902 -405.223959)
			(xy 161.596665 -405.160862) (xy 161.627814 -405.101065) (xy 161.665901 -405.04543) (xy 161.687764 -405.019764)
			(xy 161.693566 -405.012623) (xy 161.700076 -404.995429) (xy 161.700464 -404.986236) (xy 161.700464 -404.828756)
			(xy 161.700948 -404.818649) (xy 161.708694 -404.799977) (xy 161.72299 -404.785685) (xy 161.741665 -404.777945)
			(xy 161.751772 -404.777448) (xy 162.468052 -404.777448) (xy 162.478165 -404.777954) (xy 162.496858 -404.785677)
			(xy 162.511172 -404.799965) (xy 162.518928 -404.818644) (xy 162.51936 -404.828756) (xy 162.51936 -404.986236)
			(xy 162.519762 -404.995424) (xy 162.526282 -405.012608) (xy 162.53206 -405.019764) (xy 162.553921 -405.045432)
			(xy 162.592013 -405.101065) (xy 162.623166 -405.16086) (xy 162.646932 -405.223957) (xy 162.662969 -405.289446)
			(xy 162.671046 -405.356385) (xy 162.671046 -405.423809) (xy 162.66297 -405.490748) (xy 162.646934 -405.556237)
			(xy 162.623168 -405.619334) (xy 162.620889 -405.623708) (xy 163.748926 -405.623708) (xy 163.748926 -405.556283)
			(xy 163.757003 -405.489344) (xy 163.77304 -405.423855) (xy 163.796805 -405.360758) (xy 163.827957 -405.300961)
			(xy 163.866047 -405.245327) (xy 163.887912 -405.219662) (xy 163.893709 -405.212517) (xy 163.900223 -405.195326)
			(xy 163.900612 -405.186134) (xy 163.900612 -404.693882) (xy 163.900208 -404.684694) (xy 163.89369 -404.66751)
			(xy 163.887912 -404.660354) (xy 163.866069 -404.634671) (xy 163.827979 -404.579039) (xy 163.796827 -404.519246)
			(xy 163.773061 -404.456151) (xy 163.757023 -404.390664) (xy 163.748946 -404.323728) (xy 163.748944 -404.256305)
			(xy 163.757018 -404.189368) (xy 163.773051 -404.12388) (xy 163.796813 -404.060784) (xy 163.827962 -404.000989)
			(xy 163.866049 -403.945355) (xy 163.887912 -403.91969) (xy 163.893697 -403.912536) (xy 163.900218 -403.895352)
			(xy 163.900612 -403.886162) (xy 163.900612 -403.728682) (xy 163.901111 -403.718558) (xy 163.908839 -403.699841)
			(xy 163.923121 -403.685486) (xy 163.941798 -403.677663) (xy 163.95192 -403.67712) (xy 164.6682 -403.67712)
			(xy 164.678357 -403.677522) (xy 164.697113 -403.685321) (xy 164.711437 -403.699724) (xy 164.719133 -403.718523)
			(xy 164.719508 -403.728682) (xy 164.719508 -403.886162) (xy 164.719935 -403.895347) (xy 164.726437 -403.912532)
			(xy 164.732208 -403.91969) (xy 164.754093 -403.945338) (xy 164.792181 -404.000975) (xy 164.82333 -404.060774)
			(xy 164.847093 -404.123873) (xy 164.863126 -404.189364) (xy 164.8712 -404.256304) (xy 164.871198 -404.323729)
			(xy 164.86312 -404.390669) (xy 164.847083 -404.456159) (xy 164.823317 -404.519257) (xy 164.792164 -404.579054)
			(xy 164.754073 -404.634689) (xy 164.732208 -404.660354) (xy 164.726407 -404.667496) (xy 164.719895 -404.684689)
			(xy 164.719508 -404.693882) (xy 164.719508 -405.186134) (xy 164.7199 -405.195323) (xy 164.726426 -405.212508)
			(xy 164.732208 -405.219662) (xy 164.754066 -405.245332) (xy 164.792154 -405.300966) (xy 164.823305 -405.360762)
			(xy 164.847069 -405.423858) (xy 164.863104 -405.489346) (xy 164.871181 -405.556284) (xy 164.871181 -405.623707)
			(xy 164.863106 -405.690645) (xy 164.847072 -405.756133) (xy 164.823308 -405.81923) (xy 164.792159 -405.879026)
			(xy 164.754071 -405.934661) (xy 164.732208 -405.960326) (xy 164.726419 -405.967477) (xy 164.719899 -405.984663)
			(xy 164.719508 -405.993854) (xy 164.719508 -406.151334) (xy 164.719003 -406.161457) (xy 164.711273 -406.18017)
			(xy 164.696993 -406.194523) (xy 164.67832 -406.20235) (xy 164.6682 -406.202896) (xy 163.95192 -406.202896)
			(xy 163.941767 -406.202462) (xy 163.923014 -406.194672) (xy 163.90869 -406.180279) (xy 163.90099 -406.161489)
			(xy 163.900612 -406.151334) (xy 163.900612 -405.993854) (xy 163.900173 -405.98467) (xy 163.893679 -405.967485)
			(xy 163.887912 -405.960326) (xy 163.866042 -405.934666) (xy 163.827952 -405.879031) (xy 163.796801 -405.819234)
			(xy 163.773037 -405.756137) (xy 163.757001 -405.690647) (xy 163.748926 -405.623708) (xy 162.620889 -405.623708)
			(xy 162.592016 -405.67913) (xy 162.553925 -405.734763) (xy 162.53206 -405.760428) (xy 162.526264 -405.767573)
			(xy 162.51975 -405.784764) (xy 162.51936 -405.793956) (xy 162.51936 -406.286208) (xy 162.519775 -406.295394)
			(xy 162.526286 -406.312578) (xy 162.53206 -406.319736) (xy 162.553894 -406.345426) (xy 162.591986 -406.401056)
			(xy 162.623141 -406.460849) (xy 162.646908 -406.523942) (xy 162.662947 -406.589429) (xy 162.671026 -406.656365)
			(xy 162.671029 -406.72373) (xy 165.949066 -406.72373) (xy 165.949069 -406.656422) (xy 165.957117 -406.589597)
			(xy 165.973094 -406.524213) (xy 165.996771 -406.461207) (xy 166.027808 -406.401483) (xy 166.065762 -406.345896)
			(xy 166.087552 -406.320244) (xy 166.093361 -406.313108) (xy 166.099867 -406.29591) (xy 166.100252 -406.286716)
			(xy 166.100252 -405.793448) (xy 166.099807 -405.784265) (xy 166.093316 -405.767081) (xy 166.087552 -405.75992)
			(xy 166.06576 -405.734271) (xy 166.027811 -405.678685) (xy 165.996777 -405.618961) (xy 165.973104 -405.555956)
			(xy 165.957131 -405.490573) (xy 165.949087 -405.42375) (xy 165.949087 -405.356444) (xy 165.957132 -405.289621)
			(xy 165.973105 -405.224239) (xy 165.996779 -405.161234) (xy 166.027814 -405.10151) (xy 166.065764 -405.045924)
			(xy 166.087552 -405.020272) (xy 166.093349 -405.013128) (xy 166.099862 -404.995936) (xy 166.100252 -404.986744)
			(xy 166.100252 -404.828756) (xy 166.100685 -404.818605) (xy 166.108486 -404.799861) (xy 166.122878 -404.785541)
			(xy 166.141661 -404.777834) (xy 166.151814 -404.777448) (xy 166.868094 -404.777448) (xy 166.878221 -404.777932)
			(xy 166.896944 -404.785659) (xy 166.911301 -404.799946) (xy 166.919119 -404.818631) (xy 166.919656 -404.828756)
			(xy 166.919656 -404.986744) (xy 166.920055 -404.995932) (xy 166.926578 -405.013116) (xy 166.932356 -405.020272)
			(xy 166.95414 -405.045927) (xy 166.992089 -405.101513) (xy 167.023123 -405.161236) (xy 167.046796 -405.22424)
			(xy 167.062769 -405.289622) (xy 167.070814 -405.356445) (xy 167.070814 -405.423749) (xy 167.06277 -405.490572)
			(xy 167.046798 -405.555954) (xy 167.023125 -405.618958) (xy 167.020688 -405.623648) (xy 168.149245 -405.623648)
			(xy 168.149246 -405.556343) (xy 168.15729 -405.489521) (xy 168.173263 -405.424139) (xy 168.196934 -405.361134)
			(xy 168.227966 -405.30141) (xy 168.265913 -405.245823) (xy 168.2877 -405.22017) (xy 168.293492 -405.213021)
			(xy 168.300009 -405.195834) (xy 168.3004 -405.186642) (xy 168.3004 -404.693374) (xy 168.300003 -404.684185)
			(xy 168.29348 -404.667001) (xy 168.2877 -404.659846) (xy 168.265935 -404.634176) (xy 168.227988 -404.578591)
			(xy 168.196956 -404.518869) (xy 168.173284 -404.455867) (xy 168.15731 -404.390488) (xy 168.149265 -404.323668)
			(xy 168.149263 -404.256365) (xy 168.157305 -404.189545) (xy 168.173274 -404.124164) (xy 168.196943 -404.061161)
			(xy 168.227971 -404.001438) (xy 168.265915 -403.945851) (xy 168.2877 -403.920198) (xy 168.29348 -403.913041)
			(xy 168.300005 -403.89586) (xy 168.3004 -403.88667) (xy 168.3004 -403.728682) (xy 168.300917 -403.718528)
			(xy 168.308691 -403.699765) (xy 168.323049 -403.685402) (xy 168.341808 -403.677621) (xy 168.351962 -403.67712)
			(xy 169.068242 -403.67712) (xy 169.0784 -403.677599) (xy 169.097167 -403.685383) (xy 169.11153 -403.699753)
			(xy 169.119306 -403.718524) (xy 169.119804 -403.728682) (xy 169.119804 -403.88667) (xy 169.120228 -403.895856)
			(xy 169.126732 -403.91304) (xy 169.132504 -403.920198) (xy 169.154312 -403.945833) (xy 169.192257 -404.001423)
			(xy 169.223287 -404.061149) (xy 169.246957 -404.124156) (xy 169.262927 -404.18954) (xy 169.270969 -404.256364)
			(xy 169.270967 -404.32367) (xy 169.262921 -404.390493) (xy 169.246947 -404.455876) (xy 169.223274 -404.518881)
			(xy 169.19224 -404.578606) (xy 169.154292 -404.634193) (xy 169.132504 -404.659846) (xy 169.126706 -404.66699)
			(xy 169.120192 -404.684181) (xy 169.119804 -404.693374) (xy 169.119804 -405.186642) (xy 169.120193 -405.195832)
			(xy 169.126721 -405.213016) (xy 169.132504 -405.22017) (xy 169.154284 -405.245828) (xy 169.192231 -405.301414)
			(xy 169.223262 -405.361137) (xy 169.246933 -405.424141) (xy 169.262905 -405.489522) (xy 169.270949 -405.556344)
			(xy 169.27095 -405.623647) (xy 169.262907 -405.690469) (xy 169.246936 -405.75585) (xy 169.223266 -405.818854)
			(xy 169.192235 -405.878578) (xy 169.15429 -405.934165) (xy 169.132504 -405.959818) (xy 169.126718 -405.966971)
			(xy 169.120197 -405.984155) (xy 169.119804 -405.993346) (xy 169.119804 -406.151334) (xy 169.119296 -406.161489)
			(xy 169.111518 -406.180251) (xy 169.097157 -406.194613) (xy 169.078397 -406.202394) (xy 169.068242 -406.202896)
			(xy 168.351962 -406.202896) (xy 168.341806 -406.202399) (xy 168.323042 -406.194618) (xy 168.30868 -406.180254)
			(xy 168.300901 -406.16149) (xy 168.3004 -406.151334) (xy 168.3004 -405.993346) (xy 168.299968 -405.984161)
			(xy 168.293469 -405.966977) (xy 168.2877 -405.959818) (xy 168.265908 -405.93417) (xy 168.227961 -405.878582)
			(xy 168.196931 -405.818858) (xy 168.17326 -405.755853) (xy 168.157289 -405.69047) (xy 168.149245 -405.623648)
			(xy 167.020688 -405.623648) (xy 166.992092 -405.678681) (xy 166.954143 -405.734268) (xy 166.932356 -405.75992)
			(xy 166.926563 -405.767067) (xy 166.920047 -405.784256) (xy 166.919656 -405.793448) (xy 166.919656 -406.286716)
			(xy 166.920068 -406.295903) (xy 166.926582 -406.313087) (xy 166.932356 -406.320244) (xy 166.954112 -406.345922)
			(xy 166.992062 -406.401505) (xy 167.023097 -406.461225) (xy 167.046772 -406.524226) (xy 167.062747 -406.589605)
			(xy 167.070794 -406.656425) (xy 167.070797 -406.723727) (xy 167.070789 -406.72379) (xy 170.348835 -406.72379)
			(xy 170.348838 -406.656362) (xy 170.356917 -406.589421) (xy 170.372958 -406.52393) (xy 170.396728 -406.460831)
			(xy 170.427885 -406.401034) (xy 170.46598 -406.3454) (xy 170.487848 -406.319736) (xy 170.49366 -406.312602)
			(xy 170.500164 -406.295403) (xy 170.500548 -406.286208) (xy 170.500548 -405.793956) (xy 170.500148 -405.784768)
			(xy 170.493626 -405.767584) (xy 170.487848 -405.760428) (xy 170.465978 -405.734767) (xy 170.427887 -405.679133)
			(xy 170.396733 -405.619337) (xy 170.372967 -405.556239) (xy 170.356931 -405.490749) (xy 170.348854 -405.423809)
			(xy 170.348855 -405.356385) (xy 170.356932 -405.289445) (xy 170.372969 -405.223955) (xy 170.396736 -405.160858)
			(xy 170.42789 -405.101062) (xy 170.465982 -405.045428) (xy 170.487848 -405.019764) (xy 170.493648 -405.012622)
			(xy 170.500159 -404.995429) (xy 170.500548 -404.986236) (xy 170.500548 -404.828756) (xy 170.501048 -404.818651)
			(xy 170.50879 -404.799982) (xy 170.523082 -404.78569) (xy 170.541751 -404.777948) (xy 170.551856 -404.777448)
			(xy 171.268136 -404.777448) (xy 171.278241 -404.777954) (xy 171.29691 -404.785694) (xy 171.311201 -404.799984)
			(xy 171.318944 -404.818651) (xy 171.319444 -404.828756) (xy 171.319444 -404.986236) (xy 171.31985 -404.995423)
			(xy 171.326368 -405.012607) (xy 171.332144 -405.019764) (xy 171.354006 -405.045432) (xy 171.392099 -405.101064)
			(xy 171.423253 -405.16086) (xy 171.447019 -405.223956) (xy 171.463057 -405.289446) (xy 171.471134 -405.356385)
			(xy 171.471134 -405.423809) (xy 171.463058 -405.490748) (xy 171.447021 -405.556238) (xy 171.423255 -405.619335)
			(xy 171.421007 -405.623649) (xy 172.549012 -405.623649) (xy 172.549013 -405.556342) (xy 172.557058 -405.489518)
			(xy 172.573033 -405.424135) (xy 172.596709 -405.36113) (xy 172.627746 -405.301407) (xy 172.665698 -405.245822)
			(xy 172.687488 -405.22017) (xy 172.693278 -405.21302) (xy 172.699797 -405.195833) (xy 172.700188 -405.186642)
			(xy 172.700188 -404.693374) (xy 172.699793 -404.684185) (xy 172.693269 -404.667001) (xy 172.687488 -404.659846)
			(xy 172.66572 -404.634177) (xy 172.627768 -404.578594) (xy 172.596731 -404.518873) (xy 172.573055 -404.455871)
			(xy 172.557079 -404.39049) (xy 172.549032 -404.323669) (xy 172.54903 -404.256364) (xy 172.557073 -404.189542)
			(xy 172.573045 -404.124161) (xy 172.596717 -404.061157) (xy 172.627751 -404.001435) (xy 172.6657 -403.945849)
			(xy 172.687488 -403.920198) (xy 172.693267 -403.91304) (xy 172.699792 -403.895859) (xy 172.700188 -403.88667)
			(xy 172.700188 -403.728682) (xy 172.70055 -403.718503) (xy 172.708351 -403.699698) (xy 172.722756 -403.685313)
			(xy 172.74157 -403.677537) (xy 172.75175 -403.67712) (xy 173.46803 -403.67712) (xy 173.478187 -403.677608)
			(xy 173.496954 -403.685389) (xy 173.511317 -403.699756) (xy 173.519094 -403.718524) (xy 173.519592 -403.728682)
			(xy 173.519592 -403.88667) (xy 173.520018 -403.895855) (xy 173.526521 -403.91304) (xy 173.532292 -403.920198)
			(xy 173.5541 -403.945833) (xy 173.592047 -404.001422) (xy 173.623077 -404.061149) (xy 173.646747 -404.124155)
			(xy 173.662718 -404.189539) (xy 173.67076 -404.256363) (xy 173.670758 -404.32367) (xy 173.662712 -404.390493)
			(xy 173.646738 -404.455876) (xy 173.623064 -404.518882) (xy 173.59203 -404.578606) (xy 173.55408 -404.634193)
			(xy 173.532292 -404.659846) (xy 173.526492 -404.666989) (xy 173.51998 -404.684181) (xy 173.519592 -404.693374)
			(xy 173.519592 -405.186642) (xy 173.519984 -405.195831) (xy 173.52651 -405.213015) (xy 173.532292 -405.22017)
			(xy 173.554073 -405.245827) (xy 173.59202 -405.301414) (xy 173.623052 -405.361137) (xy 173.646723 -405.424141)
			(xy 173.662696 -405.489522) (xy 173.67074 -405.556343) (xy 173.670741 -405.623647) (xy 173.662698 -405.690469)
			(xy 173.646726 -405.755851) (xy 173.623055 -405.818855) (xy 173.592025 -405.878578) (xy 173.554078 -405.934165)
			(xy 173.532292 -405.959818) (xy 173.526504 -405.96697) (xy 173.519985 -405.984155) (xy 173.519592 -405.993346)
			(xy 173.519592 -406.151334) (xy 173.519095 -406.16149) (xy 173.511315 -406.180254) (xy 173.496951 -406.194617)
			(xy 173.478186 -406.202396) (xy 173.46803 -406.202896) (xy 172.75175 -406.202896) (xy 172.741586 -406.202396)
			(xy 172.722799 -406.194634) (xy 172.708413 -406.180272) (xy 172.70062 -406.161497) (xy 172.700188 -406.151334)
			(xy 172.700188 -405.993346) (xy 172.699759 -405.984161) (xy 172.693259 -405.966976) (xy 172.687488 -405.959818)
			(xy 172.665693 -405.934171) (xy 172.627741 -405.878585) (xy 172.596705 -405.818861) (xy 172.573031 -405.755856)
			(xy 172.557057 -405.690473) (xy 172.549012 -405.623649) (xy 171.421007 -405.623649) (xy 171.392102 -405.67913)
			(xy 171.35401 -405.734764) (xy 171.332144 -405.760428) (xy 171.326346 -405.767572) (xy 171.319834 -405.784764)
			(xy 171.319444 -405.793956) (xy 171.319444 -406.286208) (xy 171.319863 -406.295394) (xy 171.326372 -406.312578)
			(xy 171.332144 -406.319736) (xy 171.353978 -406.345426) (xy 171.392072 -406.401056) (xy 171.423227 -406.460848)
			(xy 171.446996 -406.523942) (xy 171.463035 -406.589428) (xy 171.471114 -406.656365) (xy 171.471117 -406.72373)
			(xy 174.749154 -406.72373) (xy 174.749157 -406.656422) (xy 174.757205 -406.589597) (xy 174.773181 -406.524213)
			(xy 174.796857 -406.461208) (xy 174.827894 -406.401483) (xy 174.865846 -406.345896) (xy 174.887636 -406.320244)
			(xy 174.893443 -406.313107) (xy 174.899951 -406.29591) (xy 174.900336 -406.286716) (xy 174.900336 -405.793448)
			(xy 174.899895 -405.784264) (xy 174.893402 -405.76708) (xy 174.887636 -405.75992) (xy 174.865844 -405.734271)
			(xy 174.827896 -405.678684) (xy 174.796863 -405.61896) (xy 174.77319 -405.555955) (xy 174.757218 -405.490573)
			(xy 174.749174 -405.42375) (xy 174.749174 -405.356444) (xy 174.757219 -405.289621) (xy 174.773192 -405.224239)
			(xy 174.796865 -405.161234) (xy 174.827899 -405.101511) (xy 174.865848 -405.045924) (xy 174.887636 -405.020272)
			(xy 174.893432 -405.013126) (xy 174.899946 -404.995936) (xy 174.900336 -404.986744) (xy 174.900336 -404.828756)
			(xy 174.900686 -404.818594) (xy 174.908503 -404.799834) (xy 174.922922 -404.785511) (xy 174.941734 -404.77782)
			(xy 174.951898 -404.777448) (xy 175.668178 -404.777448) (xy 175.678304 -404.777945) (xy 175.697027 -404.785667)
			(xy 175.711384 -404.79995) (xy 175.719202 -404.818632) (xy 175.71974 -404.828756) (xy 175.71974 -404.986744)
			(xy 175.720142 -404.995932) (xy 175.726663 -405.013115) (xy 175.73244 -405.020272) (xy 175.754224 -405.045927)
			(xy 175.792175 -405.101513) (xy 175.823209 -405.161236) (xy 175.846883 -405.22424) (xy 175.862857 -405.289622)
			(xy 175.870902 -405.356444) (xy 175.870902 -405.42375) (xy 175.862858 -405.490572) (xy 175.846885 -405.555954)
			(xy 175.823212 -405.618959) (xy 175.792178 -405.678682) (xy 175.754228 -405.734268) (xy 175.73244 -405.75992)
			(xy 175.726645 -405.767066) (xy 175.720131 -405.784256) (xy 175.71974 -405.793448) (xy 175.71974 -406.286716)
			(xy 175.720156 -406.295902) (xy 175.726667 -406.313086) (xy 175.73244 -406.320244) (xy 175.754197 -406.345922)
			(xy 175.792148 -406.401504) (xy 175.823184 -406.461224) (xy 175.846859 -406.524225) (xy 175.862835 -406.589604)
			(xy 175.870882 -406.656424) (xy 175.870885 -406.723727) (xy 175.862844 -406.790548) (xy 175.846873 -406.855929)
			(xy 175.823203 -406.918932) (xy 175.792173 -406.978655) (xy 175.754226 -407.03424) (xy 175.73244 -407.059892)
			(xy 175.726657 -407.067046) (xy 175.720136 -407.08423) (xy 175.71974 -407.09342) (xy 175.71974 -407.251408)
			(xy 175.719286 -407.261558) (xy 175.711495 -407.280302) (xy 175.697109 -407.294624) (xy 175.678329 -407.302331)
			(xy 175.668178 -407.302716) (xy 174.951898 -407.302716) (xy 174.941766 -407.302274) (xy 174.923036 -407.294537)
			(xy 174.908679 -407.280237) (xy 174.900867 -407.261538) (xy 174.900336 -407.251408) (xy 174.900336 -407.09342)
			(xy 174.899908 -407.084235) (xy 174.893406 -407.067051) (xy 174.887636 -407.059892) (xy 174.865817 -407.034266)
			(xy 174.827869 -406.978676) (xy 174.796837 -406.918948) (xy 174.773167 -406.85594) (xy 174.757196 -406.790555)
			(xy 174.749154 -406.72373) (xy 171.471117 -406.72373) (xy 171.471117 -406.723787) (xy 171.463044 -406.790724)
			(xy 171.44701 -406.856212) (xy 171.423247 -406.919308) (xy 171.392097 -406.979103) (xy 171.354008 -407.034736)
			(xy 171.332144 -407.0604) (xy 171.326358 -407.067552) (xy 171.319839 -407.084738) (xy 171.319444 -407.093928)
			(xy 171.319444 -407.251408) (xy 171.318922 -407.261512) (xy 171.31119 -407.280182) (xy 171.296905 -407.294475)
			(xy 171.278239 -407.302217) (xy 171.268136 -407.302716) (xy 170.551856 -407.302716) (xy 170.541746 -407.302251)
			(xy 170.52307 -407.294502) (xy 170.508778 -407.280199) (xy 170.501042 -407.261518) (xy 170.500548 -407.251408)
			(xy 170.500548 -407.093928) (xy 170.500114 -407.084744) (xy 170.493616 -407.067559) (xy 170.487848 -407.0604)
			(xy 170.465951 -407.034762) (xy 170.42786 -406.979124) (xy 170.396708 -406.919325) (xy 170.372944 -406.856224)
			(xy 170.356909 -406.790732) (xy 170.348835 -406.72379) (xy 167.070789 -406.72379) (xy 167.062756 -406.790548)
			(xy 167.046786 -406.855928) (xy 167.023117 -406.918931) (xy 166.992087 -406.978654) (xy 166.954142 -407.03424)
			(xy 166.932356 -407.059892) (xy 166.926575 -407.067048) (xy 166.920052 -407.08423) (xy 166.919656 -407.09342)
			(xy 166.919656 -407.251408) (xy 166.919186 -407.261556) (xy 166.911398 -407.280297) (xy 166.897017 -407.294618)
			(xy 166.878243 -407.302328) (xy 166.868094 -407.302716) (xy 166.151814 -407.302716) (xy 166.141683 -407.302261)
			(xy 166.122954 -407.294529) (xy 166.108595 -407.280233) (xy 166.100783 -407.261537) (xy 166.100252 -407.251408)
			(xy 166.100252 -407.09342) (xy 166.099821 -407.084235) (xy 166.093321 -407.067051) (xy 166.087552 -407.059892)
			(xy 166.065732 -407.034266) (xy 166.027784 -406.978676) (xy 165.996751 -406.918949) (xy 165.973079 -406.855941)
			(xy 165.957108 -406.790556) (xy 165.949066 -406.72373) (xy 162.671029 -406.72373) (xy 162.671029 -406.723787)
			(xy 162.662956 -406.790724) (xy 162.646923 -406.856212) (xy 162.62316 -406.919307) (xy 162.592011 -406.979102)
			(xy 162.553923 -407.034735) (xy 162.53206 -407.0604) (xy 162.526276 -407.067554) (xy 162.519755 -407.084738)
			(xy 162.51936 -407.093928) (xy 162.51936 -407.251408) (xy 162.518989 -407.261536) (xy 162.511231 -407.280247)
			(xy 162.4969 -407.294563) (xy 162.47818 -407.3023) (xy 162.468052 -407.302716) (xy 161.751772 -407.302716)
			(xy 161.741663 -407.302238) (xy 161.722988 -407.294494) (xy 161.708694 -407.280196) (xy 161.700958 -407.261517)
			(xy 161.700464 -407.251408) (xy 161.700464 -407.093928) (xy 161.700026 -407.084744) (xy 161.69353 -407.06756)
			(xy 161.687764 -407.0604) (xy 161.66587 -407.03476) (xy 161.627784 -406.979121) (xy 161.596637 -406.919321)
			(xy 161.572876 -406.856221) (xy 161.556844 -406.790729) (xy 161.548771 -406.723789) (xy 154.57678 -406.723789)
			(xy 154.57678 -409.523827) (xy 159.349136 -409.523827) (xy 159.34914 -409.456519) (xy 159.357187 -409.389695)
			(xy 159.373163 -409.324311) (xy 159.396839 -409.261305) (xy 159.427875 -409.20158) (xy 159.465827 -409.145992)
			(xy 159.487616 -409.12034) (xy 159.493422 -409.113202) (xy 159.499931 -409.096006) (xy 159.500316 -409.086812)
			(xy 159.500316 -408.593544) (xy 159.499881 -408.58436) (xy 159.493384 -408.567175) (xy 159.487616 -408.560016)
			(xy 159.465821 -408.53437) (xy 159.427874 -408.478782) (xy 159.396842 -408.419058) (xy 159.373171 -408.356052)
			(xy 159.357199 -408.29067) (xy 159.349156 -408.223847) (xy 159.349157 -408.156541) (xy 159.357201 -408.089719)
			(xy 159.373175 -408.024336) (xy 159.396847 -407.961331) (xy 159.42788 -407.901607) (xy 159.465828 -407.84602)
			(xy 159.487616 -407.820368) (xy 159.49341 -407.813221) (xy 159.499926 -407.796032) (xy 159.500316 -407.78684)
			(xy 159.500316 -407.628852) (xy 159.500683 -407.618693) (xy 159.508497 -407.599936) (xy 159.522911 -407.585614)
			(xy 159.541716 -407.577919) (xy 159.551878 -407.577544) (xy 160.268158 -407.577544) (xy 160.278283 -407.578061)
			(xy 160.297003 -407.585776) (xy 160.311361 -407.600053) (xy 160.319181 -407.61873) (xy 160.31972 -407.628852)
			(xy 160.31972 -407.78684) (xy 160.320107 -407.79603) (xy 160.326636 -407.813214) (xy 160.33242 -407.820368)
			(xy 160.354201 -407.846026) (xy 160.392153 -407.901611) (xy 160.423189 -407.961333) (xy 160.446864 -408.024337)
			(xy 160.462838 -408.089719) (xy 160.470884 -408.156541) (xy 160.470885 -408.223847) (xy 160.462841 -408.290669)
			(xy 160.446867 -408.356052) (xy 160.423194 -408.419056) (xy 160.392159 -408.478779) (xy 160.354208 -408.534364)
			(xy 160.33242 -408.560016) (xy 160.326636 -408.567171) (xy 160.320113 -408.584354) (xy 160.31972 -408.593544)
			(xy 160.31972 -409.086812) (xy 160.32012 -409.096) (xy 160.32664 -409.113185) (xy 160.33242 -409.12034)
			(xy 160.354174 -409.146021) (xy 160.392126 -409.201602) (xy 160.423163 -409.261321) (xy 160.44684 -409.324322)
			(xy 160.462817 -409.389701) (xy 160.470864 -409.456521) (xy 160.470867 -409.523824) (xy 160.462826 -409.590645)
			(xy 160.446856 -409.656026) (xy 160.423185 -409.719029) (xy 160.392154 -409.778751) (xy 160.354207 -409.834336)
			(xy 160.33242 -409.859988) (xy 160.326606 -409.867121) (xy 160.320101 -409.884321) (xy 160.31972 -409.893516)
			(xy 160.31972 -410.051504) (xy 160.319282 -410.061656) (xy 160.311489 -410.080404) (xy 160.297098 -410.094727)
			(xy 160.278312 -410.10243) (xy 160.268158 -410.102812) (xy 159.551878 -410.102812) (xy 159.541756 -410.102293)
			(xy 159.523044 -410.094568) (xy 159.508691 -410.080292) (xy 159.500863 -410.061623) (xy 159.500316 -410.051504)
			(xy 159.500316 -409.893516) (xy 159.499894 -409.88433) (xy 159.493388 -409.867146) (xy 159.487616 -409.859988)
			(xy 159.465794 -409.834365) (xy 159.427847 -409.778774) (xy 159.396817 -409.719046) (xy 159.373147 -409.656038)
			(xy 159.357177 -409.590652) (xy 159.349136 -409.523827) (xy 154.57678 -409.523827) (xy 154.57678 -410.6237)
			(xy 161.548783 -410.6237) (xy 161.548784 -410.556276) (xy 161.556861 -410.489337) (xy 161.572897 -410.423848)
			(xy 161.596662 -410.36075) (xy 161.627812 -410.300953) (xy 161.6659 -410.245318) (xy 161.687764 -410.219652)
			(xy 161.693571 -410.212515) (xy 161.700078 -410.195318) (xy 161.700464 -410.186124) (xy 161.700464 -409.693872)
			(xy 161.700053 -409.684685) (xy 161.693538 -409.667502) (xy 161.687764 -409.660344) (xy 161.665913 -409.634668)
			(xy 161.627826 -409.579035) (xy 161.596677 -409.519239) (xy 161.572914 -409.456144) (xy 161.556879 -409.390657)
			(xy 161.548802 -409.32372) (xy 161.548801 -409.256298) (xy 161.556875 -409.189361) (xy 161.572909 -409.123873)
			(xy 161.59667 -409.060777) (xy 161.627817 -409.000981) (xy 161.665902 -408.945346) (xy 161.687764 -408.91968)
			(xy 161.693559 -408.912534) (xy 161.700073 -408.895344) (xy 161.700464 -408.886152) (xy 161.700464 -408.728672)
			(xy 161.700961 -408.718566) (xy 161.708701 -408.699894) (xy 161.722994 -408.685601) (xy 161.741666 -408.677861)
			(xy 161.751772 -408.677364) (xy 162.468052 -408.677364) (xy 162.478167 -408.677854) (xy 162.496863 -408.68558)
			(xy 162.511177 -408.699874) (xy 162.518931 -408.718558) (xy 162.51936 -408.728672) (xy 162.51936 -408.886152)
			(xy 162.519802 -408.895336) (xy 162.526295 -408.91252) (xy 162.53206 -408.91968) (xy 162.553937 -408.945335)
			(xy 162.592028 -409.00097) (xy 162.623181 -409.060767) (xy 162.646946 -409.123866) (xy 162.662982 -409.189356)
			(xy 162.671057 -409.256296) (xy 162.671056 -409.323722) (xy 162.662978 -409.390662) (xy 162.64694 -409.456152)
			(xy 162.623173 -409.519249) (xy 162.620757 -409.523886) (xy 163.748905 -409.523886) (xy 163.748908 -409.45646)
			(xy 163.756988 -409.389519) (xy 163.773027 -409.324027) (xy 163.796796 -409.260929) (xy 163.827952 -409.201132)
			(xy 163.866045 -409.145497) (xy 163.887912 -409.119832) (xy 163.893721 -409.112696) (xy 163.900228 -409.095498)
			(xy 163.900612 -409.086304) (xy 163.900612 -408.594052) (xy 163.900174 -408.584868) (xy 163.893679 -408.567683)
			(xy 163.887912 -408.560524) (xy 163.86604 -408.534865) (xy 163.82795 -408.47923) (xy 163.796799 -408.419433)
			(xy 163.773035 -408.356335) (xy 163.757 -408.290845) (xy 163.748925 -408.223906) (xy 163.748925 -408.156482)
			(xy 163.757002 -408.089543) (xy 163.773039 -408.024053) (xy 163.796804 -407.960956) (xy 163.827957 -407.901159)
			(xy 163.866047 -407.845525) (xy 163.887912 -407.81986) (xy 163.893709 -407.812715) (xy 163.900223 -407.795524)
			(xy 163.900612 -407.786332) (xy 163.900612 -407.628852) (xy 163.901046 -407.618739) (xy 163.908802 -407.600057)
			(xy 163.923114 -407.585764) (xy 163.941806 -407.578033) (xy 163.95192 -407.577544) (xy 164.6682 -407.577544)
			(xy 164.678302 -407.578084) (xy 164.696969 -407.585811) (xy 164.711262 -407.60009) (xy 164.719007 -407.618751)
			(xy 164.719508 -407.628852) (xy 164.719508 -407.786332) (xy 164.719901 -407.795521) (xy 164.726426 -407.812705)
			(xy 164.732208 -407.81986) (xy 164.754064 -407.845532) (xy 164.792152 -407.901166) (xy 164.823303 -407.960961)
			(xy 164.847067 -408.024057) (xy 164.863103 -408.089545) (xy 164.871179 -408.156483) (xy 164.87118 -408.223905)
			(xy 164.863105 -408.290843) (xy 164.847071 -408.356332) (xy 164.823308 -408.419428) (xy 164.792158 -408.479224)
			(xy 164.754071 -408.534859) (xy 164.732208 -408.560524) (xy 164.72642 -408.567675) (xy 164.7199 -408.584861)
			(xy 164.719508 -408.594052) (xy 164.719508 -409.086304) (xy 164.719915 -409.095492) (xy 164.726431 -409.112676)
			(xy 164.732208 -409.119832) (xy 164.754036 -409.145527) (xy 164.792126 -409.201157) (xy 164.823277 -409.260949)
			(xy 164.847043 -409.324042) (xy 164.863081 -409.389528) (xy 164.87116 -409.456463) (xy 164.871163 -409.523883)
			(xy 164.863091 -409.590819) (xy 164.847059 -409.656306) (xy 164.8233 -409.719401) (xy 164.792153 -409.779196)
			(xy 164.75407 -409.834831) (xy 164.732208 -409.860496) (xy 164.726432 -409.867656) (xy 164.719905 -409.884835)
			(xy 164.719508 -409.894024) (xy 164.719508 -410.051504) (xy 164.719018 -410.061612) (xy 164.711281 -410.080289)
			(xy 164.696985 -410.094583) (xy 164.678308 -410.102319) (xy 164.6682 -410.102812) (xy 163.95192 -410.102812)
			(xy 163.9418 -410.102368) (xy 163.923099 -410.094629) (xy 163.908785 -410.080321) (xy 163.901037 -410.061624)
			(xy 163.900612 -410.051504) (xy 163.900612 -409.894024) (xy 163.900188 -409.884838) (xy 163.893683 -409.867654)
			(xy 163.887912 -409.860496) (xy 163.866012 -409.83486) (xy 163.827924 -409.779222) (xy 163.796774 -409.719422)
			(xy 163.773011 -409.656321) (xy 163.756978 -409.590828) (xy 163.748905 -409.523886) (xy 162.620757 -409.523886)
			(xy 162.592019 -409.579046) (xy 162.553926 -409.634679) (xy 162.53206 -409.660344) (xy 162.526257 -409.667485)
			(xy 162.519747 -409.684679) (xy 162.51936 -409.693872) (xy 162.51936 -410.186124) (xy 162.519768 -410.195311)
			(xy 162.526284 -410.212495) (xy 162.53206 -410.219652) (xy 162.55391 -410.24533) (xy 162.592001 -410.300961)
			(xy 162.623155 -410.360755) (xy 162.646922 -410.423851) (xy 162.66296 -410.489339) (xy 162.671038 -410.556276)
			(xy 162.671039 -410.623641) (xy 165.949078 -410.623641) (xy 165.949079 -410.556335) (xy 165.957125 -410.489511)
			(xy 165.9731 -410.424127) (xy 165.996775 -410.361122) (xy 166.027811 -410.301398) (xy 166.065763 -410.245812)
			(xy 166.087552 -410.22016) (xy 166.093354 -410.213019) (xy 166.099864 -410.195825) (xy 166.100252 -410.186632)
			(xy 166.100252 -409.693364) (xy 166.099847 -409.684176) (xy 166.093328 -409.666993) (xy 166.087552 -409.659836)
			(xy 166.065776 -409.634174) (xy 166.027826 -409.578589) (xy 165.996791 -409.518867) (xy 165.973117 -409.455864)
			(xy 165.957143 -409.390483) (xy 165.949098 -409.323661) (xy 165.949097 -409.256357) (xy 165.95714 -409.189535)
			(xy 165.973112 -409.124153) (xy 165.996784 -409.061149) (xy 166.027817 -409.001426) (xy 166.065765 -408.94584)
			(xy 166.087552 -408.920188) (xy 166.093343 -408.913039) (xy 166.099859 -408.895851) (xy 166.100252 -408.88666)
			(xy 166.100252 -408.728672) (xy 166.100698 -408.718522) (xy 166.108493 -408.699778) (xy 166.122882 -408.685458)
			(xy 166.141662 -408.67775) (xy 166.151814 -408.677364) (xy 166.868094 -408.677364) (xy 166.878223 -408.677832)
			(xy 166.896949 -408.685562) (xy 166.911306 -408.699855) (xy 166.919121 -408.718545) (xy 166.919656 -408.728672)
			(xy 166.919656 -408.88666) (xy 166.920095 -408.895844) (xy 166.92659 -408.913028) (xy 166.932356 -408.920188)
			(xy 166.954156 -408.94583) (xy 166.992105 -409.001418) (xy 167.023138 -409.061143) (xy 167.04681 -409.124149)
			(xy 167.062782 -409.189532) (xy 167.070826 -409.256356) (xy 167.070824 -409.323662) (xy 167.062779 -409.390486)
			(xy 167.046805 -409.455869) (xy 167.02313 -409.518874) (xy 167.020557 -409.523826) (xy 168.149224 -409.523826)
			(xy 168.149228 -409.456519) (xy 168.157275 -409.389695) (xy 168.17325 -409.324311) (xy 168.196925 -409.261305)
			(xy 168.227961 -409.201581) (xy 168.265911 -409.145993) (xy 168.2877 -409.12034) (xy 168.293505 -409.1132)
			(xy 168.300014 -409.096006) (xy 168.3004 -409.086812) (xy 168.3004 -408.593544) (xy 168.299969 -408.584359)
			(xy 168.29347 -408.567174) (xy 168.2877 -408.560016) (xy 168.265906 -408.53437) (xy 168.22796 -408.478782)
			(xy 168.196929 -408.419057) (xy 168.173258 -408.356052) (xy 168.157287 -408.290669) (xy 168.149244 -408.223846)
			(xy 168.149245 -408.156542) (xy 168.157289 -408.089719) (xy 168.173262 -408.024337) (xy 168.196934 -407.961332)
			(xy 168.227966 -407.901608) (xy 168.265913 -407.846021) (xy 168.2877 -407.820368) (xy 168.293493 -407.81322)
			(xy 168.30001 -407.796032) (xy 168.3004 -407.78684) (xy 168.3004 -407.628852) (xy 168.300782 -407.618695)
			(xy 168.308594 -407.599941) (xy 168.323002 -407.58562) (xy 168.341802 -407.577922) (xy 168.351962 -407.577544)
			(xy 169.068242 -407.577544) (xy 169.078372 -407.577992) (xy 169.097095 -407.585735) (xy 169.11145 -407.600032)
			(xy 169.119267 -407.618724) (xy 169.119804 -407.628852) (xy 169.119804 -407.78684) (xy 169.120194 -407.796029)
			(xy 169.126721 -407.813214) (xy 169.132504 -407.820368) (xy 169.154283 -407.846027) (xy 169.192229 -407.901614)
			(xy 169.22326 -407.961337) (xy 169.246931 -408.02434) (xy 169.262904 -408.089721) (xy 169.270948 -408.156542)
			(xy 169.270948 -408.223846) (xy 169.262906 -408.290667) (xy 169.246935 -408.356048) (xy 169.223265 -408.419052)
			(xy 169.192235 -408.478776) (xy 169.15429 -408.534363) (xy 169.132504 -408.560016) (xy 169.126719 -408.567169)
			(xy 169.120197 -408.584354) (xy 169.119804 -408.593544) (xy 169.119804 -409.086812) (xy 169.120208 -409.096)
			(xy 169.126726 -409.113184) (xy 169.132504 -409.12034) (xy 169.154255 -409.146022) (xy 169.192202 -409.201605)
			(xy 169.223235 -409.261325) (xy 169.246908 -409.324325) (xy 169.262882 -409.389704) (xy 169.270928 -409.456522)
			(xy 169.270931 -409.523824) (xy 169.262891 -409.590643) (xy 169.246924 -409.656023) (xy 169.223257 -409.719026)
			(xy 169.19223 -409.778748) (xy 169.154288 -409.834335) (xy 169.132504 -409.859988) (xy 169.126688 -409.86712)
			(xy 169.120185 -409.88432) (xy 169.119804 -409.893516) (xy 169.119804 -410.051504) (xy 169.119382 -410.061658)
			(xy 169.111586 -410.08041) (xy 169.097189 -410.094733) (xy 169.078398 -410.102433) (xy 169.068242 -410.102812)
			(xy 168.351962 -410.102812) (xy 168.341839 -410.102306) (xy 168.323127 -410.094575) (xy 168.308774 -410.080296)
			(xy 168.300947 -410.061624) (xy 168.3004 -410.051504) (xy 168.3004 -409.893516) (xy 168.299982 -409.88433)
			(xy 168.293474 -409.867145) (xy 168.2877 -409.859988) (xy 168.265878 -409.834364) (xy 168.227933 -409.778773)
			(xy 168.196903 -409.719045) (xy 168.173234 -409.656037) (xy 168.157265 -409.590652) (xy 168.149224 -409.523826)
			(xy 167.020557 -409.523826) (xy 166.992095 -409.578598) (xy 166.954145 -409.634184) (xy 166.932356 -409.659836)
			(xy 166.926556 -409.666979) (xy 166.920045 -409.684171) (xy 166.919656 -409.693364) (xy 166.919656 -410.186632)
			(xy 166.920061 -410.19582) (xy 166.926579 -410.213003) (xy 166.932356 -410.22016) (xy 166.954128 -410.245825)
			(xy 166.992078 -410.30141) (xy 167.023112 -410.361131) (xy 167.046786 -410.424134) (xy 167.06276 -410.489515)
			(xy 167.070805 -410.556336) (xy 167.070807 -410.62364) (xy 167.0708 -410.623701) (xy 170.348846 -410.623701)
			(xy 170.348847 -410.556275) (xy 170.356926 -410.489335) (xy 170.372964 -410.423844) (xy 170.396732 -410.360747)
			(xy 170.427888 -410.30095) (xy 170.465981 -410.245316) (xy 170.487848 -410.219652) (xy 170.493653 -410.212513)
			(xy 170.500162 -410.195318) (xy 170.500548 -410.186124) (xy 170.500548 -409.693872) (xy 170.50014 -409.684685)
			(xy 170.493624 -409.667501) (xy 170.487848 -409.660344) (xy 170.465994 -409.63467) (xy 170.427902 -409.579038)
			(xy 170.396748 -409.519243) (xy 170.372981 -409.456147) (xy 170.356943 -409.390659) (xy 170.348866 -409.323721)
			(xy 170.348865 -409.256297) (xy 170.35694 -409.189359) (xy 170.372976 -409.12387) (xy 170.396741 -409.060773)
			(xy 170.427893 -409.000978) (xy 170.465983 -408.945344) (xy 170.487848 -408.91968) (xy 170.493642 -408.912533)
			(xy 170.500157 -408.895344) (xy 170.500548 -408.886152) (xy 170.500548 -408.728672) (xy 170.501061 -408.718568)
			(xy 170.508798 -408.699899) (xy 170.523086 -408.685607) (xy 170.541752 -408.677864) (xy 170.551856 -408.677364)
			(xy 171.268136 -408.677364) (xy 171.278243 -408.677855) (xy 171.296915 -408.685598) (xy 171.311207 -408.699892)
			(xy 171.318947 -408.718565) (xy 171.319444 -408.728672) (xy 171.319444 -408.886152) (xy 171.31989 -408.895335)
			(xy 171.32638 -408.912519) (xy 171.332144 -408.91968) (xy 171.354022 -408.945335) (xy 171.392114 -409.000969)
			(xy 171.423267 -409.060766) (xy 171.447033 -409.123865) (xy 171.463069 -409.189356) (xy 171.471145 -409.256296)
			(xy 171.471144 -409.323722) (xy 171.463066 -409.390662) (xy 171.447028 -409.456152) (xy 171.42326 -409.51925)
			(xy 171.420875 -409.523827) (xy 172.548991 -409.523827) (xy 172.548995 -409.456519) (xy 172.557043 -409.389693)
			(xy 172.573021 -409.324308) (xy 172.5967 -409.261302) (xy 172.62774 -409.201577) (xy 172.665697 -409.145992)
			(xy 172.687488 -409.12034) (xy 172.693291 -409.113199) (xy 172.699802 -409.096005) (xy 172.700188 -409.086812)
			(xy 172.700188 -408.593544) (xy 172.699759 -408.584359) (xy 172.693259 -408.567174) (xy 172.687488 -408.560016)
			(xy 172.665691 -408.534371) (xy 172.627739 -408.478785) (xy 172.596704 -408.419061) (xy 172.573029 -408.356055)
			(xy 172.557055 -408.290671) (xy 172.549011 -408.223847) (xy 172.549012 -408.156541) (xy 172.557057 -408.089717)
			(xy 172.573033 -408.024333) (xy 172.596708 -407.961328) (xy 172.627745 -407.901605) (xy 172.665698 -407.84602)
			(xy 172.687488 -407.820368) (xy 172.693279 -407.813219) (xy 172.699797 -407.796031) (xy 172.700188 -407.78684)
			(xy 172.700188 -407.628852) (xy 172.700582 -407.618696) (xy 172.708391 -407.599945) (xy 172.722796 -407.585624)
			(xy 172.741592 -407.577924) (xy 172.75175 -407.577544) (xy 173.46803 -407.577544) (xy 173.478159 -407.578002)
			(xy 173.496882 -407.58574) (xy 173.511237 -407.600035) (xy 173.519055 -407.618725) (xy 173.519592 -407.628852)
			(xy 173.519592 -407.78684) (xy 173.519985 -407.796029) (xy 173.526511 -407.813213) (xy 173.532292 -407.820368)
			(xy 173.554071 -407.846027) (xy 173.592018 -407.901613) (xy 173.62305 -407.961336) (xy 173.646722 -408.02434)
			(xy 173.662694 -408.089721) (xy 173.670739 -408.156542) (xy 173.670739 -408.223846) (xy 173.662697 -408.290667)
			(xy 173.646725 -408.356049) (xy 173.623055 -408.419053) (xy 173.592024 -408.478776) (xy 173.554078 -408.534363)
			(xy 173.532292 -408.560016) (xy 173.526505 -408.567168) (xy 173.519985 -408.584353) (xy 173.519592 -408.593544)
			(xy 173.519592 -409.086812) (xy 173.519998 -409.096) (xy 173.526515 -409.113184) (xy 173.532292 -409.12034)
			(xy 173.554043 -409.146022) (xy 173.591991 -409.201605) (xy 173.623024 -409.261324) (xy 173.646698 -409.324325)
			(xy 173.662672 -409.389703) (xy 173.670719 -409.456522) (xy 173.670722 -409.523824) (xy 173.662682 -409.590643)
			(xy 173.646714 -409.656023) (xy 173.623047 -409.719026) (xy 173.592019 -409.778749) (xy 173.554077 -409.834336)
			(xy 173.532292 -409.859988) (xy 173.526475 -409.867118) (xy 173.519973 -409.88432) (xy 173.519592 -409.893516)
			(xy 173.519592 -410.051504) (xy 173.519181 -410.061659) (xy 173.511383 -410.080413) (xy 173.496983 -410.094737)
			(xy 173.478187 -410.102435) (xy 173.46803 -410.102812) (xy 172.75175 -410.102812) (xy 172.741633 -410.102234)
			(xy 172.722923 -410.094532) (xy 172.708567 -410.080274) (xy 172.700736 -410.061618) (xy 172.700188 -410.051504)
			(xy 172.700188 -409.893516) (xy 172.699773 -409.884329) (xy 172.693263 -409.867145) (xy 172.687488 -409.859988)
			(xy 172.665663 -409.834366) (xy 172.627713 -409.778776) (xy 172.596678 -409.719049) (xy 172.573005 -409.65604)
			(xy 172.557033 -409.590654) (xy 172.548991 -409.523827) (xy 171.420875 -409.523827) (xy 171.392104 -409.579046)
			(xy 171.354011 -409.63468) (xy 171.332144 -409.660344) (xy 171.326339 -409.667483) (xy 171.319831 -409.684679)
			(xy 171.319444 -409.693872) (xy 171.319444 -410.186124) (xy 171.319855 -410.195311) (xy 171.32637 -410.212494)
			(xy 171.332144 -410.219652) (xy 171.353994 -410.245329) (xy 171.392087 -410.300961) (xy 171.423242 -410.360755)
			(xy 171.447009 -410.42385) (xy 171.463047 -410.489338) (xy 171.471125 -410.556276) (xy 171.471127 -410.623641)
			(xy 174.749166 -410.623641) (xy 174.749167 -410.556335) (xy 174.757213 -410.489511) (xy 174.773187 -410.424128)
			(xy 174.796862 -410.361123) (xy 174.827897 -410.301399) (xy 174.865847 -410.245812) (xy 174.887636 -410.22016)
			(xy 174.893437 -410.213018) (xy 174.899948 -410.195825) (xy 174.900336 -410.186632) (xy 174.900336 -409.693364)
			(xy 174.899935 -409.684176) (xy 174.893414 -409.666992) (xy 174.887636 -409.659836) (xy 174.86586 -409.634174)
			(xy 174.827911 -409.578589) (xy 174.796878 -409.518867) (xy 174.773205 -409.455863) (xy 174.757231 -409.390482)
			(xy 174.749186 -409.323661) (xy 174.749185 -409.256357) (xy 174.757228 -409.189535) (xy 174.773199 -409.124154)
			(xy 174.79687 -409.06115) (xy 174.827902 -409.001427) (xy 174.865849 -408.94584) (xy 174.887636 -408.920188)
			(xy 174.893425 -408.913037) (xy 174.899943 -408.895851) (xy 174.900336 -408.88666) (xy 174.900336 -408.728672)
			(xy 174.900699 -408.718512) (xy 174.908511 -408.699752) (xy 174.922926 -408.685428) (xy 174.941735 -408.677736)
			(xy 174.951898 -408.677364) (xy 175.668178 -408.677364) (xy 175.678306 -408.677845) (xy 175.697032 -408.68557)
			(xy 175.711389 -408.699859) (xy 175.719205 -408.718546) (xy 175.71974 -408.728672) (xy 175.71974 -408.88666)
			(xy 175.720183 -408.895843) (xy 175.726675 -408.913028) (xy 175.73244 -408.920188) (xy 175.75424 -408.94583)
			(xy 175.79219 -409.001418) (xy 175.823224 -409.061142) (xy 175.846897 -409.124148) (xy 175.862869 -409.189532)
			(xy 175.870913 -409.256356) (xy 175.870912 -409.323662) (xy 175.862866 -409.390486) (xy 175.846891 -409.455869)
			(xy 175.823216 -409.518874) (xy 175.792181 -409.578598) (xy 175.754229 -409.634184) (xy 175.73244 -409.659836)
			(xy 175.726638 -409.666977) (xy 175.720128 -409.684171) (xy 175.71974 -409.693364) (xy 175.71974 -410.186632)
			(xy 175.720148 -410.195819) (xy 175.726665 -410.213003) (xy 175.73244 -410.22016) (xy 175.754213 -410.245825)
			(xy 175.792163 -410.301409) (xy 175.823198 -410.361131) (xy 175.846873 -410.424134) (xy 175.862848 -410.489514)
			(xy 175.870893 -410.556336) (xy 175.870895 -410.62364) (xy 175.862852 -410.690462) (xy 175.84688 -410.755843)
			(xy 175.823208 -410.818847) (xy 175.792176 -410.87857) (xy 175.754227 -410.934156) (xy 175.73244 -410.959808)
			(xy 175.72665 -410.966958) (xy 175.720133 -410.984145) (xy 175.71974 -410.993336) (xy 175.71974 -411.151324)
			(xy 175.719299 -411.161475) (xy 175.711503 -411.18022) (xy 175.697113 -411.194541) (xy 175.678331 -411.202247)
			(xy 175.668178 -411.202632) (xy 174.951898 -411.202632) (xy 174.941768 -411.202174) (xy 174.923041 -411.194441)
			(xy 174.908684 -411.180145) (xy 174.90087 -411.161452) (xy 174.900336 -411.151324) (xy 174.900336 -410.993336)
			(xy 174.8999 -410.984152) (xy 174.893403 -410.966968) (xy 174.887636 -410.959808) (xy 174.865833 -410.934169)
			(xy 174.827884 -410.87858) (xy 174.796852 -410.818855) (xy 174.77318 -410.755849) (xy 174.757208 -410.690465)
			(xy 174.749166 -410.623641) (xy 171.471127 -410.623641) (xy 171.471127 -410.6237) (xy 171.463052 -410.690638)
			(xy 171.447016 -410.756127) (xy 171.423251 -410.819223) (xy 171.392099 -410.879019) (xy 171.354009 -410.934652)
			(xy 171.332144 -410.960316) (xy 171.326351 -410.967464) (xy 171.319836 -410.984653) (xy 171.319444 -410.993844)
			(xy 171.319444 -411.151324) (xy 171.318936 -411.161429) (xy 171.311198 -411.180099) (xy 171.296909 -411.194392)
			(xy 171.278241 -411.202133) (xy 171.268136 -411.202632) (xy 170.551856 -411.202632) (xy 170.541748 -411.202152)
			(xy 170.523075 -411.194405) (xy 170.508783 -411.180108) (xy 170.501044 -411.161432) (xy 170.500548 -411.151324)
			(xy 170.500548 -410.993844) (xy 170.500106 -410.98466) (xy 170.493613 -410.967476) (xy 170.487848 -410.960316)
			(xy 170.465967 -410.934665) (xy 170.427875 -410.879029) (xy 170.396723 -410.819232) (xy 170.372957 -410.756133)
			(xy 170.356921 -410.690641) (xy 170.348846 -410.623701) (xy 167.0708 -410.623701) (xy 167.062764 -410.690461)
			(xy 167.046793 -410.755843) (xy 167.023122 -410.818847) (xy 166.99209 -410.87857) (xy 166.954143 -410.934156)
			(xy 166.932356 -410.959808) (xy 166.926568 -410.966959) (xy 166.920049 -410.984145) (xy 166.919656 -410.993336)
			(xy 166.919656 -411.151324) (xy 166.919199 -411.161473) (xy 166.911406 -411.180215) (xy 166.897021 -411.194535)
			(xy 166.878245 -411.202244) (xy 166.868094 -411.202632) (xy 166.151814 -411.202632) (xy 166.141685 -411.202161)
			(xy 166.122959 -411.194433) (xy 166.108601 -411.180141) (xy 166.100786 -411.161451) (xy 166.100252 -411.151324)
			(xy 166.100252 -410.993336) (xy 166.099813 -410.984152) (xy 166.093318 -410.966968) (xy 166.087552 -410.959808)
			(xy 166.065748 -410.934169) (xy 166.027799 -410.878581) (xy 165.996765 -410.818856) (xy 165.973093 -410.75585)
			(xy 165.957121 -410.690466) (xy 165.949078 -410.623641) (xy 162.671039 -410.623641) (xy 162.671039 -410.6237)
			(xy 162.662964 -410.690637) (xy 162.646929 -410.756126) (xy 162.623165 -410.819223) (xy 162.592014 -410.879018)
			(xy 162.553924 -410.934651) (xy 162.53206 -410.960316) (xy 162.526269 -410.967465) (xy 162.519752 -410.984653)
			(xy 162.51936 -410.993844) (xy 162.51936 -411.151324) (xy 162.519003 -411.161453) (xy 162.511239 -411.180165)
			(xy 162.496904 -411.19448) (xy 162.478182 -411.202217) (xy 162.468052 -411.202632) (xy 161.751772 -411.202632)
			(xy 161.741665 -411.202139) (xy 161.722993 -411.194398) (xy 161.7087 -411.180104) (xy 161.700961 -411.161431)
			(xy 161.700464 -411.151324) (xy 161.700464 -410.993844) (xy 161.700019 -410.984661) (xy 161.693528 -410.967477)
			(xy 161.687764 -410.960316) (xy 161.665886 -410.934663) (xy 161.6278 -410.879026) (xy 161.596652 -410.819228)
			(xy 161.57289 -410.756129) (xy 161.556857 -410.690639) (xy 161.548783 -410.6237) (xy 154.57678 -410.6237)
			(xy 154.57678 -417.371276) (xy 154.576371 -417.383441) (xy 154.568857 -417.406581) (xy 154.554556 -417.426265)
			(xy 154.53487 -417.440562) (xy 154.511729 -417.448073) (xy 154.499564 -417.448492) (xy 141.100302 -417.448492)
			(xy 141.088157 -417.448035) (xy 141.06506 -417.440516) (xy 141.045426 -417.426216) (xy 141.031183 -417.406541)
			(xy 141.02373 -417.383422) (xy 141.02334 -417.371276) (xy 66.525648 -417.371276) (xy 66.525648 -417.533836)
			(xy 66.525172 -417.545883) (xy 66.517735 -417.568802) (xy 66.503597 -417.588313) (xy 66.484133 -417.602517)
			(xy 66.46124 -417.610031) (xy 66.449194 -417.610544) (xy 53.151024 -417.610544) (xy 53.138954 -417.610016)
			(xy 53.115994 -417.602564) (xy 53.09646 -417.588383) (xy 53.082263 -417.56886) (xy 53.074793 -417.545905)
			(xy 53.074316 -417.533836) (xy 53.074316 -417.289488) (xy 53.073808 -417.289488) (xy 0.682829 -417.289488)
			(xy 0.737106 -417.383499) (xy 0.799937 -417.475656) (xy 0.86948 -417.56286) (xy 0.945345 -417.644623)
			(xy 1.027108 -417.720488) (xy 1.114312 -417.790031) (xy 1.206469 -417.852862) (xy 1.303064 -417.908631)
			(xy 1.403556 -417.957026) (xy 1.507384 -417.997775) (xy 1.613967 -418.030652) (xy 1.722709 -418.055471)
			(xy 1.833001 -418.072095) (xy 1.944227 -418.080431) (xy 1.999996 -418.080952) (xy 6.799834 -418.080952)
			(xy 6.80085 -418.081968) (xy 7.986268 -418.081968)
		)
		(stroke
			(width 0)
			(type solid)
		)
		(fill yes)
		(layer "In14.Cu")
		(net "GND")
	)
	(gr_poly
		(pts
			(xy 139.76985 -195.612512) (xy 139.76985 -192.564512) (xy 139.64285 -192.437512) (xy 135.95985 -192.437512)
			(xy 135.70585 -192.691512) (xy 135.70585 -195.485512) (xy 135.95985 -195.739512) (xy 139.64285 -195.739512)
		)
		(stroke
			(width 0)
			(type solid)
		)
		(fill yes)
		(layer "In15.Cu")
		(net "GND")
	)
	(gr_poly
		(pts
			(arc
				(start 186.981846 -218.89212)
				(mid 186.690762 -218.89212)
				(end 186.981846 -218.89212)
			)
		)
		(stroke
			(width 0)
			(type solid)
		)
		(fill yes)
		(layer "In15.Cu")
		(net "GND")
	)
	(gr_poly
		(pts
			(arc
				(start 130.0353 -79.025496)
				(mid 129.726436 -79.025496)
				(end 130.0353 -79.025496)
			)
		)
		(stroke
			(width 0)
			(type solid)
		)
		(fill yes)
		(layer "In15.Cu")
		(net "GND")
	)
	(gr_poly
		(pts
			(arc
				(start 252.3998 -211.61629)
				(mid 252.075188 -211.61629)
				(end 252.3998 -211.61629)
			)
		)
		(stroke
			(width 0)
			(type solid)
		)
		(fill yes)
		(layer "In15.Cu")
		(net "GND")
	)
	(gr_poly
		(pts
			(arc
				(start 394.139674 -243.610384)
				(mid 393.818618 -243.610384)
				(end 394.139674 -243.610384)
			)
		)
		(stroke
			(width 0)
			(type solid)
		)
		(fill yes)
		(layer "In15.Cu")
		(net "GND")
	)
	(gr_poly
		(pts
			(arc
				(start 446.534794 -209.578194)
				(mid 446.225422 -209.578194)
				(end 446.534794 -209.578194)
			)
		)
		(stroke
			(width 0)
			(type solid)
		)
		(fill yes)
		(layer "In15.Cu")
		(net "GND")
	)
	(gr_poly
		(pts
			(arc
				(start 446.552066 -208.31937)
				(mid 446.20815 -208.31937)
				(end 446.552066 -208.31937)
			)
		)
		(stroke
			(width 0)
			(type solid)
		)
		(fill yes)
		(layer "In15.Cu")
		(net "GND")
	)
	(gr_poly
		(pts
			(arc
				(start 241.82197 -376.463306)
				(mid 241.841493 -376.459405)
				(end 241.858038 -376.44832)
			)
			(arc
				(start 242.310666 -375.995692)
				(mid 242.321777 -375.979158)
				(end 242.325652 -375.959624)
			)
			(arc
				(start 242.325652 -368.584988)
				(mid 242.321751 -368.565465)
				(end 242.310666 -368.54892)
			)
			(arc
				(start 242.213638 -368.451892)
				(mid 242.197104 -368.440781)
				(end 242.17757 -368.436906)
			)
			(arc
				(start 236.355128 -368.436906)
				(mid 236.335605 -368.440807)
				(end 236.31906 -368.451892)
			)
			(arc
				(start 236.08411 -368.686842)
				(mid 236.072999 -368.703376)
				(end 236.069124 -368.72291)
			)
			(arc
				(start 236.069124 -376.01144)
				(mid 236.073025 -376.030963)
				(end 236.08411 -376.047508)
			)
			(arc
				(start 236.484922 -376.44832)
				(mid 236.501456 -376.459431)
				(end 236.52099 -376.463306)
			)
		)
		(stroke
			(width 0)
			(type solid)
		)
		(fill yes)
		(layer "In15.Cu")
		(net "P12V_STBY_R1")
	)
	(gr_poly
		(pts
			(arc
				(start 252.431042 -397.963136)
				(mid 252.450565 -397.959235)
				(end 252.46711 -397.94815)
			)
			(arc
				(start 252.932438 -397.482822)
				(mid 252.943549 -397.466288)
				(end 252.947424 -397.446754)
			)
			(arc
				(start 252.947424 -392.961114)
				(mid 252.943523 -392.941591)
				(end 252.932438 -392.925046)
			)
			(arc
				(start 252.451362 -392.44397)
				(mid 252.434828 -392.432859)
				(end 252.415294 -392.428984)
			)
			(arc
				(start 245.184422 -392.428984)
				(mid 245.164899 -392.432885)
				(end 245.148354 -392.44397)
			)
			(arc
				(start 244.746526 -392.845798)
				(mid 244.735415 -392.862332)
				(end 244.73154 -392.881866)
			)
			(arc
				(start 244.73154 -397.594328)
				(mid 244.735441 -397.613851)
				(end 244.746526 -397.630396)
			)
			(arc
				(start 245.06428 -397.94815)
				(mid 245.080814 -397.959261)
				(end 245.100348 -397.963136)
			)
		)
		(stroke
			(width 0)
			(type solid)
		)
		(fill yes)
		(layer "In15.Cu")
		(net "P12V_STBY_FUSE")
	)
	(gr_poly
		(pts
			(arc
				(start 132.2832 -179.03444)
				(mid 132.325377 -179.027631)
				(end 132.368036 -179.025296)
			)
			(arc
				(start 132.368036 -179.025296)
				(mid 132.410693 -179.027645)
				(end 132.452872 -179.03444)
			)
			(xy 132.457952 -179.035456)
			(arc
				(start 133.987286 -179.035456)
				(mid 134.006809 -179.031555)
				(end 134.023354 -179.02047)
			)
			(arc
				(start 134.097268 -178.946556)
				(mid 134.108379 -178.930022)
				(end 134.112254 -178.910488)
			)
			(arc
				(start 134.112254 -176.398428)
				(mid 134.108353 -176.378905)
				(end 134.097268 -176.36236)
			)
			(arc
				(start 134.003796 -176.268888)
				(mid 133.987262 -176.257777)
				(end 133.967728 -176.253902)
			)
			(arc
				(start 131.460748 -176.253902)
				(mid 131.441225 -176.257803)
				(end 131.42468 -176.268888)
			)
			(arc
				(start 131.335018 -176.35855)
				(mid 131.323907 -176.375084)
				(end 131.320032 -176.394618)
			)
			(xy 131.320032 -176.597056)
			(arc
				(start 131.322318 -176.604168)
				(mid 131.339848 -176.722278)
				(end 131.322318 -176.840388)
			)
			(xy 131.320032 -176.8475) (xy 131.320032 -178.0032)
			(arc
				(start 131.322826 -178.011074)
				(mid 131.339356 -178.076198)
				(end 131.344924 -178.143154)
			)
			(arc
				(start 131.344924 -178.143154)
				(mid 131.339336 -178.210107)
				(end 131.322826 -178.275234)
			)
			(xy 131.320032 -178.283108)
			(arc
				(start 131.320032 -178.682396)
				(mid 131.323933 -178.701919)
				(end 131.335018 -178.718464)
			)
			(arc
				(start 131.637024 -179.02047)
				(mid 131.653558 -179.031581)
				(end 131.673092 -179.035456)
			)
			(xy 132.27812 -179.035456)
		)
		(stroke
			(width 0)
			(type solid)
		)
		(fill yes)
		(layer "In15.Cu")
		(net "GND")
	)
	(gr_poly
		(pts
			(xy 253.958598 -377.813824) (xy 253.964948 -377.820174)
			(arc
				(start 263.88441 -377.820174)
				(mid 263.903933 -377.816273)
				(end 263.920478 -377.805188)
			)
			(xy 263.947402 -377.778264) (xy 263.954768 -377.763024)
			(arc
				(start 263.955784 -377.754388)
				(mid 264.818333 -374.977853)
				(end 266.61618 -372.69293)
			)
			(arc
				(start 266.61618 -372.69293)
				(mid 266.62895 -372.67562)
				(end 266.633452 -372.654576)
			)
			(arc
				(start 266.633452 -368.922046)
				(mid 266.629551 -368.902523)
				(end 266.618466 -368.885978)
			)
			(arc
				(start 266.291568 -368.55908)
				(mid 266.275034 -368.547969)
				(end 266.2555 -368.544094)
			)
			(xy 243.539264 -368.544094) (xy 243.533676 -368.538506)
			(arc
				(start 242.778534 -368.538506)
				(mid 242.759011 -368.542407)
				(end 242.742466 -368.553492)
			)
			(arc
				(start 242.620038 -368.67592)
				(mid 242.608927 -368.692454)
				(end 242.605052 -368.711988)
			)
			(arc
				(start 242.605052 -377.229624)
				(mid 242.608953 -377.249147)
				(end 242.620038 -377.265692)
			)
			(arc
				(start 243.148358 -377.794012)
				(mid 243.164892 -377.805123)
				(end 243.184426 -377.808998)
			)
			(xy 248.743978 -377.808998) (xy 248.76252 -377.816618) (xy 248.766076 -377.820174) (xy 253.958598 -377.820174)
		)
		(stroke
			(width 0)
			(type solid)
		)
		(fill yes)
		(layer "In15.Cu")
		(net "P12V_STBY_R2")
	)
	(gr_poly
		(pts
			(arc
				(start 250.795028 -82.265012)
				(mid 250.814551 -82.261111)
				(end 250.831096 -82.250026)
			)
			(arc
				(start 250.992894 -82.088228)
				(mid 251.004005 -82.071694)
				(end 251.00788 -82.05216)
			)
			(arc
				(start 251.00788 -80.25638)
				(mid 251.003275 -80.234989)
				(end 250.9901 -80.217518)
			)
			(xy 250.922536 -80.160114) (xy 250.9012 -80.154272)
			(arc
				(start 250.890024 -80.15605)
				(mid 250.859767 -80.159673)
				(end 250.829318 -80.160876)
			)
			(arc
				(start 250.829318 -80.160876)
				(mid 250.44781 -79.779368)
				(end 250.829318 -79.39786)
			)
			(arc
				(start 250.829318 -79.39786)
				(mid 250.859768 -79.399057)
				(end 250.890024 -79.402686)
			)
			(xy 250.9012 -79.404464) (xy 250.922536 -79.398622)
			(arc
				(start 250.9901 -79.341218)
				(mid 251.003276 -79.323748)
				(end 251.00788 -79.302356)
			)
			(arc
				(start 251.00788 -78.410562)
				(mid 251.003979 -78.391039)
				(end 250.992894 -78.374494)
			)
			(xy 250.43765 -77.81925) (xy 250.430538 -77.811884) (xy 250.411742 -77.804264)
			(arc
				(start 247.658636 -77.804264)
				(mid 247.639249 -77.808214)
				(end 247.622822 -77.81925)
			)
			(arc
				(start 247.35663 -78.085188)
				(mid 247.345656 -78.101751)
				(end 247.341898 -78.121256)
			)
			(arc
				(start 247.341898 -82.17535)
				(mid 247.345799 -82.194873)
				(end 247.356884 -82.211418)
			)
			(arc
				(start 247.395492 -82.250026)
				(mid 247.412026 -82.261137)
				(end 247.43156 -82.265012)
			)
		)
		(stroke
			(width 0)
			(type solid)
		)
		(fill yes)
		(layer "In15.Cu")
		(net "GND")
	)
	(gr_poly
		(pts
			(xy 332.564232 -205.564994)
			(arc
				(start 332.564232 -203.928472)
				(mid 332.568098 -203.879242)
				(end 332.579472 -203.83119)
			)
			(xy 332.581758 -203.823824)
			(arc
				(start 332.581758 -203.269088)
				(mid 332.577857 -203.249565)
				(end 332.566772 -203.23302)
			)
			(arc
				(start 331.92466 -202.590908)
				(mid 331.908126 -202.579797)
				(end 331.888592 -202.575922)
			)
			(arc
				(start 330.280772 -202.575922)
				(mid 330.254748 -202.582943)
				(end 330.236068 -202.602338)
			)
			(xy 330.186538 -202.69327) (xy 330.187554 -202.720702)
			(arc
				(start 330.195428 -202.73264)
				(mid 330.240885 -202.83174)
				(end 330.256388 -202.93965)
			)
			(arc
				(start 330.256388 -202.93965)
				(mid 330.144647 -203.209417)
				(end 329.87488 -203.321158)
			)
			(arc
				(start 329.87488 -203.321158)
				(mid 329.681427 -203.268513)
				(end 329.541378 -203.12507)
			)
			(xy 329.535028 -203.113386) (xy 329.512676 -203.09967) (xy 329.3999 -203.094336) (xy 329.376532 -203.105766)
			(arc
				(start 329.368912 -203.116942)
				(mid 329.232183 -203.238258)
				(end 329.054714 -203.282042)
			)
			(arc
				(start 329.054714 -203.282042)
				(mid 328.952274 -203.267961)
				(end 328.857356 -203.226924)
			)
			(xy 328.845418 -203.219812) (xy 328.81824 -203.219304)
			(arc
				(start 328.729086 -203.269596)
				(mid 328.710122 -203.288306)
				(end 328.703178 -203.314046)
			)
			(xy 328.703178 -205.510892) (xy 328.951082 -205.758796) (xy 332.37043 -205.758796)
		)
		(stroke
			(width 0)
			(type solid)
		)
		(fill yes)
		(layer "In15.Cu")
		(net "GND")
	)
	(gr_poly
		(pts
			(xy 242.379246 -94.382336) (xy 242.389239 -94.381809) (xy 242.407688 -94.374114) (xy 242.41506 -94.36735)
			(xy 243.164614 -93.617796) (xy 243.171469 -93.610401) (xy 243.179216 -93.591802) (xy 243.1796 -93.581728)
			(xy 243.1796 -92.274136) (xy 243.177314 -92.266516) (xy 243.169043 -92.238536) (xy 243.160111 -92.180879)
			(xy 243.159534 -92.151708) (xy 243.160105 -92.122536) (xy 243.169033 -92.064878) (xy 243.177314 -92.0369)
			(xy 243.1796 -92.02928) (xy 243.1796 -90.454988) (xy 243.179175 -90.444919) (xy 243.171457 -90.426318)
			(xy 243.164614 -90.41892) (xy 242.802918 -90.057224) (xy 242.795516 -90.050388) (xy 242.776918 -90.04268)
			(xy 242.76685 -90.042238) (xy 238.789464 -90.042238) (xy 238.779397 -90.042668) (xy 238.760806 -90.050396)
			(xy 238.753396 -90.057224) (xy 238.648494 -90.162126) (xy 238.641652 -90.169526) (xy 238.633928 -90.188124)
			(xy 238.633508 -90.198194) (xy 238.633508 -91.650312) (xy 239.454434 -91.650312) (xy 239.458505 -91.59469)
			(xy 239.470631 -91.540253) (xy 239.490554 -91.488162) (xy 239.51785 -91.439527) (xy 239.551936 -91.395384)
			(xy 239.592085 -91.356675) (xy 239.637443 -91.324224) (xy 239.687043 -91.298723) (xy 239.739827 -91.280716)
			(xy 239.79467 -91.270586) (xy 239.850404 -91.268549) (xy 239.905841 -91.274649) (xy 239.959798 -91.288755)
			(xy 240.011127 -91.310567) (xy 240.058733 -91.339621) (xy 240.101601 -91.375296) (xy 240.138818 -91.416833)
			(xy 240.169591 -91.463346) (xy 240.193263 -91.513843) (xy 240.209331 -91.56725) (xy 240.217451 -91.622426)
			(xy 240.21796 -91.650312) (xy 240.217451 -91.678198) (xy 240.209331 -91.733374) (xy 240.193263 -91.786781)
			(xy 240.169591 -91.837278) (xy 240.138818 -91.883791) (xy 240.101601 -91.925328) (xy 240.058733 -91.961003)
			(xy 240.011127 -91.990057) (xy 239.959798 -92.011869) (xy 239.905841 -92.025975) (xy 239.850404 -92.032075)
			(xy 239.79467 -92.030038) (xy 239.739827 -92.019908) (xy 239.687043 -92.001901) (xy 239.637443 -91.9764)
			(xy 239.592085 -91.943949) (xy 239.551936 -91.90524) (xy 239.51785 -91.861097) (xy 239.490554 -91.812462)
			(xy 239.470631 -91.760371) (xy 239.458505 -91.705934) (xy 239.454434 -91.650312) (xy 238.633508 -91.650312)
			(xy 238.633508 -91.693492) (xy 238.634044 -91.70348) (xy 238.641757 -91.721913) (xy 238.648494 -91.729306)
			(xy 238.669317 -91.750919) (xy 238.704589 -91.799472) (xy 238.731828 -91.852947) (xy 238.750363 -91.910025)
			(xy 238.759738 -91.969301) (xy 238.760254 -91.999308) (xy 238.759717 -92.029315) (xy 238.750363 -92.088595)
			(xy 238.731839 -92.145678) (xy 238.704603 -92.199155) (xy 238.669327 -92.247707) (xy 238.648494 -92.26931)
			(xy 238.641685 -92.276656) (xy 238.633958 -92.295118) (xy 238.633508 -92.305124) (xy 238.633508 -94.213426)
			(xy 238.633936 -94.223494) (xy 238.641658 -94.242091) (xy 238.648494 -94.249494) (xy 238.76635 -94.36735)
			(xy 238.773696 -94.374158) (xy 238.792159 -94.38188) (xy 238.802164 -94.382336)
		)
		(stroke
			(width 0)
			(type solid)
		)
		(fill yes)
		(layer "In15.Cu")
		(net "GND")
	)
	(gr_poly
		(pts
			(xy 42.390314 -13.820648) (xy 42.390314 -13.401548) (xy 42.34688 -13.358114)
			(arc
				(start 34.964878 -13.358114)
				(mid 33.898562 -12.916432)
				(end 33.45688 -11.850116)
			)
			(arc
				(start 33.45688 -1.999996)
				(mid 33.019884 -0.944996)
				(end 31.964884 -0.508)
			)
			(arc
				(start 19.964908 -0.508)
				(mid 18.909908 -0.944996)
				(end 18.472912 -1.999996)
			)
			(xy 18.472912 -11.631422) (xy 18.980404 -11.631422)
			(arc
				(start 18.980404 -1.999996)
				(mid 19.268759 -1.303847)
				(end 19.964908 -1.015492)
			)
			(arc
				(start 31.964884 -1.015492)
				(mid 32.661033 -1.303847)
				(end 32.949388 -1.999996)
			)
			(arc
				(start 32.949388 -11.850116)
				(mid 33.539801 -13.275118)
				(end 34.964878 -13.865352)
			)
			(xy 42.34561 -13.865352)
		)
		(stroke
			(width 0)
			(type solid)
		)
		(fill yes)
		(layer "In15.Cu")
		(net "GND")
	)
	(gr_poly
		(pts
			(xy 68.431156 -13.728954) (xy 68.431156 -13.494512) (xy 68.294758 -13.358114)
			(arc
				(start 60.96508 -13.358114)
				(mid 59.898764 -12.916432)
				(end 59.457082 -11.850116)
			)
			(arc
				(start 59.457082 -1.999996)
				(mid 59.020086 -0.944996)
				(end 57.965086 -0.508)
			)
			(arc
				(start 45.96511 -0.508)
				(mid 44.91011 -0.944996)
				(end 44.473114 -1.999996)
			)
			(xy 44.473114 -11.726418) (xy 44.980352 -11.726418)
			(arc
				(start 44.980352 -1.999996)
				(mid 45.268617 -1.303936)
				(end 45.964602 -1.015492)
			)
			(arc
				(start 57.965086 -1.015492)
				(mid 58.661325 -1.303831)
				(end 58.949844 -1.999996)
			)
			(arc
				(start 58.949844 -11.850116)
				(mid 59.540093 -13.275103)
				(end 60.96508 -13.865352)
			)
			(xy 68.294758 -13.865352)
		)
		(stroke
			(width 0)
			(type solid)
		)
		(fill yes)
		(layer "In15.Cu")
		(net "GND")
	)
	(gr_poly
		(pts
			(xy 94.285816 -13.833856) (xy 94.285816 -13.444728) (xy 94.199202 -13.358114)
			(arc
				(start 86.965028 -13.358114)
				(mid 85.898712 -12.916432)
				(end 85.45703 -11.850116)
			)
			(arc
				(start 85.45703 -1.999996)
				(mid 85.020034 -0.944996)
				(end 83.965034 -0.508)
			)
			(arc
				(start 71.965058 -0.508)
				(mid 70.910058 -0.944996)
				(end 70.473062 -1.999996)
			)
			(xy 70.473062 -11.716004) (xy 70.9803 -11.716004)
			(arc
				(start 70.9803 -1.999996)
				(mid 71.268565 -1.303936)
				(end 71.96455 -1.015492)
			)
			(arc
				(start 83.965034 -1.015492)
				(mid 84.661273 -1.303831)
				(end 84.949792 -1.999996)
			)
			(arc
				(start 84.949792 -11.850116)
				(mid 85.540041 -13.275103)
				(end 86.965028 -13.865352)
			)
			(xy 94.25432 -13.865352)
		)
		(stroke
			(width 0)
			(type solid)
		)
		(fill yes)
		(layer "In15.Cu")
		(net "GND")
	)
	(gr_poly
		(pts
			(xy 132.291582 -13.80998) (xy 132.291582 -13.413486) (xy 132.23621 -13.358114)
			(arc
				(start 125.065028 -13.358114)
				(mid 123.998712 -12.916432)
				(end 123.55703 -11.850116)
			)
			(arc
				(start 123.55703 -1.999996)
				(mid 123.120034 -0.944996)
				(end 122.065034 -0.508)
			)
			(arc
				(start 97.965006 -0.508)
				(mid 96.910006 -0.944996)
				(end 96.47301 -1.999996)
			)
			(xy 96.47301 -11.72464) (xy 96.980248 -11.72464)
			(arc
				(start 96.980248 -1.999996)
				(mid 97.268513 -1.303936)
				(end 97.964498 -1.015492)
			)
			(arc
				(start 122.065034 -1.015492)
				(mid 122.761273 -1.303831)
				(end 123.049792 -1.999996)
			)
			(arc
				(start 123.049792 -11.850116)
				(mid 123.640041 -13.275103)
				(end 125.065028 -13.865352)
			)
			(xy 132.23621 -13.865352)
		)
		(stroke
			(width 0)
			(type solid)
		)
		(fill yes)
		(layer "In15.Cu")
		(net "GND")
	)
	(gr_poly
		(pts
			(xy 158.365444 -13.805662) (xy 158.365444 -13.417804) (xy 158.305754 -13.358114)
			(arc
				(start 151.064976 -13.358114)
				(mid 149.99866 -12.916432)
				(end 149.556978 -11.850116)
			)
			(arc
				(start 149.556978 -1.999996)
				(mid 149.119982 -0.944996)
				(end 148.064982 -0.508)
			)
			(arc
				(start 136.065006 -0.508)
				(mid 135.010006 -0.944996)
				(end 134.57301 -1.999996)
			)
			(xy 134.57301 -11.817604) (xy 135.080248 -11.817604)
			(arc
				(start 135.080248 -1.999996)
				(mid 135.368513 -1.303936)
				(end 136.064498 -1.015492)
			)
			(arc
				(start 148.064982 -1.015492)
				(mid 148.761221 -1.303831)
				(end 149.04974 -1.999996)
			)
			(arc
				(start 149.04974 -11.850116)
				(mid 149.639989 -13.275103)
				(end 151.064976 -13.865352)
			)
			(xy 158.305754 -13.865352)
		)
		(stroke
			(width 0)
			(type solid)
		)
		(fill yes)
		(layer "In15.Cu")
		(net "GND")
	)
	(gr_poly
		(pts
			(xy 184.389268 -13.77569) (xy 184.389268 -13.447776) (xy 184.299606 -13.358114)
			(arc
				(start 177.064924 -13.358114)
				(mid 175.998608 -12.916432)
				(end 175.556926 -11.850116)
			)
			(arc
				(start 175.556926 -1.999996)
				(mid 175.11993 -0.944996)
				(end 174.06493 -0.508)
			)
			(arc
				(start 162.064954 -0.508)
				(mid 161.009954 -0.944996)
				(end 160.572958 -1.999996)
			)
			(xy 160.572958 -11.62304) (xy 161.080196 -11.62304)
			(arc
				(start 161.080196 -1.999996)
				(mid 161.368461 -1.303936)
				(end 162.064446 -1.015492)
			)
			(arc
				(start 174.06493 -1.015492)
				(mid 174.761169 -1.303831)
				(end 175.049688 -1.999996)
			)
			(arc
				(start 175.049688 -11.850116)
				(mid 175.639937 -13.275103)
				(end 177.064924 -13.865352)
			)
			(xy 184.299606 -13.865352)
		)
		(stroke
			(width 0)
			(type solid)
		)
		(fill yes)
		(layer "In15.Cu")
		(net "GND")
	)
	(gr_poly
		(pts
			(xy 210.250024 -13.829284) (xy 210.250024 -13.394182) (xy 210.213956 -13.358114)
			(arc
				(start 203.064872 -13.358114)
				(mid 201.998721 -12.916342)
				(end 201.556874 -11.850116)
			)
			(arc
				(start 201.556874 -1.999996)
				(mid 201.119878 -0.944996)
				(end 200.064878 -0.508)
			)
			(arc
				(start 188.064902 -0.508)
				(mid 187.009902 -0.944996)
				(end 186.572906 -1.999996)
			)
			(xy 186.572906 -11.750294) (xy 187.080144 -11.750294)
			(arc
				(start 187.080144 -1.999996)
				(mid 187.368409 -1.303936)
				(end 188.064394 -1.015492)
			)
			(arc
				(start 200.064878 -1.015492)
				(mid 200.761117 -1.303831)
				(end 201.049636 -1.999996)
			)
			(arc
				(start 201.049636 -11.850116)
				(mid 201.63987 -13.275193)
				(end 203.064872 -13.865352)
			)
			(xy 210.213956 -13.865352)
		)
		(stroke
			(width 0)
			(type solid)
		)
		(fill yes)
		(layer "In15.Cu")
		(net "GND")
	)
	(gr_poly
		(pts
			(xy 300.515782 -13.7541) (xy 300.515782 -13.469366) (xy 300.40453 -13.358114)
			(arc
				(start 293.165022 -13.358114)
				(mid 292.098706 -12.916432)
				(end 291.657024 -11.850116)
			)
			(arc
				(start 291.657024 -1.999996)
				(mid 291.220028 -0.944996)
				(end 290.165028 -0.508)
			)
			(arc
				(start 278.165052 -0.508)
				(mid 277.110052 -0.944996)
				(end 276.673056 -1.999996)
			)
			(xy 276.673056 -11.825732) (xy 277.180548 -11.825732)
			(arc
				(start 277.180548 -1.999996)
				(mid 277.468903 -1.303847)
				(end 278.165052 -1.015492)
			)
			(arc
				(start 290.165028 -1.015492)
				(mid 290.861177 -1.303847)
				(end 291.149532 -1.999996)
			)
			(arc
				(start 291.149532 -11.850116)
				(mid 291.739945 -13.275118)
				(end 293.165022 -13.865352)
			)
			(xy 300.40453 -13.865352)
		)
		(stroke
			(width 0)
			(type solid)
		)
		(fill yes)
		(layer "In15.Cu")
		(net "GND")
	)
	(gr_poly
		(pts
			(xy 442.67882 -13.82903) (xy 442.67882 -13.394436) (xy 442.642498 -13.358114)
			(arc
				(start 435.265068 -13.358114)
				(mid 434.198752 -12.916432)
				(end 433.75707 -11.850116)
			)
			(arc
				(start 433.75707 -1.999996)
				(mid 433.320074 -0.944996)
				(end 432.265074 -0.508)
			)
			(arc
				(start 420.265098 -0.508)
				(mid 419.210098 -0.944996)
				(end 418.773102 -1.999996)
			)
			(xy 418.773102 -11.73734) (xy 419.28034 -11.73734)
			(arc
				(start 419.28034 -1.999996)
				(mid 419.568605 -1.303936)
				(end 420.26459 -1.015492)
			)
			(arc
				(start 432.265074 -1.015492)
				(mid 432.961313 -1.303831)
				(end 433.249832 -1.999996)
			)
			(arc
				(start 433.249832 -11.850116)
				(mid 433.840081 -13.275103)
				(end 435.265068 -13.865352)
			)
			(xy 442.642498 -13.865352)
		)
		(stroke
			(width 0)
			(type solid)
		)
		(fill yes)
		(layer "In15.Cu")
		(net "GND")
	)
	(gr_poly
		(pts
			(xy 248.61139 -13.829538) (xy 248.61139 -13.393928) (xy 248.575576 -13.358114)
			(arc
				(start 241.164872 -13.358114)
				(mid 240.098721 -12.916342)
				(end 239.656874 -11.850116)
			)
			(arc
				(start 239.656874 -1.999996)
				(mid 239.219878 -0.944996)
				(end 238.164878 -0.508)
			)
			(arc
				(start 214.065104 -0.508)
				(mid 213.010104 -0.944996)
				(end 212.573108 -1.999996)
			)
			(xy 212.573108 -11.851132) (xy 212.571584 -11.91895) (xy 213.07933 -11.91895) (xy 213.0806 -11.850116)
			(arc
				(start 213.0806 -1.999996)
				(mid 213.368955 -1.303847)
				(end 214.065104 -1.015492)
			)
			(arc
				(start 238.164878 -1.015492)
				(mid 238.861117 -1.303831)
				(end 239.149636 -1.999996)
			)
			(arc
				(start 239.149636 -11.850116)
				(mid 239.73987 -13.275193)
				(end 241.164872 -13.865352)
			)
			(xy 248.575576 -13.865352)
		)
		(stroke
			(width 0)
			(type solid)
		)
		(fill yes)
		(layer "In15.Cu")
		(net "GND")
	)
	(gr_poly
		(pts
			(xy 274.599654 -13.810742) (xy 274.599654 -13.412724) (xy 274.545044 -13.358114)
			(arc
				(start 267.165074 -13.358114)
				(mid 266.098758 -12.916432)
				(end 265.657076 -11.850116)
			)
			(arc
				(start 265.657076 -1.999996)
				(mid 265.22008 -0.944996)
				(end 264.16508 -0.508)
			)
			(arc
				(start 252.165104 -0.508)
				(mid 251.110104 -0.944996)
				(end 250.673108 -1.999996)
			)
			(xy 250.673108 -11.850116) (xy 250.673108 -11.851386) (xy 251.1806 -11.851386) (xy 251.1806 -11.850116)
			(arc
				(start 251.1806 -1.999996)
				(mid 251.468955 -1.303847)
				(end 252.165104 -1.015492)
			)
			(arc
				(start 264.16508 -1.015492)
				(mid 264.861229 -1.303847)
				(end 265.149584 -1.999996)
			)
			(arc
				(start 265.149584 -11.850116)
				(mid 265.739997 -13.275118)
				(end 267.165074 -13.865352)
			)
			(xy 274.545044 -13.865352)
		)
		(stroke
			(width 0)
			(type solid)
		)
		(fill yes)
		(layer "In15.Cu")
		(net "GND")
	)
	(gr_poly
		(pts
			(xy 416.458146 -13.816076) (xy 416.458146 -13.40739) (xy 416.40887 -13.358114)
			(arc
				(start 409.26512 -13.358114)
				(mid 408.198804 -12.916432)
				(end 407.757122 -11.850116)
			)
			(arc
				(start 407.757122 -1.999996)
				(mid 407.320126 -0.944996)
				(end 406.265126 -0.508)
			)
			(arc
				(start 394.264896 -0.508)
				(mid 393.209896 -0.944996)
				(end 392.7729 -1.999996)
			)
			(arc
				(start 392.7729 -11.850116)
				(mid 392.702216 -12.306469)
				(end 392.496802 -12.720066)
			)
			(xy 392.496802 -12.748514) (xy 392.499088 -12.7508)
			(arc
				(start 393.067794 -12.7508)
				(mid 393.226496 -12.312827)
				(end 393.280392 -11.850116)
			)
			(arc
				(start 393.280392 -1.999996)
				(mid 393.568747 -1.303847)
				(end 394.264896 -1.015492)
			)
			(arc
				(start 406.265126 -1.015492)
				(mid 406.961365 -1.303831)
				(end 407.249884 -1.999996)
			)
			(arc
				(start 407.249884 -11.850116)
				(mid 407.840133 -13.275103)
				(end 409.26512 -13.865352)
			)
			(xy 416.40887 -13.865352)
		)
		(stroke
			(width 0)
			(type solid)
		)
		(fill yes)
		(layer "In15.Cu")
		(net "GND")
	)
	(gr_poly
		(pts
			(xy 364.71606 -13.770102) (xy 364.71606 -13.453364) (xy 364.62081 -13.358114)
			(arc
				(start 357.26497 -13.358114)
				(mid 356.198654 -12.916432)
				(end 355.756972 -11.850116)
			)
			(arc
				(start 355.756972 -1.999996)
				(mid 355.319976 -0.944996)
				(end 354.264976 -0.508)
			)
			(arc
				(start 330.164948 -0.508)
				(mid 329.109948 -0.944996)
				(end 328.672952 -1.999996)
			)
			(arc
				(start 328.672952 -11.850116)
				(mid 328.570197 -12.397292)
				(end 328.27595 -12.869926)
			)
			(xy 328.27595 -12.876784) (xy 328.28738 -12.888214) (xy 328.885042 -12.888214)
			(arc
				(start 328.90333 -12.869926)
				(mid 329.10994 -12.378512)
				(end 329.180444 -11.850116)
			)
			(arc
				(start 329.180444 -1.999996)
				(mid 329.468799 -1.303847)
				(end 330.164948 -1.015492)
			)
			(arc
				(start 354.264976 -1.015492)
				(mid 354.961125 -1.303847)
				(end 355.24948 -1.999996)
			)
			(arc
				(start 355.24948 -11.850116)
				(mid 355.839893 -13.275118)
				(end 357.26497 -13.865352)
			)
			(xy 364.62081 -13.865352)
		)
		(stroke
			(width 0)
			(type solid)
		)
		(fill yes)
		(layer "In15.Cu")
		(net "GND")
	)
	(gr_poly
		(pts
			(xy 390.499092 -13.810996) (xy 390.499092 -13.41247) (xy 390.444736 -13.358114)
			(arc
				(start 383.264918 -13.358114)
				(mid 382.198602 -12.916432)
				(end 381.75692 -11.850116)
			)
			(arc
				(start 381.75692 -1.999996)
				(mid 381.319924 -0.944996)
				(end 380.264924 -0.508)
			)
			(arc
				(start 368.264948 -0.508)
				(mid 367.209948 -0.944996)
				(end 366.772952 -1.999996)
			)
			(arc
				(start 366.772952 -11.850116)
				(mid 366.670132 -12.397459)
				(end 366.375696 -12.87018)
			)
			(xy 366.375696 -12.899644) (xy 366.434878 -12.958826) (xy 366.914684 -12.958826)
			(arc
				(start 367.00333 -12.87018)
				(mid 367.209881 -12.378884)
				(end 367.280444 -11.850624)
			)
			(arc
				(start 367.280444 -1.999996)
				(mid 367.568799 -1.303847)
				(end 368.264948 -1.015492)
			)
			(arc
				(start 380.264924 -1.015492)
				(mid 380.961073 -1.303847)
				(end 381.249428 -1.999996)
			)
			(arc
				(start 381.249428 -11.850116)
				(mid 381.839841 -13.275118)
				(end 383.264918 -13.865352)
			)
			(xy 390.444736 -13.865352)
		)
		(stroke
			(width 0)
			(type solid)
		)
		(fill yes)
		(layer "In15.Cu")
		(net "GND")
	)
	(gr_poly
		(pts
			(xy 326.45985 -13.852906) (xy 326.45985 -13.37945) (xy 326.438514 -13.358114)
			(arc
				(start 319.16497 -13.358114)
				(mid 318.098654 -12.916432)
				(end 317.656972 -11.850116)
			)
			(arc
				(start 317.656972 -1.999996)
				(mid 317.219976 -0.944996)
				(end 316.164976 -0.508)
			)
			(arc
				(start 304.165 -0.508)
				(mid 303.11 -0.944996)
				(end 302.673004 -1.999996)
			)
			(arc
				(start 302.673004 -11.850116)
				(mid 302.577528 -12.378214)
				(end 302.30318 -12.839446)
			)
			(xy 302.30318 -12.884912) (xy 302.304196 -12.885928) (xy 302.874426 -12.885928)
			(arc
				(start 302.920908 -12.839446)
				(mid 303.114524 -12.361527)
				(end 303.180496 -11.850116)
			)
			(arc
				(start 303.180496 -1.999996)
				(mid 303.468851 -1.303847)
				(end 304.165 -1.015492)
			)
			(arc
				(start 316.164976 -1.015492)
				(mid 316.861125 -1.303847)
				(end 317.14948 -1.999996)
			)
			(arc
				(start 317.14948 -11.850116)
				(mid 317.739893 -13.275118)
				(end 319.16497 -13.865352)
			)
			(xy 326.438514 -13.865352) (xy 326.447404 -13.865352)
		)
		(stroke
			(width 0)
			(type solid)
		)
		(fill yes)
		(layer "In15.Cu")
		(net "GND")
	)
	(gr_poly
		(pts
			(xy 111.469678 -397.678148) (xy 111.479741 -397.677709) (xy 111.49832 -397.669969) (xy 111.505746 -397.663162)
			(xy 112.042702 -397.126206) (xy 112.049549 -397.118808) (xy 112.057286 -397.10021) (xy 112.057688 -397.090138)
			(xy 112.057688 -396.46479) (xy 112.057776 -396.45977) (xy 112.059689 -396.449915) (xy 112.061498 -396.445232)
			(xy 112.068864 -396.42796) (xy 112.07066 -396.423273) (xy 112.072571 -396.413421) (xy 112.072674 -396.408402)
			(xy 112.072674 -394.498068) (xy 112.073102 -394.488) (xy 112.080822 -394.469401) (xy 112.08766 -394.462)
			(xy 112.097566 -394.452094) (xy 112.098074 -394.451586) (xy 112.10466 -394.444206) (xy 112.112121 -394.425907)
			(xy 112.112552 -394.416026) (xy 112.112552 -393.30503) (xy 112.104932 -393.286234) (xy 112.097566 -393.279122)
			(xy 111.772954 -392.95451) (xy 111.766858 -392.951208) (xy 111.729236 -392.92959) (xy 111.657507 -392.88075)
			(xy 111.623602 -392.853672) (xy 111.239554 -392.54049) (xy 111.202779 -392.50977) (xy 111.134659 -392.442369)
			(xy 111.073312 -392.368751) (xy 111.019303 -392.289592) (xy 110.995714 -392.247882) (xy 110.990888 -392.239246)
			(xy 109.599222 -391.104374) (xy 109.592206 -391.099132) (xy 109.575715 -391.09327) (xy 109.566964 -391.092944)
			(xy 107.149138 -391.092944) (xy 107.139074 -391.09338) (xy 107.12049 -391.101115) (xy 107.11307 -391.10793)
			(xy 106.944922 -391.276078) (xy 106.941112 -391.286492) (xy 106.931152 -391.312097) (xy 106.904933 -391.360378)
			(xy 106.872059 -391.404398) (xy 106.833212 -391.443248) (xy 106.789193 -391.476123) (xy 106.740914 -391.502344)
			(xy 106.715306 -391.512298) (xy 106.704892 -391.516108) (xy 106.618532 -391.602468) (xy 106.611693 -391.609869)
			(xy 106.603978 -391.628467) (xy 106.603546 -391.638536) (xy 106.603546 -391.654538) (xy 108.000036 -391.654538)
			(xy 108.004107 -391.598916) (xy 108.016233 -391.544479) (xy 108.036156 -391.492388) (xy 108.063452 -391.443753)
			(xy 108.097538 -391.39961) (xy 108.137687 -391.360901) (xy 108.183045 -391.32845) (xy 108.232645 -391.302949)
			(xy 108.285429 -391.284942) (xy 108.340272 -391.274812) (xy 108.396006 -391.272775) (xy 108.451443 -391.278875)
			(xy 108.5054 -391.292981) (xy 108.556729 -391.314793) (xy 108.604335 -391.343847) (xy 108.647203 -391.379522)
			(xy 108.68442 -391.421059) (xy 108.715193 -391.467572) (xy 108.738865 -391.518069) (xy 108.754933 -391.571476)
			(xy 108.763053 -391.626652) (xy 108.763562 -391.654538) (xy 108.763053 -391.682424) (xy 108.754933 -391.7376)
			(xy 108.738865 -391.791007) (xy 108.715193 -391.841504) (xy 108.68442 -391.888017) (xy 108.647203 -391.929554)
			(xy 108.604335 -391.965229) (xy 108.556729 -391.994283) (xy 108.5054 -392.016095) (xy 108.451443 -392.030201)
			(xy 108.396006 -392.036301) (xy 108.340272 -392.034264) (xy 108.285429 -392.024134) (xy 108.232645 -392.006127)
			(xy 108.183045 -391.980626) (xy 108.137687 -391.948175) (xy 108.097538 -391.909466) (xy 108.063452 -391.865323)
			(xy 108.036156 -391.816688) (xy 108.016233 -391.764597) (xy 108.004107 -391.71016) (xy 108.000036 -391.654538)
			(xy 106.603546 -391.654538) (xy 106.603546 -391.99566) (xy 106.603964 -392.005708) (xy 106.611666 -392.024269)
			(xy 106.625905 -392.03845) (xy 106.635042 -392.04265) (xy 106.736388 -392.084306) (xy 106.766614 -392.07821)
			(xy 106.777536 -392.067034) (xy 106.799189 -392.045876) (xy 106.847946 -392.009994) (xy 106.901757 -391.98226)
			(xy 106.959272 -391.963371) (xy 107.019048 -391.9538) (xy 107.049316 -391.953242) (xy 107.076563 -391.953729)
			(xy 107.130502 -391.961487) (xy 107.182788 -391.976841) (xy 107.232356 -391.99948) (xy 107.278199 -392.028943)
			(xy 107.319382 -392.06463) (xy 107.355067 -392.105814) (xy 107.384528 -392.151658) (xy 107.407165 -392.201227)
			(xy 107.422517 -392.253514) (xy 107.430272 -392.307453) (xy 107.430272 -392.361947) (xy 107.422517 -392.415886)
			(xy 107.407165 -392.468173) (xy 107.384528 -392.517742) (xy 107.355067 -392.563586) (xy 107.319382 -392.60477)
			(xy 107.278199 -392.640457) (xy 107.232356 -392.66992) (xy 107.182788 -392.692559) (xy 107.130502 -392.707913)
			(xy 107.076563 -392.715671) (xy 107.049316 -392.716258) (xy 107.019048 -392.715679) (xy 106.959273 -392.706118)
			(xy 106.901758 -392.687234) (xy 106.847949 -392.6595) (xy 106.799197 -392.623615) (xy 106.777536 -392.602466)
			(xy 106.766614 -392.59129) (xy 106.736388 -392.585194) (xy 106.635042 -392.62685) (xy 106.625909 -392.631057)
			(xy 106.611673 -392.645235) (xy 106.603972 -392.663793) (xy 106.603546 -392.67384) (xy 106.603546 -395.68374)
			(xy 106.603978 -395.693806) (xy 106.611708 -395.712395) (xy 106.618532 -395.719808) (xy 107.092242 -396.193518)
			(xy 107.095733 -396.197129) (xy 107.10136 -396.205447) (xy 107.103418 -396.210028) (xy 107.114594 -396.236952)
			(xy 107.121706 -396.244064) (xy 108.540804 -397.663162) (xy 108.548201 -397.670012) (xy 108.566799 -397.677751)
			(xy 108.576872 -397.678148)
		)
		(stroke
			(width 0)
			(type solid)
		)
		(fill yes)
		(layer "In15.Cu")
		(net "GND")
	)
	(gr_poly
		(pts
			(arc
				(start 239.526318 -205.606396)
				(mid 239.543749 -205.603312)
				(end 239.559084 -205.594458)
			)
			(xy 239.56137 -205.59268) (xy 239.62106 -205.52918) (xy 239.628172 -205.509876) (xy 239.627664 -205.499208)
			(arc
				(start 239.627156 -205.47711)
				(mid 239.738897 -205.207343)
				(end 240.008664 -205.095602)
			)
			(arc
				(start 240.008664 -205.095602)
				(mid 240.262137 -205.191979)
				(end 240.387632 -205.432406)
			)
			(xy 240.389156 -205.44663)
			(arc
				(start 240.390426 -205.47711)
				(mid 240.389388 -205.506277)
				(end 240.386108 -205.535276)
			)
			(xy 240.384076 -205.547468) (xy 240.391696 -205.570328)
			(arc
				(start 240.400332 -205.578964)
				(mid 240.43631 -205.593904)
				(end 240.472214 -205.578964)
			)
			(arc
				(start 240.78057 -205.270354)
				(mid 240.791681 -205.25382)
				(end 240.795556 -205.234286)
			)
			(arc
				(start 240.795556 -200.381108)
				(mid 240.791655 -200.361585)
				(end 240.78057 -200.34504)
			)
			(xy 240.643156 -200.207626) (xy 240.636044 -200.20026) (xy 240.617248 -200.19264)
			(arc
				(start 239.886236 -200.19264)
				(mid 239.862297 -200.198634)
				(end 239.844072 -200.215246)
			)
			(xy 239.78997 -200.296018) (xy 239.78743 -200.321164)
			(arc
				(start 239.792256 -200.333102)
				(mid 239.813879 -200.404451)
				(end 239.821212 -200.478644)
			)
			(arc
				(start 239.821212 -200.478644)
				(mid 239.439704 -200.860152)
				(end 239.058196 -200.478644)
			)
			(arc
				(start 239.058196 -200.478644)
				(mid 239.06553 -200.404452)
				(end 239.087152 -200.333102)
			)
			(xy 239.091978 -200.321164) (xy 239.089438 -200.296018)
			(arc
				(start 239.035336 -200.215246)
				(mid 239.017074 -200.198703)
				(end 238.993172 -200.19264)
			)
			(arc
				(start 237.593378 -200.19264)
				(mid 237.577314 -200.195247)
				(end 237.562898 -200.2028)
			)
			(xy 237.561374 -200.20407)
			(arc
				(start 237.34903 -200.416414)
				(mid 237.341749 -200.42847)
				(end 237.338108 -200.442068)
			)
			(xy 237.338108 -200.594722) (xy 237.3376 -200.613518)
			(arc
				(start 237.3376 -202.513438)
				(mid 237.338149 -202.521148)
				(end 237.339886 -202.528678)
			)
			(xy 237.346744 -202.550014)
			(arc
				(start 237.350554 -202.55611)
				(mid 237.414454 -202.767438)
				(end 237.350554 -202.978766)
			)
			(xy 237.346744 -202.984862)
			(arc
				(start 237.339886 -203.006198)
				(mid 237.338174 -203.013732)
				(end 237.3376 -203.021438)
			)
			(arc
				(start 237.3376 -205.017878)
				(mid 237.341501 -205.037401)
				(end 237.352586 -205.053946)
			)
			(arc
				(start 237.788704 -205.490318)
				(mid 237.79925 -205.49846)
				(end 237.811564 -205.503526)
			)
			(arc
				(start 237.811564 -205.503526)
				(mid 237.827301 -205.505211)
				(end 237.842806 -205.502002)
			)
			(xy 237.94339 -205.463902) (xy 237.960916 -205.440026)
			(arc
				(start 237.961932 -205.42504)
				(mid 238.081662 -205.171157)
				(end 238.342678 -205.067916)
			)
			(arc
				(start 238.342678 -205.067916)
				(mid 238.612445 -205.179657)
				(end 238.724186 -205.449424)
			)
			(arc
				(start 238.724186 -205.449424)
				(mid 238.72355 -205.471432)
				(end 238.721646 -205.493366)
			)
			(xy 238.720376 -205.504034) (xy 238.72698 -205.524862) (xy 238.784638 -205.589378)
			(arc
				(start 238.786162 -205.591156)
				(mid 238.802783 -205.602454)
				(end 238.822484 -205.606396)
			)
		)
		(stroke
			(width 0)
			(type solid)
		)
		(fill yes)
		(layer "In15.Cu")
		(net "GND")
	)
	(gr_poly
		(pts
			(arc
				(start 200.481692 -418.081968)
				(mid 201.086106 -417.953924)
				(end 201.586846 -417.592002)
			)
			(arc
				(start 201.586846 -417.592002)
				(mid 202.42889 -416.98332)
				(end 203.445364 -416.768026)
			)
			(arc
				(start 271.794732 -416.768026)
				(mid 272.811071 -416.983322)
				(end 273.652996 -417.592002)
			)
			(arc
				(start 273.652996 -417.592002)
				(mid 274.153727 -417.953921)
				(end 274.75815 -418.081968)
			)
			(arc
				(start 465.600034 -418.081968)
				(mid 466.655034 -417.644972)
				(end 467.09203 -416.589972)
			)
			(xy 467.09203 -317.499746) (xy 466.584792 -317.499746)
			(arc
				(start 466.584792 -416.589972)
				(mid 466.296527 -417.286032)
				(end 465.600542 -417.574476)
			)
			(xy 414.915604 -417.574476) (xy 414.915604 -417.797742) (xy 400.95424 -417.797742) (xy 400.95424 -417.574476)
			(xy 326.621648 -417.574476) (xy 326.621648 -417.747958) (xy 313.065922 -417.747958) (xy 313.065922 -417.574476)
			(arc
				(start 274.757896 -417.574476)
				(mid 274.359217 -417.490052)
				(end 274.028916 -417.251388)
			)
			(arc
				(start 274.028916 -417.251388)
				(mid 273.01669 -416.519565)
				(end 271.794732 -416.260788)
			)
			(arc
				(start 203.445364 -416.260788)
				(mid 202.223266 -416.519531)
				(end 201.210926 -417.251388)
			)
			(arc
				(start 201.210926 -417.251388)
				(mid 200.880626 -417.490098)
				(end 200.481946 -417.574476)
			)
			(xy 154.673554 -417.574476) (xy 154.673554 -417.693856) (xy 141.027912 -417.693856) (xy 141.027912 -417.574476)
			(xy 66.745104 -417.574476) (xy 66.745104 -417.671758) (xy 53.039772 -417.671758) (xy 53.039772 -417.574476)
			(arc
				(start 1.999996 -417.574476)
				(mid 1.303847 -417.286121)
				(end 1.015492 -416.589972)
			)
			(xy 1.015492 -316.13983) (xy 0.508 -316.13983)
			(arc
				(start 0.508 -416.589972)
				(mid 0.944996 -417.644972)
				(end 1.999996 -418.081968)
			)
		)
		(stroke
			(width 0)
			(type solid)
		)
		(fill yes)
		(layer "In15.Cu")
		(net "GND")
	)
	(gr_poly
		(pts
			(arc
				(start 1.015492 -246.48795)
				(mid 1.090466 -246.111319)
				(end 1.303782 -245.79199)
			)
			(arc
				(start 3.93192 -243.163852)
				(mid 4.58575 -242.18556)
				(end 4.815332 -241.031522)
			)
			(arc
				(start 4.815332 -87.588344)
				(mid 4.585694 -86.434435)
				(end 3.93192 -85.456268)
			)
			(arc
				(start 1.303528 -82.827876)
				(mid 1.090411 -82.508641)
				(end 1.015492 -82.13217)
			)
			(arc
				(start 1.015492 -1.999996)
				(mid 1.303847 -1.303847)
				(end 1.999996 -1.015492)
			)
			(arc
				(start 5.964936 -1.015492)
				(mid 6.661085 -1.303847)
				(end 6.94944 -1.999996)
			)
			(arc
				(start 6.94944 -11.850116)
				(mid 7.539853 -13.275118)
				(end 8.96493 -13.865352)
			)
			(xy 16.2814 -13.865352) (xy 16.371316 -13.775436) (xy 16.371316 -13.44803) (xy 16.2814 -13.358114)
			(arc
				(start 8.96493 -13.358114)
				(mid 7.898614 -12.916432)
				(end 7.456932 -11.850116)
			)
			(arc
				(start 7.456932 -1.999996)
				(mid 7.019936 -0.944996)
				(end 5.964936 -0.508)
			)
			(arc
				(start 1.999996 -0.508)
				(mid 0.944996 -0.944996)
				(end 0.508 -1.999996)
			)
			(arc
				(start 0.508 -82.131916)
				(mid 0.621601 -82.702644)
				(end 0.94488 -83.186524)
			)
			(arc
				(start 3.573272 -85.81517)
				(mid 4.117081 -86.628665)
				(end 4.308094 -87.588344)
			)
			(arc
				(start 4.308094 -241.031522)
				(mid 4.117082 -241.991334)
				(end 3.573272 -242.80495)
			)
			(arc
				(start 0.94488 -245.433342)
				(mid 0.621552 -245.917331)
				(end 0.508 -246.488204)
			)
			(xy 0.508 -307.918358) (xy 1.015492 -307.918358)
		)
		(stroke
			(width 0)
			(type solid)
		)
		(fill yes)
		(layer "In15.Cu")
		(net "GND")
	)
	(gr_poly
		(pts
			(arc
				(start 235.636562 -413.132016)
				(mid 235.656085 -413.128115)
				(end 235.67263 -413.11703)
			)
			(arc
				(start 236.812328 -411.977332)
				(mid 236.823439 -411.960798)
				(end 236.827314 -411.941264)
			)
			(arc
				(start 236.827314 -402.776436)
				(mid 236.831215 -402.756913)
				(end 236.8423 -402.740368)
			)
			(arc
				(start 238.886238 -400.69643)
				(mid 238.902772 -400.685319)
				(end 238.922306 -400.681444)
			)
			(arc
				(start 242.916964 -400.681444)
				(mid 242.936487 -400.677543)
				(end 242.953032 -400.666458)
			)
			(arc
				(start 243.86286 -399.75663)
				(mid 243.873971 -399.740096)
				(end 243.877846 -399.720562)
			)
			(arc
				(start 243.877846 -392.486896)
				(mid 243.881747 -392.467373)
				(end 243.892832 -392.450828)
			)
			(xy 243.896388 -392.447272)
			(arc
				(start 243.896388 -391.97026)
				(mid 243.900289 -391.950737)
				(end 243.911374 -391.934192)
			)
			(arc
				(start 245.02999 -390.815576)
				(mid 245.046524 -390.804465)
				(end 245.066058 -390.80059)
			)
			(arc
				(start 259.092954 -390.80059)
				(mid 259.112477 -390.796689)
				(end 259.129022 -390.785604)
			)
			(arc
				(start 262.060944 -387.853682)
				(mid 262.072055 -387.837148)
				(end 262.07593 -387.817614)
			)
			(arc
				(start 262.07593 -379.165866)
				(mid 262.072029 -379.146343)
				(end 262.060944 -379.129798)
			)
			(arc
				(start 261.987538 -379.056392)
				(mid 261.971004 -379.045281)
				(end 261.95147 -379.041406)
			)
			(xy 243.1415 -379.041406) (xy 243.140484 -379.042422)
			(arc
				(start 240.581688 -379.042422)
				(mid 240.562165 -379.046323)
				(end 240.54562 -379.057408)
			)
			(arc
				(start 239.903 -379.700028)
				(mid 239.886466 -379.711139)
				(end 239.866932 -379.715014)
			)
			(arc
				(start 237.06963 -379.715014)
				(mid 237.050107 -379.711113)
				(end 237.033562 -379.700028)
			)
			(arc
				(start 232.94086 -375.607326)
				(mid 232.929749 -375.590792)
				(end 232.925874 -375.571258)
			)
			(arc
				(start 232.925874 -372.098062)
				(mid 232.921973 -372.078539)
				(end 232.910888 -372.061994)
			)
			(arc
				(start 232.189274 -371.34038)
				(mid 232.178163 -371.323846)
				(end 232.174288 -371.304312)
			)
			(arc
				(start 232.174288 -371.057424)
				(mid 232.170387 -371.037901)
				(end 232.159302 -371.021356)
			)
			(xy 232.119932 -370.981986) (xy 232.118408 -370.981986)
			(arc
				(start 232.015284 -370.878862)
				(mid 232.004173 -370.862328)
				(end 232.000298 -370.842794)
			)
			(arc
				(start 232.000298 -367.379758)
				(mid 231.996397 -367.360235)
				(end 231.985312 -367.34369)
			)
			(arc
				(start 231.905048 -367.263426)
				(mid 231.888514 -367.252315)
				(end 231.86898 -367.24844)
			)
			(arc
				(start 228.707696 -367.24844)
				(mid 228.688173 -367.252341)
				(end 228.671628 -367.263426)
			)
			(arc
				(start 228.614478 -367.320576)
				(mid 228.603367 -367.33711)
				(end 228.599492 -367.356644)
			)
			(arc
				(start 228.599492 -370.828062)
				(mid 228.595591 -370.847585)
				(end 228.584506 -370.86413)
			)
			(arc
				(start 228.431344 -371.017292)
				(mid 228.420233 -371.033826)
				(end 228.416358 -371.05336)
			)
			(arc
				(start 228.416358 -371.446552)
				(mid 228.412457 -371.466075)
				(end 228.401372 -371.48262)
			)
			(arc
				(start 227.137722 -372.74627)
				(mid 227.126611 -372.762804)
				(end 227.122736 -372.782338)
			)
			(arc
				(start 227.122736 -374.248426)
				(mid 227.118835 -374.267949)
				(end 227.10775 -374.284494)
			)
			(arc
				(start 225.693224 -375.69902)
				(mid 225.67669 -375.710131)
				(end 225.657156 -375.714006)
			)
			(arc
				(start 223.582484 -375.714006)
				(mid 223.562961 -375.710105)
				(end 223.546416 -375.69902)
			)
			(arc
				(start 221.539816 -373.69242)
				(mid 221.528705 -373.675886)
				(end 221.52483 -373.656352)
			)
			(arc
				(start 221.52483 -371.070124)
				(mid 221.520929 -371.050601)
				(end 221.509844 -371.034056)
			)
			(arc
				(start 221.337632 -370.861844)
				(mid 221.326521 -370.84531)
				(end 221.322646 -370.825776)
			)
			(arc
				(start 221.322646 -367.359692)
				(mid 221.318745 -367.340169)
				(end 221.30766 -367.323624)
			)
			(arc
				(start 221.24416 -367.260124)
				(mid 221.227626 -367.249013)
				(end 221.208092 -367.245138)
			)
			(arc
				(start 218.078304 -367.245138)
				(mid 218.058781 -367.249039)
				(end 218.042236 -367.260124)
			)
			(arc
				(start 217.916506 -367.385854)
				(mid 217.905395 -367.402388)
				(end 217.90152 -367.421922)
			)
			(arc
				(start 217.90152 -370.80063)
				(mid 217.897619 -370.820153)
				(end 217.886534 -370.836698)
			)
			(arc
				(start 216.72931 -371.993922)
				(mid 216.712776 -372.005033)
				(end 216.693242 -372.008908)
			)
			(arc
				(start 210.338924 -372.008908)
				(mid 210.319401 -372.005007)
				(end 210.302856 -371.993922)
			)
			(arc
				(start 210.054698 -371.745764)
				(mid 210.043587 -371.72923)
				(end 210.039712 -371.709696)
			)
			(arc
				(start 210.039712 -371.274086)
				(mid 210.035811 -371.254563)
				(end 210.024726 -371.238018)
			)
			(arc
				(start 209.986626 -371.199918)
				(mid 209.970063 -371.188944)
				(end 209.950558 -371.185186)
			)
			(arc
				(start 209.475324 -371.185186)
				(mid 209.455801 -371.181285)
				(end 209.439256 -371.1702)
			)
			(arc
				(start 208.832196 -370.56314)
				(mid 208.821085 -370.546606)
				(end 208.81721 -370.527072)
			)
			(arc
				(start 208.81721 -370.46027)
				(mid 208.813309 -370.440747)
				(end 208.802224 -370.424202)
			)
			(xy 208.795366 -370.417344)
			(arc
				(start 208.220056 -370.417344)
				(mid 208.200533 -370.413443)
				(end 208.183988 -370.402358)
			)
			(arc
				(start 208.098898 -370.317268)
				(mid 208.087787 -370.300734)
				(end 208.083912 -370.2812)
			)
			(arc
				(start 208.083912 -367.384584)
				(mid 208.080011 -367.365061)
				(end 208.068926 -367.348516)
			)
			(arc
				(start 207.996028 -367.275618)
				(mid 207.979494 -367.264507)
				(end 207.95996 -367.260632)
			)
			(arc
				(start 204.786484 -367.260632)
				(mid 204.766961 -367.264533)
				(end 204.750416 -367.275618)
			)
			(arc
				(start 204.68082 -367.345214)
				(mid 204.669709 -367.361748)
				(end 204.665834 -367.381282)
			)
			(arc
				(start 204.665834 -370.837714)
				(mid 204.669735 -370.857237)
				(end 204.68082 -370.873782)
			)
			(arc
				(start 204.794104 -370.987066)
				(mid 204.805215 -371.0036)
				(end 204.80909 -371.023134)
			)
			(arc
				(start 204.80909 -372.841012)
				(mid 204.815471 -372.865662)
				(end 204.832966 -372.884192)
			)
			(xy 204.917548 -372.93677) (xy 204.94371 -372.93804)
			(arc
				(start 204.955648 -372.932198)
				(mid 205.037716 -372.902845)
				(end 205.124304 -372.892828)
			)
			(arc
				(start 205.124304 -372.892828)
				(mid 205.505812 -373.274336)
				(end 205.124304 -373.655844)
			)
			(arc
				(start 205.124304 -373.655844)
				(mid 205.037702 -373.645885)
				(end 204.955648 -373.616474)
			)
			(xy 204.94371 -373.610632) (xy 204.917548 -373.611902)
			(arc
				(start 204.832966 -373.66448)
				(mid 204.815396 -373.682968)
				(end 204.80909 -373.70766)
			)
			(arc
				(start 204.80909 -374.498616)
				(mid 204.812991 -374.518139)
				(end 204.824076 -374.534684)
			)
			(arc
				(start 204.905102 -374.61571)
				(mid 204.916213 -374.632244)
				(end 204.920088 -374.651778)
			)
			(arc
				(start 204.920088 -387.060948)
				(mid 204.923989 -387.080471)
				(end 204.935074 -387.097016)
			)
			(arc
				(start 207.491838 -389.65378)
				(mid 207.502949 -389.670314)
				(end 207.506824 -389.689848)
			)
			(arc
				(start 207.506824 -411.710124)
				(mid 207.510725 -411.729647)
				(end 207.52181 -411.746192)
			)
			(arc
				(start 208.892648 -413.11703)
				(mid 208.909182 -413.128141)
				(end 208.928716 -413.132016)
			)
		)
		(stroke
			(width 0)
			(type solid)
		)
		(fill yes)
		(layer "In15.Cu")
		(net "P12V_STBY")
	)
	(gr_poly
		(pts
			(xy 260.833108 -243.1288) (xy 261.935214 -243.1288) (xy 261.977632 -243.086382) (xy 262.19277 -242.764056)
			(xy 262.199981 -242.752468) (xy 262.208583 -242.726576) (xy 262.210025 -242.69933) (xy 262.204205 -242.672675)
			(xy 262.191538 -242.64851) (xy 262.172926 -242.62856) (xy 262.161528 -242.621054) (xy 262.138114 -242.606082)
			(xy 262.095485 -242.570425) (xy 262.058487 -242.528956) (xy 262.027904 -242.482552) (xy 262.004385 -242.432199)
			(xy 261.988428 -242.378964) (xy 261.980373 -242.323976) (xy 261.979918 -242.296188) (xy 261.980382 -242.268936)
			(xy 261.988141 -242.214988) (xy 262.003498 -242.162693) (xy 262.026142 -242.113116) (xy 262.05561 -242.067267)
			(xy 262.091304 -242.026077) (xy 262.132497 -241.990387) (xy 262.17835 -241.960923) (xy 262.227929 -241.938285)
			(xy 262.280225 -241.922933) (xy 262.334174 -241.915179) (xy 262.361426 -241.91468) (xy 262.361934 -241.91468)
			(xy 262.391309 -241.915236) (xy 262.449358 -241.924289) (xy 262.477504 -241.932714) (xy 262.50284 -241.933211)
			(xy 262.553045 -241.940093) (xy 262.57758 -241.94643) (xy 262.590278 -241.941874) (xy 262.61286 -241.927129)
			(xy 262.630797 -241.906991) (xy 262.64284 -241.88286) (xy 262.645906 -241.869722) (xy 262.666226 -241.768122)
			(xy 262.666226 -238.14786) (xy 262.665731 -238.133718) (xy 262.65791 -238.106536) (xy 262.642934 -238.08254)
			(xy 262.621952 -238.063571) (xy 262.596573 -238.051084) (xy 262.568741 -238.046035) (xy 262.540593 -238.048812)
			(xy 262.527288 -238.053626) (xy 262.50493 -238.062063) (xy 262.45864 -238.073932) (xy 262.411228 -238.079916)
			(xy 262.387334 -238.080296) (xy 262.386826 -238.080296) (xy 262.359572 -238.079834) (xy 262.305619 -238.07208)
			(xy 262.253319 -238.056726) (xy 262.203736 -238.034085) (xy 262.157881 -238.004618) (xy 262.116686 -237.968924)
			(xy 262.080991 -237.927731) (xy 262.051521 -237.881876) (xy 262.028878 -237.832294) (xy 262.013523 -237.779995)
			(xy 262.005767 -237.726042) (xy 262.005318 -237.698788) (xy 262.005318 -237.698534) (xy 262.005757 -237.672237)
			(xy 262.012983 -237.620142) (xy 262.027303 -237.569535) (xy 262.048444 -237.521377) (xy 262.076005 -237.476582)
			(xy 262.109462 -237.436003) (xy 262.128508 -237.417864) (xy 262.138526 -237.408052) (xy 262.153219 -237.38418)
			(xy 262.160853 -237.357208) (xy 262.160851 -237.329176) (xy 262.153213 -237.302205) (xy 262.138516 -237.278336)
			(xy 262.128508 -237.268512) (xy 262.109459 -237.250379) (xy 262.07602 -237.209785) (xy 262.048468 -237.164987)
			(xy 262.027327 -237.116831) (xy 262.012994 -237.066228) (xy 262.005743 -237.014138) (xy 262.005318 -236.987842)
			(xy 262.005318 -236.987588) (xy 262.005441 -236.975232) (xy 262.007094 -236.950574) (xy 262.00862 -236.938312)
			(xy 261.582662 -236.512354) (xy 257.780536 -236.512354) (xy 257.397504 -236.895386) (xy 255.631442 -236.895386)
			(xy 254.919226 -237.607602) (xy 254.919226 -238.333788) (xy 257.356608 -238.333788) (xy 257.360679 -238.278166)
			(xy 257.372805 -238.223729) (xy 257.392728 -238.171638) (xy 257.420024 -238.123003) (xy 257.45411 -238.07886)
			(xy 257.494259 -238.040151) (xy 257.539617 -238.0077) (xy 257.589217 -237.982199) (xy 257.642001 -237.964192)
			(xy 257.696844 -237.954062) (xy 257.752578 -237.952025) (xy 257.808015 -237.958125) (xy 257.861972 -237.972231)
			(xy 257.913301 -237.994043) (xy 257.960907 -238.023097) (xy 258.003775 -238.058772) (xy 258.040992 -238.100309)
			(xy 258.071765 -238.146822) (xy 258.095437 -238.197319) (xy 258.111505 -238.250726) (xy 258.119625 -238.305902)
			(xy 258.120134 -238.333788) (xy 260.557008 -238.333788) (xy 260.561079 -238.278166) (xy 260.573205 -238.223729)
			(xy 260.593128 -238.171638) (xy 260.620424 -238.123003) (xy 260.65451 -238.07886) (xy 260.694659 -238.040151)
			(xy 260.740017 -238.0077) (xy 260.789617 -237.982199) (xy 260.842401 -237.964192) (xy 260.897244 -237.954062)
			(xy 260.952978 -237.952025) (xy 261.008415 -237.958125) (xy 261.062372 -237.972231) (xy 261.113701 -237.994043)
			(xy 261.161307 -238.023097) (xy 261.204175 -238.058772) (xy 261.241392 -238.100309) (xy 261.272165 -238.146822)
			(xy 261.295837 -238.197319) (xy 261.311905 -238.250726) (xy 261.320025 -238.305902) (xy 261.320534 -238.333788)
			(xy 261.32007 -238.359188) (xy 261.446008 -238.359188) (xy 261.450079 -238.303566) (xy 261.462205 -238.249129)
			(xy 261.482128 -238.197038) (xy 261.509424 -238.148403) (xy 261.54351 -238.10426) (xy 261.583659 -238.065551)
			(xy 261.629017 -238.0331) (xy 261.678617 -238.007599) (xy 261.731401 -237.989592) (xy 261.786244 -237.979462)
			(xy 261.841978 -237.977425) (xy 261.897415 -237.983525) (xy 261.951372 -237.997631) (xy 262.002701 -238.019443)
			(xy 262.050307 -238.048497) (xy 262.093175 -238.084172) (xy 262.130392 -238.125709) (xy 262.161165 -238.172222)
			(xy 262.184837 -238.222719) (xy 262.200905 -238.276126) (xy 262.209025 -238.331302) (xy 262.209534 -238.359188)
			(xy 262.209025 -238.387074) (xy 262.200905 -238.44225) (xy 262.184837 -238.495657) (xy 262.161165 -238.546154)
			(xy 262.130392 -238.592667) (xy 262.093175 -238.634204) (xy 262.050307 -238.669879) (xy 262.002701 -238.698933)
			(xy 261.951372 -238.720745) (xy 261.897415 -238.734851) (xy 261.841978 -238.740951) (xy 261.786244 -238.738914)
			(xy 261.731401 -238.728784) (xy 261.678617 -238.710777) (xy 261.629017 -238.685276) (xy 261.583659 -238.652825)
			(xy 261.54351 -238.614116) (xy 261.509424 -238.569973) (xy 261.482128 -238.521338) (xy 261.462205 -238.469247)
			(xy 261.450079 -238.41481) (xy 261.446008 -238.359188) (xy 261.32007 -238.359188) (xy 261.320025 -238.361674)
			(xy 261.311905 -238.41685) (xy 261.295837 -238.470257) (xy 261.272165 -238.520754) (xy 261.241392 -238.567267)
			(xy 261.204175 -238.608804) (xy 261.161307 -238.644479) (xy 261.113701 -238.673533) (xy 261.062372 -238.695345)
			(xy 261.008415 -238.709451) (xy 260.952978 -238.715551) (xy 260.897244 -238.713514) (xy 260.842401 -238.703384)
			(xy 260.789617 -238.685377) (xy 260.740017 -238.659876) (xy 260.694659 -238.627425) (xy 260.65451 -238.588716)
			(xy 260.620424 -238.544573) (xy 260.593128 -238.495938) (xy 260.573205 -238.443847) (xy 260.561079 -238.38941)
			(xy 260.557008 -238.333788) (xy 258.120134 -238.333788) (xy 258.119625 -238.361674) (xy 258.111505 -238.41685)
			(xy 258.095437 -238.470257) (xy 258.071765 -238.520754) (xy 258.040992 -238.567267) (xy 258.003775 -238.608804)
			(xy 257.960907 -238.644479) (xy 257.913301 -238.673533) (xy 257.861972 -238.695345) (xy 257.808015 -238.709451)
			(xy 257.752578 -238.715551) (xy 257.696844 -238.713514) (xy 257.642001 -238.703384) (xy 257.589217 -238.685377)
			(xy 257.539617 -238.659876) (xy 257.494259 -238.627425) (xy 257.45411 -238.588716) (xy 257.420024 -238.544573)
			(xy 257.392728 -238.495938) (xy 257.372805 -238.443847) (xy 257.360679 -238.38941) (xy 257.356608 -238.333788)
			(xy 254.919226 -238.333788) (xy 254.919226 -240.551716) (xy 254.919718 -240.565856) (xy 254.927535 -240.593037)
			(xy 254.942509 -240.61703) (xy 254.963491 -240.635995) (xy 254.988871 -240.648476) (xy 255.016701 -240.653514)
			(xy 255.044845 -240.650725) (xy 255.058164 -240.64595) (xy 255.080522 -240.637511) (xy 255.126812 -240.625636)
			(xy 255.174224 -240.619647) (xy 255.198118 -240.61928) (xy 255.198626 -240.61928) (xy 255.225888 -240.619738)
			(xy 255.279857 -240.627487) (xy 255.332174 -240.642838) (xy 255.381775 -240.665479) (xy 255.427648 -240.694948)
			(xy 255.46886 -240.730645) (xy 255.504572 -240.771845) (xy 255.519682 -240.79454) (xy 255.527963 -240.806467)
			(xy 255.549899 -240.825471) (xy 255.576299 -240.837526) (xy 255.605026 -240.841656) (xy 255.633753 -240.837526)
			(xy 255.660153 -240.825471) (xy 255.682089 -240.806467) (xy 255.69037 -240.79454) (xy 255.705524 -240.771878)
			(xy 255.741237 -240.730689) (xy 255.782446 -240.694999) (xy 255.828311 -240.665532) (xy 255.877902 -240.642888)
			(xy 255.930209 -240.627528) (xy 255.984168 -240.619764) (xy 256.011426 -240.61928) (xy 256.037401 -240.619721)
			(xy 256.088869 -240.626775) (xy 256.138904 -240.64075) (xy 256.186579 -240.661387) (xy 256.231012 -240.688303)
			(xy 256.27138 -240.721001) (xy 256.306937 -240.758875) (xy 256.322322 -240.779808) (xy 256.330731 -240.790821)
			(xy 256.352263 -240.808241) (xy 256.377685 -240.819233) (xy 256.405126 -240.82299) (xy 256.432567 -240.819233)
			(xy 256.457989 -240.808241) (xy 256.479521 -240.790821) (xy 256.48793 -240.779808) (xy 256.503324 -240.758881)
			(xy 256.53887 -240.720995) (xy 256.579233 -240.68829) (xy 256.623665 -240.66137) (xy 256.671342 -240.640736)
			(xy 256.721379 -240.626769) (xy 256.772851 -240.619729) (xy 256.798826 -240.61928) (xy 256.826077 -240.619768)
			(xy 256.880024 -240.627527) (xy 256.932317 -240.642885) (xy 256.981892 -240.665529) (xy 257.027741 -240.694996)
			(xy 257.068929 -240.730689) (xy 257.104619 -240.77188) (xy 257.134084 -240.817731) (xy 257.156724 -240.867308)
			(xy 257.172078 -240.919602) (xy 257.179834 -240.973549) (xy 257.179834 -241.028051) (xy 257.172078 -241.081998)
			(xy 257.156724 -241.134292) (xy 257.134084 -241.183869) (xy 257.104619 -241.22972) (xy 257.068929 -241.270911)
			(xy 257.027741 -241.306604) (xy 256.981892 -241.336071) (xy 256.932317 -241.358715) (xy 256.880024 -241.374073)
			(xy 256.826077 -241.381832) (xy 256.798826 -241.382296) (xy 256.772853 -241.381852) (xy 256.721389 -241.374792)
			(xy 256.671359 -241.360811) (xy 256.62369 -241.34017) (xy 256.579263 -241.31325) (xy 256.538901 -241.280549)
			(xy 256.503351 -241.242673) (xy 256.48793 -241.221768) (xy 256.479521 -241.210755) (xy 256.457989 -241.193335)
			(xy 256.432567 -241.182343) (xy 256.405126 -241.178586) (xy 256.377685 -241.182343) (xy 256.352263 -241.193335)
			(xy 256.330731 -241.210755) (xy 256.322322 -241.221768) (xy 256.306927 -241.242694) (xy 256.271379 -241.280577)
			(xy 256.231015 -241.313282) (xy 256.186584 -241.340202) (xy 256.138908 -241.360838) (xy 256.088871 -241.374809)
			(xy 256.037401 -241.381854) (xy 256.011426 -241.382296) (xy 255.984166 -241.381835) (xy 255.930201 -241.374079)
			(xy 255.87789 -241.358723) (xy 255.828296 -241.336078) (xy 255.782429 -241.306605) (xy 255.741224 -241.270905)
			(xy 255.70552 -241.229703) (xy 255.69037 -241.207036) (xy 255.682089 -241.195109) (xy 255.660153 -241.176105)
			(xy 255.633753 -241.16405) (xy 255.605026 -241.15992) (xy 255.576299 -241.16405) (xy 255.549899 -241.176105)
			(xy 255.527963 -241.195109) (xy 255.519682 -241.207036) (xy 255.504526 -241.229697) (xy 255.468811 -241.270883)
			(xy 255.427602 -241.306572) (xy 255.381737 -241.336039) (xy 255.332148 -241.358684) (xy 255.279842 -241.374048)
			(xy 255.225883 -241.381818) (xy 255.198626 -241.382296) (xy 255.198118 -241.382296) (xy 255.174225 -241.38191)
			(xy 255.126814 -241.375919) (xy 255.08052 -241.364066) (xy 255.058164 -241.355626) (xy 255.044844 -241.350854)
			(xy 255.016698 -241.348066) (xy 254.988867 -241.353104) (xy 254.963486 -241.365584) (xy 254.942501 -241.384547)
			(xy 254.927523 -241.408539) (xy 254.919701 -241.435719) (xy 254.919226 -241.44986) (xy 254.919226 -242.395756)
			(xy 254.944118 -242.420648) (xy 254.972058 -242.420648) (xy 254.990369 -242.39914) (xy 255.032233 -242.361221)
			(xy 255.079213 -242.329861) (xy 255.130289 -242.305741) (xy 255.184353 -242.289383) (xy 255.240233 -242.281142)
			(xy 255.268476 -242.280694) (xy 255.295894 -242.281158) (xy 255.350173 -242.288959) (xy 255.402788 -242.304405)
			(xy 255.45267 -242.327183) (xy 255.498803 -242.356828) (xy 255.516761 -242.372388) (xy 256.721608 -242.372388)
			(xy 256.725679 -242.316766) (xy 256.737805 -242.262329) (xy 256.757728 -242.210238) (xy 256.785024 -242.161603)
			(xy 256.81911 -242.11746) (xy 256.859259 -242.078751) (xy 256.904617 -242.0463) (xy 256.954217 -242.020799)
			(xy 257.007001 -242.002792) (xy 257.061844 -241.992662) (xy 257.117578 -241.990625) (xy 257.173015 -241.996725)
			(xy 257.226972 -242.010831) (xy 257.278301 -242.032643) (xy 257.325907 -242.061697) (xy 257.368775 -242.097372)
			(xy 257.405992 -242.138909) (xy 257.436765 -242.185422) (xy 257.460437 -242.235919) (xy 257.476505 -242.289326)
			(xy 257.484625 -242.344502) (xy 257.485134 -242.372388) (xy 257.484625 -242.400274) (xy 257.476505 -242.45545)
			(xy 257.460437 -242.508857) (xy 257.436765 -242.559354) (xy 257.405992 -242.605867) (xy 257.368775 -242.647404)
			(xy 257.325907 -242.683079) (xy 257.278301 -242.712133) (xy 257.226972 -242.733945) (xy 257.173015 -242.748051)
			(xy 257.117578 -242.754151) (xy 257.061844 -242.752114) (xy 257.007001 -242.741984) (xy 256.954217 -242.723977)
			(xy 256.904617 -242.698476) (xy 256.859259 -242.666025) (xy 256.81911 -242.627316) (xy 256.785024 -242.583173)
			(xy 256.757728 -242.534538) (xy 256.737805 -242.482447) (xy 256.725679 -242.42801) (xy 256.721608 -242.372388)
			(xy 255.516761 -242.372388) (xy 255.540246 -242.392737) (xy 255.576158 -242.434178) (xy 255.605805 -242.480309)
			(xy 255.628586 -242.530189) (xy 255.644036 -242.582804) (xy 255.65184 -242.637082) (xy 255.65184 -242.691918)
			(xy 255.644036 -242.746196) (xy 255.628586 -242.798811) (xy 255.605805 -242.848691) (xy 255.576158 -242.894822)
			(xy 255.540246 -242.936263) (xy 255.498803 -242.972172) (xy 255.45267 -243.001817) (xy 255.402788 -243.024595)
			(xy 255.350173 -243.040041) (xy 255.295894 -243.047842) (xy 255.268476 -243.048282) (xy 255.242175 -243.047849)
			(xy 255.190067 -243.040665) (xy 255.139426 -243.026436) (xy 255.091202 -243.005428) (xy 255.046297 -242.978033)
			(xy 255.005552 -242.944766) (xy 254.969729 -242.906247) (xy 254.954278 -242.88496) (xy 254.919226 -242.920012)
			(xy 254.919226 -243.388134) (xy 255.2446 -243.713508) (xy 260.2484 -243.713508)
		)
		(stroke
			(width 0)
			(type solid)
		)
		(fill yes)
		(layer "In15.Cu")
		(net "GND")
	)
	(gr_poly
		(pts
			(xy 457.406248 -251.75464) (xy 457.420127 -251.754123) (xy 457.446836 -251.746555) (xy 457.47052 -251.732073)
			(xy 457.489428 -251.711747) (xy 457.502164 -251.68708) (xy 457.507786 -251.659894) (xy 457.505878 -251.632199)
			(xy 457.496581 -251.606041) (xy 457.489052 -251.594366) (xy 457.47247 -251.570037) (xy 457.446194 -251.51735)
			(xy 457.428321 -251.461254) (xy 457.419274 -251.403078) (xy 457.418694 -251.37364) (xy 457.419155 -251.346385)
			(xy 457.426907 -251.29243) (xy 457.44226 -251.240128) (xy 457.4649 -251.190543) (xy 457.494367 -251.144685)
			(xy 457.53006 -251.103487) (xy 457.571254 -251.06779) (xy 457.617109 -251.038318) (xy 457.666692 -251.015673)
			(xy 457.718993 -251.000315) (xy 457.772947 -250.992557) (xy 457.800202 -250.992132) (xy 457.827993 -250.992634)
			(xy 457.882986 -251.000698) (xy 457.936227 -251.016656) (xy 457.98659 -251.040169) (xy 458.033008 -251.070741)
			(xy 458.0745 -251.107723) (xy 458.110187 -251.150334) (xy 458.139314 -251.197672) (xy 458.150722 -251.223018)
			(xy 458.157078 -251.236453) (xy 458.176196 -251.259193) (xy 458.201042 -251.27548) (xy 458.229521 -251.28394)
			(xy 458.259229 -251.28386) (xy 458.287662 -251.275245) (xy 458.300328 -251.267468) (xy 458.56652 -251.089922)
			(xy 458.737208 -250.919234) (xy 458.952346 -250.596908) (xy 458.959551 -250.585322) (xy 458.968143 -250.559436)
			(xy 458.969576 -250.532199) (xy 458.963749 -250.505555) (xy 458.951076 -250.481404) (xy 458.932463 -250.461468)
			(xy 458.921104 -250.453906) (xy 458.897693 -250.438932) (xy 458.855072 -250.403273) (xy 458.818081 -250.361801)
			(xy 458.787506 -250.315397) (xy 458.763995 -250.265045) (xy 458.748046 -250.211811) (xy 458.739998 -250.156826)
			(xy 458.739494 -250.12904) (xy 458.739955 -250.101785) (xy 458.747707 -250.04783) (xy 458.76306 -249.995528)
			(xy 458.7857 -249.945943) (xy 458.815167 -249.900085) (xy 458.85086 -249.858887) (xy 458.892054 -249.82319)
			(xy 458.937909 -249.793718) (xy 458.987492 -249.771073) (xy 459.039793 -249.755715) (xy 459.093747 -249.747957)
			(xy 459.121002 -249.747532) (xy 459.12151 -249.747532) (xy 459.150884 -249.748094) (xy 459.20893 -249.757157)
			(xy 459.23708 -249.765566) (xy 459.262416 -249.766062) (xy 459.312621 -249.772941) (xy 459.337156 -249.779282)
			(xy 459.349859 -249.774729) (xy 459.372453 -249.759991) (xy 459.390404 -249.739855) (xy 459.402462 -249.715725)
			(xy 459.405482 -249.702574) (xy 459.425802 -249.600974) (xy 459.425802 -245.980712) (xy 459.425301 -245.966577)
			(xy 459.417473 -245.93941) (xy 459.402495 -245.91543) (xy 459.381517 -245.896476) (xy 459.356146 -245.884)
			(xy 459.328326 -245.878958) (xy 459.300191 -245.881737) (xy 459.286864 -245.886478) (xy 459.264506 -245.894915)
			(xy 459.218216 -245.906782) (xy 459.170804 -245.912764) (xy 459.14691 -245.913148) (xy 459.146402 -245.913148)
			(xy 459.11915 -245.912662) (xy 459.0652 -245.904906) (xy 459.012902 -245.889552) (xy 458.963322 -245.866911)
			(xy 458.917469 -245.837446) (xy 458.876275 -245.801755) (xy 458.84058 -245.760565) (xy 458.811109 -245.714715)
			(xy 458.788463 -245.665137) (xy 458.773103 -245.612842) (xy 458.765341 -245.558892) (xy 458.764894 -245.53164)
			(xy 458.764894 -245.531386) (xy 458.765462 -245.501972) (xy 458.774538 -245.443847) (xy 458.792427 -245.387803)
			(xy 458.818705 -245.335169) (xy 458.85275 -245.287191) (xy 458.872844 -245.265702) (xy 458.638148 -245.031006)
			(xy 458.638148 -244.609874) (xy 458.935836 -244.312186) (xy 459.316582 -244.312186) (xy 459.316582 -244.13464)
			(xy 451.932802 -244.13464) (xy 451.678802 -244.38864) (xy 451.678802 -246.16664) (xy 454.116184 -246.16664)
			(xy 454.120255 -246.111018) (xy 454.132381 -246.056581) (xy 454.152304 -246.00449) (xy 454.1796 -245.955855)
			(xy 454.213686 -245.911712) (xy 454.253835 -245.873003) (xy 454.299193 -245.840552) (xy 454.348793 -245.815051)
			(xy 454.401577 -245.797044) (xy 454.45642 -245.786914) (xy 454.512154 -245.784877) (xy 454.567591 -245.790977)
			(xy 454.621548 -245.805083) (xy 454.672877 -245.826895) (xy 454.720483 -245.855949) (xy 454.763351 -245.891624)
			(xy 454.800568 -245.933161) (xy 454.831341 -245.979674) (xy 454.855013 -246.030171) (xy 454.871081 -246.083578)
			(xy 454.879201 -246.138754) (xy 454.87971 -246.16664) (xy 457.316584 -246.16664) (xy 457.320655 -246.111018)
			(xy 457.332781 -246.056581) (xy 457.352704 -246.00449) (xy 457.38 -245.955855) (xy 457.414086 -245.911712)
			(xy 457.454235 -245.873003) (xy 457.499593 -245.840552) (xy 457.549193 -245.815051) (xy 457.601977 -245.797044)
			(xy 457.65682 -245.786914) (xy 457.712554 -245.784877) (xy 457.767991 -245.790977) (xy 457.821948 -245.805083)
			(xy 457.873277 -245.826895) (xy 457.920883 -245.855949) (xy 457.963751 -245.891624) (xy 458.000968 -245.933161)
			(xy 458.031741 -245.979674) (xy 458.055413 -246.030171) (xy 458.071481 -246.083578) (xy 458.079601 -246.138754)
			(xy 458.08011 -246.16664) (xy 458.079646 -246.19204) (xy 458.205584 -246.19204) (xy 458.209655 -246.136418)
			(xy 458.221781 -246.081981) (xy 458.241704 -246.02989) (xy 458.269 -245.981255) (xy 458.303086 -245.937112)
			(xy 458.343235 -245.898403) (xy 458.388593 -245.865952) (xy 458.438193 -245.840451) (xy 458.490977 -245.822444)
			(xy 458.54582 -245.812314) (xy 458.601554 -245.810277) (xy 458.656991 -245.816377) (xy 458.710948 -245.830483)
			(xy 458.762277 -245.852295) (xy 458.809883 -245.881349) (xy 458.852751 -245.917024) (xy 458.889968 -245.958561)
			(xy 458.920741 -246.005074) (xy 458.944413 -246.055571) (xy 458.960481 -246.108978) (xy 458.968601 -246.164154)
			(xy 458.96911 -246.19204) (xy 458.968601 -246.219926) (xy 458.960481 -246.275102) (xy 458.944413 -246.328509)
			(xy 458.920741 -246.379006) (xy 458.889968 -246.425519) (xy 458.852751 -246.467056) (xy 458.809883 -246.502731)
			(xy 458.762277 -246.531785) (xy 458.710948 -246.553597) (xy 458.656991 -246.567703) (xy 458.601554 -246.573803)
			(xy 458.54582 -246.571766) (xy 458.490977 -246.561636) (xy 458.438193 -246.543629) (xy 458.388593 -246.518128)
			(xy 458.343235 -246.485677) (xy 458.303086 -246.446968) (xy 458.269 -246.402825) (xy 458.241704 -246.35419)
			(xy 458.221781 -246.302099) (xy 458.209655 -246.247662) (xy 458.205584 -246.19204) (xy 458.079646 -246.19204)
			(xy 458.079601 -246.194526) (xy 458.071481 -246.249702) (xy 458.055413 -246.303109) (xy 458.031741 -246.353606)
			(xy 458.000968 -246.400119) (xy 457.963751 -246.441656) (xy 457.920883 -246.477331) (xy 457.873277 -246.506385)
			(xy 457.821948 -246.528197) (xy 457.767991 -246.542303) (xy 457.712554 -246.548403) (xy 457.65682 -246.546366)
			(xy 457.601977 -246.536236) (xy 457.549193 -246.518229) (xy 457.499593 -246.492728) (xy 457.454235 -246.460277)
			(xy 457.414086 -246.421568) (xy 457.38 -246.377425) (xy 457.352704 -246.32879) (xy 457.332781 -246.276699)
			(xy 457.320655 -246.222262) (xy 457.316584 -246.16664) (xy 454.87971 -246.16664) (xy 454.879201 -246.194526)
			(xy 454.871081 -246.249702) (xy 454.855013 -246.303109) (xy 454.831341 -246.353606) (xy 454.800568 -246.400119)
			(xy 454.763351 -246.441656) (xy 454.720483 -246.477331) (xy 454.672877 -246.506385) (xy 454.621548 -246.528197)
			(xy 454.567591 -246.542303) (xy 454.512154 -246.548403) (xy 454.45642 -246.546366) (xy 454.401577 -246.536236)
			(xy 454.348793 -246.518229) (xy 454.299193 -246.492728) (xy 454.253835 -246.460277) (xy 454.213686 -246.421568)
			(xy 454.1796 -246.377425) (xy 454.152304 -246.32879) (xy 454.132381 -246.276699) (xy 454.120255 -246.222262)
			(xy 454.116184 -246.16664) (xy 451.678802 -246.16664) (xy 451.678802 -248.384568) (xy 451.6793 -248.398705)
			(xy 451.687126 -248.425876) (xy 451.702102 -248.44986) (xy 451.723082 -248.468818) (xy 451.748455 -248.481296)
			(xy 451.776278 -248.486338) (xy 451.804417 -248.483556) (xy 451.81774 -248.478802) (xy 451.840098 -248.470366)
			(xy 451.886389 -248.458499) (xy 451.9338 -248.452519) (xy 451.957694 -248.452132) (xy 451.958202 -248.452132)
			(xy 451.98546 -248.452618) (xy 452.039421 -248.460375) (xy 452.091729 -248.475732) (xy 452.14132 -248.498375)
			(xy 452.187185 -248.527844) (xy 452.228389 -248.56354) (xy 452.264095 -248.604735) (xy 452.279258 -248.627392)
			(xy 452.287539 -248.639319) (xy 452.309475 -248.658323) (xy 452.335875 -248.670378) (xy 452.364602 -248.674508)
			(xy 452.393329 -248.670378) (xy 452.419729 -248.658323) (xy 452.441665 -248.639319) (xy 452.449946 -248.627392)
			(xy 452.465101 -248.604731) (xy 452.500816 -248.563545) (xy 452.542025 -248.527856) (xy 452.587891 -248.498391)
			(xy 452.63748 -248.475747) (xy 452.689786 -248.460386) (xy 452.743745 -248.45262) (xy 452.771002 -248.452132)
			(xy 452.796977 -248.452571) (xy 452.848446 -248.459624) (xy 452.898482 -248.473597) (xy 452.946157 -248.494234)
			(xy 452.99059 -248.521151) (xy 453.030957 -248.553851) (xy 453.066513 -248.591728) (xy 453.081898 -248.61266)
			(xy 453.090307 -248.623673) (xy 453.111839 -248.641093) (xy 453.137261 -248.652085) (xy 453.164702 -248.655842)
			(xy 453.192143 -248.652085) (xy 453.217565 -248.641093) (xy 453.239097 -248.623673) (xy 453.247506 -248.61266)
			(xy 453.262901 -248.591734) (xy 453.298448 -248.553851) (xy 453.338812 -248.521147) (xy 453.383244 -248.494228)
			(xy 453.43092 -248.473593) (xy 453.480957 -248.459625) (xy 453.532427 -248.452583) (xy 453.558402 -248.452132)
			(xy 453.58565 -248.452618) (xy 453.639592 -248.460374) (xy 453.691881 -248.475728) (xy 453.741453 -248.498367)
			(xy 453.787298 -248.52783) (xy 453.828484 -248.563518) (xy 453.864171 -248.604704) (xy 453.893634 -248.650549)
			(xy 453.916273 -248.700121) (xy 453.931626 -248.75241) (xy 453.939382 -248.806352) (xy 453.939382 -248.860848)
			(xy 453.931626 -248.91479) (xy 453.916273 -248.967079) (xy 453.893634 -249.016651) (xy 453.864171 -249.062496)
			(xy 453.828484 -249.103682) (xy 453.787298 -249.13937) (xy 453.741453 -249.168833) (xy 453.691881 -249.191472)
			(xy 453.639592 -249.206826) (xy 453.58565 -249.214582) (xy 453.558402 -249.215148) (xy 453.532427 -249.214709)
			(xy 453.480958 -249.207657) (xy 453.430923 -249.193683) (xy 453.383248 -249.173046) (xy 453.338815 -249.146128)
			(xy 453.298449 -249.113428) (xy 453.262895 -249.07555) (xy 453.247506 -249.05462) (xy 453.239097 -249.043607)
			(xy 453.217565 -249.026187) (xy 453.192143 -249.015195) (xy 453.164702 -249.011438) (xy 453.137261 -249.015195)
			(xy 453.111839 -249.026187) (xy 453.090307 -249.043607) (xy 453.081898 -249.05462) (xy 453.066504 -249.075547)
			(xy 453.030957 -249.113433) (xy 452.990594 -249.146139) (xy 452.946163 -249.17306) (xy 452.898486 -249.193696)
			(xy 452.848449 -249.207665) (xy 452.796978 -249.214708) (xy 452.771002 -249.215148) (xy 452.743744 -249.214662)
			(xy 452.689783 -249.206905) (xy 452.637475 -249.191548) (xy 452.587885 -249.168905) (xy 452.542021 -249.139435)
			(xy 452.500817 -249.103739) (xy 452.465113 -249.062542) (xy 452.449946 -249.039888) (xy 452.441665 -249.027961)
			(xy 452.419729 -249.008957) (xy 452.393329 -248.996902) (xy 452.364602 -248.992772) (xy 452.335875 -248.996902)
			(xy 452.309475 -249.008957) (xy 452.287539 -249.027961) (xy 452.279258 -249.039888) (xy 452.264103 -249.06255)
			(xy 452.22839 -249.103739) (xy 452.187181 -249.13943) (xy 452.141316 -249.168897) (xy 452.091726 -249.191543)
			(xy 452.039419 -249.206905) (xy 451.98546 -249.214673) (xy 451.958202 -249.215148) (xy 451.957694 -249.215148)
			(xy 451.933801 -249.21476) (xy 451.886392 -249.208766) (xy 451.8401 -249.196909) (xy 451.81774 -249.188478)
			(xy 451.804419 -249.183711) (xy 451.776275 -249.180931) (xy 451.748448 -249.185973) (xy 451.723069 -249.198452)
			(xy 451.702085 -249.217412) (xy 451.687102 -249.241398) (xy 451.679271 -249.268573) (xy 451.678802 -249.282712)
			(xy 451.678802 -249.74804) (xy 451.67941 -249.763599) (xy 451.688864 -249.79325) (xy 451.706794 -249.818688)
			(xy 451.731541 -249.837561) (xy 451.760816 -249.848122) (xy 451.776338 -249.849386) (xy 451.804135 -249.850981)
			(xy 451.85886 -249.861224) (xy 451.911514 -249.879313) (xy 451.960981 -249.904864) (xy 452.006208 -249.937333)
			(xy 452.046236 -249.976031) (xy 452.080213 -250.020136) (xy 452.107419 -250.068712) (xy 452.127275 -250.120726)
			(xy 452.13936 -250.175074) (xy 452.141564 -250.20524) (xy 453.481184 -250.20524) (xy 453.485255 -250.149618)
			(xy 453.497381 -250.095181) (xy 453.517304 -250.04309) (xy 453.5446 -249.994455) (xy 453.578686 -249.950312)
			(xy 453.618835 -249.911603) (xy 453.664193 -249.879152) (xy 453.713793 -249.853651) (xy 453.766577 -249.835644)
			(xy 453.82142 -249.825514) (xy 453.877154 -249.823477) (xy 453.932591 -249.829577) (xy 453.986548 -249.843683)
			(xy 454.037877 -249.865495) (xy 454.085483 -249.894549) (xy 454.128351 -249.930224) (xy 454.165568 -249.971761)
			(xy 454.196341 -250.018274) (xy 454.220013 -250.068771) (xy 454.236081 -250.122178) (xy 454.244201 -250.177354)
			(xy 454.24471 -250.20524) (xy 454.244201 -250.233126) (xy 454.236081 -250.288302) (xy 454.220013 -250.341709)
			(xy 454.196341 -250.392206) (xy 454.165568 -250.438719) (xy 454.128351 -250.480256) (xy 454.085483 -250.515931)
			(xy 454.037877 -250.544985) (xy 453.986548 -250.566797) (xy 453.932591 -250.580903) (xy 453.877154 -250.587003)
			(xy 453.82142 -250.584966) (xy 453.766577 -250.574836) (xy 453.713793 -250.556829) (xy 453.664193 -250.531328)
			(xy 453.618835 -250.498877) (xy 453.578686 -250.460168) (xy 453.5446 -250.416025) (xy 453.517304 -250.36739)
			(xy 453.497381 -250.315299) (xy 453.485255 -250.260862) (xy 453.481184 -250.20524) (xy 452.141564 -250.20524)
			(xy 452.143417 -250.230602) (xy 452.139359 -250.286129) (xy 452.127274 -250.340477) (xy 452.107417 -250.392491)
			(xy 452.080211 -250.441066) (xy 452.046233 -250.485171) (xy 452.006206 -250.523869) (xy 451.960978 -250.556338)
			(xy 451.911512 -250.581888) (xy 451.858856 -250.599976) (xy 451.804131 -250.610219) (xy 451.776338 -250.611894)
			(xy 451.760792 -250.613063) (xy 451.731468 -250.623603) (xy 451.706682 -250.642488) (xy 451.688738 -250.667963)
			(xy 451.679303 -250.697661) (xy 451.678802 -250.71324) (xy 451.678802 -251.37364) (xy 452.059802 -251.75464)
		)
		(stroke
			(width 0)
			(type solid)
		)
		(fill yes)
		(layer "In15.Cu")
		(net "GND")
	)
	(gr_poly
		(pts
			(xy 148.476208 -244.679978) (xy 148.490094 -244.679466) (xy 148.51682 -244.671903) (xy 148.540521 -244.657421)
			(xy 148.559444 -244.63709) (xy 148.572192 -244.612413) (xy 148.577822 -244.585215) (xy 148.575918 -244.557505)
			(xy 148.566619 -244.531333) (xy 148.559012 -244.519704) (xy 148.542425 -244.495377) (xy 148.51614 -244.442692)
			(xy 148.498258 -244.386595) (xy 148.489204 -244.328417) (xy 148.488654 -244.298978) (xy 148.489141 -244.271727)
			(xy 148.4969 -244.217779) (xy 148.512257 -244.165485) (xy 148.534899 -244.115908) (xy 148.564365 -244.070058)
			(xy 148.600056 -244.028867) (xy 148.641245 -243.993175) (xy 148.687094 -243.963706) (xy 148.73667 -243.941062)
			(xy 148.788964 -243.925704) (xy 148.842911 -243.917942) (xy 148.870162 -243.91747) (xy 148.897954 -243.917969)
			(xy 148.952949 -243.926029) (xy 149.006193 -243.941984) (xy 149.056559 -243.965495) (xy 149.10298 -243.996067)
			(xy 149.144473 -244.03305) (xy 149.180161 -244.075663) (xy 149.209287 -244.123004) (xy 149.220682 -244.148356)
			(xy 149.227041 -244.161792) (xy 149.246162 -244.184533) (xy 149.27101 -244.200823) (xy 149.29949 -244.209288)
			(xy 149.329201 -244.209216) (xy 149.35764 -244.200613) (xy 149.370288 -244.192806) (xy 149.63648 -244.01526)
			(xy 149.807168 -243.844572) (xy 150.022306 -243.522246) (xy 150.029513 -243.510657) (xy 150.03811 -243.484765)
			(xy 150.039549 -243.457522) (xy 150.033729 -243.430869) (xy 150.021065 -243.406706) (xy 150.002458 -243.386755)
			(xy 149.991064 -243.379244) (xy 149.967653 -243.364269) (xy 149.925032 -243.328609) (xy 149.888041 -243.287138)
			(xy 149.857465 -243.240734) (xy 149.833951 -243.190382) (xy 149.817999 -243.137149) (xy 149.809947 -243.082164)
			(xy 149.809454 -243.054378) (xy 149.809941 -243.027127) (xy 149.8177 -242.973179) (xy 149.833057 -242.920885)
			(xy 149.855699 -242.871308) (xy 149.885165 -242.825458) (xy 149.920856 -242.784267) (xy 149.962045 -242.748575)
			(xy 150.007894 -242.719106) (xy 150.05747 -242.696462) (xy 150.109764 -242.681104) (xy 150.163711 -242.673342)
			(xy 150.190962 -242.67287) (xy 150.19147 -242.67287) (xy 150.220845 -242.673429) (xy 150.278892 -242.682487)
			(xy 150.30704 -242.690904) (xy 150.332375 -242.691404) (xy 150.382579 -242.69829) (xy 150.407116 -242.70462)
			(xy 150.41981 -242.70006) (xy 150.442383 -242.685311) (xy 150.460312 -242.665171) (xy 150.472348 -242.641042)
			(xy 150.475442 -242.627912) (xy 150.495762 -242.526312) (xy 150.495762 -238.90605) (xy 150.495266 -238.891914)
			(xy 150.487443 -238.864744) (xy 150.472468 -238.840761) (xy 150.451489 -238.821806) (xy 150.426115 -238.809333)
			(xy 150.398293 -238.804298) (xy 150.370156 -238.807088) (xy 150.356824 -238.811816) (xy 150.334466 -238.820255)
			(xy 150.288176 -238.832129) (xy 150.240764 -238.838117) (xy 150.21687 -238.838486) (xy 150.216362 -238.838486)
			(xy 150.189113 -238.837997) (xy 150.135171 -238.830236) (xy 150.082882 -238.814877) (xy 150.033311 -238.792234)
			(xy 149.987467 -238.762766) (xy 149.946283 -238.727074) (xy 149.910598 -238.685885) (xy 149.881137 -238.640036)
			(xy 149.858502 -238.590462) (xy 149.843151 -238.538171) (xy 149.835399 -238.484227) (xy 149.834854 -238.456978)
			(xy 149.834854 -238.456724) (xy 149.835294 -238.430428) (xy 149.842522 -238.378334) (xy 149.856843 -238.327728)
			(xy 149.877986 -238.279572) (xy 149.90555 -238.234781) (xy 149.93901 -238.194205) (xy 149.958044 -238.176054)
			(xy 149.968066 -238.166244) (xy 149.982766 -238.142375) (xy 149.990403 -238.115402) (xy 149.990398 -238.087369)
			(xy 149.982754 -238.060398) (xy 149.968047 -238.036533) (xy 149.958044 -238.026702) (xy 149.938994 -238.00857)
			(xy 149.905553 -237.967977) (xy 149.878 -237.923179) (xy 149.856857 -237.875022) (xy 149.842525 -237.824419)
			(xy 149.835274 -237.772328) (xy 149.834854 -237.746032) (xy 149.834854 -237.745778) (xy 149.835196 -237.722567)
			(xy 149.840835 -237.676489) (xy 149.852038 -237.63144) (xy 149.86 -237.609634) (xy 149.86 -237.283498)
			(xy 149.32025 -237.059978) (xy 143.397732 -237.059978) (xy 142.748762 -237.708948) (xy 142.748762 -239.091978)
			(xy 145.186144 -239.091978) (xy 145.190215 -239.036356) (xy 145.202341 -238.981919) (xy 145.222264 -238.929828)
			(xy 145.24956 -238.881193) (xy 145.283646 -238.83705) (xy 145.323795 -238.798341) (xy 145.369153 -238.76589)
			(xy 145.418753 -238.740389) (xy 145.471537 -238.722382) (xy 145.52638 -238.712252) (xy 145.582114 -238.710215)
			(xy 145.637551 -238.716315) (xy 145.691508 -238.730421) (xy 145.742837 -238.752233) (xy 145.790443 -238.781287)
			(xy 145.833311 -238.816962) (xy 145.870528 -238.858499) (xy 145.901301 -238.905012) (xy 145.924973 -238.955509)
			(xy 145.941041 -239.008916) (xy 145.949161 -239.064092) (xy 145.94967 -239.091978) (xy 148.386544 -239.091978)
			(xy 148.390615 -239.036356) (xy 148.402741 -238.981919) (xy 148.422664 -238.929828) (xy 148.44996 -238.881193)
			(xy 148.484046 -238.83705) (xy 148.524195 -238.798341) (xy 148.569553 -238.76589) (xy 148.619153 -238.740389)
			(xy 148.671937 -238.722382) (xy 148.72678 -238.712252) (xy 148.782514 -238.710215) (xy 148.837951 -238.716315)
			(xy 148.891908 -238.730421) (xy 148.943237 -238.752233) (xy 148.990843 -238.781287) (xy 149.033711 -238.816962)
			(xy 149.070928 -238.858499) (xy 149.101701 -238.905012) (xy 149.125373 -238.955509) (xy 149.141441 -239.008916)
			(xy 149.149561 -239.064092) (xy 149.15007 -239.091978) (xy 149.149606 -239.117378) (xy 149.275544 -239.117378)
			(xy 149.279615 -239.061756) (xy 149.291741 -239.007319) (xy 149.311664 -238.955228) (xy 149.33896 -238.906593)
			(xy 149.373046 -238.86245) (xy 149.413195 -238.823741) (xy 149.458553 -238.79129) (xy 149.508153 -238.765789)
			(xy 149.560937 -238.747782) (xy 149.61578 -238.737652) (xy 149.671514 -238.735615) (xy 149.726951 -238.741715)
			(xy 149.780908 -238.755821) (xy 149.832237 -238.777633) (xy 149.879843 -238.806687) (xy 149.922711 -238.842362)
			(xy 149.959928 -238.883899) (xy 149.990701 -238.930412) (xy 150.014373 -238.980909) (xy 150.030441 -239.034316)
			(xy 150.038561 -239.089492) (xy 150.03907 -239.117378) (xy 150.038561 -239.145264) (xy 150.030441 -239.20044)
			(xy 150.014373 -239.253847) (xy 149.990701 -239.304344) (xy 149.959928 -239.350857) (xy 149.922711 -239.392394)
			(xy 149.879843 -239.428069) (xy 149.832237 -239.457123) (xy 149.780908 -239.478935) (xy 149.726951 -239.493041)
			(xy 149.671514 -239.499141) (xy 149.61578 -239.497104) (xy 149.560937 -239.486974) (xy 149.508153 -239.468967)
			(xy 149.458553 -239.443466) (xy 149.413195 -239.411015) (xy 149.373046 -239.372306) (xy 149.33896 -239.328163)
			(xy 149.311664 -239.279528) (xy 149.291741 -239.227437) (xy 149.279615 -239.173) (xy 149.275544 -239.117378)
			(xy 149.149606 -239.117378) (xy 149.149561 -239.119864) (xy 149.141441 -239.17504) (xy 149.125373 -239.228447)
			(xy 149.101701 -239.278944) (xy 149.070928 -239.325457) (xy 149.033711 -239.366994) (xy 148.990843 -239.402669)
			(xy 148.943237 -239.431723) (xy 148.891908 -239.453535) (xy 148.837951 -239.467641) (xy 148.782514 -239.473741)
			(xy 148.72678 -239.471704) (xy 148.671937 -239.461574) (xy 148.619153 -239.443567) (xy 148.569553 -239.418066)
			(xy 148.524195 -239.385615) (xy 148.484046 -239.346906) (xy 148.44996 -239.302763) (xy 148.422664 -239.254128)
			(xy 148.402741 -239.202037) (xy 148.390615 -239.1476) (xy 148.386544 -239.091978) (xy 145.94967 -239.091978)
			(xy 145.949161 -239.119864) (xy 145.941041 -239.17504) (xy 145.924973 -239.228447) (xy 145.901301 -239.278944)
			(xy 145.870528 -239.325457) (xy 145.833311 -239.366994) (xy 145.790443 -239.402669) (xy 145.742837 -239.431723)
			(xy 145.691508 -239.453535) (xy 145.637551 -239.467641) (xy 145.582114 -239.473741) (xy 145.52638 -239.471704)
			(xy 145.471537 -239.461574) (xy 145.418753 -239.443567) (xy 145.369153 -239.418066) (xy 145.323795 -239.385615)
			(xy 145.283646 -239.346906) (xy 145.24956 -239.302763) (xy 145.222264 -239.254128) (xy 145.202341 -239.202037)
			(xy 145.190215 -239.1476) (xy 145.186144 -239.091978) (xy 142.748762 -239.091978) (xy 142.748762 -241.309906)
			(xy 142.749252 -241.324052) (xy 142.757068 -241.351245) (xy 142.772043 -241.375251) (xy 142.793027 -241.394229)
			(xy 142.818413 -241.406724) (xy 142.846252 -241.411776) (xy 142.874409 -241.408999) (xy 142.8877 -241.40414)
			(xy 142.910058 -241.395703) (xy 142.956348 -241.383834) (xy 143.00376 -241.377849) (xy 143.027654 -241.37747)
			(xy 143.028162 -241.37747) (xy 143.055421 -241.377953) (xy 143.109384 -241.385706) (xy 143.161695 -241.40106)
			(xy 143.211289 -241.423701) (xy 143.257156 -241.45317) (xy 143.298362 -241.488866) (xy 143.334069 -241.530063)
			(xy 143.349218 -241.55273) (xy 143.357499 -241.564657) (xy 143.379435 -241.583661) (xy 143.405835 -241.595716)
			(xy 143.434562 -241.599846) (xy 143.463289 -241.595716) (xy 143.489689 -241.583661) (xy 143.511625 -241.564657)
			(xy 143.519906 -241.55273) (xy 143.535061 -241.53007) (xy 143.570776 -241.488886) (xy 143.611985 -241.4532)
			(xy 143.657851 -241.423738) (xy 143.707441 -241.4011) (xy 143.759747 -241.385745) (xy 143.813705 -241.377986)
			(xy 143.840962 -241.37747) (xy 143.866936 -241.377913) (xy 143.918402 -241.384972) (xy 143.968433 -241.39895)
			(xy 144.016105 -241.419589) (xy 144.060535 -241.446507) (xy 144.1009 -241.479206) (xy 144.136454 -241.51708)
			(xy 144.151858 -241.537998) (xy 144.160267 -241.549011) (xy 144.181799 -241.566431) (xy 144.207221 -241.577423)
			(xy 144.234662 -241.58118) (xy 144.262103 -241.577423) (xy 144.287525 -241.566431) (xy 144.309057 -241.549011)
			(xy 144.317466 -241.537998) (xy 144.332859 -241.517069) (xy 144.368404 -241.479178) (xy 144.408766 -241.446466)
			(xy 144.453197 -241.41954) (xy 144.500874 -241.398898) (xy 144.550912 -241.384924) (xy 144.602385 -241.377875)
			(xy 144.628362 -241.37747) (xy 144.655618 -241.37793) (xy 144.709576 -241.385683) (xy 144.761882 -241.401037)
			(xy 144.81147 -241.423679) (xy 144.85733 -241.453147) (xy 144.89853 -241.488843) (xy 144.93423 -241.530039)
			(xy 144.963703 -241.575897) (xy 144.98635 -241.625482) (xy 145.001709 -241.677786) (xy 145.009467 -241.731744)
			(xy 145.009467 -241.786256) (xy 145.001709 -241.840214) (xy 144.98635 -241.892518) (xy 144.963703 -241.942103)
			(xy 144.93423 -241.987961) (xy 144.89853 -242.029157) (xy 144.85733 -242.064853) (xy 144.81147 -242.094321)
			(xy 144.761882 -242.116963) (xy 144.709576 -242.132317) (xy 144.655618 -242.14007) (xy 144.628362 -242.140486)
			(xy 144.602388 -242.140044) (xy 144.550921 -242.132988) (xy 144.500888 -242.119011) (xy 144.453216 -242.098372)
			(xy 144.408786 -242.071454) (xy 144.368421 -242.038754) (xy 144.332868 -242.000877) (xy 144.317466 -241.979958)
			(xy 144.309057 -241.968945) (xy 144.287525 -241.951525) (xy 144.262103 -241.940533) (xy 144.234662 -241.936776)
			(xy 144.207221 -241.940533) (xy 144.181799 -241.951525) (xy 144.160267 -241.968945) (xy 144.151858 -241.979958)
			(xy 144.136464 -242.000886) (xy 144.100917 -242.038774) (xy 144.060554 -242.071483) (xy 144.016123 -242.098408)
			(xy 143.968448 -242.119049) (xy 143.91841 -242.133025) (xy 143.866938 -242.140075) (xy 143.840962 -242.140486)
			(xy 143.813702 -242.140004) (xy 143.759735 -242.132255) (xy 143.70742 -242.116906) (xy 143.657821 -242.094268)
			(xy 143.611949 -242.064803) (xy 143.570735 -242.02911) (xy 143.535021 -241.987917) (xy 143.519906 -241.965226)
			(xy 143.511625 -241.953299) (xy 143.489689 -241.934295) (xy 143.463289 -241.92224) (xy 143.434562 -241.91811)
			(xy 143.405835 -241.92224) (xy 143.379435 -241.934295) (xy 143.357499 -241.953299) (xy 143.349218 -241.965226)
			(xy 143.334061 -241.987884) (xy 143.298345 -242.029065) (xy 143.257134 -242.064748) (xy 143.211269 -242.094208)
			(xy 143.161679 -242.116846) (xy 143.109375 -242.132201) (xy 143.055418 -242.139962) (xy 143.028162 -242.140486)
			(xy 143.027654 -242.140486) (xy 143.003761 -242.140096) (xy 142.956354 -242.134097) (xy 142.910063 -242.122237)
			(xy 142.8877 -242.113816) (xy 142.874384 -242.109054) (xy 142.846251 -242.106282) (xy 142.818436 -242.11133)
			(xy 142.793072 -242.123811) (xy 142.772102 -242.142769) (xy 142.757134 -242.16675) (xy 142.749316 -242.193917)
			(xy 142.748762 -242.20805) (xy 142.748762 -242.673378) (xy 142.749361 -242.688945) (xy 142.758803 -242.718617)
			(xy 142.776729 -242.744078) (xy 142.801479 -242.762972) (xy 142.830764 -242.773552) (xy 142.846298 -242.774724)
			(xy 142.874096 -242.776323) (xy 142.928823 -242.786574) (xy 142.98148 -242.804671) (xy 143.030947 -242.830228)
			(xy 143.076174 -242.862703) (xy 143.116201 -242.901407) (xy 143.150178 -242.945518) (xy 143.177384 -242.994098)
			(xy 143.19724 -243.046116) (xy 143.209324 -243.100468) (xy 143.211524 -243.130578) (xy 144.551144 -243.130578)
			(xy 144.555215 -243.074956) (xy 144.567341 -243.020519) (xy 144.587264 -242.968428) (xy 144.61456 -242.919793)
			(xy 144.648646 -242.87565) (xy 144.688795 -242.836941) (xy 144.734153 -242.80449) (xy 144.783753 -242.778989)
			(xy 144.836537 -242.760982) (xy 144.89138 -242.750852) (xy 144.947114 -242.748815) (xy 145.002551 -242.754915)
			(xy 145.056508 -242.769021) (xy 145.107837 -242.790833) (xy 145.155443 -242.819887) (xy 145.198311 -242.855562)
			(xy 145.235528 -242.897099) (xy 145.266301 -242.943612) (xy 145.289973 -242.994109) (xy 145.306041 -243.047516)
			(xy 145.314161 -243.102692) (xy 145.31467 -243.130578) (xy 145.314161 -243.158464) (xy 145.306041 -243.21364)
			(xy 145.289973 -243.267047) (xy 145.266301 -243.317544) (xy 145.235528 -243.364057) (xy 145.198311 -243.405594)
			(xy 145.155443 -243.441269) (xy 145.107837 -243.470323) (xy 145.056508 -243.492135) (xy 145.002551 -243.506241)
			(xy 144.947114 -243.512341) (xy 144.89138 -243.510304) (xy 144.836537 -243.500174) (xy 144.783753 -243.482167)
			(xy 144.734153 -243.456666) (xy 144.688795 -243.424215) (xy 144.648646 -243.385506) (xy 144.61456 -243.341363)
			(xy 144.587264 -243.292728) (xy 144.567341 -243.240637) (xy 144.555215 -243.1862) (xy 144.551144 -243.130578)
			(xy 143.211524 -243.130578) (xy 143.213381 -243.155999) (xy 143.209325 -243.21153) (xy 143.19724 -243.265882)
			(xy 143.177384 -243.317901) (xy 143.150179 -243.366481) (xy 143.116202 -243.410591) (xy 143.076175 -243.449295)
			(xy 143.030948 -243.481771) (xy 142.981481 -243.507329) (xy 142.928825 -243.525425) (xy 142.874098 -243.535677)
			(xy 142.846298 -243.537232) (xy 142.830758 -243.538406) (xy 142.801449 -243.548954) (xy 142.77668 -243.567842)
			(xy 142.758753 -243.593314) (xy 142.749333 -243.623004) (xy 142.748762 -243.638578) (xy 142.748762 -244.298978)
			(xy 143.129762 -244.679978)
		)
		(stroke
			(width 0)
			(type solid)
		)
		(fill yes)
		(layer "In15.Cu")
		(net "GND")
	)
	(gr_poly
		(pts
			(xy 17.144492 -215.701372) (xy 17.158379 -215.700862) (xy 17.185108 -215.693302) (xy 17.208812 -215.67882)
			(xy 17.227738 -215.658489) (xy 17.240487 -215.63381) (xy 17.246116 -215.60661) (xy 17.24421 -215.578898)
			(xy 17.234908 -215.552724) (xy 17.227296 -215.541098) (xy 17.21071 -215.51677) (xy 17.184427 -215.464085)
			(xy 17.166547 -215.407988) (xy 17.157494 -215.349811) (xy 17.156938 -215.320372) (xy 17.157403 -215.293122)
			(xy 17.165164 -215.239176) (xy 17.180523 -215.186884) (xy 17.203167 -215.137311) (xy 17.232637 -215.091464)
			(xy 17.268331 -215.050279) (xy 17.309524 -215.014592) (xy 17.355376 -214.985132) (xy 17.404954 -214.962497)
			(xy 17.457249 -214.947148) (xy 17.511196 -214.939398) (xy 17.538446 -214.938864) (xy 17.566234 -214.939369)
			(xy 17.621222 -214.947439) (xy 17.674458 -214.963402) (xy 17.724814 -214.986919) (xy 17.771225 -215.017494)
			(xy 17.812709 -215.054479) (xy 17.848388 -215.097091) (xy 17.877507 -215.144429) (xy 17.888966 -215.16975)
			(xy 17.895324 -215.183188) (xy 17.914445 -215.205935) (xy 17.939294 -215.222229) (xy 17.967777 -215.230699)
			(xy 17.997493 -215.230631) (xy 18.025936 -215.222028) (xy 18.038572 -215.2142) (xy 18.304764 -215.036654)
			(xy 18.475452 -214.865966) (xy 18.69059 -214.54364) (xy 18.697797 -214.532051) (xy 18.706394 -214.506161)
			(xy 18.707832 -214.478919) (xy 18.702011 -214.452267) (xy 18.689344 -214.428106) (xy 18.670736 -214.408158)
			(xy 18.659348 -214.400638) (xy 18.635933 -214.385666) (xy 18.593304 -214.35001) (xy 18.556306 -214.308541)
			(xy 18.525723 -214.262137) (xy 18.502205 -214.211784) (xy 18.48625 -214.158548) (xy 18.478196 -214.10356)
			(xy 18.477738 -214.075772) (xy 18.478203 -214.048522) (xy 18.485964 -213.994576) (xy 18.501323 -213.942284)
			(xy 18.523967 -213.892711) (xy 18.553437 -213.846864) (xy 18.589131 -213.805679) (xy 18.630324 -213.769992)
			(xy 18.676176 -213.740532) (xy 18.725754 -213.717897) (xy 18.778049 -213.702548) (xy 18.831996 -213.694798)
			(xy 18.859246 -213.694264) (xy 18.859754 -213.694264) (xy 18.889129 -213.694822) (xy 18.947177 -213.703877)
			(xy 18.975324 -213.712298) (xy 19.00066 -213.712797) (xy 19.050864 -213.719681) (xy 19.0754 -213.726014)
			(xy 19.088095 -213.721455) (xy 19.110671 -213.706708) (xy 19.128601 -213.686568) (xy 19.140638 -213.662438)
			(xy 19.143726 -213.649306) (xy 19.164046 -213.547706) (xy 19.164046 -209.927444) (xy 19.163549 -209.913303)
			(xy 19.155726 -209.886121) (xy 19.140749 -209.862126) (xy 19.119767 -209.843157) (xy 19.094388 -209.830668)
			(xy 19.066558 -209.825616) (xy 19.038409 -209.828388) (xy 19.025108 -209.83321) (xy 19.00275 -209.841648)
			(xy 18.95646 -209.853521) (xy 18.909048 -209.859507) (xy 18.885154 -209.85988) (xy 18.884646 -209.85988)
			(xy 18.857392 -209.85942) (xy 18.803437 -209.851668) (xy 18.751136 -209.836316) (xy 18.701551 -209.813675)
			(xy 18.655695 -209.784208) (xy 18.614499 -209.748514) (xy 18.578803 -209.70732) (xy 18.549333 -209.661464)
			(xy 18.526691 -209.611881) (xy 18.511336 -209.55958) (xy 18.503582 -209.505626) (xy 18.503138 -209.478372)
			(xy 18.503138 -209.478118) (xy 18.503572 -209.451819) (xy 18.510788 -209.399718) (xy 18.525099 -209.349104)
			(xy 18.546234 -209.300939) (xy 18.57379 -209.256137) (xy 18.607245 -209.215549) (xy 18.626328 -209.197448)
			(xy 18.636342 -209.187635) (xy 18.651028 -209.163764) (xy 18.658657 -209.136795) (xy 18.658652 -209.108768)
			(xy 18.651013 -209.081802) (xy 18.636318 -209.057936) (xy 18.626328 -209.048096) (xy 18.607279 -209.029963)
			(xy 18.57384 -208.98937) (xy 18.546289 -208.944571) (xy 18.525148 -208.896415) (xy 18.510817 -208.845812)
			(xy 18.503567 -208.793722) (xy 18.503138 -208.767426) (xy 18.503138 -208.767172) (xy 18.503603 -208.739922)
			(xy 18.511364 -208.685976) (xy 18.526723 -208.633684) (xy 18.549367 -208.584111) (xy 18.578837 -208.538264)
			(xy 18.614531 -208.497079) (xy 18.655724 -208.461392) (xy 18.701576 -208.431932) (xy 18.751154 -208.409297)
			(xy 18.803449 -208.393948) (xy 18.857396 -208.386198) (xy 18.884646 -208.385664) (xy 18.885154 -208.385664)
			(xy 18.909046 -208.386055) (xy 18.956454 -208.392055) (xy 19.002743 -208.403918) (xy 19.025108 -208.412334)
			(xy 19.038426 -208.417093) (xy 19.06656 -208.419861) (xy 19.094376 -208.414812) (xy 19.119743 -208.402332)
			(xy 19.140717 -208.383377) (xy 19.155692 -208.359398) (xy 19.163521 -208.332234) (xy 19.164046 -208.3181)
			(xy 19.164046 -208.081372) (xy 11.671046 -208.081372) (xy 11.417046 -208.335372) (xy 11.417046 -210.113372)
			(xy 13.854428 -210.113372) (xy 13.858499 -210.05775) (xy 13.870625 -210.003313) (xy 13.890548 -209.951222)
			(xy 13.917844 -209.902587) (xy 13.95193 -209.858444) (xy 13.992079 -209.819735) (xy 14.037437 -209.787284)
			(xy 14.087037 -209.761783) (xy 14.139821 -209.743776) (xy 14.194664 -209.733646) (xy 14.250398 -209.731609)
			(xy 14.305835 -209.737709) (xy 14.359792 -209.751815) (xy 14.411121 -209.773627) (xy 14.458727 -209.802681)
			(xy 14.501595 -209.838356) (xy 14.538812 -209.879893) (xy 14.569585 -209.926406) (xy 14.593257 -209.976903)
			(xy 14.609325 -210.03031) (xy 14.617445 -210.085486) (xy 14.617954 -210.113372) (xy 17.054828 -210.113372)
			(xy 17.058899 -210.05775) (xy 17.071025 -210.003313) (xy 17.090948 -209.951222) (xy 17.118244 -209.902587)
			(xy 17.15233 -209.858444) (xy 17.192479 -209.819735) (xy 17.237837 -209.787284) (xy 17.287437 -209.761783)
			(xy 17.340221 -209.743776) (xy 17.395064 -209.733646) (xy 17.450798 -209.731609) (xy 17.506235 -209.737709)
			(xy 17.560192 -209.751815) (xy 17.611521 -209.773627) (xy 17.659127 -209.802681) (xy 17.701995 -209.838356)
			(xy 17.739212 -209.879893) (xy 17.769985 -209.926406) (xy 17.793657 -209.976903) (xy 17.809725 -210.03031)
			(xy 17.817845 -210.085486) (xy 17.818354 -210.113372) (xy 17.81789 -210.138772) (xy 17.943828 -210.138772)
			(xy 17.947899 -210.08315) (xy 17.960025 -210.028713) (xy 17.979948 -209.976622) (xy 18.007244 -209.927987)
			(xy 18.04133 -209.883844) (xy 18.081479 -209.845135) (xy 18.126837 -209.812684) (xy 18.176437 -209.787183)
			(xy 18.229221 -209.769176) (xy 18.284064 -209.759046) (xy 18.339798 -209.757009) (xy 18.395235 -209.763109)
			(xy 18.449192 -209.777215) (xy 18.500521 -209.799027) (xy 18.548127 -209.828081) (xy 18.590995 -209.863756)
			(xy 18.628212 -209.905293) (xy 18.658985 -209.951806) (xy 18.682657 -210.002303) (xy 18.698725 -210.05571)
			(xy 18.706845 -210.110886) (xy 18.707354 -210.138772) (xy 18.706845 -210.166658) (xy 18.698725 -210.221834)
			(xy 18.682657 -210.275241) (xy 18.658985 -210.325738) (xy 18.628212 -210.372251) (xy 18.590995 -210.413788)
			(xy 18.548127 -210.449463) (xy 18.500521 -210.478517) (xy 18.449192 -210.500329) (xy 18.395235 -210.514435)
			(xy 18.339798 -210.520535) (xy 18.284064 -210.518498) (xy 18.229221 -210.508368) (xy 18.176437 -210.490361)
			(xy 18.126837 -210.46486) (xy 18.081479 -210.432409) (xy 18.04133 -210.3937) (xy 18.007244 -210.349557)
			(xy 17.979948 -210.300922) (xy 17.960025 -210.248831) (xy 17.947899 -210.194394) (xy 17.943828 -210.138772)
			(xy 17.81789 -210.138772) (xy 17.817845 -210.141258) (xy 17.809725 -210.196434) (xy 17.793657 -210.249841)
			(xy 17.769985 -210.300338) (xy 17.739212 -210.346851) (xy 17.701995 -210.388388) (xy 17.659127 -210.424063)
			(xy 17.611521 -210.453117) (xy 17.560192 -210.474929) (xy 17.506235 -210.489035) (xy 17.450798 -210.495135)
			(xy 17.395064 -210.493098) (xy 17.340221 -210.482968) (xy 17.287437 -210.464961) (xy 17.237837 -210.43946)
			(xy 17.192479 -210.407009) (xy 17.15233 -210.3683) (xy 17.118244 -210.324157) (xy 17.090948 -210.275522)
			(xy 17.071025 -210.223431) (xy 17.058899 -210.168994) (xy 17.054828 -210.113372) (xy 14.617954 -210.113372)
			(xy 14.617445 -210.141258) (xy 14.609325 -210.196434) (xy 14.593257 -210.249841) (xy 14.569585 -210.300338)
			(xy 14.538812 -210.346851) (xy 14.501595 -210.388388) (xy 14.458727 -210.424063) (xy 14.411121 -210.453117)
			(xy 14.359792 -210.474929) (xy 14.305835 -210.489035) (xy 14.250398 -210.495135) (xy 14.194664 -210.493098)
			(xy 14.139821 -210.482968) (xy 14.087037 -210.464961) (xy 14.037437 -210.43946) (xy 13.992079 -210.407009)
			(xy 13.95193 -210.3683) (xy 13.917844 -210.324157) (xy 13.890548 -210.275522) (xy 13.870625 -210.223431)
			(xy 13.858499 -210.168994) (xy 13.854428 -210.113372) (xy 11.417046 -210.113372) (xy 11.417046 -212.3313)
			(xy 11.417549 -212.34543) (xy 11.425379 -212.372587) (xy 11.440356 -212.396556) (xy 11.461332 -212.415498)
			(xy 11.486698 -212.427963) (xy 11.51451 -212.432994) (xy 11.542635 -212.430206) (xy 11.555984 -212.425534)
			(xy 11.578342 -212.417096) (xy 11.624632 -212.405225) (xy 11.672044 -212.399238) (xy 11.695938 -212.398864)
			(xy 11.696446 -212.398864) (xy 11.723705 -212.399346) (xy 11.77767 -212.407097) (xy 11.829983 -212.422449)
			(xy 11.879579 -212.445089) (xy 11.925448 -212.474557) (xy 11.966656 -212.510252) (xy 12.002366 -212.551448)
			(xy 12.017502 -212.574124) (xy 12.025783 -212.586051) (xy 12.047719 -212.605055) (xy 12.074119 -212.61711)
			(xy 12.102846 -212.62124) (xy 12.131573 -212.61711) (xy 12.157973 -212.605055) (xy 12.179909 -212.586051)
			(xy 12.18819 -212.574124) (xy 12.203345 -212.551464) (xy 12.23906 -212.510278) (xy 12.280269 -212.474591)
			(xy 12.326135 -212.445129) (xy 12.375725 -212.422489) (xy 12.428031 -212.407132) (xy 12.481989 -212.399371)
			(xy 12.509246 -212.398864) (xy 12.535219 -212.399306) (xy 12.586684 -212.406364) (xy 12.636715 -212.420343)
			(xy 12.684385 -212.440984) (xy 12.728811 -212.467905) (xy 12.769172 -212.500608) (xy 12.80472 -212.538487)
			(xy 12.820142 -212.559392) (xy 12.828551 -212.570405) (xy 12.850083 -212.587825) (xy 12.875505 -212.598817)
			(xy 12.902946 -212.602574) (xy 12.930387 -212.598817) (xy 12.955809 -212.587825) (xy 12.977341 -212.570405)
			(xy 12.98575 -212.559392) (xy 13.001143 -212.538462) (xy 13.036687 -212.50057) (xy 13.077049 -212.467858)
			(xy 13.12148 -212.44093) (xy 13.169157 -212.420287) (xy 13.219196 -212.40631) (xy 13.270669 -212.39926)
			(xy 13.296646 -212.398864) (xy 13.323899 -212.399327) (xy 13.37785 -212.407084) (xy 13.430148 -212.422439)
			(xy 13.479728 -212.445081) (xy 13.525582 -212.474549) (xy 13.566775 -212.510242) (xy 13.602469 -212.551435)
			(xy 13.631937 -212.597288) (xy 13.654579 -212.646868) (xy 13.669936 -212.699166) (xy 13.677693 -212.753117)
			(xy 13.677693 -212.807623) (xy 13.669936 -212.861574) (xy 13.654579 -212.913872) (xy 13.631937 -212.963452)
			(xy 13.602469 -213.009305) (xy 13.566775 -213.050498) (xy 13.525582 -213.086191) (xy 13.479728 -213.115659)
			(xy 13.430148 -213.138301) (xy 13.37785 -213.153656) (xy 13.323899 -213.161413) (xy 13.296646 -213.16188)
			(xy 13.270672 -213.161437) (xy 13.219207 -213.154379) (xy 13.169176 -213.1404) (xy 13.121505 -213.11976)
			(xy 13.077077 -213.092841) (xy 13.036715 -213.06014) (xy 13.001164 -213.022263) (xy 12.98575 -213.001352)
			(xy 12.977341 -212.990339) (xy 12.955809 -212.972919) (xy 12.930387 -212.961927) (xy 12.902946 -212.95817)
			(xy 12.875505 -212.961927) (xy 12.850083 -212.972919) (xy 12.828551 -212.990339) (xy 12.820142 -213.001352)
			(xy 12.804748 -213.022279) (xy 12.769201 -213.060166) (xy 12.728838 -213.092875) (xy 12.684407 -213.119798)
			(xy 12.636731 -213.140438) (xy 12.586693 -213.154411) (xy 12.535222 -213.16146) (xy 12.509246 -213.16188)
			(xy 12.481986 -213.161397) (xy 12.428021 -213.153646) (xy 12.375708 -213.138295) (xy 12.326111 -213.115656)
			(xy 12.28024 -213.086189) (xy 12.23903 -213.050496) (xy 12.203317 -213.009302) (xy 12.18819 -212.98662)
			(xy 12.179909 -212.974693) (xy 12.157973 -212.955689) (xy 12.131573 -212.943634) (xy 12.102846 -212.939504)
			(xy 12.074119 -212.943634) (xy 12.047719 -212.955689) (xy 12.025783 -212.974693) (xy 12.017502 -212.98662)
			(xy 12.002345 -213.009278) (xy 11.966628 -213.050458) (xy 11.925418 -213.08614) (xy 11.879552 -213.115598)
			(xy 11.829963 -213.138234) (xy 11.777658 -213.153588) (xy 11.723702 -213.161347) (xy 11.696446 -213.16188)
			(xy 11.695938 -213.16188) (xy 11.672046 -213.161489) (xy 11.624638 -213.155488) (xy 11.578349 -213.143626)
			(xy 11.555984 -213.13521) (xy 11.542662 -213.130436) (xy 11.514511 -213.127643) (xy 11.486673 -213.132679)
			(xy 11.461285 -213.145158) (xy 11.440294 -213.164122) (xy 11.425309 -213.188116) (xy 11.417481 -213.2153)
			(xy 11.417046 -213.229444) (xy 11.417046 -213.694772) (xy 11.417644 -213.710341) (xy 11.427085 -213.740016)
			(xy 11.445009 -213.765481) (xy 11.469759 -213.78438) (xy 11.499046 -213.794965) (xy 11.514582 -213.796118)
			(xy 11.542379 -213.797716) (xy 11.597105 -213.807965) (xy 11.64976 -213.826059) (xy 11.699226 -213.851614)
			(xy 11.744452 -213.884087) (xy 11.784478 -213.922789) (xy 11.818455 -213.966897) (xy 11.84566 -214.015475)
			(xy 11.865515 -214.067491) (xy 11.8776 -214.121841) (xy 11.879801 -214.151972) (xy 13.219428 -214.151972)
			(xy 13.223499 -214.09635) (xy 13.235625 -214.041913) (xy 13.255548 -213.989822) (xy 13.282844 -213.941187)
			(xy 13.31693 -213.897044) (xy 13.357079 -213.858335) (xy 13.402437 -213.825884) (xy 13.452037 -213.800383)
			(xy 13.504821 -213.782376) (xy 13.559664 -213.772246) (xy 13.615398 -213.770209) (xy 13.670835 -213.776309)
			(xy 13.724792 -213.790415) (xy 13.776121 -213.812227) (xy 13.823727 -213.841281) (xy 13.866595 -213.876956)
			(xy 13.903812 -213.918493) (xy 13.934585 -213.965006) (xy 13.958257 -214.015503) (xy 13.974325 -214.06891)
			(xy 13.982445 -214.124086) (xy 13.982954 -214.151972) (xy 13.982445 -214.179858) (xy 13.974325 -214.235034)
			(xy 13.958257 -214.288441) (xy 13.934585 -214.338938) (xy 13.903812 -214.385451) (xy 13.866595 -214.426988)
			(xy 13.823727 -214.462663) (xy 13.776121 -214.491717) (xy 13.724792 -214.513529) (xy 13.670835 -214.527635)
			(xy 13.615398 -214.533735) (xy 13.559664 -214.531698) (xy 13.504821 -214.521568) (xy 13.452037 -214.503561)
			(xy 13.402437 -214.47806) (xy 13.357079 -214.445609) (xy 13.31693 -214.4069) (xy 13.282844 -214.362757)
			(xy 13.255548 -214.314122) (xy 13.235625 -214.262031) (xy 13.223499 -214.207594) (xy 13.219428 -214.151972)
			(xy 11.879801 -214.151972) (xy 11.881657 -214.17737) (xy 11.8776 -214.232899) (xy 11.865515 -214.287249)
			(xy 11.84566 -214.339265) (xy 11.818455 -214.387843) (xy 11.784478 -214.431951) (xy 11.744452 -214.470653)
			(xy 11.699225 -214.503126) (xy 11.64976 -214.528681) (xy 11.597105 -214.546775) (xy 11.542379 -214.557024)
			(xy 11.514582 -214.558626) (xy 11.499043 -214.559802) (xy 11.469738 -214.570353) (xy 11.444972 -214.589241)
			(xy 11.427047 -214.614712) (xy 11.417627 -214.6444) (xy 11.417046 -214.659972) (xy 11.417046 -215.320372)
			(xy 11.798046 -215.701372)
		)
		(stroke
			(width 0)
			(type solid)
		)
		(fill yes)
		(layer "In15.Cu")
		(net "GND")
	)
	(gr_poly
		(pts
			(xy 233.037126 -215.750648) (xy 233.049201 -215.749986) (xy 233.0707 -215.738991) (xy 233.078274 -215.729566)
			(xy 233.133646 -215.652604) (xy 233.137202 -215.62822) (xy 233.133392 -215.616536) (xy 233.124834 -215.589263)
			(xy 233.115649 -215.532847) (xy 233.115104 -215.504268) (xy 233.115596 -215.477904) (xy 233.123455 -215.425764)
			(xy 233.138997 -215.375379) (xy 233.161875 -215.327872) (xy 233.191578 -215.284306) (xy 233.227442 -215.245653)
			(xy 233.268667 -215.212778) (xy 233.314331 -215.186413) (xy 233.363415 -215.16715) (xy 233.414821 -215.155416)
			(xy 233.467402 -215.151476) (xy 233.519983 -215.155416) (xy 233.571389 -215.16715) (xy 233.620473 -215.186413)
			(xy 233.666137 -215.212778) (xy 233.707362 -215.245653) (xy 233.743226 -215.284306) (xy 233.772929 -215.327872)
			(xy 233.795807 -215.375379) (xy 233.811349 -215.425764) (xy 233.819208 -215.477904) (xy 233.8197 -215.504268)
			(xy 233.819163 -215.532848) (xy 233.809967 -215.589261) (xy 233.801412 -215.616536) (xy 233.797602 -215.62822)
			(xy 233.801158 -215.652604) (xy 233.85653 -215.729566) (xy 233.864141 -215.73895) (xy 233.885616 -215.749949)
			(xy 233.897678 -215.750648) (xy 237.009686 -215.750648) (xy 237.019748 -215.750208) (xy 237.038325 -215.742466)
			(xy 237.045754 -215.735662) (xy 237.423706 -215.35771) (xy 237.430553 -215.350312) (xy 237.438291 -215.331714)
			(xy 237.438692 -215.321642) (xy 237.438692 -212.729318) (xy 237.438254 -212.719255) (xy 237.430517 -212.700673)
			(xy 237.423706 -212.69325) (xy 237.181644 -212.451188) (xy 237.174247 -212.444341) (xy 237.155647 -212.436613)
			(xy 237.145576 -212.436202) (xy 236.18825 -212.436202) (xy 236.164628 -212.450172) (xy 236.15777 -212.462618)
			(xy 236.145226 -212.484623) (xy 236.114487 -212.524878) (xy 236.077968 -212.559975) (xy 236.036523 -212.589091)
			(xy 235.991124 -212.611547) (xy 235.94283 -212.626815) (xy 235.892773 -212.63454) (xy 235.842123 -212.63454)
			(xy 235.792066 -212.626815) (xy 235.743772 -212.611547) (xy 235.698373 -212.589091) (xy 235.656928 -212.559975)
			(xy 235.620409 -212.524878) (xy 235.58967 -212.484623) (xy 235.577126 -212.462618) (xy 235.570268 -212.450172)
			(xy 235.546646 -212.436202) (xy 233.788204 -212.436202) (xy 233.764582 -212.450172) (xy 233.757724 -212.462618)
			(xy 233.74518 -212.484623) (xy 233.714441 -212.524878) (xy 233.677922 -212.559975) (xy 233.636477 -212.589091)
			(xy 233.591078 -212.611547) (xy 233.542784 -212.626815) (xy 233.492727 -212.63454) (xy 233.442077 -212.63454)
			(xy 233.39202 -212.626815) (xy 233.343726 -212.611547) (xy 233.298327 -212.589091) (xy 233.256882 -212.559975)
			(xy 233.220363 -212.524878) (xy 233.189624 -212.484623) (xy 233.17708 -212.462618) (xy 233.170222 -212.450172)
			(xy 233.1466 -212.436202) (xy 232.30967 -212.436202) (xy 232.299602 -212.436631) (xy 232.281006 -212.444353)
			(xy 232.273602 -212.451188) (xy 231.793542 -212.931248) (xy 231.786699 -212.938647) (xy 231.778975 -212.957246)
			(xy 231.778556 -212.967316) (xy 231.778556 -213.130463) (xy 233.137204 -213.130463) (xy 233.137204 -213.078489)
			(xy 233.145334 -213.027154) (xy 233.161395 -212.977724) (xy 233.184991 -212.931414) (xy 233.215541 -212.889366)
			(xy 233.252292 -212.852615) (xy 233.29434 -212.822065) (xy 233.34065 -212.798469) (xy 233.39008 -212.782408)
			(xy 233.441415 -212.774278) (xy 233.493389 -212.774278) (xy 233.544724 -212.782408) (xy 233.594154 -212.798469)
			(xy 233.640464 -212.822065) (xy 233.682512 -212.852615) (xy 233.719263 -212.889366) (xy 233.749813 -212.931414)
			(xy 233.773409 -212.977724) (xy 233.78947 -213.027154) (xy 233.7976 -213.078489) (xy 233.79811 -213.104476)
			(xy 233.7976 -213.130463) (xy 233.78947 -213.181798) (xy 233.773409 -213.231228) (xy 233.749813 -213.277538)
			(xy 233.719263 -213.319586) (xy 233.682512 -213.356337) (xy 233.640464 -213.386887) (xy 233.594154 -213.410483)
			(xy 233.544724 -213.426544) (xy 233.493389 -213.434674) (xy 233.441415 -213.434674) (xy 233.39008 -213.426544)
			(xy 233.34065 -213.410483) (xy 233.29434 -213.386887) (xy 233.252292 -213.356337) (xy 233.215541 -213.319586)
			(xy 233.184991 -213.277538) (xy 233.161395 -213.231228) (xy 233.145334 -213.181798) (xy 233.137204 -213.130463)
			(xy 231.778556 -213.130463) (xy 231.778556 -213.472268) (xy 231.779051 -213.482081) (xy 231.786486 -213.50025)
			(xy 231.793034 -213.507574) (xy 231.849168 -213.565486) (xy 231.867202 -213.57336) (xy 231.877108 -213.573868)
			(xy 231.902582 -213.575087) (xy 231.952724 -213.58439) (xy 232.000844 -213.601279) (xy 232.045801 -213.625353)
			(xy 232.086532 -213.656041) (xy 232.122069 -213.692618) (xy 232.151572 -213.734215) (xy 232.17434 -213.779848)
			(xy 232.189835 -213.828434) (xy 232.197689 -213.878823) (xy 232.198164 -213.904322) (xy 232.197679 -213.930309)
			(xy 232.337358 -213.930309) (xy 232.337358 -213.878335) (xy 232.345488 -213.827) (xy 232.361549 -213.77757)
			(xy 232.385145 -213.73126) (xy 232.415695 -213.689212) (xy 232.452446 -213.652461) (xy 232.494494 -213.621911)
			(xy 232.540804 -213.598315) (xy 232.590234 -213.582254) (xy 232.641569 -213.574124) (xy 232.693543 -213.574124)
			(xy 232.744878 -213.582254) (xy 232.794308 -213.598315) (xy 232.840618 -213.621911) (xy 232.882666 -213.652461)
			(xy 232.919417 -213.689212) (xy 232.949967 -213.73126) (xy 232.973563 -213.77757) (xy 232.989624 -213.827)
			(xy 232.997754 -213.878335) (xy 232.998264 -213.904322) (xy 232.997754 -213.930309) (xy 233.137204 -213.930309)
			(xy 233.137204 -213.878335) (xy 233.145334 -213.827) (xy 233.161395 -213.77757) (xy 233.184991 -213.73126)
			(xy 233.215541 -213.689212) (xy 233.252292 -213.652461) (xy 233.29434 -213.621911) (xy 233.34065 -213.598315)
			(xy 233.39008 -213.582254) (xy 233.441415 -213.574124) (xy 233.493389 -213.574124) (xy 233.544724 -213.582254)
			(xy 233.594154 -213.598315) (xy 233.640464 -213.621911) (xy 233.682512 -213.652461) (xy 233.719263 -213.689212)
			(xy 233.749813 -213.73126) (xy 233.773409 -213.77757) (xy 233.78947 -213.827) (xy 233.7976 -213.878335)
			(xy 233.79811 -213.904322) (xy 233.7976 -213.930309) (xy 233.937304 -213.930309) (xy 233.937304 -213.878335)
			(xy 233.945434 -213.827) (xy 233.961495 -213.77757) (xy 233.985091 -213.73126) (xy 234.015641 -213.689212)
			(xy 234.052392 -213.652461) (xy 234.09444 -213.621911) (xy 234.14075 -213.598315) (xy 234.19018 -213.582254)
			(xy 234.241515 -213.574124) (xy 234.293489 -213.574124) (xy 234.344824 -213.582254) (xy 234.394254 -213.598315)
			(xy 234.440564 -213.621911) (xy 234.482612 -213.652461) (xy 234.519363 -213.689212) (xy 234.549913 -213.73126)
			(xy 234.573509 -213.77757) (xy 234.58957 -213.827) (xy 234.5977 -213.878335) (xy 234.59821 -213.904322)
			(xy 234.5977 -213.930309) (xy 234.58957 -213.981644) (xy 234.573509 -214.031074) (xy 234.549913 -214.077384)
			(xy 234.519363 -214.119432) (xy 234.482612 -214.156183) (xy 234.440564 -214.186733) (xy 234.394254 -214.210329)
			(xy 234.344824 -214.22639) (xy 234.293489 -214.23452) (xy 234.241515 -214.23452) (xy 234.19018 -214.22639)
			(xy 234.14075 -214.210329) (xy 234.09444 -214.186733) (xy 234.052392 -214.156183) (xy 234.015641 -214.119432)
			(xy 233.985091 -214.077384) (xy 233.961495 -214.031074) (xy 233.945434 -213.981644) (xy 233.937304 -213.930309)
			(xy 233.7976 -213.930309) (xy 233.78947 -213.981644) (xy 233.773409 -214.031074) (xy 233.749813 -214.077384)
			(xy 233.719263 -214.119432) (xy 233.682512 -214.156183) (xy 233.640464 -214.186733) (xy 233.594154 -214.210329)
			(xy 233.544724 -214.22639) (xy 233.493389 -214.23452) (xy 233.441415 -214.23452) (xy 233.39008 -214.22639)
			(xy 233.34065 -214.210329) (xy 233.29434 -214.186733) (xy 233.252292 -214.156183) (xy 233.215541 -214.119432)
			(xy 233.184991 -214.077384) (xy 233.161395 -214.031074) (xy 233.145334 -213.981644) (xy 233.137204 -213.930309)
			(xy 232.997754 -213.930309) (xy 232.989624 -213.981644) (xy 232.973563 -214.031074) (xy 232.949967 -214.077384)
			(xy 232.919417 -214.119432) (xy 232.882666 -214.156183) (xy 232.840618 -214.186733) (xy 232.794308 -214.210329)
			(xy 232.744878 -214.22639) (xy 232.693543 -214.23452) (xy 232.641569 -214.23452) (xy 232.590234 -214.22639)
			(xy 232.540804 -214.210329) (xy 232.494494 -214.186733) (xy 232.452446 -214.156183) (xy 232.415695 -214.119432)
			(xy 232.385145 -214.077384) (xy 232.361549 -214.031074) (xy 232.345488 -213.981644) (xy 232.337358 -213.930309)
			(xy 232.197679 -213.930309) (xy 232.189545 -213.981642) (xy 232.17348 -214.031071) (xy 232.149881 -214.077378)
			(xy 232.119327 -214.119423) (xy 232.082573 -214.15617) (xy 232.040522 -214.186715) (xy 231.99421 -214.210306)
			(xy 231.944778 -214.22636) (xy 231.893443 -214.234484) (xy 231.867456 -214.23503) (xy 231.834436 -214.233252)
			(xy 231.831896 -214.232998) (xy 231.829356 -214.232998) (xy 231.819354 -214.233494) (xy 231.800877 -214.241161)
			(xy 231.786737 -214.255312) (xy 231.779085 -214.273796) (xy 231.778556 -214.283798) (xy 231.778556 -214.324946)
			(xy 231.779051 -214.334951) (xy 231.786718 -214.353434) (xy 231.800867 -214.367584) (xy 231.819351 -214.375249)
			(xy 231.829356 -214.375746) (xy 231.831896 -214.375746) (xy 231.834436 -214.375492) (xy 231.867456 -214.373714)
			(xy 231.893446 -214.374194) (xy 231.944786 -214.382319) (xy 231.994223 -214.398376) (xy 232.04054 -214.42197)
			(xy 232.082594 -214.45252) (xy 232.119352 -214.489272) (xy 232.149907 -214.531323) (xy 232.173507 -214.577636)
			(xy 232.189571 -214.627071) (xy 232.197703 -214.67841) (xy 232.197703 -214.73039) (xy 232.1977 -214.730409)
			(xy 232.337358 -214.730409) (xy 232.337358 -214.678435) (xy 232.345488 -214.6271) (xy 232.361549 -214.57767)
			(xy 232.385145 -214.53136) (xy 232.415695 -214.489312) (xy 232.452446 -214.452561) (xy 232.494494 -214.422011)
			(xy 232.540804 -214.398415) (xy 232.590234 -214.382354) (xy 232.641569 -214.374224) (xy 232.693543 -214.374224)
			(xy 232.744878 -214.382354) (xy 232.794308 -214.398415) (xy 232.840618 -214.422011) (xy 232.882666 -214.452561)
			(xy 232.919417 -214.489312) (xy 232.949967 -214.53136) (xy 232.973563 -214.57767) (xy 232.989624 -214.6271)
			(xy 232.997754 -214.678435) (xy 232.998264 -214.704422) (xy 232.997754 -214.730409) (xy 233.137204 -214.730409)
			(xy 233.137204 -214.678435) (xy 233.145334 -214.6271) (xy 233.161395 -214.57767) (xy 233.184991 -214.53136)
			(xy 233.215541 -214.489312) (xy 233.252292 -214.452561) (xy 233.29434 -214.422011) (xy 233.34065 -214.398415)
			(xy 233.39008 -214.382354) (xy 233.441415 -214.374224) (xy 233.493389 -214.374224) (xy 233.544724 -214.382354)
			(xy 233.594154 -214.398415) (xy 233.640464 -214.422011) (xy 233.682512 -214.452561) (xy 233.719263 -214.489312)
			(xy 233.749813 -214.53136) (xy 233.773409 -214.57767) (xy 233.78947 -214.6271) (xy 233.7976 -214.678435)
			(xy 233.79811 -214.704422) (xy 233.7976 -214.730409) (xy 233.937304 -214.730409) (xy 233.937304 -214.678435)
			(xy 233.945434 -214.6271) (xy 233.961495 -214.57767) (xy 233.985091 -214.53136) (xy 234.015641 -214.489312)
			(xy 234.052392 -214.452561) (xy 234.09444 -214.422011) (xy 234.14075 -214.398415) (xy 234.19018 -214.382354)
			(xy 234.241515 -214.374224) (xy 234.293489 -214.374224) (xy 234.344824 -214.382354) (xy 234.394254 -214.398415)
			(xy 234.440564 -214.422011) (xy 234.482612 -214.452561) (xy 234.519363 -214.489312) (xy 234.549913 -214.53136)
			(xy 234.573509 -214.57767) (xy 234.58957 -214.6271) (xy 234.5977 -214.678435) (xy 234.59821 -214.704422)
			(xy 234.5977 -214.730409) (xy 234.73715 -214.730409) (xy 234.73715 -214.678435) (xy 234.74528 -214.6271)
			(xy 234.761341 -214.57767) (xy 234.784937 -214.53136) (xy 234.815487 -214.489312) (xy 234.852238 -214.452561)
			(xy 234.894286 -214.422011) (xy 234.940596 -214.398415) (xy 234.990026 -214.382354) (xy 235.041361 -214.374224)
			(xy 235.093335 -214.374224) (xy 235.14467 -214.382354) (xy 235.1941 -214.398415) (xy 235.24041 -214.422011)
			(xy 235.282458 -214.452561) (xy 235.319209 -214.489312) (xy 235.349759 -214.53136) (xy 235.373355 -214.57767)
			(xy 235.389416 -214.6271) (xy 235.397546 -214.678435) (xy 235.398056 -214.704422) (xy 235.397546 -214.730409)
			(xy 235.389416 -214.781744) (xy 235.373355 -214.831174) (xy 235.349759 -214.877484) (xy 235.319209 -214.919532)
			(xy 235.282458 -214.956283) (xy 235.24041 -214.986833) (xy 235.1941 -215.010429) (xy 235.14467 -215.02649)
			(xy 235.093335 -215.03462) (xy 235.041361 -215.03462) (xy 234.990026 -215.02649) (xy 234.940596 -215.010429)
			(xy 234.894286 -214.986833) (xy 234.852238 -214.956283) (xy 234.815487 -214.919532) (xy 234.784937 -214.877484)
			(xy 234.761341 -214.831174) (xy 234.74528 -214.781744) (xy 234.73715 -214.730409) (xy 234.5977 -214.730409)
			(xy 234.58957 -214.781744) (xy 234.573509 -214.831174) (xy 234.549913 -214.877484) (xy 234.519363 -214.919532)
			(xy 234.482612 -214.956283) (xy 234.440564 -214.986833) (xy 234.394254 -215.010429) (xy 234.344824 -215.02649)
			(xy 234.293489 -215.03462) (xy 234.241515 -215.03462) (xy 234.19018 -215.02649) (xy 234.14075 -215.010429)
			(xy 234.09444 -214.986833) (xy 234.052392 -214.956283) (xy 234.015641 -214.919532) (xy 233.985091 -214.877484)
			(xy 233.961495 -214.831174) (xy 233.945434 -214.781744) (xy 233.937304 -214.730409) (xy 233.7976 -214.730409)
			(xy 233.78947 -214.781744) (xy 233.773409 -214.831174) (xy 233.749813 -214.877484) (xy 233.719263 -214.919532)
			(xy 233.682512 -214.956283) (xy 233.640464 -214.986833) (xy 233.594154 -215.010429) (xy 233.544724 -215.02649)
			(xy 233.493389 -215.03462) (xy 233.441415 -215.03462) (xy 233.39008 -215.02649) (xy 233.34065 -215.010429)
			(xy 233.29434 -214.986833) (xy 233.252292 -214.956283) (xy 233.215541 -214.919532) (xy 233.184991 -214.877484)
			(xy 233.161395 -214.831174) (xy 233.145334 -214.781744) (xy 233.137204 -214.730409) (xy 232.997754 -214.730409)
			(xy 232.989624 -214.781744) (xy 232.973563 -214.831174) (xy 232.949967 -214.877484) (xy 232.919417 -214.919532)
			(xy 232.882666 -214.956283) (xy 232.840618 -214.986833) (xy 232.794308 -215.010429) (xy 232.744878 -215.02649)
			(xy 232.693543 -215.03462) (xy 232.641569 -215.03462) (xy 232.590234 -215.02649) (xy 232.540804 -215.010429)
			(xy 232.494494 -214.986833) (xy 232.452446 -214.956283) (xy 232.415695 -214.919532) (xy 232.385145 -214.877484)
			(xy 232.361549 -214.831174) (xy 232.345488 -214.781744) (xy 232.337358 -214.730409) (xy 232.1977 -214.730409)
			(xy 232.189571 -214.781729) (xy 232.173507 -214.831164) (xy 232.149907 -214.877477) (xy 232.119352 -214.919528)
			(xy 232.082594 -214.95628) (xy 232.04054 -214.98683) (xy 231.994223 -215.010424) (xy 231.944786 -215.026481)
			(xy 231.893446 -215.034606) (xy 231.867456 -215.03513) (xy 231.834436 -215.033352) (xy 231.831896 -215.033098)
			(xy 231.829356 -215.033098) (xy 231.819354 -215.033594) (xy 231.800877 -215.041261) (xy 231.786737 -215.055412)
			(xy 231.779085 -215.073896) (xy 231.778556 -215.083898) (xy 231.778556 -215.124792) (xy 231.779042 -215.134804)
			(xy 231.786699 -215.153306) (xy 231.80085 -215.167472) (xy 231.819345 -215.175148) (xy 231.829356 -215.175592)
			(xy 231.831896 -215.175592) (xy 231.834436 -215.175338) (xy 231.867456 -215.17356) (xy 231.893448 -215.17404)
			(xy 231.944794 -215.182165) (xy 231.994237 -215.198223) (xy 232.040558 -215.221818) (xy 232.082618 -215.252369)
			(xy 232.119381 -215.289124) (xy 232.149942 -215.331177) (xy 232.173548 -215.377493) (xy 232.189617 -215.426932)
			(xy 232.197754 -215.478276) (xy 232.198164 -215.504268) (xy 232.197583 -215.532515) (xy 232.187999 -215.588192)
			(xy 232.179114 -215.615012) (xy 232.174796 -215.62695) (xy 232.178098 -215.65108) (xy 232.233216 -215.729058)
			(xy 232.240841 -215.738681) (xy 232.262612 -215.749944) (xy 232.274872 -215.750648)
		)
		(stroke
			(width 0)
			(type solid)
		)
		(fill yes)
		(layer "In15.Cu")
		(net "P1V2_BIC_USB2AV12")
	)
	(gr_poly
		(pts
			(xy 130.549142 -181.608222) (xy 130.558032 -181.606698) (xy 130.565906 -181.604666) (xy 130.596209 -181.594835)
			(xy 130.659023 -181.584232) (xy 130.690874 -181.583584) (xy 130.723733 -181.58427) (xy 130.788485 -181.595505)
			(xy 130.819652 -181.605936) (xy 130.828034 -181.608984) (xy 137.139934 -181.608984) (xy 137.150001 -181.608554)
			(xy 137.168595 -181.600829) (xy 137.176002 -181.593998) (xy 137.221214 -181.548786) (xy 137.228068 -181.541391)
			(xy 137.23581 -181.522792) (xy 137.2362 -181.512718) (xy 137.2362 -174.492412) (xy 137.235779 -174.482341)
			(xy 137.228068 -174.463733) (xy 137.221214 -174.456344) (xy 136.932162 -174.167292) (xy 136.92505 -174.159926)
			(xy 136.906254 -174.152306) (xy 136.137904 -174.152306) (xy 136.129622 -174.152623) (xy 136.113935 -174.157934)
			(xy 136.10717 -174.16272) (xy 136.084835 -174.179247) (xy 136.036333 -174.206346) (xy 135.984412 -174.226123)
			(xy 135.930172 -174.238159) (xy 135.87476 -174.242199) (xy 135.819348 -174.238159) (xy 135.765108 -174.226123)
			(xy 135.713187 -174.206346) (xy 135.664685 -174.179247) (xy 135.64235 -174.16272) (xy 135.635567 -174.157967)
			(xy 135.619891 -174.152655) (xy 135.611616 -174.152306) (xy 132.948934 -174.152306) (xy 132.937913 -174.15284)
			(xy 132.917887 -174.162051) (xy 132.910326 -174.170086) (xy 132.852922 -174.236888) (xy 132.846826 -174.257716)
			(xy 132.848604 -174.268892) (xy 132.850534 -174.282845) (xy 132.852571 -174.310941) (xy 132.852668 -174.325026)
			(xy 132.852182 -174.352277) (xy 132.844426 -174.406225) (xy 132.829071 -174.45852) (xy 132.806429 -174.508097)
			(xy 132.776963 -174.553947) (xy 132.741272 -174.595138) (xy 132.700081 -174.630829) (xy 132.654231 -174.660295)
			(xy 132.604654 -174.682937) (xy 132.552359 -174.698292) (xy 132.498411 -174.706048) (xy 132.443909 -174.706048)
			(xy 132.389961 -174.698292) (xy 132.337666 -174.682937) (xy 132.288089 -174.660295) (xy 132.242239 -174.630829)
			(xy 132.201048 -174.595138) (xy 132.165357 -174.553947) (xy 132.135891 -174.508097) (xy 132.113249 -174.45852)
			(xy 132.097894 -174.406225) (xy 132.090138 -174.352277) (xy 132.089652 -174.325026) (xy 132.089764 -174.310941)
			(xy 132.091797 -174.282846) (xy 132.093716 -174.268892) (xy 132.095494 -174.257716) (xy 132.089398 -174.236888)
			(xy 132.031994 -174.170086) (xy 132.024421 -174.162065) (xy 132.004404 -174.15285) (xy 131.993386 -174.152306)
			(xy 130.521456 -174.152306) (xy 130.510348 -174.152869) (xy 130.490194 -174.162219) (xy 130.482594 -174.17034)
			(xy 130.432556 -174.23003) (xy 130.425809 -174.238896) (xy 130.419999 -174.260378) (xy 130.42138 -174.271432)
			(xy 130.42138 -174.271686) (xy 130.423927 -174.287375) (xy 130.426725 -174.319039) (xy 130.426968 -174.334932)
			(xy 130.426968 -174.338742) (xy 130.426344 -174.365898) (xy 130.418354 -174.419626) (xy 130.402823 -174.471678)
			(xy 130.380067 -174.521) (xy 130.350545 -174.566596) (xy 130.314855 -174.607544) (xy 130.273718 -174.643016)
			(xy 130.227965 -174.672294) (xy 130.178522 -174.694787) (xy 130.126389 -174.71004) (xy 130.072619 -174.717744)
			(xy 130.018301 -174.717744) (xy 129.964531 -174.71004) (xy 129.912398 -174.694787) (xy 129.862955 -174.672294)
			(xy 129.817202 -174.643016) (xy 129.776065 -174.607544) (xy 129.740375 -174.566596) (xy 129.710853 -174.521)
			(xy 129.688097 -174.471678) (xy 129.672566 -174.419626) (xy 129.664576 -174.365898) (xy 129.663952 -174.338742)
			(xy 129.663952 -174.336456) (xy 129.664134 -174.320181) (xy 129.666933 -174.287752) (xy 129.66954 -174.271686)
			(xy 129.66954 -174.271432) (xy 129.670875 -174.260379) (xy 129.665083 -174.238907) (xy 129.658364 -174.23003)
			(xy 129.608326 -174.17034) (xy 129.600733 -174.162213) (xy 129.580574 -174.152876) (xy 129.569464 -174.152306)
			(xy 129.279396 -174.152306) (xy 129.269326 -174.15273) (xy 129.250723 -174.160446) (xy 129.243328 -174.167292)
			(xy 129.088642 -174.321978) (xy 129.081276 -174.32909) (xy 129.073656 -174.347886) (xy 129.073656 -176.7223)
			(xy 130.559711 -176.7223) (xy 130.56388 -176.666676) (xy 130.576293 -176.612294) (xy 130.596673 -176.56037)
			(xy 130.624565 -176.512064) (xy 130.659345 -176.468455) (xy 130.700237 -176.430517) (xy 130.746327 -176.399097)
			(xy 130.796585 -176.374899) (xy 130.849888 -176.358461) (xy 130.905046 -176.350152) (xy 130.932936 -176.34966)
			(xy 130.948762 -176.349821) (xy 130.9803 -176.352494) (xy 130.995928 -176.354994) (xy 131.005082 -176.356156)
			(xy 131.023182 -176.352642) (xy 131.031234 -176.348136) (xy 131.05765 -176.331626) (xy 131.065213 -176.326567)
			(xy 131.076417 -176.312249) (xy 131.079494 -176.303686) (xy 131.087259 -176.280294) (xy 131.109266 -176.236194)
			(xy 131.138083 -176.196212) (xy 131.155186 -176.178464) (xy 131.15544 -176.178464) (xy 131.244594 -176.08931)
			(xy 131.244594 -176.089056) (xy 131.253138 -176.0807) (xy 131.271317 -176.065186) (xy 131.280916 -176.058068)
			(xy 131.287199 -176.053179) (xy 131.296633 -176.040366) (xy 131.299458 -176.032922) (xy 131.308602 -176.005236)
			(xy 131.308602 -175.97374) (xy 131.30075 -175.947382) (xy 131.29233 -175.893034) (xy 131.291838 -175.865536)
			(xy 131.292346 -175.837549) (xy 131.301098 -175.782265) (xy 131.318391 -175.72903) (xy 131.343801 -175.679157)
			(xy 131.376701 -175.633873) (xy 131.416281 -175.594295) (xy 131.461565 -175.561396) (xy 131.511439 -175.535988)
			(xy 131.564674 -175.518695) (xy 131.619959 -175.509945) (xy 131.647946 -175.509428) (xy 131.675266 -175.509975)
			(xy 131.729266 -175.518305) (xy 131.781363 -175.53478) (xy 131.830335 -175.559012) (xy 131.875035 -175.590434)
			(xy 131.895088 -175.608996) (xy 131.9022 -175.616108) (xy 131.920234 -175.62322) (xy 132.010658 -175.62322)
			(xy 132.028692 -175.616108) (xy 132.035804 -175.608996) (xy 132.055822 -175.590389) (xy 132.100514 -175.558932)
			(xy 132.149491 -175.534682) (xy 132.201602 -175.518209) (xy 132.255619 -175.509901) (xy 132.282946 -175.509428)
			(xy 132.310932 -175.509899) (xy 132.366214 -175.518662) (xy 132.419445 -175.535965) (xy 132.469314 -175.561382)
			(xy 132.514593 -175.594287) (xy 132.554167 -175.63387) (xy 132.587061 -175.679156) (xy 132.612467 -175.729031)
			(xy 132.629757 -175.782266) (xy 132.638508 -175.83755) (xy 132.639054 -175.865536) (xy 132.638038 -175.890682)
			(xy 132.63753 -175.90135) (xy 132.644388 -175.921162) (xy 132.7023 -175.983392) (xy 132.709779 -175.990711)
			(xy 132.728933 -175.999091) (xy 132.739384 -175.999648) (xy 132.763768 -175.999648) (xy 132.774043 -175.999142)
			(xy 132.792921 -175.991021) (xy 132.800344 -175.9839) (xy 132.85851 -175.923702) (xy 132.865876 -175.904398)
			(xy 132.865368 -175.893984) (xy 132.865114 -175.880522) (xy 132.865633 -175.852536) (xy 132.874386 -175.797253)
			(xy 132.89168 -175.74402) (xy 132.91709 -175.694149) (xy 132.949988 -175.648866) (xy 132.989566 -175.609288)
			(xy 133.034849 -175.57639) (xy 133.08472 -175.55098) (xy 133.137953 -175.533686) (xy 133.193236 -175.524933)
			(xy 133.221222 -175.524414) (xy 133.248543 -175.524918) (xy 133.302546 -175.533259) (xy 133.354643 -175.549744)
			(xy 133.403614 -175.573986) (xy 133.448312 -175.605417) (xy 133.468364 -175.623982) (xy 133.475476 -175.631094)
			(xy 133.49351 -175.638206) (xy 133.583934 -175.638206) (xy 133.601968 -175.631094) (xy 133.60908 -175.623982)
			(xy 133.629106 -175.605384) (xy 133.673796 -175.573926) (xy 133.722772 -175.549674) (xy 133.77488 -175.533199)
			(xy 133.828896 -175.524889) (xy 133.856222 -175.524414) (xy 133.884207 -175.524921) (xy 133.939487 -175.53368)
			(xy 133.992716 -175.550979) (xy 134.042584 -175.576391) (xy 134.087862 -175.609292) (xy 134.127436 -175.648871)
			(xy 134.160332 -175.694154) (xy 134.185738 -175.744025) (xy 134.203031 -175.797256) (xy 134.211783 -175.852537)
			(xy 134.21233 -175.880522) (xy 134.211903 -175.907112) (xy 134.204015 -175.959704) (xy 134.188374 -176.010531)
			(xy 134.177278 -176.0347) (xy 134.170166 -176.049178) (xy 134.175754 -176.080928) (xy 134.2771 -176.182274)
			(xy 134.278878 -176.184306) (xy 134.286643 -176.191448) (xy 134.306236 -176.199221) (xy 134.327304 -176.198525)
			(xy 134.337044 -176.194466) (xy 134.361226 -176.18341) (xy 134.412055 -176.167805) (xy 134.464637 -176.159909)
			(xy 134.491222 -176.159414) (xy 134.519207 -176.159921) (xy 134.574487 -176.16868) (xy 134.627716 -176.185979)
			(xy 134.677584 -176.211391) (xy 134.722862 -176.244292) (xy 134.762436 -176.283871) (xy 134.795332 -176.329154)
			(xy 134.820738 -176.379025) (xy 134.838031 -176.432256) (xy 134.846783 -176.487537) (xy 134.84733 -176.515522)
			(xy 134.846814 -176.542843) (xy 134.838474 -176.596844) (xy 134.821991 -176.64894) (xy 134.797752 -176.697912)
			(xy 134.766325 -176.742611) (xy 134.747762 -176.762664) (xy 134.74065 -176.769776) (xy 134.733538 -176.78781)
			(xy 134.733538 -176.878234) (xy 134.74065 -176.896268) (xy 134.747762 -176.90338) (xy 134.766351 -176.923415)
			(xy 134.797812 -176.968101) (xy 134.822066 -177.017074) (xy 134.838543 -177.069182) (xy 134.846855 -177.123196)
			(xy 134.84733 -177.150522) (xy 134.846814 -177.177843) (xy 134.838474 -177.231844) (xy 134.821991 -177.28394)
			(xy 134.797752 -177.332912) (xy 134.766325 -177.377611) (xy 134.747762 -177.397664) (xy 134.74065 -177.404776)
			(xy 134.733538 -177.42281) (xy 134.733538 -177.513234) (xy 134.74065 -177.531268) (xy 134.747762 -177.53838)
			(xy 134.766351 -177.558415) (xy 134.797812 -177.603101) (xy 134.822066 -177.652074) (xy 134.838543 -177.704182)
			(xy 134.846855 -177.758196) (xy 134.84733 -177.785522) (xy 134.846919 -177.810307) (xy 134.840047 -177.859399)
			(xy 134.826427 -177.907061) (xy 134.806321 -177.95237) (xy 134.780119 -177.99445) (xy 134.74833 -178.032484)
			(xy 134.730236 -178.049428) (xy 134.722108 -178.056794) (xy 134.713472 -178.076352) (xy 134.713726 -178.173888)
			(xy 134.722616 -178.193192) (xy 134.730744 -178.200558) (xy 134.749035 -178.217556) (xy 134.781227 -178.255724)
			(xy 134.807774 -178.298014) (xy 134.828153 -178.343598) (xy 134.841966 -178.391581) (xy 134.843218 -178.400456)
			(xy 135.78408 -178.400456) (xy 135.788151 -178.344834) (xy 135.800277 -178.290397) (xy 135.8202 -178.238306)
			(xy 135.847496 -178.189671) (xy 135.881582 -178.145528) (xy 135.921731 -178.106819) (xy 135.967089 -178.074368)
			(xy 136.016689 -178.048867) (xy 136.069473 -178.03086) (xy 136.124316 -178.02073) (xy 136.18005 -178.018693)
			(xy 136.235487 -178.024793) (xy 136.289444 -178.038899) (xy 136.340773 -178.060711) (xy 136.388379 -178.089765)
			(xy 136.431247 -178.12544) (xy 136.468464 -178.166977) (xy 136.499237 -178.21349) (xy 136.522909 -178.263987)
			(xy 136.538977 -178.317394) (xy 136.547097 -178.37257) (xy 136.547606 -178.400456) (xy 136.547097 -178.428342)
			(xy 136.538977 -178.483518) (xy 136.522909 -178.536925) (xy 136.499237 -178.587422) (xy 136.468464 -178.633935)
			(xy 136.431247 -178.675472) (xy 136.388379 -178.711147) (xy 136.340773 -178.740201) (xy 136.289444 -178.762013)
			(xy 136.235487 -178.776119) (xy 136.18005 -178.782219) (xy 136.124316 -178.780182) (xy 136.069473 -178.770052)
			(xy 136.016689 -178.752045) (xy 135.967089 -178.726544) (xy 135.921731 -178.694093) (xy 135.881582 -178.655384)
			(xy 135.847496 -178.611241) (xy 135.8202 -178.562606) (xy 135.800277 -178.510515) (xy 135.788151 -178.456078)
			(xy 135.78408 -178.400456) (xy 134.843218 -178.400456) (xy 134.848941 -178.441022) (xy 134.849362 -178.465988)
			(xy 134.848876 -178.493975) (xy 134.840121 -178.549261) (xy 134.822824 -178.602496) (xy 134.797411 -178.652369)
			(xy 134.764509 -178.697653) (xy 134.724927 -178.737231) (xy 134.67964 -178.770129) (xy 134.629764 -178.795537)
			(xy 134.576528 -178.812829) (xy 134.521241 -178.821579) (xy 134.493254 -178.822096) (xy 134.476577 -178.821882)
			(xy 134.443374 -178.818702) (xy 134.42696 -178.815746) (xy 134.422134 -178.814984) (xy 134.417308 -178.814984)
			(xy 134.407303 -178.815494) (xy 134.388814 -178.823148) (xy 134.374662 -178.837294) (xy 134.366999 -178.855779)
			(xy 134.366508 -178.865784) (xy 134.366508 -178.910742) (xy 134.366088 -178.93474) (xy 134.358615 -178.982149)
			(xy 134.343797 -179.0278) (xy 134.322002 -179.07056) (xy 134.293768 -179.109372) (xy 134.2771 -179.126642)
			(xy 134.276846 -179.126642) (xy 134.20344 -179.200048) (xy 134.20344 -179.200302) (xy 134.191942 -179.211458)
			(xy 134.166997 -179.231563) (xy 134.153656 -179.240434) (xy 134.144477 -179.247112) (xy 134.13261 -179.266428)
			(xy 134.130175 -179.288968) (xy 134.133336 -179.29987) (xy 134.143036 -179.329609) (xy 134.153503 -179.391278)
			(xy 134.154164 -179.422552) (xy 134.153621 -179.449167) (xy 134.146053 -179.501855) (xy 134.131063 -179.552929)
			(xy 134.108957 -179.601351) (xy 134.080185 -179.646134) (xy 134.045333 -179.686366) (xy 134.005109 -179.721229)
			(xy 133.960334 -179.750012) (xy 133.911918 -179.77213) (xy 133.860847 -179.787133) (xy 133.80816 -179.794715)
			(xy 133.781546 -179.79517) (xy 133.75559 -179.794733) (xy 133.704182 -179.787521) (xy 133.654273 -179.773244)
			(xy 133.606827 -179.752179) (xy 133.562765 -179.724733) (xy 133.522937 -179.691437) (xy 133.505194 -179.672488)
			(xy 133.497673 -179.664832) (xy 133.478072 -179.656144) (xy 133.467348 -179.655724) (xy 133.392164 -179.655724)
			(xy 133.381474 -179.656304) (xy 133.361919 -179.66495) (xy 133.354318 -179.672488) (xy 133.334932 -179.693136)
			(xy 133.291024 -179.728908) (xy 133.242208 -179.757622) (xy 133.189609 -179.778618) (xy 133.134438 -179.791413)
			(xy 133.077966 -179.79571) (xy 133.021494 -179.791413) (xy 132.966323 -179.778618) (xy 132.913724 -179.757622)
			(xy 132.864908 -179.728908) (xy 132.821 -179.693136) (xy 132.801614 -179.672488) (xy 132.794085 -179.664841)
			(xy 132.77449 -179.656148) (xy 132.763768 -179.655724) (xy 132.688584 -179.655724) (xy 132.677895 -179.656315)
			(xy 132.65834 -179.664954) (xy 132.650738 -179.672488) (xy 132.631352 -179.693136) (xy 132.587444 -179.728908)
			(xy 132.538628 -179.757622) (xy 132.486029 -179.778618) (xy 132.430858 -179.791413) (xy 132.374386 -179.79571)
			(xy 132.317914 -179.791413) (xy 132.262743 -179.778618) (xy 132.210144 -179.757622) (xy 132.161328 -179.728908)
			(xy 132.11742 -179.693136) (xy 132.098034 -179.672488) (xy 132.090498 -179.66485) (xy 132.070908 -179.656151)
			(xy 132.060188 -179.655724) (xy 131.985004 -179.655724) (xy 131.97431 -179.656272) (xy 131.954755 -179.664941)
			(xy 131.947158 -179.672488) (xy 131.929408 -179.69143) (xy 131.889584 -179.724728) (xy 131.845523 -179.752175)
			(xy 131.798078 -179.773239) (xy 131.748169 -179.787513) (xy 131.696761 -179.794721) (xy 131.670806 -179.79517)
			(xy 131.644186 -179.79476) (xy 131.591488 -179.787183) (xy 131.540405 -179.772184) (xy 131.491977 -179.750066)
			(xy 131.44719 -179.721281) (xy 131.406956 -179.686414) (xy 131.372094 -179.646176) (xy 131.343314 -179.601386)
			(xy 131.321202 -179.552955) (xy 131.306208 -179.501871) (xy 131.298637 -179.449172) (xy 131.298188 -179.422552)
			(xy 131.298618 -179.397218) (xy 131.305489 -179.347018) (xy 131.319097 -179.298212) (xy 131.339191 -179.251699)
			(xy 131.365401 -179.208337) (xy 131.380992 -179.188364) (xy 131.386554 -179.180873) (xy 131.392261 -179.163121)
			(xy 131.39127 -179.1445) (xy 131.383713 -179.127453) (xy 131.377436 -179.120546) (xy 131.15544 -178.89855)
			(xy 131.155186 -178.89855) (xy 131.13851 -178.88128) (xy 131.110262 -178.842464) (xy 131.088434 -178.799707)
			(xy 131.073562 -178.754062) (xy 131.066014 -178.706653) (xy 131.065524 -178.68265) (xy 131.065524 -178.61661)
			(xy 131.065076 -178.606268) (xy 131.056937 -178.587256) (xy 131.049776 -178.57978) (xy 130.988308 -178.521614)
			(xy 130.969258 -178.514502) (xy 130.95859 -178.515264) (xy 130.938016 -178.515772) (xy 130.910125 -178.51537)
			(xy 130.854966 -178.507058) (xy 130.801662 -178.490618) (xy 130.751403 -178.466417) (xy 130.705313 -178.434995)
			(xy 130.664421 -178.397055) (xy 130.629641 -178.353443) (xy 130.601749 -178.305135) (xy 130.581369 -178.253209)
			(xy 130.568956 -178.198826) (xy 130.564787 -178.1432) (xy 130.568956 -178.087574) (xy 130.581369 -178.033191)
			(xy 130.601749 -177.981265) (xy 130.629641 -177.932957) (xy 130.664421 -177.889345) (xy 130.705313 -177.851405)
			(xy 130.751403 -177.819983) (xy 130.801662 -177.795782) (xy 130.854966 -177.779342) (xy 130.910125 -177.77103)
			(xy 130.938016 -177.770536) (xy 130.95859 -177.771044) (xy 130.969258 -177.771806) (xy 130.988308 -177.764694)
			(xy 131.049776 -177.706528) (xy 131.056887 -177.699016) (xy 131.065029 -177.680028) (xy 131.065524 -177.669698)
			(xy 131.065524 -177.19548) (xy 131.065059 -177.185048) (xy 131.05679 -177.165895) (xy 131.049522 -177.158396)
			(xy 130.9878 -177.100484) (xy 130.967988 -177.093372) (xy 130.95732 -177.094134) (xy 130.932936 -177.094896)
			(xy 130.905046 -177.094448) (xy 130.849888 -177.086139) (xy 130.796585 -177.069701) (xy 130.746327 -177.045503)
			(xy 130.700237 -177.014083) (xy 130.659345 -176.976145) (xy 130.624565 -176.932536) (xy 130.596673 -176.88423)
			(xy 130.576293 -176.832306) (xy 130.56388 -176.777924) (xy 130.559711 -176.7223) (xy 129.073656 -176.7223)
			(xy 129.073656 -181.004718) (xy 135.60628 -181.004718) (xy 135.610351 -180.949096) (xy 135.622477 -180.894659)
			(xy 135.6424 -180.842568) (xy 135.669696 -180.793933) (xy 135.703782 -180.74979) (xy 135.743931 -180.711081)
			(xy 135.789289 -180.67863) (xy 135.838889 -180.653129) (xy 135.891673 -180.635122) (xy 135.946516 -180.624992)
			(xy 136.00225 -180.622955) (xy 136.057687 -180.629055) (xy 136.111644 -180.643161) (xy 136.162973 -180.664973)
			(xy 136.210579 -180.694027) (xy 136.253447 -180.729702) (xy 136.290664 -180.771239) (xy 136.321437 -180.817752)
			(xy 136.345109 -180.868249) (xy 136.361177 -180.921656) (xy 136.369297 -180.976832) (xy 136.369806 -181.004718)
			(xy 136.369297 -181.032604) (xy 136.361177 -181.08778) (xy 136.345109 -181.141187) (xy 136.321437 -181.191684)
			(xy 136.290664 -181.238197) (xy 136.253447 -181.279734) (xy 136.210579 -181.315409) (xy 136.162973 -181.344463)
			(xy 136.111644 -181.366275) (xy 136.057687 -181.380381) (xy 136.00225 -181.386481) (xy 135.946516 -181.384444)
			(xy 135.891673 -181.374314) (xy 135.838889 -181.356307) (xy 135.789289 -181.330806) (xy 135.743931 -181.298355)
			(xy 135.703782 -181.259646) (xy 135.669696 -181.215503) (xy 135.6424 -181.166868) (xy 135.622477 -181.114777)
			(xy 135.610351 -181.06034) (xy 135.60628 -181.004718) (xy 129.073656 -181.004718) (xy 129.073656 -181.352698)
			(xy 129.07408 -181.362767) (xy 129.0818 -181.381367) (xy 129.088642 -181.388766) (xy 129.293874 -181.593998)
			(xy 129.301277 -181.600833) (xy 129.319875 -181.608541) (xy 129.329942 -181.608984) (xy 130.540252 -181.608984)
		)
		(stroke
			(width 0)
			(type solid)
		)
		(fill yes)
		(layer "In15.Cu")
		(net "P3V3_DB2000QL_VDD")
	)
	(gr_poly
		(pts
			(arc
				(start 200.481692 -418.081968)
				(mid 201.086106 -417.953924)
				(end 201.586846 -417.592002)
			)
			(arc
				(start 201.586846 -417.592002)
				(mid 202.42889 -416.98332)
				(end 203.445364 -416.768026)
			)
			(arc
				(start 271.794732 -416.768026)
				(mid 272.811071 -416.983322)
				(end 273.652996 -417.592002)
			)
			(arc
				(start 273.652996 -417.592002)
				(mid 274.153727 -417.953921)
				(end 274.75815 -418.081968)
			)
			(arc
				(start 465.600034 -418.081968)
				(mid 466.655034 -417.644972)
				(end 467.09203 -416.589972)
			)
			(arc
				(start 467.09203 -246.488204)
				(mid 466.978493 -245.917325)
				(end 466.65515 -245.433342)
			)
			(arc
				(start 464.026504 -242.80495)
				(mid 463.482885 -241.991412)
				(end 463.291936 -241.031776)
			)
			(arc
				(start 463.291936 -87.588344)
				(mid 463.482826 -86.628673)
				(end 464.026504 -85.81517)
			)
			(arc
				(start 466.65515 -83.186524)
				(mid 466.978483 -82.702667)
				(end 467.09203 -82.131916)
			)
			(arc
				(start 467.09203 -1.999996)
				(mid 466.655034 -0.944996)
				(end 465.600034 -0.508)
			)
			(arc
				(start 446.265046 -0.508)
				(mid 445.210046 -0.944996)
				(end 444.77305 -1.999996)
			)
			(arc
				(start 444.77305 -11.850116)
				(mid 444.676277 -12.381671)
				(end 444.3984 -12.845034)
			)
			(xy 444.3984 -12.869164) (xy 444.399924 -12.870688)
			(arc
				(start 445.002666 -12.870688)
				(mid 445.20965 -12.378943)
				(end 445.280288 -11.850116)
			)
			(arc
				(start 445.280288 -1.999996)
				(mid 445.568553 -1.303936)
				(end 446.264538 -1.015492)
			)
			(arc
				(start 465.600034 -1.015492)
				(mid 466.296273 -1.303831)
				(end 466.584792 -1.999996)
			)
			(arc
				(start 466.584792 -82.131916)
				(mid 466.509885 -82.508586)
				(end 466.296502 -82.827876)
			)
			(arc
				(start 463.667856 -85.456522)
				(mid 463.014235 -86.434595)
				(end 462.784698 -87.588344)
			)
			(xy 462.784444 -87.588344) (xy 462.784444 -241.031776)
			(arc
				(start 462.784698 -241.031776)
				(mid 463.014268 -242.185519)
				(end 463.667856 -243.163598)
			)
			(arc
				(start 466.296502 -245.79199)
				(mid 466.509882 -246.11143)
				(end 466.584792 -246.488204)
			)
			(arc
				(start 466.584792 -416.589972)
				(mid 466.296527 -417.286032)
				(end 465.600542 -417.574476)
			)
			(xy 414.915604 -417.574476) (xy 414.915604 -417.797742) (xy 400.95424 -417.797742) (xy 400.95424 -417.574476)
			(xy 326.621648 -417.574476) (xy 326.621648 -417.747958) (xy 313.065922 -417.747958) (xy 313.065922 -417.574476)
			(arc
				(start 274.757896 -417.574476)
				(mid 274.359217 -417.490052)
				(end 274.028916 -417.251388)
			)
			(arc
				(start 274.028916 -417.251388)
				(mid 273.01669 -416.519565)
				(end 271.794732 -416.260788)
			)
			(arc
				(start 203.445364 -416.260788)
				(mid 202.223266 -416.519531)
				(end 201.210926 -417.251388)
			)
			(arc
				(start 201.210926 -417.251388)
				(mid 200.880626 -417.490098)
				(end 200.481946 -417.574476)
			)
			(xy 154.673554 -417.574476) (xy 154.673554 -417.693856) (xy 141.027912 -417.693856) (xy 141.027912 -417.574476)
			(xy 66.745104 -417.574476) (xy 66.745104 -417.671758) (xy 53.039772 -417.671758) (xy 53.039772 -417.574476)
			(arc
				(start 1.999996 -417.574476)
				(mid 1.303847 -417.286121)
				(end 1.015492 -416.589972)
			)
			(arc
				(start 1.015492 -246.48795)
				(mid 1.090466 -246.111319)
				(end 1.303782 -245.79199)
			)
			(arc
				(start 3.93192 -243.163852)
				(mid 4.58575 -242.18556)
				(end 4.815332 -241.031522)
			)
			(arc
				(start 4.815332 -87.588344)
				(mid 4.585694 -86.434435)
				(end 3.93192 -85.456268)
			)
			(arc
				(start 1.303528 -82.827876)
				(mid 1.090411 -82.508641)
				(end 1.015492 -82.13217)
			)
			(arc
				(start 1.015492 -1.999996)
				(mid 1.303847 -1.303847)
				(end 1.999996 -1.015492)
			)
			(arc
				(start 5.964936 -1.015492)
				(mid 6.661085 -1.303847)
				(end 6.94944 -1.999996)
			)
			(arc
				(start 6.94944 -11.850116)
				(mid 7.539853 -13.275118)
				(end 8.96493 -13.865352)
			)
			(xy 16.2814 -13.865352) (xy 16.371316 -13.775436) (xy 16.371316 -13.44803) (xy 16.2814 -13.358114)
			(arc
				(start 8.96493 -13.358114)
				(mid 7.898614 -12.916432)
				(end 7.456932 -11.850116)
			)
			(arc
				(start 7.456932 -1.999996)
				(mid 7.019936 -0.944996)
				(end 5.964936 -0.508)
			)
			(arc
				(start 1.999996 -0.508)
				(mid 0.944996 -0.944996)
				(end 0.508 -1.999996)
			)
			(arc
				(start 0.508 -82.131916)
				(mid 0.621601 -82.702644)
				(end 0.94488 -83.186524)
			)
			(arc
				(start 3.573272 -85.81517)
				(mid 4.117081 -86.628665)
				(end 4.308094 -87.588344)
			)
			(arc
				(start 4.308094 -241.031522)
				(mid 4.117082 -241.991334)
				(end 3.573272 -242.80495)
			)
			(arc
				(start 0.94488 -245.433342)
				(mid 0.621552 -245.917331)
				(end 0.508 -246.488204)
			)
			(arc
				(start 0.508 -416.589972)
				(mid 0.944996 -417.644972)
				(end 1.999996 -418.081968)
			)
		)
		(stroke
			(width 0)
			(type solid)
		)
		(fill yes)
		(layer "In15.Cu")
		(net "GND")
	)
	(gr_poly
		(pts
			(xy 182.927498 -205.664054) (xy 182.937567 -205.66363) (xy 182.956168 -205.655911) (xy 182.963566 -205.649068)
			(xy 184.879742 -203.732892) (xy 184.886594 -203.725496) (xy 184.894334 -203.706897) (xy 184.894728 -203.696824)
			(xy 184.894728 -201.883772) (xy 184.894236 -201.873766) (xy 184.886572 -201.855279) (xy 184.872421 -201.841128)
			(xy 184.853934 -201.833464) (xy 184.843928 -201.832972) (xy 181.35346 -201.832972) (xy 181.341522 -201.83602)
			(xy 181.335934 -201.838814) (xy 181.308405 -201.852647) (xy 181.249992 -201.872218) (xy 181.189191 -201.882141)
			(xy 181.158388 -201.882756) (xy 181.131136 -201.882269) (xy 181.077187 -201.874512) (xy 181.024891 -201.859156)
			(xy 180.975312 -201.836515) (xy 180.92946 -201.807049) (xy 180.888267 -201.771358) (xy 180.852572 -201.730169)
			(xy 180.823102 -201.684319) (xy 180.800456 -201.634743) (xy 180.785096 -201.582448) (xy 180.777333 -201.5285)
			(xy 180.77688 -201.501248) (xy 180.777355 -201.473879) (xy 180.785185 -201.419704) (xy 180.800677 -201.367204)
			(xy 180.823513 -201.317457) (xy 180.853224 -201.271485) (xy 180.87086 -201.25055) (xy 180.876956 -201.243438)
			(xy 180.883306 -201.22642) (xy 180.883306 -201.141076) (xy 180.876956 -201.124058) (xy 180.87086 -201.116946)
			(xy 180.853219 -201.096015) (xy 180.823494 -201.050048) (xy 180.800655 -201.000301) (xy 180.785169 -200.947797)
			(xy 180.777357 -200.893618) (xy 180.77688 -200.866248) (xy 180.77734 -200.838993) (xy 180.785091 -200.785036)
			(xy 180.800443 -200.732731) (xy 180.823082 -200.683144) (xy 180.852549 -200.637284) (xy 180.888242 -200.596085)
			(xy 180.929436 -200.560385) (xy 180.975292 -200.530911) (xy 181.024875 -200.508264) (xy 181.077177 -200.492904)
			(xy 181.131133 -200.485144) (xy 181.158388 -200.48474) (xy 181.18919 -200.485351) (xy 181.249989 -200.495286)
			(xy 181.308404 -200.514853) (xy 181.335934 -200.528682) (xy 181.341522 -200.531476) (xy 181.35346 -200.534524)
			(xy 184.843928 -200.534524) (xy 184.853934 -200.534032) (xy 184.87242 -200.526368) (xy 184.88657 -200.512217)
			(xy 184.894232 -200.49373) (xy 184.894728 -200.483724) (xy 184.894728 -187.85586) (xy 184.88914 -187.850272)
			(xy 184.88914 -185.75655) (xy 184.888706 -185.746485) (xy 184.880972 -185.7279) (xy 184.874154 -185.720482)
			(xy 184.64911 -185.495438) (xy 184.641714 -185.488586) (xy 184.623116 -185.480842) (xy 184.613042 -185.480452)
			(xy 183.780176 -185.480452) (xy 183.770109 -185.480881) (xy 183.751516 -185.488607) (xy 183.744108 -185.495438)
			(xy 181.538372 -187.701174) (xy 182.793894 -187.701174) (xy 182.79438 -187.673923) (xy 182.802136 -187.619975)
			(xy 182.817491 -187.56768) (xy 182.840133 -187.518103) (xy 182.869599 -187.472253) (xy 182.90529 -187.431062)
			(xy 182.946481 -187.395371) (xy 182.992331 -187.365905) (xy 183.041908 -187.343263) (xy 183.094203 -187.327908)
			(xy 183.148151 -187.320152) (xy 183.202653 -187.320152) (xy 183.256601 -187.327908) (xy 183.308896 -187.343263)
			(xy 183.358473 -187.365905) (xy 183.404323 -187.395371) (xy 183.445514 -187.431062) (xy 183.481205 -187.472253)
			(xy 183.510671 -187.518103) (xy 183.533313 -187.56768) (xy 183.548668 -187.619975) (xy 183.556424 -187.673923)
			(xy 183.55691 -187.701174) (xy 183.556487 -187.727308) (xy 183.549362 -187.779087) (xy 183.535227 -187.829406)
			(xy 183.514349 -187.877322) (xy 183.487118 -187.921936) (xy 183.454047 -187.962409) (xy 183.415754 -187.997984)
			(xy 183.394604 -188.01334) (xy 183.383213 -188.021858) (xy 183.36532 -188.043955) (xy 183.354218 -188.070132)
			(xy 183.350769 -188.098355) (xy 183.355241 -188.126435) (xy 183.367288 -188.15219) (xy 183.385973 -188.173622)
			(xy 183.397652 -188.181742) (xy 183.420083 -188.196909) (xy 183.460817 -188.232582) (xy 183.496096 -188.273657)
			(xy 183.525211 -188.319309) (xy 183.547576 -188.368621) (xy 183.562742 -188.4206) (xy 183.570404 -188.474201)
			(xy 183.57088 -188.501274) (xy 183.570394 -188.528525) (xy 183.562638 -188.582473) (xy 183.547283 -188.634768)
			(xy 183.524641 -188.684345) (xy 183.495175 -188.730195) (xy 183.459484 -188.771386) (xy 183.418293 -188.807077)
			(xy 183.372443 -188.836543) (xy 183.322866 -188.859185) (xy 183.270571 -188.87454) (xy 183.216623 -188.882296)
			(xy 183.162121 -188.882296) (xy 183.108173 -188.87454) (xy 183.055878 -188.859185) (xy 183.006301 -188.836543)
			(xy 182.960451 -188.807077) (xy 182.91926 -188.771386) (xy 182.883569 -188.730195) (xy 182.854103 -188.684345)
			(xy 182.831461 -188.634768) (xy 182.816106 -188.582473) (xy 182.80835 -188.528525) (xy 182.807864 -188.501274)
			(xy 182.808259 -188.47514) (xy 182.815391 -188.42336) (xy 182.829531 -188.37304) (xy 182.850414 -188.325124)
			(xy 182.877649 -188.280511) (xy 182.910724 -188.240038) (xy 182.949019 -188.204464) (xy 182.97017 -188.189108)
			(xy 182.981516 -188.180533) (xy 182.999413 -188.15845) (xy 183.010521 -188.132286) (xy 183.013977 -188.104072)
			(xy 183.009512 -188.076001) (xy 182.997474 -188.050251) (xy 182.978797 -188.028824) (xy 182.967122 -188.020706)
			(xy 182.944708 -188.005516) (xy 182.903974 -187.969846) (xy 182.868695 -187.928775) (xy 182.839579 -187.883126)
			(xy 182.817211 -187.833819) (xy 182.80204 -187.781844) (xy 182.794373 -187.728246) (xy 182.793894 -187.701174)
			(xy 181.538372 -187.701174) (xy 178.412902 -190.826644) (xy 178.406069 -190.834006) (xy 178.398315 -190.85252)
			(xy 178.398257 -190.872591) (xy 178.401726 -190.882016) (xy 178.443636 -190.983108) (xy 178.468782 -191.000126)
			(xy 178.48453 -191.000126) (xy 178.511732 -191.000682) (xy 178.565567 -191.008558) (xy 178.617736 -191.024002)
			(xy 178.667181 -191.046702) (xy 178.7129 -191.076197) (xy 178.753965 -191.111889) (xy 178.789541 -191.153052)
			(xy 178.818909 -191.198853) (xy 178.841471 -191.248362) (xy 178.856769 -191.300574) (xy 178.864495 -191.35443)
			(xy 178.865022 -191.381634) (xy 178.864534 -191.408884) (xy 178.856774 -191.462829) (xy 178.841416 -191.51512)
			(xy 178.818773 -191.564694) (xy 178.789306 -191.610541) (xy 178.753614 -191.651729) (xy 178.712425 -191.687418)
			(xy 178.666577 -191.716882) (xy 178.617002 -191.739523) (xy 178.564709 -191.754878) (xy 178.510764 -191.762635)
			(xy 178.483514 -191.763142) (xy 178.456307 -191.76266) (xy 178.402446 -191.754932) (xy 178.350228 -191.73963)
			(xy 178.300715 -191.717064) (xy 178.254909 -191.687693) (xy 178.213741 -191.652112) (xy 178.178046 -191.611043)
			(xy 178.148547 -191.56532) (xy 178.125843 -191.51587) (xy 178.110396 -191.463695) (xy 178.102517 -191.409855)
			(xy 178.102006 -191.38265) (xy 178.102006 -191.366902) (xy 178.084988 -191.341756) (xy 177.983896 -191.299846)
			(xy 177.974447 -191.296498) (xy 177.954423 -191.296564) (xy 177.935946 -191.304282) (xy 177.928524 -191.311022)
			(xy 176.044352 -193.195194) (xy 178.547266 -193.195194) (xy 178.551337 -193.139572) (xy 178.563463 -193.085135)
			(xy 178.583386 -193.033044) (xy 178.610682 -192.984409) (xy 178.644768 -192.940266) (xy 178.684917 -192.901557)
			(xy 178.730275 -192.869106) (xy 178.779875 -192.843605) (xy 178.832659 -192.825598) (xy 178.887502 -192.815468)
			(xy 178.943236 -192.813431) (xy 178.998673 -192.819531) (xy 179.05263 -192.833637) (xy 179.103959 -192.855449)
			(xy 179.151565 -192.884503) (xy 179.194433 -192.920178) (xy 179.23165 -192.961715) (xy 179.262423 -193.008228)
			(xy 179.286095 -193.058725) (xy 179.302163 -193.112132) (xy 179.310283 -193.167308) (xy 179.310792 -193.195194)
			(xy 179.310283 -193.22308) (xy 179.302163 -193.278256) (xy 179.286095 -193.331663) (xy 179.262423 -193.38216)
			(xy 179.23165 -193.428673) (xy 179.194433 -193.47021) (xy 179.151565 -193.505885) (xy 179.103959 -193.534939)
			(xy 179.05263 -193.556751) (xy 178.998673 -193.570857) (xy 178.943236 -193.576957) (xy 178.887502 -193.57492)
			(xy 178.832659 -193.56479) (xy 178.779875 -193.546783) (xy 178.730275 -193.521282) (xy 178.684917 -193.488831)
			(xy 178.644768 -193.450122) (xy 178.610682 -193.405979) (xy 178.583386 -193.357344) (xy 178.563463 -193.305253)
			(xy 178.551337 -193.250816) (xy 178.547266 -193.195194) (xy 176.044352 -193.195194) (xy 175.222916 -194.01663)
			(xy 175.215516 -194.023471) (xy 175.196917 -194.031186) (xy 175.186848 -194.031616) (xy 171.00677 -194.031616)
			(xy 170.992038 -194.032124) (xy 157.022038 -194.032124) (xy 157.012076 -194.03261) (xy 156.993653 -194.040199)
			(xy 156.986224 -194.046856) (xy 156.821124 -194.211956) (xy 175.476406 -194.211956) (xy 175.480477 -194.156334)
			(xy 175.492603 -194.101897) (xy 175.512526 -194.049806) (xy 175.539822 -194.001171) (xy 175.573908 -193.957028)
			(xy 175.614057 -193.918319) (xy 175.659415 -193.885868) (xy 175.709015 -193.860367) (xy 175.761799 -193.84236)
			(xy 175.816642 -193.83223) (xy 175.872376 -193.830193) (xy 175.927813 -193.836293) (xy 175.98177 -193.850399)
			(xy 176.033099 -193.872211) (xy 176.080705 -193.901265) (xy 176.123573 -193.93694) (xy 176.16079 -193.978477)
			(xy 176.191563 -194.02499) (xy 176.215235 -194.075487) (xy 176.231303 -194.128894) (xy 176.239423 -194.18407)
			(xy 176.239932 -194.211956) (xy 176.239423 -194.239842) (xy 176.231303 -194.295018) (xy 176.215235 -194.348425)
			(xy 176.191563 -194.398922) (xy 176.16079 -194.445435) (xy 176.123573 -194.486972) (xy 176.080705 -194.522647)
			(xy 176.033099 -194.551701) (xy 175.98177 -194.573513) (xy 175.927813 -194.587619) (xy 175.872376 -194.593719)
			(xy 175.816642 -194.591682) (xy 175.761799 -194.581552) (xy 175.709015 -194.563545) (xy 175.659415 -194.538044)
			(xy 175.614057 -194.505593) (xy 175.573908 -194.466884) (xy 175.539822 -194.422741) (xy 175.512526 -194.374106)
			(xy 175.492603 -194.322015) (xy 175.480477 -194.267578) (xy 175.476406 -194.211956) (xy 156.821124 -194.211956)
			(xy 156.349446 -194.683634) (xy 178.101496 -194.683634) (xy 178.105567 -194.628012) (xy 178.117693 -194.573575)
			(xy 178.137616 -194.521484) (xy 178.164912 -194.472849) (xy 178.198998 -194.428706) (xy 178.239147 -194.389997)
			(xy 178.284505 -194.357546) (xy 178.334105 -194.332045) (xy 178.386889 -194.314038) (xy 178.441732 -194.303908)
			(xy 178.497466 -194.301871) (xy 178.552903 -194.307971) (xy 178.60686 -194.322077) (xy 178.658189 -194.343889)
			(xy 178.705795 -194.372943) (xy 178.748663 -194.408618) (xy 178.78588 -194.450155) (xy 178.816653 -194.496668)
			(xy 178.840325 -194.547165) (xy 178.856393 -194.600572) (xy 178.864513 -194.655748) (xy 178.865022 -194.683634)
			(xy 178.864513 -194.71152) (xy 178.856393 -194.766696) (xy 178.840325 -194.820103) (xy 178.816653 -194.8706)
			(xy 178.78588 -194.917113) (xy 178.748663 -194.95865) (xy 178.705795 -194.994325) (xy 178.658189 -195.023379)
			(xy 178.60686 -195.045191) (xy 178.552903 -195.059297) (xy 178.497466 -195.065397) (xy 178.441732 -195.06336)
			(xy 178.386889 -195.05323) (xy 178.334105 -195.035223) (xy 178.284505 -195.009722) (xy 178.239147 -194.977271)
			(xy 178.198998 -194.938562) (xy 178.164912 -194.894419) (xy 178.137616 -194.845784) (xy 178.117693 -194.793693)
			(xy 178.105567 -194.739256) (xy 178.101496 -194.683634) (xy 156.349446 -194.683634) (xy 155.158694 -195.874386)
			(xy 178.09794 -195.874386) (xy 178.102011 -195.818764) (xy 178.114137 -195.764327) (xy 178.13406 -195.712236)
			(xy 178.161356 -195.663601) (xy 178.195442 -195.619458) (xy 178.235591 -195.580749) (xy 178.280949 -195.548298)
			(xy 178.330549 -195.522797) (xy 178.383333 -195.50479) (xy 178.438176 -195.49466) (xy 178.49391 -195.492623)
			(xy 178.549347 -195.498723) (xy 178.603304 -195.512829) (xy 178.654633 -195.534641) (xy 178.702239 -195.563695)
			(xy 178.745107 -195.59937) (xy 178.782324 -195.640907) (xy 178.813097 -195.68742) (xy 178.836769 -195.737917)
			(xy 178.852837 -195.791324) (xy 178.860957 -195.8465) (xy 178.861466 -195.874386) (xy 178.860957 -195.902272)
			(xy 178.852837 -195.957448) (xy 178.836769 -196.010855) (xy 178.813097 -196.061352) (xy 178.782324 -196.107865)
			(xy 178.745107 -196.149402) (xy 178.702239 -196.185077) (xy 178.654633 -196.214131) (xy 178.603304 -196.235943)
			(xy 178.549347 -196.250049) (xy 178.49391 -196.256149) (xy 178.438176 -196.254112) (xy 178.383333 -196.243982)
			(xy 178.330549 -196.225975) (xy 178.280949 -196.200474) (xy 178.235591 -196.168023) (xy 178.195442 -196.129314)
			(xy 178.161356 -196.085171) (xy 178.13406 -196.036536) (xy 178.114137 -195.984445) (xy 178.102011 -195.930008)
			(xy 178.09794 -195.874386) (xy 155.158694 -195.874386) (xy 154.577034 -196.456046) (xy 175.442116 -196.456046)
			(xy 175.446187 -196.400424) (xy 175.458313 -196.345987) (xy 175.478236 -196.293896) (xy 175.505532 -196.245261)
			(xy 175.539618 -196.201118) (xy 175.579767 -196.162409) (xy 175.625125 -196.129958) (xy 175.674725 -196.104457)
			(xy 175.727509 -196.08645) (xy 175.782352 -196.07632) (xy 175.838086 -196.074283) (xy 175.893523 -196.080383)
			(xy 175.94748 -196.094489) (xy 175.998809 -196.116301) (xy 176.046415 -196.145355) (xy 176.089283 -196.18103)
			(xy 176.1265 -196.222567) (xy 176.157273 -196.26908) (xy 176.180945 -196.319577) (xy 176.197013 -196.372984)
			(xy 176.205133 -196.42816) (xy 176.205642 -196.456046) (xy 176.205133 -196.483932) (xy 176.197013 -196.539108)
			(xy 176.180945 -196.592515) (xy 176.157273 -196.643012) (xy 176.1265 -196.689525) (xy 176.089283 -196.731062)
			(xy 176.046415 -196.766737) (xy 175.998809 -196.795791) (xy 175.94748 -196.817603) (xy 175.893523 -196.831709)
			(xy 175.838086 -196.837809) (xy 175.782352 -196.835772) (xy 175.727509 -196.825642) (xy 175.674725 -196.807635)
			(xy 175.625125 -196.782134) (xy 175.579767 -196.749683) (xy 175.539618 -196.710974) (xy 175.505532 -196.666831)
			(xy 175.478236 -196.618196) (xy 175.458313 -196.566105) (xy 175.446187 -196.511668) (xy 175.442116 -196.456046)
			(xy 154.577034 -196.456046) (xy 153.173684 -197.859396) (xy 175.425352 -197.859396) (xy 175.429423 -197.803774)
			(xy 175.441549 -197.749337) (xy 175.461472 -197.697246) (xy 175.488768 -197.648611) (xy 175.522854 -197.604468)
			(xy 175.563003 -197.565759) (xy 175.608361 -197.533308) (xy 175.657961 -197.507807) (xy 175.710745 -197.4898)
			(xy 175.765588 -197.47967) (xy 175.821322 -197.477633) (xy 175.876759 -197.483733) (xy 175.930716 -197.497839)
			(xy 175.982045 -197.519651) (xy 176.029651 -197.548705) (xy 176.072519 -197.58438) (xy 176.109736 -197.625917)
			(xy 176.140509 -197.67243) (xy 176.164181 -197.722927) (xy 176.180249 -197.776334) (xy 176.188369 -197.83151)
			(xy 176.188878 -197.859396) (xy 176.188369 -197.887282) (xy 176.180249 -197.942458) (xy 176.164181 -197.995865)
			(xy 176.140509 -198.046362) (xy 176.109736 -198.092875) (xy 176.072519 -198.134412) (xy 176.029651 -198.170087)
			(xy 175.982045 -198.199141) (xy 175.930716 -198.220953) (xy 175.876759 -198.235059) (xy 175.821322 -198.241159)
			(xy 175.765588 -198.239122) (xy 175.710745 -198.228992) (xy 175.657961 -198.210985) (xy 175.608361 -198.185484)
			(xy 175.563003 -198.153033) (xy 175.522854 -198.114324) (xy 175.488768 -198.070181) (xy 175.461472 -198.021546)
			(xy 175.441549 -197.969455) (xy 175.429423 -197.915018) (xy 175.425352 -197.859396) (xy 153.173684 -197.859396)
			(xy 152.250826 -198.782254) (xy 181.847155 -198.782254) (xy 181.847155 -198.727746) (xy 181.854913 -198.673791)
			(xy 181.870271 -198.621491) (xy 181.892916 -198.571908) (xy 181.922388 -198.526053) (xy 181.958085 -198.48486)
			(xy 181.999282 -198.449166) (xy 182.04514 -198.419699) (xy 182.094724 -198.397059) (xy 182.147027 -198.381706)
			(xy 182.200981 -198.373953) (xy 182.228236 -198.373492) (xy 182.254805 -198.37397) (xy 182.307431 -198.381332)
			(xy 182.358526 -198.395923) (xy 182.407104 -198.417461) (xy 182.452225 -198.445529) (xy 182.493016 -198.479584)
			(xy 182.511192 -198.498968) (xy 182.518558 -198.507096) (xy 182.538116 -198.515732) (xy 182.635906 -198.51497)
			(xy 182.65521 -198.506334) (xy 182.662576 -198.497952) (xy 182.680786 -198.478028) (xy 182.721824 -198.442968)
			(xy 182.767392 -198.414039) (xy 182.816581 -198.391819) (xy 182.868411 -198.376752) (xy 182.921846 -198.369137)
			(xy 182.948834 -198.368666) (xy 182.976082 -198.369207) (xy 183.030022 -198.376966) (xy 183.082309 -198.392323)
			(xy 183.131879 -198.414965) (xy 183.177722 -198.44443) (xy 183.218905 -198.480119) (xy 183.25459 -198.521306)
			(xy 183.284051 -198.567151) (xy 183.306688 -198.616723) (xy 183.322041 -198.669011) (xy 183.329796 -198.722952)
			(xy 183.329796 -198.777448) (xy 183.322041 -198.831389) (xy 183.306688 -198.883677) (xy 183.284051 -198.933249)
			(xy 183.25459 -198.979094) (xy 183.218905 -199.020281) (xy 183.177722 -199.05597) (xy 183.131879 -199.085435)
			(xy 183.082309 -199.108077) (xy 183.030022 -199.123434) (xy 182.976082 -199.131193) (xy 182.948834 -199.131682)
			(xy 182.922265 -199.1312) (xy 182.869641 -199.123835) (xy 182.818546 -199.109243) (xy 182.769969 -199.087706)
			(xy 182.724848 -199.059641) (xy 182.684056 -199.025588) (xy 182.665878 -199.006206) (xy 182.658512 -198.998078)
			(xy 182.638954 -198.989442) (xy 182.541164 -198.990204) (xy 182.52186 -198.99884) (xy 182.514494 -199.007222)
			(xy 182.496293 -199.027155) (xy 182.455255 -199.062216) (xy 182.409685 -199.091144) (xy 182.360493 -199.113363)
			(xy 182.308661 -199.128428) (xy 182.255224 -199.136039) (xy 182.228236 -199.136508) (xy 182.200981 -199.136047)
			(xy 182.147027 -199.128294) (xy 182.094724 -199.112941) (xy 182.04514 -199.090301) (xy 181.999282 -199.060834)
			(xy 181.958085 -199.02514) (xy 181.922388 -198.983947) (xy 181.892916 -198.938092) (xy 181.870271 -198.888509)
			(xy 181.854913 -198.836209) (xy 181.847155 -198.782254) (xy 152.250826 -198.782254) (xy 151.729694 -199.303386)
			(xy 178.09794 -199.303386) (xy 178.102011 -199.247764) (xy 178.114137 -199.193327) (xy 178.13406 -199.141236)
			(xy 178.161356 -199.092601) (xy 178.195442 -199.048458) (xy 178.235591 -199.009749) (xy 178.280949 -198.977298)
			(xy 178.330549 -198.951797) (xy 178.383333 -198.93379) (xy 178.438176 -198.92366) (xy 178.49391 -198.921623)
			(xy 178.549347 -198.927723) (xy 178.603304 -198.941829) (xy 178.654633 -198.963641) (xy 178.702239 -198.992695)
			(xy 178.745107 -199.02837) (xy 178.782324 -199.069907) (xy 178.813097 -199.11642) (xy 178.836769 -199.166917)
			(xy 178.852837 -199.220324) (xy 178.860957 -199.2755) (xy 178.861466 -199.303386) (xy 178.860957 -199.331272)
			(xy 178.852837 -199.386448) (xy 178.836769 -199.439855) (xy 178.813097 -199.490352) (xy 178.782324 -199.536865)
			(xy 178.745107 -199.578402) (xy 178.702239 -199.614077) (xy 178.654633 -199.643131) (xy 178.635254 -199.651366)
			(xy 180.827932 -199.651366) (xy 180.832003 -199.595744) (xy 180.844129 -199.541307) (xy 180.864052 -199.489216)
			(xy 180.891348 -199.440581) (xy 180.925434 -199.396438) (xy 180.965583 -199.357729) (xy 181.010941 -199.325278)
			(xy 181.060541 -199.299777) (xy 181.113325 -199.28177) (xy 181.168168 -199.27164) (xy 181.223902 -199.269603)
			(xy 181.279339 -199.275703) (xy 181.333296 -199.289809) (xy 181.384625 -199.311621) (xy 181.432231 -199.340675)
			(xy 181.475099 -199.37635) (xy 181.512316 -199.417887) (xy 181.543089 -199.4644) (xy 181.566761 -199.514897)
			(xy 181.582829 -199.568304) (xy 181.590949 -199.62348) (xy 181.591458 -199.651366) (xy 181.590949 -199.679252)
			(xy 181.582829 -199.734428) (xy 181.566761 -199.787835) (xy 181.543089 -199.838332) (xy 181.512316 -199.884845)
			(xy 181.475099 -199.926382) (xy 181.432231 -199.962057) (xy 181.384625 -199.991111) (xy 181.333296 -200.012923)
			(xy 181.279339 -200.027029) (xy 181.223902 -200.033129) (xy 181.168168 -200.031092) (xy 181.113325 -200.020962)
			(xy 181.060541 -200.002955) (xy 181.010941 -199.977454) (xy 180.965583 -199.945003) (xy 180.925434 -199.906294)
			(xy 180.891348 -199.862151) (xy 180.864052 -199.813516) (xy 180.844129 -199.761425) (xy 180.832003 -199.706988)
			(xy 180.827932 -199.651366) (xy 178.635254 -199.651366) (xy 178.603304 -199.664943) (xy 178.549347 -199.679049)
			(xy 178.49391 -199.685149) (xy 178.438176 -199.683112) (xy 178.383333 -199.672982) (xy 178.330549 -199.654975)
			(xy 178.280949 -199.629474) (xy 178.235591 -199.597023) (xy 178.195442 -199.558314) (xy 178.161356 -199.514171)
			(xy 178.13406 -199.465536) (xy 178.114137 -199.413445) (xy 178.102011 -199.359008) (xy 178.09794 -199.303386)
			(xy 151.729694 -199.303386) (xy 150.61311 -200.41997) (xy 150.606309 -200.427319) (xy 150.598601 -200.445781)
			(xy 150.598124 -200.455784) (xy 150.598124 -201.0664) (xy 150.597655 -201.092475) (xy 150.589526 -201.143988)
			(xy 150.573437 -201.193594) (xy 150.549784 -201.240071) (xy 150.519151 -201.282276) (xy 150.501096 -201.301096)
			(xy 149.104096 -202.698096) (xy 149.084792 -202.715876) (xy 149.076765 -202.723447) (xy 149.067537 -202.743463)
			(xy 149.067012 -202.754484) (xy 149.067012 -205.325726) (xy 149.06744 -205.335794) (xy 149.075163 -205.35439)
			(xy 149.081998 -205.361794) (xy 149.369272 -205.649068) (xy 149.376673 -205.655907) (xy 149.395271 -205.66362)
			(xy 149.40534 -205.664054)
		)
		(stroke
			(width 0)
			(type solid)
		)
		(fill yes)
		(layer "In15.Cu")
		(net "P1V8_PEX")
	)
	(gr_poly
		(pts
			(xy 248.171208 -321.442842) (xy 248.181276 -321.442416) (xy 248.199873 -321.434693) (xy 248.207276 -321.427856)
			(xy 248.538238 -321.096894) (xy 248.54509 -321.089498) (xy 248.552832 -321.070899) (xy 248.553224 -321.060826)
			(xy 248.553224 -310.68518) (xy 248.552747 -310.675214) (xy 248.545174 -310.656775) (xy 248.538492 -310.649366)
			(xy 248.480834 -310.5912) (xy 248.462546 -310.58358) (xy 248.452386 -310.58358) (xy 248.425254 -310.582923)
			(xy 248.371582 -310.574878) (xy 248.319593 -310.559307) (xy 248.270334 -310.536526) (xy 248.224802 -310.506993)
			(xy 248.183914 -310.471306) (xy 248.148497 -310.430184) (xy 248.119265 -310.384458) (xy 248.096809 -310.33505)
			(xy 248.081581 -310.282959) (xy 248.07389 -310.229235) (xy 248.07389 -310.174964) (xy 248.081581 -310.121241)
			(xy 248.096809 -310.069149) (xy 248.119265 -310.019742) (xy 248.148497 -309.974016) (xy 248.183914 -309.932894)
			(xy 248.224802 -309.897207) (xy 248.270335 -309.867674) (xy 248.319593 -309.844893) (xy 248.371583 -309.829322)
			(xy 248.425254 -309.821277) (xy 248.452386 -309.820564) (xy 248.462546 -309.820564) (xy 248.480834 -309.812944)
			(xy 248.538492 -309.754778) (xy 248.545173 -309.747368) (xy 248.552749 -309.728931) (xy 248.553224 -309.718964)
			(xy 248.553224 -308.977284) (xy 248.52884 -308.948836) (xy 248.510044 -308.946042) (xy 248.483358 -308.941463)
			(xy 248.431543 -308.925757) (xy 248.382469 -308.902884) (xy 248.33712 -308.873304) (xy 248.296409 -308.83761)
			(xy 248.261151 -308.79652) (xy 248.232056 -308.750859) (xy 248.209708 -308.701543) (xy 248.194556 -308.649564)
			(xy 248.186903 -308.595964) (xy 248.186904 -308.541821) (xy 248.194559 -308.488222) (xy 248.209713 -308.436243)
			(xy 248.232063 -308.386928) (xy 248.26116 -308.341268) (xy 248.296419 -308.300179) (xy 248.337132 -308.264487)
			(xy 248.382482 -308.234909) (xy 248.431557 -308.212038) (xy 248.483373 -308.196334) (xy 248.510044 -308.191662)
			(xy 248.52884 -308.188868) (xy 248.553224 -308.16042) (xy 248.553224 -307.892704) (xy 248.52884 -307.864256)
			(xy 248.510044 -307.861462) (xy 248.483357 -307.856883) (xy 248.431539 -307.841176) (xy 248.382462 -307.818303)
			(xy 248.337111 -307.788722) (xy 248.296397 -307.753027) (xy 248.261137 -307.711935) (xy 248.23204 -307.666271)
			(xy 248.209691 -307.616953) (xy 248.194537 -307.564971) (xy 248.186884 -307.511369) (xy 248.186884 -307.457223)
			(xy 248.194539 -307.403621) (xy 248.209694 -307.351639) (xy 248.232044 -307.302321) (xy 248.261142 -307.256659)
			(xy 248.296403 -307.215567) (xy 248.337118 -307.179873) (xy 248.382469 -307.150293) (xy 248.431547 -307.127421)
			(xy 248.483365 -307.111715) (xy 248.510044 -307.107082) (xy 248.52884 -307.104288) (xy 248.553224 -307.07584)
			(xy 248.553224 -289.698176) (xy 248.552797 -289.688107) (xy 248.545079 -289.669507) (xy 248.538238 -289.662108)
			(xy 248.231406 -289.355276) (xy 248.224012 -289.34842) (xy 248.205413 -289.340671) (xy 248.195338 -289.34029)
			(xy 238.008922 -289.34029) (xy 237.998897 -289.340706) (xy 237.980371 -289.348371) (xy 237.966189 -289.362544)
			(xy 237.958512 -289.381065) (xy 237.958122 -289.39109) (xy 237.958122 -289.391344) (xy 237.957633 -289.418594)
			(xy 237.949872 -289.472537) (xy 237.934513 -289.524828) (xy 237.911869 -289.5744) (xy 237.882402 -289.620246)
			(xy 237.846711 -289.661432) (xy 237.805522 -289.69712) (xy 237.759674 -289.726584) (xy 237.710099 -289.749223)
			(xy 237.657808 -289.764578) (xy 237.603864 -289.772335) (xy 237.576614 -289.772852) (xy 237.54649 -289.772284)
			(xy 237.486991 -289.762813) (xy 237.429721 -289.744104) (xy 237.376105 -289.716623) (xy 237.327478 -289.681053)
			(xy 237.30585 -289.660076) (xy 237.298738 -289.65271) (xy 237.279942 -289.64509) (xy 237.187486 -289.64509)
			(xy 237.16869 -289.65271) (xy 237.161578 -289.660076) (xy 237.139953 -289.681056) (xy 237.091319 -289.716616)
			(xy 237.037702 -289.744094) (xy 236.980434 -289.762806) (xy 236.920938 -289.77229) (xy 236.890814 -289.772852)
			(xy 236.863561 -289.772367) (xy 236.809609 -289.764613) (xy 236.75731 -289.749259) (xy 236.707729 -289.726619)
			(xy 236.661873 -289.697154) (xy 236.620678 -289.661463) (xy 236.584981 -289.620273) (xy 236.555508 -289.574422)
			(xy 236.532861 -289.524844) (xy 236.5175 -289.472547) (xy 236.509737 -289.418597) (xy 236.509306 -289.391344)
			(xy 236.509306 -289.39109) (xy 236.508816 -289.381083) (xy 236.501155 -289.362594) (xy 236.487003 -289.348443)
			(xy 236.468513 -289.340783) (xy 236.458506 -289.34029) (xy 234.544362 -289.34029) (xy 234.534295 -289.34072)
			(xy 234.515699 -289.348443) (xy 234.508294 -289.355276) (xy 234.49026 -289.37331) (xy 234.483408 -289.380706)
			(xy 234.475668 -289.399305) (xy 234.475274 -289.409378) (xy 234.475274 -290.900149) (xy 243.338104 -290.900149)
			(xy 243.338104 -290.845651) (xy 243.34586 -290.791707) (xy 243.361214 -290.739416) (xy 243.383853 -290.689843)
			(xy 243.413317 -290.643996) (xy 243.449006 -290.602809) (xy 243.490193 -290.567119) (xy 243.536039 -290.537655)
			(xy 243.585613 -290.515015) (xy 243.637903 -290.499661) (xy 243.691847 -290.491904) (xy 243.719096 -290.491418)
			(xy 243.746466 -290.491882) (xy 243.800646 -290.4997) (xy 243.853149 -290.515189) (xy 243.902896 -290.538031)
			(xy 243.948862 -290.567756) (xy 243.969794 -290.585398) (xy 243.976906 -290.591494) (xy 243.993924 -290.597844)
			(xy 244.079268 -290.597844) (xy 244.096286 -290.591494) (xy 244.103398 -290.585398) (xy 244.12432 -290.567746)
			(xy 244.170295 -290.538036) (xy 244.220046 -290.515203) (xy 244.272549 -290.499715) (xy 244.326726 -290.49189)
			(xy 244.354096 -290.491418) (xy 244.381351 -290.491829) (xy 244.435306 -290.499586) (xy 244.487608 -290.514942)
			(xy 244.537192 -290.537586) (xy 244.583049 -290.567056) (xy 244.624245 -290.602752) (xy 244.659941 -290.643948)
			(xy 244.689412 -290.689804) (xy 244.712056 -290.739388) (xy 244.727413 -290.79169) (xy 244.735171 -290.845645)
			(xy 244.735171 -290.900155) (xy 244.727413 -290.95411) (xy 244.712056 -291.006412) (xy 244.689412 -291.055996)
			(xy 244.659941 -291.101852) (xy 244.624245 -291.143048) (xy 244.583049 -291.178744) (xy 244.537192 -291.208214)
			(xy 244.487608 -291.230858) (xy 244.435306 -291.246214) (xy 244.381351 -291.253971) (xy 244.354096 -291.254434)
			(xy 244.326725 -291.253986) (xy 244.272544 -291.246167) (xy 244.22004 -291.230674) (xy 244.170294 -291.207828)
			(xy 244.124328 -291.178098) (xy 244.103398 -291.160454) (xy 244.096286 -291.154358) (xy 244.079268 -291.148008)
			(xy 243.993924 -291.148008) (xy 243.976906 -291.154358) (xy 243.969794 -291.160454) (xy 243.948869 -291.178102)
			(xy 243.902895 -291.207814) (xy 243.853146 -291.230649) (xy 243.800643 -291.246138) (xy 243.746466 -291.253962)
			(xy 243.719096 -291.254434) (xy 243.691847 -291.253896) (xy 243.637903 -291.246139) (xy 243.585613 -291.230785)
			(xy 243.536039 -291.208145) (xy 243.490193 -291.178681) (xy 243.449006 -291.142991) (xy 243.413317 -291.101804)
			(xy 243.383853 -291.055957) (xy 243.361214 -291.006384) (xy 243.34586 -290.954093) (xy 243.338104 -290.900149)
			(xy 234.475274 -290.900149) (xy 234.475274 -291.545049) (xy 236.34701 -291.545049) (xy 236.34701 -291.490551)
			(xy 236.354766 -291.436608) (xy 236.37012 -291.384318) (xy 236.392759 -291.334745) (xy 236.422223 -291.288898)
			(xy 236.457911 -291.247711) (xy 236.499098 -291.212023) (xy 236.544945 -291.182559) (xy 236.594518 -291.15992)
			(xy 236.646808 -291.144566) (xy 236.700751 -291.13681) (xy 236.728 -291.136324) (xy 236.755371 -291.136784)
			(xy 236.80955 -291.144603) (xy 236.862053 -291.160093) (xy 236.9118 -291.182936) (xy 236.957767 -291.212662)
			(xy 236.978698 -291.230304) (xy 236.98581 -291.2364) (xy 237.002828 -291.24275) (xy 237.088172 -291.24275)
			(xy 237.10519 -291.2364) (xy 237.112302 -291.230304) (xy 237.133223 -291.212651) (xy 237.179199 -291.182941)
			(xy 237.228949 -291.160108) (xy 237.281452 -291.14462) (xy 237.33563 -291.136796) (xy 237.363 -291.136324)
			(xy 237.390254 -291.136746) (xy 237.444206 -291.144503) (xy 237.496505 -291.159859) (xy 237.546086 -291.182502)
			(xy 237.591941 -291.211971) (xy 237.633134 -291.247666) (xy 237.668829 -291.288859) (xy 237.698298 -291.334714)
			(xy 237.720941 -291.384295) (xy 237.736297 -291.436594) (xy 237.744054 -291.490546) (xy 237.744054 -291.545054)
			(xy 237.736297 -291.599006) (xy 237.720941 -291.651305) (xy 237.698298 -291.700886) (xy 237.668829 -291.746741)
			(xy 237.633134 -291.787934) (xy 237.591941 -291.823629) (xy 237.546086 -291.853098) (xy 237.496505 -291.875741)
			(xy 237.444206 -291.891097) (xy 237.390254 -291.898854) (xy 237.363 -291.89934) (xy 237.335629 -291.898889)
			(xy 237.281449 -291.891069) (xy 237.228945 -291.875578) (xy 237.179198 -291.852732) (xy 237.133233 -291.823004)
			(xy 237.112302 -291.80536) (xy 237.10519 -291.799264) (xy 237.088172 -291.792914) (xy 237.002828 -291.792914)
			(xy 236.98581 -291.799264) (xy 236.978698 -291.80536) (xy 236.957772 -291.823007) (xy 236.911798 -291.852719)
			(xy 236.862049 -291.875554) (xy 236.809547 -291.891043) (xy 236.75537 -291.898868) (xy 236.728 -291.89934)
			(xy 236.700751 -291.89879) (xy 236.646808 -291.891034) (xy 236.594518 -291.87568) (xy 236.544945 -291.853041)
			(xy 236.499098 -291.823577) (xy 236.457911 -291.787889) (xy 236.422223 -291.746702) (xy 236.392759 -291.700855)
			(xy 236.37012 -291.651282) (xy 236.354766 -291.598992) (xy 236.34701 -291.545049) (xy 234.475274 -291.545049)
			(xy 234.475274 -306.744116) (xy 238.199674 -306.744116) (xy 238.203745 -306.688494) (xy 238.215871 -306.634057)
			(xy 238.235794 -306.581966) (xy 238.26309 -306.533331) (xy 238.297176 -306.489188) (xy 238.337325 -306.450479)
			(xy 238.382683 -306.418028) (xy 238.432283 -306.392527) (xy 238.485067 -306.37452) (xy 238.53991 -306.36439)
			(xy 238.595644 -306.362353) (xy 238.651081 -306.368453) (xy 238.705038 -306.382559) (xy 238.756367 -306.404371)
			(xy 238.803973 -306.433425) (xy 238.846841 -306.4691) (xy 238.884058 -306.510637) (xy 238.914831 -306.55715)
			(xy 238.938503 -306.607647) (xy 238.954571 -306.661054) (xy 238.962691 -306.71623) (xy 238.9632 -306.744116)
			(xy 238.962691 -306.772002) (xy 238.960478 -306.787042) (xy 245.473726 -306.787042) (xy 245.477797 -306.73142)
			(xy 245.489923 -306.676983) (xy 245.509846 -306.624892) (xy 245.537142 -306.576257) (xy 245.571228 -306.532114)
			(xy 245.611377 -306.493405) (xy 245.656735 -306.460954) (xy 245.706335 -306.435453) (xy 245.759119 -306.417446)
			(xy 245.813962 -306.407316) (xy 245.869696 -306.405279) (xy 245.925133 -306.411379) (xy 245.97909 -306.425485)
			(xy 246.030419 -306.447297) (xy 246.078025 -306.476351) (xy 246.120893 -306.512026) (xy 246.15811 -306.553563)
			(xy 246.188883 -306.600076) (xy 246.212555 -306.650573) (xy 246.228623 -306.70398) (xy 246.236743 -306.759156)
			(xy 246.237252 -306.787042) (xy 246.236743 -306.814928) (xy 246.228623 -306.870104) (xy 246.212555 -306.923511)
			(xy 246.188883 -306.974008) (xy 246.15811 -307.020521) (xy 246.120893 -307.062058) (xy 246.078025 -307.097733)
			(xy 246.030419 -307.126787) (xy 245.97909 -307.148599) (xy 245.925133 -307.162705) (xy 245.869696 -307.168805)
			(xy 245.813962 -307.166768) (xy 245.759119 -307.156638) (xy 245.706335 -307.138631) (xy 245.656735 -307.11313)
			(xy 245.611377 -307.080679) (xy 245.571228 -307.04197) (xy 245.537142 -306.997827) (xy 245.509846 -306.949192)
			(xy 245.489923 -306.897101) (xy 245.477797 -306.842664) (xy 245.473726 -306.787042) (xy 238.960478 -306.787042)
			(xy 238.954571 -306.827178) (xy 238.938503 -306.880585) (xy 238.914831 -306.931082) (xy 238.884058 -306.977595)
			(xy 238.846841 -307.019132) (xy 238.803973 -307.054807) (xy 238.756367 -307.083861) (xy 238.705038 -307.105673)
			(xy 238.651081 -307.119779) (xy 238.595644 -307.125879) (xy 238.53991 -307.123842) (xy 238.485067 -307.113712)
			(xy 238.432283 -307.095705) (xy 238.382683 -307.070204) (xy 238.337325 -307.037753) (xy 238.297176 -306.999044)
			(xy 238.26309 -306.954901) (xy 238.235794 -306.906266) (xy 238.215871 -306.854175) (xy 238.203745 -306.799738)
			(xy 238.199674 -306.744116) (xy 234.475274 -306.744116) (xy 234.475274 -307.446426) (xy 243.125242 -307.446426)
			(xy 243.129313 -307.390804) (xy 243.141439 -307.336367) (xy 243.161362 -307.284276) (xy 243.188658 -307.235641)
			(xy 243.222744 -307.191498) (xy 243.262893 -307.152789) (xy 243.308251 -307.120338) (xy 243.357851 -307.094837)
			(xy 243.410635 -307.07683) (xy 243.465478 -307.0667) (xy 243.521212 -307.064663) (xy 243.576649 -307.070763)
			(xy 243.630606 -307.084869) (xy 243.681935 -307.106681) (xy 243.729541 -307.135735) (xy 243.772409 -307.17141)
			(xy 243.809626 -307.212947) (xy 243.840399 -307.25946) (xy 243.864071 -307.309957) (xy 243.880139 -307.363364)
			(xy 243.888259 -307.41854) (xy 243.888768 -307.446426) (xy 243.888259 -307.474312) (xy 243.880139 -307.529488)
			(xy 243.864071 -307.582895) (xy 243.840399 -307.633392) (xy 243.809626 -307.679905) (xy 243.772409 -307.721442)
			(xy 243.729541 -307.757117) (xy 243.681935 -307.786171) (xy 243.630606 -307.807983) (xy 243.576649 -307.822089)
			(xy 243.521212 -307.828189) (xy 243.465478 -307.826152) (xy 243.410635 -307.816022) (xy 243.357851 -307.798015)
			(xy 243.308251 -307.772514) (xy 243.262893 -307.740063) (xy 243.222744 -307.701354) (xy 243.188658 -307.657211)
			(xy 243.161362 -307.608576) (xy 243.141439 -307.556485) (xy 243.129313 -307.502048) (xy 243.125242 -307.446426)
			(xy 234.475274 -307.446426) (xy 234.475274 -308.402228) (xy 244.183152 -308.402228) (xy 244.187223 -308.346606)
			(xy 244.199349 -308.292169) (xy 244.219272 -308.240078) (xy 244.246568 -308.191443) (xy 244.280654 -308.1473)
			(xy 244.320803 -308.108591) (xy 244.366161 -308.07614) (xy 244.415761 -308.050639) (xy 244.468545 -308.032632)
			(xy 244.523388 -308.022502) (xy 244.579122 -308.020465) (xy 244.634559 -308.026565) (xy 244.688516 -308.040671)
			(xy 244.739845 -308.062483) (xy 244.787451 -308.091537) (xy 244.830319 -308.127212) (xy 244.867536 -308.168749)
			(xy 244.898309 -308.215262) (xy 244.921981 -308.265759) (xy 244.938049 -308.319166) (xy 244.946169 -308.374342)
			(xy 244.946678 -308.402228) (xy 244.946169 -308.430114) (xy 244.938049 -308.48529) (xy 244.921981 -308.538697)
			(xy 244.898309 -308.589194) (xy 244.867536 -308.635707) (xy 244.830319 -308.677244) (xy 244.787451 -308.712919)
			(xy 244.739845 -308.741973) (xy 244.688516 -308.763785) (xy 244.634559 -308.777891) (xy 244.579122 -308.783991)
			(xy 244.523388 -308.781954) (xy 244.468545 -308.771824) (xy 244.415761 -308.753817) (xy 244.366161 -308.728316)
			(xy 244.320803 -308.695865) (xy 244.280654 -308.657156) (xy 244.246568 -308.613013) (xy 244.219272 -308.564378)
			(xy 244.199349 -308.512287) (xy 244.187223 -308.45785) (xy 244.183152 -308.402228) (xy 234.475274 -308.402228)
			(xy 234.475274 -309.018178) (xy 246.191276 -309.018178) (xy 246.195347 -308.962556) (xy 246.207473 -308.908119)
			(xy 246.227396 -308.856028) (xy 246.254692 -308.807393) (xy 246.288778 -308.76325) (xy 246.328927 -308.724541)
			(xy 246.374285 -308.69209) (xy 246.423885 -308.666589) (xy 246.476669 -308.648582) (xy 246.531512 -308.638452)
			(xy 246.587246 -308.636415) (xy 246.642683 -308.642515) (xy 246.69664 -308.656621) (xy 246.747969 -308.678433)
			(xy 246.795575 -308.707487) (xy 246.838443 -308.743162) (xy 246.87566 -308.784699) (xy 246.906433 -308.831212)
			(xy 246.930105 -308.881709) (xy 246.946173 -308.935116) (xy 246.954293 -308.990292) (xy 246.954802 -309.018178)
			(xy 246.954293 -309.046064) (xy 246.946173 -309.10124) (xy 246.930105 -309.154647) (xy 246.906433 -309.205144)
			(xy 246.87566 -309.251657) (xy 246.838443 -309.293194) (xy 246.795575 -309.328869) (xy 246.747969 -309.357923)
			(xy 246.69664 -309.379735) (xy 246.642683 -309.393841) (xy 246.587246 -309.399941) (xy 246.531512 -309.397904)
			(xy 246.476669 -309.387774) (xy 246.423885 -309.369767) (xy 246.374285 -309.344266) (xy 246.328927 -309.311815)
			(xy 246.288778 -309.273106) (xy 246.254692 -309.228963) (xy 246.227396 -309.180328) (xy 246.207473 -309.128237)
			(xy 246.195347 -309.0738) (xy 246.191276 -309.018178) (xy 234.475274 -309.018178) (xy 234.475274 -309.908448)
			(xy 242.571268 -309.908448) (xy 242.575339 -309.852826) (xy 242.587465 -309.798389) (xy 242.607388 -309.746298)
			(xy 242.634684 -309.697663) (xy 242.66877 -309.65352) (xy 242.708919 -309.614811) (xy 242.754277 -309.58236)
			(xy 242.803877 -309.556859) (xy 242.856661 -309.538852) (xy 242.911504 -309.528722) (xy 242.967238 -309.526685)
			(xy 243.022675 -309.532785) (xy 243.076632 -309.546891) (xy 243.127961 -309.568703) (xy 243.175567 -309.597757)
			(xy 243.218435 -309.633432) (xy 243.255652 -309.674969) (xy 243.286425 -309.721482) (xy 243.297509 -309.745126)
			(xy 244.286784 -309.745126) (xy 244.290855 -309.689504) (xy 244.302981 -309.635067) (xy 244.322904 -309.582976)
			(xy 244.3502 -309.534341) (xy 244.384286 -309.490198) (xy 244.424435 -309.451489) (xy 244.469793 -309.419038)
			(xy 244.519393 -309.393537) (xy 244.572177 -309.37553) (xy 244.62702 -309.3654) (xy 244.682754 -309.363363)
			(xy 244.738191 -309.369463) (xy 244.792148 -309.383569) (xy 244.843477 -309.405381) (xy 244.891083 -309.434435)
			(xy 244.933951 -309.47011) (xy 244.971168 -309.511647) (xy 245.001941 -309.55816) (xy 245.025613 -309.608657)
			(xy 245.041681 -309.662064) (xy 245.049801 -309.71724) (xy 245.05031 -309.745126) (xy 245.049801 -309.773012)
			(xy 245.041681 -309.828188) (xy 245.025613 -309.881595) (xy 245.001941 -309.932092) (xy 244.971168 -309.978605)
			(xy 244.933951 -310.020142) (xy 244.891083 -310.055817) (xy 244.843477 -310.084871) (xy 244.792148 -310.106683)
			(xy 244.738191 -310.120789) (xy 244.682754 -310.126889) (xy 244.62702 -310.124852) (xy 244.572177 -310.114722)
			(xy 244.519393 -310.096715) (xy 244.469793 -310.071214) (xy 244.424435 -310.038763) (xy 244.384286 -310.000054)
			(xy 244.3502 -309.955911) (xy 244.322904 -309.907276) (xy 244.302981 -309.855185) (xy 244.290855 -309.800748)
			(xy 244.286784 -309.745126) (xy 243.297509 -309.745126) (xy 243.310097 -309.771979) (xy 243.326165 -309.825386)
			(xy 243.334285 -309.880562) (xy 243.334794 -309.908448) (xy 243.334285 -309.936334) (xy 243.326165 -309.99151)
			(xy 243.310097 -310.044917) (xy 243.286425 -310.095414) (xy 243.255652 -310.141927) (xy 243.218435 -310.183464)
			(xy 243.175567 -310.219139) (xy 243.127961 -310.248193) (xy 243.076632 -310.270005) (xy 243.022675 -310.284111)
			(xy 242.967238 -310.290211) (xy 242.911504 -310.288174) (xy 242.856661 -310.278044) (xy 242.803877 -310.260037)
			(xy 242.754277 -310.234536) (xy 242.708919 -310.202085) (xy 242.66877 -310.163376) (xy 242.634684 -310.119233)
			(xy 242.607388 -310.070598) (xy 242.587465 -310.018507) (xy 242.575339 -309.96407) (xy 242.571268 -309.908448)
			(xy 234.475274 -309.908448) (xy 234.475274 -311.215786) (xy 243.749066 -311.215786) (xy 243.753137 -311.160164)
			(xy 243.765263 -311.105727) (xy 243.785186 -311.053636) (xy 243.812482 -311.005001) (xy 243.846568 -310.960858)
			(xy 243.886717 -310.922149) (xy 243.932075 -310.889698) (xy 243.981675 -310.864197) (xy 244.034459 -310.84619)
			(xy 244.089302 -310.83606) (xy 244.145036 -310.834023) (xy 244.200473 -310.840123) (xy 244.25443 -310.854229)
			(xy 244.305759 -310.876041) (xy 244.353365 -310.905095) (xy 244.396233 -310.94077) (xy 244.43345 -310.982307)
			(xy 244.464223 -311.02882) (xy 244.487895 -311.079317) (xy 244.503963 -311.132724) (xy 244.512083 -311.1879)
			(xy 244.512592 -311.215786) (xy 244.512083 -311.243672) (xy 244.503963 -311.298848) (xy 244.487895 -311.352255)
			(xy 244.464223 -311.402752) (xy 244.43345 -311.449265) (xy 244.396233 -311.490802) (xy 244.353365 -311.526477)
			(xy 244.305759 -311.555531) (xy 244.25443 -311.577343) (xy 244.200473 -311.591449) (xy 244.145036 -311.597549)
			(xy 244.089302 -311.595512) (xy 244.034459 -311.585382) (xy 243.981675 -311.567375) (xy 243.932075 -311.541874)
			(xy 243.886717 -311.509423) (xy 243.846568 -311.470714) (xy 243.812482 -311.426571) (xy 243.785186 -311.377936)
			(xy 243.765263 -311.325845) (xy 243.753137 -311.271408) (xy 243.749066 -311.215786) (xy 234.475274 -311.215786)
			(xy 234.475274 -320.816732) (xy 241.138202 -320.816732) (xy 241.138686 -320.789362) (xy 241.1465 -320.735184)
			(xy 241.161984 -320.682681) (xy 241.184822 -320.632934) (xy 241.214543 -320.586966) (xy 241.232182 -320.566034)
			(xy 241.238278 -320.558922) (xy 241.244628 -320.541904) (xy 241.244628 -320.45656) (xy 241.238278 -320.439542)
			(xy 241.232182 -320.43243) (xy 241.214541 -320.4115) (xy 241.18483 -320.365526) (xy 241.161995 -320.315778)
			(xy 241.146504 -320.263277) (xy 241.138676 -320.209101) (xy 241.138202 -320.181732) (xy 241.138685 -320.154479)
			(xy 241.146438 -320.100529) (xy 241.16179 -320.048231) (xy 241.18443 -319.99865) (xy 241.213896 -319.952796)
			(xy 241.249587 -319.911603) (xy 241.290779 -319.875909) (xy 241.336631 -319.846441) (xy 241.38621 -319.823798)
			(xy 241.438507 -319.808443) (xy 241.492458 -319.800687) (xy 241.51971 -319.800224) (xy 241.547081 -319.800678)
			(xy 241.601261 -319.808498) (xy 241.653764 -319.82399) (xy 241.703511 -319.846834) (xy 241.749477 -319.876561)
			(xy 241.770408 -319.894204) (xy 241.77752 -319.9003) (xy 241.794538 -319.90665) (xy 241.879882 -319.90665)
			(xy 241.8969 -319.9003) (xy 241.904012 -319.894204) (xy 241.924945 -319.876563) (xy 241.970913 -319.846839)
			(xy 242.020659 -319.823993) (xy 242.073161 -319.808497) (xy 242.127339 -319.800668) (xy 242.182081 -319.800668)
			(xy 242.236259 -319.808497) (xy 242.288761 -319.823993) (xy 242.338507 -319.846839) (xy 242.384475 -319.876563)
			(xy 242.405408 -319.894204) (xy 242.41252 -319.9003) (xy 242.429538 -319.90665) (xy 242.514882 -319.90665)
			(xy 242.5319 -319.9003) (xy 242.539012 -319.894204) (xy 242.559967 -319.876593) (xy 242.605933 -319.846877)
			(xy 242.655675 -319.824036) (xy 242.708171 -319.808538) (xy 242.762342 -319.800702) (xy 242.78971 -319.800224)
			(xy 242.816965 -319.800646) (xy 242.870919 -319.808405) (xy 242.923219 -319.823764) (xy 242.972802 -319.84641)
			(xy 243.018656 -319.875882) (xy 243.05985 -319.91158) (xy 243.095543 -319.952777) (xy 243.12501 -319.998635)
			(xy 243.147651 -320.04822) (xy 243.163004 -320.100522) (xy 243.170757 -320.154477) (xy 243.171218 -320.181732)
			(xy 243.170791 -320.209104) (xy 243.162967 -320.263285) (xy 243.14747 -320.31579) (xy 243.124619 -320.365536)
			(xy 243.094884 -320.4115) (xy 243.077238 -320.43243) (xy 243.071142 -320.439542) (xy 243.064792 -320.45656)
			(xy 243.064792 -320.541904) (xy 243.071142 -320.558922) (xy 243.077238 -320.566034) (xy 243.094866 -320.586975)
			(xy 243.124578 -320.632946) (xy 243.147416 -320.682691) (xy 243.16291 -320.73519) (xy 243.170742 -320.789364)
			(xy 243.171218 -320.816732) (xy 243.170752 -320.843984) (xy 243.162991 -320.897931) (xy 243.147633 -320.950226)
			(xy 243.124989 -320.999803) (xy 243.09552 -321.045652) (xy 243.059826 -321.086842) (xy 243.018635 -321.122533)
			(xy 242.972783 -321.151999) (xy 242.923205 -321.17464) (xy 242.87091 -321.189996) (xy 242.816962 -321.197754)
			(xy 242.78971 -321.19824) (xy 242.762339 -321.197783) (xy 242.708159 -321.189965) (xy 242.655655 -321.174475)
			(xy 242.605909 -321.151631) (xy 242.559943 -321.121903) (xy 242.539012 -321.10426) (xy 242.5319 -321.098164)
			(xy 242.514882 -321.091814) (xy 242.429538 -321.091814) (xy 242.41252 -321.098164) (xy 242.405408 -321.10426)
			(xy 242.384475 -321.121901) (xy 242.338507 -321.151625) (xy 242.288761 -321.174471) (xy 242.236259 -321.189967)
			(xy 242.182081 -321.197796) (xy 242.127339 -321.197796) (xy 242.073161 -321.189967) (xy 242.020659 -321.174471)
			(xy 241.970913 -321.151625) (xy 241.924945 -321.121901) (xy 241.904012 -321.10426) (xy 241.8969 -321.098164)
			(xy 241.879882 -321.091814) (xy 241.794538 -321.091814) (xy 241.77752 -321.098164) (xy 241.770408 -321.10426)
			(xy 241.749479 -321.121903) (xy 241.703506 -321.151615) (xy 241.653758 -321.174451) (xy 241.601256 -321.189941)
			(xy 241.547079 -321.197767) (xy 241.51971 -321.19824) (xy 241.49246 -321.197713) (xy 241.438516 -321.189958)
			(xy 241.386224 -321.174606) (xy 241.336649 -321.151968) (xy 241.2908 -321.122506) (xy 241.249611 -321.086819)
			(xy 241.213919 -321.045634) (xy 241.184452 -320.999788) (xy 241.161809 -320.950215) (xy 241.146451 -320.897925)
			(xy 241.13869 -320.843981) (xy 241.138202 -320.816732) (xy 234.475274 -320.816732) (xy 234.475274 -321.122548)
			(xy 234.475705 -321.132615) (xy 234.483429 -321.151209) (xy 234.49026 -321.158616) (xy 234.7595 -321.427856)
			(xy 234.766896 -321.434707) (xy 234.785495 -321.442449) (xy 234.795568 -321.442842)
		)
		(stroke
			(width 0)
			(type solid)
		)
		(fill yes)
		(layer "In15.Cu")
		(net "GND")
	)
	(gr_poly
		(pts
			(xy 110.105952 -241.983514) (xy 110.116018 -241.983082) (xy 110.13461 -241.975356) (xy 110.14202 -241.968528)
			(xy 110.260638 -241.84991) (xy 110.267493 -241.842515) (xy 110.275241 -241.823916) (xy 110.275624 -241.813842)
			(xy 110.275624 -223.823022) (xy 110.282228 -223.816672) (xy 110.282228 -213.274402) (xy 110.281692 -213.264414)
			(xy 110.273982 -213.245978) (xy 110.267242 -213.238588) (xy 110.120938 -213.092284) (xy 110.11353 -213.085595)
			(xy 110.095094 -213.078002) (xy 110.085124 -213.077552) (xy 100.829872 -213.077552) (xy 100.828602 -213.078568)
			(xy 100.70592 -213.078568) (xy 100.691188 -213.079076) (xy 99.09302 -213.079076) (xy 99.083058 -213.079564)
			(xy 99.064635 -213.087152) (xy 99.057206 -213.093808) (xy 98.010218 -214.140796) (xy 98.003369 -214.148194)
			(xy 97.99563 -214.166792) (xy 97.995232 -214.176864) (xy 97.995232 -219.08643) (xy 97.995838 -219.097759)
			(xy 98.005602 -219.118203) (xy 98.014028 -219.1258) (xy 98.083878 -219.182696) (xy 98.105722 -219.188284)
			(xy 98.117152 -219.185744) (xy 98.13606 -219.182147) (xy 98.17436 -219.178328) (xy 98.193606 -219.178124)
			(xy 98.220855 -219.178611) (xy 98.274797 -219.186367) (xy 98.327087 -219.201721) (xy 98.376659 -219.224361)
			(xy 98.422505 -219.253825) (xy 98.463691 -219.289513) (xy 98.499379 -219.3307) (xy 98.528842 -219.376546)
			(xy 98.551481 -219.426119) (xy 98.566834 -219.478409) (xy 98.57459 -219.532351) (xy 98.57459 -219.559886)
			(xy 100.279706 -219.559886) (xy 100.283777 -219.504264) (xy 100.295903 -219.449827) (xy 100.315826 -219.397736)
			(xy 100.343122 -219.349101) (xy 100.377208 -219.304958) (xy 100.417357 -219.266249) (xy 100.462715 -219.233798)
			(xy 100.512315 -219.208297) (xy 100.565099 -219.19029) (xy 100.619942 -219.18016) (xy 100.675676 -219.178123)
			(xy 100.731113 -219.184223) (xy 100.78507 -219.198329) (xy 100.836399 -219.220141) (xy 100.884005 -219.249195)
			(xy 100.926873 -219.28487) (xy 100.96409 -219.326407) (xy 100.994863 -219.37292) (xy 101.018535 -219.423417)
			(xy 101.034603 -219.476824) (xy 101.042723 -219.532) (xy 101.043223 -219.559378) (xy 102.352854 -219.559378)
			(xy 102.356925 -219.503756) (xy 102.369051 -219.449319) (xy 102.388974 -219.397228) (xy 102.41627 -219.348593)
			(xy 102.450356 -219.30445) (xy 102.490505 -219.265741) (xy 102.535863 -219.23329) (xy 102.585463 -219.207789)
			(xy 102.638247 -219.189782) (xy 102.69309 -219.179652) (xy 102.748824 -219.177615) (xy 102.804261 -219.183715)
			(xy 102.858218 -219.197821) (xy 102.909547 -219.219633) (xy 102.957153 -219.248687) (xy 103.000021 -219.284362)
			(xy 103.037238 -219.325899) (xy 103.068011 -219.372412) (xy 103.091683 -219.422909) (xy 103.107751 -219.476316)
			(xy 103.115871 -219.531492) (xy 103.11638 -219.559378) (xy 103.115871 -219.587264) (xy 103.107751 -219.64244)
			(xy 103.091683 -219.695847) (xy 103.068011 -219.746344) (xy 103.037238 -219.792857) (xy 103.000021 -219.834394)
			(xy 102.957153 -219.870069) (xy 102.909547 -219.899123) (xy 102.858218 -219.920935) (xy 102.804261 -219.935041)
			(xy 102.748824 -219.941141) (xy 102.69309 -219.939104) (xy 102.638247 -219.928974) (xy 102.585463 -219.910967)
			(xy 102.535863 -219.885466) (xy 102.490505 -219.853015) (xy 102.450356 -219.814306) (xy 102.41627 -219.770163)
			(xy 102.388974 -219.721528) (xy 102.369051 -219.669437) (xy 102.356925 -219.615) (xy 102.352854 -219.559378)
			(xy 101.043223 -219.559378) (xy 101.043232 -219.559886) (xy 101.042723 -219.587772) (xy 101.034603 -219.642948)
			(xy 101.018535 -219.696355) (xy 100.994863 -219.746852) (xy 100.96409 -219.793365) (xy 100.926873 -219.834902)
			(xy 100.884005 -219.870577) (xy 100.836399 -219.899631) (xy 100.78507 -219.921443) (xy 100.731113 -219.935549)
			(xy 100.675676 -219.941649) (xy 100.619942 -219.939612) (xy 100.565099 -219.929482) (xy 100.512315 -219.911475)
			(xy 100.462715 -219.885974) (xy 100.417357 -219.853523) (xy 100.377208 -219.814814) (xy 100.343122 -219.770671)
			(xy 100.315826 -219.722036) (xy 100.295903 -219.669945) (xy 100.283777 -219.615508) (xy 100.279706 -219.559886)
			(xy 98.57459 -219.559886) (xy 98.57459 -219.586849) (xy 98.566834 -219.640791) (xy 98.551481 -219.693081)
			(xy 98.528842 -219.742654) (xy 98.499379 -219.7885) (xy 98.463691 -219.829687) (xy 98.422505 -219.865375)
			(xy 98.376659 -219.894839) (xy 98.327087 -219.917479) (xy 98.274797 -219.932833) (xy 98.220855 -219.940589)
			(xy 98.193606 -219.94114) (xy 98.174361 -219.940923) (xy 98.136062 -219.937103) (xy 98.117152 -219.93352)
			(xy 98.105722 -219.93098) (xy 98.083878 -219.936568) (xy 98.014028 -219.993464) (xy 98.005639 -220.001084)
			(xy 97.9959 -220.021518) (xy 97.995232 -220.032834) (xy 97.995232 -221.146116) (xy 100.565456 -221.146116)
			(xy 100.569527 -221.090494) (xy 100.581653 -221.036057) (xy 100.601576 -220.983966) (xy 100.628872 -220.935331)
			(xy 100.662958 -220.891188) (xy 100.703107 -220.852479) (xy 100.748465 -220.820028) (xy 100.798065 -220.794527)
			(xy 100.850849 -220.77652) (xy 100.905692 -220.76639) (xy 100.961426 -220.764353) (xy 101.016863 -220.770453)
			(xy 101.07082 -220.784559) (xy 101.122149 -220.806371) (xy 101.169755 -220.835425) (xy 101.212623 -220.8711)
			(xy 101.24984 -220.912637) (xy 101.255253 -220.920818) (xy 102.937562 -220.920818) (xy 102.941633 -220.865196)
			(xy 102.953759 -220.810759) (xy 102.973682 -220.758668) (xy 103.000978 -220.710033) (xy 103.035064 -220.66589)
			(xy 103.075213 -220.627181) (xy 103.120571 -220.59473) (xy 103.170171 -220.569229) (xy 103.222955 -220.551222)
			(xy 103.277798 -220.541092) (xy 103.333532 -220.539055) (xy 103.388969 -220.545155) (xy 103.442926 -220.559261)
			(xy 103.494255 -220.581073) (xy 103.541861 -220.610127) (xy 103.584729 -220.645802) (xy 103.621946 -220.687339)
			(xy 103.652719 -220.733852) (xy 103.676391 -220.784349) (xy 103.692459 -220.837756) (xy 103.700579 -220.892932)
			(xy 103.701088 -220.920818) (xy 103.700579 -220.948704) (xy 103.692459 -221.00388) (xy 103.676391 -221.057287)
			(xy 103.652719 -221.107784) (xy 103.621946 -221.154297) (xy 103.584729 -221.195834) (xy 103.541861 -221.231509)
			(xy 103.494255 -221.260563) (xy 103.442926 -221.282375) (xy 103.388969 -221.296481) (xy 103.333532 -221.302581)
			(xy 103.277798 -221.300544) (xy 103.222955 -221.290414) (xy 103.170171 -221.272407) (xy 103.120571 -221.246906)
			(xy 103.075213 -221.214455) (xy 103.035064 -221.175746) (xy 103.000978 -221.131603) (xy 102.973682 -221.082968)
			(xy 102.953759 -221.030877) (xy 102.941633 -220.97644) (xy 102.937562 -220.920818) (xy 101.255253 -220.920818)
			(xy 101.280613 -220.95915) (xy 101.304285 -221.009647) (xy 101.320353 -221.063054) (xy 101.328473 -221.11823)
			(xy 101.328982 -221.146116) (xy 101.328473 -221.174002) (xy 101.320353 -221.229178) (xy 101.304285 -221.282585)
			(xy 101.280613 -221.333082) (xy 101.24984 -221.379595) (xy 101.212623 -221.421132) (xy 101.169755 -221.456807)
			(xy 101.122149 -221.485861) (xy 101.07082 -221.507673) (xy 101.016863 -221.521779) (xy 100.961426 -221.527879)
			(xy 100.905692 -221.525842) (xy 100.850849 -221.515712) (xy 100.798065 -221.497705) (xy 100.748465 -221.472204)
			(xy 100.703107 -221.439753) (xy 100.662958 -221.401044) (xy 100.628872 -221.356901) (xy 100.601576 -221.308266)
			(xy 100.581653 -221.256175) (xy 100.569527 -221.201738) (xy 100.565456 -221.146116) (xy 97.995232 -221.146116)
			(xy 97.995232 -222.46463) (xy 99.334318 -222.46463) (xy 99.338389 -222.409008) (xy 99.350515 -222.354571)
			(xy 99.370438 -222.30248) (xy 99.397734 -222.253845) (xy 99.43182 -222.209702) (xy 99.471969 -222.170993)
			(xy 99.517327 -222.138542) (xy 99.566927 -222.113041) (xy 99.619711 -222.095034) (xy 99.674554 -222.084904)
			(xy 99.730288 -222.082867) (xy 99.785725 -222.088967) (xy 99.839682 -222.103073) (xy 99.891011 -222.124885)
			(xy 99.938617 -222.153939) (xy 99.981485 -222.189614) (xy 100.018702 -222.231151) (xy 100.049475 -222.277664)
			(xy 100.073147 -222.328161) (xy 100.089215 -222.381568) (xy 100.097335 -222.436744) (xy 100.097844 -222.46463)
			(xy 100.097335 -222.492516) (xy 100.089215 -222.547692) (xy 100.073147 -222.601099) (xy 100.049475 -222.651596)
			(xy 100.018702 -222.698109) (xy 99.981485 -222.739646) (xy 99.938617 -222.775321) (xy 99.891011 -222.804375)
			(xy 99.839682 -222.826187) (xy 99.785725 -222.840293) (xy 99.730288 -222.846393) (xy 99.674554 -222.844356)
			(xy 99.619711 -222.834226) (xy 99.566927 -222.816219) (xy 99.517327 -222.790718) (xy 99.471969 -222.758267)
			(xy 99.43182 -222.719558) (xy 99.397734 -222.675415) (xy 99.370438 -222.62678) (xy 99.350515 -222.574689)
			(xy 99.338389 -222.520252) (xy 99.334318 -222.46463) (xy 97.995232 -222.46463) (xy 97.995232 -223.135698)
			(xy 101.499414 -223.135698) (xy 101.503485 -223.080076) (xy 101.515611 -223.025639) (xy 101.535534 -222.973548)
			(xy 101.56283 -222.924913) (xy 101.596916 -222.88077) (xy 101.637065 -222.842061) (xy 101.682423 -222.80961)
			(xy 101.732023 -222.784109) (xy 101.784807 -222.766102) (xy 101.83965 -222.755972) (xy 101.895384 -222.753935)
			(xy 101.950821 -222.760035) (xy 102.004778 -222.774141) (xy 102.056107 -222.795953) (xy 102.103713 -222.825007)
			(xy 102.146581 -222.860682) (xy 102.183798 -222.902219) (xy 102.214571 -222.948732) (xy 102.238243 -222.999229)
			(xy 102.254311 -223.052636) (xy 102.262431 -223.107812) (xy 102.26294 -223.135698) (xy 102.262431 -223.163584)
			(xy 102.254311 -223.21876) (xy 102.238243 -223.272167) (xy 102.214571 -223.322664) (xy 102.183798 -223.369177)
			(xy 102.146581 -223.410714) (xy 102.103713 -223.446389) (xy 102.056107 -223.475443) (xy 102.004778 -223.497255)
			(xy 101.950821 -223.511361) (xy 101.895384 -223.517461) (xy 101.83965 -223.515424) (xy 101.784807 -223.505294)
			(xy 101.732023 -223.487287) (xy 101.682423 -223.461786) (xy 101.637065 -223.429335) (xy 101.596916 -223.390626)
			(xy 101.56283 -223.346483) (xy 101.535534 -223.297848) (xy 101.515611 -223.245757) (xy 101.503485 -223.19132)
			(xy 101.499414 -223.135698) (xy 97.995232 -223.135698) (xy 97.995232 -223.849946) (xy 102.606346 -223.849946)
			(xy 102.610417 -223.794324) (xy 102.622543 -223.739887) (xy 102.642466 -223.687796) (xy 102.669762 -223.639161)
			(xy 102.703848 -223.595018) (xy 102.743997 -223.556309) (xy 102.789355 -223.523858) (xy 102.838955 -223.498357)
			(xy 102.891739 -223.48035) (xy 102.946582 -223.47022) (xy 103.002316 -223.468183) (xy 103.057753 -223.474283)
			(xy 103.11171 -223.488389) (xy 103.163039 -223.510201) (xy 103.210645 -223.539255) (xy 103.253513 -223.57493)
			(xy 103.29073 -223.616467) (xy 103.321503 -223.66298) (xy 103.345175 -223.713477) (xy 103.361243 -223.766884)
			(xy 103.369363 -223.82206) (xy 103.369872 -223.849946) (xy 103.369363 -223.877832) (xy 103.361243 -223.933008)
			(xy 103.345175 -223.986415) (xy 103.321503 -224.036912) (xy 103.29073 -224.083425) (xy 103.253513 -224.124962)
			(xy 103.210645 -224.160637) (xy 103.163039 -224.189691) (xy 103.11171 -224.211503) (xy 103.057753 -224.225609)
			(xy 103.002316 -224.231709) (xy 102.946582 -224.229672) (xy 102.891739 -224.219542) (xy 102.838955 -224.201535)
			(xy 102.789355 -224.176034) (xy 102.743997 -224.143583) (xy 102.703848 -224.104874) (xy 102.669762 -224.060731)
			(xy 102.642466 -224.012096) (xy 102.622543 -223.960005) (xy 102.610417 -223.905568) (xy 102.606346 -223.849946)
			(xy 97.995232 -223.849946) (xy 97.995232 -224.531174) (xy 107.58373 -224.531174) (xy 107.587801 -224.475552)
			(xy 107.599927 -224.421115) (xy 107.61985 -224.369024) (xy 107.647146 -224.320389) (xy 107.681232 -224.276246)
			(xy 107.721381 -224.237537) (xy 107.766739 -224.205086) (xy 107.816339 -224.179585) (xy 107.869123 -224.161578)
			(xy 107.923966 -224.151448) (xy 107.9797 -224.149411) (xy 108.035137 -224.155511) (xy 108.089094 -224.169617)
			(xy 108.140423 -224.191429) (xy 108.188029 -224.220483) (xy 108.230897 -224.256158) (xy 108.268114 -224.297695)
			(xy 108.298887 -224.344208) (xy 108.322559 -224.394705) (xy 108.338627 -224.448112) (xy 108.346747 -224.503288)
			(xy 108.347256 -224.531174) (xy 108.346747 -224.55906) (xy 108.338627 -224.614236) (xy 108.322559 -224.667643)
			(xy 108.298887 -224.71814) (xy 108.268114 -224.764653) (xy 108.230897 -224.80619) (xy 108.188029 -224.841865)
			(xy 108.140423 -224.870919) (xy 108.089094 -224.892731) (xy 108.035137 -224.906837) (xy 107.9797 -224.912937)
			(xy 107.923966 -224.9109) (xy 107.869123 -224.90077) (xy 107.816339 -224.882763) (xy 107.766739 -224.857262)
			(xy 107.721381 -224.824811) (xy 107.681232 -224.786102) (xy 107.647146 -224.741959) (xy 107.61985 -224.693324)
			(xy 107.599927 -224.641233) (xy 107.587801 -224.586796) (xy 107.58373 -224.531174) (xy 97.995232 -224.531174)
			(xy 97.995232 -236.391704) (xy 99.087938 -236.391704) (xy 99.092009 -236.336082) (xy 99.104135 -236.281645)
			(xy 99.124058 -236.229554) (xy 99.151354 -236.180919) (xy 99.18544 -236.136776) (xy 99.225589 -236.098067)
			(xy 99.270947 -236.065616) (xy 99.320547 -236.040115) (xy 99.373331 -236.022108) (xy 99.428174 -236.011978)
			(xy 99.483908 -236.009941) (xy 99.539345 -236.016041) (xy 99.593302 -236.030147) (xy 99.644631 -236.051959)
			(xy 99.692237 -236.081013) (xy 99.735105 -236.116688) (xy 99.772322 -236.158225) (xy 99.803095 -236.204738)
			(xy 99.826767 -236.255235) (xy 99.842835 -236.308642) (xy 99.850955 -236.363818) (xy 99.851464 -236.391704)
			(xy 99.850955 -236.41959) (xy 99.842835 -236.474766) (xy 99.826767 -236.528173) (xy 99.803095 -236.57867)
			(xy 99.772322 -236.625183) (xy 99.735105 -236.66672) (xy 99.692237 -236.702395) (xy 99.644631 -236.731449)
			(xy 99.593302 -236.753261) (xy 99.539345 -236.767367) (xy 99.483908 -236.773467) (xy 99.428174 -236.77143)
			(xy 99.373331 -236.7613) (xy 99.320547 -236.743293) (xy 99.270947 -236.717792) (xy 99.225589 -236.685341)
			(xy 99.18544 -236.646632) (xy 99.151354 -236.602489) (xy 99.124058 -236.553854) (xy 99.104135 -236.501763)
			(xy 99.092009 -236.447326) (xy 99.087938 -236.391704) (xy 97.995232 -236.391704) (xy 97.995232 -236.775244)
			(xy 101.503226 -236.775244) (xy 101.503712 -236.747874) (xy 101.511524 -236.693696) (xy 101.527008 -236.641193)
			(xy 101.549845 -236.591446) (xy 101.579566 -236.545478) (xy 101.597206 -236.524546) (xy 101.603302 -236.517434)
			(xy 101.609652 -236.500416) (xy 101.609652 -236.415072) (xy 101.603302 -236.398054) (xy 101.597206 -236.390942)
			(xy 101.579574 -236.370004) (xy 101.549861 -236.324033) (xy 101.527024 -236.274287) (xy 101.511531 -236.221788)
			(xy 101.503701 -236.167613) (xy 101.503226 -236.140244) (xy 101.503712 -236.112993) (xy 101.511468 -236.059045)
			(xy 101.526823 -236.00675) (xy 101.549465 -235.957173) (xy 101.578931 -235.911323) (xy 101.614622 -235.870132)
			(xy 101.655813 -235.834441) (xy 101.701663 -235.804975) (xy 101.75124 -235.782333) (xy 101.803535 -235.766978)
			(xy 101.857483 -235.759222) (xy 101.911985 -235.759222) (xy 101.965933 -235.766978) (xy 102.018228 -235.782333)
			(xy 102.067805 -235.804975) (xy 102.113655 -235.834441) (xy 102.154846 -235.870132) (xy 102.190537 -235.911323)
			(xy 102.220003 -235.957173) (xy 102.242645 -236.00675) (xy 102.258 -236.059045) (xy 102.265756 -236.112993)
			(xy 102.266242 -236.140244) (xy 102.265757 -236.167614) (xy 102.257946 -236.221793) (xy 102.242462 -236.274296)
			(xy 102.219624 -236.324043) (xy 102.189902 -236.37001) (xy 102.172262 -236.390942) (xy 102.166166 -236.398054)
			(xy 102.159816 -236.415072) (xy 102.159816 -236.500416) (xy 102.166166 -236.517434) (xy 102.172262 -236.524546)
			(xy 102.189883 -236.545492) (xy 102.219599 -236.591461) (xy 102.242439 -236.641205) (xy 102.257934 -236.693702)
			(xy 102.265766 -236.747876) (xy 102.266242 -236.775244) (xy 103.535226 -236.775244) (xy 103.535712 -236.747874)
			(xy 103.543524 -236.693696) (xy 103.559008 -236.641193) (xy 103.581845 -236.591446) (xy 103.611566 -236.545478)
			(xy 103.629206 -236.524546) (xy 103.635302 -236.517434) (xy 103.641652 -236.500416) (xy 103.641652 -236.415072)
			(xy 103.635302 -236.398054) (xy 103.629206 -236.390942) (xy 103.611574 -236.370004) (xy 103.581861 -236.324033)
			(xy 103.559024 -236.274287) (xy 103.543531 -236.221788) (xy 103.535701 -236.167613) (xy 103.535226 -236.140244)
			(xy 103.535712 -236.112993) (xy 103.543468 -236.059045) (xy 103.558823 -236.00675) (xy 103.581465 -235.957173)
			(xy 103.610931 -235.911323) (xy 103.646622 -235.870132) (xy 103.687813 -235.834441) (xy 103.733663 -235.804975)
			(xy 103.78324 -235.782333) (xy 103.835535 -235.766978) (xy 103.889483 -235.759222) (xy 103.943985 -235.759222)
			(xy 103.997933 -235.766978) (xy 104.050228 -235.782333) (xy 104.099805 -235.804975) (xy 104.145655 -235.834441)
			(xy 104.186846 -235.870132) (xy 104.222537 -235.911323) (xy 104.252003 -235.957173) (xy 104.274645 -236.00675)
			(xy 104.29 -236.059045) (xy 104.297756 -236.112993) (xy 104.298242 -236.140244) (xy 104.297757 -236.167614)
			(xy 104.289946 -236.221793) (xy 104.274462 -236.274296) (xy 104.251624 -236.324043) (xy 104.221902 -236.37001)
			(xy 104.204262 -236.390942) (xy 104.198166 -236.398054) (xy 104.191816 -236.415072) (xy 104.191816 -236.500416)
			(xy 104.198166 -236.517434) (xy 104.204262 -236.524546) (xy 104.221883 -236.545492) (xy 104.251599 -236.591461)
			(xy 104.274439 -236.641205) (xy 104.289934 -236.693702) (xy 104.297766 -236.747876) (xy 104.298242 -236.775244)
			(xy 105.567226 -236.775244) (xy 105.567712 -236.747874) (xy 105.575524 -236.693696) (xy 105.591008 -236.641193)
			(xy 105.613845 -236.591446) (xy 105.643566 -236.545478) (xy 105.661206 -236.524546) (xy 105.667302 -236.517434)
			(xy 105.673652 -236.500416) (xy 105.673652 -236.415072) (xy 105.667302 -236.398054) (xy 105.661206 -236.390942)
			(xy 105.643574 -236.370004) (xy 105.613861 -236.324033) (xy 105.591024 -236.274287) (xy 105.575531 -236.221788)
			(xy 105.567701 -236.167613) (xy 105.567226 -236.140244) (xy 105.567712 -236.112993) (xy 105.575468 -236.059045)
			(xy 105.590823 -236.00675) (xy 105.613465 -235.957173) (xy 105.642931 -235.911323) (xy 105.678622 -235.870132)
			(xy 105.719813 -235.834441) (xy 105.765663 -235.804975) (xy 105.81524 -235.782333) (xy 105.867535 -235.766978)
			(xy 105.921483 -235.759222) (xy 105.975985 -235.759222) (xy 106.029933 -235.766978) (xy 106.082228 -235.782333)
			(xy 106.131805 -235.804975) (xy 106.177655 -235.834441) (xy 106.218846 -235.870132) (xy 106.254537 -235.911323)
			(xy 106.284003 -235.957173) (xy 106.306645 -236.00675) (xy 106.322 -236.059045) (xy 106.329756 -236.112993)
			(xy 106.330242 -236.140244) (xy 106.329757 -236.167614) (xy 106.321946 -236.221793) (xy 106.306462 -236.274296)
			(xy 106.283624 -236.324043) (xy 106.253902 -236.37001) (xy 106.236262 -236.390942) (xy 106.230166 -236.398054)
			(xy 106.223816 -236.415072) (xy 106.223816 -236.500416) (xy 106.230166 -236.517434) (xy 106.236262 -236.524546)
			(xy 106.253883 -236.545492) (xy 106.283599 -236.591461) (xy 106.306439 -236.641205) (xy 106.321934 -236.693702)
			(xy 106.329766 -236.747876) (xy 106.330242 -236.775244) (xy 107.599226 -236.775244) (xy 107.599712 -236.747874)
			(xy 107.607524 -236.693696) (xy 107.623008 -236.641193) (xy 107.645845 -236.591446) (xy 107.675566 -236.545478)
			(xy 107.693206 -236.524546) (xy 107.699302 -236.517434) (xy 107.705652 -236.500416) (xy 107.705652 -236.415072)
			(xy 107.699302 -236.398054) (xy 107.693206 -236.390942) (xy 107.675574 -236.370004) (xy 107.645861 -236.324033)
			(xy 107.623024 -236.274287) (xy 107.607531 -236.221788) (xy 107.599701 -236.167613) (xy 107.599226 -236.140244)
			(xy 107.599712 -236.112993) (xy 107.607468 -236.059045) (xy 107.622823 -236.00675) (xy 107.645465 -235.957173)
			(xy 107.674931 -235.911323) (xy 107.710622 -235.870132) (xy 107.751813 -235.834441) (xy 107.797663 -235.804975)
			(xy 107.84724 -235.782333) (xy 107.899535 -235.766978) (xy 107.953483 -235.759222) (xy 108.007985 -235.759222)
			(xy 108.061933 -235.766978) (xy 108.114228 -235.782333) (xy 108.163805 -235.804975) (xy 108.209655 -235.834441)
			(xy 108.250846 -235.870132) (xy 108.286537 -235.911323) (xy 108.316003 -235.957173) (xy 108.338645 -236.00675)
			(xy 108.354 -236.059045) (xy 108.361756 -236.112993) (xy 108.362242 -236.140244) (xy 108.361757 -236.167614)
			(xy 108.353946 -236.221793) (xy 108.338462 -236.274296) (xy 108.315624 -236.324043) (xy 108.285902 -236.37001)
			(xy 108.268262 -236.390942) (xy 108.262166 -236.398054) (xy 108.255816 -236.415072) (xy 108.255816 -236.500416)
			(xy 108.262166 -236.517434) (xy 108.268262 -236.524546) (xy 108.285883 -236.545492) (xy 108.315599 -236.591461)
			(xy 108.338439 -236.641205) (xy 108.353934 -236.693702) (xy 108.361766 -236.747876) (xy 108.362242 -236.775244)
			(xy 108.361756 -236.802495) (xy 108.354 -236.856443) (xy 108.338645 -236.908738) (xy 108.316003 -236.958315)
			(xy 108.286537 -237.004165) (xy 108.250846 -237.045356) (xy 108.209655 -237.081047) (xy 108.163805 -237.110513)
			(xy 108.114228 -237.133155) (xy 108.061933 -237.14851) (xy 108.007985 -237.156266) (xy 107.953483 -237.156266)
			(xy 107.899535 -237.14851) (xy 107.84724 -237.133155) (xy 107.797663 -237.110513) (xy 107.751813 -237.081047)
			(xy 107.710622 -237.045356) (xy 107.674931 -237.004165) (xy 107.645465 -236.958315) (xy 107.622823 -236.908738)
			(xy 107.607468 -236.856443) (xy 107.599712 -236.802495) (xy 107.599226 -236.775244) (xy 106.330242 -236.775244)
			(xy 106.329756 -236.802495) (xy 106.322 -236.856443) (xy 106.306645 -236.908738) (xy 106.284003 -236.958315)
			(xy 106.254537 -237.004165) (xy 106.218846 -237.045356) (xy 106.177655 -237.081047) (xy 106.131805 -237.110513)
			(xy 106.082228 -237.133155) (xy 106.029933 -237.14851) (xy 105.975985 -237.156266) (xy 105.921483 -237.156266)
			(xy 105.867535 -237.14851) (xy 105.81524 -237.133155) (xy 105.765663 -237.110513) (xy 105.719813 -237.081047)
			(xy 105.678622 -237.045356) (xy 105.642931 -237.004165) (xy 105.613465 -236.958315) (xy 105.590823 -236.908738)
			(xy 105.575468 -236.856443) (xy 105.567712 -236.802495) (xy 105.567226 -236.775244) (xy 104.298242 -236.775244)
			(xy 104.297756 -236.802495) (xy 104.29 -236.856443) (xy 104.274645 -236.908738) (xy 104.252003 -236.958315)
			(xy 104.222537 -237.004165) (xy 104.186846 -237.045356) (xy 104.145655 -237.081047) (xy 104.099805 -237.110513)
			(xy 104.050228 -237.133155) (xy 103.997933 -237.14851) (xy 103.943985 -237.156266) (xy 103.889483 -237.156266)
			(xy 103.835535 -237.14851) (xy 103.78324 -237.133155) (xy 103.733663 -237.110513) (xy 103.687813 -237.081047)
			(xy 103.646622 -237.045356) (xy 103.610931 -237.004165) (xy 103.581465 -236.958315) (xy 103.558823 -236.908738)
			(xy 103.543468 -236.856443) (xy 103.535712 -236.802495) (xy 103.535226 -236.775244) (xy 102.266242 -236.775244)
			(xy 102.265756 -236.802495) (xy 102.258 -236.856443) (xy 102.242645 -236.908738) (xy 102.220003 -236.958315)
			(xy 102.190537 -237.004165) (xy 102.154846 -237.045356) (xy 102.113655 -237.081047) (xy 102.067805 -237.110513)
			(xy 102.018228 -237.133155) (xy 101.965933 -237.14851) (xy 101.911985 -237.156266) (xy 101.857483 -237.156266)
			(xy 101.803535 -237.14851) (xy 101.75124 -237.133155) (xy 101.701663 -237.110513) (xy 101.655813 -237.081047)
			(xy 101.614622 -237.045356) (xy 101.578931 -237.004165) (xy 101.549465 -236.958315) (xy 101.526823 -236.908738)
			(xy 101.511468 -236.856443) (xy 101.503712 -236.802495) (xy 101.503226 -236.775244) (xy 97.995232 -236.775244)
			(xy 97.995232 -240.470436) (xy 97.995664 -240.481008) (xy 98.004205 -240.500348) (xy 98.011742 -240.507774)
			(xy 98.030804 -240.525924) (xy 98.064263 -240.566554) (xy 98.091825 -240.611396) (xy 98.112966 -240.659597)
			(xy 98.127287 -240.710246) (xy 98.134516 -240.762381) (xy 98.134932 -240.788698) (xy 98.13451 -240.815016)
			(xy 98.127308 -240.867158) (xy 98.112999 -240.917812) (xy 98.108467 -240.928144) (xy 99.417122 -240.928144)
			(xy 99.421193 -240.872522) (xy 99.433319 -240.818085) (xy 99.453242 -240.765994) (xy 99.480538 -240.717359)
			(xy 99.514624 -240.673216) (xy 99.554773 -240.634507) (xy 99.600131 -240.602056) (xy 99.649731 -240.576555)
			(xy 99.702515 -240.558548) (xy 99.757358 -240.548418) (xy 99.813092 -240.546381) (xy 99.868529 -240.552481)
			(xy 99.922486 -240.566587) (xy 99.973815 -240.588399) (xy 100.021421 -240.617453) (xy 100.064289 -240.653128)
			(xy 100.101506 -240.694665) (xy 100.132279 -240.741178) (xy 100.155951 -240.791675) (xy 100.172019 -240.845082)
			(xy 100.180139 -240.900258) (xy 100.180648 -240.928144) (xy 100.180139 -240.95603) (xy 100.172019 -241.011206)
			(xy 100.155951 -241.064613) (xy 100.132279 -241.11511) (xy 100.101506 -241.161623) (xy 100.064289 -241.20316)
			(xy 100.021421 -241.238835) (xy 99.973815 -241.267889) (xy 99.922486 -241.289701) (xy 99.868529 -241.303807)
			(xy 99.813092 -241.309907) (xy 99.757358 -241.30787) (xy 99.702515 -241.29774) (xy 99.649731 -241.279733)
			(xy 99.600131 -241.254232) (xy 99.554773 -241.221781) (xy 99.514624 -241.183072) (xy 99.480538 -241.138929)
			(xy 99.453242 -241.090294) (xy 99.433319 -241.038203) (xy 99.421193 -240.983766) (xy 99.417122 -240.928144)
			(xy 98.108467 -240.928144) (xy 98.091857 -240.966015) (xy 98.064282 -241.010851) (xy 98.0308 -241.051465)
			(xy 98.011742 -241.069622) (xy 98.004353 -241.077149) (xy 97.995848 -241.096428) (xy 97.995232 -241.10696)
			(xy 97.995232 -241.754406) (xy 97.995657 -241.764475) (xy 98.003376 -241.783075) (xy 98.010218 -241.790474)
			(xy 98.188272 -241.968528) (xy 98.195671 -241.975371) (xy 98.21427 -241.98309) (xy 98.22434 -241.983514)
		)
		(stroke
			(width 0)
			(type solid)
		)
		(fill yes)
		(layer "In15.Cu")
		(net "GND")
	)
	(gr_poly
		(pts
			(xy 462.542128 -321.566286) (xy 462.552196 -321.565857) (xy 462.570791 -321.558134) (xy 462.578196 -321.5513)
			(xy 462.909158 -321.220338) (xy 462.915999 -321.212938) (xy 462.923718 -321.194339) (xy 462.924144 -321.18427)
			(xy 462.924144 -317.569596) (xy 462.923602 -317.558959) (xy 462.915005 -317.539501) (xy 462.899278 -317.525175)
			(xy 462.889346 -317.521336) (xy 462.805905 -317.493303) (xy 462.641395 -317.430621) (xy 462.47991 -317.360515)
			(xy 462.321784 -317.28313) (xy 462.167344 -317.198628) (xy 462.016911 -317.107182) (xy 461.870796 -317.008984)
			(xy 461.729304 -316.904235) (xy 461.592726 -316.793155) (xy 461.461347 -316.675972) (xy 461.335438 -316.55293)
			(xy 461.215261 -316.424284) (xy 461.101065 -316.290301) (xy 460.993086 -316.151258) (xy 460.891549 -316.007443)
			(xy 460.796663 -315.859156) (xy 460.708627 -315.706703) (xy 460.627621 -315.5504) (xy 460.553815 -315.390572)
			(xy 460.487361 -315.22755) (xy 460.428397 -315.061672) (xy 460.377046 -314.893281) (xy 460.333413 -314.722728)
			(xy 460.297589 -314.550365) (xy 460.269649 -314.37655) (xy 460.24965 -314.201643) (xy 460.237634 -314.026007)
			(xy 460.233625 -313.850006) (xy 460.237633 -313.674005) (xy 460.249648 -313.49837) (xy 460.269647 -313.323463)
			(xy 460.297587 -313.149647) (xy 460.33341 -312.977284) (xy 460.377042 -312.806731) (xy 460.428393 -312.63834)
			(xy 460.487357 -312.472461) (xy 460.55381 -312.309439) (xy 460.627616 -312.149611) (xy 460.708621 -311.993308)
			(xy 460.796657 -311.840855) (xy 460.891542 -311.692567) (xy 460.993078 -311.548753) (xy 461.101057 -311.409709)
			(xy 461.215252 -311.275725) (xy 461.335429 -311.147079) (xy 461.461338 -311.024037) (xy 461.592717 -310.906853)
			(xy 461.729294 -310.795772) (xy 461.870786 -310.691024) (xy 462.0169 -310.592825) (xy 462.167333 -310.501379)
			(xy 462.321772 -310.416876) (xy 462.479899 -310.339491) (xy 462.641384 -310.269384) (xy 462.805893 -310.206701)
			(xy 462.889346 -310.178704) (xy 462.899275 -310.174843) (xy 462.915032 -310.160544) (xy 462.923637 -310.141084)
			(xy 462.924144 -310.130444) (xy 462.924144 -309.80761) (xy 462.923721 -309.79754) (xy 462.916003 -309.778938)
			(xy 462.909158 -309.771542) (xy 462.419446 -309.28183) (xy 462.412606 -309.27443) (xy 462.404889 -309.255831)
			(xy 462.40446 -309.245762) (xy 462.40446 -306.965858) (xy 462.404892 -306.955793) (xy 462.412624 -306.937205)
			(xy 462.419446 -306.92979) (xy 462.909158 -306.440078) (xy 462.916006 -306.43268) (xy 462.923739 -306.414082)
			(xy 462.924144 -306.40401) (xy 462.924144 -289.82162) (xy 462.923705 -289.811558) (xy 462.915964 -289.792979)
			(xy 462.909158 -289.785552) (xy 462.602326 -289.47872) (xy 462.594924 -289.471883) (xy 462.576326 -289.464173)
			(xy 462.566258 -289.463734) (xy 453.663304 -289.463734) (xy 453.653285 -289.464153) (xy 453.634772 -289.471824)
			(xy 453.620607 -289.485998) (xy 453.612948 -289.504514) (xy 453.612504 -289.514534) (xy 453.612504 -289.514788)
			(xy 453.612041 -289.542041) (xy 453.604286 -289.595993) (xy 453.588931 -289.648292) (xy 453.566289 -289.697874)
			(xy 453.536821 -289.743728) (xy 453.501128 -289.784922) (xy 453.459934 -289.820616) (xy 453.414081 -289.850085)
			(xy 453.3645 -289.872728) (xy 453.312201 -289.888084) (xy 453.258249 -289.895841) (xy 453.230996 -289.896296)
			(xy 453.203626 -289.895824) (xy 453.149448 -289.888) (xy 453.096945 -289.872512) (xy 453.047194 -289.849679)
			(xy 453.001218 -289.81997) (xy 452.980298 -289.802316) (xy 452.973186 -289.79622) (xy 452.956168 -289.78987)
			(xy 452.870824 -289.78987) (xy 452.853806 -289.79622) (xy 452.846694 -289.802316) (xy 452.825762 -289.819957)
			(xy 452.779795 -289.849681) (xy 452.730048 -289.872523) (xy 452.677545 -289.888011) (xy 452.623366 -289.895829)
			(xy 452.595996 -289.896296) (xy 452.568744 -289.895832) (xy 452.514794 -289.888075) (xy 452.462497 -289.872718)
			(xy 452.412918 -289.850075) (xy 452.367067 -289.820607) (xy 452.325875 -289.784913) (xy 452.290183 -289.743721)
			(xy 452.260717 -289.697868) (xy 452.238076 -289.648288) (xy 452.222722 -289.595991) (xy 452.214966 -289.54204)
			(xy 452.214488 -289.514788) (xy 452.214488 -289.514534) (xy 452.214074 -289.504509) (xy 452.20641 -289.485982)
			(xy 452.192236 -289.471802) (xy 452.173713 -289.46413) (xy 452.163688 -289.463734) (xy 448.915282 -289.463734)
			(xy 448.905214 -289.464161) (xy 448.886617 -289.471884) (xy 448.879214 -289.47872) (xy 448.86118 -289.496754)
			(xy 448.854333 -289.504151) (xy 448.846606 -289.522751) (xy 448.846194 -289.532822) (xy 448.846194 -290.834847)
			(xy 458.605926 -290.834847) (xy 458.605926 -290.780353) (xy 458.613681 -290.726413) (xy 458.629034 -290.674125)
			(xy 458.651672 -290.624555) (xy 458.681133 -290.578711) (xy 458.716819 -290.537526) (xy 458.758003 -290.501839)
			(xy 458.803846 -290.472376) (xy 458.853416 -290.449738) (xy 458.905703 -290.434384) (xy 458.959643 -290.426627)
			(xy 458.98689 -290.42614) (xy 459.01426 -290.426602) (xy 459.06844 -290.434419) (xy 459.120944 -290.449909)
			(xy 459.17069 -290.472752) (xy 459.216657 -290.502478) (xy 459.237588 -290.52012) (xy 459.2447 -290.526216)
			(xy 459.261718 -290.532566) (xy 459.347062 -290.532566) (xy 459.36408 -290.526216) (xy 459.371192 -290.52012)
			(xy 459.392119 -290.502474) (xy 459.438093 -290.472763) (xy 459.487842 -290.449928) (xy 459.540344 -290.434438)
			(xy 459.59452 -290.426613) (xy 459.62189 -290.42614) (xy 459.649147 -290.426506) (xy 459.703106 -290.434263)
			(xy 459.755411 -290.44962) (xy 459.804999 -290.472265) (xy 459.850859 -290.501736) (xy 459.892058 -290.537435)
			(xy 459.927758 -290.578633) (xy 459.95723 -290.624492) (xy 459.979876 -290.674079) (xy 459.995235 -290.726385)
			(xy 460.002993 -290.780343) (xy 460.002993 -290.834857) (xy 459.995235 -290.888815) (xy 459.979876 -290.941121)
			(xy 459.95723 -290.990708) (xy 459.927758 -291.036567) (xy 459.892058 -291.077765) (xy 459.850859 -291.113464)
			(xy 459.804999 -291.142935) (xy 459.755411 -291.16558) (xy 459.703106 -291.180937) (xy 459.649147 -291.188694)
			(xy 459.62189 -291.189156) (xy 459.594519 -291.188707) (xy 459.540339 -291.180886) (xy 459.487835 -291.165394)
			(xy 459.438088 -291.142548) (xy 459.392123 -291.112819) (xy 459.371192 -291.095176) (xy 459.36408 -291.08908)
			(xy 459.347062 -291.08273) (xy 459.261718 -291.08273) (xy 459.2447 -291.08908) (xy 459.237588 -291.095176)
			(xy 459.21663 -291.112784) (xy 459.170665 -291.142501) (xy 459.120924 -291.165343) (xy 459.068429 -291.180842)
			(xy 459.014257 -291.188678) (xy 458.98689 -291.189156) (xy 458.959643 -291.188573) (xy 458.905703 -291.180816)
			(xy 458.853416 -291.165462) (xy 458.803846 -291.142824) (xy 458.758003 -291.113361) (xy 458.716819 -291.077674)
			(xy 458.681133 -291.036489) (xy 458.651672 -290.990645) (xy 458.629034 -290.941075) (xy 458.613681 -290.888787)
			(xy 458.605926 -290.834847) (xy 448.846194 -290.834847) (xy 448.846194 -291.574054) (xy 452.196643 -291.574054)
			(xy 452.196643 -291.519546) (xy 452.2044 -291.465593) (xy 452.219757 -291.413292) (xy 452.242401 -291.36371)
			(xy 452.271871 -291.317855) (xy 452.307566 -291.276661) (xy 452.348761 -291.240966) (xy 452.394617 -291.211497)
			(xy 452.4442 -291.188854) (xy 452.4965 -291.173499) (xy 452.550454 -291.165742) (xy 452.577708 -291.16528)
			(xy 452.605079 -291.165722) (xy 452.65926 -291.173543) (xy 452.711764 -291.189036) (xy 452.761511 -291.211884)
			(xy 452.807476 -291.241615) (xy 452.828406 -291.25926) (xy 452.835518 -291.265356) (xy 452.852536 -291.271706)
			(xy 452.93788 -291.271706) (xy 452.954898 -291.265356) (xy 452.96201 -291.25926) (xy 452.982922 -291.241596)
			(xy 453.028901 -291.211889) (xy 453.078654 -291.189059) (xy 453.131158 -291.173573) (xy 453.185338 -291.165751)
			(xy 453.212708 -291.16528) (xy 453.239958 -291.165791) (xy 453.293903 -291.173548) (xy 453.346195 -291.188903)
			(xy 453.39577 -291.211544) (xy 453.441618 -291.24101) (xy 453.482806 -291.2767) (xy 453.518495 -291.317889)
			(xy 453.54796 -291.363737) (xy 453.5706 -291.413312) (xy 453.585954 -291.465605) (xy 453.59371 -291.51955)
			(xy 453.59371 -291.57405) (xy 453.585954 -291.627995) (xy 453.5706 -291.680288) (xy 453.54796 -291.729863)
			(xy 453.518495 -291.775711) (xy 453.482806 -291.8169) (xy 453.441618 -291.85259) (xy 453.39577 -291.882056)
			(xy 453.346195 -291.904697) (xy 453.293903 -291.920052) (xy 453.239958 -291.927809) (xy 453.212708 -291.928296)
			(xy 453.185338 -291.927826) (xy 453.131159 -291.920009) (xy 453.078656 -291.904521) (xy 453.028909 -291.88168)
			(xy 452.982942 -291.851957) (xy 452.96201 -291.834316) (xy 452.954898 -291.82822) (xy 452.93788 -291.82187)
			(xy 452.852536 -291.82187) (xy 452.835518 -291.82822) (xy 452.828406 -291.834316) (xy 452.807485 -291.851968)
			(xy 452.761509 -291.881678) (xy 452.711758 -291.904511) (xy 452.659255 -291.919999) (xy 452.605078 -291.927824)
			(xy 452.577708 -291.928296) (xy 452.550454 -291.927858) (xy 452.4965 -291.920101) (xy 452.4442 -291.904746)
			(xy 452.394617 -291.882103) (xy 452.348761 -291.852634) (xy 452.307566 -291.816939) (xy 452.271871 -291.775745)
			(xy 452.242401 -291.72989) (xy 452.219757 -291.680308) (xy 452.2044 -291.628007) (xy 452.196643 -291.574054)
			(xy 448.846194 -291.574054) (xy 448.846194 -305.500786) (xy 448.846602 -305.510439) (xy 448.853749 -305.528371)
			(xy 448.86706 -305.542352) (xy 448.875658 -305.54676) (xy 448.949441 -305.581642) (xy 449.093925 -305.657579)
			(xy 449.234572 -305.740405) (xy 449.371057 -305.829925) (xy 449.503059 -305.925932) (xy 449.630272 -306.0282)
			(xy 449.752398 -306.136492) (xy 449.775075 -306.158646) (xy 459.899002 -306.158646) (xy 459.903073 -306.103024)
			(xy 459.915199 -306.048587) (xy 459.935122 -305.996496) (xy 459.962418 -305.947861) (xy 459.996504 -305.903718)
			(xy 460.036653 -305.865009) (xy 460.082011 -305.832558) (xy 460.131611 -305.807057) (xy 460.184395 -305.78905)
			(xy 460.239238 -305.77892) (xy 460.294972 -305.776883) (xy 460.350409 -305.782983) (xy 460.404366 -305.797089)
			(xy 460.455695 -305.818901) (xy 460.503301 -305.847955) (xy 460.546169 -305.88363) (xy 460.583386 -305.925167)
			(xy 460.614159 -305.97168) (xy 460.637831 -306.022177) (xy 460.653899 -306.075584) (xy 460.662019 -306.13076)
			(xy 460.662528 -306.158646) (xy 460.662019 -306.186532) (xy 460.653899 -306.241708) (xy 460.637831 -306.295115)
			(xy 460.614159 -306.345612) (xy 460.583386 -306.392125) (xy 460.546169 -306.433662) (xy 460.503301 -306.469337)
			(xy 460.455695 -306.498391) (xy 460.404366 -306.520203) (xy 460.350409 -306.534309) (xy 460.294972 -306.540409)
			(xy 460.239238 -306.538372) (xy 460.184395 -306.528242) (xy 460.131611 -306.510235) (xy 460.082011 -306.484734)
			(xy 460.036653 -306.452283) (xy 459.996504 -306.413574) (xy 459.962418 -306.369431) (xy 459.935122 -306.320796)
			(xy 459.915199 -306.268705) (xy 459.903073 -306.214268) (xy 459.899002 -306.158646) (xy 449.775075 -306.158646)
			(xy 449.869152 -306.250555) (xy 449.980262 -306.370123) (xy 450.085469 -306.494917) (xy 450.184527 -306.624645)
			(xy 450.277206 -306.759005) (xy 450.34459 -306.86756) (xy 452.570594 -306.86756) (xy 452.574665 -306.811938)
			(xy 452.586791 -306.757501) (xy 452.606714 -306.70541) (xy 452.63401 -306.656775) (xy 452.668096 -306.612632)
			(xy 452.708245 -306.573923) (xy 452.753603 -306.541472) (xy 452.803203 -306.515971) (xy 452.855987 -306.497964)
			(xy 452.91083 -306.487834) (xy 452.966564 -306.485797) (xy 453.022001 -306.491897) (xy 453.075958 -306.506003)
			(xy 453.127287 -306.527815) (xy 453.174893 -306.556869) (xy 453.217761 -306.592544) (xy 453.254978 -306.634081)
			(xy 453.285751 -306.680594) (xy 453.309423 -306.731091) (xy 453.325491 -306.784498) (xy 453.333611 -306.839674)
			(xy 453.33412 -306.86756) (xy 453.333611 -306.895446) (xy 453.325491 -306.950622) (xy 453.309423 -307.004029)
			(xy 453.285751 -307.054526) (xy 453.254978 -307.101039) (xy 453.217761 -307.142576) (xy 453.174893 -307.178251)
			(xy 453.127287 -307.207305) (xy 453.075958 -307.229117) (xy 453.022001 -307.243223) (xy 452.966564 -307.249323)
			(xy 452.91083 -307.247286) (xy 452.855987 -307.237156) (xy 452.803203 -307.219149) (xy 452.753603 -307.193648)
			(xy 452.708245 -307.161197) (xy 452.668096 -307.122488) (xy 452.63401 -307.078345) (xy 452.606714 -307.02971)
			(xy 452.586791 -306.977619) (xy 452.574665 -306.923182) (xy 452.570594 -306.86756) (xy 450.34459 -306.86756)
			(xy 450.363288 -306.897683) (xy 450.442573 -307.040357) (xy 450.514877 -307.186692) (xy 450.58003 -307.336349)
			(xy 450.63788 -307.488976) (xy 450.664149 -307.56987) (xy 457.496162 -307.56987) (xy 457.500233 -307.514248)
			(xy 457.512359 -307.459811) (xy 457.532282 -307.40772) (xy 457.559578 -307.359085) (xy 457.593664 -307.314942)
			(xy 457.633813 -307.276233) (xy 457.679171 -307.243782) (xy 457.728771 -307.218281) (xy 457.781555 -307.200274)
			(xy 457.836398 -307.190144) (xy 457.892132 -307.188107) (xy 457.947569 -307.194207) (xy 458.001526 -307.208313)
			(xy 458.052855 -307.230125) (xy 458.100461 -307.259179) (xy 458.143329 -307.294854) (xy 458.180546 -307.336391)
			(xy 458.211319 -307.382904) (xy 458.234991 -307.433401) (xy 458.251059 -307.486808) (xy 458.259179 -307.541984)
			(xy 458.259688 -307.56987) (xy 458.259179 -307.597756) (xy 458.251059 -307.652932) (xy 458.234991 -307.706339)
			(xy 458.211319 -307.756836) (xy 458.180546 -307.803349) (xy 458.143329 -307.844886) (xy 458.100461 -307.880561)
			(xy 458.052855 -307.909615) (xy 458.001526 -307.931427) (xy 457.947569 -307.945533) (xy 457.892132 -307.951633)
			(xy 457.836398 -307.949596) (xy 457.781555 -307.939466) (xy 457.728771 -307.921459) (xy 457.679171 -307.895958)
			(xy 457.633813 -307.863507) (xy 457.593664 -307.824798) (xy 457.559578 -307.780655) (xy 457.532282 -307.73202)
			(xy 457.512359 -307.679929) (xy 457.500233 -307.625492) (xy 457.496162 -307.56987) (xy 450.664149 -307.56987)
			(xy 450.688293 -307.64422) (xy 450.731151 -307.801716) (xy 450.766354 -307.961098) (xy 450.793819 -308.121994)
			(xy 450.813483 -308.284029) (xy 450.8253 -308.446824) (xy 450.827205 -308.525672) (xy 458.554072 -308.525672)
			(xy 458.558143 -308.47005) (xy 458.570269 -308.415613) (xy 458.590192 -308.363522) (xy 458.617488 -308.314887)
			(xy 458.651574 -308.270744) (xy 458.691723 -308.232035) (xy 458.737081 -308.199584) (xy 458.786681 -308.174083)
			(xy 458.839465 -308.156076) (xy 458.894308 -308.145946) (xy 458.950042 -308.143909) (xy 459.005479 -308.150009)
			(xy 459.059436 -308.164115) (xy 459.110765 -308.185927) (xy 459.158371 -308.214981) (xy 459.201239 -308.250656)
			(xy 459.238456 -308.292193) (xy 459.269229 -308.338706) (xy 459.292901 -308.389203) (xy 459.308969 -308.44261)
			(xy 459.317089 -308.497786) (xy 459.317598 -308.525672) (xy 459.317089 -308.553558) (xy 459.308969 -308.608734)
			(xy 459.292901 -308.662141) (xy 459.269229 -308.712638) (xy 459.238456 -308.759151) (xy 459.201239 -308.800688)
			(xy 459.158371 -308.836363) (xy 459.110765 -308.865417) (xy 459.059436 -308.887229) (xy 459.005479 -308.901335)
			(xy 458.950042 -308.907435) (xy 458.894308 -308.905398) (xy 458.839465 -308.895268) (xy 458.786681 -308.877261)
			(xy 458.737081 -308.85176) (xy 458.691723 -308.819309) (xy 458.651574 -308.7806) (xy 458.617488 -308.736457)
			(xy 458.590192 -308.687822) (xy 458.570269 -308.635731) (xy 458.558143 -308.581294) (xy 458.554072 -308.525672)
			(xy 450.827205 -308.525672) (xy 450.829242 -308.61) (xy 450.8253 -308.773176) (xy 450.813483 -308.935971)
			(xy 450.793819 -309.098006) (xy 450.786374 -309.141622) (xy 460.562196 -309.141622) (xy 460.566267 -309.086)
			(xy 460.578393 -309.031563) (xy 460.598316 -308.979472) (xy 460.625612 -308.930837) (xy 460.659698 -308.886694)
			(xy 460.699847 -308.847985) (xy 460.745205 -308.815534) (xy 460.794805 -308.790033) (xy 460.847589 -308.772026)
			(xy 460.902432 -308.761896) (xy 460.958166 -308.759859) (xy 461.013603 -308.765959) (xy 461.06756 -308.780065)
			(xy 461.118889 -308.801877) (xy 461.166495 -308.830931) (xy 461.209363 -308.866606) (xy 461.24658 -308.908143)
			(xy 461.277353 -308.954656) (xy 461.301025 -309.005153) (xy 461.317093 -309.05856) (xy 461.325213 -309.113736)
			(xy 461.325722 -309.141622) (xy 461.325213 -309.169508) (xy 461.317093 -309.224684) (xy 461.301025 -309.278091)
			(xy 461.277353 -309.328588) (xy 461.24658 -309.375101) (xy 461.209363 -309.416638) (xy 461.166495 -309.452313)
			(xy 461.118889 -309.481367) (xy 461.06756 -309.503179) (xy 461.013603 -309.517285) (xy 460.958166 -309.523385)
			(xy 460.902432 -309.521348) (xy 460.847589 -309.511218) (xy 460.794805 -309.493211) (xy 460.745205 -309.46771)
			(xy 460.699847 -309.435259) (xy 460.659698 -309.39655) (xy 460.625612 -309.352407) (xy 460.598316 -309.303772)
			(xy 460.578393 -309.251681) (xy 460.566267 -309.197244) (xy 460.562196 -309.141622) (xy 450.786374 -309.141622)
			(xy 450.766354 -309.258902) (xy 450.731151 -309.418284) (xy 450.688293 -309.57578) (xy 450.63788 -309.731024)
			(xy 450.58003 -309.883651) (xy 450.515493 -310.031892) (xy 456.942188 -310.031892) (xy 456.946259 -309.97627)
			(xy 456.958385 -309.921833) (xy 456.978308 -309.869742) (xy 457.005604 -309.821107) (xy 457.03969 -309.776964)
			(xy 457.079839 -309.738255) (xy 457.125197 -309.705804) (xy 457.174797 -309.680303) (xy 457.227581 -309.662296)
			(xy 457.282424 -309.652166) (xy 457.338158 -309.650129) (xy 457.393595 -309.656229) (xy 457.447552 -309.670335)
			(xy 457.498881 -309.692147) (xy 457.546487 -309.721201) (xy 457.589355 -309.756876) (xy 457.626572 -309.798413)
			(xy 457.657345 -309.844926) (xy 457.668429 -309.86857) (xy 458.657704 -309.86857) (xy 458.661775 -309.812948)
			(xy 458.673901 -309.758511) (xy 458.693824 -309.70642) (xy 458.72112 -309.657785) (xy 458.755206 -309.613642)
			(xy 458.795355 -309.574933) (xy 458.840713 -309.542482) (xy 458.890313 -309.516981) (xy 458.943097 -309.498974)
			(xy 458.99794 -309.488844) (xy 459.053674 -309.486807) (xy 459.109111 -309.492907) (xy 459.163068 -309.507013)
			(xy 459.214397 -309.528825) (xy 459.262003 -309.557879) (xy 459.304871 -309.593554) (xy 459.342088 -309.635091)
			(xy 459.372861 -309.681604) (xy 459.396533 -309.732101) (xy 459.412601 -309.785508) (xy 459.420721 -309.840684)
			(xy 459.42123 -309.86857) (xy 459.420721 -309.896456) (xy 459.412601 -309.951632) (xy 459.396533 -310.005039)
			(xy 459.372861 -310.055536) (xy 459.342088 -310.102049) (xy 459.304871 -310.143586) (xy 459.262003 -310.179261)
			(xy 459.214397 -310.208315) (xy 459.163068 -310.230127) (xy 459.109111 -310.244233) (xy 459.053674 -310.250333)
			(xy 458.99794 -310.248296) (xy 458.943097 -310.238166) (xy 458.890313 -310.220159) (xy 458.840713 -310.194658)
			(xy 458.795355 -310.162207) (xy 458.755206 -310.123498) (xy 458.72112 -310.079355) (xy 458.693824 -310.03072)
			(xy 458.673901 -309.978629) (xy 458.661775 -309.924192) (xy 458.657704 -309.86857) (xy 457.668429 -309.86857)
			(xy 457.681017 -309.895423) (xy 457.697085 -309.94883) (xy 457.705205 -310.004006) (xy 457.705714 -310.031892)
			(xy 457.705205 -310.059778) (xy 457.697085 -310.114954) (xy 457.681017 -310.168361) (xy 457.657345 -310.218858)
			(xy 457.626572 -310.265371) (xy 457.589355 -310.306908) (xy 457.546487 -310.342583) (xy 457.498881 -310.371637)
			(xy 457.447552 -310.393449) (xy 457.393595 -310.407555) (xy 457.338158 -310.413655) (xy 457.282424 -310.411618)
			(xy 457.227581 -310.401488) (xy 457.174797 -310.383481) (xy 457.125197 -310.35798) (xy 457.079839 -310.325529)
			(xy 457.03969 -310.28682) (xy 457.005604 -310.242677) (xy 456.978308 -310.194042) (xy 456.958385 -310.141951)
			(xy 456.946259 -310.087514) (xy 456.942188 -310.031892) (xy 450.515493 -310.031892) (xy 450.514877 -310.033308)
			(xy 450.442573 -310.179643) (xy 450.363288 -310.322317) (xy 450.277206 -310.460995) (xy 450.184527 -310.595355)
			(xy 450.085469 -310.725083) (xy 449.980262 -310.849877) (xy 449.869152 -310.969445) (xy 449.752398 -311.083508)
			(xy 449.630272 -311.1918) (xy 449.503059 -311.294068) (xy 449.440965 -311.33923) (xy 458.119986 -311.33923)
			(xy 458.124057 -311.283608) (xy 458.136183 -311.229171) (xy 458.156106 -311.17708) (xy 458.183402 -311.128445)
			(xy 458.217488 -311.084302) (xy 458.257637 -311.045593) (xy 458.302995 -311.013142) (xy 458.352595 -310.987641)
			(xy 458.405379 -310.969634) (xy 458.460222 -310.959504) (xy 458.515956 -310.957467) (xy 458.571393 -310.963567)
			(xy 458.62535 -310.977673) (xy 458.676679 -310.999485) (xy 458.724285 -311.028539) (xy 458.767153 -311.064214)
			(xy 458.80437 -311.105751) (xy 458.835143 -311.152264) (xy 458.858815 -311.202761) (xy 458.874883 -311.256168)
			(xy 458.883003 -311.311344) (xy 458.883512 -311.33923) (xy 458.883003 -311.367116) (xy 458.874883 -311.422292)
			(xy 458.858815 -311.475699) (xy 458.842059 -311.511442) (xy 459.73441 -311.511442) (xy 459.738481 -311.45582)
			(xy 459.750607 -311.401383) (xy 459.77053 -311.349292) (xy 459.797826 -311.300657) (xy 459.831912 -311.256514)
			(xy 459.872061 -311.217805) (xy 459.917419 -311.185354) (xy 459.967019 -311.159853) (xy 460.019803 -311.141846)
			(xy 460.074646 -311.131716) (xy 460.13038 -311.129679) (xy 460.185817 -311.135779) (xy 460.239774 -311.149885)
			(xy 460.291103 -311.171697) (xy 460.338709 -311.200751) (xy 460.381577 -311.236426) (xy 460.418794 -311.277963)
			(xy 460.449567 -311.324476) (xy 460.473239 -311.374973) (xy 460.489307 -311.42838) (xy 460.497427 -311.483556)
			(xy 460.497936 -311.511442) (xy 460.497427 -311.539328) (xy 460.489307 -311.594504) (xy 460.473239 -311.647911)
			(xy 460.449567 -311.698408) (xy 460.418794 -311.744921) (xy 460.381577 -311.786458) (xy 460.338709 -311.822133)
			(xy 460.291103 -311.851187) (xy 460.239774 -311.872999) (xy 460.185817 -311.887105) (xy 460.13038 -311.893205)
			(xy 460.074646 -311.891168) (xy 460.019803 -311.881038) (xy 459.967019 -311.863031) (xy 459.917419 -311.83753)
			(xy 459.872061 -311.805079) (xy 459.831912 -311.76637) (xy 459.797826 -311.722227) (xy 459.77053 -311.673592)
			(xy 459.750607 -311.621501) (xy 459.738481 -311.567064) (xy 459.73441 -311.511442) (xy 458.842059 -311.511442)
			(xy 458.835143 -311.526196) (xy 458.80437 -311.572709) (xy 458.767153 -311.614246) (xy 458.724285 -311.649921)
			(xy 458.676679 -311.678975) (xy 458.62535 -311.700787) (xy 458.571393 -311.714893) (xy 458.515956 -311.720993)
			(xy 458.460222 -311.718956) (xy 458.405379 -311.708826) (xy 458.352595 -311.690819) (xy 458.302995 -311.665318)
			(xy 458.257637 -311.632867) (xy 458.217488 -311.594158) (xy 458.183402 -311.550015) (xy 458.156106 -311.50138)
			(xy 458.136183 -311.449289) (xy 458.124057 -311.394852) (xy 458.119986 -311.33923) (xy 449.440965 -311.33923)
			(xy 449.371057 -311.390075) (xy 449.234572 -311.479595) (xy 449.093925 -311.562421) (xy 448.949441 -311.638358)
			(xy 448.875658 -311.67324) (xy 448.867103 -311.677692) (xy 448.853864 -311.691696) (xy 448.84669 -311.709581)
			(xy 448.846194 -311.719214) (xy 448.846194 -320.940176) (xy 455.509122 -320.940176) (xy 455.509569 -320.912805)
			(xy 455.51739 -320.858625) (xy 455.532884 -320.806121) (xy 455.55573 -320.756375) (xy 455.585459 -320.710409)
			(xy 455.603102 -320.689478) (xy 455.609198 -320.682366) (xy 455.615548 -320.665348) (xy 455.615548 -320.580004)
			(xy 455.609198 -320.562986) (xy 455.603102 -320.555874) (xy 455.585484 -320.534925) (xy 455.555769 -320.488957)
			(xy 455.532929 -320.439213) (xy 455.517433 -320.386717) (xy 455.509599 -320.332544) (xy 455.509122 -320.305176)
			(xy 455.509533 -320.277921) (xy 455.517294 -320.223967) (xy 455.532654 -320.171666) (xy 455.555302 -320.122084)
			(xy 455.584775 -320.076229) (xy 455.620474 -320.035036) (xy 455.661673 -319.999343) (xy 455.707531 -319.969876)
			(xy 455.757117 -319.947235) (xy 455.80942 -319.931882) (xy 455.863375 -319.924129) (xy 455.89063 -319.923668)
			(xy 455.918002 -319.9241) (xy 455.972183 -319.931923) (xy 456.024687 -319.94742) (xy 456.074433 -319.970269)
			(xy 456.120398 -320.000002) (xy 456.141328 -320.017648) (xy 456.14844 -320.023744) (xy 456.165458 -320.030094)
			(xy 456.250802 -320.030094) (xy 456.26782 -320.023744) (xy 456.274932 -320.017648) (xy 456.295865 -320.000007)
			(xy 456.341833 -319.970283) (xy 456.391579 -319.947437) (xy 456.444081 -319.931941) (xy 456.498259 -319.924112)
			(xy 456.553001 -319.924112) (xy 456.607179 -319.931941) (xy 456.659681 -319.947437) (xy 456.709427 -319.970283)
			(xy 456.755395 -320.000007) (xy 456.776328 -320.017648) (xy 456.78344 -320.023744) (xy 456.800458 -320.030094)
			(xy 456.885802 -320.030094) (xy 456.90282 -320.023744) (xy 456.909932 -320.017648) (xy 456.930885 -320.000035)
			(xy 456.976851 -319.970317) (xy 457.026593 -319.947476) (xy 457.07909 -319.931979) (xy 457.133262 -319.924145)
			(xy 457.16063 -319.923668) (xy 457.187881 -319.92415) (xy 457.241828 -319.93191) (xy 457.294121 -319.947268)
			(xy 457.343697 -319.96991) (xy 457.389546 -319.999378) (xy 457.430735 -320.035069) (xy 457.466426 -320.076259)
			(xy 457.495892 -320.122109) (xy 457.518535 -320.171685) (xy 457.533891 -320.223978) (xy 457.541651 -320.277925)
			(xy 457.542138 -320.305176) (xy 457.541673 -320.332546) (xy 457.533857 -320.386726) (xy 457.518369 -320.43923)
			(xy 457.495526 -320.488977) (xy 457.4658 -320.534943) (xy 457.448158 -320.555874) (xy 457.442062 -320.562986)
			(xy 457.435712 -320.580004) (xy 457.435712 -320.665348) (xy 457.442062 -320.682366) (xy 457.448158 -320.689478)
			(xy 457.465794 -320.710413) (xy 457.495507 -320.756384) (xy 457.518345 -320.806131) (xy 457.533836 -320.858631)
			(xy 457.541664 -320.912807) (xy 457.542138 -320.940176) (xy 457.5416 -320.967425) (xy 457.533847 -321.021369)
			(xy 457.518496 -321.073661) (xy 457.49586 -321.123236) (xy 457.466399 -321.169085) (xy 457.430713 -321.210275)
			(xy 457.389529 -321.245967) (xy 457.343684 -321.275434) (xy 457.294112 -321.298078) (xy 457.241822 -321.313436)
			(xy 457.187879 -321.321196) (xy 457.16063 -321.321684) (xy 457.13326 -321.321204) (xy 457.079082 -321.31339)
			(xy 457.026578 -321.297905) (xy 456.976831 -321.275066) (xy 456.930864 -321.245344) (xy 456.909932 -321.227704)
			(xy 456.90282 -321.221608) (xy 456.885802 -321.215258) (xy 456.800458 -321.215258) (xy 456.78344 -321.221608)
			(xy 456.776328 -321.227704) (xy 456.755395 -321.245345) (xy 456.709427 -321.275069) (xy 456.659681 -321.297915)
			(xy 456.607179 -321.313411) (xy 456.553001 -321.32124) (xy 456.498259 -321.32124) (xy 456.444081 -321.313411)
			(xy 456.391579 -321.297915) (xy 456.341833 -321.275069) (xy 456.295865 -321.245345) (xy 456.274932 -321.227704)
			(xy 456.26782 -321.221608) (xy 456.250802 -321.215258) (xy 456.165458 -321.215258) (xy 456.14844 -321.221608)
			(xy 456.141328 -321.227704) (xy 456.120397 -321.245344) (xy 456.074424 -321.275056) (xy 456.024676 -321.297891)
			(xy 455.972175 -321.313382) (xy 455.917999 -321.32121) (xy 455.89063 -321.321684) (xy 455.863377 -321.321217)
			(xy 455.809425 -321.313463) (xy 455.757126 -321.29811) (xy 455.707544 -321.275469) (xy 455.661689 -321.246002)
			(xy 455.620496 -321.210308) (xy 455.584802 -321.169115) (xy 455.555334 -321.123261) (xy 455.532692 -321.07368)
			(xy 455.517338 -321.021381) (xy 455.509584 -320.967429) (xy 455.509122 -320.940176) (xy 448.846194 -320.940176)
			(xy 448.846194 -321.245992) (xy 448.846615 -321.256063) (xy 448.854327 -321.27467) (xy 448.86118 -321.28206)
			(xy 449.13042 -321.5513) (xy 449.13782 -321.558143) (xy 449.156418 -321.56587) (xy 449.166488 -321.566286)
		)
		(stroke
			(width 0)
			(type solid)
		)
		(fill yes)
		(layer "In15.Cu")
		(net "GND")
	)
	(gr_poly
		(pts
			(xy 213.72322 -135.397748) (xy 213.733098 -135.397289) (xy 213.7514 -135.38985) (xy 213.75878 -135.38327)
			(xy 213.759034 -135.383016) (xy 216.229184 -132.912866) (xy 216.235857 -132.905454) (xy 216.243434 -132.887028)
			(xy 216.243421 -132.867105) (xy 216.235818 -132.848689) (xy 216.229184 -132.841238) (xy 213.200996 -129.81305)
			(xy 213.194158 -129.805649) (xy 213.186442 -129.787051) (xy 213.18601 -129.776982) (xy 213.18601 -129.647442)
			(xy 213.176866 -129.61874) (xy 213.172802 -129.612898) (xy 213.160851 -129.594063) (xy 213.14195 -129.553659)
			(xy 213.129131 -129.510935) (xy 213.122668 -129.466799) (xy 213.122256 -129.444496) (xy 213.122256 -115.75796)
			(xy 213.12171 -115.747977) (xy 213.113982 -115.729559) (xy 213.10727 -115.722146) (xy 212.679788 -115.294664)
			(xy 212.672392 -115.287813) (xy 212.653793 -115.280073) (xy 212.64372 -115.279678) (xy 209.902044 -115.279678)
			(xy 209.889307 -115.280374) (xy 209.866898 -115.292495) (xy 209.859372 -115.302792) (xy 209.813144 -115.37442)
			(xy 209.808802 -115.381664) (xy 209.804704 -115.398039) (xy 209.806158 -115.414856) (xy 209.809334 -115.42268)
			(xy 209.809334 -115.422934) (xy 209.819835 -115.447534) (xy 209.834639 -115.498933) (xy 209.842139 -115.551892)
			(xy 209.842608 -115.578636) (xy 209.842608 -115.583462) (xy 209.841796 -115.610488) (xy 209.833486 -115.663915)
			(xy 209.817717 -115.715633) (xy 209.794805 -115.764606) (xy 209.765208 -115.809855) (xy 209.729519 -115.850472)
			(xy 209.688454 -115.885644) (xy 209.642835 -115.914666) (xy 209.593575 -115.936957) (xy 209.541661 -115.952071)
			(xy 209.488134 -115.959704) (xy 209.434066 -115.959704) (xy 209.380539 -115.952071) (xy 209.328625 -115.936957)
			(xy 209.279365 -115.914666) (xy 209.233746 -115.885644) (xy 209.192681 -115.850472) (xy 209.156992 -115.809855)
			(xy 209.127395 -115.764606) (xy 209.104483 -115.715633) (xy 209.088714 -115.663915) (xy 209.080404 -115.610488)
			(xy 209.079592 -115.583462) (xy 209.079592 -115.578636) (xy 209.080037 -115.551889) (xy 209.087512 -115.498922)
			(xy 209.102333 -115.447523) (xy 209.112866 -115.422934) (xy 209.112866 -115.42268) (xy 209.11737 -115.410786)
			(xy 209.115364 -115.385465) (xy 209.109056 -115.37442) (xy 209.062828 -115.302792) (xy 209.057966 -115.295858)
			(xy 209.044631 -115.285433) (xy 209.02862 -115.279943) (xy 209.020156 -115.279678) (xy 206.230982 -115.279678)
			(xy 206.206344 -115.295172) (xy 206.199994 -115.308888) (xy 206.188061 -115.333044) (xy 206.158411 -115.378028)
			(xy 206.122727 -115.418394) (xy 206.08172 -115.453338) (xy 206.036204 -115.482166) (xy 205.987086 -115.504304)
			(xy 205.935342 -115.519312) (xy 205.882 -115.526891) (xy 205.828124 -115.526891) (xy 205.774782 -115.519312)
			(xy 205.723038 -115.504304) (xy 205.67392 -115.482166) (xy 205.628404 -115.453338) (xy 205.587397 -115.418394)
			(xy 205.551713 -115.378028) (xy 205.522063 -115.333044) (xy 205.51013 -115.308888) (xy 205.50378 -115.295172)
			(xy 205.479142 -115.279678) (xy 204.623924 -115.279678) (xy 204.613898 -115.280093) (xy 204.595369 -115.287758)
			(xy 204.581184 -115.30193) (xy 204.573502 -115.320452) (xy 204.573124 -115.330478) (xy 204.573124 -115.866447)
			(xy 206.842418 -115.866447) (xy 206.842418 -115.811953) (xy 206.850173 -115.758015) (xy 206.865524 -115.705729)
			(xy 206.88816 -115.65616) (xy 206.917619 -115.610316) (xy 206.953303 -115.569131) (xy 206.994484 -115.533443)
			(xy 207.040324 -115.503979) (xy 207.089891 -115.481338) (xy 207.142176 -115.465981) (xy 207.196114 -115.458221)
			(xy 207.22336 -115.457732) (xy 207.252276 -115.458267) (xy 207.309447 -115.466991) (xy 207.364646 -115.484245)
			(xy 207.416609 -115.509633) (xy 207.464143 -115.542574) (xy 207.50616 -115.582313) (xy 207.52435 -115.604798)
			(xy 207.531938 -115.613533) (xy 207.552677 -115.623731) (xy 207.564228 -115.624356) (xy 207.644492 -115.624356)
			(xy 207.656062 -115.623796) (xy 207.676834 -115.613596) (xy 207.68437 -115.604798) (xy 207.702577 -115.582328)
			(xy 207.744594 -115.542592) (xy 207.792125 -115.509652) (xy 207.844083 -115.484261) (xy 207.899278 -115.467002)
			(xy 207.956445 -115.458269) (xy 207.98536 -115.457732) (xy 208.012618 -115.458112) (xy 208.066579 -115.465865)
			(xy 208.118887 -115.48122) (xy 208.168477 -115.503862) (xy 208.21434 -115.533332) (xy 208.255542 -115.56903)
			(xy 208.291244 -115.610228) (xy 208.320719 -115.656088) (xy 208.343366 -115.705676) (xy 208.358726 -115.757982)
			(xy 208.366485 -115.811942) (xy 208.366485 -115.866458) (xy 208.358726 -115.920418) (xy 208.343366 -115.972724)
			(xy 208.320719 -116.022312) (xy 208.291244 -116.068172) (xy 208.255542 -116.10937) (xy 208.21434 -116.145068)
			(xy 208.168477 -116.174538) (xy 208.118887 -116.19718) (xy 208.066579 -116.212535) (xy 208.012618 -116.220288)
			(xy 207.98536 -116.220748) (xy 207.956444 -116.220207) (xy 207.899273 -116.211485) (xy 207.844073 -116.194233)
			(xy 207.792111 -116.168846) (xy 207.744577 -116.135905) (xy 207.70256 -116.096167) (xy 207.68437 -116.073682)
			(xy 207.67682 -116.064908) (xy 207.656052 -116.054732) (xy 207.644492 -116.054124) (xy 207.564228 -116.054124)
			(xy 207.552661 -116.054702) (xy 207.531889 -116.06489) (xy 207.52435 -116.073682) (xy 207.506126 -116.096138)
			(xy 207.464114 -116.135876) (xy 207.416586 -116.168818) (xy 207.364631 -116.194212) (xy 207.309439 -116.211474)
			(xy 207.252274 -116.220209) (xy 207.22336 -116.220748) (xy 207.196114 -116.220179) (xy 207.142176 -116.212419)
			(xy 207.089891 -116.197062) (xy 207.040324 -116.174421) (xy 206.994484 -116.144957) (xy 206.953303 -116.109269)
			(xy 206.917619 -116.068084) (xy 206.88816 -116.02224) (xy 206.865524 -115.972671) (xy 206.850173 -115.920385)
			(xy 206.842418 -115.866447) (xy 204.573124 -115.866447) (xy 204.573124 -120.922034) (xy 205.550516 -120.922034)
			(xy 205.550998 -120.894664) (xy 205.558811 -120.840486) (xy 205.574297 -120.787983) (xy 205.597135 -120.738236)
			(xy 205.626856 -120.692268) (xy 205.644496 -120.671336) (xy 205.650592 -120.664224) (xy 205.656942 -120.647206)
			(xy 205.656942 -120.561862) (xy 205.650592 -120.544844) (xy 205.644496 -120.537732) (xy 205.62689 -120.516772)
			(xy 205.597166 -120.470808) (xy 205.574321 -120.421066) (xy 205.558823 -120.368568) (xy 205.550992 -120.314394)
			(xy 205.550988 -120.259657) (xy 205.558812 -120.205482) (xy 205.574303 -120.152982) (xy 205.597141 -120.103237)
			(xy 205.626859 -120.057269) (xy 205.644496 -120.036336) (xy 205.650592 -120.029224) (xy 205.656942 -120.012206)
			(xy 205.656942 -119.926862) (xy 205.650592 -119.909844) (xy 205.644496 -119.902732) (xy 205.62689 -119.881772)
			(xy 205.597166 -119.835808) (xy 205.574321 -119.786066) (xy 205.558823 -119.733568) (xy 205.550992 -119.679394)
			(xy 205.550988 -119.624657) (xy 205.558812 -119.570482) (xy 205.574303 -119.517982) (xy 205.597141 -119.468237)
			(xy 205.626859 -119.422269) (xy 205.644496 -119.401336) (xy 205.650592 -119.394224) (xy 205.656942 -119.377206)
			(xy 205.656942 -119.291862) (xy 205.650592 -119.274844) (xy 205.644496 -119.267732) (xy 205.626858 -119.246799)
			(xy 205.597146 -119.200827) (xy 205.57431 -119.151079) (xy 205.558819 -119.098579) (xy 205.55099 -119.044403)
			(xy 205.550516 -119.017034) (xy 205.551002 -118.989783) (xy 205.558758 -118.935835) (xy 205.574113 -118.88354)
			(xy 205.596755 -118.833963) (xy 205.626221 -118.788113) (xy 205.661912 -118.746922) (xy 205.703103 -118.711231)
			(xy 205.748953 -118.681765) (xy 205.79853 -118.659123) (xy 205.850825 -118.643768) (xy 205.904773 -118.636012)
			(xy 205.959275 -118.636012) (xy 206.013223 -118.643768) (xy 206.065518 -118.659123) (xy 206.115095 -118.681765)
			(xy 206.160945 -118.711231) (xy 206.202136 -118.746922) (xy 206.237827 -118.788113) (xy 206.267293 -118.833963)
			(xy 206.289935 -118.88354) (xy 206.30529 -118.935835) (xy 206.313046 -118.989783) (xy 206.313532 -119.017034)
			(xy 206.313102 -119.044406) (xy 206.308435 -119.076724) (xy 206.521812 -119.076724) (xy 206.522278 -119.049471)
			(xy 206.530032 -118.995519) (xy 206.545386 -118.94322) (xy 206.568027 -118.893639) (xy 206.597494 -118.847784)
			(xy 206.633188 -118.806591) (xy 206.674381 -118.770897) (xy 206.720235 -118.741429) (xy 206.769816 -118.718787)
			(xy 206.822115 -118.703433) (xy 206.876067 -118.695678) (xy 206.90332 -118.695216) (xy 206.929636 -118.695671)
			(xy 206.98177 -118.70289) (xy 207.032419 -118.717202) (xy 207.080621 -118.738336) (xy 207.125463 -118.765892)
			(xy 207.166094 -118.799346) (xy 207.184244 -118.818406) (xy 207.191747 -118.82583) (xy 207.211041 -118.834341)
			(xy 207.221582 -118.834916) (xy 207.296258 -118.834916) (xy 207.306806 -118.834373) (xy 207.326101 -118.825847)
			(xy 207.333596 -118.818406) (xy 207.351734 -118.79933) (xy 207.392353 -118.765851) (xy 207.437193 -118.73828)
			(xy 207.4854 -118.717141) (xy 207.536057 -118.702836) (xy 207.588201 -118.695637) (xy 207.61452 -118.695216)
			(xy 207.641774 -118.695636) (xy 207.695728 -118.703397) (xy 207.748028 -118.718756) (xy 207.79761 -118.741403)
			(xy 207.843464 -118.770875) (xy 207.884658 -118.806574) (xy 207.920351 -118.847771) (xy 207.949818 -118.893628)
			(xy 207.972459 -118.943213) (xy 207.987813 -118.995515) (xy 207.995567 -119.049469) (xy 207.996028 -119.076724)
			(xy 207.995484 -119.105052) (xy 207.987121 -119.161088) (xy 207.970565 -119.215272) (xy 207.946183 -119.266414)
			(xy 207.914508 -119.31339) (xy 207.876238 -119.355167) (xy 207.832213 -119.390828) (xy 207.808068 -119.405654)
			(xy 207.796384 -119.412512) (xy 207.783176 -119.435118) (xy 207.781398 -119.548656) (xy 207.793844 -119.57177)
			(xy 207.805274 -119.578882) (xy 207.828199 -119.593999) (xy 207.869907 -119.629718) (xy 207.906067 -119.671043)
			(xy 207.935935 -119.717122) (xy 207.958893 -119.767004) (xy 207.974469 -119.819661) (xy 207.982341 -119.874006)
			(xy 207.98282 -119.901462) (xy 207.982309 -119.928713) (xy 207.974558 -119.982662) (xy 207.959207 -120.034958)
			(xy 207.93657 -120.084537) (xy 207.907107 -120.13039) (xy 207.871418 -120.171583) (xy 207.83023 -120.207277)
			(xy 207.784381 -120.236746) (xy 207.734805 -120.25939) (xy 207.682511 -120.274747) (xy 207.628563 -120.282506)
			(xy 207.601312 -120.28297) (xy 207.573942 -120.282504) (xy 207.519762 -120.274687) (xy 207.467259 -120.259199)
			(xy 207.417512 -120.236357) (xy 207.371545 -120.206632) (xy 207.350614 -120.18899) (xy 207.343502 -120.182894)
			(xy 207.326484 -120.176544) (xy 207.24114 -120.176544) (xy 207.224122 -120.182894) (xy 207.21701 -120.18899)
			(xy 207.196084 -120.206636) (xy 207.150109 -120.236347) (xy 207.100361 -120.259182) (xy 207.047858 -120.274671)
			(xy 206.993682 -120.282497) (xy 206.966312 -120.28297) (xy 206.939058 -120.282533) (xy 206.885104 -120.274777)
			(xy 206.832803 -120.259421) (xy 206.783221 -120.236777) (xy 206.737366 -120.207306) (xy 206.696172 -120.17161)
			(xy 206.660478 -120.130414) (xy 206.631011 -120.084557) (xy 206.60837 -120.034972) (xy 206.593017 -119.982671)
			(xy 206.585265 -119.928716) (xy 206.584804 -119.901462) (xy 206.585272 -119.875526) (xy 206.592293 -119.824132)
			(xy 206.606213 -119.774163) (xy 206.626776 -119.726542) (xy 206.653603 -119.682146) (xy 206.686198 -119.641795)
			(xy 206.723961 -119.606233) (xy 206.744824 -119.59082) (xy 206.755746 -119.582946) (xy 206.766922 -119.55907)
			(xy 206.758286 -119.445532) (xy 206.743554 -119.423434) (xy 206.731616 -119.417338) (xy 206.708293 -119.405108)
			(xy 206.664963 -119.375173) (xy 206.626166 -119.339561) (xy 206.592639 -119.298948) (xy 206.56502 -119.254107)
			(xy 206.543835 -119.205892) (xy 206.529488 -119.15522) (xy 206.52225 -119.103056) (xy 206.521812 -119.076724)
			(xy 206.308435 -119.076724) (xy 206.305278 -119.098587) (xy 206.289782 -119.151091) (xy 206.266931 -119.200838)
			(xy 206.237198 -119.246802) (xy 206.219552 -119.267732) (xy 206.213456 -119.274844) (xy 206.207106 -119.291862)
			(xy 206.207106 -119.377206) (xy 206.213456 -119.394224) (xy 206.219552 -119.401336) (xy 206.237227 -119.422241)
			(xy 206.266952 -119.468213) (xy 206.289797 -119.517964) (xy 206.305291 -119.57047) (xy 206.313117 -119.624653)
			(xy 206.313113 -119.679398) (xy 206.30528 -119.73358) (xy 206.289779 -119.786084) (xy 206.266927 -119.835832)
			(xy 206.237196 -119.8818) (xy 206.219552 -119.902732) (xy 206.213456 -119.909844) (xy 206.207106 -119.926862)
			(xy 206.207106 -120.012206) (xy 206.213456 -120.029224) (xy 206.219552 -120.036336) (xy 206.237227 -120.057241)
			(xy 206.266952 -120.103213) (xy 206.289797 -120.152964) (xy 206.305291 -120.20547) (xy 206.313117 -120.259653)
			(xy 206.313113 -120.314398) (xy 206.310753 -120.330722) (xy 208.104232 -120.330722) (xy 208.104703 -120.303352)
			(xy 208.112519 -120.249173) (xy 208.128006 -120.196669) (xy 208.150847 -120.146922) (xy 208.180571 -120.100956)
			(xy 208.198212 -120.080024) (xy 208.204308 -120.072912) (xy 208.210658 -120.055894) (xy 208.210658 -119.97055)
			(xy 208.204308 -119.953532) (xy 208.198212 -119.94642) (xy 208.180571 -119.92549) (xy 208.150859 -119.879517)
			(xy 208.128023 -119.829769) (xy 208.112533 -119.777268) (xy 208.104705 -119.723091) (xy 208.104232 -119.695722)
			(xy 208.104676 -119.668468) (xy 208.112431 -119.614514) (xy 208.127786 -119.562214) (xy 208.150429 -119.512631)
			(xy 208.179898 -119.466776) (xy 208.215594 -119.425582) (xy 208.25679 -119.389888) (xy 208.302647 -119.36042)
			(xy 208.35223 -119.33778) (xy 208.404532 -119.322427) (xy 208.458486 -119.314675) (xy 208.48574 -119.314214)
			(xy 208.514863 -119.314748) (xy 208.572435 -119.32358) (xy 208.627995 -119.341064) (xy 208.680251 -119.366792)
			(xy 208.727987 -119.400166) (xy 208.770093 -119.440411) (xy 208.80559 -119.48659) (xy 208.833653 -119.53763)
			(xy 208.853629 -119.592343) (xy 208.859882 -119.620792) (xy 208.862168 -119.632476) (xy 208.876646 -119.651272)
			(xy 208.971388 -119.696992) (xy 208.99501 -119.696738) (xy 209.005932 -119.69115) (xy 209.033036 -119.677866)
			(xy 209.090393 -119.659068) (xy 209.149997 -119.649557) (xy 209.180176 -119.648986) (xy 209.207428 -119.649478)
			(xy 209.261378 -119.657231) (xy 209.313675 -119.672584) (xy 209.363254 -119.695223) (xy 209.409107 -119.724688)
			(xy 209.4503 -119.760379) (xy 209.485994 -119.801569) (xy 209.515462 -119.847419) (xy 209.538106 -119.896997)
			(xy 209.553462 -119.949293) (xy 209.56122 -120.003242) (xy 209.561684 -120.030494) (xy 209.561218 -120.057864)
			(xy 209.553401 -120.112044) (xy 209.537912 -120.164547) (xy 209.51507 -120.214294) (xy 209.485345 -120.26026)
			(xy 209.467704 -120.281192) (xy 209.461608 -120.288304) (xy 209.455258 -120.305322) (xy 209.455258 -120.390666)
			(xy 209.461608 -120.407684) (xy 209.467704 -120.414796) (xy 209.485355 -120.435718) (xy 209.515065 -120.481694)
			(xy 209.537899 -120.531444) (xy 209.553387 -120.583947) (xy 209.561212 -120.638124) (xy 209.561684 -120.665494)
			(xy 209.561239 -120.692748) (xy 209.553482 -120.746701) (xy 209.538126 -120.799) (xy 209.515482 -120.848582)
			(xy 209.486013 -120.894436) (xy 209.450317 -120.93563) (xy 209.409122 -120.971323) (xy 209.363266 -121.000791)
			(xy 209.313683 -121.023432) (xy 209.261383 -121.038786) (xy 209.20743 -121.04654) (xy 209.180176 -121.047002)
			(xy 209.151054 -121.046441) (xy 209.093484 -121.037611) (xy 209.037925 -121.020131) (xy 208.98567 -120.994406)
			(xy 208.937935 -120.961035) (xy 208.895828 -120.920794) (xy 208.86033 -120.874618) (xy 208.832266 -120.823582)
			(xy 208.812288 -120.768872) (xy 208.806034 -120.740424) (xy 208.803748 -120.72874) (xy 208.78927 -120.709944)
			(xy 208.694528 -120.664224) (xy 208.670906 -120.664478) (xy 208.659984 -120.670066) (xy 208.632878 -120.683346)
			(xy 208.575522 -120.702145) (xy 208.515919 -120.711658) (xy 208.48574 -120.71223) (xy 208.458489 -120.711708)
			(xy 208.404541 -120.703957) (xy 208.352246 -120.688607) (xy 208.302668 -120.665971) (xy 208.256815 -120.636509)
			(xy 208.215623 -120.600821) (xy 208.179928 -120.559634) (xy 208.150459 -120.513787) (xy 208.127815 -120.464212)
			(xy 208.112457 -120.411919) (xy 208.104697 -120.357973) (xy 208.104232 -120.330722) (xy 206.310753 -120.330722)
			(xy 206.30528 -120.36858) (xy 206.289779 -120.421084) (xy 206.266927 -120.470832) (xy 206.237196 -120.5168)
			(xy 206.219552 -120.537732) (xy 206.213456 -120.544844) (xy 206.207106 -120.561862) (xy 206.207106 -120.647206)
			(xy 206.213456 -120.664224) (xy 206.219552 -120.671336) (xy 206.237167 -120.692288) (xy 206.266884 -120.738254)
			(xy 206.289726 -120.787997) (xy 206.305222 -120.840493) (xy 206.313055 -120.894666) (xy 206.313532 -120.922034)
			(xy 206.313046 -120.949285) (xy 206.30529 -121.003233) (xy 206.289935 -121.055528) (xy 206.267293 -121.105105)
			(xy 206.237827 -121.150955) (xy 206.202136 -121.192146) (xy 206.160945 -121.227837) (xy 206.115095 -121.257303)
			(xy 206.065518 -121.279945) (xy 206.013223 -121.2953) (xy 205.959275 -121.303056) (xy 205.904773 -121.303056)
			(xy 205.850825 -121.2953) (xy 205.79853 -121.279945) (xy 205.748953 -121.257303) (xy 205.703103 -121.227837)
			(xy 205.661912 -121.192146) (xy 205.626221 -121.150955) (xy 205.596755 -121.105105) (xy 205.574113 -121.055528)
			(xy 205.558758 -121.003233) (xy 205.551002 -120.949285) (xy 205.550516 -120.922034) (xy 204.573124 -120.922034)
			(xy 204.573124 -122.094549) (xy 210.164198 -122.094549) (xy 210.164198 -122.040051) (xy 210.171954 -121.986109)
			(xy 210.187306 -121.933819) (xy 210.209944 -121.884247) (xy 210.239406 -121.8384) (xy 210.275093 -121.797213)
			(xy 210.316278 -121.761523) (xy 210.362122 -121.732058) (xy 210.411693 -121.709416) (xy 210.463982 -121.694059)
			(xy 210.517924 -121.6863) (xy 210.545172 -121.685812) (xy 210.572542 -121.686292) (xy 210.62672 -121.694106)
			(xy 210.679223 -121.709591) (xy 210.728971 -121.73243) (xy 210.774938 -121.762152) (xy 210.79587 -121.779792)
			(xy 210.802982 -121.785888) (xy 210.82 -121.792238) (xy 210.905344 -121.792238) (xy 210.922362 -121.785888)
			(xy 210.929474 -121.779792) (xy 210.950407 -121.762151) (xy 210.996375 -121.732427) (xy 211.046121 -121.709581)
			(xy 211.098623 -121.694085) (xy 211.152801 -121.686256) (xy 211.207543 -121.686256) (xy 211.261721 -121.694085)
			(xy 211.314223 -121.709581) (xy 211.363969 -121.732427) (xy 211.409937 -121.762151) (xy 211.43087 -121.779792)
			(xy 211.437982 -121.785888) (xy 211.455 -121.792238) (xy 211.540344 -121.792238) (xy 211.557362 -121.785888)
			(xy 211.564474 -121.779792) (xy 211.585404 -121.76215) (xy 211.631378 -121.732439) (xy 211.681126 -121.709604)
			(xy 211.733627 -121.694113) (xy 211.787803 -121.686286) (xy 211.815172 -121.685812) (xy 211.842428 -121.686233)
			(xy 211.896384 -121.693987) (xy 211.948688 -121.709342) (xy 211.998275 -121.731984) (xy 212.044134 -121.761452)
			(xy 212.085332 -121.797148) (xy 212.121031 -121.838344) (xy 212.150503 -121.884201) (xy 212.173149 -121.933785)
			(xy 212.188507 -121.986088) (xy 212.196265 -122.040044) (xy 212.196265 -122.094556) (xy 212.188507 -122.148512)
			(xy 212.173149 -122.200815) (xy 212.150503 -122.250399) (xy 212.121031 -122.296256) (xy 212.085332 -122.337452)
			(xy 212.044134 -122.373148) (xy 211.998275 -122.402616) (xy 211.948688 -122.425258) (xy 211.896384 -122.440613)
			(xy 211.842428 -122.448367) (xy 211.815172 -122.448828) (xy 211.7878 -122.448396) (xy 211.733619 -122.440573)
			(xy 211.681115 -122.425077) (xy 211.631369 -122.402227) (xy 211.585404 -122.372494) (xy 211.564474 -122.354848)
			(xy 211.557362 -122.348752) (xy 211.540344 -122.342402) (xy 211.455 -122.342402) (xy 211.437982 -122.348752)
			(xy 211.43087 -122.354848) (xy 211.409937 -122.372489) (xy 211.363969 -122.402213) (xy 211.314223 -122.425059)
			(xy 211.261721 -122.440555) (xy 211.207543 -122.448384) (xy 211.152801 -122.448384) (xy 211.098623 -122.440555)
			(xy 211.046121 -122.425059) (xy 210.996375 -122.402213) (xy 210.950407 -122.372489) (xy 210.929474 -122.354848)
			(xy 210.922362 -122.348752) (xy 210.905344 -122.342402) (xy 210.82 -122.342402) (xy 210.802982 -122.348752)
			(xy 210.79587 -122.354848) (xy 210.774916 -122.37246) (xy 210.72895 -122.402177) (xy 210.679208 -122.425019)
			(xy 210.626712 -122.440517) (xy 210.57254 -122.448351) (xy 210.545172 -122.448828) (xy 210.517924 -122.4483)
			(xy 210.463982 -122.440541) (xy 210.411693 -122.425184) (xy 210.362122 -122.402542) (xy 210.316278 -122.373077)
			(xy 210.275093 -122.337387) (xy 210.239406 -122.2962) (xy 210.209944 -122.250353) (xy 210.187306 -122.200781)
			(xy 210.171954 -122.148491) (xy 210.164198 -122.094549) (xy 204.573124 -122.094549) (xy 204.573124 -122.972347)
			(xy 210.707522 -122.972347) (xy 210.707522 -122.917853) (xy 210.715277 -122.863913) (xy 210.730629 -122.811626)
			(xy 210.753266 -122.762057) (xy 210.782727 -122.716213) (xy 210.818412 -122.675028) (xy 210.859595 -122.63934)
			(xy 210.905437 -122.609877) (xy 210.955006 -122.587237) (xy 211.007292 -122.571882) (xy 211.061231 -122.564124)
			(xy 211.088478 -122.563636) (xy 211.116082 -122.564094) (xy 211.170715 -122.572036) (xy 211.223632 -122.587773)
			(xy 211.273727 -122.610975) (xy 211.319953 -122.641157) (xy 211.361345 -122.677689) (xy 211.397036 -122.719807)
			(xy 211.412074 -122.74296) (xy 211.420048 -122.754782) (xy 211.441213 -122.773872) (xy 211.466832 -122.786362)
			(xy 211.494906 -122.791279) (xy 211.523245 -122.78824) (xy 211.549637 -122.77748) (xy 211.572024 -122.759841)
			(xy 211.58073 -122.748548) (xy 211.596147 -122.7278) (xy 211.631687 -122.690264) (xy 211.67197 -122.657871)
			(xy 211.716258 -122.631215) (xy 211.76374 -122.610784) (xy 211.813546 -122.596953) (xy 211.864764 -122.589973)
			(xy 211.89061 -122.589544) (xy 211.917857 -122.590127) (xy 211.971797 -122.597884) (xy 212.024084 -122.613238)
			(xy 212.073654 -122.635876) (xy 212.119497 -122.665339) (xy 212.160681 -122.701026) (xy 212.196367 -122.742211)
			(xy 212.225828 -122.788055) (xy 212.248466 -122.837625) (xy 212.263819 -122.889913) (xy 212.271574 -122.943853)
			(xy 212.271574 -122.998347) (xy 212.263819 -123.052287) (xy 212.248466 -123.104575) (xy 212.225828 -123.154145)
			(xy 212.196367 -123.199989) (xy 212.160681 -123.241174) (xy 212.119497 -123.276861) (xy 212.073654 -123.306324)
			(xy 212.024084 -123.328962) (xy 211.971797 -123.344316) (xy 211.917857 -123.352073) (xy 211.89061 -123.35256)
			(xy 211.863008 -123.352036) (xy 211.808378 -123.344106) (xy 211.755463 -123.328381) (xy 211.705368 -123.30519)
			(xy 211.659141 -123.275018) (xy 211.617747 -123.238495) (xy 211.582053 -123.196385) (xy 211.567014 -123.173236)
			(xy 211.559055 -123.161403) (xy 211.537887 -123.142314) (xy 211.512265 -123.129824) (xy 211.484188 -123.124908)
			(xy 211.455847 -123.12795) (xy 211.429452 -123.138712) (xy 211.407064 -123.156354) (xy 211.398358 -123.167648)
			(xy 211.382947 -123.188401) (xy 211.347407 -123.225937) (xy 211.307123 -123.258329) (xy 211.262833 -123.284985)
			(xy 211.21535 -123.305415) (xy 211.165543 -123.319246) (xy 211.114324 -123.326223) (xy 211.088478 -123.326652)
			(xy 211.061231 -123.326076) (xy 211.007292 -123.318318) (xy 210.955006 -123.302963) (xy 210.905437 -123.280323)
			(xy 210.859595 -123.25086) (xy 210.818412 -123.215172) (xy 210.782727 -123.173987) (xy 210.753266 -123.128143)
			(xy 210.730629 -123.078574) (xy 210.715277 -123.026287) (xy 210.707522 -122.972347) (xy 204.573124 -122.972347)
			(xy 204.573124 -124.621544) (xy 211.274914 -124.621544) (xy 211.275345 -124.595227) (xy 211.282569 -124.543092)
			(xy 211.296886 -124.492443) (xy 211.318025 -124.444241) (xy 211.345584 -124.3994) (xy 211.379042 -124.358769)
			(xy 211.398104 -124.34062) (xy 211.405499 -124.333093) (xy 211.414027 -124.313817) (xy 211.414614 -124.303282)
			(xy 211.414614 -124.228606) (xy 211.414091 -124.218056) (xy 211.405551 -124.198761) (xy 211.398104 -124.191268)
			(xy 211.37901 -124.173148) (xy 211.345533 -124.132525) (xy 211.317964 -124.087681) (xy 211.296828 -124.039471)
			(xy 211.282527 -123.988811) (xy 211.275333 -123.936664) (xy 211.274914 -123.910344) (xy 211.2754 -123.883093)
			(xy 211.283156 -123.829145) (xy 211.298511 -123.77685) (xy 211.321153 -123.727273) (xy 211.350619 -123.681423)
			(xy 211.38631 -123.640232) (xy 211.427501 -123.604541) (xy 211.473351 -123.575075) (xy 211.522928 -123.552433)
			(xy 211.575223 -123.537078) (xy 211.629171 -123.529322) (xy 211.683673 -123.529322) (xy 211.737621 -123.537078)
			(xy 211.789916 -123.552433) (xy 211.839493 -123.575075) (xy 211.885343 -123.604541) (xy 211.926534 -123.640232)
			(xy 211.962225 -123.681423) (xy 211.991691 -123.727273) (xy 212.014333 -123.77685) (xy 212.029688 -123.829145)
			(xy 212.037444 -123.883093) (xy 212.03793 -123.910344) (xy 212.037476 -123.93666) (xy 212.030255 -123.988794)
			(xy 212.015941 -124.039441) (xy 211.994807 -124.087643) (xy 211.967252 -124.132485) (xy 211.9338 -124.173117)
			(xy 211.91474 -124.191268) (xy 211.907357 -124.198805) (xy 211.898821 -124.218073) (xy 211.89823 -124.228606)
			(xy 211.89823 -124.303282) (xy 211.898746 -124.313833) (xy 211.90729 -124.333129) (xy 211.91474 -124.34062)
			(xy 211.933818 -124.358757) (xy 211.967298 -124.399375) (xy 211.99487 -124.444215) (xy 212.01601 -124.492422)
			(xy 212.030314 -124.54308) (xy 212.037511 -124.595224) (xy 212.03793 -124.621544) (xy 212.037444 -124.648795)
			(xy 212.029688 -124.702743) (xy 212.014333 -124.755038) (xy 211.991691 -124.804615) (xy 211.962225 -124.850465)
			(xy 211.926534 -124.891656) (xy 211.885343 -124.927347) (xy 211.839493 -124.956813) (xy 211.789916 -124.979455)
			(xy 211.737621 -124.99481) (xy 211.683673 -125.002566) (xy 211.629171 -125.002566) (xy 211.575223 -124.99481)
			(xy 211.522928 -124.979455) (xy 211.473351 -124.956813) (xy 211.427501 -124.927347) (xy 211.38631 -124.891656)
			(xy 211.350619 -124.850465) (xy 211.321153 -124.804615) (xy 211.298511 -124.755038) (xy 211.283156 -124.702743)
			(xy 211.2754 -124.648795) (xy 211.274914 -124.621544) (xy 204.573124 -124.621544) (xy 204.573124 -126.228602)
			(xy 204.573662 -126.238589) (xy 204.581379 -126.257018) (xy 204.58811 -126.264416) (xy 207.021176 -128.697482)
			(xy 211.268308 -128.697482) (xy 211.272379 -128.64186) (xy 211.284505 -128.587423) (xy 211.304428 -128.535332)
			(xy 211.331724 -128.486697) (xy 211.36581 -128.442554) (xy 211.405959 -128.403845) (xy 211.451317 -128.371394)
			(xy 211.500917 -128.345893) (xy 211.553701 -128.327886) (xy 211.608544 -128.317756) (xy 211.664278 -128.315719)
			(xy 211.719715 -128.321819) (xy 211.773672 -128.335925) (xy 211.825001 -128.357737) (xy 211.872607 -128.386791)
			(xy 211.915475 -128.422466) (xy 211.952692 -128.464003) (xy 211.983465 -128.510516) (xy 212.007137 -128.561013)
			(xy 212.023205 -128.61442) (xy 212.031325 -128.669596) (xy 212.031834 -128.697482) (xy 212.031325 -128.725368)
			(xy 212.023205 -128.780544) (xy 212.007137 -128.833951) (xy 211.983465 -128.884448) (xy 211.952692 -128.930961)
			(xy 211.915475 -128.972498) (xy 211.872607 -129.008173) (xy 211.825001 -129.037227) (xy 211.773672 -129.059039)
			(xy 211.719715 -129.073145) (xy 211.664278 -129.079245) (xy 211.608544 -129.077208) (xy 211.553701 -129.067078)
			(xy 211.500917 -129.049071) (xy 211.451317 -129.02357) (xy 211.405959 -128.991119) (xy 211.36581 -128.95241)
			(xy 211.331724 -128.908267) (xy 211.304428 -128.859632) (xy 211.284505 -128.807541) (xy 211.272379 -128.753104)
			(xy 211.268308 -128.697482) (xy 207.021176 -128.697482) (xy 212.908896 -134.585202) (xy 212.926979 -134.603995)
			(xy 212.957604 -134.646208) (xy 212.981246 -134.692693) (xy 212.997323 -134.742305) (xy 213.005438 -134.793822)
			(xy 213.005924 -134.819898) (xy 213.005924 -135.396986) (xy 213.01456 -135.397748)
		)
		(stroke
			(width 0)
			(type solid)
		)
		(fill yes)
		(layer "In15.Cu")
		(net "GND")
	)
	(gr_poly
		(pts
			(xy 112.46993 -337.975448) (xy 112.477534 -337.973931) (xy 112.491366 -337.966943) (xy 112.497108 -337.961732)
			(xy 116.42852 -334.03032) (xy 116.435362 -334.022921) (xy 116.44308 -334.004322) (xy 116.443506 -333.994252)
			(xy 116.443506 -330.350114) (xy 116.443092 -330.34053) (xy 116.436066 -330.322695) (xy 116.423014 -330.308655)
			(xy 116.41455 -330.30414) (xy 116.331492 -330.26477) (xy 116.322723 -330.261021) (xy 116.303714 -330.259682)
			(xy 116.285542 -330.265418) (xy 116.277898 -330.27112) (xy 116.27739 -330.271628) (xy 116.277136 -330.271882)
			(xy 116.256589 -330.28814) (xy 116.211885 -330.315469) (xy 116.163864 -330.33643) (xy 116.113429 -330.350627)
			(xy 116.061526 -330.357796) (xy 116.035328 -330.358242) (xy 116.013932 -330.357913) (xy 115.971414 -330.353077)
			(xy 115.950492 -330.34859) (xy 115.943639 -330.347325) (xy 115.929729 -330.348092) (xy 115.92306 -330.350114)
			(xy 115.916481 -330.352531) (xy 115.904887 -330.360396) (xy 115.9002 -330.365608) (xy 115.842288 -330.435204)
			(xy 115.836593 -330.442687) (xy 115.830548 -330.460477) (xy 115.831317 -330.47925) (xy 115.834668 -330.488036)
			(xy 115.846389 -330.516641) (xy 115.862894 -330.576214) (xy 115.871225 -330.637467) (xy 115.871752 -330.668376)
			(xy 115.871752 -331.53223) (xy 115.871263 -331.56216) (xy 115.86346 -331.621509) (xy 115.847991 -331.679336)
			(xy 115.825119 -331.734653) (xy 115.795234 -331.78652) (xy 115.758846 -331.83405) (xy 115.716576 -331.876434)
			(xy 115.669143 -331.91295) (xy 115.617357 -331.942973) (xy 115.562101 -331.965994) (xy 115.504316 -331.981619)
			(xy 115.444988 -331.989581) (xy 115.41506 -331.990192) (xy 115.40617 -331.989938) (xy 115.369776 -331.988665)
			(xy 115.298063 -331.976025) (xy 115.263422 -331.964792) (xy 115.24488 -331.958188) (xy 115.240308 -331.95641)
			(xy 115.221766 -331.947774) (xy 115.187476 -331.930248) (xy 115.179094 -331.925422) (xy 115.169442 -331.923898)
			(xy 115.164805 -331.92336) (xy 115.155479 -331.923749) (xy 115.1509 -331.92466) (xy 115.120674 -331.931518)
			(xy 115.116006 -331.932685) (xy 115.107182 -331.936516) (xy 115.103148 -331.939138) (xy 115.096036 -331.943964)
			(xy 115.090194 -331.951584) (xy 115.08994 -331.952092) (xy 115.074521 -331.972875) (xy 115.038974 -332.010482)
			(xy 114.998668 -332.042938) (xy 114.954344 -332.069645) (xy 114.906815 -332.090114) (xy 114.856956 -332.103968)
			(xy 114.80568 -332.110953) (xy 114.779806 -332.11135) (xy 114.764312 -332.111096) (xy 114.764058 -332.111096)
			(xy 114.737559 -332.10955) (xy 114.685338 -332.10004) (xy 114.63494 -332.083382) (xy 114.587338 -332.059895)
			(xy 114.543453 -332.030036) (xy 114.504132 -331.99438) (xy 114.470135 -331.953615) (xy 114.442119 -331.908531)
			(xy 114.420625 -331.859998) (xy 114.406068 -331.808953) (xy 114.39873 -331.756382) (xy 114.398298 -331.729842)
			(xy 114.398758 -331.702587) (xy 114.406511 -331.648632) (xy 114.421863 -331.59633) (xy 114.444503 -331.546745)
			(xy 114.47397 -331.500887) (xy 114.509664 -331.459689) (xy 114.550858 -331.423992) (xy 114.596713 -331.394521)
			(xy 114.646296 -331.371876) (xy 114.698597 -331.356518) (xy 114.752551 -331.348761) (xy 114.779806 -331.348334)
			(xy 114.794599 -331.348476) (xy 114.824096 -331.350763) (xy 114.838734 -331.352906) (xy 114.849656 -331.354684)
			(xy 114.870992 -331.348588) (xy 114.938048 -331.291438) (xy 114.946072 -331.283866) (xy 114.955298 -331.26385)
			(xy 114.955828 -331.25283) (xy 114.955828 -330.94803) (xy 114.955294 -330.937008) (xy 114.946086 -330.91698)
			(xy 114.938048 -330.909422) (xy 114.870992 -330.852272) (xy 114.849656 -330.846176) (xy 114.838734 -330.847954)
			(xy 114.823908 -330.850127) (xy 114.794028 -330.852416) (xy 114.779044 -330.852526) (xy 114.77879 -330.852526)
			(xy 114.751585 -330.851971) (xy 114.697746 -330.844099) (xy 114.645571 -330.828656) (xy 114.59612 -330.805958)
			(xy 114.550395 -330.776465) (xy 114.509324 -330.740774) (xy 114.47374 -330.69961) (xy 114.444365 -330.653809)
			(xy 114.421796 -330.604298) (xy 114.406489 -330.552084) (xy 114.398756 -330.498224) (xy 114.398298 -330.471018)
			(xy 114.39876 -330.443764) (xy 114.406515 -330.389812) (xy 114.42187 -330.337512) (xy 114.444511 -330.28793)
			(xy 114.473979 -330.242075) (xy 114.509672 -330.200881) (xy 114.550866 -330.165186) (xy 114.59672 -330.135717)
			(xy 114.646301 -330.113074) (xy 114.6986 -330.097718) (xy 114.752552 -330.089961) (xy 114.779806 -330.08951)
			(xy 114.805679 -330.089941) (xy 114.85695 -330.096933) (xy 114.906806 -330.110787) (xy 114.954334 -330.13125)
			(xy 114.998661 -330.157946) (xy 115.038975 -330.190387) (xy 115.074537 -330.227976) (xy 115.08994 -330.248768)
			(xy 115.090194 -330.249276) (xy 115.096036 -330.256896) (xy 115.103148 -330.261722) (xy 115.107176 -330.264357)
			(xy 115.115999 -330.268197) (xy 115.120674 -330.269342) (xy 115.1509 -330.2762) (xy 115.155473 -330.277158)
			(xy 115.164807 -330.277546) (xy 115.169442 -330.276962) (xy 115.179094 -330.275438) (xy 115.187476 -330.270612)
			(xy 115.199706 -330.263776) (xy 115.224871 -330.251449) (xy 115.237768 -330.245974) (xy 115.268248 -330.234544)
			(xy 115.303597 -330.223399) (xy 115.376733 -330.211397) (xy 115.41379 -330.210668) (xy 115.448033 -330.211306)
			(xy 115.515754 -330.221506) (xy 115.548664 -330.230988) (xy 115.56238 -330.235306) (xy 115.590066 -330.228194)
			(xy 115.673124 -330.142342) (xy 115.67922 -330.114402) (xy 115.674648 -330.10094) (xy 115.666014 -330.074374)
			(xy 115.65572 -330.019471) (xy 115.653542 -329.963653) (xy 115.659525 -329.908115) (xy 115.673542 -329.854043)
			(xy 115.695293 -329.802592) (xy 115.724314 -329.754863) (xy 115.759985 -329.711875) (xy 115.801541 -329.674547)
			(xy 115.848097 -329.643678) (xy 115.898655 -329.619927) (xy 115.952137 -329.603801) (xy 116.007398 -329.595646)
			(xy 116.035328 -329.595226) (xy 116.064694 -329.595725) (xy 116.122741 -329.604653) (xy 116.150898 -329.613006)
			(xy 116.163598 -329.61707) (xy 116.188998 -329.61199) (xy 116.26469 -329.547982) (xy 116.271069 -329.542159)
			(xy 116.279822 -329.527281) (xy 116.28314 -329.510341) (xy 116.282216 -329.501754) (xy 116.280368 -329.488431)
			(xy 116.278334 -329.461609) (xy 116.278152 -329.44816) (xy 116.278152 -329.447652) (xy 116.277719 -329.437587)
			(xy 116.269987 -329.419) (xy 116.263166 -329.411584) (xy 115.877086 -329.025504) (xy 115.869687 -329.01866)
			(xy 115.851089 -329.01093) (xy 115.841018 -329.010518) (xy 114.26571 -329.010518) (xy 114.246914 -329.018138)
			(xy 114.239802 -329.025504) (xy 110.178342 -333.086964) (xy 111.605566 -333.086964) (xy 111.609637 -333.031342)
			(xy 111.621763 -332.976905) (xy 111.641686 -332.924814) (xy 111.668982 -332.876179) (xy 111.703068 -332.832036)
			(xy 111.743217 -332.793327) (xy 111.788575 -332.760876) (xy 111.838175 -332.735375) (xy 111.890959 -332.717368)
			(xy 111.945802 -332.707238) (xy 112.001536 -332.705201) (xy 112.056973 -332.711301) (xy 112.11093 -332.725407)
			(xy 112.162259 -332.747219) (xy 112.209865 -332.776273) (xy 112.252733 -332.811948) (xy 112.28995 -332.853485)
			(xy 112.320723 -332.899998) (xy 112.344395 -332.950495) (xy 112.360463 -333.003902) (xy 112.368583 -333.059078)
			(xy 112.369092 -333.086964) (xy 112.368583 -333.11485) (xy 112.360463 -333.170026) (xy 112.344395 -333.223433)
			(xy 112.320723 -333.27393) (xy 112.28995 -333.320443) (xy 112.252733 -333.36198) (xy 112.209865 -333.397655)
			(xy 112.162259 -333.426709) (xy 112.11093 -333.448521) (xy 112.056973 -333.462627) (xy 112.001536 -333.468727)
			(xy 111.945802 -333.46669) (xy 111.890959 -333.45656) (xy 111.838175 -333.438553) (xy 111.788575 -333.413052)
			(xy 111.743217 -333.380601) (xy 111.703068 -333.341892) (xy 111.668982 -333.297749) (xy 111.641686 -333.249114)
			(xy 111.621763 -333.197023) (xy 111.609637 -333.142586) (xy 111.605566 -333.086964) (xy 110.178342 -333.086964)
			(xy 110.019338 -333.245968) (xy 110.013123 -333.252802) (xy 110.005607 -333.269661) (xy 110.004537 -333.288088)
			(xy 110.006892 -333.297022) (xy 110.011718 -333.312516) (xy 110.015782 -333.318866) (xy 110.016036 -333.31912)
			(xy 110.031229 -333.342786) (xy 110.055249 -333.393636) (xy 110.071551 -333.447459) (xy 110.079783 -333.503091)
			(xy 110.080298 -333.53121) (xy 110.080298 -333.539338) (xy 110.079226 -333.567253) (xy 110.069916 -333.622336)
			(xy 110.05266 -333.675467) (xy 110.027828 -333.725508) (xy 109.995953 -333.771386) (xy 109.977174 -333.792068)
			(xy 109.97057 -333.79918) (xy 109.963458 -333.816706) (xy 109.963208 -333.855314) (xy 112.467134 -333.855314)
			(xy 112.471205 -333.799692) (xy 112.483331 -333.745255) (xy 112.503254 -333.693164) (xy 112.53055 -333.644529)
			(xy 112.564636 -333.600386) (xy 112.604785 -333.561677) (xy 112.650143 -333.529226) (xy 112.699743 -333.503725)
			(xy 112.752527 -333.485718) (xy 112.80737 -333.475588) (xy 112.863104 -333.473551) (xy 112.918541 -333.479651)
			(xy 112.972498 -333.493757) (xy 113.023827 -333.515569) (xy 113.071433 -333.544623) (xy 113.114301 -333.580298)
			(xy 113.151518 -333.621835) (xy 113.182291 -333.668348) (xy 113.205963 -333.718845) (xy 113.222031 -333.772252)
			(xy 113.230151 -333.827428) (xy 113.23066 -333.855314) (xy 113.230151 -333.8832) (xy 113.222031 -333.938376)
			(xy 113.205963 -333.991783) (xy 113.182291 -334.04228) (xy 113.151518 -334.088793) (xy 113.114301 -334.13033)
			(xy 113.071433 -334.166005) (xy 113.023827 -334.195059) (xy 112.972498 -334.216871) (xy 112.918541 -334.230977)
			(xy 112.863104 -334.237077) (xy 112.80737 -334.23504) (xy 112.752527 -334.22491) (xy 112.699743 -334.206903)
			(xy 112.650143 -334.181402) (xy 112.604785 -334.148951) (xy 112.564636 -334.110242) (xy 112.53055 -334.066099)
			(xy 112.503254 -334.017464) (xy 112.483331 -333.965373) (xy 112.471205 -333.910936) (xy 112.467134 -333.855314)
			(xy 109.963208 -333.855314) (xy 109.96295 -333.895192) (xy 109.96422 -333.906622) (xy 109.966506 -333.914242)
			(xy 109.970062 -333.922878) (xy 109.976158 -333.929736) (xy 109.994792 -333.950931) (xy 110.026253 -333.997783)
			(xy 110.050467 -334.048759) (xy 110.066905 -334.102746) (xy 110.075208 -334.158567) (xy 110.075726 -334.186784)
			(xy 110.07524 -334.214035) (xy 110.067484 -334.267983) (xy 110.052129 -334.320278) (xy 110.029487 -334.369855)
			(xy 110.000021 -334.415705) (xy 109.96433 -334.456896) (xy 109.923139 -334.492587) (xy 109.877289 -334.522053)
			(xy 109.827712 -334.544695) (xy 109.775417 -334.56005) (xy 109.721469 -334.567806) (xy 109.666967 -334.567806)
			(xy 109.613019 -334.56005) (xy 109.560724 -334.544695) (xy 109.511147 -334.522053) (xy 109.465297 -334.492587)
			(xy 109.424106 -334.456896) (xy 109.388415 -334.415705) (xy 109.358949 -334.369855) (xy 109.336307 -334.320278)
			(xy 109.320952 -334.267983) (xy 109.313196 -334.214035) (xy 109.31271 -334.186784) (xy 109.313232 -334.158045)
			(xy 109.321857 -334.101219) (xy 109.338909 -334.04633) (xy 109.364003 -333.994619) (xy 109.39657 -333.947259)
			(xy 109.415834 -333.925926) (xy 109.422438 -333.918814) (xy 109.42955 -333.901288) (xy 109.430058 -333.822802)
			(xy 109.428788 -333.811372) (xy 109.426502 -333.803752) (xy 109.422946 -333.795116) (xy 109.41685 -333.788258)
			(xy 109.400229 -333.769474) (xy 109.371561 -333.728316) (xy 109.3597 -333.706216) (xy 109.349794 -333.685134)
			(xy 109.343444 -333.671164) (xy 109.318552 -333.654908) (xy 104.756204 -333.654908) (xy 104.746133 -333.654486)
			(xy 104.727527 -333.646774) (xy 104.720136 -333.639922) (xy 104.04856 -332.968346) (xy 104.041715 -332.960948)
			(xy 104.033991 -332.942349) (xy 104.033574 -332.932278) (xy 104.033574 -330.489814) (xy 104.033135 -330.479751)
			(xy 104.025395 -330.461172) (xy 104.018588 -330.453746) (xy 103.48849 -329.923648) (xy 103.481093 -329.916798)
			(xy 103.462495 -329.909059) (xy 103.452422 -329.908662) (xy 100.475796 -329.908662) (xy 100.465727 -329.908237)
			(xy 100.447127 -329.900518) (xy 100.439728 -329.893676) (xy 99.220528 -328.674476) (xy 99.213129 -328.667633)
			(xy 99.19453 -328.659913) (xy 99.18446 -328.65949) (xy 97.185226 -328.65949) (xy 97.175162 -328.659926)
			(xy 97.156576 -328.667658) (xy 97.149158 -328.674476) (xy 96.726502 -329.097132) (xy 96.71966 -329.104532)
			(xy 96.711937 -329.12313) (xy 96.711516 -329.1332) (xy 96.711516 -330.416662) (xy 97.355152 -330.416662)
			(xy 97.355152 -329.553062) (xy 97.355593 -329.523076) (xy 97.363425 -329.463618) (xy 97.378951 -329.405691)
			(xy 97.401905 -329.350287) (xy 97.431894 -329.298352) (xy 97.468406 -329.250775) (xy 97.510814 -329.208371)
			(xy 97.558395 -329.171865) (xy 97.610333 -329.141882) (xy 97.665741 -329.118934) (xy 97.723669 -329.103415)
			(xy 97.783128 -329.095589) (xy 97.813114 -329.0951) (xy 97.842756 -329.095621) (xy 97.901537 -329.103334)
			(xy 97.958836 -329.118554) (xy 98.013697 -329.141027) (xy 98.039682 -329.155298) (xy 98.048094 -329.159547)
			(xy 98.066725 -329.162278) (xy 98.076004 -329.160632) (xy 98.10623 -329.153774) (xy 98.115222 -329.151344)
			(xy 98.130728 -329.141053) (xy 98.136456 -329.133708) (xy 98.151889 -329.112868) (xy 98.187456 -329.075131)
			(xy 98.22781 -329.042564) (xy 98.272206 -329.015767) (xy 98.319824 -328.995235) (xy 98.369786 -328.981346)
			(xy 98.42117 -328.974358) (xy 98.447098 -328.973942) (xy 98.474355 -328.974305) (xy 98.528313 -328.982063)
			(xy 98.580618 -328.99742) (xy 98.630205 -329.020066) (xy 98.676064 -329.049538) (xy 98.717263 -329.085236)
			(xy 98.752961 -329.126434) (xy 98.782433 -329.172293) (xy 98.805079 -329.22188) (xy 98.820437 -329.274185)
			(xy 98.828195 -329.328143) (xy 98.828195 -329.382657) (xy 98.820437 -329.436615) (xy 98.805079 -329.48892)
			(xy 98.782433 -329.538507) (xy 98.752961 -329.584366) (xy 98.717263 -329.625564) (xy 98.676064 -329.661262)
			(xy 98.630205 -329.690734) (xy 98.580618 -329.71338) (xy 98.528313 -329.728737) (xy 98.474355 -329.736495)
			(xy 98.447098 -329.736958) (xy 98.432305 -329.736825) (xy 98.402807 -329.734535) (xy 98.38817 -329.732386)
			(xy 98.377248 -329.730608) (xy 98.355912 -329.736704) (xy 98.288602 -329.794108) (xy 98.280632 -329.801698)
			(xy 98.271549 -329.82172) (xy 98.271076 -329.832716) (xy 98.271076 -330.25588) (xy 98.271626 -330.267088)
			(xy 98.281115 -330.28739) (xy 98.289364 -330.294996) (xy 98.358198 -330.352146) (xy 98.380042 -330.357734)
			(xy 98.391218 -330.355702) (xy 98.408645 -330.352623) (xy 98.443881 -330.349311) (xy 98.461576 -330.349098)
			(xy 98.48883 -330.349548) (xy 98.542785 -330.357302) (xy 98.595086 -330.372656) (xy 98.64467 -330.395298)
			(xy 98.690527 -330.424766) (xy 98.731723 -330.46046) (xy 98.76742 -330.501654) (xy 98.796891 -330.547509)
			(xy 98.819535 -330.597091) (xy 98.834893 -330.649392) (xy 98.842651 -330.703346) (xy 98.842651 -330.757854)
			(xy 98.834893 -330.811808) (xy 98.819535 -330.864109) (xy 98.796891 -330.913691) (xy 98.76742 -330.959546)
			(xy 98.731723 -331.00074) (xy 98.690527 -331.036434) (xy 98.64467 -331.065902) (xy 98.595086 -331.088544)
			(xy 98.542785 -331.103898) (xy 98.48883 -331.111652) (xy 98.461576 -331.112114) (xy 98.434521 -331.111646)
			(xy 98.380956 -331.103986) (xy 98.32901 -331.088836) (xy 98.279724 -331.0665) (xy 98.234088 -331.037427)
			(xy 98.193016 -331.002198) (xy 98.157332 -330.961522) (xy 98.127751 -330.916213) (xy 98.115882 -330.891896)
			(xy 98.111564 -330.883006) (xy 98.097594 -330.869798) (xy 98.014028 -330.837032) (xy 97.994724 -330.837032)
			(xy 97.98558 -330.840842) (xy 97.958097 -330.851529) (xy 97.901075 -330.866554) (xy 97.842598 -330.874149)
			(xy 97.813114 -330.874624) (xy 97.783127 -330.87418) (xy 97.723666 -330.866353) (xy 97.665736 -330.850831)
			(xy 97.610327 -330.82788) (xy 97.558388 -330.797893) (xy 97.510809 -330.761382) (xy 97.468402 -330.718973)
			(xy 97.431894 -330.671392) (xy 97.401909 -330.619451) (xy 97.378961 -330.564042) (xy 97.363443 -330.50611)
			(xy 97.355619 -330.446649) (xy 97.355152 -330.416662) (xy 96.711516 -330.416662) (xy 96.711516 -332.038452)
			(xy 99.004118 -332.038452) (xy 99.008189 -331.98283) (xy 99.020315 -331.928393) (xy 99.040238 -331.876302)
			(xy 99.067534 -331.827667) (xy 99.10162 -331.783524) (xy 99.141769 -331.744815) (xy 99.187127 -331.712364)
			(xy 99.236727 -331.686863) (xy 99.289511 -331.668856) (xy 99.344354 -331.658726) (xy 99.400088 -331.656689)
			(xy 99.455525 -331.662789) (xy 99.509482 -331.676895) (xy 99.560811 -331.698707) (xy 99.608417 -331.727761)
			(xy 99.651285 -331.763436) (xy 99.688502 -331.804973) (xy 99.719275 -331.851486) (xy 99.742947 -331.901983)
			(xy 99.759015 -331.95539) (xy 99.767135 -332.010566) (xy 99.767644 -332.038452) (xy 99.767551 -332.043532)
			(xy 101.474776 -332.043532) (xy 101.478847 -331.98791) (xy 101.490973 -331.933473) (xy 101.510896 -331.881382)
			(xy 101.538192 -331.832747) (xy 101.572278 -331.788604) (xy 101.612427 -331.749895) (xy 101.657785 -331.717444)
			(xy 101.707385 -331.691943) (xy 101.760169 -331.673936) (xy 101.815012 -331.663806) (xy 101.870746 -331.661769)
			(xy 101.926183 -331.667869) (xy 101.98014 -331.681975) (xy 102.031469 -331.703787) (xy 102.079075 -331.732841)
			(xy 102.121943 -331.768516) (xy 102.15916 -331.810053) (xy 102.189933 -331.856566) (xy 102.213605 -331.907063)
			(xy 102.229673 -331.96047) (xy 102.237793 -332.015646) (xy 102.238302 -332.043532) (xy 102.237793 -332.071418)
			(xy 102.229673 -332.126594) (xy 102.213605 -332.180001) (xy 102.189933 -332.230498) (xy 102.15916 -332.277011)
			(xy 102.121943 -332.318548) (xy 102.079075 -332.354223) (xy 102.031469 -332.383277) (xy 101.98014 -332.405089)
			(xy 101.926183 -332.419195) (xy 101.870746 -332.425295) (xy 101.815012 -332.423258) (xy 101.760169 -332.413128)
			(xy 101.707385 -332.395121) (xy 101.657785 -332.36962) (xy 101.612427 -332.337169) (xy 101.572278 -332.29846)
			(xy 101.538192 -332.254317) (xy 101.510896 -332.205682) (xy 101.490973 -332.153591) (xy 101.478847 -332.099154)
			(xy 101.474776 -332.043532) (xy 99.767551 -332.043532) (xy 99.767135 -332.066338) (xy 99.759015 -332.121514)
			(xy 99.742947 -332.174921) (xy 99.719275 -332.225418) (xy 99.688502 -332.271931) (xy 99.651285 -332.313468)
			(xy 99.608417 -332.349143) (xy 99.560811 -332.378197) (xy 99.509482 -332.400009) (xy 99.455525 -332.414115)
			(xy 99.400088 -332.420215) (xy 99.344354 -332.418178) (xy 99.289511 -332.408048) (xy 99.236727 -332.390041)
			(xy 99.187127 -332.36454) (xy 99.141769 -332.332089) (xy 99.10162 -332.29338) (xy 99.067534 -332.249237)
			(xy 99.040238 -332.200602) (xy 99.020315 -332.148511) (xy 99.008189 -332.094074) (xy 99.004118 -332.038452)
			(xy 96.711516 -332.038452) (xy 96.711516 -334.297274) (xy 102.382064 -334.297274) (xy 102.386135 -334.241652)
			(xy 102.398261 -334.187215) (xy 102.418184 -334.135124) (xy 102.44548 -334.086489) (xy 102.479566 -334.042346)
			(xy 102.519715 -334.003637) (xy 102.565073 -333.971186) (xy 102.614673 -333.945685) (xy 102.667457 -333.927678)
			(xy 102.7223 -333.917548) (xy 102.778034 -333.915511) (xy 102.833471 -333.921611) (xy 102.887428 -333.935717)
			(xy 102.938757 -333.957529) (xy 102.986363 -333.986583) (xy 103.029231 -334.022258) (xy 103.066448 -334.063795)
			(xy 103.097221 -334.110308) (xy 103.111639 -334.141064) (xy 103.559862 -334.141064) (xy 103.563933 -334.085442)
			(xy 103.576059 -334.031005) (xy 103.595982 -333.978914) (xy 103.623278 -333.930279) (xy 103.657364 -333.886136)
			(xy 103.697513 -333.847427) (xy 103.742871 -333.814976) (xy 103.792471 -333.789475) (xy 103.845255 -333.771468)
			(xy 103.900098 -333.761338) (xy 103.955832 -333.759301) (xy 104.011269 -333.765401) (xy 104.065226 -333.779507)
			(xy 104.116555 -333.801319) (xy 104.164161 -333.830373) (xy 104.207029 -333.866048) (xy 104.244246 -333.907585)
			(xy 104.275019 -333.954098) (xy 104.298691 -334.004595) (xy 104.314759 -334.058002) (xy 104.322879 -334.113178)
			(xy 104.323388 -334.141064) (xy 104.322879 -334.16895) (xy 104.314759 -334.224126) (xy 104.298691 -334.277533)
			(xy 104.275019 -334.32803) (xy 104.244246 -334.374543) (xy 104.207029 -334.41608) (xy 104.164161 -334.451755)
			(xy 104.116555 -334.480809) (xy 104.065226 -334.502621) (xy 104.011269 -334.516727) (xy 103.955832 -334.522827)
			(xy 103.900098 -334.52079) (xy 103.845255 -334.51066) (xy 103.792471 -334.492653) (xy 103.742871 -334.467152)
			(xy 103.697513 -334.434701) (xy 103.657364 -334.395992) (xy 103.623278 -334.351849) (xy 103.595982 -334.303214)
			(xy 103.576059 -334.251123) (xy 103.563933 -334.196686) (xy 103.559862 -334.141064) (xy 103.111639 -334.141064)
			(xy 103.120893 -334.160805) (xy 103.136961 -334.214212) (xy 103.145081 -334.269388) (xy 103.14559 -334.297274)
			(xy 103.145081 -334.32516) (xy 103.136961 -334.380336) (xy 103.120893 -334.433743) (xy 103.097221 -334.48424)
			(xy 103.066448 -334.530753) (xy 103.029231 -334.57229) (xy 102.986363 -334.607965) (xy 102.938757 -334.637019)
			(xy 102.887428 -334.658831) (xy 102.833471 -334.672937) (xy 102.778034 -334.679037) (xy 102.7223 -334.677)
			(xy 102.667457 -334.66687) (xy 102.614673 -334.648863) (xy 102.565073 -334.623362) (xy 102.519715 -334.590911)
			(xy 102.479566 -334.552202) (xy 102.44548 -334.508059) (xy 102.418184 -334.459424) (xy 102.398261 -334.407333)
			(xy 102.386135 -334.352896) (xy 102.382064 -334.297274) (xy 96.711516 -334.297274) (xy 96.711516 -334.774794)
			(xy 104.55224 -334.774794) (xy 104.556311 -334.719172) (xy 104.568437 -334.664735) (xy 104.58836 -334.612644)
			(xy 104.615656 -334.564009) (xy 104.649742 -334.519866) (xy 104.689891 -334.481157) (xy 104.735249 -334.448706)
			(xy 104.784849 -334.423205) (xy 104.837633 -334.405198) (xy 104.892476 -334.395068) (xy 104.94821 -334.393031)
			(xy 105.003647 -334.399131) (xy 105.057604 -334.413237) (xy 105.108933 -334.435049) (xy 105.156539 -334.464103)
			(xy 105.199407 -334.499778) (xy 105.236624 -334.541315) (xy 105.267397 -334.587828) (xy 105.291069 -334.638325)
			(xy 105.307137 -334.691732) (xy 105.308558 -334.701388) (xy 106.182412 -334.701388) (xy 106.186483 -334.645766)
			(xy 106.198609 -334.591329) (xy 106.218532 -334.539238) (xy 106.245828 -334.490603) (xy 106.279914 -334.44646)
			(xy 106.320063 -334.407751) (xy 106.365421 -334.3753) (xy 106.415021 -334.349799) (xy 106.467805 -334.331792)
			(xy 106.522648 -334.321662) (xy 106.578382 -334.319625) (xy 106.633819 -334.325725) (xy 106.687776 -334.339831)
			(xy 106.739105 -334.361643) (xy 106.786711 -334.390697) (xy 106.829579 -334.426372) (xy 106.866796 -334.467909)
			(xy 106.897569 -334.514422) (xy 106.921241 -334.564919) (xy 106.937309 -334.618326) (xy 106.945429 -334.673502)
			(xy 106.945938 -334.701388) (xy 106.945429 -334.729274) (xy 106.937309 -334.78445) (xy 106.921241 -334.837857)
			(xy 106.897569 -334.888354) (xy 106.866796 -334.934867) (xy 106.829579 -334.976404) (xy 106.786711 -335.012079)
			(xy 106.739105 -335.041133) (xy 106.687776 -335.062945) (xy 106.633819 -335.077051) (xy 106.578382 -335.083151)
			(xy 106.522648 -335.081114) (xy 106.467805 -335.070984) (xy 106.415021 -335.052977) (xy 106.365421 -335.027476)
			(xy 106.320063 -334.995025) (xy 106.279914 -334.956316) (xy 106.245828 -334.912173) (xy 106.218532 -334.863538)
			(xy 106.198609 -334.811447) (xy 106.186483 -334.75701) (xy 106.182412 -334.701388) (xy 105.308558 -334.701388)
			(xy 105.315257 -334.746908) (xy 105.315766 -334.774794) (xy 105.315257 -334.80268) (xy 105.307137 -334.857856)
			(xy 105.291069 -334.911263) (xy 105.267397 -334.96176) (xy 105.236624 -335.008273) (xy 105.199407 -335.04981)
			(xy 105.156539 -335.085485) (xy 105.108933 -335.114539) (xy 105.057604 -335.136351) (xy 105.003647 -335.150457)
			(xy 104.94821 -335.156557) (xy 104.892476 -335.15452) (xy 104.837633 -335.14439) (xy 104.784849 -335.126383)
			(xy 104.735249 -335.100882) (xy 104.689891 -335.068431) (xy 104.649742 -335.029722) (xy 104.615656 -334.985579)
			(xy 104.58836 -334.936944) (xy 104.568437 -334.884853) (xy 104.556311 -334.830416) (xy 104.55224 -334.774794)
			(xy 96.711516 -334.774794) (xy 96.711516 -335.205754) (xy 101.972536 -335.205754) (xy 101.980293 -335.1518)
			(xy 101.995649 -335.099498) (xy 102.018292 -335.049914) (xy 102.047761 -335.004058) (xy 102.083457 -334.962862)
			(xy 102.124652 -334.927166) (xy 102.170507 -334.897696) (xy 102.220091 -334.875052) (xy 102.272392 -334.859694)
			(xy 102.326346 -334.851937) (xy 102.380855 -334.851937) (xy 102.43481 -334.859695) (xy 102.487111 -334.875052)
			(xy 102.536694 -334.897696) (xy 102.58255 -334.927167) (xy 102.623744 -334.962863) (xy 102.65944 -335.004059)
			(xy 102.688909 -335.049916) (xy 102.711552 -335.099499) (xy 102.726908 -335.151801) (xy 102.734664 -335.205755)
			(xy 102.735126 -335.23301) (xy 102.734618 -335.253584) (xy 102.733856 -335.264506) (xy 102.741222 -335.284064)
			(xy 102.808786 -335.353152) (xy 102.82809 -335.361026) (xy 102.839012 -335.360772) (xy 102.849934 -335.360518)
			(xy 102.877182 -335.361015) (xy 102.931122 -335.368775) (xy 102.983409 -335.384132) (xy 103.032979 -335.406774)
			(xy 103.078821 -335.43624) (xy 103.120004 -335.47193) (xy 103.155689 -335.513117) (xy 103.185149 -335.558963)
			(xy 103.207785 -335.608536) (xy 103.223136 -335.660825) (xy 103.230889 -335.714766) (xy 103.230888 -335.73593)
			(xy 103.44988 -335.73593) (xy 103.453951 -335.680308) (xy 103.466077 -335.625871) (xy 103.486 -335.57378)
			(xy 103.513296 -335.525145) (xy 103.547382 -335.481002) (xy 103.587531 -335.442293) (xy 103.632889 -335.409842)
			(xy 103.682489 -335.384341) (xy 103.735273 -335.366334) (xy 103.790116 -335.356204) (xy 103.84585 -335.354167)
			(xy 103.901287 -335.360267) (xy 103.955244 -335.374373) (xy 104.006573 -335.396185) (xy 104.054179 -335.425239)
			(xy 104.097047 -335.460914) (xy 104.134264 -335.502451) (xy 104.165037 -335.548964) (xy 104.188709 -335.599461)
			(xy 104.204777 -335.652868) (xy 104.212897 -335.708044) (xy 104.213406 -335.73593) (xy 104.212897 -335.763816)
			(xy 104.204777 -335.818992) (xy 104.188709 -335.872399) (xy 104.165037 -335.922896) (xy 104.134264 -335.969409)
			(xy 104.097047 -336.010946) (xy 104.054179 -336.046621) (xy 104.006573 -336.075675) (xy 103.955244 -336.097487)
			(xy 103.901287 -336.111593) (xy 103.84585 -336.117693) (xy 103.790116 -336.115656) (xy 103.735273 -336.105526)
			(xy 103.682489 -336.087519) (xy 103.632889 -336.062018) (xy 103.587531 -336.029567) (xy 103.547382 -335.990858)
			(xy 103.513296 -335.946715) (xy 103.486 -335.89808) (xy 103.466077 -335.845989) (xy 103.453951 -335.791552)
			(xy 103.44988 -335.73593) (xy 103.230888 -335.73593) (xy 103.230887 -335.769262) (xy 103.22313 -335.823203)
			(xy 103.207775 -335.875491) (xy 103.185135 -335.925061) (xy 103.155672 -335.970905) (xy 103.119984 -336.01209)
			(xy 103.078799 -336.047777) (xy 103.032954 -336.077239) (xy 102.983383 -336.099878) (xy 102.931095 -336.115231)
			(xy 102.877154 -336.122987) (xy 102.822658 -336.122988) (xy 102.768717 -336.115234) (xy 102.716428 -336.099882)
			(xy 102.666856 -336.077245) (xy 102.621011 -336.047784) (xy 102.579824 -336.012099) (xy 102.544135 -335.970915)
			(xy 102.51467 -335.925072) (xy 102.492029 -335.875502) (xy 102.476673 -335.823214) (xy 102.468914 -335.769274)
			(xy 102.468426 -335.742026) (xy 102.468934 -335.721452) (xy 102.469696 -335.71053) (xy 102.46233 -335.690972)
			(xy 102.394766 -335.621884) (xy 102.375462 -335.61401) (xy 102.36454 -335.614264) (xy 102.353618 -335.614518)
			(xy 102.326363 -335.614064) (xy 102.272409 -335.606309) (xy 102.220107 -335.590955) (xy 102.170523 -335.568313)
			(xy 102.124665 -335.538844) (xy 102.083469 -335.50315) (xy 102.047772 -335.461956) (xy 102.0183 -335.416101)
			(xy 101.995655 -335.366518) (xy 101.980296 -335.314217) (xy 101.972538 -335.260263) (xy 101.972536 -335.205754)
			(xy 96.711516 -335.205754) (xy 96.711516 -336.590257) (xy 108.719509 -336.590257) (xy 108.719509 -336.535743)
			(xy 108.727267 -336.481784) (xy 108.742626 -336.429478) (xy 108.765273 -336.37989) (xy 108.794747 -336.334031)
			(xy 108.830447 -336.292833) (xy 108.871647 -336.257135) (xy 108.917508 -336.227663) (xy 108.967097 -336.205019)
			(xy 109.019403 -336.189663) (xy 109.073363 -336.181908) (xy 109.10062 -336.181446) (xy 109.128557 -336.181925)
			(xy 109.183834 -336.190072) (xy 109.237332 -336.206189) (xy 109.28791 -336.229932) (xy 109.334487 -336.260794)
			(xy 109.376069 -336.298116) (xy 109.411765 -336.3411) (xy 109.440816 -336.388828) (xy 109.452156 -336.414364)
			(xy 109.457743 -336.426638) (xy 109.474384 -336.447852) (xy 109.495991 -336.463978) (xy 109.521063 -336.473895)
			(xy 109.547856 -336.476912) (xy 109.574505 -336.47282) (xy 109.599158 -336.461903) (xy 109.60989 -336.453734)
			(xy 109.630411 -336.437536) (xy 109.67502 -336.410275) (xy 109.722937 -336.389368) (xy 109.773262 -336.375208)
			(xy 109.82505 -336.36806) (xy 109.85119 -336.367628) (xy 109.878446 -336.368018) (xy 109.932403 -336.375775)
			(xy 109.984707 -336.391131) (xy 110.034293 -336.413776) (xy 110.080152 -336.443246) (xy 110.12135 -336.478943)
			(xy 110.157048 -336.52014) (xy 110.18652 -336.565998) (xy 110.209165 -336.615584) (xy 110.224523 -336.667887)
			(xy 110.232281 -336.721844) (xy 110.232281 -336.776356) (xy 110.224523 -336.830313) (xy 110.209165 -336.882616)
			(xy 110.18652 -336.932202) (xy 110.157048 -336.97806) (xy 110.12135 -337.019257) (xy 110.080152 -337.054954)
			(xy 110.034293 -337.084424) (xy 109.984707 -337.107069) (xy 109.932403 -337.122425) (xy 109.878446 -337.130182)
			(xy 109.85119 -337.130644) (xy 109.823253 -337.130163) (xy 109.767976 -337.122017) (xy 109.714477 -337.105901)
			(xy 109.663899 -337.082158) (xy 109.617322 -337.051296) (xy 109.575741 -337.013975) (xy 109.540044 -336.970991)
			(xy 109.510994 -336.923263) (xy 109.499654 -336.897726) (xy 109.49403 -336.885468) (xy 109.477404 -336.864243)
			(xy 109.455805 -336.848108) (xy 109.430737 -336.838184) (xy 109.403945 -336.835165) (xy 109.377297 -336.839259)
			(xy 109.352648 -336.850183) (xy 109.34192 -336.858356) (xy 109.321429 -336.874594) (xy 109.276812 -336.901849)
			(xy 109.228887 -336.922748) (xy 109.178556 -336.936899) (xy 109.126762 -336.944036) (xy 109.10062 -336.944462)
			(xy 109.073363 -336.944092) (xy 109.019403 -336.936337) (xy 108.967097 -336.920981) (xy 108.917508 -336.898337)
			(xy 108.871647 -336.868865) (xy 108.830447 -336.833167) (xy 108.794747 -336.791969) (xy 108.765273 -336.74611)
			(xy 108.742626 -336.696522) (xy 108.727267 -336.644216) (xy 108.719509 -336.590257) (xy 96.711516 -336.590257)
			(xy 96.711516 -337.142582) (xy 96.711955 -337.152645) (xy 96.719692 -337.171227) (xy 96.726502 -337.17865)
			(xy 97.509076 -337.961224) (xy 97.516475 -337.968067) (xy 97.535074 -337.975785) (xy 97.545144 -337.97621)
			(xy 112.461548 -337.97621)
		)
		(stroke
			(width 0)
			(type solid)
		)
		(fill yes)
		(layer "In15.Cu")
		(net "P3V3")
	)
	(gr_poly
		(pts
			(xy 231.92105 -321.442842) (xy 231.931115 -321.442408) (xy 231.949701 -321.434675) (xy 231.957118 -321.427856)
			(xy 232.28808 -321.096894) (xy 232.294928 -321.089496) (xy 232.302663 -321.070898) (xy 232.303066 -321.060826)
			(xy 232.303066 -310.620918) (xy 232.302469 -310.609584) (xy 232.292718 -310.589125) (xy 232.28427 -310.581548)
			(xy 232.213912 -310.524398) (xy 232.19156 -310.519318) (xy 232.180384 -310.521604) (xy 232.160805 -310.525509)
			(xy 232.121099 -310.529709) (xy 232.101136 -310.529986) (xy 232.073883 -310.529525) (xy 232.019931 -310.521773)
			(xy 231.967632 -310.506421) (xy 231.91805 -310.483782) (xy 231.872195 -310.454316) (xy 231.831001 -310.418625)
			(xy 231.795305 -310.377433) (xy 231.765836 -310.331581) (xy 231.743192 -310.282002) (xy 231.727835 -310.229704)
			(xy 231.720077 -310.175753) (xy 231.720077 -310.121247) (xy 231.727835 -310.067296) (xy 231.743192 -310.014998)
			(xy 231.765836 -309.965419) (xy 231.795305 -309.919567) (xy 231.831001 -309.878375) (xy 231.872195 -309.842684)
			(xy 231.91805 -309.813218) (xy 231.967632 -309.790579) (xy 232.019931 -309.775227) (xy 232.073883 -309.767475)
			(xy 232.101136 -309.76697) (xy 232.1211 -309.767235) (xy 232.160806 -309.771436) (xy 232.180384 -309.775352)
			(xy 232.19156 -309.777638) (xy 232.213912 -309.772558) (xy 232.28427 -309.715408) (xy 232.292672 -309.707792)
			(xy 232.302439 -309.687359) (xy 232.303066 -309.676038) (xy 232.303066 -308.996334) (xy 232.302692 -308.987282)
			(xy 232.296394 -308.970308) (xy 232.284602 -308.956571) (xy 232.268778 -308.947773) (xy 232.259886 -308.946042)
			(xy 232.233184 -308.941482) (xy 232.181334 -308.925806) (xy 232.132223 -308.902953) (xy 232.08684 -308.873381)
			(xy 232.046096 -308.837685) (xy 232.010813 -308.796585) (xy 231.981699 -308.750906) (xy 231.959341 -308.701568)
			(xy 231.944188 -308.649562) (xy 231.936546 -308.595936) (xy 231.936036 -308.568852) (xy 231.936472 -308.542767)
			(xy 231.943602 -308.491086) (xy 231.957708 -308.440859) (xy 231.978528 -308.393023) (xy 232.005672 -308.348471)
			(xy 232.038634 -308.308033) (xy 232.057448 -308.28996) (xy 232.057956 -308.289198) (xy 232.28808 -308.059328)
			(xy 232.294917 -308.051926) (xy 232.302629 -308.033328) (xy 232.303066 -308.02326) (xy 232.303066 -308.008782)
			(xy 232.060496 -307.766212) (xy 232.058972 -307.764688) (xy 232.039952 -307.746567) (xy 232.00657 -307.706004)
			(xy 231.979073 -307.661242) (xy 231.957982 -307.613128) (xy 231.943697 -307.562575) (xy 231.936488 -307.510539)
			(xy 231.936036 -307.484272) (xy 231.936511 -307.457188) (xy 231.944174 -307.403564) (xy 231.959342 -307.351563)
			(xy 231.981709 -307.302229) (xy 232.010827 -307.256552) (xy 232.046111 -307.215452) (xy 232.086852 -307.179753)
			(xy 232.13223 -307.150173) (xy 232.181335 -307.127306) (xy 232.23318 -307.111612) (xy 232.259886 -307.107082)
			(xy 232.268787 -307.105364) (xy 232.284633 -307.096588) (xy 232.296431 -307.082842) (xy 232.302704 -307.065848)
			(xy 232.303066 -307.05679) (xy 232.303066 -290.133024) (xy 232.302628 -290.122961) (xy 232.294891 -290.104379)
			(xy 232.28808 -290.096956) (xy 231.5464 -289.355276) (xy 231.539005 -289.348422) (xy 231.520406 -289.340675)
			(xy 231.510332 -289.34029) (xy 221.758764 -289.34029) (xy 221.74876 -289.340784) (xy 221.730279 -289.34845)
			(xy 221.716135 -289.362601) (xy 221.708479 -289.381086) (xy 221.707964 -289.39109) (xy 221.707964 -289.391344)
			(xy 221.707475 -289.418592) (xy 221.699713 -289.472533) (xy 221.684353 -289.524819) (xy 221.661709 -289.574388)
			(xy 221.632241 -289.62023) (xy 221.596549 -289.661411) (xy 221.555359 -289.697094) (xy 221.509511 -289.726551)
			(xy 221.459937 -289.749184) (xy 221.407646 -289.764532) (xy 221.353704 -289.772281) (xy 221.326456 -289.772852)
			(xy 221.296331 -289.772287) (xy 221.236828 -289.762822) (xy 221.179554 -289.744118) (xy 221.125934 -289.71664)
			(xy 221.077301 -289.681073) (xy 221.055692 -289.660076) (xy 221.048297 -289.653223) (xy 221.029698 -289.645479)
			(xy 221.019624 -289.64509) (xy 220.947488 -289.64509) (xy 220.937418 -289.645515) (xy 220.918816 -289.653231)
			(xy 220.91142 -289.660076) (xy 220.889794 -289.681052) (xy 220.841159 -289.716605) (xy 220.787541 -289.744075)
			(xy 220.730273 -289.762779) (xy 220.670778 -289.772253) (xy 220.640656 -289.772852) (xy 220.613406 -289.772363)
			(xy 220.55946 -289.764602) (xy 220.507168 -289.749243) (xy 220.457594 -289.7266) (xy 220.411746 -289.697134)
			(xy 220.370557 -289.661443) (xy 220.334866 -289.620254) (xy 220.3054 -289.574406) (xy 220.282757 -289.524832)
			(xy 220.267398 -289.47254) (xy 220.259637 -289.418594) (xy 220.259148 -289.391344) (xy 220.259148 -289.39109)
			(xy 220.258659 -289.38108) (xy 220.250999 -289.362584) (xy 220.236848 -289.348422) (xy 220.218357 -289.340749)
			(xy 220.208348 -289.34029) (xy 218.294204 -289.34029) (xy 218.284133 -289.340712) (xy 218.265527 -289.348424)
			(xy 218.258136 -289.355276) (xy 218.240102 -289.37331) (xy 218.233257 -289.380709) (xy 218.225526 -289.399307)
			(xy 218.225116 -289.409378) (xy 218.225116 -290.900153) (xy 227.087881 -290.900153) (xy 227.087881 -290.845647)
			(xy 227.095639 -290.791697) (xy 227.110996 -290.739399) (xy 227.133639 -290.68982) (xy 227.163109 -290.643968)
			(xy 227.198804 -290.602777) (xy 227.239999 -290.567086) (xy 227.285853 -290.537621) (xy 227.335435 -290.514982)
			(xy 227.387734 -290.499631) (xy 227.441685 -290.491879) (xy 227.468938 -290.491418) (xy 227.496307 -290.491916)
			(xy 227.550485 -290.499725) (xy 227.602988 -290.515207) (xy 227.652735 -290.538042) (xy 227.698703 -290.56776)
			(xy 227.719636 -290.585398) (xy 227.71989 -290.585652) (xy 227.726971 -290.591247) (xy 227.743892 -290.597487)
			(xy 227.75291 -290.597844) (xy 227.819966 -290.597844) (xy 227.828983 -290.597483) (xy 227.8459 -290.59124)
			(xy 227.852986 -290.585652) (xy 227.852986 -290.585398) (xy 227.85324 -290.585398) (xy 227.874184 -290.567773)
			(xy 227.920153 -290.538059) (xy 227.969898 -290.515221) (xy 228.022396 -290.499726) (xy 228.07657 -290.491894)
			(xy 228.103938 -290.491418) (xy 228.131189 -290.491854) (xy 228.185137 -290.499616) (xy 228.23743 -290.514975)
			(xy 228.287006 -290.53762) (xy 228.332855 -290.56709) (xy 228.374043 -290.602783) (xy 228.409733 -290.643976)
			(xy 228.439198 -290.689827) (xy 228.461838 -290.739405) (xy 228.477192 -290.791701) (xy 228.484948 -290.845649)
			(xy 228.484948 -290.900151) (xy 228.477192 -290.954099) (xy 228.461838 -291.006395) (xy 228.439198 -291.055973)
			(xy 228.409733 -291.101824) (xy 228.374043 -291.143017) (xy 228.332855 -291.17871) (xy 228.287006 -291.20818)
			(xy 228.23743 -291.230825) (xy 228.185137 -291.246184) (xy 228.131189 -291.253946) (xy 228.103938 -291.254434)
			(xy 228.076568 -291.253962) (xy 228.022388 -291.246148) (xy 227.969885 -291.230661) (xy 227.920138 -291.20782)
			(xy 227.874171 -291.178096) (xy 227.85324 -291.160454) (xy 227.852986 -291.1602) (xy 227.845908 -291.154601)
			(xy 227.828985 -291.148362) (xy 227.819966 -291.148008) (xy 227.75291 -291.148008) (xy 227.743893 -291.148368)
			(xy 227.726976 -291.154613) (xy 227.71989 -291.1602) (xy 227.71989 -291.160454) (xy 227.719636 -291.160454)
			(xy 227.698695 -291.178083) (xy 227.652726 -291.207798) (xy 227.60298 -291.230636) (xy 227.550481 -291.24613)
			(xy 227.496307 -291.253959) (xy 227.468938 -291.254434) (xy 227.441685 -291.253921) (xy 227.387734 -291.246169)
			(xy 227.335435 -291.230818) (xy 227.285853 -291.208179) (xy 227.239999 -291.178714) (xy 227.198804 -291.143023)
			(xy 227.163109 -291.101832) (xy 227.133639 -291.05598) (xy 227.110996 -291.006401) (xy 227.095639 -290.954103)
			(xy 227.087881 -290.900153) (xy 218.225116 -290.900153) (xy 218.225116 -291.639549) (xy 220.096598 -291.639549)
			(xy 220.096598 -291.585051) (xy 220.104354 -291.531107) (xy 220.119708 -291.478816) (xy 220.142347 -291.429242)
			(xy 220.17181 -291.383395) (xy 220.207499 -291.342207) (xy 220.248685 -291.306518) (xy 220.294532 -291.277052)
			(xy 220.344105 -291.254412) (xy 220.396395 -291.239057) (xy 220.450339 -291.231299) (xy 220.477588 -291.230812)
			(xy 220.504958 -291.231282) (xy 220.559137 -291.239099) (xy 220.61164 -291.254587) (xy 220.661387 -291.277427)
			(xy 220.707354 -291.307151) (xy 220.728286 -291.324792) (xy 220.72854 -291.325046) (xy 220.735636 -291.330619)
			(xy 220.752546 -291.336873) (xy 220.76156 -291.337238) (xy 220.828616 -291.337238) (xy 220.837633 -291.336881)
			(xy 220.854549 -291.330632) (xy 220.861636 -291.325046) (xy 220.861636 -291.324792) (xy 220.86189 -291.324792)
			(xy 220.882814 -291.307143) (xy 220.928789 -291.277433) (xy 220.978539 -291.254599) (xy 221.031041 -291.23911)
			(xy 221.085218 -291.231285) (xy 221.112588 -291.230812) (xy 221.139843 -291.231234) (xy 221.193798 -291.23899)
			(xy 221.2461 -291.254346) (xy 221.295684 -291.276989) (xy 221.341541 -291.306458) (xy 221.382738 -291.342154)
			(xy 221.418435 -291.383349) (xy 221.447905 -291.429205) (xy 221.47055 -291.478789) (xy 221.485907 -291.53109)
			(xy 221.493665 -291.585045) (xy 221.493665 -291.639555) (xy 221.485907 -291.69351) (xy 221.47055 -291.745811)
			(xy 221.447905 -291.795395) (xy 221.418435 -291.841251) (xy 221.382738 -291.882446) (xy 221.341541 -291.918142)
			(xy 221.295684 -291.947611) (xy 221.2461 -291.970254) (xy 221.193798 -291.98561) (xy 221.139843 -291.993366)
			(xy 221.112588 -291.993828) (xy 221.085217 -291.993387) (xy 221.031036 -291.985565) (xy 220.978532 -291.970072)
			(xy 220.928785 -291.947224) (xy 220.88282 -291.917493) (xy 220.86189 -291.899848) (xy 220.861636 -291.899594)
			(xy 220.854544 -291.894016) (xy 220.837631 -291.887764) (xy 220.828616 -291.887402) (xy 220.76156 -291.887402)
			(xy 220.752541 -291.88774) (xy 220.735624 -291.894001) (xy 220.72854 -291.899594) (xy 220.72854 -291.899848)
			(xy 220.728286 -291.899848) (xy 220.707326 -291.917452) (xy 220.661361 -291.947171) (xy 220.611621 -291.970015)
			(xy 220.559126 -291.985514) (xy 220.504955 -291.99335) (xy 220.477588 -291.993828) (xy 220.450339 -291.993301)
			(xy 220.396395 -291.985543) (xy 220.344105 -291.970188) (xy 220.294532 -291.947548) (xy 220.248685 -291.918082)
			(xy 220.207499 -291.882393) (xy 220.17181 -291.841205) (xy 220.142347 -291.795358) (xy 220.119708 -291.745784)
			(xy 220.104354 -291.693493) (xy 220.096598 -291.639549) (xy 218.225116 -291.639549) (xy 218.225116 -306.744116)
			(xy 221.949516 -306.744116) (xy 221.953587 -306.688494) (xy 221.965713 -306.634057) (xy 221.985636 -306.581966)
			(xy 222.012932 -306.533331) (xy 222.047018 -306.489188) (xy 222.087167 -306.450479) (xy 222.132525 -306.418028)
			(xy 222.182125 -306.392527) (xy 222.234909 -306.37452) (xy 222.289752 -306.36439) (xy 222.345486 -306.362353)
			(xy 222.400923 -306.368453) (xy 222.45488 -306.382559) (xy 222.506209 -306.404371) (xy 222.553815 -306.433425)
			(xy 222.596683 -306.4691) (xy 222.6339 -306.510637) (xy 222.664673 -306.55715) (xy 222.688345 -306.607647)
			(xy 222.704413 -306.661054) (xy 222.712533 -306.71623) (xy 222.713042 -306.744116) (xy 222.712533 -306.772002)
			(xy 222.71032 -306.787042) (xy 229.223568 -306.787042) (xy 229.227639 -306.73142) (xy 229.239765 -306.676983)
			(xy 229.259688 -306.624892) (xy 229.286984 -306.576257) (xy 229.32107 -306.532114) (xy 229.361219 -306.493405)
			(xy 229.406577 -306.460954) (xy 229.456177 -306.435453) (xy 229.508961 -306.417446) (xy 229.563804 -306.407316)
			(xy 229.619538 -306.405279) (xy 229.674975 -306.411379) (xy 229.728932 -306.425485) (xy 229.780261 -306.447297)
			(xy 229.827867 -306.476351) (xy 229.870735 -306.512026) (xy 229.907952 -306.553563) (xy 229.938725 -306.600076)
			(xy 229.962397 -306.650573) (xy 229.978465 -306.70398) (xy 229.986585 -306.759156) (xy 229.987094 -306.787042)
			(xy 229.986585 -306.814928) (xy 229.978465 -306.870104) (xy 229.962397 -306.923511) (xy 229.938725 -306.974008)
			(xy 229.907952 -307.020521) (xy 229.870735 -307.062058) (xy 229.827867 -307.097733) (xy 229.780261 -307.126787)
			(xy 229.728932 -307.148599) (xy 229.674975 -307.162705) (xy 229.619538 -307.168805) (xy 229.563804 -307.166768)
			(xy 229.508961 -307.156638) (xy 229.456177 -307.138631) (xy 229.406577 -307.11313) (xy 229.361219 -307.080679)
			(xy 229.32107 -307.04197) (xy 229.286984 -306.997827) (xy 229.259688 -306.949192) (xy 229.239765 -306.897101)
			(xy 229.227639 -306.842664) (xy 229.223568 -306.787042) (xy 222.71032 -306.787042) (xy 222.704413 -306.827178)
			(xy 222.688345 -306.880585) (xy 222.664673 -306.931082) (xy 222.6339 -306.977595) (xy 222.596683 -307.019132)
			(xy 222.553815 -307.054807) (xy 222.506209 -307.083861) (xy 222.45488 -307.105673) (xy 222.400923 -307.119779)
			(xy 222.345486 -307.125879) (xy 222.289752 -307.123842) (xy 222.234909 -307.113712) (xy 222.182125 -307.095705)
			(xy 222.132525 -307.070204) (xy 222.087167 -307.037753) (xy 222.047018 -306.999044) (xy 222.012932 -306.954901)
			(xy 221.985636 -306.906266) (xy 221.965713 -306.854175) (xy 221.953587 -306.799738) (xy 221.949516 -306.744116)
			(xy 218.225116 -306.744116) (xy 218.225116 -307.446426) (xy 226.875084 -307.446426) (xy 226.879155 -307.390804)
			(xy 226.891281 -307.336367) (xy 226.911204 -307.284276) (xy 226.9385 -307.235641) (xy 226.972586 -307.191498)
			(xy 227.012735 -307.152789) (xy 227.058093 -307.120338) (xy 227.107693 -307.094837) (xy 227.160477 -307.07683)
			(xy 227.21532 -307.0667) (xy 227.271054 -307.064663) (xy 227.326491 -307.070763) (xy 227.380448 -307.084869)
			(xy 227.431777 -307.106681) (xy 227.479383 -307.135735) (xy 227.522251 -307.17141) (xy 227.559468 -307.212947)
			(xy 227.590241 -307.25946) (xy 227.613913 -307.309957) (xy 227.629981 -307.363364) (xy 227.638101 -307.41854)
			(xy 227.63861 -307.446426) (xy 227.638101 -307.474312) (xy 227.629981 -307.529488) (xy 227.613913 -307.582895)
			(xy 227.590241 -307.633392) (xy 227.559468 -307.679905) (xy 227.522251 -307.721442) (xy 227.479383 -307.757117)
			(xy 227.431777 -307.786171) (xy 227.380448 -307.807983) (xy 227.326491 -307.822089) (xy 227.271054 -307.828189)
			(xy 227.21532 -307.826152) (xy 227.160477 -307.816022) (xy 227.107693 -307.798015) (xy 227.058093 -307.772514)
			(xy 227.012735 -307.740063) (xy 226.972586 -307.701354) (xy 226.9385 -307.657211) (xy 226.911204 -307.608576)
			(xy 226.891281 -307.556485) (xy 226.879155 -307.502048) (xy 226.875084 -307.446426) (xy 218.225116 -307.446426)
			(xy 218.225116 -308.000654) (xy 218.225496 -308.010779) (xy 218.233237 -308.029484) (xy 218.247639 -308.043711)
			(xy 218.256866 -308.047898) (xy 218.332522 -308.07903) (xy 218.481053 -308.147655) (xy 218.626088 -308.22339)
			(xy 218.767287 -308.306057) (xy 218.904319 -308.395462) (xy 218.913667 -308.402228) (xy 227.932994 -308.402228)
			(xy 227.937065 -308.346606) (xy 227.949191 -308.292169) (xy 227.969114 -308.240078) (xy 227.99641 -308.191443)
			(xy 228.030496 -308.1473) (xy 228.070645 -308.108591) (xy 228.116003 -308.07614) (xy 228.165603 -308.050639)
			(xy 228.218387 -308.032632) (xy 228.27323 -308.022502) (xy 228.328964 -308.020465) (xy 228.384401 -308.026565)
			(xy 228.438358 -308.040671) (xy 228.489687 -308.062483) (xy 228.537293 -308.091537) (xy 228.580161 -308.127212)
			(xy 228.617378 -308.168749) (xy 228.648151 -308.215262) (xy 228.671823 -308.265759) (xy 228.687891 -308.319166)
			(xy 228.696011 -308.374342) (xy 228.69652 -308.402228) (xy 228.696011 -308.430114) (xy 228.687891 -308.48529)
			(xy 228.671823 -308.538697) (xy 228.648151 -308.589194) (xy 228.617378 -308.635707) (xy 228.580161 -308.677244)
			(xy 228.537293 -308.712919) (xy 228.489687 -308.741973) (xy 228.438358 -308.763785) (xy 228.384401 -308.777891)
			(xy 228.328964 -308.783991) (xy 228.27323 -308.781954) (xy 228.218387 -308.771824) (xy 228.165603 -308.753817)
			(xy 228.116003 -308.728316) (xy 228.070645 -308.695865) (xy 228.030496 -308.657156) (xy 227.99641 -308.613013)
			(xy 227.969114 -308.564378) (xy 227.949191 -308.512287) (xy 227.937065 -308.45785) (xy 227.932994 -308.402228)
			(xy 218.913667 -308.402228) (xy 219.036862 -308.491395) (xy 219.164607 -308.593631) (xy 219.287253 -308.701932)
			(xy 219.404512 -308.816042) (xy 219.516111 -308.935694) (xy 219.585892 -309.018178) (xy 229.941118 -309.018178)
			(xy 229.945189 -308.962556) (xy 229.957315 -308.908119) (xy 229.977238 -308.856028) (xy 230.004534 -308.807393)
			(xy 230.03862 -308.76325) (xy 230.078769 -308.724541) (xy 230.124127 -308.69209) (xy 230.173727 -308.666589)
			(xy 230.226511 -308.648582) (xy 230.281354 -308.638452) (xy 230.337088 -308.636415) (xy 230.392525 -308.642515)
			(xy 230.446482 -308.656621) (xy 230.497811 -308.678433) (xy 230.545417 -308.707487) (xy 230.588285 -308.743162)
			(xy 230.625502 -308.784699) (xy 230.656275 -308.831212) (xy 230.679947 -308.881709) (xy 230.696015 -308.935116)
			(xy 230.704135 -308.990292) (xy 230.704644 -309.018178) (xy 230.704135 -309.046064) (xy 230.696015 -309.10124)
			(xy 230.679947 -309.154647) (xy 230.656275 -309.205144) (xy 230.625502 -309.251657) (xy 230.588285 -309.293194)
			(xy 230.545417 -309.328869) (xy 230.497811 -309.357923) (xy 230.446482 -309.379735) (xy 230.392525 -309.393841)
			(xy 230.337088 -309.399941) (xy 230.281354 -309.397904) (xy 230.226511 -309.387774) (xy 230.173727 -309.369767)
			(xy 230.124127 -309.344266) (xy 230.078769 -309.311815) (xy 230.03862 -309.273106) (xy 230.004534 -309.228963)
			(xy 229.977238 -309.180328) (xy 229.957315 -309.128237) (xy 229.945189 -309.0738) (xy 229.941118 -309.018178)
			(xy 219.585892 -309.018178) (xy 219.621787 -309.060608) (xy 219.721293 -309.190491) (xy 219.814395 -309.325039)
			(xy 219.900874 -309.463935) (xy 219.980529 -309.606854) (xy 220.053173 -309.753462) (xy 220.118635 -309.903415)
			(xy 220.120548 -309.908448) (xy 226.32111 -309.908448) (xy 226.325181 -309.852826) (xy 226.337307 -309.798389)
			(xy 226.35723 -309.746298) (xy 226.384526 -309.697663) (xy 226.418612 -309.65352) (xy 226.458761 -309.614811)
			(xy 226.504119 -309.58236) (xy 226.553719 -309.556859) (xy 226.606503 -309.538852) (xy 226.661346 -309.528722)
			(xy 226.71708 -309.526685) (xy 226.772517 -309.532785) (xy 226.826474 -309.546891) (xy 226.877803 -309.568703)
			(xy 226.925409 -309.597757) (xy 226.968277 -309.633432) (xy 227.005494 -309.674969) (xy 227.036267 -309.721482)
			(xy 227.047351 -309.745126) (xy 228.036626 -309.745126) (xy 228.040697 -309.689504) (xy 228.052823 -309.635067)
			(xy 228.072746 -309.582976) (xy 228.100042 -309.534341) (xy 228.134128 -309.490198) (xy 228.174277 -309.451489)
			(xy 228.219635 -309.419038) (xy 228.269235 -309.393537) (xy 228.322019 -309.37553) (xy 228.376862 -309.3654)
			(xy 228.432596 -309.363363) (xy 228.488033 -309.369463) (xy 228.54199 -309.383569) (xy 228.593319 -309.405381)
			(xy 228.640925 -309.434435) (xy 228.683793 -309.47011) (xy 228.72101 -309.511647) (xy 228.751783 -309.55816)
			(xy 228.775455 -309.608657) (xy 228.791523 -309.662064) (xy 228.799643 -309.71724) (xy 228.800152 -309.745126)
			(xy 228.799643 -309.773012) (xy 228.791523 -309.828188) (xy 228.775455 -309.881595) (xy 228.751783 -309.932092)
			(xy 228.72101 -309.978605) (xy 228.683793 -310.020142) (xy 228.640925 -310.055817) (xy 228.593319 -310.084871)
			(xy 228.54199 -310.106683) (xy 228.488033 -310.120789) (xy 228.432596 -310.126889) (xy 228.376862 -310.124852)
			(xy 228.322019 -310.114722) (xy 228.269235 -310.096715) (xy 228.219635 -310.071214) (xy 228.174277 -310.038763)
			(xy 228.134128 -310.000054) (xy 228.100042 -309.955911) (xy 228.072746 -309.907276) (xy 228.052823 -309.855185)
			(xy 228.040697 -309.800748) (xy 228.036626 -309.745126) (xy 227.047351 -309.745126) (xy 227.059939 -309.771979)
			(xy 227.076007 -309.825386) (xy 227.084127 -309.880562) (xy 227.084636 -309.908448) (xy 227.084127 -309.936334)
			(xy 227.076007 -309.99151) (xy 227.059939 -310.044917) (xy 227.036267 -310.095414) (xy 227.005494 -310.141927)
			(xy 226.968277 -310.183464) (xy 226.925409 -310.219139) (xy 226.877803 -310.248193) (xy 226.826474 -310.270005)
			(xy 226.772517 -310.284111) (xy 226.71708 -310.290211) (xy 226.661346 -310.288174) (xy 226.606503 -310.278044)
			(xy 226.553719 -310.260037) (xy 226.504119 -310.234536) (xy 226.458761 -310.202085) (xy 226.418612 -310.163376)
			(xy 226.384526 -310.119233) (xy 226.35723 -310.070598) (xy 226.337307 -310.018507) (xy 226.325181 -309.96407)
			(xy 226.32111 -309.908448) (xy 220.120548 -309.908448) (xy 220.176761 -310.05636) (xy 220.227416 -310.21194)
			(xy 220.270481 -310.369789) (xy 220.305854 -310.529538) (xy 220.316363 -310.590946) (xy 230.918764 -310.590946)
			(xy 230.922835 -310.535324) (xy 230.934961 -310.480887) (xy 230.954884 -310.428796) (xy 230.98218 -310.380161)
			(xy 231.016266 -310.336018) (xy 231.056415 -310.297309) (xy 231.101773 -310.264858) (xy 231.151373 -310.239357)
			(xy 231.204157 -310.22135) (xy 231.259 -310.21122) (xy 231.314734 -310.209183) (xy 231.370171 -310.215283)
			(xy 231.424128 -310.229389) (xy 231.475457 -310.251201) (xy 231.523063 -310.280255) (xy 231.565931 -310.31593)
			(xy 231.603148 -310.357467) (xy 231.633921 -310.40398) (xy 231.657593 -310.454477) (xy 231.673661 -310.507884)
			(xy 231.681781 -310.56306) (xy 231.68229 -310.590946) (xy 231.681781 -310.618832) (xy 231.673661 -310.674008)
			(xy 231.657593 -310.727415) (xy 231.633921 -310.777912) (xy 231.603148 -310.824425) (xy 231.565931 -310.865962)
			(xy 231.523063 -310.901637) (xy 231.475457 -310.930691) (xy 231.424128 -310.952503) (xy 231.370171 -310.966609)
			(xy 231.314734 -310.972709) (xy 231.259 -310.970672) (xy 231.204157 -310.960542) (xy 231.151373 -310.942535)
			(xy 231.101773 -310.917034) (xy 231.056415 -310.884583) (xy 231.016266 -310.845874) (xy 230.98218 -310.801731)
			(xy 230.954884 -310.753096) (xy 230.934961 -310.701005) (xy 230.922835 -310.646568) (xy 230.918764 -310.590946)
			(xy 220.316363 -310.590946) (xy 220.333453 -310.690812) (xy 220.353213 -310.853232) (xy 220.365088 -311.016419)
			(xy 220.36905 -311.179989) (xy 220.368183 -311.215786) (xy 227.498908 -311.215786) (xy 227.502979 -311.160164)
			(xy 227.515105 -311.105727) (xy 227.535028 -311.053636) (xy 227.562324 -311.005001) (xy 227.59641 -310.960858)
			(xy 227.636559 -310.922149) (xy 227.681917 -310.889698) (xy 227.731517 -310.864197) (xy 227.784301 -310.84619)
			(xy 227.839144 -310.83606) (xy 227.894878 -310.834023) (xy 227.950315 -310.840123) (xy 228.004272 -310.854229)
			(xy 228.055601 -310.876041) (xy 228.103207 -310.905095) (xy 228.146075 -310.94077) (xy 228.183292 -310.982307)
			(xy 228.214065 -311.02882) (xy 228.237737 -311.079317) (xy 228.253805 -311.132724) (xy 228.261925 -311.1879)
			(xy 228.262434 -311.215786) (xy 228.261925 -311.243672) (xy 228.253805 -311.298848) (xy 228.237737 -311.352255)
			(xy 228.214065 -311.402752) (xy 228.183292 -311.449265) (xy 228.146075 -311.490802) (xy 228.103207 -311.526477)
			(xy 228.055601 -311.555531) (xy 228.025463 -311.568338) (xy 229.820468 -311.568338) (xy 229.824539 -311.512716)
			(xy 229.836665 -311.458279) (xy 229.856588 -311.406188) (xy 229.883884 -311.357553) (xy 229.91797 -311.31341)
			(xy 229.958119 -311.274701) (xy 230.003477 -311.24225) (xy 230.053077 -311.216749) (xy 230.105861 -311.198742)
			(xy 230.160704 -311.188612) (xy 230.216438 -311.186575) (xy 230.271875 -311.192675) (xy 230.325832 -311.206781)
			(xy 230.377161 -311.228593) (xy 230.424767 -311.257647) (xy 230.467635 -311.293322) (xy 230.504852 -311.334859)
			(xy 230.535625 -311.381372) (xy 230.559297 -311.431869) (xy 230.575365 -311.485276) (xy 230.583485 -311.540452)
			(xy 230.583994 -311.568338) (xy 230.583485 -311.596224) (xy 230.575365 -311.6514) (xy 230.559297 -311.704807)
			(xy 230.535625 -311.755304) (xy 230.504852 -311.801817) (xy 230.467635 -311.843354) (xy 230.424767 -311.879029)
			(xy 230.377161 -311.908083) (xy 230.325832 -311.929895) (xy 230.271875 -311.944001) (xy 230.216438 -311.950101)
			(xy 230.160704 -311.948064) (xy 230.105861 -311.937934) (xy 230.053077 -311.919927) (xy 230.003477 -311.894426)
			(xy 229.958119 -311.861975) (xy 229.91797 -311.823266) (xy 229.883884 -311.779123) (xy 229.856588 -311.730488)
			(xy 229.836665 -311.678397) (xy 229.824539 -311.62396) (xy 229.820468 -311.568338) (xy 228.025463 -311.568338)
			(xy 228.004272 -311.577343) (xy 227.950315 -311.591449) (xy 227.894878 -311.597549) (xy 227.839144 -311.595512)
			(xy 227.784301 -311.585382) (xy 227.731517 -311.567375) (xy 227.681917 -311.541874) (xy 227.636559 -311.509423)
			(xy 227.59641 -311.470714) (xy 227.562324 -311.426571) (xy 227.535028 -311.377936) (xy 227.515105 -311.325845)
			(xy 227.502979 -311.271408) (xy 227.498908 -311.215786) (xy 220.368183 -311.215786) (xy 220.365089 -311.34356)
			(xy 220.353215 -311.506747) (xy 220.333456 -311.669168) (xy 220.305858 -311.830442) (xy 220.270486 -311.990191)
			(xy 220.227422 -312.14804) (xy 220.176768 -312.30362) (xy 220.118643 -312.456566) (xy 220.053182 -312.606519)
			(xy 219.980539 -312.753127) (xy 219.900885 -312.896047) (xy 219.814406 -313.034944) (xy 219.761159 -313.111896)
			(xy 230.52354 -313.111896) (xy 230.527611 -313.056274) (xy 230.539737 -313.001837) (xy 230.55966 -312.949746)
			(xy 230.586956 -312.901111) (xy 230.621042 -312.856968) (xy 230.661191 -312.818259) (xy 230.706549 -312.785808)
			(xy 230.756149 -312.760307) (xy 230.808933 -312.7423) (xy 230.863776 -312.73217) (xy 230.91951 -312.730133)
			(xy 230.974947 -312.736233) (xy 231.028904 -312.750339) (xy 231.080233 -312.772151) (xy 231.127839 -312.801205)
			(xy 231.170707 -312.83688) (xy 231.207924 -312.878417) (xy 231.238697 -312.92493) (xy 231.262369 -312.975427)
			(xy 231.278437 -313.028834) (xy 231.286557 -313.08401) (xy 231.287066 -313.111896) (xy 231.286557 -313.139782)
			(xy 231.278437 -313.194958) (xy 231.262369 -313.248365) (xy 231.238697 -313.298862) (xy 231.207924 -313.345375)
			(xy 231.170707 -313.386912) (xy 231.127839 -313.422587) (xy 231.080233 -313.451641) (xy 231.028904 -313.473453)
			(xy 230.974947 -313.487559) (xy 230.91951 -313.493659) (xy 230.863776 -313.491622) (xy 230.808933 -313.481492)
			(xy 230.756149 -313.463485) (xy 230.706549 -313.437984) (xy 230.661191 -313.405533) (xy 230.621042 -313.366824)
			(xy 230.586956 -313.322681) (xy 230.55966 -313.274046) (xy 230.539737 -313.221955) (xy 230.527611 -313.167518)
			(xy 230.52354 -313.111896) (xy 219.761159 -313.111896) (xy 219.721305 -313.169492) (xy 219.6218 -313.299375)
			(xy 219.516125 -313.42429) (xy 219.404527 -313.543943) (xy 219.287268 -313.658054) (xy 219.164623 -313.766355)
			(xy 219.036879 -313.868592) (xy 218.904336 -313.964526) (xy 218.767305 -314.053932) (xy 218.626106 -314.1366)
			(xy 218.481072 -314.212335) (xy 218.332541 -314.280962) (xy 218.256866 -314.312046) (xy 218.24766 -314.316259)
			(xy 218.233297 -314.330503) (xy 218.225515 -314.349176) (xy 218.225116 -314.35929) (xy 218.225116 -320.816732)
			(xy 224.888044 -320.816732) (xy 224.888518 -320.789362) (xy 224.896332 -320.735183) (xy 224.911819 -320.682679)
			(xy 224.934659 -320.632932) (xy 224.964383 -320.586966) (xy 224.982024 -320.566034) (xy 224.982278 -320.56578)
			(xy 224.987888 -320.55871) (xy 224.994119 -320.54178) (xy 224.99447 -320.53276) (xy 224.99447 -320.465704)
			(xy 224.994118 -320.456686) (xy 224.987868 -320.439769) (xy 224.982278 -320.432684) (xy 224.982024 -320.432684)
			(xy 224.982024 -320.43243) (xy 224.964389 -320.411494) (xy 224.934676 -320.365523) (xy 224.911839 -320.315776)
			(xy 224.896347 -320.263276) (xy 224.888518 -320.209101) (xy 224.888044 -320.181732) (xy 224.888608 -320.154484)
			(xy 224.896359 -320.100541) (xy 224.911707 -320.048251) (xy 224.934341 -319.998677) (xy 224.9638 -319.952829)
			(xy 224.999483 -319.91164) (xy 225.040665 -319.875948) (xy 225.086507 -319.84648) (xy 225.136076 -319.823835)
			(xy 225.188363 -319.808476) (xy 225.242304 -319.800714) (xy 225.269552 -319.800224) (xy 225.296921 -319.800712)
			(xy 225.3511 -319.808524) (xy 225.403603 -319.824007) (xy 225.45335 -319.846844) (xy 225.499318 -319.876565)
			(xy 225.52025 -319.894204) (xy 225.520504 -319.894458) (xy 225.52758 -319.900059) (xy 225.544505 -319.906296)
			(xy 225.553524 -319.90665) (xy 225.62058 -319.90665) (xy 225.629597 -319.906294) (xy 225.646515 -319.900047)
			(xy 225.6536 -319.894458) (xy 225.6536 -319.894204) (xy 225.653854 -319.894204) (xy 225.674787 -319.876563)
			(xy 225.720755 -319.846839) (xy 225.770501 -319.823993) (xy 225.823003 -319.808497) (xy 225.877181 -319.800668)
			(xy 225.931923 -319.800668) (xy 225.986101 -319.808497) (xy 226.038603 -319.823993) (xy 226.088349 -319.846839)
			(xy 226.134317 -319.876563) (xy 226.15525 -319.894204) (xy 226.155504 -319.894458) (xy 226.16258 -319.900059)
			(xy 226.179505 -319.906296) (xy 226.188524 -319.90665) (xy 226.25558 -319.90665) (xy 226.264597 -319.906294)
			(xy 226.281515 -319.900047) (xy 226.2886 -319.894458) (xy 226.2886 -319.894204) (xy 226.288854 -319.894204)
			(xy 226.309793 -319.876574) (xy 226.355764 -319.84686) (xy 226.40551 -319.824023) (xy 226.458009 -319.80853)
			(xy 226.512183 -319.800699) (xy 226.539552 -319.800224) (xy 226.566805 -319.8007) (xy 226.620757 -319.808451)
			(xy 226.673057 -319.823803) (xy 226.722639 -319.846442) (xy 226.768494 -319.875908) (xy 226.809688 -319.911601)
			(xy 226.845382 -319.952793) (xy 226.87485 -319.998647) (xy 226.897492 -320.048228) (xy 226.912845 -320.100527)
			(xy 226.920599 -320.154479) (xy 226.92106 -320.181732) (xy 226.920622 -320.209103) (xy 226.912799 -320.263284)
			(xy 226.897304 -320.315788) (xy 226.874456 -320.365534) (xy 226.844725 -320.4115) (xy 226.82708 -320.43243)
			(xy 226.826826 -320.432684) (xy 226.821231 -320.439765) (xy 226.814991 -320.456686) (xy 226.814634 -320.465704)
			(xy 226.814634 -320.53276) (xy 226.815003 -320.541776) (xy 226.821241 -320.558693) (xy 226.826826 -320.56578)
			(xy 226.82708 -320.56578) (xy 226.82708 -320.566034) (xy 226.844699 -320.586983) (xy 226.874414 -320.632951)
			(xy 226.897254 -320.682694) (xy 226.91275 -320.735191) (xy 226.920583 -320.789364) (xy 226.92106 -320.816732)
			(xy 226.920675 -320.843988) (xy 226.912912 -320.897944) (xy 226.89755 -320.950246) (xy 226.8749 -320.99983)
			(xy 226.845424 -321.045685) (xy 226.809722 -321.086879) (xy 226.768521 -321.122572) (xy 226.72266 -321.152038)
			(xy 226.673071 -321.174678) (xy 226.620766 -321.190029) (xy 226.566808 -321.19778) (xy 226.539552 -321.19824)
			(xy 226.512182 -321.197758) (xy 226.458003 -321.189946) (xy 226.4055 -321.174462) (xy 226.355752 -321.151623)
			(xy 226.309786 -321.121901) (xy 226.288854 -321.10426) (xy 226.2886 -321.104006) (xy 226.281517 -321.098414)
			(xy 226.264598 -321.09217) (xy 226.25558 -321.091814) (xy 226.188524 -321.091814) (xy 226.179508 -321.092179)
			(xy 226.162591 -321.098421) (xy 226.155504 -321.104006) (xy 226.15525 -321.10426) (xy 226.134317 -321.121901)
			(xy 226.088349 -321.151625) (xy 226.038603 -321.174471) (xy 225.986101 -321.189967) (xy 225.931923 -321.197796)
			(xy 225.877181 -321.197796) (xy 225.823003 -321.189967) (xy 225.770501 -321.174471) (xy 225.720755 -321.151625)
			(xy 225.674787 -321.121901) (xy 225.653854 -321.10426) (xy 225.6536 -321.104006) (xy 225.646517 -321.098414)
			(xy 225.629598 -321.09217) (xy 225.62058 -321.091814) (xy 225.553524 -321.091814) (xy 225.544508 -321.092179)
			(xy 225.527591 -321.098421) (xy 225.520504 -321.104006) (xy 225.520504 -321.10426) (xy 225.52025 -321.10426)
			(xy 225.499305 -321.121883) (xy 225.453336 -321.151599) (xy 225.403592 -321.174438) (xy 225.351094 -321.189933)
			(xy 225.29692 -321.197764) (xy 225.269552 -321.19824) (xy 225.242301 -321.197767) (xy 225.188355 -321.190005)
			(xy 225.136062 -321.174645) (xy 225.086486 -321.152001) (xy 225.040638 -321.122532) (xy 224.999449 -321.08684)
			(xy 224.963758 -321.04565) (xy 224.934292 -320.9998) (xy 224.911649 -320.950223) (xy 224.896292 -320.89793)
			(xy 224.888532 -320.843983) (xy 224.888044 -320.816732) (xy 218.225116 -320.816732) (xy 218.225116 -321.122548)
			(xy 218.225548 -321.132614) (xy 218.233277 -321.151204) (xy 218.240102 -321.158616) (xy 218.509342 -321.427856)
			(xy 218.516741 -321.4347) (xy 218.535339 -321.442427) (xy 218.54541 -321.442842)
		)
		(stroke
			(width 0)
			(type solid)
		)
		(fill yes)
		(layer "In15.Cu")
		(net "GND")
	)
	(gr_poly
		(pts
			(xy 253.685548 -90.242644) (xy 253.694403 -90.242264) (xy 253.711063 -90.236252) (xy 253.724704 -90.224956)
			(xy 253.72949 -90.217498) (xy 253.780544 -90.130122) (xy 253.780798 -90.103198) (xy 253.77648 -90.095324)
			(xy 253.764288 -90.073474) (xy 253.745102 -90.027263) (xy 253.732124 -89.97894) (xy 253.725577 -89.929334)
			(xy 253.725172 -89.904316) (xy 253.725658 -89.877065) (xy 253.733414 -89.823117) (xy 253.748769 -89.770822)
			(xy 253.771411 -89.721245) (xy 253.800877 -89.675395) (xy 253.836568 -89.634204) (xy 253.877759 -89.598513)
			(xy 253.923609 -89.569047) (xy 253.973186 -89.546405) (xy 254.025481 -89.53105) (xy 254.079429 -89.523294)
			(xy 254.133931 -89.523294) (xy 254.187879 -89.53105) (xy 254.240174 -89.546405) (xy 254.289751 -89.569047)
			(xy 254.335601 -89.598513) (xy 254.376792 -89.634204) (xy 254.412483 -89.675395) (xy 254.441949 -89.721245)
			(xy 254.464591 -89.770822) (xy 254.479946 -89.823117) (xy 254.487702 -89.877065) (xy 254.488188 -89.904316)
			(xy 254.488188 -89.90457) (xy 254.487584 -89.935583) (xy 254.477558 -89.996792) (xy 254.457764 -90.055574)
			(xy 254.428723 -90.110381) (xy 254.410464 -90.135456) (xy 254.405249 -90.142933) (xy 254.400007 -90.16038)
			(xy 254.401229 -90.178555) (xy 254.404622 -90.187018) (xy 254.416052 -90.212672) (xy 254.420463 -90.221358)
			(xy 254.434508 -90.234833) (xy 254.45255 -90.242134) (xy 254.46228 -90.242644) (xy 254.504952 -90.242644)
			(xy 254.515017 -90.24221) (xy 254.533602 -90.234476) (xy 254.54102 -90.227658) (xy 255.369314 -89.399618)
			(xy 255.376713 -89.392772) (xy 255.395311 -89.38504) (xy 255.405382 -89.384632) (xy 255.476502 -89.384632)
			(xy 255.480244 -89.384549) (xy 255.48764 -89.383394) (xy 255.491234 -89.382346) (xy 255.498346 -89.380314)
			(xy 255.504696 -89.375996) (xy 255.524704 -89.363046) (xy 255.567732 -89.34255) (xy 255.613311 -89.328621)
			(xy 255.660445 -89.321563) (xy 255.684274 -89.321132) (xy 264.965434 -89.321132) (xy 264.974832 -89.32037)
			(xy 264.98116 -89.318992) (xy 264.992865 -89.313463) (xy 264.997946 -89.309448) (xy 264.999724 -89.307924)
			(xy 265.669776 -88.637872) (xy 265.671554 -88.636094) (xy 265.677049 -88.629475) (xy 265.683683 -88.613613)
			(xy 265.684741 -88.596452) (xy 265.68273 -88.588088) (xy 265.682222 -88.586564) (xy 265.682222 -88.58631)
			(xy 265.654282 -88.500204) (xy 265.651892 -88.493658) (xy 265.644168 -88.482065) (xy 265.639042 -88.477344)
			(xy 265.633708 -88.472772) (xy 265.621262 -88.467184) (xy 265.61415 -88.465914) (xy 265.587671 -88.461124)
			(xy 265.536309 -88.445084) (xy 265.487707 -88.421993) (xy 265.442827 -88.392308) (xy 265.402558 -88.356617)
			(xy 265.367698 -88.315628) (xy 265.338936 -88.270151) (xy 265.316843 -88.221087) (xy 265.301855 -88.169408)
			(xy 265.29427 -88.116136) (xy 265.293856 -88.089232) (xy 265.29434 -88.061978) (xy 265.302092 -88.008025)
			(xy 265.317444 -87.955725) (xy 265.340083 -87.906141) (xy 265.369548 -87.860284) (xy 265.405239 -87.819087)
			(xy 265.44643 -87.783389) (xy 265.492281 -87.753916) (xy 265.541861 -87.731268) (xy 265.594159 -87.715907)
			(xy 265.64811 -87.708144) (xy 265.675364 -87.707724) (xy 265.699506 -87.708114) (xy 265.747401 -87.714232)
			(xy 265.770868 -87.719916) (xy 265.782806 -87.722964) (xy 265.793982 -87.720424) (xy 265.799463 -87.719155)
			(xy 265.809722 -87.714545) (xy 265.814302 -87.71128) (xy 265.842496 -87.689436) (xy 265.87831 -87.66175)
			(xy 265.887172 -87.654164) (xy 265.897484 -87.633266) (xy 265.898122 -87.621618) (xy 265.898122 -86.820756)
			(xy 265.897927 -86.813739) (xy 265.894179 -86.800216) (xy 265.890756 -86.794086) (xy 265.889994 -86.79307)
			(xy 265.88339 -86.784942) (xy 265.868912 -86.77021) (xy 265.865608 -86.767021) (xy 265.858068 -86.76178)
			(xy 265.853926 -86.759796) (xy 265.829796 -86.74862) (xy 265.82116 -86.747858) (xy 265.793048 -86.744825)
			(xy 265.738093 -86.731522) (xy 265.685703 -86.710254) (xy 265.637027 -86.681486) (xy 265.59313 -86.645848)
			(xy 265.554975 -86.604121) (xy 265.523396 -86.557219) (xy 265.499087 -86.50617) (xy 265.482578 -86.452091)
			(xy 265.474233 -86.396169) (xy 265.474233 -86.339627) (xy 265.482579 -86.283704) (xy 265.499088 -86.229626)
			(xy 265.523399 -86.178577) (xy 265.554978 -86.131676) (xy 265.593134 -86.089949) (xy 265.637031 -86.054312)
			(xy 265.685708 -86.025544) (xy 265.738097 -86.004276) (xy 265.793052 -85.990974) (xy 265.82116 -85.98789)
			(xy 265.829796 -85.987128) (xy 265.853926 -85.975952) (xy 265.858056 -85.973948) (xy 265.865589 -85.968705)
			(xy 265.868912 -85.965538) (xy 265.88339 -85.950806) (xy 265.889994 -85.942678) (xy 265.890756 -85.941662)
			(xy 265.894222 -85.93555) (xy 265.897973 -85.922016) (xy 265.898122 -85.914992) (xy 265.898122 -84.773516)
			(xy 265.897778 -84.764824) (xy 265.891934 -84.748453) (xy 265.886692 -84.741512) (xy 265.88339 -84.737702)
			(xy 262.469122 -81.323434) (xy 262.465395 -81.319907) (xy 262.456825 -81.314267) (xy 262.452104 -81.312258)
			(xy 262.443468 -81.308702) (xy 257.00101 -81.308702) (xy 256.995145 -81.308871) (xy 256.983729 -81.311571)
			(xy 256.978404 -81.314036) (xy 256.95402 -81.326228) (xy 256.945638 -81.332578) (xy 256.943352 -81.335372)
			(xy 256.942082 -81.33715) (xy 256.923864 -81.358906) (xy 256.88209 -81.397306) (xy 256.835088 -81.429095)
			(xy 256.783896 -81.453571) (xy 256.729644 -81.470195) (xy 256.673527 -81.4786) (xy 256.616785 -81.4786)
			(xy 256.560668 -81.470195) (xy 256.506416 -81.453571) (xy 256.455224 -81.429095) (xy 256.408222 -81.397306)
			(xy 256.366448 -81.358906) (xy 256.34823 -81.33715) (xy 256.34696 -81.335372) (xy 256.344674 -81.332578)
			(xy 256.336292 -81.326228) (xy 256.311908 -81.314036) (xy 256.306584 -81.311568) (xy 256.295168 -81.308863)
			(xy 256.289302 -81.308702) (xy 253.272036 -81.308702) (xy 253.263342 -81.309042) (xy 253.246962 -81.314873)
			(xy 253.240032 -81.320132) (xy 253.236222 -81.323434) (xy 252.71095 -81.848706) (xy 253.2794 -81.848706)
			(xy 253.283471 -81.793084) (xy 253.295597 -81.738647) (xy 253.31552 -81.686556) (xy 253.342816 -81.637921)
			(xy 253.376902 -81.593778) (xy 253.417051 -81.555069) (xy 253.462409 -81.522618) (xy 253.512009 -81.497117)
			(xy 253.564793 -81.47911) (xy 253.619636 -81.46898) (xy 253.67537 -81.466943) (xy 253.730807 -81.473043)
			(xy 253.784764 -81.487149) (xy 253.836093 -81.508961) (xy 253.883699 -81.538015) (xy 253.926567 -81.57369)
			(xy 253.963784 -81.615227) (xy 253.994557 -81.66174) (xy 254.018229 -81.712237) (xy 254.034297 -81.765644)
			(xy 254.042417 -81.82082) (xy 254.042926 -81.848706) (xy 254.042417 -81.876592) (xy 254.034297 -81.931768)
			(xy 254.018229 -81.985175) (xy 253.994557 -82.035672) (xy 253.980792 -82.056478) (xy 254.425956 -82.056478)
			(xy 254.430027 -82.000856) (xy 254.442153 -81.946419) (xy 254.462076 -81.894328) (xy 254.489372 -81.845693)
			(xy 254.523458 -81.80155) (xy 254.563607 -81.762841) (xy 254.608965 -81.73039) (xy 254.658565 -81.704889)
			(xy 254.711349 -81.686882) (xy 254.766192 -81.676752) (xy 254.821926 -81.674715) (xy 254.877363 -81.680815)
			(xy 254.93132 -81.694921) (xy 254.982649 -81.716733) (xy 255.030255 -81.745787) (xy 255.073123 -81.781462)
			(xy 255.11034 -81.822999) (xy 255.141113 -81.869512) (xy 255.164785 -81.920009) (xy 255.180853 -81.973416)
			(xy 255.188973 -82.028592) (xy 255.189482 -82.056478) (xy 255.188973 -82.084364) (xy 255.181676 -82.133948)
			(xy 257.009898 -82.133948) (xy 257.013969 -82.078326) (xy 257.026095 -82.023889) (xy 257.046018 -81.971798)
			(xy 257.073314 -81.923163) (xy 257.1074 -81.87902) (xy 257.147549 -81.840311) (xy 257.192907 -81.80786)
			(xy 257.242507 -81.782359) (xy 257.295291 -81.764352) (xy 257.350134 -81.754222) (xy 257.405868 -81.752185)
			(xy 257.461305 -81.758285) (xy 257.515262 -81.772391) (xy 257.566591 -81.794203) (xy 257.614197 -81.823257)
			(xy 257.657065 -81.858932) (xy 257.694282 -81.900469) (xy 257.725055 -81.946982) (xy 257.748727 -81.997479)
			(xy 257.752875 -82.011266) (xy 259.066536 -82.011266) (xy 259.070607 -81.955644) (xy 259.082733 -81.901207)
			(xy 259.102656 -81.849116) (xy 259.129952 -81.800481) (xy 259.164038 -81.756338) (xy 259.204187 -81.717629)
			(xy 259.249545 -81.685178) (xy 259.299145 -81.659677) (xy 259.351929 -81.64167) (xy 259.406772 -81.63154)
			(xy 259.462506 -81.629503) (xy 259.517943 -81.635603) (xy 259.5719 -81.649709) (xy 259.623229 -81.671521)
			(xy 259.670835 -81.700575) (xy 259.713703 -81.73625) (xy 259.75092 -81.777787) (xy 259.781693 -81.8243)
			(xy 259.805365 -81.874797) (xy 259.821433 -81.928204) (xy 259.829553 -81.98338) (xy 259.830062 -82.011266)
			(xy 259.829937 -82.018124) (xy 260.23011 -82.018124) (xy 260.234181 -81.962502) (xy 260.246307 -81.908065)
			(xy 260.26623 -81.855974) (xy 260.293526 -81.807339) (xy 260.327612 -81.763196) (xy 260.367761 -81.724487)
			(xy 260.413119 -81.692036) (xy 260.462719 -81.666535) (xy 260.515503 -81.648528) (xy 260.570346 -81.638398)
			(xy 260.62608 -81.636361) (xy 260.681517 -81.642461) (xy 260.735474 -81.656567) (xy 260.786803 -81.678379)
			(xy 260.834409 -81.707433) (xy 260.877277 -81.743108) (xy 260.914494 -81.784645) (xy 260.945267 -81.831158)
			(xy 260.968939 -81.881655) (xy 260.985007 -81.935062) (xy 260.993127 -81.990238) (xy 260.993636 -82.018124)
			(xy 260.993127 -82.04601) (xy 260.985007 -82.101186) (xy 260.968939 -82.154593) (xy 260.945267 -82.20509)
			(xy 260.914494 -82.251603) (xy 260.877277 -82.29314) (xy 260.834409 -82.328815) (xy 260.786803 -82.357869)
			(xy 260.735474 -82.379681) (xy 260.681517 -82.393787) (xy 260.62608 -82.399887) (xy 260.570346 -82.39785)
			(xy 260.515503 -82.38772) (xy 260.462719 -82.369713) (xy 260.413119 -82.344212) (xy 260.367761 -82.311761)
			(xy 260.327612 -82.273052) (xy 260.293526 -82.228909) (xy 260.26623 -82.180274) (xy 260.246307 -82.128183)
			(xy 260.234181 -82.073746) (xy 260.23011 -82.018124) (xy 259.829937 -82.018124) (xy 259.829553 -82.039152)
			(xy 259.821433 -82.094328) (xy 259.805365 -82.147735) (xy 259.781693 -82.198232) (xy 259.75092 -82.244745)
			(xy 259.713703 -82.286282) (xy 259.670835 -82.321957) (xy 259.623229 -82.351011) (xy 259.5719 -82.372823)
			(xy 259.517943 -82.386929) (xy 259.462506 -82.393029) (xy 259.406772 -82.390992) (xy 259.351929 -82.380862)
			(xy 259.299145 -82.362855) (xy 259.249545 -82.337354) (xy 259.204187 -82.304903) (xy 259.164038 -82.266194)
			(xy 259.129952 -82.222051) (xy 259.102656 -82.173416) (xy 259.082733 -82.121325) (xy 259.070607 -82.066888)
			(xy 259.066536 -82.011266) (xy 257.752875 -82.011266) (xy 257.764795 -82.050886) (xy 257.772915 -82.106062)
			(xy 257.773424 -82.133948) (xy 257.772915 -82.161834) (xy 257.764795 -82.21701) (xy 257.748727 -82.270417)
			(xy 257.725055 -82.320914) (xy 257.694282 -82.367427) (xy 257.657065 -82.408964) (xy 257.614197 -82.444639)
			(xy 257.566591 -82.473693) (xy 257.515262 -82.495505) (xy 257.461305 -82.509611) (xy 257.405868 -82.515711)
			(xy 257.350134 -82.513674) (xy 257.295291 -82.503544) (xy 257.242507 -82.485537) (xy 257.192907 -82.460036)
			(xy 257.147549 -82.427585) (xy 257.1074 -82.388876) (xy 257.073314 -82.344733) (xy 257.046018 -82.296098)
			(xy 257.026095 -82.244007) (xy 257.013969 -82.18957) (xy 257.009898 -82.133948) (xy 255.181676 -82.133948)
			(xy 255.180853 -82.13954) (xy 255.164785 -82.192947) (xy 255.141113 -82.243444) (xy 255.11034 -82.289957)
			(xy 255.073123 -82.331494) (xy 255.030255 -82.367169) (xy 254.982649 -82.396223) (xy 254.93132 -82.418035)
			(xy 254.877363 -82.432141) (xy 254.821926 -82.438241) (xy 254.766192 -82.436204) (xy 254.711349 -82.426074)
			(xy 254.658565 -82.408067) (xy 254.608965 -82.382566) (xy 254.563607 -82.350115) (xy 254.523458 -82.311406)
			(xy 254.489372 -82.267263) (xy 254.462076 -82.218628) (xy 254.442153 -82.166537) (xy 254.430027 -82.1121)
			(xy 254.425956 -82.056478) (xy 253.980792 -82.056478) (xy 253.963784 -82.082185) (xy 253.926567 -82.123722)
			(xy 253.883699 -82.159397) (xy 253.836093 -82.188451) (xy 253.784764 -82.210263) (xy 253.730807 -82.224369)
			(xy 253.67537 -82.230469) (xy 253.619636 -82.228432) (xy 253.564793 -82.218302) (xy 253.512009 -82.200295)
			(xy 253.462409 -82.174794) (xy 253.417051 -82.142343) (xy 253.376902 -82.103634) (xy 253.342816 -82.059491)
			(xy 253.31552 -82.010856) (xy 253.295597 -81.958765) (xy 253.283471 -81.904328) (xy 253.2794 -81.848706)
			(xy 252.71095 -81.848706) (xy 252.076966 -82.48269) (xy 252.073444 -82.48642) (xy 252.067812 -82.494993)
			(xy 252.06579 -82.499708) (xy 252.062234 -82.508344) (xy 252.062234 -82.778854) (xy 261.582408 -82.778854)
			(xy 261.58293 -82.750012) (xy 261.591615 -82.692986) (xy 261.608779 -82.637915) (xy 261.634032 -82.586053)
			(xy 261.666799 -82.53858) (xy 261.706335 -82.496576) (xy 261.728712 -82.478372) (xy 261.737484 -82.47082)
			(xy 261.747661 -82.450054) (xy 261.74827 -82.438494) (xy 261.74827 -82.35823) (xy 261.747693 -82.346663)
			(xy 261.737504 -82.325891) (xy 261.728712 -82.318352) (xy 261.706325 -82.300159) (xy 261.666787 -82.258155)
			(xy 261.634019 -82.210681) (xy 261.608768 -82.158816) (xy 261.59161 -82.103742) (xy 261.582934 -82.046713)
			(xy 261.582408 -82.01787) (xy 261.582894 -81.990619) (xy 261.59065 -81.936671) (xy 261.606005 -81.884376)
			(xy 261.628647 -81.834799) (xy 261.658113 -81.788949) (xy 261.693804 -81.747758) (xy 261.734995 -81.712067)
			(xy 261.780845 -81.682601) (xy 261.830422 -81.659959) (xy 261.882717 -81.644604) (xy 261.936665 -81.636848)
			(xy 261.991167 -81.636848) (xy 262.045115 -81.644604) (xy 262.09741 -81.659959) (xy 262.146987 -81.682601)
			(xy 262.192837 -81.712067) (xy 262.234028 -81.747758) (xy 262.269719 -81.788949) (xy 262.299185 -81.834799)
			(xy 262.321827 -81.884376) (xy 262.337182 -81.936671) (xy 262.344938 -81.990619) (xy 262.345424 -82.01787)
			(xy 262.344907 -82.046712) (xy 262.33622 -82.103738) (xy 262.319054 -82.158808) (xy 262.2938 -82.21067)
			(xy 262.261032 -82.258143) (xy 262.221497 -82.300147) (xy 262.19912 -82.318352) (xy 262.190371 -82.325925)
			(xy 262.180184 -82.346676) (xy 262.179562 -82.35823) (xy 262.179562 -82.438494) (xy 262.180115 -82.450065)
			(xy 262.19032 -82.470837) (xy 262.19912 -82.478372) (xy 262.221525 -82.496544) (xy 262.261061 -82.538553)
			(xy 262.293825 -82.586032) (xy 262.319073 -82.637901) (xy 262.336228 -82.692979) (xy 262.3449 -82.75001)
			(xy 262.345424 -82.778854) (xy 262.344908 -82.808427) (xy 262.335786 -82.866866) (xy 262.317753 -82.923197)
			(xy 262.291242 -82.976069) (xy 262.256887 -83.024216) (xy 262.215513 -83.066483) (xy 262.168111 -83.101857)
			(xy 262.142224 -83.116166) (xy 262.129778 -83.12277) (xy 262.115046 -83.1469) (xy 262.115554 -83.25104)
			(xy 262.115961 -83.26027) (xy 262.122511 -83.277528) (xy 262.134748 -83.29135) (xy 262.142732 -83.295998)
			(xy 262.165525 -83.308464) (xy 262.207872 -83.338555) (xy 262.245744 -83.374115) (xy 262.278439 -83.414485)
			(xy 262.305353 -83.458919) (xy 262.325988 -83.506594) (xy 262.339961 -83.556629) (xy 262.347015 -83.608097)
			(xy 262.347456 -83.634072) (xy 262.34697 -83.661323) (xy 262.339214 -83.715271) (xy 262.323859 -83.767566)
			(xy 262.301217 -83.817143) (xy 262.271751 -83.862993) (xy 262.23606 -83.904184) (xy 262.194869 -83.939875)
			(xy 262.149019 -83.969341) (xy 262.099442 -83.991983) (xy 262.047147 -84.007338) (xy 261.993199 -84.015094)
			(xy 261.938697 -84.015094) (xy 261.884749 -84.007338) (xy 261.832454 -83.991983) (xy 261.782877 -83.969341)
			(xy 261.737027 -83.939875) (xy 261.695836 -83.904184) (xy 261.660145 -83.862993) (xy 261.630679 -83.817143)
			(xy 261.608037 -83.767566) (xy 261.592682 -83.715271) (xy 261.584926 -83.661323) (xy 261.58444 -83.634072)
			(xy 261.584996 -83.6045) (xy 261.594113 -83.546064) (xy 261.612141 -83.489736) (xy 261.638646 -83.436864)
			(xy 261.672993 -83.388717) (xy 261.714361 -83.346449) (xy 261.761756 -83.311071) (xy 261.78764 -83.29676)
			(xy 261.800086 -83.290156) (xy 261.814818 -83.266026) (xy 261.81431 -83.161886) (xy 261.813902 -83.152656)
			(xy 261.807356 -83.135395) (xy 261.795118 -83.121574) (xy 261.787132 -83.116928) (xy 261.764299 -83.104531)
			(xy 261.721953 -83.07443) (xy 261.684083 -83.038859) (xy 261.651392 -82.998479) (xy 261.624483 -82.954035)
			(xy 261.603855 -82.90635) (xy 261.589889 -82.856307) (xy 261.582844 -82.804832) (xy 261.582408 -82.778854)
			(xy 252.062234 -82.778854) (xy 252.062234 -83.173062) (xy 257.00304 -83.173062) (xy 257.007111 -83.11744)
			(xy 257.019237 -83.063003) (xy 257.03916 -83.010912) (xy 257.066456 -82.962277) (xy 257.100542 -82.918134)
			(xy 257.140691 -82.879425) (xy 257.186049 -82.846974) (xy 257.235649 -82.821473) (xy 257.288433 -82.803466)
			(xy 257.343276 -82.793336) (xy 257.39901 -82.791299) (xy 257.454447 -82.797399) (xy 257.508404 -82.811505)
			(xy 257.559733 -82.833317) (xy 257.607339 -82.862371) (xy 257.650207 -82.898046) (xy 257.687424 -82.939583)
			(xy 257.718197 -82.986096) (xy 257.741869 -83.036593) (xy 257.757937 -83.09) (xy 257.766057 -83.145176)
			(xy 257.766566 -83.173062) (xy 257.766057 -83.200948) (xy 257.757937 -83.256124) (xy 257.741869 -83.309531)
			(xy 257.718197 -83.360028) (xy 257.687424 -83.406541) (xy 257.650207 -83.448078) (xy 257.607339 -83.483753)
			(xy 257.559733 -83.512807) (xy 257.508404 -83.534619) (xy 257.454447 -83.548725) (xy 257.39901 -83.554825)
			(xy 257.343276 -83.552788) (xy 257.288433 -83.542658) (xy 257.235649 -83.524651) (xy 257.186049 -83.49915)
			(xy 257.140691 -83.466699) (xy 257.100542 -83.42799) (xy 257.066456 -83.383847) (xy 257.03916 -83.335212)
			(xy 257.019237 -83.283121) (xy 257.007111 -83.228684) (xy 257.00304 -83.173062) (xy 252.062234 -83.173062)
			(xy 252.062234 -84.748116) (xy 253.089916 -84.748116) (xy 253.093987 -84.692494) (xy 253.106113 -84.638057)
			(xy 253.126036 -84.585966) (xy 253.153332 -84.537331) (xy 253.187418 -84.493188) (xy 253.227567 -84.454479)
			(xy 253.272925 -84.422028) (xy 253.322525 -84.396527) (xy 253.375309 -84.37852) (xy 253.430152 -84.36839)
			(xy 253.485886 -84.366353) (xy 253.541323 -84.372453) (xy 253.59528 -84.386559) (xy 253.646609 -84.408371)
			(xy 253.694215 -84.437425) (xy 253.714113 -84.453984) (xy 254.399286 -84.453984) (xy 254.403357 -84.398362)
			(xy 254.415483 -84.343925) (xy 254.435406 -84.291834) (xy 254.462702 -84.243199) (xy 254.496788 -84.199056)
			(xy 254.536937 -84.160347) (xy 254.582295 -84.127896) (xy 254.631895 -84.102395) (xy 254.684679 -84.084388)
			(xy 254.739522 -84.074258) (xy 254.795256 -84.072221) (xy 254.850693 -84.078321) (xy 254.90465 -84.092427)
			(xy 254.955979 -84.114239) (xy 255.003585 -84.143293) (xy 255.046453 -84.178968) (xy 255.08367 -84.220505)
			(xy 255.114443 -84.267018) (xy 255.138115 -84.317515) (xy 255.154183 -84.370922) (xy 255.162303 -84.426098)
			(xy 255.162812 -84.453984) (xy 255.162303 -84.48187) (xy 255.154183 -84.537046) (xy 255.138115 -84.590453)
			(xy 255.119454 -84.63026) (xy 257.000754 -84.63026) (xy 257.004825 -84.574638) (xy 257.016951 -84.520201)
			(xy 257.036874 -84.46811) (xy 257.06417 -84.419475) (xy 257.098256 -84.375332) (xy 257.138405 -84.336623)
			(xy 257.183763 -84.304172) (xy 257.233363 -84.278671) (xy 257.286147 -84.260664) (xy 257.34099 -84.250534)
			(xy 257.396724 -84.248497) (xy 257.452161 -84.254597) (xy 257.506118 -84.268703) (xy 257.557447 -84.290515)
			(xy 257.605053 -84.319569) (xy 257.647921 -84.355244) (xy 257.685138 -84.396781) (xy 257.715911 -84.443294)
			(xy 257.739583 -84.493791) (xy 257.755651 -84.547198) (xy 257.763771 -84.602374) (xy 257.76428 -84.63026)
			(xy 257.763771 -84.658146) (xy 257.755651 -84.713322) (xy 257.743884 -84.752434) (xy 261.58774 -84.752434)
			(xy 261.591811 -84.696812) (xy 261.603937 -84.642375) (xy 261.62386 -84.590284) (xy 261.651156 -84.541649)
			(xy 261.685242 -84.497506) (xy 261.725391 -84.458797) (xy 261.770749 -84.426346) (xy 261.820349 -84.400845)
			(xy 261.873133 -84.382838) (xy 261.927976 -84.372708) (xy 261.98371 -84.370671) (xy 262.039147 -84.376771)
			(xy 262.093104 -84.390877) (xy 262.144433 -84.412689) (xy 262.192039 -84.441743) (xy 262.234907 -84.477418)
			(xy 262.272124 -84.518955) (xy 262.302897 -84.565468) (xy 262.326569 -84.615965) (xy 262.342637 -84.669372)
			(xy 262.350757 -84.724548) (xy 262.351266 -84.752434) (xy 262.350757 -84.78032) (xy 262.342637 -84.835496)
			(xy 262.326569 -84.888903) (xy 262.302897 -84.9394) (xy 262.272124 -84.985913) (xy 262.234907 -85.02745)
			(xy 262.192039 -85.063125) (xy 262.144433 -85.092179) (xy 262.093104 -85.113991) (xy 262.039147 -85.128097)
			(xy 261.98371 -85.134197) (xy 261.927976 -85.13216) (xy 261.873133 -85.12203) (xy 261.820349 -85.104023)
			(xy 261.770749 -85.078522) (xy 261.725391 -85.046071) (xy 261.685242 -85.007362) (xy 261.651156 -84.963219)
			(xy 261.62386 -84.914584) (xy 261.603937 -84.862493) (xy 261.591811 -84.808056) (xy 261.58774 -84.752434)
			(xy 257.743884 -84.752434) (xy 257.739583 -84.766729) (xy 257.715911 -84.817226) (xy 257.685138 -84.863739)
			(xy 257.647921 -84.905276) (xy 257.605053 -84.940951) (xy 257.557447 -84.970005) (xy 257.506118 -84.991817)
			(xy 257.452161 -85.005923) (xy 257.396724 -85.012023) (xy 257.34099 -85.009986) (xy 257.286147 -84.999856)
			(xy 257.233363 -84.981849) (xy 257.183763 -84.956348) (xy 257.138405 -84.923897) (xy 257.098256 -84.885188)
			(xy 257.06417 -84.841045) (xy 257.036874 -84.79241) (xy 257.016951 -84.740319) (xy 257.004825 -84.685882)
			(xy 257.000754 -84.63026) (xy 255.119454 -84.63026) (xy 255.114443 -84.64095) (xy 255.08367 -84.687463)
			(xy 255.046453 -84.729) (xy 255.003585 -84.764675) (xy 254.955979 -84.793729) (xy 254.90465 -84.815541)
			(xy 254.850693 -84.829647) (xy 254.795256 -84.835747) (xy 254.739522 -84.83371) (xy 254.684679 -84.82358)
			(xy 254.631895 -84.805573) (xy 254.582295 -84.780072) (xy 254.536937 -84.747621) (xy 254.496788 -84.708912)
			(xy 254.462702 -84.664769) (xy 254.435406 -84.616134) (xy 254.415483 -84.564043) (xy 254.403357 -84.509606)
			(xy 254.399286 -84.453984) (xy 253.714113 -84.453984) (xy 253.737083 -84.4731) (xy 253.7743 -84.514637)
			(xy 253.805073 -84.56115) (xy 253.828745 -84.611647) (xy 253.844813 -84.665054) (xy 253.852933 -84.72023)
			(xy 253.853442 -84.748116) (xy 253.852933 -84.776002) (xy 253.844813 -84.831178) (xy 253.828745 -84.884585)
			(xy 253.805073 -84.935082) (xy 253.7743 -84.981595) (xy 253.737083 -85.023132) (xy 253.694215 -85.058807)
			(xy 253.646609 -85.087861) (xy 253.59528 -85.109673) (xy 253.541323 -85.123779) (xy 253.485886 -85.129879)
			(xy 253.430152 -85.127842) (xy 253.375309 -85.117712) (xy 253.322525 -85.099705) (xy 253.272925 -85.074204)
			(xy 253.227567 -85.041753) (xy 253.187418 -85.003044) (xy 253.153332 -84.958901) (xy 253.126036 -84.910266)
			(xy 253.106113 -84.858175) (xy 253.093987 -84.803738) (xy 253.089916 -84.748116) (xy 252.062234 -84.748116)
			(xy 252.062234 -84.820252) (xy 252.062603 -84.829686) (xy 252.069412 -84.847283) (xy 252.082127 -84.861224)
			(xy 252.090428 -84.865718) (xy 252.171962 -84.906104) (xy 252.178404 -84.90905) (xy 252.192325 -84.911635)
			(xy 252.199394 -84.911184) (xy 252.199648 -84.911184) (xy 252.224794 -84.901532) (xy 252.225302 -84.901278)
			(xy 252.22962 -84.89823) (xy 252.230382 -84.897468) (xy 252.255038 -84.88011) (xy 252.308679 -84.852574)
			(xy 252.365987 -84.83383) (xy 252.425532 -84.824346) (xy 252.45568 -84.823808) (xy 252.482933 -84.82427)
			(xy 252.536886 -84.832025) (xy 252.589185 -84.847379) (xy 252.638767 -84.870021) (xy 252.684621 -84.899488)
			(xy 252.725815 -84.935182) (xy 252.761509 -84.976376) (xy 252.790977 -85.02223) (xy 252.813619 -85.071811)
			(xy 252.828974 -85.12411) (xy 252.83673 -85.178063) (xy 252.837188 -85.205316) (xy 252.836632 -85.234992)
			(xy 252.82746 -85.293632) (xy 252.809324 -85.350146) (xy 252.782661 -85.403172) (xy 252.748113 -85.451433)
			(xy 252.706513 -85.493767) (xy 252.68301 -85.511894) (xy 252.675136 -85.517736) (xy 252.670564 -85.524848)
			(xy 252.668159 -85.528927) (xy 252.664716 -85.537747) (xy 252.663706 -85.542374) (xy 252.660658 -85.557614)
			(xy 252.648466 -85.618574) (xy 252.649736 -85.62594) (xy 252.665102 -85.64986) (xy 252.689402 -85.701256)
			(xy 252.705909 -85.755657) (xy 252.714267 -85.811891) (xy 252.714469 -85.823552) (xy 261.571232 -85.823552)
			(xy 261.571718 -85.796301) (xy 261.579474 -85.742353) (xy 261.594829 -85.690058) (xy 261.617471 -85.640481)
			(xy 261.646937 -85.594631) (xy 261.682628 -85.55344) (xy 261.723819 -85.517749) (xy 261.769669 -85.488283)
			(xy 261.819246 -85.465641) (xy 261.871541 -85.450286) (xy 261.925489 -85.44253) (xy 261.979991 -85.44253)
			(xy 262.033939 -85.450286) (xy 262.086234 -85.465641) (xy 262.135811 -85.488283) (xy 262.181661 -85.517749)
			(xy 262.222852 -85.55344) (xy 262.258543 -85.594631) (xy 262.288009 -85.640481) (xy 262.310651 -85.690058)
			(xy 262.326006 -85.742353) (xy 262.333762 -85.796301) (xy 262.334248 -85.823552) (xy 262.333685 -85.852529)
			(xy 262.324931 -85.909818) (xy 262.307619 -85.965125) (xy 262.282144 -86.01718) (xy 262.249094 -86.064786)
			(xy 262.209227 -86.106848) (xy 262.186674 -86.12505) (xy 262.176201 -86.133708) (xy 262.159887 -86.155428)
			(xy 262.149882 -86.180682) (xy 262.146895 -86.207682) (xy 262.151139 -86.234513) (xy 262.162312 -86.259273)
			(xy 262.179621 -86.280207) (xy 262.190484 -86.288372) (xy 262.211606 -86.303746) (xy 262.249835 -86.339354)
			(xy 262.282849 -86.379843) (xy 262.310032 -86.424456) (xy 262.330876 -86.472361) (xy 262.34499 -86.522661)
			(xy 262.352111 -86.574417) (xy 262.352536 -86.600538) (xy 262.35205 -86.627789) (xy 262.344294 -86.681737)
			(xy 262.328939 -86.734032) (xy 262.306297 -86.783609) (xy 262.276831 -86.829459) (xy 262.24114 -86.87065)
			(xy 262.199949 -86.906341) (xy 262.154099 -86.935807) (xy 262.104522 -86.958449) (xy 262.052227 -86.973804)
			(xy 261.998279 -86.98156) (xy 261.943777 -86.98156) (xy 261.889829 -86.973804) (xy 261.837534 -86.958449)
			(xy 261.787957 -86.935807) (xy 261.742107 -86.906341) (xy 261.700916 -86.87065) (xy 261.665225 -86.829459)
			(xy 261.635759 -86.783609) (xy 261.613117 -86.734032) (xy 261.597762 -86.681737) (xy 261.590006 -86.627789)
			(xy 261.58952 -86.600538) (xy 261.590089 -86.571561) (xy 261.598843 -86.514273) (xy 261.616155 -86.458967)
			(xy 261.641628 -86.406912) (xy 261.674677 -86.359306) (xy 261.714542 -86.317242) (xy 261.737094 -86.29904)
			(xy 261.74757 -86.290388) (xy 261.763872 -86.268663) (xy 261.773869 -86.243409) (xy 261.776852 -86.216412)
			(xy 261.772609 -86.189584) (xy 261.761443 -86.164825) (xy 261.744142 -86.143887) (xy 261.733284 -86.135718)
			(xy 261.71215 -86.120359) (xy 261.673923 -86.084748) (xy 261.640911 -86.044256) (xy 261.61373 -85.99964)
			(xy 261.592888 -85.951733) (xy 261.578776 -85.901431) (xy 261.571657 -85.849674) (xy 261.571232 -85.823552)
			(xy 252.714469 -85.823552) (xy 252.71476 -85.840316) (xy 252.71429 -85.867894) (xy 252.706438 -85.922489)
			(xy 252.690897 -85.975411) (xy 252.667982 -86.025582) (xy 252.63816 -86.071981) (xy 252.602038 -86.113664)
			(xy 252.560352 -86.149781) (xy 252.51395 -86.179599) (xy 252.463777 -86.202509) (xy 252.410854 -86.218046)
			(xy 252.356258 -86.225893) (xy 252.32868 -86.226396) (xy 252.30297 -86.225958) (xy 252.252008 -86.219105)
			(xy 252.202406 -86.20555) (xy 252.178566 -86.195916) (xy 252.171499 -86.196543) (xy 252.1581 -86.201194)
			(xy 252.15215 -86.20506) (xy 252.083824 -86.252812) (xy 252.074246 -86.26039) (xy 252.062988 -86.282021)
			(xy 252.062234 -86.294214) (xy 252.062234 -86.336886) (xy 256.999484 -86.336886) (xy 257.003555 -86.281264)
			(xy 257.015681 -86.226827) (xy 257.035604 -86.174736) (xy 257.0629 -86.126101) (xy 257.096986 -86.081958)
			(xy 257.137135 -86.043249) (xy 257.182493 -86.010798) (xy 257.232093 -85.985297) (xy 257.284877 -85.96729)
			(xy 257.33972 -85.95716) (xy 257.395454 -85.955123) (xy 257.450891 -85.961223) (xy 257.504848 -85.975329)
			(xy 257.556177 -85.997141) (xy 257.603783 -86.026195) (xy 257.646651 -86.06187) (xy 257.683868 -86.103407)
			(xy 257.714641 -86.14992) (xy 257.738313 -86.200417) (xy 257.754381 -86.253824) (xy 257.762501 -86.309)
			(xy 257.76301 -86.336886) (xy 257.762501 -86.364772) (xy 257.754381 -86.419948) (xy 257.738313 -86.473355)
			(xy 257.714641 -86.523852) (xy 257.683868 -86.570365) (xy 257.657516 -86.599776) (xy 259.420612 -86.599776)
			(xy 259.424683 -86.544154) (xy 259.436809 -86.489717) (xy 259.456732 -86.437626) (xy 259.484028 -86.388991)
			(xy 259.518114 -86.344848) (xy 259.558263 -86.306139) (xy 259.603621 -86.273688) (xy 259.653221 -86.248187)
			(xy 259.706005 -86.23018) (xy 259.760848 -86.22005) (xy 259.816582 -86.218013) (xy 259.872019 -86.224113)
			(xy 259.925976 -86.238219) (xy 259.977305 -86.260031) (xy 260.024911 -86.289085) (xy 260.067779 -86.32476)
			(xy 260.104996 -86.366297) (xy 260.135769 -86.41281) (xy 260.159441 -86.463307) (xy 260.175509 -86.516714)
			(xy 260.183629 -86.57189) (xy 260.184138 -86.599776) (xy 260.183629 -86.627662) (xy 260.175509 -86.682838)
			(xy 260.159441 -86.736245) (xy 260.135769 -86.786742) (xy 260.104996 -86.833255) (xy 260.067779 -86.874792)
			(xy 260.024911 -86.910467) (xy 259.977305 -86.939521) (xy 259.925976 -86.961333) (xy 259.872019 -86.975439)
			(xy 259.816582 -86.981539) (xy 259.760848 -86.979502) (xy 259.706005 -86.969372) (xy 259.653221 -86.951365)
			(xy 259.603621 -86.925864) (xy 259.558263 -86.893413) (xy 259.518114 -86.854704) (xy 259.484028 -86.810561)
			(xy 259.456732 -86.761926) (xy 259.436809 -86.709835) (xy 259.424683 -86.655398) (xy 259.420612 -86.599776)
			(xy 257.657516 -86.599776) (xy 257.646651 -86.611902) (xy 257.603783 -86.647577) (xy 257.556177 -86.676631)
			(xy 257.504848 -86.698443) (xy 257.450891 -86.712549) (xy 257.395454 -86.718649) (xy 257.33972 -86.716612)
			(xy 257.284877 -86.706482) (xy 257.232093 -86.688475) (xy 257.182493 -86.662974) (xy 257.137135 -86.630523)
			(xy 257.096986 -86.591814) (xy 257.0629 -86.547671) (xy 257.035604 -86.499036) (xy 257.015681 -86.446945)
			(xy 257.003555 -86.392508) (xy 256.999484 -86.336886) (xy 252.062234 -86.336886) (xy 252.062234 -87.499444)
			(xy 256.099562 -87.499444) (xy 256.103633 -87.443822) (xy 256.115759 -87.389385) (xy 256.135682 -87.337294)
			(xy 256.162978 -87.288659) (xy 256.197064 -87.244516) (xy 256.237213 -87.205807) (xy 256.282571 -87.173356)
			(xy 256.332171 -87.147855) (xy 256.384955 -87.129848) (xy 256.439798 -87.119718) (xy 256.495532 -87.117681)
			(xy 256.550969 -87.123781) (xy 256.604926 -87.137887) (xy 256.656255 -87.159699) (xy 256.703861 -87.188753)
			(xy 256.746729 -87.224428) (xy 256.783946 -87.265965) (xy 256.814719 -87.312478) (xy 256.838391 -87.362975)
			(xy 256.854459 -87.416382) (xy 256.862579 -87.471558) (xy 256.863088 -87.499444) (xy 256.862579 -87.52733)
			(xy 256.854459 -87.582506) (xy 256.838391 -87.635913) (xy 256.814719 -87.68641) (xy 256.783946 -87.732923)
			(xy 256.746729 -87.77446) (xy 256.703861 -87.810135) (xy 256.656255 -87.839189) (xy 256.604926 -87.861001)
			(xy 256.550969 -87.875107) (xy 256.495532 -87.881207) (xy 256.439798 -87.87917) (xy 256.384955 -87.86904)
			(xy 256.332171 -87.851033) (xy 256.282571 -87.825532) (xy 256.237213 -87.793081) (xy 256.197064 -87.754372)
			(xy 256.162978 -87.710229) (xy 256.135682 -87.661594) (xy 256.115759 -87.609503) (xy 256.103633 -87.555066)
			(xy 256.099562 -87.499444) (xy 252.062234 -87.499444) (xy 252.062234 -88.634316) (xy 253.724662 -88.634316)
			(xy 253.728733 -88.578694) (xy 253.740859 -88.524257) (xy 253.760782 -88.472166) (xy 253.788078 -88.423531)
			(xy 253.822164 -88.379388) (xy 253.862313 -88.340679) (xy 253.907671 -88.308228) (xy 253.957271 -88.282727)
			(xy 254.010055 -88.26472) (xy 254.064898 -88.25459) (xy 254.120632 -88.252553) (xy 254.176069 -88.258653)
			(xy 254.230026 -88.272759) (xy 254.281355 -88.294571) (xy 254.328961 -88.323625) (xy 254.371829 -88.3593)
			(xy 254.409046 -88.400837) (xy 254.439819 -88.44735) (xy 254.463491 -88.497847) (xy 254.479559 -88.551254)
			(xy 254.487679 -88.60643) (xy 254.488188 -88.634316) (xy 254.487679 -88.662202) (xy 254.479559 -88.717378)
			(xy 254.463491 -88.770785) (xy 254.439819 -88.821282) (xy 254.409046 -88.867795) (xy 254.371829 -88.909332)
			(xy 254.328961 -88.945007) (xy 254.281355 -88.974061) (xy 254.230026 -88.995873) (xy 254.176069 -89.009979)
			(xy 254.120632 -89.016079) (xy 254.064898 -89.014042) (xy 254.010055 -89.003912) (xy 253.957271 -88.985905)
			(xy 253.907671 -88.960404) (xy 253.862313 -88.927953) (xy 253.822164 -88.889244) (xy 253.788078 -88.845101)
			(xy 253.760782 -88.796466) (xy 253.740859 -88.744375) (xy 253.728733 -88.689938) (xy 253.724662 -88.634316)
			(xy 252.062234 -88.634316) (xy 252.062234 -89.11971) (xy 252.062996 -89.128092) (xy 252.064509 -89.135697)
			(xy 252.071494 -89.149533) (xy 252.076712 -89.15527) (xy 252.43536 -89.513918) (xy 252.440694 -89.51849)
			(xy 252.441202 -89.518998) (xy 252.451843 -89.525842) (xy 252.476893 -89.529171) (xy 252.488954 -89.525348)
			(xy 252.517402 -89.513664) (xy 252.5776 -89.488518) (xy 252.584414 -89.485427) (xy 252.596025 -89.476002)
			(xy 252.60046 -89.469976) (xy 252.60427 -89.46388) (xy 252.608588 -89.44991) (xy 252.608588 -89.441528)
			(xy 252.609049 -89.414274) (xy 252.616803 -89.360321) (xy 252.632156 -89.308021) (xy 252.654796 -89.258438)
			(xy 252.684261 -89.212582) (xy 252.719954 -89.171386) (xy 252.761145 -89.135689) (xy 252.806998 -89.106217)
			(xy 252.856578 -89.083572) (xy 252.908877 -89.068212) (xy 252.962829 -89.060453) (xy 253.017336 -89.06045)
			(xy 253.071289 -89.068205) (xy 253.123589 -89.083559) (xy 253.173171 -89.106201) (xy 253.219027 -89.135668)
			(xy 253.260222 -89.171361) (xy 253.295918 -89.212554) (xy 253.325388 -89.258408) (xy 253.348032 -89.307988)
			(xy 253.36339 -89.360287) (xy 253.371148 -89.41424) (xy 253.371149 -89.468747) (xy 253.363393 -89.5227)
			(xy 253.348037 -89.574999) (xy 253.325394 -89.624581) (xy 253.295926 -89.670435) (xy 253.260231 -89.711629)
			(xy 253.219038 -89.747324) (xy 253.173183 -89.776793) (xy 253.123602 -89.799436) (xy 253.071302 -89.814792)
			(xy 253.01735 -89.822549) (xy 252.990096 -89.823036) (xy 252.989588 -89.823036) (xy 252.982088 -89.823275)
			(xy 252.967751 -89.827683) (xy 252.961394 -89.831672) (xy 252.955298 -89.835482) (xy 252.9459 -89.846912)
			(xy 252.91796 -89.914222) (xy 252.906276 -89.94267) (xy 252.902412 -89.954729) (xy 252.905735 -89.9798)
			(xy 252.912626 -89.990422) (xy 252.913134 -89.99093) (xy 252.917452 -89.99601) (xy 253.149354 -90.227658)
			(xy 253.156753 -90.2345) (xy 253.175352 -90.242222) (xy 253.185422 -90.242644)
		)
		(stroke
			(width 0)
			(type solid)
		)
		(fill yes)
		(layer "In15.Cu")
		(net "P3V3_CLK_GEN_VDDMXCK_CK440")
	)
	(gr_poly
		(pts
			(xy 95.470218 -239.110266) (xy 95.480286 -239.109839) (xy 95.498883 -239.102116) (xy 95.506286 -239.09528)
			(xy 96.515936 -238.08563) (xy 96.522779 -238.078231) (xy 96.530498 -238.059632) (xy 96.530922 -238.049562)
			(xy 96.530922 -221.940882) (xy 96.530496 -221.930813) (xy 96.52278 -221.912211) (xy 96.515936 -221.904814)
			(xy 95.894398 -221.283276) (xy 95.891858 -221.281244) (xy 95.883406 -221.274652) (xy 95.867265 -221.260544)
			(xy 95.8596 -221.25305) (xy 95.413576 -220.807026) (xy 95.406071 -220.799372) (xy 95.391962 -220.78323)
			(xy 95.385382 -220.774768) (xy 95.38335 -220.772228) (xy 95.251524 -220.640402) (xy 95.244675 -220.633005)
			(xy 95.236936 -220.614407) (xy 95.236538 -220.604334) (xy 95.236538 -220.17101) (xy 95.236115 -220.16094)
			(xy 95.228396 -220.142339) (xy 95.221552 -220.134942) (xy 94.748096 -219.661486) (xy 94.740701 -219.654631)
			(xy 94.722102 -219.646884) (xy 94.712028 -219.6465) (xy 70.344284 -219.6465) (xy 70.317868 -219.665296)
			(xy 70.312534 -219.68079) (xy 70.303085 -219.707027) (xy 70.277608 -219.756633) (xy 70.245177 -219.801999)
			(xy 70.206485 -219.842157) (xy 70.162355 -219.876251) (xy 70.11373 -219.903554) (xy 70.061647 -219.923482)
			(xy 70.007217 -219.935612) (xy 69.9516 -219.939684) (xy 69.895983 -219.935612) (xy 69.841553 -219.923482)
			(xy 69.78947 -219.903554) (xy 69.740845 -219.876251) (xy 69.696715 -219.842157) (xy 69.658023 -219.801999)
			(xy 69.625592 -219.756633) (xy 69.600115 -219.707027) (xy 69.590666 -219.68079) (xy 69.585332 -219.665296)
			(xy 69.558916 -219.6465) (xy 22.575012 -219.6465) (xy 22.564941 -219.646921) (xy 22.546333 -219.654632)
			(xy 22.538944 -219.661486) (xy 21.676106 -220.524324) (xy 25.975562 -220.524324) (xy 25.979633 -220.468702)
			(xy 25.991759 -220.414265) (xy 26.011682 -220.362174) (xy 26.038978 -220.313539) (xy 26.073064 -220.269396)
			(xy 26.113213 -220.230687) (xy 26.158571 -220.198236) (xy 26.208171 -220.172735) (xy 26.260955 -220.154728)
			(xy 26.315798 -220.144598) (xy 26.371532 -220.142561) (xy 26.426969 -220.148661) (xy 26.480926 -220.162767)
			(xy 26.532255 -220.184579) (xy 26.579861 -220.213633) (xy 26.622729 -220.249308) (xy 26.659946 -220.290845)
			(xy 26.690719 -220.337358) (xy 26.714391 -220.387855) (xy 26.730459 -220.441262) (xy 26.738579 -220.496438)
			(xy 26.739088 -220.524324) (xy 26.738579 -220.55221) (xy 26.730459 -220.607386) (xy 26.714391 -220.660793)
			(xy 26.690719 -220.71129) (xy 26.659946 -220.757803) (xy 26.622729 -220.79934) (xy 26.579861 -220.835015)
			(xy 26.532255 -220.864069) (xy 26.480926 -220.885881) (xy 26.426969 -220.899987) (xy 26.371532 -220.906087)
			(xy 26.315798 -220.90405) (xy 26.260955 -220.89392) (xy 26.208171 -220.875913) (xy 26.158571 -220.850412)
			(xy 26.113213 -220.817961) (xy 26.073064 -220.779252) (xy 26.038978 -220.735109) (xy 26.011682 -220.686474)
			(xy 25.991759 -220.634383) (xy 25.979633 -220.579946) (xy 25.975562 -220.524324) (xy 21.676106 -220.524324)
			(xy 20.867624 -221.332806) (xy 22.477982 -221.332806) (xy 22.482053 -221.277184) (xy 22.494179 -221.222747)
			(xy 22.514102 -221.170656) (xy 22.541398 -221.122021) (xy 22.575484 -221.077878) (xy 22.615633 -221.039169)
			(xy 22.660991 -221.006718) (xy 22.710591 -220.981217) (xy 22.763375 -220.96321) (xy 22.818218 -220.95308)
			(xy 22.873952 -220.951043) (xy 22.929389 -220.957143) (xy 22.983346 -220.971249) (xy 23.034675 -220.993061)
			(xy 23.082281 -221.022115) (xy 23.125149 -221.05779) (xy 23.162366 -221.099327) (xy 23.193139 -221.14584)
			(xy 23.216811 -221.196337) (xy 23.232879 -221.249744) (xy 23.240999 -221.30492) (xy 23.241508 -221.332806)
			(xy 23.240999 -221.360692) (xy 23.232879 -221.415868) (xy 23.216811 -221.469275) (xy 23.193139 -221.519772)
			(xy 23.162366 -221.566285) (xy 23.125149 -221.607822) (xy 23.082281 -221.643497) (xy 23.034675 -221.672551)
			(xy 22.983346 -221.694363) (xy 22.929389 -221.708469) (xy 22.873952 -221.714569) (xy 22.818218 -221.712532)
			(xy 22.763375 -221.702402) (xy 22.710591 -221.684395) (xy 22.660991 -221.658894) (xy 22.615633 -221.626443)
			(xy 22.575484 -221.587734) (xy 22.541398 -221.543591) (xy 22.514102 -221.494956) (xy 22.494179 -221.442865)
			(xy 22.482053 -221.388428) (xy 22.477982 -221.332806) (xy 20.867624 -221.332806) (xy 20.136612 -222.063818)
			(xy 25.616662 -222.063818) (xy 25.617148 -222.036567) (xy 25.624904 -221.982619) (xy 25.640259 -221.930324)
			(xy 25.662901 -221.880747) (xy 25.692367 -221.834897) (xy 25.728058 -221.793706) (xy 25.769249 -221.758015)
			(xy 25.815099 -221.728549) (xy 25.864676 -221.705907) (xy 25.916971 -221.690552) (xy 25.970919 -221.682796)
			(xy 26.025421 -221.682796) (xy 26.079369 -221.690552) (xy 26.131664 -221.705907) (xy 26.181241 -221.728549)
			(xy 26.227091 -221.758015) (xy 26.268282 -221.793706) (xy 26.303973 -221.834897) (xy 26.333439 -221.880747)
			(xy 26.356081 -221.930324) (xy 26.371436 -221.982619) (xy 26.379192 -222.036567) (xy 26.379678 -222.063818)
			(xy 26.379197 -222.090681) (xy 26.371658 -222.143877) (xy 26.356731 -222.195488) (xy 26.334711 -222.244495)
			(xy 26.306034 -222.289929) (xy 26.289 -222.310706) (xy 26.28138 -222.319596) (xy 26.275538 -222.342202)
			(xy 26.296112 -222.443548) (xy 26.310082 -222.46209) (xy 26.320496 -222.46717) (xy 26.343793 -222.479423)
			(xy 26.387068 -222.509392) (xy 26.425814 -222.545024) (xy 26.459295 -222.585642) (xy 26.486876 -222.630476)
			(xy 26.508034 -222.678676) (xy 26.522367 -222.729326) (xy 26.529603 -222.781465) (xy 26.530046 -222.807784)
			(xy 26.52956 -222.835035) (xy 26.521804 -222.888983) (xy 26.506449 -222.941278) (xy 26.483807 -222.990855)
			(xy 26.454341 -223.036705) (xy 26.41865 -223.077896) (xy 26.377459 -223.113587) (xy 26.331609 -223.143053)
			(xy 26.282032 -223.165695) (xy 26.229737 -223.18105) (xy 26.175789 -223.188806) (xy 26.121287 -223.188806)
			(xy 26.067339 -223.18105) (xy 26.015044 -223.165695) (xy 25.965467 -223.143053) (xy 25.919617 -223.113587)
			(xy 25.878426 -223.077896) (xy 25.842735 -223.036705) (xy 25.813269 -222.990855) (xy 25.790627 -222.941278)
			(xy 25.775272 -222.888983) (xy 25.767516 -222.835035) (xy 25.76703 -222.807784) (xy 25.767476 -222.78092)
			(xy 25.775027 -222.727724) (xy 25.789964 -222.676113) (xy 25.81199 -222.627106) (xy 25.840672 -222.581673)
			(xy 25.857708 -222.560896) (xy 25.865328 -222.552006) (xy 25.87117 -222.5294) (xy 25.850596 -222.428054)
			(xy 25.836626 -222.409512) (xy 25.826212 -222.404432) (xy 25.802918 -222.392174) (xy 25.759643 -222.362206)
			(xy 25.720897 -222.326575) (xy 25.687415 -222.285958) (xy 25.659833 -222.241124) (xy 25.638675 -222.192925)
			(xy 25.624341 -222.142276) (xy 25.617105 -222.090137) (xy 25.616662 -222.063818) (xy 20.136612 -222.063818)
			(xy 19.565112 -222.635318) (xy 19.556965 -222.644557) (xy 19.549672 -222.668045) (xy 19.551142 -222.680276)
			(xy 19.568414 -222.775018) (xy 19.583654 -222.794576) (xy 19.595084 -222.799656) (xy 19.619825 -222.811341)
			(xy 19.665966 -222.840746) (xy 19.707434 -222.876441) (xy 19.743378 -222.917694) (xy 19.77306 -222.963658)
			(xy 19.795872 -223.01339) (xy 19.811346 -223.065871) (xy 19.814057 -223.084644) (xy 21.0472 -223.084644)
			(xy 21.051271 -223.029022) (xy 21.063397 -222.974585) (xy 21.08332 -222.922494) (xy 21.110616 -222.873859)
			(xy 21.144702 -222.829716) (xy 21.184851 -222.791007) (xy 21.230209 -222.758556) (xy 21.279809 -222.733055)
			(xy 21.332593 -222.715048) (xy 21.387436 -222.704918) (xy 21.44317 -222.702881) (xy 21.498607 -222.708981)
			(xy 21.552564 -222.723087) (xy 21.603893 -222.744899) (xy 21.651499 -222.773953) (xy 21.694367 -222.809628)
			(xy 21.731584 -222.851165) (xy 21.762357 -222.897678) (xy 21.786029 -222.948175) (xy 21.802097 -223.001582)
			(xy 21.810217 -223.056758) (xy 21.810726 -223.084644) (xy 21.810217 -223.11253) (xy 21.802097 -223.167706)
			(xy 21.786029 -223.221113) (xy 21.762357 -223.27161) (xy 21.731584 -223.318123) (xy 21.694367 -223.35966)
			(xy 21.651499 -223.395335) (xy 21.603893 -223.424389) (xy 21.552564 -223.446201) (xy 21.498607 -223.460307)
			(xy 21.44317 -223.466407) (xy 21.387436 -223.46437) (xy 21.332593 -223.45424) (xy 21.279809 -223.436233)
			(xy 21.230209 -223.410732) (xy 21.184851 -223.378281) (xy 21.144702 -223.339572) (xy 21.110616 -223.295429)
			(xy 21.08332 -223.246794) (xy 21.063397 -223.194703) (xy 21.051271 -223.140266) (xy 21.0472 -223.084644)
			(xy 19.814057 -223.084644) (xy 19.819165 -223.120025) (xy 19.81962 -223.147382) (xy 19.819158 -223.174636)
			(xy 19.811404 -223.22859) (xy 19.796049 -223.28089) (xy 19.773408 -223.330474) (xy 19.74394 -223.37633)
			(xy 19.708247 -223.417526) (xy 19.667054 -223.453222) (xy 19.6212 -223.482693) (xy 19.571619 -223.505339)
			(xy 19.519319 -223.520697) (xy 19.465366 -223.528456) (xy 19.438112 -223.52889) (xy 19.410755 -223.52842)
			(xy 19.356602 -223.520605) (xy 19.304121 -223.505134) (xy 19.254389 -223.482324) (xy 19.208425 -223.452644)
			(xy 19.167174 -223.416701) (xy 19.13148 -223.375233) (xy 19.102076 -223.329092) (xy 19.090386 -223.304354)
			(xy 19.085306 -223.292924) (xy 19.065748 -223.277684) (xy 18.971006 -223.260412) (xy 18.958777 -223.258924)
			(xy 18.935295 -223.266238) (xy 18.926048 -223.274382) (xy 17.899634 -224.300796) (xy 17.892819 -224.308139)
			(xy 17.88508 -224.326602) (xy 17.884648 -224.33661) (xy 17.884648 -224.536) (xy 27.78328 -224.536)
			(xy 27.787351 -224.480378) (xy 27.799477 -224.425941) (xy 27.8194 -224.37385) (xy 27.846696 -224.325215)
			(xy 27.880782 -224.281072) (xy 27.920931 -224.242363) (xy 27.966289 -224.209912) (xy 28.015889 -224.184411)
			(xy 28.068673 -224.166404) (xy 28.123516 -224.156274) (xy 28.17925 -224.154237) (xy 28.234687 -224.160337)
			(xy 28.288644 -224.174443) (xy 28.339973 -224.196255) (xy 28.387579 -224.225309) (xy 28.430447 -224.260984)
			(xy 28.467664 -224.302521) (xy 28.498437 -224.349034) (xy 28.522109 -224.399531) (xy 28.538177 -224.452938)
			(xy 28.546297 -224.508114) (xy 28.546806 -224.536) (xy 28.546297 -224.563886) (xy 28.538177 -224.619062)
			(xy 28.522109 -224.672469) (xy 28.498437 -224.722966) (xy 28.467664 -224.769479) (xy 28.430447 -224.811016)
			(xy 28.387579 -224.846691) (xy 28.339973 -224.875745) (xy 28.288644 -224.897557) (xy 28.234687 -224.911663)
			(xy 28.17925 -224.917763) (xy 28.123516 -224.915726) (xy 28.068673 -224.905596) (xy 28.015889 -224.887589)
			(xy 27.966289 -224.862088) (xy 27.920931 -224.829637) (xy 27.880782 -224.790928) (xy 27.846696 -224.746785)
			(xy 27.8194 -224.69815) (xy 27.799477 -224.646059) (xy 27.787351 -224.591622) (xy 27.78328 -224.536)
			(xy 17.884648 -224.536) (xy 17.884648 -225.82251) (xy 18.421094 -225.82251) (xy 18.425165 -225.766888)
			(xy 18.437291 -225.712451) (xy 18.457214 -225.66036) (xy 18.48451 -225.611725) (xy 18.518596 -225.567582)
			(xy 18.558745 -225.528873) (xy 18.604103 -225.496422) (xy 18.653703 -225.470921) (xy 18.706487 -225.452914)
			(xy 18.76133 -225.442784) (xy 18.817064 -225.440747) (xy 18.872501 -225.446847) (xy 18.926458 -225.460953)
			(xy 18.977787 -225.482765) (xy 19.025393 -225.511819) (xy 19.068261 -225.547494) (xy 19.105478 -225.589031)
			(xy 19.136251 -225.635544) (xy 19.158408 -225.68281) (xy 20.720048 -225.68281) (xy 20.724119 -225.627188)
			(xy 20.736245 -225.572751) (xy 20.756168 -225.52066) (xy 20.783464 -225.472025) (xy 20.81755 -225.427882)
			(xy 20.857699 -225.389173) (xy 20.903057 -225.356722) (xy 20.952657 -225.331221) (xy 21.005441 -225.313214)
			(xy 21.060284 -225.303084) (xy 21.116018 -225.301047) (xy 21.171455 -225.307147) (xy 21.225412 -225.321253)
			(xy 21.276741 -225.343065) (xy 21.324347 -225.372119) (xy 21.367215 -225.407794) (xy 21.404432 -225.449331)
			(xy 21.435205 -225.495844) (xy 21.458877 -225.546341) (xy 21.46058 -225.552) (xy 30.83128 -225.552)
			(xy 30.835351 -225.496378) (xy 30.847477 -225.441941) (xy 30.8674 -225.38985) (xy 30.894696 -225.341215)
			(xy 30.928782 -225.297072) (xy 30.968931 -225.258363) (xy 31.014289 -225.225912) (xy 31.063889 -225.200411)
			(xy 31.116673 -225.182404) (xy 31.171516 -225.172274) (xy 31.22725 -225.170237) (xy 31.282687 -225.176337)
			(xy 31.336644 -225.190443) (xy 31.387973 -225.212255) (xy 31.435579 -225.241309) (xy 31.478447 -225.276984)
			(xy 31.515664 -225.318521) (xy 31.546437 -225.365034) (xy 31.570109 -225.415531) (xy 31.586177 -225.468938)
			(xy 31.594297 -225.524114) (xy 31.594806 -225.552) (xy 31.594297 -225.579886) (xy 31.586177 -225.635062)
			(xy 31.570109 -225.688469) (xy 31.546437 -225.738966) (xy 31.515664 -225.785479) (xy 31.478447 -225.827016)
			(xy 31.435579 -225.862691) (xy 31.387973 -225.891745) (xy 31.336644 -225.913557) (xy 31.282687 -225.927663)
			(xy 31.22725 -225.933763) (xy 31.171516 -225.931726) (xy 31.116673 -225.921596) (xy 31.063889 -225.903589)
			(xy 31.014289 -225.878088) (xy 30.968931 -225.845637) (xy 30.928782 -225.806928) (xy 30.894696 -225.762785)
			(xy 30.8674 -225.71415) (xy 30.847477 -225.662059) (xy 30.835351 -225.607622) (xy 30.83128 -225.552)
			(xy 21.46058 -225.552) (xy 21.474945 -225.599748) (xy 21.483065 -225.654924) (xy 21.483574 -225.68281)
			(xy 21.483065 -225.710696) (xy 21.474945 -225.765872) (xy 21.458877 -225.819279) (xy 21.435205 -225.869776)
			(xy 21.404432 -225.916289) (xy 21.367215 -225.957826) (xy 21.324347 -225.993501) (xy 21.276741 -226.022555)
			(xy 21.225412 -226.044367) (xy 21.171455 -226.058473) (xy 21.116018 -226.064573) (xy 21.060284 -226.062536)
			(xy 21.005441 -226.052406) (xy 20.952657 -226.034399) (xy 20.903057 -226.008898) (xy 20.857699 -225.976447)
			(xy 20.81755 -225.937738) (xy 20.783464 -225.893595) (xy 20.756168 -225.84496) (xy 20.736245 -225.792869)
			(xy 20.724119 -225.738432) (xy 20.720048 -225.68281) (xy 19.158408 -225.68281) (xy 19.159923 -225.686041)
			(xy 19.175991 -225.739448) (xy 19.184111 -225.794624) (xy 19.18462 -225.82251) (xy 19.184111 -225.850396)
			(xy 19.175991 -225.905572) (xy 19.159923 -225.958979) (xy 19.136251 -226.009476) (xy 19.105478 -226.055989)
			(xy 19.068261 -226.097526) (xy 19.025393 -226.133201) (xy 18.977787 -226.162255) (xy 18.926458 -226.184067)
			(xy 18.872501 -226.198173) (xy 18.817064 -226.204273) (xy 18.76133 -226.202236) (xy 18.706487 -226.192106)
			(xy 18.653703 -226.174099) (xy 18.604103 -226.148598) (xy 18.558745 -226.116147) (xy 18.518596 -226.077438)
			(xy 18.48451 -226.033295) (xy 18.457214 -225.98466) (xy 18.437291 -225.932569) (xy 18.425165 -225.878132)
			(xy 18.421094 -225.82251) (xy 17.884648 -225.82251) (xy 17.884648 -226.324922) (xy 25.607262 -226.324922)
			(xy 25.611333 -226.2693) (xy 25.623459 -226.214863) (xy 25.643382 -226.162772) (xy 25.670678 -226.114137)
			(xy 25.704764 -226.069994) (xy 25.744913 -226.031285) (xy 25.790271 -225.998834) (xy 25.839871 -225.973333)
			(xy 25.892655 -225.955326) (xy 25.947498 -225.945196) (xy 26.003232 -225.943159) (xy 26.058669 -225.949259)
			(xy 26.112626 -225.963365) (xy 26.163955 -225.985177) (xy 26.211561 -226.014231) (xy 26.254429 -226.049906)
			(xy 26.291646 -226.091443) (xy 26.322419 -226.137956) (xy 26.346091 -226.188453) (xy 26.362159 -226.24186)
			(xy 26.370279 -226.297036) (xy 26.370788 -226.324922) (xy 26.370279 -226.352808) (xy 26.362159 -226.407984)
			(xy 26.346091 -226.461391) (xy 26.322419 -226.511888) (xy 26.291646 -226.558401) (xy 26.283045 -226.568)
			(xy 30.95828 -226.568) (xy 30.962351 -226.512378) (xy 30.974477 -226.457941) (xy 30.9944 -226.40585)
			(xy 31.021696 -226.357215) (xy 31.055782 -226.313072) (xy 31.095931 -226.274363) (xy 31.141289 -226.241912)
			(xy 31.190889 -226.216411) (xy 31.243673 -226.198404) (xy 31.298516 -226.188274) (xy 31.35425 -226.186237)
			(xy 31.409687 -226.192337) (xy 31.463644 -226.206443) (xy 31.514973 -226.228255) (xy 31.562579 -226.257309)
			(xy 31.581561 -226.273106) (xy 70.331582 -226.273106) (xy 70.335653 -226.217484) (xy 70.347779 -226.163047)
			(xy 70.367702 -226.110956) (xy 70.394998 -226.062321) (xy 70.429084 -226.018178) (xy 70.469233 -225.979469)
			(xy 70.514591 -225.947018) (xy 70.564191 -225.921517) (xy 70.616975 -225.90351) (xy 70.671818 -225.89338)
			(xy 70.727552 -225.891343) (xy 70.782989 -225.897443) (xy 70.836946 -225.911549) (xy 70.888275 -225.933361)
			(xy 70.935881 -225.962415) (xy 70.978749 -225.99809) (xy 71.015966 -226.039627) (xy 71.046739 -226.08614)
			(xy 71.070411 -226.136637) (xy 71.086479 -226.190044) (xy 71.094599 -226.24522) (xy 71.095108 -226.273106)
			(xy 71.094599 -226.300992) (xy 71.086479 -226.356168) (xy 71.070411 -226.409575) (xy 71.046739 -226.460072)
			(xy 71.015966 -226.506585) (xy 70.978749 -226.548122) (xy 70.935881 -226.583797) (xy 70.888275 -226.612851)
			(xy 70.836946 -226.634663) (xy 70.782989 -226.648769) (xy 70.727552 -226.654869) (xy 70.671818 -226.652832)
			(xy 70.616975 -226.642702) (xy 70.564191 -226.624695) (xy 70.514591 -226.599194) (xy 70.469233 -226.566743)
			(xy 70.429084 -226.528034) (xy 70.394998 -226.483891) (xy 70.367702 -226.435256) (xy 70.347779 -226.383165)
			(xy 70.335653 -226.328728) (xy 70.331582 -226.273106) (xy 31.581561 -226.273106) (xy 31.605447 -226.292984)
			(xy 31.642664 -226.334521) (xy 31.673437 -226.381034) (xy 31.697109 -226.431531) (xy 31.713177 -226.484938)
			(xy 31.721297 -226.540114) (xy 31.721806 -226.568) (xy 31.721297 -226.595886) (xy 31.713177 -226.651062)
			(xy 31.697109 -226.704469) (xy 31.673437 -226.754966) (xy 31.642664 -226.801479) (xy 31.605447 -226.843016)
			(xy 31.562579 -226.878691) (xy 31.514973 -226.907745) (xy 31.463644 -226.929557) (xy 31.409687 -226.943663)
			(xy 31.35425 -226.949763) (xy 31.298516 -226.947726) (xy 31.243673 -226.937596) (xy 31.190889 -226.919589)
			(xy 31.141289 -226.894088) (xy 31.095931 -226.861637) (xy 31.055782 -226.822928) (xy 31.021696 -226.778785)
			(xy 30.9944 -226.73015) (xy 30.974477 -226.678059) (xy 30.962351 -226.623622) (xy 30.95828 -226.568)
			(xy 26.283045 -226.568) (xy 26.254429 -226.599938) (xy 26.211561 -226.635613) (xy 26.163955 -226.664667)
			(xy 26.112626 -226.686479) (xy 26.058669 -226.700585) (xy 26.003232 -226.706685) (xy 25.947498 -226.704648)
			(xy 25.892655 -226.694518) (xy 25.839871 -226.676511) (xy 25.790271 -226.65101) (xy 25.744913 -226.618559)
			(xy 25.704764 -226.57985) (xy 25.670678 -226.535707) (xy 25.643382 -226.487072) (xy 25.623459 -226.434981)
			(xy 25.611333 -226.380544) (xy 25.607262 -226.324922) (xy 17.884648 -226.324922) (xy 17.884648 -227.809806)
			(xy 17.88513 -227.819435) (xy 17.89233 -227.837303) (xy 17.905578 -227.851291) (xy 17.914112 -227.85578)
			(xy 18.010886 -227.900992) (xy 18.04035 -227.897182) (xy 18.05178 -227.88753) (xy 18.072484 -227.870776)
			(xy 18.11766 -227.842568) (xy 18.16632 -227.820917) (xy 18.217519 -227.806244) (xy 18.27026 -227.798835)
			(xy 18.29689 -227.798376) (xy 18.324144 -227.798838) (xy 18.378099 -227.806594) (xy 18.4304 -227.82195)
			(xy 18.479984 -227.844593) (xy 18.52584 -227.874062) (xy 18.567036 -227.909757) (xy 18.602732 -227.950952)
			(xy 18.632202 -227.996808) (xy 18.654846 -228.04639) (xy 18.661526 -228.06914) (xy 18.973544 -228.06914)
			(xy 18.977615 -228.013518) (xy 18.989741 -227.959081) (xy 19.009664 -227.90699) (xy 19.03696 -227.858355)
			(xy 19.071046 -227.814212) (xy 19.111195 -227.775503) (xy 19.156553 -227.743052) (xy 19.206153 -227.717551)
			(xy 19.258937 -227.699544) (xy 19.31378 -227.689414) (xy 19.369514 -227.687377) (xy 19.424951 -227.693477)
			(xy 19.478908 -227.707583) (xy 19.530237 -227.729395) (xy 19.577843 -227.758449) (xy 19.620711 -227.794124)
			(xy 19.657928 -227.835661) (xy 19.688701 -227.882174) (xy 19.712373 -227.932671) (xy 19.728441 -227.986078)
			(xy 19.736561 -228.041254) (xy 19.73707 -228.06914) (xy 19.736917 -228.077522) (xy 20.024088 -228.077522)
			(xy 20.028159 -228.0219) (xy 20.040285 -227.967463) (xy 20.060208 -227.915372) (xy 20.087504 -227.866737)
			(xy 20.12159 -227.822594) (xy 20.161739 -227.783885) (xy 20.207097 -227.751434) (xy 20.256697 -227.725933)
			(xy 20.309481 -227.707926) (xy 20.364324 -227.697796) (xy 20.420058 -227.695759) (xy 20.475495 -227.701859)
			(xy 20.529452 -227.715965) (xy 20.580781 -227.737777) (xy 20.628387 -227.766831) (xy 20.671255 -227.802506)
			(xy 20.708472 -227.844043) (xy 20.739245 -227.890556) (xy 20.762917 -227.941053) (xy 20.778985 -227.99446)
			(xy 20.787105 -228.049636) (xy 20.787614 -228.077522) (xy 20.787105 -228.105408) (xy 20.778985 -228.160584)
			(xy 20.762917 -228.213991) (xy 20.739245 -228.264488) (xy 20.708472 -228.311001) (xy 20.671255 -228.352538)
			(xy 20.628387 -228.388213) (xy 20.580781 -228.417267) (xy 20.529452 -228.439079) (xy 20.475495 -228.453185)
			(xy 20.420058 -228.459285) (xy 20.364324 -228.457248) (xy 20.309481 -228.447118) (xy 20.256697 -228.429111)
			(xy 20.207097 -228.40361) (xy 20.161739 -228.371159) (xy 20.12159 -228.33245) (xy 20.087504 -228.288307)
			(xy 20.060208 -228.239672) (xy 20.040285 -228.187581) (xy 20.028159 -228.133144) (xy 20.024088 -228.077522)
			(xy 19.736917 -228.077522) (xy 19.736561 -228.097026) (xy 19.728441 -228.152202) (xy 19.712373 -228.205609)
			(xy 19.688701 -228.256106) (xy 19.657928 -228.302619) (xy 19.620711 -228.344156) (xy 19.577843 -228.379831)
			(xy 19.530237 -228.408885) (xy 19.478908 -228.430697) (xy 19.424951 -228.444803) (xy 19.369514 -228.450903)
			(xy 19.31378 -228.448866) (xy 19.258937 -228.438736) (xy 19.206153 -228.420729) (xy 19.156553 -228.395228)
			(xy 19.111195 -228.362777) (xy 19.071046 -228.324068) (xy 19.03696 -228.279925) (xy 19.009664 -228.23129)
			(xy 18.989741 -228.179199) (xy 18.977615 -228.124762) (xy 18.973544 -228.06914) (xy 18.661526 -228.06914)
			(xy 18.670204 -228.098691) (xy 18.677961 -228.152646) (xy 18.677961 -228.207154) (xy 18.670204 -228.261109)
			(xy 18.654846 -228.31341) (xy 18.632202 -228.362992) (xy 18.602732 -228.408848) (xy 18.567036 -228.450043)
			(xy 18.52584 -228.485738) (xy 18.479984 -228.515207) (xy 18.4304 -228.53785) (xy 18.378099 -228.553206)
			(xy 18.324144 -228.560962) (xy 18.29689 -228.561392) (xy 18.270261 -228.560928) (xy 18.21752 -228.553518)
			(xy 18.166323 -228.538845) (xy 18.117665 -228.517193) (xy 18.072491 -228.488983) (xy 18.05178 -228.472238)
			(xy 18.04035 -228.462586) (xy 18.010886 -228.458776) (xy 17.914112 -228.503988) (xy 17.905523 -228.508401)
			(xy 17.892234 -228.52239) (xy 17.88509 -228.540314) (xy 17.884648 -228.549962) (xy 17.884648 -228.67493)
			(xy 25.95575 -228.67493) (xy 25.959821 -228.619308) (xy 25.971947 -228.564871) (xy 25.99187 -228.51278)
			(xy 26.019166 -228.464145) (xy 26.053252 -228.420002) (xy 26.093401 -228.381293) (xy 26.138759 -228.348842)
			(xy 26.188359 -228.323341) (xy 26.241143 -228.305334) (xy 26.295986 -228.295204) (xy 26.35172 -228.293167)
			(xy 26.407157 -228.299267) (xy 26.461114 -228.313373) (xy 26.512443 -228.335185) (xy 26.560049 -228.364239)
			(xy 26.602917 -228.399914) (xy 26.640134 -228.441451) (xy 26.644202 -228.4476) (xy 69.569582 -228.4476)
			(xy 69.573653 -228.391978) (xy 69.585779 -228.337541) (xy 69.605702 -228.28545) (xy 69.632998 -228.236815)
			(xy 69.667084 -228.192672) (xy 69.707233 -228.153963) (xy 69.752591 -228.121512) (xy 69.802191 -228.096011)
			(xy 69.854975 -228.078004) (xy 69.909818 -228.067874) (xy 69.965552 -228.065837) (xy 70.020989 -228.071937)
			(xy 70.074946 -228.086043) (xy 70.126275 -228.107855) (xy 70.173881 -228.136909) (xy 70.216749 -228.172584)
			(xy 70.253966 -228.214121) (xy 70.284739 -228.260634) (xy 70.308411 -228.311131) (xy 70.324479 -228.364538)
			(xy 70.332599 -228.419714) (xy 70.333108 -228.4476) (xy 70.332599 -228.475486) (xy 70.324479 -228.530662)
			(xy 70.308411 -228.584069) (xy 70.284739 -228.634566) (xy 70.253966 -228.681079) (xy 70.216749 -228.722616)
			(xy 70.173881 -228.758291) (xy 70.126275 -228.787345) (xy 70.074946 -228.809157) (xy 70.020989 -228.823263)
			(xy 69.965552 -228.829363) (xy 69.909818 -228.827326) (xy 69.854975 -228.817196) (xy 69.802191 -228.799189)
			(xy 69.752591 -228.773688) (xy 69.707233 -228.741237) (xy 69.667084 -228.702528) (xy 69.632998 -228.658385)
			(xy 69.605702 -228.60975) (xy 69.585779 -228.557659) (xy 69.573653 -228.503222) (xy 69.569582 -228.4476)
			(xy 26.644202 -228.4476) (xy 26.670907 -228.487964) (xy 26.694579 -228.538461) (xy 26.710647 -228.591868)
			(xy 26.718767 -228.647044) (xy 26.719276 -228.67493) (xy 26.718767 -228.702816) (xy 26.710647 -228.757992)
			(xy 26.694579 -228.811399) (xy 26.670907 -228.861896) (xy 26.640134 -228.908409) (xy 26.602917 -228.949946)
			(xy 26.560049 -228.985621) (xy 26.512443 -229.014675) (xy 26.461114 -229.036487) (xy 26.407157 -229.050593)
			(xy 26.35172 -229.056693) (xy 26.295986 -229.054656) (xy 26.241143 -229.044526) (xy 26.188359 -229.026519)
			(xy 26.138759 -229.001018) (xy 26.093401 -228.968567) (xy 26.053252 -228.929858) (xy 26.019166 -228.885715)
			(xy 25.99187 -228.83708) (xy 25.971947 -228.784989) (xy 25.959821 -228.730552) (xy 25.95575 -228.67493)
			(xy 17.884648 -228.67493) (xy 17.884648 -229.94493) (xy 22.83028 -229.94493) (xy 22.834351 -229.889308)
			(xy 22.846477 -229.834871) (xy 22.8664 -229.78278) (xy 22.893696 -229.734145) (xy 22.927782 -229.690002)
			(xy 22.967931 -229.651293) (xy 23.013289 -229.618842) (xy 23.062889 -229.593341) (xy 23.115673 -229.575334)
			(xy 23.170516 -229.565204) (xy 23.22625 -229.563167) (xy 23.281687 -229.569267) (xy 23.335644 -229.583373)
			(xy 23.386973 -229.605185) (xy 23.434579 -229.634239) (xy 23.477447 -229.669914) (xy 23.514664 -229.711451)
			(xy 23.545437 -229.757964) (xy 23.569109 -229.808461) (xy 23.585177 -229.861868) (xy 23.593297 -229.917044)
			(xy 23.593806 -229.94493) (xy 23.593297 -229.972816) (xy 23.585177 -230.027992) (xy 23.569109 -230.081399)
			(xy 23.545437 -230.131896) (xy 23.514664 -230.178409) (xy 23.477447 -230.219946) (xy 23.434579 -230.255621)
			(xy 23.386973 -230.284675) (xy 23.335644 -230.306487) (xy 23.281687 -230.320593) (xy 23.22625 -230.326693)
			(xy 23.170516 -230.324656) (xy 23.115673 -230.314526) (xy 23.062889 -230.296519) (xy 23.013289 -230.271018)
			(xy 22.967931 -230.238567) (xy 22.927782 -230.199858) (xy 22.893696 -230.155715) (xy 22.8664 -230.10708)
			(xy 22.846477 -230.054989) (xy 22.834351 -230.000552) (xy 22.83028 -229.94493) (xy 17.884648 -229.94493)
			(xy 17.884648 -230.043228) (xy 17.885192 -230.053212) (xy 17.892918 -230.071632) (xy 17.899634 -230.079042)
			(xy 19.276314 -231.455722) (xy 19.299682 -231.48163) (xy 19.300952 -231.483154) (xy 19.317995 -231.503459)
			(xy 19.346067 -231.548425) (xy 19.366624 -231.597285) (xy 19.379144 -231.648795) (xy 19.381724 -231.675178)
			(xy 19.381978 -231.67721) (xy 19.383067 -231.68708) (xy 19.384208 -231.706905) (xy 19.384264 -231.716834)
			(xy 19.384264 -231.94264) (xy 19.384808 -231.952625) (xy 19.392527 -231.97105) (xy 19.39925 -231.978454)
			(xy 19.46021 -232.039414) (xy 19.467064 -232.046809) (xy 19.474808 -232.065408) (xy 19.475196 -232.075482)
			(xy 19.475196 -235.290106) (xy 70.550276 -235.290106) (xy 70.554347 -235.234484) (xy 70.566473 -235.180047)
			(xy 70.586396 -235.127956) (xy 70.613692 -235.079321) (xy 70.647778 -235.035178) (xy 70.687927 -234.996469)
			(xy 70.733285 -234.964018) (xy 70.782885 -234.938517) (xy 70.835669 -234.92051) (xy 70.890512 -234.91038)
			(xy 70.946246 -234.908343) (xy 71.001683 -234.914443) (xy 71.05564 -234.928549) (xy 71.106969 -234.950361)
			(xy 71.154575 -234.979415) (xy 71.160738 -234.984544) (xy 93.107 -234.984544) (xy 93.111071 -234.928922)
			(xy 93.123197 -234.874485) (xy 93.14312 -234.822394) (xy 93.170416 -234.773759) (xy 93.204502 -234.729616)
			(xy 93.244651 -234.690907) (xy 93.290009 -234.658456) (xy 93.339609 -234.632955) (xy 93.392393 -234.614948)
			(xy 93.447236 -234.604818) (xy 93.50297 -234.602781) (xy 93.558407 -234.608881) (xy 93.612364 -234.622987)
			(xy 93.663693 -234.644799) (xy 93.711299 -234.673853) (xy 93.754167 -234.709528) (xy 93.791384 -234.751065)
			(xy 93.822157 -234.797578) (xy 93.845829 -234.848075) (xy 93.861897 -234.901482) (xy 93.870017 -234.956658)
			(xy 93.870526 -234.984544) (xy 93.870017 -235.01243) (xy 93.861897 -235.067606) (xy 93.845829 -235.121013)
			(xy 93.822157 -235.17151) (xy 93.791384 -235.218023) (xy 93.754167 -235.25956) (xy 93.711299 -235.295235)
			(xy 93.663693 -235.324289) (xy 93.612364 -235.346101) (xy 93.558407 -235.360207) (xy 93.50297 -235.366307)
			(xy 93.447236 -235.36427) (xy 93.392393 -235.35414) (xy 93.339609 -235.336133) (xy 93.290009 -235.310632)
			(xy 93.244651 -235.278181) (xy 93.204502 -235.239472) (xy 93.170416 -235.195329) (xy 93.14312 -235.146694)
			(xy 93.123197 -235.094603) (xy 93.111071 -235.040166) (xy 93.107 -234.984544) (xy 71.160738 -234.984544)
			(xy 71.197443 -235.01509) (xy 71.23466 -235.056627) (xy 71.265433 -235.10314) (xy 71.289105 -235.153637)
			(xy 71.305173 -235.207044) (xy 71.313293 -235.26222) (xy 71.313802 -235.290106) (xy 71.313293 -235.317992)
			(xy 71.305173 -235.373168) (xy 71.289105 -235.426575) (xy 71.265433 -235.477072) (xy 71.23466 -235.523585)
			(xy 71.197443 -235.565122) (xy 71.154575 -235.600797) (xy 71.106969 -235.629851) (xy 71.05564 -235.651663)
			(xy 71.001683 -235.665769) (xy 70.946246 -235.671869) (xy 70.890512 -235.669832) (xy 70.835669 -235.659702)
			(xy 70.782885 -235.641695) (xy 70.733285 -235.616194) (xy 70.687927 -235.583743) (xy 70.647778 -235.545034)
			(xy 70.613692 -235.500891) (xy 70.586396 -235.452256) (xy 70.566473 -235.400165) (xy 70.554347 -235.345728)
			(xy 70.550276 -235.290106) (xy 19.475196 -235.290106) (xy 19.475196 -236.561884) (xy 93.248986 -236.561884)
			(xy 93.253057 -236.506262) (xy 93.265183 -236.451825) (xy 93.285106 -236.399734) (xy 93.312402 -236.351099)
			(xy 93.346488 -236.306956) (xy 93.386637 -236.268247) (xy 93.431995 -236.235796) (xy 93.481595 -236.210295)
			(xy 93.534379 -236.192288) (xy 93.589222 -236.182158) (xy 93.644956 -236.180121) (xy 93.700393 -236.186221)
			(xy 93.75435 -236.200327) (xy 93.805679 -236.222139) (xy 93.853285 -236.251193) (xy 93.896153 -236.286868)
			(xy 93.93337 -236.328405) (xy 93.964143 -236.374918) (xy 93.987815 -236.425415) (xy 94.003883 -236.478822)
			(xy 94.012003 -236.533998) (xy 94.012512 -236.561884) (xy 94.012003 -236.58977) (xy 94.003883 -236.644946)
			(xy 93.987815 -236.698353) (xy 93.964143 -236.74885) (xy 93.93337 -236.795363) (xy 93.896153 -236.8369)
			(xy 93.853285 -236.872575) (xy 93.805679 -236.901629) (xy 93.75435 -236.923441) (xy 93.700393 -236.937547)
			(xy 93.644956 -236.943647) (xy 93.589222 -236.94161) (xy 93.534379 -236.93148) (xy 93.481595 -236.913473)
			(xy 93.431995 -236.887972) (xy 93.386637 -236.855521) (xy 93.346488 -236.816812) (xy 93.312402 -236.772669)
			(xy 93.285106 -236.724034) (xy 93.265183 -236.671943) (xy 93.253057 -236.617506) (xy 93.248986 -236.561884)
			(xy 19.475196 -236.561884) (xy 19.475196 -237.3757) (xy 92.775276 -237.3757) (xy 92.779347 -237.320078)
			(xy 92.791473 -237.265641) (xy 92.811396 -237.21355) (xy 92.838692 -237.164915) (xy 92.872778 -237.120772)
			(xy 92.912927 -237.082063) (xy 92.958285 -237.049612) (xy 93.007885 -237.024111) (xy 93.060669 -237.006104)
			(xy 93.115512 -236.995974) (xy 93.171246 -236.993937) (xy 93.226683 -237.000037) (xy 93.28064 -237.014143)
			(xy 93.331969 -237.035955) (xy 93.379575 -237.065009) (xy 93.422443 -237.100684) (xy 93.45966 -237.142221)
			(xy 93.490433 -237.188734) (xy 93.514105 -237.239231) (xy 93.530173 -237.292638) (xy 93.538293 -237.347814)
			(xy 93.538802 -237.3757) (xy 93.538293 -237.403586) (xy 93.530173 -237.458762) (xy 93.514105 -237.512169)
			(xy 93.508304 -237.524544) (xy 94.323914 -237.524544) (xy 94.327985 -237.468922) (xy 94.340111 -237.414485)
			(xy 94.360034 -237.362394) (xy 94.38733 -237.313759) (xy 94.421416 -237.269616) (xy 94.461565 -237.230907)
			(xy 94.506923 -237.198456) (xy 94.556523 -237.172955) (xy 94.609307 -237.154948) (xy 94.66415 -237.144818)
			(xy 94.719884 -237.142781) (xy 94.775321 -237.148881) (xy 94.829278 -237.162987) (xy 94.880607 -237.184799)
			(xy 94.928213 -237.213853) (xy 94.971081 -237.249528) (xy 95.008298 -237.291065) (xy 95.039071 -237.337578)
			(xy 95.062743 -237.388075) (xy 95.078811 -237.441482) (xy 95.086931 -237.496658) (xy 95.08744 -237.524544)
			(xy 95.086931 -237.55243) (xy 95.078811 -237.607606) (xy 95.062743 -237.661013) (xy 95.039071 -237.71151)
			(xy 95.008298 -237.758023) (xy 94.971081 -237.79956) (xy 94.928213 -237.835235) (xy 94.880607 -237.864289)
			(xy 94.829278 -237.886101) (xy 94.775321 -237.900207) (xy 94.719884 -237.906307) (xy 94.66415 -237.90427)
			(xy 94.609307 -237.89414) (xy 94.556523 -237.876133) (xy 94.506923 -237.850632) (xy 94.461565 -237.818181)
			(xy 94.421416 -237.779472) (xy 94.38733 -237.735329) (xy 94.360034 -237.686694) (xy 94.340111 -237.634603)
			(xy 94.327985 -237.580166) (xy 94.323914 -237.524544) (xy 93.508304 -237.524544) (xy 93.490433 -237.562666)
			(xy 93.45966 -237.609179) (xy 93.422443 -237.650716) (xy 93.379575 -237.686391) (xy 93.331969 -237.715445)
			(xy 93.28064 -237.737257) (xy 93.226683 -237.751363) (xy 93.171246 -237.757463) (xy 93.115512 -237.755426)
			(xy 93.060669 -237.745296) (xy 93.007885 -237.727289) (xy 92.958285 -237.701788) (xy 92.912927 -237.669337)
			(xy 92.872778 -237.630628) (xy 92.838692 -237.586485) (xy 92.811396 -237.53785) (xy 92.791473 -237.485759)
			(xy 92.779347 -237.431322) (xy 92.775276 -237.3757) (xy 19.475196 -237.3757) (xy 19.475196 -237.519718)
			(xy 19.475623 -237.529787) (xy 19.483341 -237.548387) (xy 19.490182 -237.555786) (xy 19.789902 -237.855506)
			(xy 70.417688 -237.855506) (xy 70.421759 -237.799884) (xy 70.433885 -237.745447) (xy 70.453808 -237.693356)
			(xy 70.481104 -237.644721) (xy 70.51519 -237.600578) (xy 70.555339 -237.561869) (xy 70.600697 -237.529418)
			(xy 70.650297 -237.503917) (xy 70.703081 -237.48591) (xy 70.757924 -237.47578) (xy 70.813658 -237.473743)
			(xy 70.869095 -237.479843) (xy 70.923052 -237.493949) (xy 70.974381 -237.515761) (xy 71.021987 -237.544815)
			(xy 71.064855 -237.58049) (xy 71.102072 -237.622027) (xy 71.132845 -237.66854) (xy 71.156517 -237.719037)
			(xy 71.172585 -237.772444) (xy 71.180705 -237.82762) (xy 71.181214 -237.855506) (xy 71.180705 -237.883392)
			(xy 71.172585 -237.938568) (xy 71.156517 -237.991975) (xy 71.132845 -238.042472) (xy 71.102072 -238.088985)
			(xy 71.064855 -238.130522) (xy 71.021987 -238.166197) (xy 70.990437 -238.185452) (xy 93.334838 -238.185452)
			(xy 93.338909 -238.12983) (xy 93.351035 -238.075393) (xy 93.370958 -238.023302) (xy 93.398254 -237.974667)
			(xy 93.43234 -237.930524) (xy 93.472489 -237.891815) (xy 93.517847 -237.859364) (xy 93.567447 -237.833863)
			(xy 93.620231 -237.815856) (xy 93.675074 -237.805726) (xy 93.730808 -237.803689) (xy 93.786245 -237.809789)
			(xy 93.840202 -237.823895) (xy 93.891531 -237.845707) (xy 93.939137 -237.874761) (xy 93.982005 -237.910436)
			(xy 94.019222 -237.951973) (xy 94.049995 -237.998486) (xy 94.073667 -238.048983) (xy 94.089735 -238.10239)
			(xy 94.097855 -238.157566) (xy 94.098364 -238.185452) (xy 94.097855 -238.213338) (xy 94.089735 -238.268514)
			(xy 94.073667 -238.321921) (xy 94.049995 -238.372418) (xy 94.019222 -238.418931) (xy 93.982005 -238.460468)
			(xy 93.939137 -238.496143) (xy 93.891531 -238.525197) (xy 93.840202 -238.547009) (xy 93.786245 -238.561115)
			(xy 93.730808 -238.567215) (xy 93.675074 -238.565178) (xy 93.620231 -238.555048) (xy 93.567447 -238.537041)
			(xy 93.517847 -238.51154) (xy 93.472489 -238.479089) (xy 93.43234 -238.44038) (xy 93.398254 -238.396237)
			(xy 93.370958 -238.347602) (xy 93.351035 -238.295511) (xy 93.338909 -238.241074) (xy 93.334838 -238.185452)
			(xy 70.990437 -238.185452) (xy 70.974381 -238.195251) (xy 70.923052 -238.217063) (xy 70.869095 -238.231169)
			(xy 70.813658 -238.237269) (xy 70.757924 -238.235232) (xy 70.703081 -238.225102) (xy 70.650297 -238.207095)
			(xy 70.600697 -238.181594) (xy 70.555339 -238.149143) (xy 70.51519 -238.110434) (xy 70.481104 -238.066291)
			(xy 70.453808 -238.017656) (xy 70.433885 -237.965565) (xy 70.421759 -237.911128) (xy 70.417688 -237.855506)
			(xy 19.789902 -237.855506) (xy 21.029676 -239.09528) (xy 21.037078 -239.102117) (xy 21.055676 -239.109826)
			(xy 21.065744 -239.110266)
		)
		(stroke
			(width 0)
			(type solid)
		)
		(fill yes)
		(layer "In15.Cu")
		(net "GND")
	)
	(gr_poly
		(pts
			(xy 111.035846 -184.152032) (xy 111.045839 -184.151505) (xy 111.064288 -184.143809) (xy 111.07166 -184.137046)
			(xy 111.12373 -184.08523) (xy 111.147509 -184.06212) (xy 111.199362 -184.020787) (xy 111.255516 -183.985518)
			(xy 111.315265 -183.956758) (xy 111.377859 -183.934867) (xy 111.442509 -183.92012) (xy 111.508404 -183.912704)
			(xy 111.54156 -183.912256) (xy 119.962422 -183.912256) (xy 119.972489 -183.911828) (xy 119.991084 -183.904103)
			(xy 119.99849 -183.89727) (xy 120.720358 -183.175148) (xy 120.727165 -183.167802) (xy 120.734885 -183.149339)
			(xy 120.735344 -183.139334) (xy 120.735344 -163.218368) (xy 120.734913 -163.208302) (xy 120.727185 -163.189711)
			(xy 120.720358 -163.1823) (xy 119.586248 -162.04819) (xy 119.579398 -162.040793) (xy 119.571659 -162.022195)
			(xy 119.571262 -162.012122) (xy 119.571262 -154.827224) (xy 119.571357 -154.822205) (xy 119.57328 -154.812355)
			(xy 119.575072 -154.807666) (xy 119.582438 -154.790394) (xy 119.584235 -154.785707) (xy 119.58615 -154.775855)
			(xy 119.586248 -154.770836) (xy 119.586248 -133.763004) (xy 119.585824 -133.752935) (xy 119.578105 -133.734334)
			(xy 119.571262 -133.726936) (xy 119.259096 -133.41477) (xy 119.251984 -133.407404) (xy 119.233188 -133.399784)
			(xy 101.148134 -133.399784) (xy 101.138069 -133.400219) (xy 101.11948 -133.407948) (xy 101.112066 -133.41477)
			(xy 100.70592 -133.820916) (xy 100.699074 -133.828314) (xy 100.691342 -133.846913) (xy 100.690934 -133.856984)
			(xy 100.690934 -139.03706) (xy 106.080052 -139.03706) (xy 106.080564 -139.008321) (xy 106.089192 -138.951494)
			(xy 106.106245 -138.896603) (xy 106.131339 -138.844892) (xy 106.163905 -138.797529) (xy 106.183176 -138.776202)
			(xy 106.18978 -138.76909) (xy 106.196892 -138.751564) (xy 106.196892 -138.662156) (xy 106.18978 -138.64463)
			(xy 106.183176 -138.637518) (xy 106.163893 -138.616202) (xy 106.131327 -138.568838) (xy 106.106236 -138.517123)
			(xy 106.089188 -138.46223) (xy 106.08057 -138.4054) (xy 106.080052 -138.37666) (xy 106.080538 -138.349409)
			(xy 106.088294 -138.295461) (xy 106.103649 -138.243166) (xy 106.126291 -138.193589) (xy 106.155757 -138.147739)
			(xy 106.191448 -138.106548) (xy 106.232639 -138.070857) (xy 106.278489 -138.041391) (xy 106.328066 -138.018749)
			(xy 106.380361 -138.003394) (xy 106.434309 -137.995638) (xy 106.488811 -137.995638) (xy 106.542759 -138.003394)
			(xy 106.595054 -138.018749) (xy 106.644631 -138.041391) (xy 106.690481 -138.070857) (xy 106.731672 -138.106548)
			(xy 106.767363 -138.147739) (xy 106.796829 -138.193589) (xy 106.819471 -138.243166) (xy 106.834826 -138.295461)
			(xy 106.842582 -138.349409) (xy 106.843068 -138.37666) (xy 106.842563 -138.405399) (xy 106.833933 -138.462227)
			(xy 106.816877 -138.517117) (xy 106.791782 -138.568828) (xy 106.759215 -138.616191) (xy 106.739944 -138.637518)
			(xy 106.73334 -138.64463) (xy 106.726228 -138.662156) (xy 106.726228 -138.751564) (xy 106.73334 -138.76909)
			(xy 106.739944 -138.776202) (xy 106.759193 -138.797548) (xy 106.791763 -138.844905) (xy 106.81686 -138.896611)
			(xy 106.833916 -138.951498) (xy 106.842544 -139.008322) (xy 106.843068 -139.03706) (xy 106.842617 -139.062965)
			(xy 106.835599 -139.114299) (xy 106.821702 -139.164211) (xy 106.80118 -139.211785) (xy 106.774411 -139.256145)
			(xy 106.758486 -139.276582) (xy 106.75239 -139.284202) (xy 106.746802 -139.30249) (xy 106.75366 -139.39139)
			(xy 106.762042 -139.408916) (xy 106.769154 -139.41552) (xy 106.788401 -139.433678) (xy 106.822229 -139.474365)
			(xy 106.850113 -139.519334) (xy 106.87152 -139.567723) (xy 106.88604 -139.618605) (xy 106.893394 -139.671004)
			(xy 106.893868 -139.69746) (xy 106.893363 -139.726199) (xy 106.884733 -139.783027) (xy 106.867677 -139.837917)
			(xy 106.842582 -139.889628) (xy 106.810015 -139.936991) (xy 106.790744 -139.958318) (xy 106.78414 -139.96543)
			(xy 106.777028 -139.982956) (xy 106.777028 -140.072364) (xy 106.78414 -140.08989) (xy 106.790744 -140.097002)
			(xy 106.809977 -140.118362) (xy 106.842546 -140.165718) (xy 106.867642 -140.217424) (xy 106.884696 -140.27231)
			(xy 106.893323 -140.329134) (xy 106.893328 -140.386608) (xy 106.884709 -140.443433) (xy 106.867663 -140.498321)
			(xy 106.842575 -140.550031) (xy 106.810013 -140.597392) (xy 106.790744 -140.618718) (xy 106.78414 -140.62583)
			(xy 106.777028 -140.643356) (xy 106.777028 -140.732764) (xy 106.78414 -140.75029) (xy 106.790744 -140.757402)
			(xy 106.809993 -140.778748) (xy 106.842563 -140.826105) (xy 106.86766 -140.877811) (xy 106.884716 -140.932698)
			(xy 106.893344 -140.989522) (xy 106.893868 -141.01826) (xy 108.518452 -141.01826) (xy 108.518964 -140.989521)
			(xy 108.527592 -140.932694) (xy 108.544645 -140.877803) (xy 108.569739 -140.826092) (xy 108.602305 -140.778729)
			(xy 108.621576 -140.757402) (xy 108.62818 -140.75029) (xy 108.635292 -140.732764) (xy 108.635292 -140.643356)
			(xy 108.62818 -140.62583) (xy 108.621576 -140.618718) (xy 108.602268 -140.597425) (xy 108.569708 -140.550055)
			(xy 108.544622 -140.498337) (xy 108.527577 -140.443442) (xy 108.518959 -140.386611) (xy 108.518963 -140.329131)
			(xy 108.52759 -140.272301) (xy 108.544643 -140.217408) (xy 108.569737 -140.165694) (xy 108.602304 -140.11833)
			(xy 108.621576 -140.097002) (xy 108.62818 -140.08989) (xy 108.635292 -140.072364) (xy 108.635292 -139.982956)
			(xy 108.62818 -139.96543) (xy 108.621576 -139.958318) (xy 108.602293 -139.937002) (xy 108.569727 -139.889638)
			(xy 108.544636 -139.837923) (xy 108.527588 -139.78303) (xy 108.51897 -139.7262) (xy 108.518452 -139.69746)
			(xy 108.518993 -139.668544) (xy 108.527715 -139.611373) (xy 108.544967 -139.556173) (xy 108.570354 -139.504211)
			(xy 108.603295 -139.456677) (xy 108.643033 -139.41466) (xy 108.665518 -139.39647) (xy 108.674292 -139.38892)
			(xy 108.684468 -139.368152) (xy 108.685076 -139.356592) (xy 108.685076 -139.276328) (xy 108.684498 -139.264761)
			(xy 108.67431 -139.243989) (xy 108.665518 -139.23645) (xy 108.643062 -139.218226) (xy 108.603324 -139.176214)
			(xy 108.570382 -139.128686) (xy 108.544988 -139.076731) (xy 108.527726 -139.021539) (xy 108.518991 -138.964374)
			(xy 108.518452 -138.93546) (xy 108.518964 -138.906721) (xy 108.527592 -138.849894) (xy 108.544645 -138.795003)
			(xy 108.569739 -138.743292) (xy 108.602305 -138.695929) (xy 108.621576 -138.674602) (xy 108.62818 -138.66749)
			(xy 108.635292 -138.649964) (xy 108.635292 -138.560556) (xy 108.62818 -138.54303) (xy 108.621576 -138.535918)
			(xy 108.602293 -138.514602) (xy 108.569727 -138.467238) (xy 108.544636 -138.415523) (xy 108.527588 -138.36063)
			(xy 108.51897 -138.3038) (xy 108.518452 -138.27506) (xy 108.51894 -138.24781) (xy 108.526701 -138.193864)
			(xy 108.54206 -138.141572) (xy 108.564702 -138.091997) (xy 108.594169 -138.046149) (xy 108.62986 -138.00496)
			(xy 108.671049 -137.969269) (xy 108.716897 -137.939802) (xy 108.766472 -137.91716) (xy 108.818764 -137.901801)
			(xy 108.87271 -137.89404) (xy 108.89996 -137.893552) (xy 108.929295 -137.894104) (xy 108.987274 -137.903069)
			(xy 109.043197 -137.920808) (xy 109.095742 -137.946903) (xy 109.143671 -137.980739) (xy 109.165136 -138.00074)
			(xy 109.172502 -138.007852) (xy 109.190282 -138.014964) (xy 109.281214 -138.014964) (xy 109.298994 -138.007852)
			(xy 109.30636 -138.00074) (xy 109.327833 -137.980749) (xy 109.375767 -137.946923) (xy 109.42831 -137.920828)
			(xy 109.484228 -137.903079) (xy 109.542203 -137.894094) (xy 109.571536 -137.893552) (xy 109.598786 -137.894044)
			(xy 109.652732 -137.901805) (xy 109.705024 -137.917162) (xy 109.754599 -137.939805) (xy 109.800447 -137.969271)
			(xy 109.841636 -138.004962) (xy 109.877327 -138.04615) (xy 109.906793 -138.091998) (xy 109.929436 -138.141572)
			(xy 109.944795 -138.193864) (xy 109.952556 -138.24781) (xy 109.953044 -138.27506) (xy 109.952545 -138.3038)
			(xy 109.943915 -138.360628) (xy 109.926858 -138.415518) (xy 109.901761 -138.467229) (xy 109.869192 -138.514591)
			(xy 109.84992 -138.535918) (xy 109.843316 -138.54303) (xy 109.836204 -138.560556) (xy 109.836204 -138.649964)
			(xy 109.843316 -138.66749) (xy 109.84992 -138.674602) (xy 109.869165 -138.695952) (xy 109.901736 -138.743307)
			(xy 109.926834 -138.795013) (xy 109.943891 -138.849899) (xy 109.95252 -138.906722) (xy 109.953044 -138.93546)
			(xy 112.090708 -138.93546) (xy 112.091205 -138.90672) (xy 112.099834 -138.849891) (xy 112.11689 -138.795)
			(xy 112.141988 -138.743289) (xy 112.174559 -138.695928) (xy 112.193832 -138.674602) (xy 112.200436 -138.66749)
			(xy 112.207548 -138.649964) (xy 112.207548 -138.560556) (xy 112.200436 -138.54303) (xy 112.193832 -138.535918)
			(xy 112.174541 -138.514608) (xy 112.141978 -138.467241) (xy 112.116889 -138.415525) (xy 112.099844 -138.360631)
			(xy 112.091226 -138.3038) (xy 112.090708 -138.27506) (xy 112.091194 -138.247809) (xy 112.09895 -138.193861)
			(xy 112.114305 -138.141566) (xy 112.136947 -138.091989) (xy 112.166413 -138.046139) (xy 112.202104 -138.004948)
			(xy 112.243295 -137.969257) (xy 112.289145 -137.939791) (xy 112.338722 -137.917149) (xy 112.391017 -137.901794)
			(xy 112.444965 -137.894038) (xy 112.499467 -137.894038) (xy 112.553415 -137.901794) (xy 112.60571 -137.917149)
			(xy 112.655287 -137.939791) (xy 112.701137 -137.969257) (xy 112.742328 -138.004948) (xy 112.778019 -138.046139)
			(xy 112.807485 -138.091989) (xy 112.830127 -138.141566) (xy 112.845482 -138.193861) (xy 112.853238 -138.247809)
			(xy 112.853724 -138.27506) (xy 112.85323 -138.3038) (xy 112.844599 -138.360628) (xy 112.827542 -138.415519)
			(xy 112.802444 -138.46723) (xy 112.769873 -138.514592) (xy 112.7506 -138.535918) (xy 112.743996 -138.54303)
			(xy 112.736884 -138.560556) (xy 112.736884 -138.649964) (xy 112.743996 -138.66749) (xy 112.7506 -138.674602)
			(xy 112.769841 -138.695955) (xy 112.802414 -138.743309) (xy 112.827513 -138.795014) (xy 112.84457 -138.849899)
			(xy 112.853199 -138.906723) (xy 112.853724 -138.93546) (xy 112.85327 -138.960927) (xy 112.84647 -139.011406)
			(xy 112.833011 -139.060531) (xy 112.813134 -139.107427) (xy 112.787191 -139.15126) (xy 112.755645 -139.19125)
			(xy 112.737646 -139.209272) (xy 112.729518 -139.2174) (xy 112.721644 -139.237974) (xy 112.728502 -139.33805)
			(xy 112.73917 -139.357608) (xy 112.748568 -139.364212) (xy 112.772282 -139.382359) (xy 112.81434 -139.42474)
			(xy 112.849289 -139.473152) (xy 112.876276 -139.526413) (xy 112.894644 -139.583226) (xy 112.903944 -139.642206)
			(xy 112.904524 -139.67206) (xy 112.90403 -139.7008) (xy 112.895399 -139.757628) (xy 112.878342 -139.812519)
			(xy 112.853244 -139.86423) (xy 112.820673 -139.911592) (xy 112.8014 -139.932918) (xy 112.794796 -139.94003)
			(xy 112.787684 -139.957556) (xy 112.787684 -140.046964) (xy 112.794796 -140.06449) (xy 112.8014 -140.071602)
			(xy 112.82063 -140.092964) (xy 112.853195 -140.140321) (xy 112.878287 -140.192027) (xy 112.895339 -140.246912)
			(xy 112.903964 -140.303734) (xy 112.903969 -140.361207) (xy 112.895352 -140.418031) (xy 112.878308 -140.472919)
			(xy 112.853224 -140.524629) (xy 112.820667 -140.571991) (xy 112.8014 -140.593318) (xy 112.794796 -140.60043)
			(xy 112.787684 -140.617956) (xy 112.787684 -140.707364) (xy 112.794796 -140.72489) (xy 112.8014 -140.732002)
			(xy 112.820641 -140.753355) (xy 112.853214 -140.800709) (xy 112.878313 -140.852414) (xy 112.89537 -140.907299)
			(xy 112.903999 -140.964123) (xy 112.90406 -140.96746) (xy 114.529108 -140.96746) (xy 114.529605 -140.93872)
			(xy 114.538234 -140.881891) (xy 114.55529 -140.827) (xy 114.580388 -140.775289) (xy 114.612959 -140.727928)
			(xy 114.632232 -140.706602) (xy 114.638836 -140.69949) (xy 114.645948 -140.681964) (xy 114.645948 -140.592556)
			(xy 114.638836 -140.57503) (xy 114.632232 -140.567918) (xy 114.612921 -140.546626) (xy 114.580357 -140.499258)
			(xy 114.555267 -140.44754) (xy 114.538219 -140.392644) (xy 114.5296 -140.335812) (xy 114.529605 -140.27833)
			(xy 114.538232 -140.221499) (xy 114.555288 -140.166605) (xy 114.580386 -140.114892) (xy 114.612958 -140.067529)
			(xy 114.632232 -140.046202) (xy 114.638836 -140.03909) (xy 114.645948 -140.021564) (xy 114.645948 -139.932156)
			(xy 114.638836 -139.91463) (xy 114.632232 -139.907518) (xy 114.612941 -139.886208) (xy 114.580378 -139.838841)
			(xy 114.555289 -139.787125) (xy 114.538244 -139.732231) (xy 114.529626 -139.6754) (xy 114.529108 -139.64666)
			(xy 114.529552 -139.620344) (xy 114.536774 -139.568209) (xy 114.551088 -139.517561) (xy 114.572224 -139.469359)
			(xy 114.599781 -139.424517) (xy 114.633237 -139.383886) (xy 114.652298 -139.365736) (xy 114.659685 -139.358203)
			(xy 114.668218 -139.338931) (xy 114.668808 -139.328398) (xy 114.668808 -139.253722) (xy 114.668278 -139.243173)
			(xy 114.659743 -139.223877) (xy 114.652298 -139.216384) (xy 114.63321 -139.198258) (xy 114.599733 -139.157635)
			(xy 114.572164 -139.112793) (xy 114.551027 -139.064584) (xy 114.536724 -139.013925) (xy 114.529528 -138.96178)
			(xy 114.529108 -138.93546) (xy 114.529605 -138.90672) (xy 114.538234 -138.849891) (xy 114.55529 -138.795)
			(xy 114.580388 -138.743289) (xy 114.612959 -138.695928) (xy 114.632232 -138.674602) (xy 114.638836 -138.66749)
			(xy 114.645948 -138.649964) (xy 114.645948 -138.560556) (xy 114.638836 -138.54303) (xy 114.632232 -138.535918)
			(xy 114.612941 -138.514608) (xy 114.580378 -138.467241) (xy 114.555289 -138.415525) (xy 114.538244 -138.360631)
			(xy 114.529626 -138.3038) (xy 114.529108 -138.27506) (xy 114.529541 -138.247807) (xy 114.537303 -138.193857)
			(xy 114.552664 -138.14156) (xy 114.575311 -138.091981) (xy 114.604783 -138.04613) (xy 114.64048 -138.00494)
			(xy 114.681675 -137.969249) (xy 114.727531 -137.939784) (xy 114.777112 -137.917144) (xy 114.829411 -137.901791)
			(xy 114.883363 -137.894037) (xy 114.910616 -137.893552) (xy 114.93829 -137.894058) (xy 114.993059 -137.902052)
			(xy 115.046094 -137.917884) (xy 115.096283 -137.94122) (xy 115.142567 -137.971571) (xy 115.1636 -137.989564)
			(xy 115.170712 -137.995914) (xy 115.189 -138.002518) (xy 115.278154 -137.999724) (xy 115.295934 -137.992104)
			(xy 115.302792 -137.985246) (xy 115.32441 -137.964521) (xy 115.372875 -137.929347) (xy 115.426241 -137.90218)
			(xy 115.483198 -137.883689) (xy 115.542344 -137.874327) (xy 115.572286 -137.87374) (xy 115.599541 -137.874169)
			(xy 115.653495 -137.881925) (xy 115.705797 -137.897281) (xy 115.75538 -137.919926) (xy 115.801236 -137.949397)
			(xy 115.84243 -137.985094) (xy 115.878124 -138.026292) (xy 115.90759 -138.07215) (xy 115.93023 -138.121735)
			(xy 115.945582 -138.174038) (xy 115.953334 -138.227993) (xy 115.953794 -138.255248) (xy 115.953301 -138.283988)
			(xy 115.944671 -138.340817) (xy 115.927614 -138.395708) (xy 115.902516 -138.447419) (xy 115.869944 -138.49478)
			(xy 115.85067 -138.516106) (xy 115.844066 -138.523218) (xy 115.836954 -138.540744) (xy 115.836954 -138.578844)
			(xy 118.705882 -138.578844) (xy 118.709953 -138.523222) (xy 118.722079 -138.468785) (xy 118.742002 -138.416694)
			(xy 118.769298 -138.368059) (xy 118.803384 -138.323916) (xy 118.843533 -138.285207) (xy 118.888891 -138.252756)
			(xy 118.938491 -138.227255) (xy 118.991275 -138.209248) (xy 119.046118 -138.199118) (xy 119.101852 -138.197081)
			(xy 119.157289 -138.203181) (xy 119.211246 -138.217287) (xy 119.262575 -138.239099) (xy 119.310181 -138.268153)
			(xy 119.353049 -138.303828) (xy 119.390266 -138.345365) (xy 119.421039 -138.391878) (xy 119.444711 -138.442375)
			(xy 119.460779 -138.495782) (xy 119.468899 -138.550958) (xy 119.469408 -138.578844) (xy 119.468899 -138.60673)
			(xy 119.460779 -138.661906) (xy 119.444711 -138.715313) (xy 119.421039 -138.76581) (xy 119.390266 -138.812323)
			(xy 119.353049 -138.85386) (xy 119.310181 -138.889535) (xy 119.262575 -138.918589) (xy 119.211246 -138.940401)
			(xy 119.157289 -138.954507) (xy 119.101852 -138.960607) (xy 119.046118 -138.95857) (xy 118.991275 -138.94844)
			(xy 118.938491 -138.930433) (xy 118.888891 -138.904932) (xy 118.843533 -138.872481) (xy 118.803384 -138.833772)
			(xy 118.769298 -138.789629) (xy 118.742002 -138.740994) (xy 118.722079 -138.688903) (xy 118.709953 -138.634466)
			(xy 118.705882 -138.578844) (xy 115.836954 -138.578844) (xy 115.836954 -138.630152) (xy 115.844066 -138.647678)
			(xy 115.85067 -138.65479) (xy 115.869965 -138.676096) (xy 115.902527 -138.723464) (xy 115.927615 -138.775181)
			(xy 115.94466 -138.830076) (xy 115.953277 -138.886908) (xy 115.953794 -138.915648) (xy 115.953355 -138.941964)
			(xy 115.946132 -138.994099) (xy 115.931816 -139.044748) (xy 115.910679 -139.09295) (xy 115.883122 -139.137791)
			(xy 115.849665 -139.178422) (xy 115.830604 -139.196572) (xy 115.823213 -139.204103) (xy 115.814683 -139.223376)
			(xy 115.814094 -139.23391) (xy 115.814094 -139.308586) (xy 115.814619 -139.319136) (xy 115.823157 -139.338431)
			(xy 115.830604 -139.345924) (xy 115.849696 -139.364046) (xy 115.883173 -139.404669) (xy 115.910741 -139.449513)
			(xy 115.931878 -139.497722) (xy 115.94618 -139.548382) (xy 115.953375 -139.600528) (xy 115.953794 -139.626848)
			(xy 115.953301 -139.655588) (xy 115.944671 -139.712417) (xy 115.927614 -139.767308) (xy 115.902516 -139.819019)
			(xy 115.869944 -139.86638) (xy 115.85067 -139.887706) (xy 115.844066 -139.894818) (xy 115.836954 -139.912344)
			(xy 115.836954 -140.001752) (xy 115.844066 -140.019278) (xy 115.85067 -140.02639) (xy 115.869989 -140.047675)
			(xy 115.902553 -140.095045) (xy 115.927642 -140.146763) (xy 115.944689 -140.20166) (xy 115.953307 -140.258494)
			(xy 115.953302 -140.315976) (xy 115.944673 -140.372808) (xy 115.927616 -140.427702) (xy 115.902518 -140.479416)
			(xy 115.869945 -140.526779) (xy 115.85067 -140.548106) (xy 115.844066 -140.555218) (xy 115.836954 -140.572744)
			(xy 115.836954 -140.662152) (xy 115.844066 -140.679678) (xy 115.85067 -140.68679) (xy 115.869965 -140.708096)
			(xy 115.902527 -140.755464) (xy 115.927615 -140.807181) (xy 115.94466 -140.862076) (xy 115.953277 -140.918908)
			(xy 115.953794 -140.947648) (xy 115.953367 -140.974901) (xy 115.945603 -141.028852) (xy 115.930241 -141.081148)
			(xy 115.907594 -141.130727) (xy 115.878121 -141.176577) (xy 115.842424 -141.217767) (xy 115.801228 -141.253458)
			(xy 115.755372 -141.282923) (xy 115.70579 -141.305563) (xy 115.653491 -141.320917) (xy 115.599539 -141.328671)
			(xy 115.572286 -141.329156) (xy 115.544612 -141.328647) (xy 115.489844 -141.320653) (xy 115.436808 -141.304822)
			(xy 115.38662 -141.281486) (xy 115.340335 -141.251136) (xy 115.319302 -141.233144) (xy 115.31219 -141.226794)
			(xy 115.293902 -141.22019) (xy 115.204748 -141.222984) (xy 115.186968 -141.230604) (xy 115.18011 -141.237462)
			(xy 115.158536 -141.258235) (xy 115.11006 -141.293403) (xy 115.056682 -141.32056) (xy 114.999716 -141.33904)
			(xy 114.940561 -141.348388) (xy 114.910616 -141.348968) (xy 114.883362 -141.34853) (xy 114.829408 -141.340774)
			(xy 114.777107 -141.325418) (xy 114.727524 -141.302774) (xy 114.681669 -141.273304) (xy 114.640475 -141.237608)
			(xy 114.604781 -141.196412) (xy 114.575314 -141.150555) (xy 114.552674 -141.10097) (xy 114.537321 -141.048669)
			(xy 114.529569 -140.994714) (xy 114.529108 -140.96746) (xy 112.90406 -140.96746) (xy 112.904524 -140.99286)
			(xy 112.904038 -141.020111) (xy 112.896282 -141.074059) (xy 112.880927 -141.126354) (xy 112.858285 -141.175931)
			(xy 112.828819 -141.221781) (xy 112.793128 -141.262972) (xy 112.751937 -141.298663) (xy 112.706087 -141.328129)
			(xy 112.65651 -141.350771) (xy 112.604215 -141.366126) (xy 112.550267 -141.373882) (xy 112.495765 -141.373882)
			(xy 112.441817 -141.366126) (xy 112.389522 -141.350771) (xy 112.339945 -141.328129) (xy 112.294095 -141.298663)
			(xy 112.252904 -141.262972) (xy 112.217213 -141.221781) (xy 112.187747 -141.175931) (xy 112.165105 -141.126354)
			(xy 112.14975 -141.074059) (xy 112.141994 -141.020111) (xy 112.141508 -140.99286) (xy 112.142005 -140.96412)
			(xy 112.150634 -140.907291) (xy 112.16769 -140.8524) (xy 112.192788 -140.800689) (xy 112.225359 -140.753328)
			(xy 112.244632 -140.732002) (xy 112.251236 -140.72489) (xy 112.258348 -140.707364) (xy 112.258348 -140.617956)
			(xy 112.251236 -140.60043) (xy 112.244632 -140.593318) (xy 112.225321 -140.572026) (xy 112.192757 -140.524658)
			(xy 112.167667 -140.47294) (xy 112.150619 -140.418044) (xy 112.142 -140.361212) (xy 112.142005 -140.30373)
			(xy 112.150632 -140.246899) (xy 112.167688 -140.192005) (xy 112.192786 -140.140292) (xy 112.225358 -140.092929)
			(xy 112.244632 -140.071602) (xy 112.251236 -140.06449) (xy 112.258348 -140.046964) (xy 112.258348 -139.957556)
			(xy 112.251236 -139.94003) (xy 112.244632 -139.932918) (xy 112.225341 -139.911608) (xy 112.192778 -139.864241)
			(xy 112.167689 -139.812525) (xy 112.150644 -139.757631) (xy 112.142026 -139.7008) (xy 112.141508 -139.67206)
			(xy 112.141965 -139.646593) (xy 112.148764 -139.596114) (xy 112.162221 -139.546989) (xy 112.182098 -139.500093)
			(xy 112.20804 -139.456259) (xy 112.239586 -139.41627) (xy 112.257586 -139.398248) (xy 112.265714 -139.39012)
			(xy 112.273588 -139.369546) (xy 112.26673 -139.26947) (xy 112.256062 -139.249912) (xy 112.246664 -139.243308)
			(xy 112.222945 -139.225168) (xy 112.18089 -139.182783) (xy 112.145944 -139.134369) (xy 112.118958 -139.081107)
			(xy 112.100591 -139.024294) (xy 112.091289 -138.965314) (xy 112.090708 -138.93546) (xy 109.953044 -138.93546)
			(xy 109.952518 -138.964377) (xy 109.943794 -139.021549) (xy 109.926539 -139.076748) (xy 109.901149 -139.128711)
			(xy 109.868205 -139.176245) (xy 109.828464 -139.218261) (xy 109.805978 -139.23645) (xy 109.797239 -139.244034)
			(xy 109.787044 -139.264776) (xy 109.78642 -139.276328) (xy 109.78642 -139.356592) (xy 109.786988 -139.36816)
			(xy 109.797184 -139.388932) (xy 109.805978 -139.39647) (xy 109.828443 -139.414684) (xy 109.86818 -139.456698)
			(xy 109.901122 -139.504228) (xy 109.926514 -139.556185) (xy 109.943774 -139.611379) (xy 109.952507 -139.668545)
			(xy 109.953044 -139.69746) (xy 109.952545 -139.7262) (xy 109.943915 -139.783028) (xy 109.926858 -139.837918)
			(xy 109.901761 -139.889629) (xy 109.869192 -139.936991) (xy 109.84992 -139.958318) (xy 109.843316 -139.96543)
			(xy 109.836204 -139.982956) (xy 109.836204 -140.072364) (xy 109.843316 -140.08989) (xy 109.84992 -140.097002)
			(xy 109.869149 -140.118364) (xy 109.901712 -140.165722) (xy 109.926803 -140.217428) (xy 109.943854 -140.272313)
			(xy 109.952479 -140.329135) (xy 109.952483 -140.386607) (xy 109.943867 -140.44343) (xy 109.926824 -140.498318)
			(xy 109.901741 -140.550028) (xy 109.869186 -140.59739) (xy 109.84992 -140.618718) (xy 109.843316 -140.62583)
			(xy 109.836204 -140.643356) (xy 109.836204 -140.732764) (xy 109.843316 -140.75029) (xy 109.84992 -140.757402)
			(xy 109.869165 -140.778752) (xy 109.901736 -140.826107) (xy 109.926834 -140.877813) (xy 109.943891 -140.932699)
			(xy 109.95252 -140.989522) (xy 109.953044 -141.01826) (xy 109.952508 -141.04551) (xy 109.944757 -141.099457)
			(xy 109.929408 -141.151751) (xy 109.906773 -141.201329) (xy 109.877312 -141.24718) (xy 109.841626 -141.288372)
			(xy 109.800441 -141.324067) (xy 109.754595 -141.353536) (xy 109.705022 -141.376181) (xy 109.652731 -141.391541)
			(xy 109.598786 -141.399302) (xy 109.571536 -141.399768) (xy 109.542202 -141.399213) (xy 109.484222 -141.390248)
			(xy 109.4283 -141.372509) (xy 109.375755 -141.346415) (xy 109.327825 -141.312581) (xy 109.30636 -141.29258)
			(xy 109.298994 -141.285468) (xy 109.281214 -141.278356) (xy 109.190282 -141.278356) (xy 109.172502 -141.285468)
			(xy 109.165136 -141.29258) (xy 109.143652 -141.312559) (xy 109.095723 -141.34639) (xy 109.043182 -141.372489)
			(xy 108.987266 -141.39024) (xy 108.929293 -141.399226) (xy 108.89996 -141.399768) (xy 108.872706 -141.399359)
			(xy 108.818753 -141.391596) (xy 108.766455 -141.376234) (xy 108.716875 -141.353585) (xy 108.671023 -141.324111)
			(xy 108.629832 -141.288412) (xy 108.594141 -141.247213) (xy 108.564676 -141.201355) (xy 108.542038 -141.15177)
			(xy 108.526687 -141.099468) (xy 108.518935 -141.045514) (xy 108.518452 -141.01826) (xy 106.893868 -141.01826)
			(xy 106.893382 -141.045511) (xy 106.885626 -141.099459) (xy 106.870271 -141.151754) (xy 106.847629 -141.201331)
			(xy 106.818163 -141.247181) (xy 106.782472 -141.288372) (xy 106.741281 -141.324063) (xy 106.695431 -141.353529)
			(xy 106.645854 -141.376171) (xy 106.593559 -141.391526) (xy 106.539611 -141.399282) (xy 106.485109 -141.399282)
			(xy 106.431161 -141.391526) (xy 106.378866 -141.376171) (xy 106.329289 -141.353529) (xy 106.283439 -141.324063)
			(xy 106.242248 -141.288372) (xy 106.206557 -141.247181) (xy 106.177091 -141.201331) (xy 106.154449 -141.151754)
			(xy 106.139094 -141.099459) (xy 106.131338 -141.045511) (xy 106.130852 -141.01826) (xy 106.131364 -140.989521)
			(xy 106.139992 -140.932694) (xy 106.157045 -140.877803) (xy 106.182139 -140.826092) (xy 106.214705 -140.778729)
			(xy 106.233976 -140.757402) (xy 106.24058 -140.75029) (xy 106.247692 -140.732764) (xy 106.247692 -140.643356)
			(xy 106.24058 -140.62583) (xy 106.233976 -140.618718) (xy 106.214668 -140.597425) (xy 106.182108 -140.550055)
			(xy 106.157022 -140.498337) (xy 106.139977 -140.443442) (xy 106.131359 -140.386611) (xy 106.131363 -140.329131)
			(xy 106.13999 -140.272301) (xy 106.157043 -140.217408) (xy 106.182137 -140.165694) (xy 106.214704 -140.11833)
			(xy 106.233976 -140.097002) (xy 106.24058 -140.08989) (xy 106.247692 -140.072364) (xy 106.247692 -139.982956)
			(xy 106.24058 -139.96543) (xy 106.233976 -139.958318) (xy 106.214693 -139.937002) (xy 106.182127 -139.889638)
			(xy 106.157036 -139.837923) (xy 106.139988 -139.78303) (xy 106.13137 -139.7262) (xy 106.130852 -139.69746)
			(xy 106.13131 -139.671555) (xy 106.138325 -139.620221) (xy 106.152221 -139.570309) (xy 106.172741 -139.522735)
			(xy 106.199509 -139.478375) (xy 106.215434 -139.457938) (xy 106.22153 -139.450318) (xy 106.227118 -139.43203)
			(xy 106.22026 -139.34313) (xy 106.211878 -139.325604) (xy 106.204766 -139.319) (xy 106.185484 -139.300878)
			(xy 106.151659 -139.260183) (xy 106.123778 -139.215207) (xy 106.102377 -139.166811) (xy 106.087865 -139.115923)
			(xy 106.080521 -139.063518) (xy 106.080052 -139.03706) (xy 100.690934 -139.03706) (xy 100.690934 -158.947612)
			(xy 107.304584 -158.947612) (xy 107.308655 -158.89199) (xy 107.320781 -158.837553) (xy 107.340704 -158.785462)
			(xy 107.368 -158.736827) (xy 107.402086 -158.692684) (xy 107.442235 -158.653975) (xy 107.487593 -158.621524)
			(xy 107.537193 -158.596023) (xy 107.589977 -158.578016) (xy 107.64482 -158.567886) (xy 107.700554 -158.565849)
			(xy 107.755991 -158.571949) (xy 107.809948 -158.586055) (xy 107.861277 -158.607867) (xy 107.908883 -158.636921)
			(xy 107.951751 -158.672596) (xy 107.988968 -158.714133) (xy 108.019741 -158.760646) (xy 108.043413 -158.811143)
			(xy 108.059481 -158.86455) (xy 108.067601 -158.919726) (xy 108.06811 -158.947612) (xy 108.067601 -158.975498)
			(xy 108.059481 -159.030674) (xy 108.043413 -159.084081) (xy 108.019741 -159.134578) (xy 107.988968 -159.181091)
			(xy 107.951751 -159.222628) (xy 107.908883 -159.258303) (xy 107.861277 -159.287357) (xy 107.809948 -159.309169)
			(xy 107.755991 -159.323275) (xy 107.700554 -159.329375) (xy 107.64482 -159.327338) (xy 107.589977 -159.317208)
			(xy 107.537193 -159.299201) (xy 107.487593 -159.2737) (xy 107.442235 -159.241249) (xy 107.402086 -159.20254)
			(xy 107.368 -159.158397) (xy 107.340704 -159.109762) (xy 107.320781 -159.057671) (xy 107.308655 -159.003234)
			(xy 107.304584 -158.947612) (xy 100.690934 -158.947612) (xy 100.690934 -159.681418) (xy 112.176558 -159.681418)
			(xy 112.180629 -159.625796) (xy 112.192755 -159.571359) (xy 112.212678 -159.519268) (xy 112.239974 -159.470633)
			(xy 112.27406 -159.42649) (xy 112.314209 -159.387781) (xy 112.359567 -159.35533) (xy 112.409167 -159.329829)
			(xy 112.461951 -159.311822) (xy 112.516794 -159.301692) (xy 112.572528 -159.299655) (xy 112.627965 -159.305755)
			(xy 112.681922 -159.319861) (xy 112.733251 -159.341673) (xy 112.780857 -159.370727) (xy 112.823725 -159.406402)
			(xy 112.860942 -159.447939) (xy 112.891715 -159.494452) (xy 112.915387 -159.544949) (xy 112.931455 -159.598356)
			(xy 112.939575 -159.653532) (xy 112.940084 -159.681418) (xy 112.939575 -159.709304) (xy 112.931455 -159.76448)
			(xy 112.915387 -159.817887) (xy 112.891715 -159.868384) (xy 112.860942 -159.914897) (xy 112.823725 -159.956434)
			(xy 112.780857 -159.992109) (xy 112.733251 -160.021163) (xy 112.681922 -160.042975) (xy 112.627965 -160.057081)
			(xy 112.572528 -160.063181) (xy 112.516794 -160.061144) (xy 112.461951 -160.051014) (xy 112.409167 -160.033007)
			(xy 112.359567 -160.007506) (xy 112.314209 -159.975055) (xy 112.27406 -159.936346) (xy 112.239974 -159.892203)
			(xy 112.212678 -159.843568) (xy 112.192755 -159.791477) (xy 112.180629 -159.73704) (xy 112.176558 -159.681418)
			(xy 100.690934 -159.681418) (xy 100.690934 -160.220406) (xy 113.389916 -160.220406) (xy 113.393987 -160.164784)
			(xy 113.406113 -160.110347) (xy 113.426036 -160.058256) (xy 113.453332 -160.009621) (xy 113.487418 -159.965478)
			(xy 113.527567 -159.926769) (xy 113.572925 -159.894318) (xy 113.622525 -159.868817) (xy 113.675309 -159.85081)
			(xy 113.730152 -159.84068) (xy 113.785886 -159.838643) (xy 113.841323 -159.844743) (xy 113.89528 -159.858849)
			(xy 113.946609 -159.880661) (xy 113.994215 -159.909715) (xy 114.037083 -159.94539) (xy 114.0743 -159.986927)
			(xy 114.105073 -160.03344) (xy 114.128745 -160.083937) (xy 114.144813 -160.137344) (xy 114.152933 -160.19252)
			(xy 114.153442 -160.220406) (xy 114.152933 -160.248292) (xy 114.144813 -160.303468) (xy 114.128745 -160.356875)
			(xy 114.105073 -160.407372) (xy 114.0743 -160.453885) (xy 114.058189 -160.471866) (xy 114.82019 -160.471866)
			(xy 114.824261 -160.416244) (xy 114.836387 -160.361807) (xy 114.85631 -160.309716) (xy 114.883606 -160.261081)
			(xy 114.917692 -160.216938) (xy 114.957841 -160.178229) (xy 115.003199 -160.145778) (xy 115.052799 -160.120277)
			(xy 115.105583 -160.10227) (xy 115.160426 -160.09214) (xy 115.21616 -160.090103) (xy 115.271597 -160.096203)
			(xy 115.325554 -160.110309) (xy 115.376883 -160.132121) (xy 115.424489 -160.161175) (xy 115.467357 -160.19685)
			(xy 115.504574 -160.238387) (xy 115.535347 -160.2849) (xy 115.559019 -160.335397) (xy 115.575087 -160.388804)
			(xy 115.583207 -160.44398) (xy 115.583716 -160.471866) (xy 115.583207 -160.499752) (xy 115.575087 -160.554928)
			(xy 115.559019 -160.608335) (xy 115.535347 -160.658832) (xy 115.504574 -160.705345) (xy 115.467357 -160.746882)
			(xy 115.424489 -160.782557) (xy 115.376883 -160.811611) (xy 115.325554 -160.833423) (xy 115.271597 -160.847529)
			(xy 115.21616 -160.853629) (xy 115.160426 -160.851592) (xy 115.105583 -160.841462) (xy 115.052799 -160.823455)
			(xy 115.003199 -160.797954) (xy 114.957841 -160.765503) (xy 114.917692 -160.726794) (xy 114.883606 -160.682651)
			(xy 114.85631 -160.634016) (xy 114.836387 -160.581925) (xy 114.824261 -160.527488) (xy 114.82019 -160.471866)
			(xy 114.058189 -160.471866) (xy 114.037083 -160.495422) (xy 113.994215 -160.531097) (xy 113.946609 -160.560151)
			(xy 113.89528 -160.581963) (xy 113.841323 -160.596069) (xy 113.785886 -160.602169) (xy 113.730152 -160.600132)
			(xy 113.675309 -160.590002) (xy 113.622525 -160.571995) (xy 113.572925 -160.546494) (xy 113.527567 -160.514043)
			(xy 113.487418 -160.475334) (xy 113.453332 -160.431191) (xy 113.426036 -160.382556) (xy 113.406113 -160.330465)
			(xy 113.393987 -160.276028) (xy 113.389916 -160.220406) (xy 100.690934 -160.220406) (xy 100.690934 -162.131502)
			(xy 111.67313 -162.131502) (xy 111.677201 -162.07588) (xy 111.689327 -162.021443) (xy 111.70925 -161.969352)
			(xy 111.736546 -161.920717) (xy 111.770632 -161.876574) (xy 111.810781 -161.837865) (xy 111.856139 -161.805414)
			(xy 111.905739 -161.779913) (xy 111.958523 -161.761906) (xy 112.013366 -161.751776) (xy 112.0691 -161.749739)
			(xy 112.124537 -161.755839) (xy 112.178494 -161.769945) (xy 112.229823 -161.791757) (xy 112.252954 -161.805874)
			(xy 113.226848 -161.805874) (xy 113.230919 -161.750252) (xy 113.243045 -161.695815) (xy 113.262968 -161.643724)
			(xy 113.290264 -161.595089) (xy 113.32435 -161.550946) (xy 113.364499 -161.512237) (xy 113.409857 -161.479786)
			(xy 113.459457 -161.454285) (xy 113.512241 -161.436278) (xy 113.567084 -161.426148) (xy 113.622818 -161.424111)
			(xy 113.678255 -161.430211) (xy 113.732212 -161.444317) (xy 113.783541 -161.466129) (xy 113.831147 -161.495183)
			(xy 113.874015 -161.530858) (xy 113.911232 -161.572395) (xy 113.942005 -161.618908) (xy 113.965677 -161.669405)
			(xy 113.981745 -161.722812) (xy 113.989865 -161.777988) (xy 113.990374 -161.805874) (xy 113.989865 -161.83376)
			(xy 113.981745 -161.888936) (xy 113.965677 -161.942343) (xy 113.942005 -161.99284) (xy 113.911232 -162.039353)
			(xy 113.874015 -162.08089) (xy 113.831147 -162.116565) (xy 113.81125 -162.128708) (xy 115.561108 -162.128708)
			(xy 115.565179 -162.073086) (xy 115.577305 -162.018649) (xy 115.597228 -161.966558) (xy 115.624524 -161.917923)
			(xy 115.65861 -161.87378) (xy 115.698759 -161.835071) (xy 115.744117 -161.80262) (xy 115.793717 -161.777119)
			(xy 115.846501 -161.759112) (xy 115.901344 -161.748982) (xy 115.957078 -161.746945) (xy 116.012515 -161.753045)
			(xy 116.066472 -161.767151) (xy 116.117801 -161.788963) (xy 116.165407 -161.818017) (xy 116.208275 -161.853692)
			(xy 116.245492 -161.895229) (xy 116.276265 -161.941742) (xy 116.299937 -161.992239) (xy 116.316005 -162.045646)
			(xy 116.324125 -162.100822) (xy 116.324634 -162.128708) (xy 116.324125 -162.156594) (xy 116.316005 -162.21177)
			(xy 116.299937 -162.265177) (xy 116.276265 -162.315674) (xy 116.245492 -162.362187) (xy 116.208275 -162.403724)
			(xy 116.165407 -162.439399) (xy 116.117801 -162.468453) (xy 116.066472 -162.490265) (xy 116.012515 -162.504371)
			(xy 115.957078 -162.510471) (xy 115.901344 -162.508434) (xy 115.846501 -162.498304) (xy 115.793717 -162.480297)
			(xy 115.744117 -162.454796) (xy 115.698759 -162.422345) (xy 115.65861 -162.383636) (xy 115.624524 -162.339493)
			(xy 115.597228 -162.290858) (xy 115.577305 -162.238767) (xy 115.565179 -162.18433) (xy 115.561108 -162.128708)
			(xy 113.81125 -162.128708) (xy 113.783541 -162.145619) (xy 113.732212 -162.167431) (xy 113.678255 -162.181537)
			(xy 113.622818 -162.187637) (xy 113.567084 -162.1856) (xy 113.512241 -162.17547) (xy 113.459457 -162.157463)
			(xy 113.409857 -162.131962) (xy 113.364499 -162.099511) (xy 113.32435 -162.060802) (xy 113.290264 -162.016659)
			(xy 113.262968 -161.968024) (xy 113.243045 -161.915933) (xy 113.230919 -161.861496) (xy 113.226848 -161.805874)
			(xy 112.252954 -161.805874) (xy 112.277429 -161.820811) (xy 112.320297 -161.856486) (xy 112.357514 -161.898023)
			(xy 112.388287 -161.944536) (xy 112.411959 -161.995033) (xy 112.428027 -162.04844) (xy 112.436147 -162.103616)
			(xy 112.436656 -162.131502) (xy 112.436147 -162.159388) (xy 112.428027 -162.214564) (xy 112.411959 -162.267971)
			(xy 112.388287 -162.318468) (xy 112.357514 -162.364981) (xy 112.320297 -162.406518) (xy 112.277429 -162.442193)
			(xy 112.229823 -162.471247) (xy 112.178494 -162.493059) (xy 112.124537 -162.507165) (xy 112.0691 -162.513265)
			(xy 112.013366 -162.511228) (xy 111.958523 -162.501098) (xy 111.905739 -162.483091) (xy 111.856139 -162.45759)
			(xy 111.810781 -162.425139) (xy 111.770632 -162.38643) (xy 111.736546 -162.342287) (xy 111.70925 -162.293652)
			(xy 111.689327 -162.241561) (xy 111.677201 -162.187124) (xy 111.67313 -162.131502) (xy 100.690934 -162.131502)
			(xy 100.690934 -163.41344) (xy 113.15268 -163.41344) (xy 113.156751 -163.357818) (xy 113.168877 -163.303381)
			(xy 113.1888 -163.25129) (xy 113.216096 -163.202655) (xy 113.250182 -163.158512) (xy 113.290331 -163.119803)
			(xy 113.335689 -163.087352) (xy 113.385289 -163.061851) (xy 113.438073 -163.043844) (xy 113.492916 -163.033714)
			(xy 113.54865 -163.031677) (xy 113.604087 -163.037777) (xy 113.658044 -163.051883) (xy 113.709373 -163.073695)
			(xy 113.756979 -163.102749) (xy 113.799847 -163.138424) (xy 113.837064 -163.179961) (xy 113.867837 -163.226474)
			(xy 113.891509 -163.276971) (xy 113.907577 -163.330378) (xy 113.915697 -163.385554) (xy 113.916206 -163.41344)
			(xy 113.915697 -163.441326) (xy 113.907577 -163.496502) (xy 113.891509 -163.549909) (xy 113.867837 -163.600406)
			(xy 113.837064 -163.646919) (xy 113.799847 -163.688456) (xy 113.756979 -163.724131) (xy 113.709373 -163.753185)
			(xy 113.658044 -163.774997) (xy 113.604087 -163.789103) (xy 113.54865 -163.795203) (xy 113.492916 -163.793166)
			(xy 113.438073 -163.783036) (xy 113.385289 -163.765029) (xy 113.335689 -163.739528) (xy 113.290331 -163.707077)
			(xy 113.250182 -163.668368) (xy 113.216096 -163.624225) (xy 113.1888 -163.57559) (xy 113.168877 -163.523499)
			(xy 113.156751 -163.469062) (xy 113.15268 -163.41344) (xy 100.690934 -163.41344) (xy 100.690934 -180.494686)
			(xy 100.691374 -180.504749) (xy 100.699114 -180.523327) (xy 100.70592 -180.530754) (xy 101.114606 -180.93944)
			(xy 107.97667 -180.93944) (xy 107.977165 -180.9107) (xy 107.985796 -180.853872) (xy 108.002853 -180.798981)
			(xy 108.027951 -180.74727) (xy 108.060521 -180.699908) (xy 108.079794 -180.678582) (xy 108.086398 -180.67147)
			(xy 108.09351 -180.653944) (xy 108.09351 -180.564536) (xy 108.086398 -180.54701) (xy 108.079794 -180.539898)
			(xy 108.060552 -180.518546) (xy 108.02798 -180.471192) (xy 108.002881 -180.419487) (xy 107.985824 -180.364601)
			(xy 107.977195 -180.307777) (xy 107.97667 -180.27904) (xy 107.977192 -180.251789) (xy 107.984943 -180.197841)
			(xy 108.000293 -180.145546) (xy 108.022929 -180.095968) (xy 108.052391 -180.050115) (xy 108.088079 -180.008923)
			(xy 108.129266 -179.973228) (xy 108.175113 -179.943759) (xy 108.224688 -179.921115) (xy 108.276981 -179.905757)
			(xy 108.330927 -179.897997) (xy 108.358178 -179.897532) (xy 108.383547 -179.897949) (xy 108.433837 -179.904672)
			(xy 108.482791 -179.918002) (xy 108.529547 -179.937705) (xy 108.573278 -179.963431) (xy 108.613213 -179.994728)
			(xy 108.631228 -180.012594) (xy 108.63834 -180.01996) (xy 108.656628 -180.027834) (xy 108.74883 -180.029104)
			(xy 108.767118 -180.021738) (xy 108.774484 -180.014626) (xy 108.795961 -179.994638) (xy 108.843891 -179.960808)
			(xy 108.896434 -179.934711) (xy 108.952352 -179.916962) (xy 109.010327 -179.907978) (xy 109.03966 -179.907438)
			(xy 109.06703 -179.907918) (xy 109.121209 -179.915731) (xy 109.173712 -179.931216) (xy 109.223459 -179.954055)
			(xy 109.269426 -179.983778) (xy 109.290358 -180.001418) (xy 109.29747 -180.007514) (xy 109.314488 -180.013864)
			(xy 109.399832 -180.013864) (xy 109.41685 -180.007514) (xy 109.423962 -180.001418) (xy 109.444895 -179.983777)
			(xy 109.490863 -179.954053) (xy 109.540609 -179.931207) (xy 109.593111 -179.915711) (xy 109.647289 -179.907882)
			(xy 109.702031 -179.907882) (xy 109.756209 -179.915711) (xy 109.808711 -179.931207) (xy 109.858457 -179.954053)
			(xy 109.904425 -179.983777) (xy 109.925358 -180.001418) (xy 109.93247 -180.007514) (xy 109.949488 -180.013864)
			(xy 110.034832 -180.013864) (xy 110.05185 -180.007514) (xy 110.058962 -180.001418) (xy 110.079895 -179.983777)
			(xy 110.125863 -179.954053) (xy 110.175609 -179.931207) (xy 110.228111 -179.915711) (xy 110.282289 -179.907882)
			(xy 110.337031 -179.907882) (xy 110.391209 -179.915711) (xy 110.443711 -179.931207) (xy 110.493457 -179.954053)
			(xy 110.539425 -179.983777) (xy 110.560358 -180.001418) (xy 110.56747 -180.007514) (xy 110.584488 -180.013864)
			(xy 110.669832 -180.013864) (xy 110.68685 -180.007514) (xy 110.693962 -180.001418) (xy 110.714895 -179.983777)
			(xy 110.760863 -179.954053) (xy 110.810609 -179.931207) (xy 110.863111 -179.915711) (xy 110.917289 -179.907882)
			(xy 110.972031 -179.907882) (xy 111.026209 -179.915711) (xy 111.078711 -179.931207) (xy 111.128457 -179.954053)
			(xy 111.174425 -179.983777) (xy 111.195358 -180.001418) (xy 111.20247 -180.007514) (xy 111.219488 -180.013864)
			(xy 111.304832 -180.013864) (xy 111.32185 -180.007514) (xy 111.328962 -180.001418) (xy 111.3499 -179.983786)
			(xy 111.395871 -179.954073) (xy 111.445617 -179.931235) (xy 111.498116 -179.915742) (xy 111.552291 -179.907913)
			(xy 111.57966 -179.907438) (xy 111.606914 -179.907893) (xy 111.660868 -179.915645) (xy 111.713168 -179.930999)
			(xy 111.762751 -179.95364) (xy 111.808607 -179.983108) (xy 111.849801 -180.018803) (xy 111.885496 -180.059998)
			(xy 111.914963 -180.105854) (xy 111.937603 -180.155437) (xy 111.952956 -180.207738) (xy 111.960708 -180.261692)
			(xy 111.961168 -180.288946) (xy 111.960654 -180.317685) (xy 111.952026 -180.374512) (xy 111.934973 -180.429402)
			(xy 111.90988 -180.481114) (xy 111.877314 -180.528477) (xy 111.858044 -180.549804) (xy 111.85144 -180.556916)
			(xy 111.844328 -180.574442) (xy 111.844328 -180.66385) (xy 111.85144 -180.681376) (xy 111.858044 -180.688488)
			(xy 111.877334 -180.709799) (xy 111.909898 -180.757165) (xy 111.934987 -180.808881) (xy 111.952033 -180.863775)
			(xy 111.96065 -180.920606) (xy 111.961168 -180.949346) (xy 111.960765 -180.9766) (xy 111.953001 -181.030553)
			(xy 111.937638 -181.082852) (xy 111.914989 -181.132432) (xy 111.885514 -181.178284) (xy 111.849814 -181.219475)
			(xy 111.808615 -181.255165) (xy 111.762756 -181.28463) (xy 111.713171 -181.307268) (xy 111.660869 -181.322619)
			(xy 111.606914 -181.330371) (xy 111.57966 -181.330854) (xy 111.552291 -181.330364) (xy 111.498112 -181.322554)
			(xy 111.445609 -181.307071) (xy 111.395861 -181.284234) (xy 111.349894 -181.254514) (xy 111.328962 -181.236874)
			(xy 111.32185 -181.230778) (xy 111.304832 -181.224428) (xy 111.219488 -181.224428) (xy 111.20247 -181.230778)
			(xy 111.195358 -181.236874) (xy 111.174425 -181.254515) (xy 111.128457 -181.284239) (xy 111.078711 -181.307085)
			(xy 111.026209 -181.322581) (xy 110.972031 -181.33041) (xy 110.917289 -181.33041) (xy 110.863111 -181.322581)
			(xy 110.810609 -181.307085) (xy 110.760863 -181.284239) (xy 110.714895 -181.254515) (xy 110.693962 -181.236874)
			(xy 110.68685 -181.230778) (xy 110.669832 -181.224428) (xy 110.584488 -181.224428) (xy 110.56747 -181.230778)
			(xy 110.560358 -181.236874) (xy 110.539425 -181.254515) (xy 110.493457 -181.284239) (xy 110.443711 -181.307085)
			(xy 110.391209 -181.322581) (xy 110.337031 -181.33041) (xy 110.282289 -181.33041) (xy 110.228111 -181.322581)
			(xy 110.175609 -181.307085) (xy 110.125863 -181.284239) (xy 110.079895 -181.254515) (xy 110.058962 -181.236874)
			(xy 110.05185 -181.230778) (xy 110.034832 -181.224428) (xy 109.949488 -181.224428) (xy 109.93247 -181.230778)
			(xy 109.925358 -181.236874) (xy 109.904425 -181.254515) (xy 109.858457 -181.284239) (xy 109.808711 -181.307085)
			(xy 109.756209 -181.322581) (xy 109.702031 -181.33041) (xy 109.647289 -181.33041) (xy 109.593111 -181.322581)
			(xy 109.540609 -181.307085) (xy 109.490863 -181.284239) (xy 109.444895 -181.254515) (xy 109.423962 -181.236874)
			(xy 109.41685 -181.230778) (xy 109.399832 -181.224428) (xy 109.314488 -181.224428) (xy 109.29747 -181.230778)
			(xy 109.290358 -181.236874) (xy 109.269412 -181.254495) (xy 109.223443 -181.284211) (xy 109.173699 -181.30705)
			(xy 109.121202 -181.322546) (xy 109.067028 -181.330378) (xy 109.03966 -181.330854) (xy 109.01429 -181.330482)
			(xy 108.963998 -181.32375) (xy 108.915042 -181.310411) (xy 108.868286 -181.290701) (xy 108.824556 -181.264966)
			(xy 108.784624 -181.233662) (xy 108.76661 -181.215792) (xy 108.759498 -181.208426) (xy 108.74121 -181.200552)
			(xy 108.649008 -181.199282) (xy 108.63072 -181.206648) (xy 108.623354 -181.21376) (xy 108.601875 -181.233744)
			(xy 108.553943 -181.267571) (xy 108.501401 -181.293668) (xy 108.445485 -181.311418) (xy 108.387511 -181.320405)
			(xy 108.358178 -181.320948) (xy 108.330928 -181.320443) (xy 108.276983 -181.312684) (xy 108.224691 -181.297328)
			(xy 108.175117 -181.274688) (xy 108.129268 -181.245223) (xy 108.088079 -181.209534) (xy 108.052388 -181.168346)
			(xy 108.022921 -181.122499) (xy 108.000278 -181.072926) (xy 107.98492 -181.020635) (xy 107.977158 -180.96669)
			(xy 107.97667 -180.93944) (xy 101.114606 -180.93944) (xy 104.24922 -184.074054) (xy 104.252834 -184.077492)
			(xy 104.261148 -184.083004) (xy 104.26573 -184.084976) (xy 104.41813 -184.148222) (xy 104.422817 -184.150017)
			(xy 104.432669 -184.151928) (xy 104.437688 -184.152032)
		)
		(stroke
			(width 0)
			(type solid)
		)
		(fill yes)
		(layer "In15.Cu")
		(net "GND")
	)
	(gr_poly
		(pts
			(xy 233.136186 -224.299526) (xy 233.137456 -224.279714) (xy 233.139867 -224.253738) (xy 233.151828 -224.202962)
			(xy 233.17161 -224.154692) (xy 233.198721 -224.110124) (xy 233.232491 -224.070363) (xy 233.272081 -224.036395)
			(xy 233.316512 -224.00906) (xy 233.364682 -223.989036) (xy 233.415398 -223.97682) (xy 233.467402 -223.972714)
			(xy 233.519406 -223.97682) (xy 233.570122 -223.989036) (xy 233.618292 -224.00906) (xy 233.662723 -224.036395)
			(xy 233.702313 -224.070363) (xy 233.736083 -224.110124) (xy 233.763194 -224.154692) (xy 233.782976 -224.202962)
			(xy 233.794937 -224.253738) (xy 233.797348 -224.279714) (xy 233.798618 -224.299526) (xy 233.827828 -224.326704)
			(xy 233.907076 -224.326704) (xy 233.936286 -224.299526) (xy 233.937556 -224.279714) (xy 233.939967 -224.253738)
			(xy 233.951928 -224.202962) (xy 233.97171 -224.154692) (xy 233.998821 -224.110124) (xy 234.032591 -224.070363)
			(xy 234.072181 -224.036395) (xy 234.116612 -224.00906) (xy 234.164782 -223.989036) (xy 234.215498 -223.97682)
			(xy 234.267502 -223.972714) (xy 234.319506 -223.97682) (xy 234.370222 -223.989036) (xy 234.418392 -224.00906)
			(xy 234.462823 -224.036395) (xy 234.502413 -224.070363) (xy 234.536183 -224.110124) (xy 234.563294 -224.154692)
			(xy 234.583076 -224.202962) (xy 234.595037 -224.253738) (xy 234.597448 -224.279714) (xy 234.598718 -224.299526)
			(xy 234.627928 -224.326704) (xy 234.706922 -224.326704) (xy 234.736132 -224.299526) (xy 234.737402 -224.279714)
			(xy 234.739674 -224.255034) (xy 234.750664 -224.206708) (xy 234.768735 -224.160559) (xy 234.793482 -224.11762)
			(xy 234.824352 -224.078848) (xy 234.860657 -224.04511) (xy 234.901584 -224.017161) (xy 234.94622 -223.995623)
			(xy 234.993567 -223.980979) (xy 235.042568 -223.973555) (xy 235.067348 -223.973136) (xy 235.092663 -223.973621)
			(xy 235.142702 -223.98134) (xy 235.190982 -223.99659) (xy 235.236375 -224.019015) (xy 235.277824 -224.048093)
			(xy 235.31436 -224.083144) (xy 235.345131 -224.123352) (xy 235.35767 -224.145348) (xy 235.363512 -224.156016)
			(xy 235.382816 -224.169478) (xy 235.475526 -224.18294) (xy 235.487367 -224.183975) (xy 235.509872 -224.176417)
			(xy 235.518706 -224.168462) (xy 235.732066 -223.955102) (xy 235.739976 -223.946254) (xy 235.747388 -223.92374)
			(xy 235.74629 -223.911922) (xy 235.733082 -223.819466) (xy 235.71962 -223.800162) (xy 235.708952 -223.79432)
			(xy 235.686962 -223.781767) (xy 235.646738 -223.751016) (xy 235.611675 -223.714489) (xy 235.582593 -223.673042)
			(xy 235.560173 -223.627645) (xy 235.544939 -223.579359) (xy 235.537247 -223.529314) (xy 235.53674 -223.503998)
			(xy 235.537223 -223.47801) (xy 235.545355 -223.426675) (xy 235.561418 -223.377244) (xy 235.585017 -223.330934)
			(xy 235.61557 -223.288887) (xy 235.652325 -223.252137) (xy 235.694377 -223.221591) (xy 235.74069 -223.197999)
			(xy 235.790123 -223.181943) (xy 235.84146 -223.173819) (xy 235.867448 -223.17329) (xy 235.892763 -223.173775)
			(xy 235.9428 -223.181495) (xy 235.991077 -223.196746) (xy 236.036468 -223.219174) (xy 236.077913 -223.248254)
			(xy 236.114444 -223.283308) (xy 236.145209 -223.323518) (xy 236.15777 -223.345502) (xy 236.163612 -223.35617)
			(xy 236.182916 -223.369632) (xy 236.275372 -223.38284) (xy 236.287185 -223.383936) (xy 236.309684 -223.376501)
			(xy 236.318552 -223.368616) (xy 236.538516 -223.148652) (xy 236.545882 -223.127062) (xy 236.544612 -223.115378)
			(xy 236.543416 -223.104368) (xy 236.542144 -223.082256) (xy 236.542072 -223.071182) (xy 236.542559 -223.043931)
			(xy 236.550317 -222.989984) (xy 236.565674 -222.93769) (xy 236.588316 -222.888114) (xy 236.617782 -222.842265)
			(xy 236.653474 -222.801075) (xy 236.694663 -222.765384) (xy 236.740513 -222.735917) (xy 236.790089 -222.713275)
			(xy 236.842382 -222.697918) (xy 236.896329 -222.690159) (xy 236.92358 -222.689674) (xy 236.934654 -222.689748)
			(xy 236.956766 -222.691021) (xy 236.967776 -222.692214) (xy 236.97946 -222.693484) (xy 237.00105 -222.686118)
			(xy 238.247936 -221.439232) (xy 238.254779 -221.431833) (xy 238.262499 -221.413234) (xy 238.262922 -221.403164)
			(xy 238.262922 -220.270832) (xy 238.262487 -220.260767) (xy 238.254758 -220.242178) (xy 238.247936 -220.234764)
			(xy 237.897924 -219.884752) (xy 237.890524 -219.877912) (xy 237.871925 -219.870197) (xy 237.861856 -219.869766)
			(xy 235.752386 -219.869766) (xy 235.742318 -219.870193) (xy 235.723724 -219.877919) (xy 235.716318 -219.884752)
			(xy 235.622084 -219.978986) (xy 235.615242 -219.986385) (xy 235.607526 -220.004984) (xy 235.607098 -220.015054)
			(xy 235.607098 -220.474794) (xy 235.606676 -220.484865) (xy 235.598963 -220.50347) (xy 235.592112 -220.510862)
			(xy 235.39196 -220.711014) (xy 235.384564 -220.717864) (xy 235.365964 -220.725597) (xy 235.355892 -220.726)
			(xy 235.26369 -220.726) (xy 235.253684 -220.72649) (xy 235.235195 -220.734151) (xy 235.221046 -220.748304)
			(xy 235.213388 -220.766794) (xy 235.21289 -220.7768) (xy 235.21289 -220.790262) (xy 235.225844 -220.813376)
			(xy 235.237528 -220.820234) (xy 235.258184 -220.833149) (xy 235.295813 -220.864088) (xy 235.328499 -220.900209)
			(xy 235.355537 -220.940732) (xy 235.376341 -220.984782) (xy 235.390463 -221.031405) (xy 235.397598 -221.079594)
			(xy 235.398056 -221.103952) (xy 235.397546 -221.129939) (xy 235.53725 -221.129939) (xy 235.53725 -221.077965)
			(xy 235.54538 -221.02663) (xy 235.561441 -220.9772) (xy 235.585037 -220.93089) (xy 235.615587 -220.888842)
			(xy 235.652338 -220.852091) (xy 235.694386 -220.821541) (xy 235.740696 -220.797945) (xy 235.790126 -220.781884)
			(xy 235.841461 -220.773754) (xy 235.893435 -220.773754) (xy 235.94477 -220.781884) (xy 235.9942 -220.797945)
			(xy 236.04051 -220.821541) (xy 236.082558 -220.852091) (xy 236.119309 -220.888842) (xy 236.149859 -220.93089)
			(xy 236.173455 -220.9772) (xy 236.189516 -221.02663) (xy 236.197646 -221.077965) (xy 236.198156 -221.103952)
			(xy 236.197646 -221.129939) (xy 236.189516 -221.181274) (xy 236.173455 -221.230704) (xy 236.149859 -221.277014)
			(xy 236.119309 -221.319062) (xy 236.082558 -221.355813) (xy 236.04051 -221.386363) (xy 235.9942 -221.409959)
			(xy 235.94477 -221.42602) (xy 235.893435 -221.43415) (xy 235.841461 -221.43415) (xy 235.790126 -221.42602)
			(xy 235.740696 -221.409959) (xy 235.694386 -221.386363) (xy 235.652338 -221.355813) (xy 235.615587 -221.319062)
			(xy 235.585037 -221.277014) (xy 235.561441 -221.230704) (xy 235.54538 -221.181274) (xy 235.53725 -221.129939)
			(xy 235.397546 -221.129939) (xy 235.389416 -221.181274) (xy 235.373355 -221.230704) (xy 235.349759 -221.277014)
			(xy 235.319209 -221.319062) (xy 235.282458 -221.355813) (xy 235.24041 -221.386363) (xy 235.1941 -221.409959)
			(xy 235.14467 -221.42602) (xy 235.093335 -221.43415) (xy 235.041361 -221.43415) (xy 234.990026 -221.42602)
			(xy 234.940596 -221.409959) (xy 234.894286 -221.386363) (xy 234.852238 -221.355813) (xy 234.815487 -221.319062)
			(xy 234.784937 -221.277014) (xy 234.761341 -221.230704) (xy 234.74528 -221.181274) (xy 234.73715 -221.129939)
			(xy 234.73664 -221.103952) (xy 234.737279 -221.075273) (xy 234.747214 -221.018782) (xy 234.766727 -220.964845)
			(xy 234.795236 -220.915073) (xy 234.813094 -220.892624) (xy 234.822746 -220.88094) (xy 234.826302 -220.851984)
			(xy 234.780836 -220.75521) (xy 234.776378 -220.746673) (xy 234.762367 -220.733482) (xy 234.744483 -220.726376)
			(xy 234.734862 -220.726) (xy 234.599988 -220.726) (xy 234.590371 -220.726414) (xy 234.572489 -220.733503)
			(xy 234.558476 -220.74668) (xy 234.554014 -220.75521) (xy 234.508548 -220.851984) (xy 234.512104 -220.88094)
			(xy 234.521756 -220.892624) (xy 234.539636 -220.91506) (xy 234.568173 -220.964822) (xy 234.587685 -221.018766)
			(xy 234.597586 -221.07527) (xy 234.59821 -221.103952) (xy 234.5977 -221.129939) (xy 234.58957 -221.181274)
			(xy 234.573509 -221.230704) (xy 234.549913 -221.277014) (xy 234.519363 -221.319062) (xy 234.482612 -221.355813)
			(xy 234.440564 -221.386363) (xy 234.394254 -221.409959) (xy 234.344824 -221.42602) (xy 234.293489 -221.43415)
			(xy 234.241515 -221.43415) (xy 234.19018 -221.42602) (xy 234.14075 -221.409959) (xy 234.09444 -221.386363)
			(xy 234.052392 -221.355813) (xy 234.015641 -221.319062) (xy 233.985091 -221.277014) (xy 233.961495 -221.230704)
			(xy 233.945434 -221.181274) (xy 233.937304 -221.129939) (xy 233.936794 -221.103952) (xy 233.937432 -221.075273)
			(xy 233.947366 -221.018781) (xy 233.966877 -220.964842) (xy 233.995383 -220.915067) (xy 234.013248 -220.892624)
			(xy 234.0229 -220.88094) (xy 234.026456 -220.851984) (xy 233.98099 -220.75521) (xy 233.97653 -220.746679)
			(xy 233.962516 -220.7335) (xy 233.944634 -220.72641) (xy 233.935016 -220.726) (xy 233.799888 -220.726)
			(xy 233.790271 -220.726414) (xy 233.772389 -220.733503) (xy 233.758376 -220.74668) (xy 233.753914 -220.75521)
			(xy 233.708448 -220.851984) (xy 233.712004 -220.88094) (xy 233.721656 -220.892624) (xy 233.739536 -220.91506)
			(xy 233.768073 -220.964822) (xy 233.787585 -221.018766) (xy 233.797486 -221.07527) (xy 233.79811 -221.103952)
			(xy 233.7976 -221.129939) (xy 233.78947 -221.181274) (xy 233.773409 -221.230704) (xy 233.749813 -221.277014)
			(xy 233.719263 -221.319062) (xy 233.682512 -221.355813) (xy 233.640464 -221.386363) (xy 233.594154 -221.409959)
			(xy 233.544724 -221.42602) (xy 233.493389 -221.43415) (xy 233.441415 -221.43415) (xy 233.39008 -221.42602)
			(xy 233.34065 -221.409959) (xy 233.29434 -221.386363) (xy 233.252292 -221.355813) (xy 233.215541 -221.319062)
			(xy 233.184991 -221.277014) (xy 233.161395 -221.230704) (xy 233.145334 -221.181274) (xy 233.137204 -221.129939)
			(xy 233.136694 -221.103952) (xy 233.137142 -221.079054) (xy 233.144607 -221.029821) (xy 233.159375 -220.982265)
			(xy 233.181113 -220.937465) (xy 233.209327 -220.896433) (xy 233.243379 -220.8601) (xy 233.262678 -220.844364)
			(xy 233.271314 -220.837506) (xy 233.28122 -220.818456) (xy 233.2863 -220.731588) (xy 233.286463 -220.720815)
			(xy 233.278823 -220.700692) (xy 233.271568 -220.692726) (xy 233.232452 -220.65361) (xy 233.225598 -220.646215)
			(xy 233.217852 -220.627616) (xy 233.217466 -220.617542) (xy 233.217466 -220.538548) (xy 233.217122 -220.530123)
			(xy 233.211689 -220.514173) (xy 233.206798 -220.507306) (xy 233.190335 -220.485376) (xy 233.164156 -220.437195)
			(xy 233.146295 -220.385351) (xy 233.137245 -220.331269) (xy 233.136694 -220.303852) (xy 233.137258 -220.276438)
			(xy 233.146341 -220.222367) (xy 233.164202 -220.170529) (xy 233.190353 -220.122339) (xy 233.206798 -220.100398)
			(xy 233.211747 -220.093558) (xy 233.217209 -220.077594) (xy 233.217466 -220.069156) (xy 233.217466 -219.74048)
			(xy 233.217066 -219.732038) (xy 233.211483 -219.716098) (xy 233.206544 -219.709238) (xy 233.189858 -219.687149)
			(xy 233.163306 -219.638577) (xy 233.145185 -219.586271) (xy 233.135996 -219.531684) (xy 233.135424 -219.504006)
			(xy 233.135424 -219.207588) (xy 233.134934 -219.19758) (xy 233.127274 -219.179088) (xy 233.113122 -219.164933)
			(xy 233.094632 -219.157268) (xy 233.084624 -219.156788) (xy 232.22331 -219.156788) (xy 232.214067 -219.157252)
			(xy 232.196814 -219.163909) (xy 232.18302 -219.176227) (xy 232.178352 -219.18422) (xy 232.129838 -219.276422)
			(xy 232.131616 -219.304616) (xy 232.139744 -219.3163) (xy 232.153543 -219.33711) (xy 232.175388 -219.382007)
			(xy 232.190233 -219.429679) (xy 232.19774 -219.479041) (xy 232.198164 -219.504006) (xy 232.197654 -219.529993)
			(xy 232.189524 -219.581328) (xy 232.173463 -219.630758) (xy 232.149867 -219.677068) (xy 232.119317 -219.719116)
			(xy 232.082566 -219.755867) (xy 232.040518 -219.786417) (xy 231.994208 -219.810013) (xy 231.944778 -219.826074)
			(xy 231.893443 -219.834204) (xy 231.841469 -219.834204) (xy 231.790134 -219.826074) (xy 231.740704 -219.810013)
			(xy 231.694394 -219.786417) (xy 231.652346 -219.755867) (xy 231.615595 -219.719116) (xy 231.585045 -219.677068)
			(xy 231.561449 -219.630758) (xy 231.545388 -219.581328) (xy 231.537258 -219.529993) (xy 231.536748 -219.504006)
			(xy 231.537525 -219.471935) (xy 231.549927 -219.409002) (xy 231.561386 -219.379038) (xy 231.567228 -219.364814)
			(xy 231.561132 -219.334842) (xy 231.55021 -219.32392) (xy 231.542776 -219.317204) (xy 231.524276 -219.309568)
			(xy 231.504262 -219.309568) (xy 231.485762 -219.317204) (xy 231.478328 -219.32392) (xy 231.397048 -219.4052)
			(xy 231.389682 -219.429076) (xy 231.392222 -219.441522) (xy 231.394989 -219.456994) (xy 231.397912 -219.48829)
			(xy 231.398064 -219.504006) (xy 231.39758 -219.529994) (xy 231.389448 -219.581329) (xy 231.373385 -219.63076)
			(xy 231.349786 -219.677069) (xy 231.319233 -219.719116) (xy 231.282478 -219.755865) (xy 231.240426 -219.786412)
			(xy 231.194114 -219.810004) (xy 231.14468 -219.82606) (xy 231.093344 -219.834184) (xy 231.067356 -219.834714)
			(xy 231.05164 -219.834553) (xy 231.020345 -219.83163) (xy 231.004872 -219.828872) (xy 230.992426 -219.826332)
			(xy 230.96855 -219.833698) (xy 230.887778 -219.91447) (xy 230.880941 -219.921836) (xy 230.873205 -219.940367)
			(xy 230.873208 -219.960448) (xy 230.88095 -219.978977) (xy 230.887778 -219.986352) (xy 230.8987 -219.997274)
			(xy 230.928418 -220.00337) (xy 230.942642 -219.997528) (xy 230.972557 -219.986154) (xy 231.03536 -219.973876)
			(xy 231.067356 -219.973144) (xy 231.093351 -219.973624) (xy 231.144703 -219.981751) (xy 231.19415 -219.997812)
			(xy 231.240476 -220.02141) (xy 231.28254 -220.051966) (xy 231.319305 -220.088727) (xy 231.349867 -220.130786)
			(xy 231.373472 -220.177109) (xy 231.389539 -220.226555) (xy 231.397673 -220.277905) (xy 231.397673 -220.329839)
			(xy 231.537258 -220.329839) (xy 231.537258 -220.277865) (xy 231.545388 -220.22653) (xy 231.561449 -220.1771)
			(xy 231.585045 -220.13079) (xy 231.615595 -220.088742) (xy 231.652346 -220.051991) (xy 231.694394 -220.021441)
			(xy 231.740704 -219.997845) (xy 231.790134 -219.981784) (xy 231.841469 -219.973654) (xy 231.893443 -219.973654)
			(xy 231.944778 -219.981784) (xy 231.994208 -219.997845) (xy 232.040518 -220.021441) (xy 232.082566 -220.051991)
			(xy 232.119317 -220.088742) (xy 232.149867 -220.13079) (xy 232.173463 -220.1771) (xy 232.189524 -220.22653)
			(xy 232.197654 -220.277865) (xy 232.198164 -220.303852) (xy 232.197654 -220.329839) (xy 232.189524 -220.381174)
			(xy 232.173463 -220.430604) (xy 232.149867 -220.476914) (xy 232.119317 -220.518962) (xy 232.082566 -220.555713)
			(xy 232.040518 -220.586263) (xy 231.994208 -220.609859) (xy 231.944778 -220.62592) (xy 231.893443 -220.63405)
			(xy 231.841469 -220.63405) (xy 231.790134 -220.62592) (xy 231.740704 -220.609859) (xy 231.694394 -220.586263)
			(xy 231.652346 -220.555713) (xy 231.615595 -220.518962) (xy 231.585045 -220.476914) (xy 231.561449 -220.430604)
			(xy 231.545388 -220.381174) (xy 231.537258 -220.329839) (xy 231.397673 -220.329839) (xy 231.397673 -220.329895)
			(xy 231.389539 -220.381245) (xy 231.373472 -220.430691) (xy 231.349867 -220.477014) (xy 231.319305 -220.519073)
			(xy 231.28254 -220.555834) (xy 231.240476 -220.58639) (xy 231.19415 -220.609988) (xy 231.144703 -220.626049)
			(xy 231.093351 -220.634176) (xy 231.067356 -220.63456) (xy 231.041099 -220.634052) (xy 230.989247 -220.625745)
			(xy 230.93936 -220.609347) (xy 230.892692 -220.58527) (xy 230.850416 -220.55412) (xy 230.831644 -220.535754)
			(xy 230.820722 -220.524832) (xy 230.790496 -220.518482) (xy 230.68915 -220.560138) (xy 230.680028 -220.564354)
			(xy 230.665815 -220.578538) (xy 230.658126 -220.597088) (xy 230.657654 -220.607128) (xy 230.657654 -220.800676)
			(xy 230.658073 -220.810726) (xy 230.665771 -220.829294) (xy 230.68 -220.843492) (xy 230.68915 -220.847666)
			(xy 230.790496 -220.889322) (xy 230.820722 -220.882972) (xy 230.831644 -220.87205) (xy 230.850409 -220.853676)
			(xy 230.892679 -220.822514) (xy 230.939349 -220.798435) (xy 230.989241 -220.782045) (xy 231.041098 -220.773759)
			(xy 231.067356 -220.773244) (xy 231.093351 -220.773724) (xy 231.144703 -220.781851) (xy 231.19415 -220.797912)
			(xy 231.240476 -220.82151) (xy 231.28254 -220.852066) (xy 231.319305 -220.888827) (xy 231.349867 -220.930886)
			(xy 231.373472 -220.977209) (xy 231.389539 -221.026655) (xy 231.397673 -221.078005) (xy 231.397673 -221.129939)
			(xy 231.537258 -221.129939) (xy 231.537258 -221.077965) (xy 231.545388 -221.02663) (xy 231.561449 -220.9772)
			(xy 231.585045 -220.93089) (xy 231.615595 -220.888842) (xy 231.652346 -220.852091) (xy 231.694394 -220.821541)
			(xy 231.740704 -220.797945) (xy 231.790134 -220.781884) (xy 231.841469 -220.773754) (xy 231.893443 -220.773754)
			(xy 231.944778 -220.781884) (xy 231.994208 -220.797945) (xy 232.040518 -220.821541) (xy 232.082566 -220.852091)
			(xy 232.119317 -220.888842) (xy 232.149867 -220.93089) (xy 232.173463 -220.9772) (xy 232.189524 -221.02663)
			(xy 232.197654 -221.077965) (xy 232.198164 -221.103952) (xy 232.197654 -221.129939) (xy 232.337358 -221.129939)
			(xy 232.337358 -221.077965) (xy 232.345488 -221.02663) (xy 232.361549 -220.9772) (xy 232.385145 -220.93089)
			(xy 232.415695 -220.888842) (xy 232.452446 -220.852091) (xy 232.494494 -220.821541) (xy 232.540804 -220.797945)
			(xy 232.590234 -220.781884) (xy 232.641569 -220.773754) (xy 232.693543 -220.773754) (xy 232.744878 -220.781884)
			(xy 232.794308 -220.797945) (xy 232.840618 -220.821541) (xy 232.882666 -220.852091) (xy 232.919417 -220.888842)
			(xy 232.949967 -220.93089) (xy 232.973563 -220.9772) (xy 232.989624 -221.02663) (xy 232.997754 -221.077965)
			(xy 232.998264 -221.103952) (xy 232.997754 -221.129939) (xy 232.989624 -221.181274) (xy 232.973563 -221.230704)
			(xy 232.949967 -221.277014) (xy 232.919417 -221.319062) (xy 232.882666 -221.355813) (xy 232.840618 -221.386363)
			(xy 232.794308 -221.409959) (xy 232.744878 -221.42602) (xy 232.693543 -221.43415) (xy 232.641569 -221.43415)
			(xy 232.590234 -221.42602) (xy 232.540804 -221.409959) (xy 232.494494 -221.386363) (xy 232.452446 -221.355813)
			(xy 232.415695 -221.319062) (xy 232.385145 -221.277014) (xy 232.361549 -221.230704) (xy 232.345488 -221.181274)
			(xy 232.337358 -221.129939) (xy 232.197654 -221.129939) (xy 232.189524 -221.181274) (xy 232.173463 -221.230704)
			(xy 232.149867 -221.277014) (xy 232.119317 -221.319062) (xy 232.082566 -221.355813) (xy 232.040518 -221.386363)
			(xy 231.994208 -221.409959) (xy 231.944778 -221.42602) (xy 231.893443 -221.43415) (xy 231.841469 -221.43415)
			(xy 231.790134 -221.42602) (xy 231.740704 -221.409959) (xy 231.694394 -221.386363) (xy 231.652346 -221.355813)
			(xy 231.615595 -221.319062) (xy 231.585045 -221.277014) (xy 231.561449 -221.230704) (xy 231.545388 -221.181274)
			(xy 231.537258 -221.129939) (xy 231.397673 -221.129939) (xy 231.397673 -221.129995) (xy 231.389539 -221.181345)
			(xy 231.373472 -221.230791) (xy 231.349867 -221.277114) (xy 231.319305 -221.319173) (xy 231.28254 -221.355934)
			(xy 231.240476 -221.38649) (xy 231.19415 -221.410088) (xy 231.144703 -221.426149) (xy 231.093351 -221.434276)
			(xy 231.067356 -221.43466) (xy 231.041099 -221.434152) (xy 230.989247 -221.425845) (xy 230.93936 -221.409447)
			(xy 230.892692 -221.38537) (xy 230.850416 -221.35422) (xy 230.831644 -221.335854) (xy 230.820722 -221.324932)
			(xy 230.790496 -221.318582) (xy 230.68915 -221.360238) (xy 230.680028 -221.364454) (xy 230.665815 -221.378638)
			(xy 230.658126 -221.397188) (xy 230.657654 -221.407228) (xy 230.657654 -221.600776) (xy 230.658073 -221.610826)
			(xy 230.665771 -221.629394) (xy 230.68 -221.643592) (xy 230.68915 -221.647766) (xy 230.790496 -221.689422)
			(xy 230.820722 -221.683072) (xy 230.831644 -221.67215) (xy 230.850409 -221.653776) (xy 230.892679 -221.622614)
			(xy 230.939349 -221.598535) (xy 230.989241 -221.582145) (xy 231.041098 -221.573859) (xy 231.067356 -221.573344)
			(xy 231.093351 -221.573824) (xy 231.144703 -221.581951) (xy 231.19415 -221.598012) (xy 231.240476 -221.62161)
			(xy 231.28254 -221.652166) (xy 231.319305 -221.688927) (xy 231.349867 -221.730986) (xy 231.373472 -221.777309)
			(xy 231.389539 -221.826755) (xy 231.397673 -221.878105) (xy 231.397673 -221.930039) (xy 231.537258 -221.930039)
			(xy 231.537258 -221.878065) (xy 231.545388 -221.82673) (xy 231.561449 -221.7773) (xy 231.585045 -221.73099)
			(xy 231.615595 -221.688942) (xy 231.652346 -221.652191) (xy 231.694394 -221.621641) (xy 231.740704 -221.598045)
			(xy 231.790134 -221.581984) (xy 231.841469 -221.573854) (xy 231.893443 -221.573854) (xy 231.944778 -221.581984)
			(xy 231.994208 -221.598045) (xy 232.040518 -221.621641) (xy 232.082566 -221.652191) (xy 232.119317 -221.688942)
			(xy 232.149867 -221.73099) (xy 232.173463 -221.7773) (xy 232.189524 -221.82673) (xy 232.197654 -221.878065)
			(xy 232.198164 -221.904052) (xy 232.197654 -221.930039) (xy 232.337358 -221.930039) (xy 232.337358 -221.878065)
			(xy 232.345488 -221.82673) (xy 232.361549 -221.7773) (xy 232.385145 -221.73099) (xy 232.415695 -221.688942)
			(xy 232.452446 -221.652191) (xy 232.494494 -221.621641) (xy 232.540804 -221.598045) (xy 232.590234 -221.581984)
			(xy 232.641569 -221.573854) (xy 232.693543 -221.573854) (xy 232.744878 -221.581984) (xy 232.794308 -221.598045)
			(xy 232.840618 -221.621641) (xy 232.882666 -221.652191) (xy 232.919417 -221.688942) (xy 232.949967 -221.73099)
			(xy 232.973563 -221.7773) (xy 232.989624 -221.82673) (xy 232.997754 -221.878065) (xy 232.998264 -221.904052)
			(xy 232.997754 -221.930039) (xy 233.137204 -221.930039) (xy 233.137204 -221.878065) (xy 233.145334 -221.82673)
			(xy 233.161395 -221.7773) (xy 233.184991 -221.73099) (xy 233.215541 -221.688942) (xy 233.252292 -221.652191)
			(xy 233.29434 -221.621641) (xy 233.34065 -221.598045) (xy 233.39008 -221.581984) (xy 233.441415 -221.573854)
			(xy 233.493389 -221.573854) (xy 233.544724 -221.581984) (xy 233.594154 -221.598045) (xy 233.640464 -221.621641)
			(xy 233.682512 -221.652191) (xy 233.719263 -221.688942) (xy 233.749813 -221.73099) (xy 233.773409 -221.7773)
			(xy 233.78947 -221.82673) (xy 233.7976 -221.878065) (xy 233.79811 -221.904052) (xy 233.7976 -221.930039)
			(xy 233.937304 -221.930039) (xy 233.937304 -221.878065) (xy 233.945434 -221.82673) (xy 233.961495 -221.7773)
			(xy 233.985091 -221.73099) (xy 234.015641 -221.688942) (xy 234.052392 -221.652191) (xy 234.09444 -221.621641)
			(xy 234.14075 -221.598045) (xy 234.19018 -221.581984) (xy 234.241515 -221.573854) (xy 234.293489 -221.573854)
			(xy 234.344824 -221.581984) (xy 234.394254 -221.598045) (xy 234.440564 -221.621641) (xy 234.482612 -221.652191)
			(xy 234.519363 -221.688942) (xy 234.549913 -221.73099) (xy 234.573509 -221.7773) (xy 234.58957 -221.82673)
			(xy 234.5977 -221.878065) (xy 234.59821 -221.904052) (xy 234.5977 -221.930039) (xy 234.73715 -221.930039)
			(xy 234.73715 -221.878065) (xy 234.74528 -221.82673) (xy 234.761341 -221.7773) (xy 234.784937 -221.73099)
			(xy 234.815487 -221.688942) (xy 234.852238 -221.652191) (xy 234.894286 -221.621641) (xy 234.940596 -221.598045)
			(xy 234.990026 -221.581984) (xy 235.041361 -221.573854) (xy 235.093335 -221.573854) (xy 235.14467 -221.581984)
			(xy 235.1941 -221.598045) (xy 235.24041 -221.621641) (xy 235.282458 -221.652191) (xy 235.319209 -221.688942)
			(xy 235.349759 -221.73099) (xy 235.373355 -221.7773) (xy 235.389416 -221.82673) (xy 235.397546 -221.878065)
			(xy 235.398056 -221.904052) (xy 235.397546 -221.930039) (xy 235.53725 -221.930039) (xy 235.53725 -221.878065)
			(xy 235.54538 -221.82673) (xy 235.561441 -221.7773) (xy 235.585037 -221.73099) (xy 235.615587 -221.688942)
			(xy 235.652338 -221.652191) (xy 235.694386 -221.621641) (xy 235.740696 -221.598045) (xy 235.790126 -221.581984)
			(xy 235.841461 -221.573854) (xy 235.893435 -221.573854) (xy 235.94477 -221.581984) (xy 235.9942 -221.598045)
			(xy 236.04051 -221.621641) (xy 236.082558 -221.652191) (xy 236.119309 -221.688942) (xy 236.149859 -221.73099)
			(xy 236.173455 -221.7773) (xy 236.189516 -221.82673) (xy 236.197646 -221.878065) (xy 236.198156 -221.904052)
			(xy 236.197646 -221.930039) (xy 236.189516 -221.981374) (xy 236.173455 -222.030804) (xy 236.149859 -222.077114)
			(xy 236.119309 -222.119162) (xy 236.082558 -222.155913) (xy 236.04051 -222.186463) (xy 235.9942 -222.210059)
			(xy 235.94477 -222.22612) (xy 235.893435 -222.23425) (xy 235.841461 -222.23425) (xy 235.790126 -222.22612)
			(xy 235.740696 -222.210059) (xy 235.694386 -222.186463) (xy 235.652338 -222.155913) (xy 235.615587 -222.119162)
			(xy 235.585037 -222.077114) (xy 235.561441 -222.030804) (xy 235.54538 -221.981374) (xy 235.53725 -221.930039)
			(xy 235.397546 -221.930039) (xy 235.389416 -221.981374) (xy 235.373355 -222.030804) (xy 235.349759 -222.077114)
			(xy 235.319209 -222.119162) (xy 235.282458 -222.155913) (xy 235.24041 -222.186463) (xy 235.1941 -222.210059)
			(xy 235.14467 -222.22612) (xy 235.093335 -222.23425) (xy 235.041361 -222.23425) (xy 234.990026 -222.22612)
			(xy 234.940596 -222.210059) (xy 234.894286 -222.186463) (xy 234.852238 -222.155913) (xy 234.815487 -222.119162)
			(xy 234.784937 -222.077114) (xy 234.761341 -222.030804) (xy 234.74528 -221.981374) (xy 234.73715 -221.930039)
			(xy 234.5977 -221.930039) (xy 234.58957 -221.981374) (xy 234.573509 -222.030804) (xy 234.549913 -222.077114)
			(xy 234.519363 -222.119162) (xy 234.482612 -222.155913) (xy 234.440564 -222.186463) (xy 234.394254 -222.210059)
			(xy 234.344824 -222.22612) (xy 234.293489 -222.23425) (xy 234.241515 -222.23425) (xy 234.19018 -222.22612)
			(xy 234.14075 -222.210059) (xy 234.09444 -222.186463) (xy 234.052392 -222.155913) (xy 234.015641 -222.119162)
			(xy 233.985091 -222.077114) (xy 233.961495 -222.030804) (xy 233.945434 -221.981374) (xy 233.937304 -221.930039)
			(xy 233.7976 -221.930039) (xy 233.78947 -221.981374) (xy 233.773409 -222.030804) (xy 233.749813 -222.077114)
			(xy 233.719263 -222.119162) (xy 233.682512 -222.155913) (xy 233.640464 -222.186463) (xy 233.594154 -222.210059)
			(xy 233.544724 -222.22612) (xy 233.493389 -222.23425) (xy 233.441415 -222.23425) (xy 233.39008 -222.22612)
			(xy 233.34065 -222.210059) (xy 233.29434 -222.186463) (xy 233.252292 -222.155913) (xy 233.215541 -222.119162)
			(xy 233.184991 -222.077114) (xy 233.161395 -222.030804) (xy 233.145334 -221.981374) (xy 233.137204 -221.930039)
			(xy 232.997754 -221.930039) (xy 232.989624 -221.981374) (xy 232.973563 -222.030804) (xy 232.949967 -222.077114)
			(xy 232.919417 -222.119162) (xy 232.882666 -222.155913) (xy 232.840618 -222.186463) (xy 232.794308 -222.210059)
			(xy 232.744878 -222.22612) (xy 232.693543 -222.23425) (xy 232.641569 -222.23425) (xy 232.590234 -222.22612)
			(xy 232.540804 -222.210059) (xy 232.494494 -222.186463) (xy 232.452446 -222.155913) (xy 232.415695 -222.119162)
			(xy 232.385145 -222.077114) (xy 232.361549 -222.030804) (xy 232.345488 -221.981374) (xy 232.337358 -221.930039)
			(xy 232.197654 -221.930039) (xy 232.189524 -221.981374) (xy 232.173463 -222.030804) (xy 232.149867 -222.077114)
			(xy 232.119317 -222.119162) (xy 232.082566 -222.155913) (xy 232.040518 -222.186463) (xy 231.994208 -222.210059)
			(xy 231.944778 -222.22612) (xy 231.893443 -222.23425) (xy 231.841469 -222.23425) (xy 231.790134 -222.22612)
			(xy 231.740704 -222.210059) (xy 231.694394 -222.186463) (xy 231.652346 -222.155913) (xy 231.615595 -222.119162)
			(xy 231.585045 -222.077114) (xy 231.561449 -222.030804) (xy 231.545388 -221.981374) (xy 231.537258 -221.930039)
			(xy 231.397673 -221.930039) (xy 231.397673 -221.930095) (xy 231.389539 -221.981445) (xy 231.373472 -222.030891)
			(xy 231.349867 -222.077214) (xy 231.319305 -222.119273) (xy 231.28254 -222.156034) (xy 231.240476 -222.18659)
			(xy 231.19415 -222.210188) (xy 231.144703 -222.226249) (xy 231.093351 -222.234376) (xy 231.067356 -222.23476)
			(xy 231.041099 -222.234252) (xy 230.989247 -222.225945) (xy 230.93936 -222.209547) (xy 230.892692 -222.18547)
			(xy 230.850416 -222.15432) (xy 230.831644 -222.135954) (xy 230.820722 -222.125032) (xy 230.790496 -222.118682)
			(xy 230.68915 -222.160338) (xy 230.680028 -222.164554) (xy 230.665815 -222.178738) (xy 230.658126 -222.197288)
			(xy 230.657654 -222.207328) (xy 230.657654 -222.400622) (xy 230.658081 -222.410667) (xy 230.665789 -222.429221)
			(xy 230.680019 -222.443404) (xy 230.68915 -222.447612) (xy 230.790496 -222.489268) (xy 230.820722 -222.482918)
			(xy 230.831644 -222.471996) (xy 230.85041 -222.453624) (xy 230.892682 -222.422468) (xy 230.939352 -222.398393)
			(xy 230.989243 -222.382006) (xy 231.041099 -222.373721) (xy 231.067356 -222.37319) (xy 231.093348 -222.37367)
			(xy 231.144692 -222.381796) (xy 231.194133 -222.397854) (xy 231.240452 -222.42145) (xy 231.28251 -222.452001)
			(xy 231.31927 -222.488757) (xy 231.349827 -222.53081) (xy 231.373429 -222.577127) (xy 231.389494 -222.626565)
			(xy 231.397627 -222.677908) (xy 231.397627 -222.729885) (xy 231.537258 -222.729885) (xy 231.537258 -222.677911)
			(xy 231.545388 -222.626576) (xy 231.561449 -222.577146) (xy 231.585045 -222.530836) (xy 231.615595 -222.488788)
			(xy 231.652346 -222.452037) (xy 231.694394 -222.421487) (xy 231.740704 -222.397891) (xy 231.790134 -222.38183)
			(xy 231.841469 -222.3737) (xy 231.893443 -222.3737) (xy 231.944778 -222.38183) (xy 231.994208 -222.397891)
			(xy 232.040518 -222.421487) (xy 232.082566 -222.452037) (xy 232.119317 -222.488788) (xy 232.149867 -222.530836)
			(xy 232.173463 -222.577146) (xy 232.189524 -222.626576) (xy 232.197654 -222.677911) (xy 232.198164 -222.703898)
			(xy 232.197654 -222.729885) (xy 232.337358 -222.729885) (xy 232.337358 -222.677911) (xy 232.345488 -222.626576)
			(xy 232.361549 -222.577146) (xy 232.385145 -222.530836) (xy 232.415695 -222.488788) (xy 232.452446 -222.452037)
			(xy 232.494494 -222.421487) (xy 232.540804 -222.397891) (xy 232.590234 -222.38183) (xy 232.641569 -222.3737)
			(xy 232.693543 -222.3737) (xy 232.744878 -222.38183) (xy 232.794308 -222.397891) (xy 232.840618 -222.421487)
			(xy 232.882666 -222.452037) (xy 232.919417 -222.488788) (xy 232.949967 -222.530836) (xy 232.973563 -222.577146)
			(xy 232.989624 -222.626576) (xy 232.997754 -222.677911) (xy 232.998264 -222.703898) (xy 232.997754 -222.729885)
			(xy 233.137204 -222.729885) (xy 233.137204 -222.677911) (xy 233.145334 -222.626576) (xy 233.161395 -222.577146)
			(xy 233.184991 -222.530836) (xy 233.215541 -222.488788) (xy 233.252292 -222.452037) (xy 233.29434 -222.421487)
			(xy 233.34065 -222.397891) (xy 233.39008 -222.38183) (xy 233.441415 -222.3737) (xy 233.493389 -222.3737)
			(xy 233.544724 -222.38183) (xy 233.594154 -222.397891) (xy 233.640464 -222.421487) (xy 233.682512 -222.452037)
			(xy 233.719263 -222.488788) (xy 233.749813 -222.530836) (xy 233.773409 -222.577146) (xy 233.78947 -222.626576)
			(xy 233.7976 -222.677911) (xy 233.79811 -222.703898) (xy 233.7976 -222.729885) (xy 233.937304 -222.729885)
			(xy 233.937304 -222.677911) (xy 233.945434 -222.626576) (xy 233.961495 -222.577146) (xy 233.985091 -222.530836)
			(xy 234.015641 -222.488788) (xy 234.052392 -222.452037) (xy 234.09444 -222.421487) (xy 234.14075 -222.397891)
			(xy 234.19018 -222.38183) (xy 234.241515 -222.3737) (xy 234.293489 -222.3737) (xy 234.344824 -222.38183)
			(xy 234.394254 -222.397891) (xy 234.440564 -222.421487) (xy 234.482612 -222.452037) (xy 234.519363 -222.488788)
			(xy 234.549913 -222.530836) (xy 234.573509 -222.577146) (xy 234.58957 -222.626576) (xy 234.5977 -222.677911)
			(xy 234.59821 -222.703898) (xy 234.5977 -222.729885) (xy 234.73715 -222.729885) (xy 234.73715 -222.677911)
			(xy 234.74528 -222.626576) (xy 234.761341 -222.577146) (xy 234.784937 -222.530836) (xy 234.815487 -222.488788)
			(xy 234.852238 -222.452037) (xy 234.894286 -222.421487) (xy 234.940596 -222.397891) (xy 234.990026 -222.38183)
			(xy 235.041361 -222.3737) (xy 235.093335 -222.3737) (xy 235.14467 -222.38183) (xy 235.1941 -222.397891)
			(xy 235.24041 -222.421487) (xy 235.282458 -222.452037) (xy 235.319209 -222.488788) (xy 235.349759 -222.530836)
			(xy 235.373355 -222.577146) (xy 235.389416 -222.626576) (xy 235.397546 -222.677911) (xy 235.398056 -222.703898)
			(xy 235.397546 -222.729885) (xy 235.53725 -222.729885) (xy 235.53725 -222.677911) (xy 235.54538 -222.626576)
			(xy 235.561441 -222.577146) (xy 235.585037 -222.530836) (xy 235.615587 -222.488788) (xy 235.652338 -222.452037)
			(xy 235.694386 -222.421487) (xy 235.740696 -222.397891) (xy 235.790126 -222.38183) (xy 235.841461 -222.3737)
			(xy 235.893435 -222.3737) (xy 235.94477 -222.38183) (xy 235.9942 -222.397891) (xy 236.04051 -222.421487)
			(xy 236.082558 -222.452037) (xy 236.119309 -222.488788) (xy 236.149859 -222.530836) (xy 236.173455 -222.577146)
			(xy 236.189516 -222.626576) (xy 236.197646 -222.677911) (xy 236.198156 -222.703898) (xy 236.197646 -222.729885)
			(xy 236.189516 -222.78122) (xy 236.173455 -222.83065) (xy 236.149859 -222.87696) (xy 236.119309 -222.919008)
			(xy 236.082558 -222.955759) (xy 236.04051 -222.986309) (xy 235.9942 -223.009905) (xy 235.94477 -223.025966)
			(xy 235.893435 -223.034096) (xy 235.841461 -223.034096) (xy 235.790126 -223.025966) (xy 235.740696 -223.009905)
			(xy 235.694386 -222.986309) (xy 235.652338 -222.955759) (xy 235.615587 -222.919008) (xy 235.585037 -222.87696)
			(xy 235.561441 -222.83065) (xy 235.54538 -222.78122) (xy 235.53725 -222.729885) (xy 235.397546 -222.729885)
			(xy 235.389416 -222.78122) (xy 235.373355 -222.83065) (xy 235.349759 -222.87696) (xy 235.319209 -222.919008)
			(xy 235.282458 -222.955759) (xy 235.24041 -222.986309) (xy 235.1941 -223.009905) (xy 235.14467 -223.025966)
			(xy 235.093335 -223.034096) (xy 235.041361 -223.034096) (xy 234.990026 -223.025966) (xy 234.940596 -223.009905)
			(xy 234.894286 -222.986309) (xy 234.852238 -222.955759) (xy 234.815487 -222.919008) (xy 234.784937 -222.87696)
			(xy 234.761341 -222.83065) (xy 234.74528 -222.78122) (xy 234.73715 -222.729885) (xy 234.5977 -222.729885)
			(xy 234.58957 -222.78122) (xy 234.573509 -222.83065) (xy 234.549913 -222.87696) (xy 234.519363 -222.919008)
			(xy 234.482612 -222.955759) (xy 234.440564 -222.986309) (xy 234.394254 -223.009905) (xy 234.344824 -223.025966)
			(xy 234.293489 -223.034096) (xy 234.241515 -223.034096) (xy 234.19018 -223.025966) (xy 234.14075 -223.009905)
			(xy 234.09444 -222.986309) (xy 234.052392 -222.955759) (xy 234.015641 -222.919008) (xy 233.985091 -222.87696)
			(xy 233.961495 -222.83065) (xy 233.945434 -222.78122) (xy 233.937304 -222.729885) (xy 233.7976 -222.729885)
			(xy 233.78947 -222.78122) (xy 233.773409 -222.83065) (xy 233.749813 -222.87696) (xy 233.719263 -222.919008)
			(xy 233.682512 -222.955759) (xy 233.640464 -222.986309) (xy 233.594154 -223.009905) (xy 233.544724 -223.025966)
			(xy 233.493389 -223.034096) (xy 233.441415 -223.034096) (xy 233.39008 -223.025966) (xy 233.34065 -223.009905)
			(xy 233.29434 -222.986309) (xy 233.252292 -222.955759) (xy 233.215541 -222.919008) (xy 233.184991 -222.87696)
			(xy 233.161395 -222.83065) (xy 233.145334 -222.78122) (xy 233.137204 -222.729885) (xy 232.997754 -222.729885)
			(xy 232.989624 -222.78122) (xy 232.973563 -222.83065) (xy 232.949967 -222.87696) (xy 232.919417 -222.919008)
			(xy 232.882666 -222.955759) (xy 232.840618 -222.986309) (xy 232.794308 -223.009905) (xy 232.744878 -223.025966)
			(xy 232.693543 -223.034096) (xy 232.641569 -223.034096) (xy 232.590234 -223.025966) (xy 232.540804 -223.009905)
			(xy 232.494494 -222.986309) (xy 232.452446 -222.955759) (xy 232.415695 -222.919008) (xy 232.385145 -222.87696)
			(xy 232.361549 -222.83065) (xy 232.345488 -222.78122) (xy 232.337358 -222.729885) (xy 232.197654 -222.729885)
			(xy 232.189524 -222.78122) (xy 232.173463 -222.83065) (xy 232.149867 -222.87696) (xy 232.119317 -222.919008)
			(xy 232.082566 -222.955759) (xy 232.040518 -222.986309) (xy 231.994208 -223.009905) (xy 231.944778 -223.025966)
			(xy 231.893443 -223.034096) (xy 231.841469 -223.034096) (xy 231.790134 -223.025966) (xy 231.740704 -223.009905)
			(xy 231.694394 -222.986309) (xy 231.652346 -222.955759) (xy 231.615595 -222.919008) (xy 231.585045 -222.87696)
			(xy 231.561449 -222.83065) (xy 231.545388 -222.78122) (xy 231.537258 -222.729885) (xy 231.397627 -222.729885)
			(xy 231.397627 -222.729892) (xy 231.389494 -222.781235) (xy 231.373429 -222.830673) (xy 231.349827 -222.87699)
			(xy 231.31927 -222.919043) (xy 231.28251 -222.955799) (xy 231.240452 -222.98635) (xy 231.194133 -223.009946)
			(xy 231.144692 -223.026004) (xy 231.093348 -223.03413) (xy 231.067356 -223.034606) (xy 231.041099 -223.034098)
			(xy 230.989246 -223.025792) (xy 230.939358 -223.009396) (xy 230.892687 -222.985321) (xy 230.850408 -222.954174)
			(xy 230.831644 -222.9358) (xy 230.820722 -222.924878) (xy 230.790496 -222.918528) (xy 230.68915 -222.960184)
			(xy 230.680022 -222.964398) (xy 230.665794 -222.978579) (xy 230.658086 -222.99713) (xy 230.657654 -223.007174)
			(xy 230.657654 -223.200722) (xy 230.658081 -223.210767) (xy 230.665789 -223.229321) (xy 230.680019 -223.243504)
			(xy 230.68915 -223.247712) (xy 230.790496 -223.289368) (xy 230.820722 -223.283018) (xy 230.831644 -223.272096)
			(xy 230.85041 -223.253724) (xy 230.892682 -223.222568) (xy 230.939352 -223.198493) (xy 230.989243 -223.182106)
			(xy 231.041099 -223.173821) (xy 231.067356 -223.17329) (xy 231.093348 -223.17377) (xy 231.144692 -223.181896)
			(xy 231.194133 -223.197954) (xy 231.240452 -223.22155) (xy 231.28251 -223.252101) (xy 231.31927 -223.288857)
			(xy 231.349827 -223.33091) (xy 231.373429 -223.377227) (xy 231.389494 -223.426665) (xy 231.397627 -223.478008)
			(xy 231.397627 -223.529985) (xy 231.537258 -223.529985) (xy 231.537258 -223.478011) (xy 231.545388 -223.426676)
			(xy 231.561449 -223.377246) (xy 231.585045 -223.330936) (xy 231.615595 -223.288888) (xy 231.652346 -223.252137)
			(xy 231.694394 -223.221587) (xy 231.740704 -223.197991) (xy 231.790134 -223.18193) (xy 231.841469 -223.1738)
			(xy 231.893443 -223.1738) (xy 231.944778 -223.18193) (xy 231.994208 -223.197991) (xy 232.040518 -223.221587)
			(xy 232.082566 -223.252137) (xy 232.119317 -223.288888) (xy 232.149867 -223.330936) (xy 232.173463 -223.377246)
			(xy 232.189524 -223.426676) (xy 232.197654 -223.478011) (xy 232.198164 -223.503998) (xy 232.197654 -223.529985)
			(xy 232.337358 -223.529985) (xy 232.337358 -223.478011) (xy 232.345488 -223.426676) (xy 232.361549 -223.377246)
			(xy 232.385145 -223.330936) (xy 232.415695 -223.288888) (xy 232.452446 -223.252137) (xy 232.494494 -223.221587)
			(xy 232.540804 -223.197991) (xy 232.590234 -223.18193) (xy 232.641569 -223.1738) (xy 232.693543 -223.1738)
			(xy 232.744878 -223.18193) (xy 232.794308 -223.197991) (xy 232.840618 -223.221587) (xy 232.882666 -223.252137)
			(xy 232.919417 -223.288888) (xy 232.949967 -223.330936) (xy 232.973563 -223.377246) (xy 232.989624 -223.426676)
			(xy 232.997754 -223.478011) (xy 232.998264 -223.503998) (xy 232.997754 -223.529985) (xy 233.137204 -223.529985)
			(xy 233.137204 -223.478011) (xy 233.145334 -223.426676) (xy 233.161395 -223.377246) (xy 233.184991 -223.330936)
			(xy 233.215541 -223.288888) (xy 233.252292 -223.252137) (xy 233.29434 -223.221587) (xy 233.34065 -223.197991)
			(xy 233.39008 -223.18193) (xy 233.441415 -223.1738) (xy 233.493389 -223.1738) (xy 233.544724 -223.18193)
			(xy 233.594154 -223.197991) (xy 233.640464 -223.221587) (xy 233.682512 -223.252137) (xy 233.719263 -223.288888)
			(xy 233.749813 -223.330936) (xy 233.773409 -223.377246) (xy 233.78947 -223.426676) (xy 233.7976 -223.478011)
			(xy 233.79811 -223.503998) (xy 233.7976 -223.529985) (xy 233.937304 -223.529985) (xy 233.937304 -223.478011)
			(xy 233.945434 -223.426676) (xy 233.961495 -223.377246) (xy 233.985091 -223.330936) (xy 234.015641 -223.288888)
			(xy 234.052392 -223.252137) (xy 234.09444 -223.221587) (xy 234.14075 -223.197991) (xy 234.19018 -223.18193)
			(xy 234.241515 -223.1738) (xy 234.293489 -223.1738) (xy 234.344824 -223.18193) (xy 234.394254 -223.197991)
			(xy 234.440564 -223.221587) (xy 234.482612 -223.252137) (xy 234.519363 -223.288888) (xy 234.549913 -223.330936)
			(xy 234.573509 -223.377246) (xy 234.58957 -223.426676) (xy 234.5977 -223.478011) (xy 234.59821 -223.503998)
			(xy 234.5977 -223.529985) (xy 234.73715 -223.529985) (xy 234.73715 -223.478011) (xy 234.74528 -223.426676)
			(xy 234.761341 -223.377246) (xy 234.784937 -223.330936) (xy 234.815487 -223.288888) (xy 234.852238 -223.252137)
			(xy 234.894286 -223.221587) (xy 234.940596 -223.197991) (xy 234.990026 -223.18193) (xy 235.041361 -223.1738)
			(xy 235.093335 -223.1738) (xy 235.14467 -223.18193) (xy 235.1941 -223.197991) (xy 235.24041 -223.221587)
			(xy 235.282458 -223.252137) (xy 235.319209 -223.288888) (xy 235.349759 -223.330936) (xy 235.373355 -223.377246)
			(xy 235.389416 -223.426676) (xy 235.397546 -223.478011) (xy 235.398056 -223.503998) (xy 235.397546 -223.529985)
			(xy 235.389416 -223.58132) (xy 235.373355 -223.63075) (xy 235.349759 -223.67706) (xy 235.319209 -223.719108)
			(xy 235.282458 -223.755859) (xy 235.24041 -223.786409) (xy 235.1941 -223.810005) (xy 235.14467 -223.826066)
			(xy 235.093335 -223.834196) (xy 235.041361 -223.834196) (xy 234.990026 -223.826066) (xy 234.940596 -223.810005)
			(xy 234.894286 -223.786409) (xy 234.852238 -223.755859) (xy 234.815487 -223.719108) (xy 234.784937 -223.67706)
			(xy 234.761341 -223.63075) (xy 234.74528 -223.58132) (xy 234.73715 -223.529985) (xy 234.5977 -223.529985)
			(xy 234.58957 -223.58132) (xy 234.573509 -223.63075) (xy 234.549913 -223.67706) (xy 234.519363 -223.719108)
			(xy 234.482612 -223.755859) (xy 234.440564 -223.786409) (xy 234.394254 -223.810005) (xy 234.344824 -223.826066)
			(xy 234.293489 -223.834196) (xy 234.241515 -223.834196) (xy 234.19018 -223.826066) (xy 234.14075 -223.810005)
			(xy 234.09444 -223.786409) (xy 234.052392 -223.755859) (xy 234.015641 -223.719108) (xy 233.985091 -223.67706)
			(xy 233.961495 -223.63075) (xy 233.945434 -223.58132) (xy 233.937304 -223.529985) (xy 233.7976 -223.529985)
			(xy 233.78947 -223.58132) (xy 233.773409 -223.63075) (xy 233.749813 -223.67706) (xy 233.719263 -223.719108)
			(xy 233.682512 -223.755859) (xy 233.640464 -223.786409) (xy 233.594154 -223.810005) (xy 233.544724 -223.826066)
			(xy 233.493389 -223.834196) (xy 233.441415 -223.834196) (xy 233.39008 -223.826066) (xy 233.34065 -223.810005)
			(xy 233.29434 -223.786409) (xy 233.252292 -223.755859) (xy 233.215541 -223.719108) (xy 233.184991 -223.67706)
			(xy 233.161395 -223.63075) (xy 233.145334 -223.58132) (xy 233.137204 -223.529985) (xy 232.997754 -223.529985)
			(xy 232.989624 -223.58132) (xy 232.973563 -223.63075) (xy 232.949967 -223.67706) (xy 232.919417 -223.719108)
			(xy 232.882666 -223.755859) (xy 232.840618 -223.786409) (xy 232.794308 -223.810005) (xy 232.744878 -223.826066)
			(xy 232.693543 -223.834196) (xy 232.641569 -223.834196) (xy 232.590234 -223.826066) (xy 232.540804 -223.810005)
			(xy 232.494494 -223.786409) (xy 232.452446 -223.755859) (xy 232.415695 -223.719108) (xy 232.385145 -223.67706)
			(xy 232.361549 -223.63075) (xy 232.345488 -223.58132) (xy 232.337358 -223.529985) (xy 232.197654 -223.529985)
			(xy 232.189524 -223.58132) (xy 232.173463 -223.63075) (xy 232.149867 -223.67706) (xy 232.119317 -223.719108)
			(xy 232.082566 -223.755859) (xy 232.040518 -223.786409) (xy 231.994208 -223.810005) (xy 231.944778 -223.826066)
			(xy 231.893443 -223.834196) (xy 231.841469 -223.834196) (xy 231.790134 -223.826066) (xy 231.740704 -223.810005)
			(xy 231.694394 -223.786409) (xy 231.652346 -223.755859) (xy 231.615595 -223.719108) (xy 231.585045 -223.67706)
			(xy 231.561449 -223.63075) (xy 231.545388 -223.58132) (xy 231.537258 -223.529985) (xy 231.397627 -223.529985)
			(xy 231.397627 -223.529992) (xy 231.389494 -223.581335) (xy 231.373429 -223.630773) (xy 231.349827 -223.67709)
			(xy 231.31927 -223.719143) (xy 231.28251 -223.755899) (xy 231.240452 -223.78645) (xy 231.194133 -223.810046)
			(xy 231.144692 -223.826104) (xy 231.093348 -223.83423) (xy 231.067356 -223.834706) (xy 231.041099 -223.834198)
			(xy 230.989246 -223.825892) (xy 230.939358 -223.809496) (xy 230.892687 -223.785421) (xy 230.850408 -223.754274)
			(xy 230.831644 -223.7359) (xy 230.820722 -223.724978) (xy 230.790496 -223.718628) (xy 230.68915 -223.760284)
			(xy 230.680022 -223.764498) (xy 230.665794 -223.778679) (xy 230.658086 -223.79723) (xy 230.657654 -223.807274)
			(xy 230.657654 -223.891348) (xy 230.658087 -223.901413) (xy 230.66582 -223.92) (xy 230.67264 -223.927416)
			(xy 231.056942 -224.311718) (xy 231.064339 -224.318567) (xy 231.082938 -224.326299) (xy 231.09301 -224.326704)
			(xy 233.106976 -224.326704)
		)
		(stroke
			(width 0)
			(type solid)
		)
		(fill yes)
		(layer "In15.Cu")
		(net "P3V3_BIC_ADCAV33")
	)
	(gr_poly
		(pts
			(xy 434.20284 -291.423598) (xy 434.213949 -291.423037) (xy 434.234104 -291.413687) (xy 434.241702 -291.405564)
			(xy 434.299106 -291.337238) (xy 434.304694 -291.315902) (xy 434.302916 -291.304472) (xy 434.300204 -291.28816)
			(xy 434.297276 -291.25522) (xy 434.297074 -291.238686) (xy 434.29756 -291.211435) (xy 434.305316 -291.157487)
			(xy 434.320671 -291.105192) (xy 434.343313 -291.055615) (xy 434.372779 -291.009765) (xy 434.40847 -290.968574)
			(xy 434.449661 -290.932883) (xy 434.495511 -290.903417) (xy 434.545088 -290.880775) (xy 434.597383 -290.86542)
			(xy 434.651331 -290.857664) (xy 434.705833 -290.857664) (xy 434.759781 -290.86542) (xy 434.812076 -290.880775)
			(xy 434.861653 -290.903417) (xy 434.907503 -290.932883) (xy 434.948694 -290.968574) (xy 434.984385 -291.009765)
			(xy 435.013851 -291.055615) (xy 435.036493 -291.105192) (xy 435.051848 -291.157487) (xy 435.059604 -291.211435)
			(xy 435.06009 -291.238686) (xy 435.059881 -291.25522) (xy 435.056957 -291.28816) (xy 435.054248 -291.304472)
			(xy 435.05247 -291.315902) (xy 435.058058 -291.337238) (xy 435.115462 -291.405564) (xy 435.123055 -291.413692)
			(xy 435.143214 -291.423033) (xy 435.154324 -291.423598) (xy 436.751222 -291.423598) (xy 436.76003 -291.423177)
			(xy 436.776582 -291.417132) (xy 436.790126 -291.405859) (xy 436.79491 -291.398452) (xy 436.810461 -291.373135)
			(xy 436.848161 -291.327218) (xy 436.892525 -291.287703) (xy 436.942482 -291.255546) (xy 436.996821 -291.231526)
			(xy 437.054228 -291.216223) (xy 437.083708 -291.212524) (xy 437.092344 -291.211762) (xy 437.108092 -291.204142)
			(xy 437.621934 -290.6903) (xy 437.629099 -290.682279) (xy 437.636714 -290.662193) (xy 437.636666 -290.651438)
			(xy 437.631078 -290.564316) (xy 437.620918 -290.545012) (xy 437.612282 -290.538408) (xy 437.589769 -290.520206)
			(xy 437.549975 -290.478159) (xy 437.516982 -290.430588) (xy 437.491546 -290.378583) (xy 437.47425 -290.323335)
			(xy 437.465489 -290.26611) (xy 437.464962 -290.237164) (xy 437.46545 -290.209914) (xy 437.473211 -290.155968)
			(xy 437.488569 -290.103676) (xy 437.511211 -290.054101) (xy 437.540678 -290.008253) (xy 437.576369 -289.967065)
			(xy 437.617558 -289.931375) (xy 437.663407 -289.901909) (xy 437.712982 -289.879267) (xy 437.765274 -289.863909)
			(xy 437.81922 -289.85615) (xy 437.84647 -289.855656) (xy 437.875417 -289.85619) (xy 437.932646 -289.864932)
			(xy 437.987899 -289.88222) (xy 438.039905 -289.907656) (xy 438.087471 -289.940657) (xy 438.129506 -289.980466)
			(xy 438.147714 -290.002976) (xy 438.154318 -290.011612) (xy 438.173622 -290.021772) (xy 438.260744 -290.02736)
			(xy 438.271515 -290.027518) (xy 438.291635 -290.019876) (xy 438.299606 -290.012628) (xy 439.217308 -289.094926)
			(xy 439.224706 -289.088078) (xy 439.243304 -289.080342) (xy 439.253376 -289.07994) (xy 442.666882 -289.07994)
			(xy 442.676944 -289.0795) (xy 442.695521 -289.071758) (xy 442.70295 -289.064954) (xy 448.234308 -283.533596)
			(xy 448.241153 -283.526197) (xy 448.248885 -283.507599) (xy 448.249294 -283.497528) (xy 448.249294 -280.30043)
			(xy 448.22364 -280.271728) (xy 448.204082 -280.269442) (xy 448.176373 -280.265963) (xy 448.122316 -280.25194)
			(xy 448.070882 -280.230186) (xy 448.02317 -280.201164) (xy 447.980199 -280.165496) (xy 447.942888 -280.123943)
			(xy 447.912035 -280.077394) (xy 447.888299 -280.026844) (xy 447.872187 -279.973373) (xy 447.864044 -279.918125)
			(xy 447.864044 -279.862279) (xy 447.872186 -279.807031) (xy 447.888298 -279.75356) (xy 447.912033 -279.703009)
			(xy 447.942886 -279.65646) (xy 447.980196 -279.614907) (xy 448.023166 -279.579238) (xy 448.070878 -279.550216)
			(xy 448.122312 -279.528461) (xy 448.176368 -279.514438) (xy 448.204082 -279.510998) (xy 448.22364 -279.508712)
			(xy 448.249294 -279.48001) (xy 448.249294 -279.271476) (xy 448.22364 -279.242774) (xy 448.204082 -279.240488)
			(xy 448.176377 -279.237008) (xy 448.122328 -279.222987) (xy 448.070902 -279.201235) (xy 448.023197 -279.172217)
			(xy 447.980233 -279.136553) (xy 447.942928 -279.095005) (xy 447.91208 -279.048463) (xy 447.888348 -278.997919)
			(xy 447.872239 -278.944456) (xy 447.864098 -278.889215) (xy 447.864098 -278.833378) (xy 447.87224 -278.778137)
			(xy 447.88835 -278.724674) (xy 447.912083 -278.674131) (xy 447.942932 -278.627589) (xy 447.980238 -278.586042)
			(xy 448.023203 -278.550379) (xy 448.070908 -278.521362) (xy 448.122335 -278.499611) (xy 448.176384 -278.48559)
			(xy 448.204082 -278.482044) (xy 448.22364 -278.479758) (xy 448.249294 -278.451056) (xy 448.249294 -259.348732)
			(xy 448.249729 -259.338667) (xy 448.25746 -259.32008) (xy 448.26428 -259.312664) (xy 449.902834 -257.67411)
			(xy 449.910234 -257.667268) (xy 449.928832 -257.659544) (xy 449.938902 -257.659124) (xy 459.929484 -257.659124)
			(xy 459.939547 -257.659563) (xy 459.958127 -257.667302) (xy 459.965552 -257.67411) (xy 461.18399 -258.892548)
			(xy 461.19083 -258.899949) (xy 461.198549 -258.918547) (xy 461.198976 -258.928616) (xy 461.198976 -274.61083)
			(xy 463.093306 -274.61083) (xy 463.097377 -274.555208) (xy 463.109503 -274.500771) (xy 463.129426 -274.44868)
			(xy 463.156722 -274.400045) (xy 463.190808 -274.355902) (xy 463.230957 -274.317193) (xy 463.276315 -274.284742)
			(xy 463.325915 -274.259241) (xy 463.378699 -274.241234) (xy 463.433542 -274.231104) (xy 463.489276 -274.229067)
			(xy 463.544713 -274.235167) (xy 463.59867 -274.249273) (xy 463.649999 -274.271085) (xy 463.697605 -274.300139)
			(xy 463.740473 -274.335814) (xy 463.77769 -274.377351) (xy 463.808463 -274.423864) (xy 463.832135 -274.474361)
			(xy 463.848203 -274.527768) (xy 463.856323 -274.582944) (xy 463.856832 -274.61083) (xy 463.856323 -274.638716)
			(xy 463.848203 -274.693892) (xy 463.832135 -274.747299) (xy 463.808463 -274.797796) (xy 463.77769 -274.844309)
			(xy 463.740473 -274.885846) (xy 463.697605 -274.921521) (xy 463.649999 -274.950575) (xy 463.59867 -274.972387)
			(xy 463.544713 -274.986493) (xy 463.489276 -274.992593) (xy 463.433542 -274.990556) (xy 463.378699 -274.980426)
			(xy 463.325915 -274.962419) (xy 463.276315 -274.936918) (xy 463.230957 -274.904467) (xy 463.190808 -274.865758)
			(xy 463.156722 -274.821615) (xy 463.129426 -274.77298) (xy 463.109503 -274.720889) (xy 463.097377 -274.666452)
			(xy 463.093306 -274.61083) (xy 461.198976 -274.61083) (xy 461.198976 -274.84578) (xy 461.199467 -274.856111)
			(xy 461.207605 -274.875105) (xy 461.214724 -274.88261) (xy 461.275684 -274.940522) (xy 461.294988 -274.947888)
			(xy 461.305402 -274.94738) (xy 461.32369 -274.946872) (xy 461.350945 -274.947334) (xy 461.4049 -274.95509)
			(xy 461.457202 -274.970446) (xy 461.506786 -274.99309) (xy 461.552642 -275.022559) (xy 461.593838 -275.058254)
			(xy 461.629535 -275.09945) (xy 461.659006 -275.145306) (xy 461.68165 -275.194889) (xy 461.697007 -275.247191)
			(xy 461.704765 -275.301145) (xy 461.704765 -275.355655) (xy 461.697007 -275.409609) (xy 461.68165 -275.461911)
			(xy 461.659006 -275.511494) (xy 461.629535 -275.55735) (xy 461.593838 -275.598546) (xy 461.552642 -275.634241)
			(xy 461.506786 -275.66371) (xy 461.457202 -275.686354) (xy 461.4049 -275.70171) (xy 461.350945 -275.709466)
			(xy 461.32369 -275.709888) (xy 461.307288 -275.709729) (xy 461.274603 -275.706931) (xy 461.258412 -275.7043)
			(xy 461.254094 -275.703538) (xy 461.249776 -275.703538) (xy 461.239761 -275.703962) (xy 461.221259 -275.711638)
			(xy 461.207103 -275.725811) (xy 461.19945 -275.744322) (xy 461.198976 -275.754338) (xy 461.198976 -275.758656)
			(xy 461.191356 -275.777198) (xy 461.13446 -275.834094) (xy 461.127606 -275.841489) (xy 461.11986 -275.860088)
			(xy 461.119474 -275.870162) (xy 461.119474 -276.220682) (xy 461.11986 -276.229534) (xy 461.12588 -276.246183)
			(xy 461.137181 -276.259812) (xy 461.14462 -276.264624) (xy 461.231742 -276.315678) (xy 461.258666 -276.316186)
			(xy 461.27035 -276.309582) (xy 461.291714 -276.298102) (xy 461.336726 -276.280045) (xy 461.383666 -276.267843)
			(xy 461.431774 -276.261695) (xy 461.456024 -276.261322) (xy 461.483272 -276.26181) (xy 461.537213 -276.269569)
			(xy 461.5895 -276.284924) (xy 461.639071 -276.307565) (xy 461.684914 -276.33703) (xy 461.726099 -276.372718)
			(xy 461.761785 -276.413905) (xy 461.791246 -276.45975) (xy 461.813884 -276.509322) (xy 461.829237 -276.561611)
			(xy 461.836992 -276.615552) (xy 461.836992 -276.64283) (xy 463.093306 -276.64283) (xy 463.097377 -276.587208)
			(xy 463.109503 -276.532771) (xy 463.129426 -276.48068) (xy 463.156722 -276.432045) (xy 463.190808 -276.387902)
			(xy 463.230957 -276.349193) (xy 463.276315 -276.316742) (xy 463.325915 -276.291241) (xy 463.378699 -276.273234)
			(xy 463.433542 -276.263104) (xy 463.489276 -276.261067) (xy 463.544713 -276.267167) (xy 463.59867 -276.281273)
			(xy 463.649999 -276.303085) (xy 463.697605 -276.332139) (xy 463.740473 -276.367814) (xy 463.77769 -276.409351)
			(xy 463.808463 -276.455864) (xy 463.832135 -276.506361) (xy 463.848203 -276.559768) (xy 463.856323 -276.614944)
			(xy 463.856832 -276.64283) (xy 463.856323 -276.670716) (xy 463.848203 -276.725892) (xy 463.832135 -276.779299)
			(xy 463.808463 -276.829796) (xy 463.77769 -276.876309) (xy 463.740473 -276.917846) (xy 463.697605 -276.953521)
			(xy 463.649999 -276.982575) (xy 463.59867 -277.004387) (xy 463.544713 -277.018493) (xy 463.489276 -277.024593)
			(xy 463.433542 -277.022556) (xy 463.378699 -277.012426) (xy 463.325915 -276.994419) (xy 463.276315 -276.968918)
			(xy 463.230957 -276.936467) (xy 463.190808 -276.897758) (xy 463.156722 -276.853615) (xy 463.129426 -276.80498)
			(xy 463.109503 -276.752889) (xy 463.097377 -276.698452) (xy 463.093306 -276.64283) (xy 461.836992 -276.64283)
			(xy 461.836992 -276.670048) (xy 461.829237 -276.723989) (xy 461.813884 -276.776278) (xy 461.791246 -276.82585)
			(xy 461.761785 -276.871695) (xy 461.726099 -276.912882) (xy 461.684914 -276.94857) (xy 461.639071 -276.978035)
			(xy 461.5895 -277.000676) (xy 461.537213 -277.016031) (xy 461.483272 -277.02379) (xy 461.456024 -277.024338)
			(xy 461.431774 -277.023961) (xy 461.383665 -277.017814) (xy 461.336724 -277.005618) (xy 461.291709 -276.987567)
			(xy 461.27035 -276.976078) (xy 461.258666 -276.969474) (xy 461.231742 -276.969982) (xy 461.14462 -277.021036)
			(xy 461.137114 -277.025782) (xy 461.125738 -277.039406) (xy 461.119718 -277.056103) (xy 461.119474 -277.064978)
			(xy 461.119474 -277.490682) (xy 461.11986 -277.499534) (xy 461.12588 -277.516183) (xy 461.137181 -277.529812)
			(xy 461.14462 -277.534624) (xy 461.231742 -277.585678) (xy 461.258666 -277.586186) (xy 461.27035 -277.579582)
			(xy 461.291714 -277.568102) (xy 461.336726 -277.550045) (xy 461.383666 -277.537843) (xy 461.431774 -277.531695)
			(xy 461.456024 -277.531322) (xy 461.483272 -277.53181) (xy 461.537213 -277.539569) (xy 461.5895 -277.554924)
			(xy 461.639071 -277.577565) (xy 461.684914 -277.60703) (xy 461.726099 -277.642718) (xy 461.741159 -277.6601)
			(xy 463.093306 -277.6601) (xy 463.097377 -277.604478) (xy 463.109503 -277.550041) (xy 463.129426 -277.49795)
			(xy 463.156722 -277.449315) (xy 463.190808 -277.405172) (xy 463.230957 -277.366463) (xy 463.276315 -277.334012)
			(xy 463.325915 -277.308511) (xy 463.378699 -277.290504) (xy 463.433542 -277.280374) (xy 463.489276 -277.278337)
			(xy 463.544713 -277.284437) (xy 463.59867 -277.298543) (xy 463.649999 -277.320355) (xy 463.697605 -277.349409)
			(xy 463.740473 -277.385084) (xy 463.77769 -277.426621) (xy 463.808463 -277.473134) (xy 463.832135 -277.523631)
			(xy 463.848203 -277.577038) (xy 463.856323 -277.632214) (xy 463.856832 -277.6601) (xy 463.856323 -277.687986)
			(xy 463.848203 -277.743162) (xy 463.832135 -277.796569) (xy 463.808463 -277.847066) (xy 463.77769 -277.893579)
			(xy 463.740473 -277.935116) (xy 463.697605 -277.970791) (xy 463.649999 -277.999845) (xy 463.59867 -278.021657)
			(xy 463.544713 -278.035763) (xy 463.489276 -278.041863) (xy 463.433542 -278.039826) (xy 463.378699 -278.029696)
			(xy 463.325915 -278.011689) (xy 463.276315 -277.986188) (xy 463.230957 -277.953737) (xy 463.190808 -277.915028)
			(xy 463.156722 -277.870885) (xy 463.129426 -277.82225) (xy 463.109503 -277.770159) (xy 463.097377 -277.715722)
			(xy 463.093306 -277.6601) (xy 461.741159 -277.6601) (xy 461.761785 -277.683905) (xy 461.791246 -277.72975)
			(xy 461.813884 -277.779322) (xy 461.829237 -277.831611) (xy 461.836992 -277.885552) (xy 461.836992 -277.940048)
			(xy 461.829237 -277.993989) (xy 461.813884 -278.046278) (xy 461.791246 -278.09585) (xy 461.761785 -278.141695)
			(xy 461.726099 -278.182882) (xy 461.684914 -278.21857) (xy 461.639071 -278.248035) (xy 461.5895 -278.270676)
			(xy 461.537213 -278.286031) (xy 461.483272 -278.29379) (xy 461.456024 -278.294338) (xy 461.431774 -278.293961)
			(xy 461.383665 -278.287814) (xy 461.336724 -278.275618) (xy 461.291709 -278.257567) (xy 461.27035 -278.246078)
			(xy 461.258666 -278.239474) (xy 461.231742 -278.239982) (xy 461.14462 -278.291036) (xy 461.137114 -278.295782)
			(xy 461.125738 -278.309406) (xy 461.119718 -278.326103) (xy 461.119474 -278.334978) (xy 461.119474 -279.268682)
			(xy 461.11986 -279.277534) (xy 461.12588 -279.294183) (xy 461.137181 -279.307812) (xy 461.14462 -279.312624)
			(xy 461.231742 -279.363678) (xy 461.258666 -279.364186) (xy 461.27035 -279.357582) (xy 461.291714 -279.346102)
			(xy 461.336726 -279.328045) (xy 461.383666 -279.315843) (xy 461.431774 -279.309695) (xy 461.456024 -279.309322)
			(xy 461.483272 -279.30981) (xy 461.537213 -279.317569) (xy 461.5895 -279.332924) (xy 461.639071 -279.355565)
			(xy 461.684914 -279.38503) (xy 461.726099 -279.420718) (xy 461.761785 -279.461905) (xy 461.791246 -279.50775)
			(xy 461.813884 -279.557322) (xy 461.829237 -279.609611) (xy 461.836992 -279.663552) (xy 461.836992 -279.718048)
			(xy 461.829237 -279.771989) (xy 461.813884 -279.824278) (xy 461.791246 -279.87385) (xy 461.761785 -279.919695)
			(xy 461.726099 -279.960882) (xy 461.684914 -279.99657) (xy 461.639071 -280.026035) (xy 461.5895 -280.048676)
			(xy 461.537213 -280.064031) (xy 461.483272 -280.07179) (xy 461.456024 -280.072338) (xy 461.431774 -280.071961)
			(xy 461.383665 -280.065814) (xy 461.336724 -280.053618) (xy 461.291709 -280.035567) (xy 461.27035 -280.024078)
			(xy 461.258666 -280.017474) (xy 461.231742 -280.017982) (xy 461.14462 -280.069036) (xy 461.137114 -280.073782)
			(xy 461.125738 -280.087406) (xy 461.119718 -280.104103) (xy 461.119474 -280.112978) (xy 461.119474 -280.96083)
			(xy 463.093816 -280.96083) (xy 463.094349 -280.931755) (xy 463.103169 -280.874278) (xy 463.12061 -280.818806)
			(xy 463.146268 -280.766622) (xy 463.179547 -280.718937) (xy 463.219678 -280.676855) (xy 463.26573 -280.641351)
			(xy 463.29092 -280.62682) (xy 463.303112 -280.620216) (xy 463.317082 -280.596848) (xy 463.318098 -280.480262)
			(xy 463.304382 -280.45664) (xy 463.292444 -280.449782) (xy 463.267877 -280.435063) (xy 463.223004 -280.399484)
			(xy 463.183955 -280.357596) (xy 463.151606 -280.310341) (xy 463.126686 -280.258782) (xy 463.109753 -280.204076)
			(xy 463.101189 -280.147453) (xy 463.100674 -280.11882) (xy 463.101216 -280.089868) (xy 463.10997 -280.032628)
			(xy 463.12728 -279.977371) (xy 463.152748 -279.925368) (xy 463.185787 -279.877814) (xy 463.205322 -279.856438)
			(xy 463.21218 -279.849072) (xy 463.219292 -279.831038) (xy 463.21853 -279.740106) (xy 463.21091 -279.722326)
			(xy 463.203798 -279.71496) (xy 463.183324 -279.693399) (xy 463.148624 -279.645121) (xy 463.121836 -279.592044)
			(xy 463.103609 -279.535452) (xy 463.094384 -279.476717) (xy 463.093816 -279.44699) (xy 463.094267 -279.420526)
			(xy 463.101577 -279.368104) (xy 463.11607 -279.317198) (xy 463.137466 -279.268787) (xy 463.165354 -279.223802)
			(xy 463.199198 -279.183107) (xy 463.238346 -279.147486) (xy 463.282047 -279.117624) (xy 463.329458 -279.094095)
			(xy 463.35442 -279.085294) (xy 463.364834 -279.081738) (xy 463.380582 -279.06726) (xy 463.41919 -278.977852)
			(xy 463.418936 -278.956516) (xy 463.414364 -278.94661) (xy 463.403448 -278.921539) (xy 463.38805 -278.869071)
			(xy 463.380279 -278.814946) (xy 463.37982 -278.787606) (xy 463.380261 -278.760352) (xy 463.388018 -278.706399)
			(xy 463.403375 -278.654099) (xy 463.426018 -278.604517) (xy 463.455488 -278.558662) (xy 463.491185 -278.517469)
			(xy 463.53238 -278.481775) (xy 463.578236 -278.452308) (xy 463.62782 -278.429667) (xy 463.68012 -278.414313)
			(xy 463.734074 -278.406559) (xy 463.761328 -278.406098) (xy 463.789236 -278.406582) (xy 463.844453 -278.41475)
			(xy 463.87131 -278.422354) (xy 463.882232 -278.425656) (xy 463.904584 -278.422354) (xy 463.988912 -278.366474)
			(xy 464.000596 -278.34717) (xy 464.001612 -278.33574) (xy 464.005129 -278.30799) (xy 464.019083 -278.253827)
			(xy 464.040794 -278.202281) (xy 464.069795 -278.154456) (xy 464.105467 -278.111376) (xy 464.147045 -278.073964)
			(xy 464.193638 -278.043021) (xy 464.244248 -278.01921) (xy 464.297792 -278.003042) (xy 464.353122 -277.994862)
			(xy 464.381088 -277.994364) (xy 464.408339 -277.994882) (xy 464.462288 -278.002637) (xy 464.514583 -278.017991)
			(xy 464.564161 -278.040631) (xy 464.610012 -278.070097) (xy 464.651203 -278.105788) (xy 464.686896 -278.146978)
			(xy 464.716363 -278.192828) (xy 464.739004 -278.242406) (xy 464.75436 -278.294701) (xy 464.762117 -278.348649)
			(xy 464.762117 -278.403151) (xy 464.75436 -278.457099) (xy 464.739004 -278.509394) (xy 464.716363 -278.558972)
			(xy 464.686896 -278.604822) (xy 464.651203 -278.646012) (xy 464.610012 -278.681703) (xy 464.564161 -278.711169)
			(xy 464.514583 -278.733809) (xy 464.462288 -278.749163) (xy 464.408339 -278.756918) (xy 464.381088 -278.75738)
			(xy 464.35318 -278.75689) (xy 464.297964 -278.748725) (xy 464.271106 -278.741124) (xy 464.260184 -278.737822)
			(xy 464.237832 -278.741124) (xy 464.153504 -278.797004) (xy 464.14182 -278.816308) (xy 464.140804 -278.827738)
			(xy 464.137448 -278.854793) (xy 464.124016 -278.90763) (xy 464.103203 -278.958018) (xy 464.075431 -279.004932)
			(xy 464.041267 -279.047417) (xy 464.001405 -279.084608) (xy 463.956657 -279.115748) (xy 463.907932 -279.140204)
			(xy 463.882232 -279.149302) (xy 463.871818 -279.152858) (xy 463.85607 -279.167336) (xy 463.817462 -279.256744)
			(xy 463.817716 -279.27808) (xy 463.822288 -279.287986) (xy 463.833232 -279.313046) (xy 463.84862 -279.365519)
			(xy 463.85638 -279.419648) (xy 463.856832 -279.44699) (xy 463.856294 -279.475943) (xy 463.847539 -279.533182)
			(xy 463.830228 -279.588439) (xy 463.804759 -279.640443) (xy 463.771719 -279.687996) (xy 463.752184 -279.709372)
			(xy 463.745326 -279.716738) (xy 463.738214 -279.734772) (xy 463.738976 -279.825704) (xy 463.746596 -279.843484)
			(xy 463.753708 -279.85085) (xy 463.774187 -279.872406) (xy 463.808887 -279.920685) (xy 463.835674 -279.973764)
			(xy 463.853899 -280.030357) (xy 463.863123 -280.089092) (xy 463.86369 -280.11882) (xy 463.863165 -280.147896)
			(xy 463.85435 -280.205375) (xy 463.836911 -280.260851) (xy 463.811253 -280.313036) (xy 463.777971 -280.360721)
			(xy 463.737836 -280.402802) (xy 463.691778 -280.438302) (xy 463.666586 -280.45283) (xy 463.654394 -280.459434)
			(xy 463.640424 -280.482802) (xy 463.639408 -280.599388) (xy 463.653124 -280.62301) (xy 463.665062 -280.629868)
			(xy 463.689652 -280.644549) (xy 463.734525 -280.680135) (xy 463.773573 -280.722029) (xy 463.805919 -280.76929)
			(xy 463.830835 -280.820856) (xy 463.847763 -280.875568) (xy 463.85632 -280.932195) (xy 463.856832 -280.96083)
			(xy 463.856346 -280.988081) (xy 463.84859 -281.042029) (xy 463.833235 -281.094324) (xy 463.810593 -281.143901)
			(xy 463.781127 -281.189751) (xy 463.745436 -281.230942) (xy 463.704245 -281.266633) (xy 463.658395 -281.296099)
			(xy 463.608818 -281.318741) (xy 463.556523 -281.334096) (xy 463.502575 -281.341852) (xy 463.448073 -281.341852)
			(xy 463.394125 -281.334096) (xy 463.34183 -281.318741) (xy 463.292253 -281.296099) (xy 463.246403 -281.266633)
			(xy 463.205212 -281.230942) (xy 463.169521 -281.189751) (xy 463.140055 -281.143901) (xy 463.117413 -281.094324)
			(xy 463.102058 -281.042029) (xy 463.094302 -280.988081) (xy 463.093816 -280.96083) (xy 461.119474 -280.96083)
			(xy 461.119474 -281.587956) (xy 461.119907 -281.598022) (xy 461.127632 -281.616614) (xy 461.13446 -281.624024)
			(xy 461.461866 -281.95143) (xy 461.469265 -281.958274) (xy 461.487864 -281.965995) (xy 461.497934 -281.966416)
			(xy 465.166202 -281.966416) (xy 465.176272 -281.965993) (xy 465.194878 -281.95828) (xy 465.20227 -281.95143)
			(xy 465.310728 -281.842972) (xy 465.317578 -281.835575) (xy 465.325313 -281.816977) (xy 465.325714 -281.806904)
			(xy 465.325714 -255.332992) (xy 465.32529 -255.322922) (xy 465.317575 -255.304318) (xy 465.310728 -255.296924)
			(xy 460.467202 -250.453398) (xy 460.436976 -250.447302) (xy 460.422498 -250.453398) (xy 460.402107 -250.461544)
			(xy 460.359716 -250.472988) (xy 460.316183 -250.478723) (xy 460.294228 -250.479052) (xy 459.430628 -250.479052)
			(xy 459.41869 -250.4821) (xy 459.413102 -250.484894) (xy 459.382871 -250.499979) (xy 459.318483 -250.520427)
			(xy 459.285086 -250.525534) (xy 459.27689 -250.526981) (xy 459.26198 -250.534355) (xy 459.255876 -250.540012)
			(xy 459.235048 -250.56084) (xy 459.229359 -250.566872) (xy 459.221858 -250.581648) (xy 459.220316 -250.589796)
			(xy 459.216173 -250.616165) (xy 459.201007 -250.667342) (xy 459.178352 -250.715672) (xy 459.163928 -250.738132)
			(xy 458.937614 -251.077222) (xy 458.931264 -251.084842) (xy 458.732128 -251.283978) (xy 458.724508 -251.290328)
			(xy 458.441298 -251.47905) (xy 458.418779 -251.493507) (xy 458.370326 -251.516222) (xy 458.319017 -251.531421)
			(xy 458.26601 -251.538761) (xy 458.212501 -251.538077) (xy 458.186028 -251.534168) (xy 458.175681 -251.533015)
			(xy 458.155516 -251.538115) (xy 458.138999 -251.550757) (xy 458.13345 -251.559568) (xy 458.118859 -251.584582)
			(xy 458.083304 -251.630289) (xy 458.041255 -251.670103) (xy 457.993676 -251.703112) (xy 457.941659 -251.728558)
			(xy 457.886397 -251.745859) (xy 457.829156 -251.754618) (xy 457.800202 -251.755148) (xy 457.785216 -251.754894)
			(xy 457.774784 -251.754968) (xy 457.755351 -251.762494) (xy 457.740548 -251.777162) (xy 457.736194 -251.786644)
			(xy 457.725834 -251.810935) (xy 457.698997 -251.856414) (xy 457.665743 -251.897434) (xy 457.6268 -251.933099)
			(xy 457.583021 -251.962627) (xy 457.535364 -251.985371) (xy 457.484872 -252.000835) (xy 457.432651 -252.008678)
			(xy 457.406248 -252.009148) (xy 451.975474 -252.009148) (xy 451.96549 -252.008604) (xy 451.94707 -252.000879)
			(xy 451.93966 -251.994162) (xy 451.43928 -251.493782) (xy 451.432601 -251.486371) (xy 451.425028 -251.467935)
			(xy 451.424548 -251.457968) (xy 451.424548 -250.712986) (xy 451.42509 -250.685749) (xy 451.433438 -250.631916)
			(xy 451.449891 -250.579984) (xy 451.474065 -250.531166) (xy 451.505395 -250.486601) (xy 451.54315 -250.44733)
			(xy 451.586447 -250.41427) (xy 451.634277 -250.388194) (xy 451.685521 -250.36971) (xy 451.738983 -250.35925)
			(xy 451.766178 -250.35764) (xy 451.782417 -250.356537) (xy 451.813566 -250.347135) (xy 451.841328 -250.330166)
			(xy 451.863898 -250.30673) (xy 451.879813 -250.278351) (xy 451.888037 -250.24687) (xy 451.888038 -250.214333)
			(xy 451.879814 -250.182852) (xy 451.8639 -250.154472) (xy 451.84133 -250.131036) (xy 451.813569 -250.114066)
			(xy 451.78242 -250.104664) (xy 451.766178 -250.10364) (xy 451.738982 -250.102033) (xy 451.685516 -250.091583)
			(xy 451.634267 -250.073106) (xy 451.586434 -250.047033) (xy 451.543134 -250.013973) (xy 451.505379 -249.9747)
			(xy 451.474052 -249.93013) (xy 451.449885 -249.881306) (xy 451.433443 -249.829369) (xy 451.42511 -249.775533)
			(xy 451.424548 -249.748294) (xy 451.424548 -249.282458) (xy 451.425062 -249.255815) (xy 451.433088 -249.203136)
			(xy 451.448879 -249.152242) (xy 451.472082 -249.104272) (xy 451.502178 -249.060298) (xy 451.538495 -249.021303)
			(xy 451.58022 -248.988158) (xy 451.62642 -248.961606) (xy 451.676064 -248.94224) (xy 451.72804 -248.930492)
			(xy 451.781186 -248.926625) (xy 451.834315 -248.930726) (xy 451.886239 -248.942703) (xy 451.911212 -248.952004)
			(xy 451.922402 -248.956053) (xy 451.945796 -248.9604) (xy 451.957694 -248.96064) (xy 451.958202 -248.96064)
			(xy 451.974135 -248.960152) (xy 452.005015 -248.952282) (xy 452.032995 -248.937032) (xy 452.056342 -248.915344)
			(xy 452.06539 -248.90222) (xy 452.081392 -248.87936) (xy 452.086175 -248.872521) (xy 452.09149 -248.856712)
			(xy 452.091806 -248.848372) (xy 452.091806 -248.818908) (xy 452.091553 -248.810558) (xy 452.086226 -248.794734)
			(xy 452.081392 -248.78792) (xy 452.06539 -248.76506) (xy 452.056349 -248.751927) (xy 452.033005 -248.730226)
			(xy 452.005023 -248.714965) (xy 451.974138 -248.70709) (xy 451.958202 -248.70664) (xy 451.957694 -248.70664)
			(xy 451.945794 -248.706858) (xy 451.922397 -248.711207) (xy 451.911212 -248.715276) (xy 451.886256 -248.72463)
			(xy 451.834325 -248.736609) (xy 451.781188 -248.740712) (xy 451.728034 -248.736844) (xy 451.676051 -248.725095)
			(xy 451.626401 -248.705725) (xy 451.580194 -248.679168) (xy 451.538464 -248.646019) (xy 451.502143 -248.607017)
			(xy 451.472044 -248.563035) (xy 451.44884 -248.515057) (xy 451.433049 -248.464156) (xy 451.425025 -248.411469)
			(xy 451.424548 -248.384822) (xy 451.424548 -244.304312) (xy 451.425039 -244.294353) (xy 451.432638 -244.275938)
			(xy 451.43928 -244.268498) (xy 451.81266 -243.895118) (xy 451.820008 -243.888315) (xy 451.838471 -243.880602)
			(xy 451.848474 -243.880132) (xy 457.573126 -243.880132) (xy 457.583133 -243.87964) (xy 457.601621 -243.871977)
			(xy 457.615774 -243.857826) (xy 457.623439 -243.839339) (xy 457.623926 -243.829332) (xy 457.623926 -240.837974)
			(xy 457.623385 -240.827988) (xy 457.615668 -240.80956) (xy 457.60894 -240.80216) (xy 457.257404 -240.45037)
			(xy 457.250009 -240.443515) (xy 457.23141 -240.435768) (xy 457.221336 -240.435384) (xy 445.983614 -240.435384)
			(xy 445.973625 -240.435919) (xy 445.955188 -240.443627) (xy 445.9478 -240.45037) (xy 445.627252 -240.770918)
			(xy 445.620403 -240.778315) (xy 445.612666 -240.796914) (xy 445.612266 -240.806986) (xy 445.612266 -243.878608)
			(xy 445.612692 -243.888676) (xy 445.620416 -243.907272) (xy 445.627252 -243.914676) (xy 445.62776 -243.915184)
			(xy 445.62776 -252.115846) (xy 446.710128 -252.115846) (xy 446.710128 -252.061354) (xy 446.717882 -252.007418)
			(xy 446.733233 -251.955134) (xy 446.755868 -251.905566) (xy 446.785326 -251.859724) (xy 446.821008 -251.81854)
			(xy 446.862187 -251.782854) (xy 446.908026 -251.75339) (xy 446.957591 -251.730749) (xy 447.009873 -251.715392)
			(xy 447.063809 -251.707631) (xy 447.091054 -251.707142) (xy 447.112189 -251.707444) (xy 447.154196 -251.712159)
			(xy 447.174874 -251.71654) (xy 447.18732 -251.719334) (xy 447.211958 -251.712476) (xy 447.291714 -251.63526)
			(xy 447.299334 -251.610876) (xy 447.296794 -251.598176) (xy 447.29359 -251.580314) (xy 447.290153 -251.544186)
			(xy 447.289936 -251.52604) (xy 447.290422 -251.498789) (xy 447.298178 -251.444841) (xy 447.313533 -251.392546)
			(xy 447.336175 -251.342969) (xy 447.365641 -251.297119) (xy 447.401332 -251.255928) (xy 447.442523 -251.220237)
			(xy 447.488373 -251.190771) (xy 447.53795 -251.168129) (xy 447.590245 -251.152774) (xy 447.644193 -251.145018)
			(xy 447.698695 -251.145018) (xy 447.752643 -251.152774) (xy 447.804938 -251.168129) (xy 447.854515 -251.190771)
			(xy 447.900365 -251.220237) (xy 447.941556 -251.255928) (xy 447.977247 -251.297119) (xy 448.006713 -251.342969)
			(xy 448.029355 -251.392546) (xy 448.04471 -251.444841) (xy 448.052466 -251.498789) (xy 448.052952 -251.52604)
			(xy 448.052382 -251.555478) (xy 448.043333 -251.613655) (xy 448.025458 -251.669752) (xy 447.999179 -251.722438)
			(xy 447.982594 -251.746766) (xy 447.976752 -251.754894) (xy 447.972434 -251.774198) (xy 447.986404 -251.86386)
			(xy 447.996564 -251.880878) (xy 448.004692 -251.88672) (xy 448.028003 -251.904869) (xy 448.069265 -251.947146)
			(xy 448.103524 -251.995273) (xy 448.129961 -252.048103) (xy 448.147945 -252.104374) (xy 448.157047 -252.162744)
			(xy 448.1576 -252.192282) (xy 448.157128 -252.219535) (xy 448.154839 -252.235462) (xy 449.858638 -252.235462)
			(xy 449.859182 -252.206164) (xy 449.868154 -252.14826) (xy 449.885866 -252.092405) (xy 449.911902 -252.039912)
			(xy 449.945652 -251.992012) (xy 449.986323 -251.94983) (xy 450.032961 -251.914356) (xy 450.08447 -251.886423)
			(xy 450.111876 -251.876052) (xy 450.12102 -251.873004) (xy 450.13499 -251.860812) (xy 450.176392 -251.784612)
			(xy 450.178932 -251.76607) (xy 450.176646 -251.756926) (xy 450.171792 -251.735151) (xy 450.166575 -251.690841)
			(xy 450.166232 -251.668534) (xy 450.166718 -251.641283) (xy 450.174474 -251.587335) (xy 450.189829 -251.53504)
			(xy 450.212471 -251.485463) (xy 450.241937 -251.439613) (xy 450.277628 -251.398422) (xy 450.318819 -251.362731)
			(xy 450.364669 -251.333265) (xy 450.414246 -251.310623) (xy 450.466541 -251.295268) (xy 450.520489 -251.287512)
			(xy 450.574991 -251.287512) (xy 450.628939 -251.295268) (xy 450.681234 -251.310623) (xy 450.730811 -251.333265)
			(xy 450.776661 -251.362731) (xy 450.817852 -251.398422) (xy 450.853543 -251.439613) (xy 450.883009 -251.485463)
			(xy 450.905651 -251.53504) (xy 450.921006 -251.587335) (xy 450.928762 -251.641283) (xy 450.929248 -251.668534)
			(xy 450.92871 -251.697832) (xy 450.919738 -251.755737) (xy 450.902026 -251.811593) (xy 450.875989 -251.864086)
			(xy 450.842238 -251.911986) (xy 450.801566 -251.954168) (xy 450.754927 -251.989642) (xy 450.703417 -252.017574)
			(xy 450.67601 -252.027944) (xy 450.666866 -252.030992) (xy 450.652896 -252.043184) (xy 450.611494 -252.119384)
			(xy 450.608954 -252.137926) (xy 450.61124 -252.14707) (xy 450.616095 -252.168845) (xy 450.621311 -252.213155)
			(xy 450.621654 -252.235462) (xy 450.621146 -252.254258) (xy 450.620638 -252.264672) (xy 450.62775 -252.283976)
			(xy 450.692266 -252.352556) (xy 450.711062 -252.360938) (xy 450.721476 -252.360938) (xy 450.748509 -252.36181)
			(xy 450.801954 -252.37009) (xy 450.853695 -252.385834) (xy 450.902693 -252.408727) (xy 450.947967 -252.43831)
			(xy 450.98861 -252.473991) (xy 451.023807 -252.515054) (xy 451.052852 -252.560675) (xy 451.075162 -252.609942)
			(xy 451.090292 -252.661865) (xy 451.097937 -252.715405) (xy 451.098412 -252.742446) (xy 451.097926 -252.769697)
			(xy 451.09622 -252.781562) (xy 451.520304 -252.781562) (xy 451.524375 -252.72594) (xy 451.536501 -252.671503)
			(xy 451.556424 -252.619412) (xy 451.58372 -252.570777) (xy 451.617806 -252.526634) (xy 451.657955 -252.487925)
			(xy 451.703313 -252.455474) (xy 451.752913 -252.429973) (xy 451.805697 -252.411966) (xy 451.86054 -252.401836)
			(xy 451.916274 -252.399799) (xy 451.971711 -252.405899) (xy 452.025668 -252.420005) (xy 452.076997 -252.441817)
			(xy 452.124603 -252.470871) (xy 452.167471 -252.506546) (xy 452.204688 -252.548083) (xy 452.235461 -252.594596)
			(xy 452.259133 -252.645093) (xy 452.275201 -252.6985) (xy 452.283321 -252.753676) (xy 452.28383 -252.781562)
			(xy 452.283321 -252.809448) (xy 452.275201 -252.864624) (xy 452.259133 -252.918031) (xy 452.235461 -252.968528)
			(xy 452.204688 -253.015041) (xy 452.167471 -253.056578) (xy 452.124603 -253.092253) (xy 452.076997 -253.121307)
			(xy 452.025668 -253.143119) (xy 451.971711 -253.157225) (xy 451.916274 -253.163325) (xy 451.86054 -253.161288)
			(xy 451.805697 -253.151158) (xy 451.752913 -253.133151) (xy 451.703313 -253.10765) (xy 451.657955 -253.075199)
			(xy 451.617806 -253.03649) (xy 451.58372 -252.992347) (xy 451.556424 -252.943712) (xy 451.536501 -252.891621)
			(xy 451.524375 -252.837184) (xy 451.520304 -252.781562) (xy 451.09622 -252.781562) (xy 451.09017 -252.823645)
			(xy 451.074815 -252.87594) (xy 451.052173 -252.925517) (xy 451.022707 -252.971367) (xy 450.987016 -253.012558)
			(xy 450.945825 -253.048249) (xy 450.899975 -253.077715) (xy 450.850398 -253.100357) (xy 450.798103 -253.115712)
			(xy 450.744155 -253.123468) (xy 450.689653 -253.123468) (xy 450.635705 -253.115712) (xy 450.58341 -253.100357)
			(xy 450.533833 -253.077715) (xy 450.487983 -253.048249) (xy 450.446792 -253.012558) (xy 450.411101 -252.971367)
			(xy 450.381635 -252.925517) (xy 450.358993 -252.87594) (xy 450.343638 -252.823645) (xy 450.335882 -252.769697)
			(xy 450.335396 -252.742446) (xy 450.335904 -252.72365) (xy 450.336412 -252.713236) (xy 450.3293 -252.693932)
			(xy 450.264784 -252.625352) (xy 450.245988 -252.61697) (xy 450.235574 -252.61697) (xy 450.20854 -252.616135)
			(xy 450.155094 -252.60785) (xy 450.103353 -252.5921) (xy 450.054355 -252.569202) (xy 450.009081 -252.539614)
			(xy 449.968439 -252.503929) (xy 449.933244 -252.462864) (xy 449.9042 -252.417239) (xy 449.881889 -252.367971)
			(xy 449.866759 -252.316046) (xy 449.859113 -252.262504) (xy 449.858638 -252.235462) (xy 448.154839 -252.235462)
			(xy 448.149373 -252.273486) (xy 448.134019 -252.325784) (xy 448.111378 -252.375365) (xy 448.081911 -252.421218)
			(xy 448.046218 -252.462411) (xy 448.005026 -252.498105) (xy 447.959173 -252.527573) (xy 447.909593 -252.550216)
			(xy 447.857296 -252.565571) (xy 447.803345 -252.573327) (xy 447.776092 -252.57379) (xy 447.750194 -252.573343)
			(xy 447.698874 -252.566339) (xy 447.648971 -252.552461) (xy 447.601404 -252.531963) (xy 447.557044 -252.505223)
			(xy 447.516707 -252.47273) (xy 447.481134 -252.435082) (xy 447.465704 -252.414278) (xy 447.459608 -252.405642)
			(xy 447.44259 -252.395228) (xy 447.349626 -252.381258) (xy 447.330068 -252.386084) (xy 447.321686 -252.392434)
			(xy 447.296641 -252.410679) (xy 447.241888 -252.439684) (xy 447.183173 -252.459473) (xy 447.122034 -252.469528)
			(xy 447.091054 -252.470158) (xy 447.063809 -252.469569) (xy 447.009873 -252.461808) (xy 446.957591 -252.446451)
			(xy 446.908026 -252.42381) (xy 446.862187 -252.394346) (xy 446.821008 -252.35866) (xy 446.785326 -252.317476)
			(xy 446.755868 -252.271634) (xy 446.733233 -252.222066) (xy 446.717882 -252.169782) (xy 446.710128 -252.115846)
			(xy 445.62776 -252.115846) (xy 445.62776 -252.55347) (xy 445.627323 -252.563534) (xy 445.619586 -252.582116)
			(xy 445.612774 -252.589538) (xy 445.44869 -252.753622) (xy 445.442197 -252.76076) (xy 445.434618 -252.778489)
			(xy 445.434094 -252.797763) (xy 445.437006 -252.806962) (xy 445.473836 -252.907546) (xy 445.497204 -252.925326)
			(xy 445.51219 -252.926596) (xy 445.532448 -252.928603) (xy 445.572411 -252.936364) (xy 445.591946 -252.94209)
			(xy 445.601344 -252.944884) (xy 445.62014 -252.94336) (xy 445.70015 -252.904244) (xy 445.71285 -252.890274)
			(xy 445.716406 -252.88113) (xy 445.72717 -252.854458) (xy 445.755554 -252.804436) (xy 445.791128 -252.759243)
			(xy 445.833084 -252.719904) (xy 445.880472 -252.687311) (xy 445.932217 -252.662204) (xy 445.987145 -252.645151)
			(xy 446.044011 -252.63654) (xy 446.072768 -252.63602) (xy 446.10229 -252.636593) (xy 446.160624 -252.645729)
			(xy 446.216855 -252.663742) (xy 446.26964 -252.690201) (xy 446.294002 -252.706886) (xy 446.302638 -252.712728)
			(xy 446.322704 -252.7173) (xy 446.414906 -252.700028) (xy 446.431924 -252.688852) (xy 446.437766 -252.680216)
			(xy 446.452974 -252.658049) (xy 446.488628 -252.617817) (xy 446.529579 -252.582993) (xy 446.575016 -252.554265)
			(xy 446.624038 -252.532205) (xy 446.675672 -252.517249) (xy 446.728896 -252.509695) (xy 446.755774 -252.509274)
			(xy 446.783029 -252.509735) (xy 446.836986 -252.517489) (xy 446.889289 -252.532844) (xy 446.938875 -252.555486)
			(xy 446.984734 -252.584955) (xy 447.025931 -252.62065) (xy 447.06163 -252.661846) (xy 447.091101 -252.707702)
			(xy 447.113747 -252.757286) (xy 447.129105 -252.809589) (xy 447.136863 -252.863545) (xy 447.136863 -252.918055)
			(xy 447.129105 -252.972011) (xy 447.113747 -253.024314) (xy 447.091101 -253.073898) (xy 447.06163 -253.119754)
			(xy 447.025931 -253.16095) (xy 446.984734 -253.196645) (xy 446.938875 -253.226114) (xy 446.889289 -253.248756)
			(xy 446.836986 -253.264111) (xy 446.783029 -253.271865) (xy 446.755774 -253.27229) (xy 446.726251 -253.27172)
			(xy 446.667914 -253.26259) (xy 446.611679 -253.244583) (xy 446.55889 -253.218128) (xy 446.53454 -253.201424)
			(xy 446.525904 -253.195582) (xy 446.505838 -253.19101) (xy 446.413636 -253.208282) (xy 446.396618 -253.219458)
			(xy 446.390776 -253.228094) (xy 446.375566 -253.250258) (xy 446.33991 -253.290483) (xy 446.298958 -253.325301)
			(xy 446.25352 -253.35402) (xy 446.204499 -253.376073) (xy 446.152865 -253.39102) (xy 446.099645 -253.398567)
			(xy 446.072768 -253.399036) (xy 446.04446 -253.398506) (xy 445.988473 -253.390094) (xy 445.961262 -253.382272)
			(xy 445.951864 -253.379478) (xy 445.933068 -253.381002) (xy 445.853058 -253.420118) (xy 445.840358 -253.434088)
			(xy 445.836802 -253.443232) (xy 445.82604 -253.469906) (xy 445.797659 -253.519934) (xy 445.762087 -253.565132)
			(xy 445.720132 -253.604476) (xy 445.672743 -253.637073) (xy 445.620997 -253.662184) (xy 445.566067 -253.67924)
			(xy 445.509199 -253.687853) (xy 445.48044 -253.688342) (xy 445.452051 -253.687817) (xy 445.395902 -253.679396)
			(xy 445.34162 -253.66275) (xy 445.290403 -253.638245) (xy 445.243382 -253.606423) (xy 445.201594 -253.567986)
			(xy 445.165961 -253.523782) (xy 445.137271 -253.474787) (xy 445.116156 -253.422082) (xy 445.103083 -253.366831)
			(xy 445.100202 -253.338584) (xy 445.098932 -253.323598) (xy 445.081152 -253.30023) (xy 444.980568 -253.2634)
			(xy 444.971373 -253.260472) (xy 444.9521 -253.260995) (xy 444.934386 -253.268609) (xy 444.927228 -253.275084)
			(xy 442.226446 -255.975866) (xy 442.219605 -255.983266) (xy 442.211887 -256.001865) (xy 442.21146 -256.011934)
			(xy 442.21146 -259.573776) (xy 446.548508 -259.573776) (xy 446.552579 -259.518154) (xy 446.564705 -259.463717)
			(xy 446.584628 -259.411626) (xy 446.611924 -259.362991) (xy 446.64601 -259.318848) (xy 446.686159 -259.280139)
			(xy 446.731517 -259.247688) (xy 446.781117 -259.222187) (xy 446.833901 -259.20418) (xy 446.888744 -259.19405)
			(xy 446.944478 -259.192013) (xy 446.999915 -259.198113) (xy 447.053872 -259.212219) (xy 447.105201 -259.234031)
			(xy 447.152807 -259.263085) (xy 447.195675 -259.29876) (xy 447.232892 -259.340297) (xy 447.263665 -259.38681)
			(xy 447.287337 -259.437307) (xy 447.303405 -259.490714) (xy 447.311525 -259.54589) (xy 447.312034 -259.573776)
			(xy 447.311525 -259.601662) (xy 447.303405 -259.656838) (xy 447.287337 -259.710245) (xy 447.263665 -259.760742)
			(xy 447.232892 -259.807255) (xy 447.195675 -259.848792) (xy 447.152807 -259.884467) (xy 447.105201 -259.913521)
			(xy 447.053872 -259.935333) (xy 446.999915 -259.949439) (xy 446.944478 -259.955539) (xy 446.888744 -259.953502)
			(xy 446.833901 -259.943372) (xy 446.781117 -259.925365) (xy 446.731517 -259.899864) (xy 446.686159 -259.867413)
			(xy 446.64601 -259.828704) (xy 446.611924 -259.784561) (xy 446.584628 -259.735926) (xy 446.564705 -259.683835)
			(xy 446.552579 -259.629398) (xy 446.548508 -259.573776) (xy 442.21146 -259.573776) (xy 442.21146 -268.454124)
			(xy 442.211889 -268.464191) (xy 442.219616 -268.482783) (xy 442.226446 -268.490192) (xy 442.852556 -269.116302)
			(xy 442.859407 -269.123699) (xy 442.867148 -269.142297) (xy 442.867542 -269.15237) (xy 442.867542 -272.877026)
			(xy 442.867113 -272.887093) (xy 442.859385 -272.905685) (xy 442.852556 -272.913094) (xy 442.226446 -273.539204)
			(xy 442.219595 -273.546601) (xy 442.211855 -273.565199) (xy 442.21146 -273.575272) (xy 442.21146 -277.420324)
			(xy 442.211031 -277.430391) (xy 442.203306 -277.448986) (xy 442.196474 -277.456392) (xy 436.125112 -283.527754)
			(xy 442.093858 -283.527754) (xy 442.094335 -283.500503) (xy 442.102097 -283.446557) (xy 442.117456 -283.394264)
			(xy 442.1401 -283.344689) (xy 442.169568 -283.29884) (xy 442.20526 -283.257652) (xy 442.24645 -283.221961)
			(xy 442.292299 -283.192494) (xy 442.341875 -283.169852) (xy 442.394169 -283.154494) (xy 442.448115 -283.146734)
			(xy 442.475366 -283.146246) (xy 442.502736 -283.146721) (xy 442.556915 -283.154535) (xy 442.609419 -283.170021)
			(xy 442.659166 -283.192861) (xy 442.705132 -283.222585) (xy 442.726064 -283.240226) (xy 442.733176 -283.246322)
			(xy 442.750194 -283.252672) (xy 442.835538 -283.252672) (xy 442.852556 -283.246322) (xy 442.859668 -283.240226)
			(xy 442.880605 -283.222592) (xy 442.926576 -283.192879) (xy 442.976322 -283.170041) (xy 443.028822 -283.154549)
			(xy 443.082997 -283.14672) (xy 443.110366 -283.146246) (xy 443.137614 -283.14681) (xy 443.191557 -283.15456)
			(xy 443.243847 -283.169909) (xy 443.293421 -283.192543) (xy 443.33927 -283.222001) (xy 443.380459 -283.257684)
			(xy 443.416151 -283.298866) (xy 443.445619 -283.344709) (xy 443.468263 -283.394278) (xy 443.483623 -283.446565)
			(xy 443.491385 -283.500506) (xy 443.491874 -283.527754) (xy 443.49149 -283.554179) (xy 443.484188 -283.606523)
			(xy 443.469732 -283.657358) (xy 443.448398 -283.705712) (xy 443.420594 -283.750658) (xy 443.386853 -283.791337)
			(xy 443.34782 -283.826969) (xy 443.304244 -283.856874) (xy 443.256957 -283.880477) (xy 443.206864 -283.897328)
			(xy 443.180978 -283.902658) (xy 443.168786 -283.904944) (xy 443.149482 -283.91993) (xy 443.104016 -284.017212)
			(xy 443.105032 -284.041596) (xy 443.111128 -284.052518) (xy 443.122831 -284.074052) (xy 443.14127 -284.119461)
			(xy 443.153736 -284.166859) (xy 443.160023 -284.215465) (xy 443.160404 -284.23997) (xy 443.159918 -284.267221)
			(xy 443.152162 -284.321169) (xy 443.136807 -284.373464) (xy 443.114165 -284.423041) (xy 443.084699 -284.468891)
			(xy 443.049008 -284.510082) (xy 443.007817 -284.545773) (xy 442.961967 -284.575239) (xy 442.91239 -284.597881)
			(xy 442.860095 -284.613236) (xy 442.806147 -284.620992) (xy 442.751645 -284.620992) (xy 442.697697 -284.613236)
			(xy 442.645402 -284.597881) (xy 442.595825 -284.575239) (xy 442.549975 -284.545773) (xy 442.508784 -284.510082)
			(xy 442.473093 -284.468891) (xy 442.443627 -284.423041) (xy 442.420985 -284.373464) (xy 442.40563 -284.321169)
			(xy 442.397874 -284.267221) (xy 442.397388 -284.23997) (xy 442.397756 -284.214848) (xy 442.404327 -284.165035)
			(xy 442.417378 -284.116515) (xy 442.436683 -284.070127) (xy 442.44895 -284.0482) (xy 442.4553 -284.037532)
			(xy 442.45657 -284.014164) (xy 442.415168 -283.916628) (xy 442.397134 -283.901388) (xy 442.385196 -283.89834)
			(xy 442.35787 -283.891179) (xy 442.305548 -283.869885) (xy 442.256939 -283.841109) (xy 442.213106 -283.805478)
			(xy 442.175006 -283.763772) (xy 442.143474 -283.716903) (xy 442.119199 -283.665897) (xy 442.102711 -283.611868)
			(xy 442.094373 -283.555998) (xy 442.093858 -283.527754) (xy 436.125112 -283.527754) (xy 432.852068 -286.800798)
			(xy 432.845214 -286.808193) (xy 432.837468 -286.826792) (xy 432.837082 -286.836866) (xy 432.837082 -288.221166)
			(xy 436.754014 -288.221166) (xy 436.758085 -288.165544) (xy 436.770211 -288.111107) (xy 436.790134 -288.059016)
			(xy 436.81743 -288.010381) (xy 436.851516 -287.966238) (xy 436.891665 -287.927529) (xy 436.937023 -287.895078)
			(xy 436.986623 -287.869577) (xy 437.039407 -287.85157) (xy 437.09425 -287.84144) (xy 437.149984 -287.839403)
			(xy 437.205421 -287.845503) (xy 437.259378 -287.859609) (xy 437.310707 -287.881421) (xy 437.358313 -287.910475)
			(xy 437.401181 -287.94615) (xy 437.438398 -287.987687) (xy 437.469171 -288.0342) (xy 437.492843 -288.084697)
			(xy 437.508911 -288.138104) (xy 437.517031 -288.19328) (xy 437.51754 -288.221166) (xy 437.517475 -288.224712)
			(xy 437.77102 -288.224712) (xy 437.771025 -288.170216) (xy 437.778785 -288.116276) (xy 437.794143 -288.063989)
			(xy 437.816786 -288.01442) (xy 437.846253 -287.968578) (xy 437.881944 -287.927396) (xy 437.923132 -287.891712)
			(xy 437.96898 -287.862254) (xy 438.018553 -287.83962) (xy 438.070842 -287.824271) (xy 438.124784 -287.81652)
			(xy 438.152032 -287.816036) (xy 438.172098 -287.816544) (xy 438.184036 -287.817306) (xy 438.205626 -287.807908)
			(xy 438.273444 -287.72739) (xy 438.279032 -287.70453) (xy 438.276492 -287.692846) (xy 438.272095 -287.672171)
			(xy 438.267389 -287.630162) (xy 438.267094 -287.609026) (xy 438.26758 -287.581775) (xy 438.275336 -287.527827)
			(xy 438.290691 -287.475532) (xy 438.313333 -287.425955) (xy 438.342799 -287.380105) (xy 438.37849 -287.338914)
			(xy 438.419681 -287.303223) (xy 438.465531 -287.273757) (xy 438.515108 -287.251115) (xy 438.567403 -287.23576)
			(xy 438.621351 -287.228004) (xy 438.675853 -287.228004) (xy 438.729801 -287.23576) (xy 438.782096 -287.251115)
			(xy 438.831673 -287.273757) (xy 438.877523 -287.303223) (xy 438.918714 -287.338914) (xy 438.954405 -287.380105)
			(xy 438.983871 -287.425955) (xy 439.006513 -287.475532) (xy 439.021868 -287.527827) (xy 439.029624 -287.581775)
			(xy 439.03011 -287.609026) (xy 439.029679 -287.63547) (xy 439.022416 -287.687857) (xy 439.015632 -287.71342)
			(xy 439.012076 -287.725866) (xy 439.01741 -287.75025) (xy 439.08853 -287.834324) (xy 439.111898 -287.843468)
			(xy 439.124852 -287.842198) (xy 439.13298 -287.841182) (xy 439.144156 -287.840166) (xy 439.163206 -287.829244)
			(xy 439.220864 -287.747456) (xy 439.224674 -287.725612) (xy 439.22188 -287.71469) (xy 439.216292 -287.69134)
			(xy 439.210305 -287.643701) (xy 439.209942 -287.619694) (xy 439.210428 -287.592443) (xy 439.218184 -287.538495)
			(xy 439.233539 -287.4862) (xy 439.256181 -287.436623) (xy 439.285647 -287.390773) (xy 439.321338 -287.349582)
			(xy 439.362529 -287.313891) (xy 439.408379 -287.284425) (xy 439.457956 -287.261783) (xy 439.510251 -287.246428)
			(xy 439.564199 -287.238672) (xy 439.618701 -287.238672) (xy 439.672649 -287.246428) (xy 439.724944 -287.261783)
			(xy 439.774521 -287.284425) (xy 439.820371 -287.313891) (xy 439.861562 -287.349582) (xy 439.897253 -287.390773)
			(xy 439.926719 -287.436623) (xy 439.949361 -287.4862) (xy 439.964716 -287.538495) (xy 439.972472 -287.592443)
			(xy 439.972958 -287.619694) (xy 439.972595 -287.645215) (xy 439.965836 -287.695808) (xy 439.959496 -287.720532)
			(xy 439.95594 -287.733486) (xy 439.962036 -287.758886) (xy 440.039252 -287.84169) (xy 440.064144 -287.849564)
			(xy 440.077098 -287.847024) (xy 440.095574 -287.843576) (xy 440.13298 -287.83989) (xy 440.151774 -287.839658)
			(xy 440.17903 -287.840127) (xy 440.232987 -287.847881) (xy 440.285291 -287.863236) (xy 440.334877 -287.885878)
			(xy 440.380736 -287.915347) (xy 440.421935 -287.951042) (xy 440.457634 -287.992238) (xy 440.487106 -288.038095)
			(xy 440.509753 -288.087679) (xy 440.525112 -288.139982) (xy 440.532871 -288.193938) (xy 440.532871 -288.24845)
			(xy 440.525114 -288.302406) (xy 440.509757 -288.35471) (xy 440.487112 -288.404295) (xy 440.457641 -288.450152)
			(xy 440.421943 -288.491349) (xy 440.380746 -288.527046) (xy 440.334888 -288.556516) (xy 440.285302 -288.57916)
			(xy 440.232998 -288.594516) (xy 440.179042 -288.602272) (xy 440.12453 -288.60227) (xy 440.070574 -288.59451)
			(xy 440.018272 -288.57915) (xy 439.968688 -288.556503) (xy 439.922831 -288.527029) (xy 439.881637 -288.491329)
			(xy 439.845942 -288.45013) (xy 439.816474 -288.40427) (xy 439.793833 -288.354683) (xy 439.77848 -288.302379)
			(xy 439.770727 -288.248422) (xy 439.770266 -288.221166) (xy 439.77064 -288.195645) (xy 439.777392 -288.145053)
			(xy 439.783728 -288.120328) (xy 439.787284 -288.107374) (xy 439.781188 -288.081974) (xy 439.703972 -287.99917)
			(xy 439.67908 -287.991296) (xy 439.666126 -287.993836) (xy 439.656292 -287.99575) (xy 439.63647 -287.998672)
			(xy 439.626502 -287.999678) (xy 439.615326 -288.000694) (xy 439.596276 -288.011616) (xy 439.538618 -288.093404)
			(xy 439.534808 -288.115248) (xy 439.537602 -288.12617) (xy 439.543182 -288.149522) (xy 439.549175 -288.197159)
			(xy 439.54954 -288.221166) (xy 439.549054 -288.248417) (xy 439.541298 -288.302365) (xy 439.525943 -288.35466)
			(xy 439.503301 -288.404237) (xy 439.473835 -288.450087) (xy 439.438144 -288.491278) (xy 439.396953 -288.526969)
			(xy 439.351103 -288.556435) (xy 439.301526 -288.579077) (xy 439.249231 -288.594432) (xy 439.195283 -288.602188)
			(xy 439.140781 -288.602188) (xy 439.086833 -288.594432) (xy 439.034538 -288.579077) (xy 438.984961 -288.556435)
			(xy 438.939111 -288.526969) (xy 438.89792 -288.491278) (xy 438.862229 -288.450087) (xy 438.832763 -288.404237)
			(xy 438.810121 -288.35466) (xy 438.794766 -288.302365) (xy 438.78701 -288.248417) (xy 438.786524 -288.221166)
			(xy 438.786952 -288.194722) (xy 438.794217 -288.142335) (xy 438.801002 -288.116772) (xy 438.804558 -288.104326)
			(xy 438.799224 -288.079942) (xy 438.728104 -287.995868) (xy 438.704736 -287.986724) (xy 438.691782 -287.987994)
			(xy 438.681025 -287.989162) (xy 438.659422 -287.990435) (xy 438.648602 -287.990534) (xy 438.628536 -287.990026)
			(xy 438.616598 -287.989264) (xy 438.595008 -287.998662) (xy 438.52719 -288.07918) (xy 438.521602 -288.10204)
			(xy 438.524142 -288.113724) (xy 438.528534 -288.1344) (xy 438.533243 -288.176408) (xy 438.53354 -288.197544)
			(xy 438.532975 -288.224792) (xy 438.525213 -288.278732) (xy 438.509854 -288.331019) (xy 438.48721 -288.380587)
			(xy 438.457742 -288.426429) (xy 438.42205 -288.46761) (xy 438.380861 -288.503293) (xy 438.335013 -288.53275)
			(xy 438.28544 -288.555383) (xy 438.23315 -288.570731) (xy 438.179208 -288.578481) (xy 438.124712 -288.578475)
			(xy 438.070772 -288.570714) (xy 438.018485 -288.555355) (xy 437.968916 -288.532712) (xy 437.923075 -288.503245)
			(xy 437.881893 -288.467553) (xy 437.84621 -288.426365) (xy 437.816752 -288.380517) (xy 437.794118 -288.330944)
			(xy 437.77877 -288.278654) (xy 437.77102 -288.224712) (xy 437.517475 -288.224712) (xy 437.517031 -288.249052)
			(xy 437.508911 -288.304228) (xy 437.492843 -288.357635) (xy 437.469171 -288.408132) (xy 437.438398 -288.454645)
			(xy 437.401181 -288.496182) (xy 437.358313 -288.531857) (xy 437.310707 -288.560911) (xy 437.259378 -288.582723)
			(xy 437.205421 -288.596829) (xy 437.149984 -288.602929) (xy 437.09425 -288.600892) (xy 437.039407 -288.590762)
			(xy 436.986623 -288.572755) (xy 436.937023 -288.547254) (xy 436.891665 -288.514803) (xy 436.851516 -288.476094)
			(xy 436.81743 -288.431951) (xy 436.790134 -288.383316) (xy 436.770211 -288.331225) (xy 436.758085 -288.276788)
			(xy 436.754014 -288.221166) (xy 432.837082 -288.221166) (xy 432.837082 -289.08502) (xy 434.087776 -289.08502)
			(xy 434.091847 -289.029398) (xy 434.103973 -288.974961) (xy 434.123896 -288.92287) (xy 434.151192 -288.874235)
			(xy 434.185278 -288.830092) (xy 434.225427 -288.791383) (xy 434.270785 -288.758932) (xy 434.320385 -288.733431)
			(xy 434.373169 -288.715424) (xy 434.428012 -288.705294) (xy 434.483746 -288.703257) (xy 434.539183 -288.709357)
			(xy 434.59314 -288.723463) (xy 434.644469 -288.745275) (xy 434.692075 -288.774329) (xy 434.734943 -288.810004)
			(xy 434.77216 -288.851541) (xy 434.802933 -288.898054) (xy 434.826605 -288.948551) (xy 434.842673 -289.001958)
			(xy 434.850793 -289.057134) (xy 434.851302 -289.08502) (xy 434.850793 -289.112906) (xy 434.842673 -289.168082)
			(xy 434.826605 -289.221489) (xy 434.802933 -289.271986) (xy 434.77216 -289.318499) (xy 434.734943 -289.360036)
			(xy 434.692075 -289.395711) (xy 434.644469 -289.424765) (xy 434.59314 -289.446577) (xy 434.539183 -289.460683)
			(xy 434.483746 -289.466783) (xy 434.428012 -289.464746) (xy 434.373169 -289.454616) (xy 434.320385 -289.436609)
			(xy 434.270785 -289.411108) (xy 434.225427 -289.378657) (xy 434.185278 -289.339948) (xy 434.151192 -289.295805)
			(xy 434.123896 -289.24717) (xy 434.103973 -289.195079) (xy 434.091847 -289.140642) (xy 434.087776 -289.08502)
			(xy 432.837082 -289.08502) (xy 432.837082 -290.2458) (xy 433.453792 -290.2458) (xy 433.457863 -290.190178)
			(xy 433.469989 -290.135741) (xy 433.489912 -290.08365) (xy 433.517208 -290.035015) (xy 433.551294 -289.990872)
			(xy 433.591443 -289.952163) (xy 433.636801 -289.919712) (xy 433.686401 -289.894211) (xy 433.739185 -289.876204)
			(xy 433.794028 -289.866074) (xy 433.849762 -289.864037) (xy 433.905199 -289.870137) (xy 433.959156 -289.884243)
			(xy 434.010485 -289.906055) (xy 434.058091 -289.935109) (xy 434.100959 -289.970784) (xy 434.138176 -290.012321)
			(xy 434.168949 -290.058834) (xy 434.192621 -290.109331) (xy 434.208689 -290.162738) (xy 434.216809 -290.217914)
			(xy 434.217318 -290.2458) (xy 434.216809 -290.273686) (xy 434.208689 -290.328862) (xy 434.192621 -290.382269)
			(xy 434.168949 -290.432766) (xy 434.138176 -290.479279) (xy 434.100959 -290.520816) (xy 434.058091 -290.556491)
			(xy 434.010485 -290.585545) (xy 433.959156 -290.607357) (xy 433.905199 -290.621463) (xy 433.849762 -290.627563)
			(xy 433.794028 -290.625526) (xy 433.739185 -290.615396) (xy 433.686401 -290.597389) (xy 433.636801 -290.571888)
			(xy 433.591443 -290.539437) (xy 433.551294 -290.500728) (xy 433.517208 -290.456585) (xy 433.489912 -290.40795)
			(xy 433.469989 -290.355859) (xy 433.457863 -290.301422) (xy 433.453792 -290.2458) (xy 432.837082 -290.2458)
			(xy 432.837082 -290.449508) (xy 432.837506 -290.459578) (xy 432.84522 -290.478182) (xy 432.852068 -290.485576)
			(xy 433.775104 -291.408612) (xy 433.782499 -291.415467) (xy 433.801098 -291.423214) (xy 433.811172 -291.423598)
		)
		(stroke
			(width 0)
			(type solid)
		)
		(fill yes)
		(layer "In15.Cu")
		(net "P3V3_AUX")
	)
	(gr_poly
		(pts
			(xy 282.895802 -416.760152) (xy 282.905871 -416.759727) (xy 282.92447 -416.752007) (xy 282.93187 -416.745166)
			(xy 283.30017 -416.376866) (xy 283.307014 -416.369467) (xy 283.314741 -416.350869) (xy 283.315156 -416.340798)
			(xy 283.315156 -393.145518) (xy 283.314607 -393.133695) (xy 283.304144 -393.112499) (xy 283.29509 -393.104878)
			(xy 283.152596 -392.996674) (xy 283.120443 -392.971713) (xy 283.059863 -392.917335) (xy 283.003916 -392.858202)
			(xy 282.952974 -392.794706) (xy 282.929838 -392.761216) (xy 282.924894 -392.754567) (xy 282.911681 -392.744586)
			(xy 282.90393 -392.741658) (xy 282.865356 -392.728293) (xy 282.790326 -392.696099) (xy 282.718177 -392.657885)
			(xy 282.649391 -392.613905) (xy 282.616656 -392.589512) (xy 282.222194 -392.289538) (xy 282.189567 -392.264211)
			(xy 282.128167 -392.208957) (xy 282.071542 -392.148818) (xy 282.020082 -392.084205) (xy 281.974137 -392.01556)
			(xy 281.953716 -391.979658) (xy 281.948636 -391.97026) (xy 280.260552 -390.687814) (xy 280.227028 -390.661797)
			(xy 280.164053 -390.604908) (xy 280.10614 -390.542874) (xy 280.053707 -390.476142) (xy 280.007135 -390.405197)
			(xy 279.96676 -390.330551) (xy 279.949402 -390.291828) (xy 279.5524 -389.379968) (xy 279.543764 -389.3693)
			(xy 279.537668 -389.365236) (xy 279.516427 -389.349867) (xy 279.477962 -389.314241) (xy 279.444735 -389.273686)
			(xy 279.417369 -389.228966) (xy 279.396382 -389.180922) (xy 279.382166 -389.130457) (xy 279.37499 -389.078522)
			(xy 279.3746 -389.052308) (xy 279.374737 -389.038927) (xy 279.376644 -389.012233) (xy 279.37841 -388.998968)
			(xy 279.379426 -388.991856) (xy 279.377394 -388.978394) (xy 278.99614 -388.102348) (xy 278.990644 -388.091598)
			(xy 278.971962 -388.076355) (xy 278.960326 -388.073138) (xy 278.86787 -388.052818) (xy 278.844756 -388.05866)
			(xy 278.835358 -388.067042) (xy 278.814314 -388.085075) (xy 278.767994 -388.115498) (xy 278.717757 -388.138896)
			(xy 278.664663 -388.154775) (xy 278.609829 -388.1628) (xy 278.58212 -388.163308) (xy 278.554866 -388.162846)
			(xy 278.500913 -388.155091) (xy 278.448613 -388.139737) (xy 278.39903 -388.117096) (xy 278.353175 -388.087628)
			(xy 278.31198 -388.051935) (xy 278.276284 -388.010741) (xy 278.246814 -387.964887) (xy 278.22417 -387.915306)
			(xy 278.208813 -387.863006) (xy 278.201055 -387.809054) (xy 278.200612 -387.7818) (xy 278.201117 -387.753645)
			(xy 278.209397 -387.697946) (xy 278.225777 -387.64407) (xy 278.2499 -387.593188) (xy 278.281244 -387.546406)
			(xy 278.319125 -387.504741) (xy 278.362721 -387.4691) (xy 278.411084 -387.440256) (xy 278.463162 -387.418837)
			(xy 278.517824 -387.405308) (xy 278.545798 -387.40207) (xy 278.558244 -387.4008) (xy 278.578564 -387.387846)
			(xy 278.62657 -387.306312) (xy 278.63207 -387.295613) (xy 278.633514 -387.271631) (xy 278.629364 -387.260338)
			(xy 278.288242 -386.477002) (xy 278.269899 -386.433514) (xy 278.240551 -386.343801) (xy 278.219818 -386.251716)
			(xy 278.213312 -386.204968) (xy 278.031448 -384.781552) (xy 278.015192 -384.760216) (xy 278.002492 -384.754882)
			(xy 277.976892 -384.743571) (xy 277.929033 -384.714557) (xy 277.885921 -384.678868) (xy 277.84848 -384.637269)
			(xy 277.81751 -384.590652) (xy 277.793676 -384.540014) (xy 277.777488 -384.486439) (xy 277.769292 -384.431075)
			(xy 277.768812 -384.403092) (xy 277.769336 -384.373856) (xy 277.778249 -384.316068) (xy 277.795879 -384.260318)
			(xy 277.821814 -384.207913) (xy 277.855446 -384.160082) (xy 277.895985 -384.117946) (xy 277.918926 -384.099816)
			(xy 277.929848 -384.091434) (xy 277.940262 -384.066542) (xy 277.64359 -381.744982) (xy 277.642045 -381.735911)
			(xy 277.633447 -381.719657) (xy 277.619673 -381.707475) (xy 277.60249 -381.700929) (xy 277.593298 -381.700532)
			(xy 276.42566 -381.700532) (xy 276.415594 -381.700963) (xy 276.397003 -381.708691) (xy 276.389592 -381.715518)
			(xy 274.864576 -383.240534) (xy 274.857179 -383.247384) (xy 274.838581 -383.25512) (xy 274.828508 -383.25552)
			(xy 274.52574 -383.25552) (xy 274.512786 -383.258822) (xy 274.507198 -383.262124) (xy 274.426641 -383.3077)
			(xy 274.262794 -383.39384) (xy 274.096016 -383.474158) (xy 273.926514 -383.548554) (xy 273.754497 -383.616936)
			(xy 273.667474 -383.648458) (xy 273.657825 -383.652443) (xy 273.642582 -383.666679) (xy 273.634218 -383.685785)
			(xy 273.633692 -383.69621) (xy 273.633692 -387.752082) (xy 274.772374 -387.752082) (xy 274.77286 -387.724831)
			(xy 274.780616 -387.670883) (xy 274.795971 -387.618588) (xy 274.818613 -387.569011) (xy 274.848079 -387.523161)
			(xy 274.88377 -387.48197) (xy 274.924961 -387.446279) (xy 274.970811 -387.416813) (xy 275.020388 -387.394171)
			(xy 275.072683 -387.378816) (xy 275.126631 -387.37106) (xy 275.181133 -387.37106) (xy 275.235081 -387.378816)
			(xy 275.287376 -387.394171) (xy 275.336953 -387.416813) (xy 275.382803 -387.446279) (xy 275.423994 -387.48197)
			(xy 275.459685 -387.523161) (xy 275.489151 -387.569011) (xy 275.511793 -387.618588) (xy 275.527148 -387.670883)
			(xy 275.534904 -387.724831) (xy 275.53539 -387.752082) (xy 275.534896 -387.779556) (xy 275.527006 -387.833936)
			(xy 275.511388 -387.886618) (xy 275.488365 -387.936511) (xy 275.458415 -387.98258) (xy 275.440648 -388.003542)
			(xy 275.431935 -388.014333) (xy 275.419948 -388.039323) (xy 275.41512 -388.066616) (xy 275.417806 -388.094202)
			(xy 275.427809 -388.120051) (xy 275.444392 -388.14226) (xy 275.466334 -388.159194) (xy 275.479002 -388.164832)
			(xy 275.505069 -388.175866) (xy 275.553838 -388.2046) (xy 275.597824 -388.240227) (xy 275.636062 -388.281963)
			(xy 275.644431 -388.294372) (xy 276.866348 -388.294372) (xy 276.870419 -388.23875) (xy 276.882545 -388.184313)
			(xy 276.902468 -388.132222) (xy 276.929764 -388.083587) (xy 276.96385 -388.039444) (xy 277.003999 -388.000735)
			(xy 277.049357 -387.968284) (xy 277.098957 -387.942783) (xy 277.151741 -387.924776) (xy 277.206584 -387.914646)
			(xy 277.262318 -387.912609) (xy 277.317755 -387.918709) (xy 277.371712 -387.932815) (xy 277.423041 -387.954627)
			(xy 277.470647 -387.983681) (xy 277.513515 -388.019356) (xy 277.550732 -388.060893) (xy 277.581505 -388.107406)
			(xy 277.605177 -388.157903) (xy 277.621245 -388.21131) (xy 277.629365 -388.266486) (xy 277.629874 -388.294372)
			(xy 277.629365 -388.322258) (xy 277.621245 -388.377434) (xy 277.605177 -388.430841) (xy 277.581505 -388.481338)
			(xy 277.550732 -388.527851) (xy 277.513515 -388.569388) (xy 277.470647 -388.605063) (xy 277.423041 -388.634117)
			(xy 277.371712 -388.655929) (xy 277.317755 -388.670035) (xy 277.262318 -388.676135) (xy 277.206584 -388.674098)
			(xy 277.151741 -388.663968) (xy 277.098957 -388.645961) (xy 277.049357 -388.62046) (xy 277.003999 -388.588009)
			(xy 276.96385 -388.5493) (xy 276.929764 -388.505157) (xy 276.902468 -388.456522) (xy 276.882545 -388.404431)
			(xy 276.870419 -388.349994) (xy 276.866348 -388.294372) (xy 275.644431 -388.294372) (xy 275.667712 -388.328892)
			(xy 275.692079 -388.379983) (xy 275.708627 -388.434115) (xy 275.716992 -388.490098) (xy 275.717508 -388.5184)
			(xy 275.717022 -388.545651) (xy 275.709266 -388.599599) (xy 275.693911 -388.651894) (xy 275.671269 -388.701471)
			(xy 275.641803 -388.747321) (xy 275.606112 -388.788512) (xy 275.564921 -388.824203) (xy 275.519071 -388.853669)
			(xy 275.469494 -388.876311) (xy 275.417199 -388.891666) (xy 275.363251 -388.899422) (xy 275.308749 -388.899422)
			(xy 275.254801 -388.891666) (xy 275.202506 -388.876311) (xy 275.152929 -388.853669) (xy 275.107079 -388.824203)
			(xy 275.065888 -388.788512) (xy 275.030197 -388.747321) (xy 275.000731 -388.701471) (xy 274.978089 -388.651894)
			(xy 274.962734 -388.599599) (xy 274.954978 -388.545651) (xy 274.954492 -388.5184) (xy 274.95498 -388.490925)
			(xy 274.962872 -388.436546) (xy 274.978492 -388.383864) (xy 275.001516 -388.333971) (xy 275.031467 -388.287902)
			(xy 275.049234 -388.26694) (xy 275.057975 -388.25617) (xy 275.069963 -388.231174) (xy 275.07479 -388.203875)
			(xy 275.0721 -388.176283) (xy 275.062092 -388.15043) (xy 275.045502 -388.12822) (xy 275.023552 -388.111287)
			(xy 275.01088 -388.10565) (xy 274.984839 -388.094559) (xy 274.936074 -388.06583) (xy 274.892089 -388.030211)
			(xy 274.85385 -387.988483) (xy 274.822198 -387.941563) (xy 274.797826 -387.89048) (xy 274.781271 -387.836357)
			(xy 274.772895 -387.780381) (xy 274.772374 -387.752082) (xy 273.633692 -387.752082) (xy 273.633692 -389.0264)
			(xy 277.811482 -389.0264) (xy 277.815553 -388.970778) (xy 277.827679 -388.916341) (xy 277.847602 -388.86425)
			(xy 277.874898 -388.815615) (xy 277.908984 -388.771472) (xy 277.949133 -388.732763) (xy 277.994491 -388.700312)
			(xy 278.044091 -388.674811) (xy 278.096875 -388.656804) (xy 278.151718 -388.646674) (xy 278.207452 -388.644637)
			(xy 278.262889 -388.650737) (xy 278.316846 -388.664843) (xy 278.368175 -388.686655) (xy 278.415781 -388.715709)
			(xy 278.458649 -388.751384) (xy 278.495866 -388.792921) (xy 278.526639 -388.839434) (xy 278.550311 -388.889931)
			(xy 278.566379 -388.943338) (xy 278.574499 -388.998514) (xy 278.575008 -389.0264) (xy 278.574499 -389.054286)
			(xy 278.566379 -389.109462) (xy 278.550311 -389.162869) (xy 278.526639 -389.213366) (xy 278.495866 -389.259879)
			(xy 278.458649 -389.301416) (xy 278.415781 -389.337091) (xy 278.368175 -389.366145) (xy 278.316846 -389.387957)
			(xy 278.262889 -389.402063) (xy 278.207452 -389.408163) (xy 278.151718 -389.406126) (xy 278.096875 -389.395996)
			(xy 278.044091 -389.377989) (xy 277.994491 -389.352488) (xy 277.949133 -389.320037) (xy 277.908984 -389.281328)
			(xy 277.874898 -389.237185) (xy 277.847602 -389.18855) (xy 277.827679 -389.136459) (xy 277.815553 -389.082022)
			(xy 277.811482 -389.0264) (xy 273.633692 -389.0264) (xy 273.633692 -389.9916) (xy 278.200102 -389.9916)
			(xy 278.204173 -389.935978) (xy 278.216299 -389.881541) (xy 278.236222 -389.82945) (xy 278.263518 -389.780815)
			(xy 278.297604 -389.736672) (xy 278.337753 -389.697963) (xy 278.383111 -389.665512) (xy 278.432711 -389.640011)
			(xy 278.485495 -389.622004) (xy 278.540338 -389.611874) (xy 278.596072 -389.609837) (xy 278.651509 -389.615937)
			(xy 278.705466 -389.630043) (xy 278.756795 -389.651855) (xy 278.804401 -389.680909) (xy 278.847269 -389.716584)
			(xy 278.884486 -389.758121) (xy 278.915259 -389.804634) (xy 278.938931 -389.855131) (xy 278.954999 -389.908538)
			(xy 278.963119 -389.963714) (xy 278.963628 -389.9916) (xy 278.963119 -390.019486) (xy 278.954999 -390.074662)
			(xy 278.938931 -390.128069) (xy 278.915259 -390.178566) (xy 278.884486 -390.225079) (xy 278.847269 -390.266616)
			(xy 278.804401 -390.302291) (xy 278.756795 -390.331345) (xy 278.705466 -390.353157) (xy 278.651509 -390.367263)
			(xy 278.596072 -390.373363) (xy 278.540338 -390.371326) (xy 278.485495 -390.361196) (xy 278.432711 -390.343189)
			(xy 278.383111 -390.317688) (xy 278.337753 -390.285237) (xy 278.297604 -390.246528) (xy 278.263518 -390.202385)
			(xy 278.236222 -390.15375) (xy 278.216299 -390.101659) (xy 278.204173 -390.047222) (xy 278.200102 -389.9916)
			(xy 273.633692 -389.9916) (xy 273.633692 -392.7602) (xy 276.865332 -392.7602) (xy 276.869403 -392.704578)
			(xy 276.881529 -392.650141) (xy 276.901452 -392.59805) (xy 276.928748 -392.549415) (xy 276.962834 -392.505272)
			(xy 277.002983 -392.466563) (xy 277.048341 -392.434112) (xy 277.097941 -392.408611) (xy 277.150725 -392.390604)
			(xy 277.205568 -392.380474) (xy 277.261302 -392.378437) (xy 277.316739 -392.384537) (xy 277.370696 -392.398643)
			(xy 277.422025 -392.420455) (xy 277.469631 -392.449509) (xy 277.512499 -392.485184) (xy 277.549716 -392.526721)
			(xy 277.580489 -392.573234) (xy 277.604161 -392.623731) (xy 277.620229 -392.677138) (xy 277.628079 -392.730482)
			(xy 278.6667 -392.730482) (xy 278.670771 -392.67486) (xy 278.682897 -392.620423) (xy 278.70282 -392.568332)
			(xy 278.730116 -392.519697) (xy 278.764202 -392.475554) (xy 278.804351 -392.436845) (xy 278.849709 -392.404394)
			(xy 278.899309 -392.378893) (xy 278.952093 -392.360886) (xy 279.006936 -392.350756) (xy 279.06267 -392.348719)
			(xy 279.118107 -392.354819) (xy 279.172064 -392.368925) (xy 279.223393 -392.390737) (xy 279.270999 -392.419791)
			(xy 279.313867 -392.455466) (xy 279.351084 -392.497003) (xy 279.381857 -392.543516) (xy 279.405529 -392.594013)
			(xy 279.421597 -392.64742) (xy 279.429717 -392.702596) (xy 279.430226 -392.730482) (xy 279.429717 -392.758368)
			(xy 279.421597 -392.813544) (xy 279.405529 -392.866951) (xy 279.381857 -392.917448) (xy 279.351084 -392.963961)
			(xy 279.313867 -393.005498) (xy 279.270999 -393.041173) (xy 279.223393 -393.070227) (xy 279.172064 -393.092039)
			(xy 279.118107 -393.106145) (xy 279.06267 -393.112245) (xy 279.006936 -393.110208) (xy 278.952093 -393.100078)
			(xy 278.899309 -393.082071) (xy 278.849709 -393.05657) (xy 278.804351 -393.024119) (xy 278.764202 -392.98541)
			(xy 278.730116 -392.941267) (xy 278.70282 -392.892632) (xy 278.682897 -392.840541) (xy 278.670771 -392.786104)
			(xy 278.6667 -392.730482) (xy 277.628079 -392.730482) (xy 277.628349 -392.732314) (xy 277.628858 -392.7602)
			(xy 277.628349 -392.788086) (xy 277.620229 -392.843262) (xy 277.604161 -392.896669) (xy 277.580489 -392.947166)
			(xy 277.549716 -392.993679) (xy 277.512499 -393.035216) (xy 277.469631 -393.070891) (xy 277.422025 -393.099945)
			(xy 277.370696 -393.121757) (xy 277.316739 -393.135863) (xy 277.261302 -393.141963) (xy 277.205568 -393.139926)
			(xy 277.150725 -393.129796) (xy 277.097941 -393.111789) (xy 277.048341 -393.086288) (xy 277.002983 -393.053837)
			(xy 276.962834 -393.015128) (xy 276.928748 -392.970985) (xy 276.901452 -392.92235) (xy 276.881529 -392.870259)
			(xy 276.869403 -392.815822) (xy 276.865332 -392.7602) (xy 273.633692 -392.7602) (xy 273.633692 -394.762482)
			(xy 276.700486 -394.762482) (xy 276.704557 -394.70686) (xy 276.716683 -394.652423) (xy 276.736606 -394.600332)
			(xy 276.763902 -394.551697) (xy 276.797988 -394.507554) (xy 276.838137 -394.468845) (xy 276.883495 -394.436394)
			(xy 276.933095 -394.410893) (xy 276.985879 -394.392886) (xy 277.040722 -394.382756) (xy 277.096456 -394.380719)
			(xy 277.151893 -394.386819) (xy 277.20585 -394.400925) (xy 277.257179 -394.422737) (xy 277.304785 -394.451791)
			(xy 277.347653 -394.487466) (xy 277.38487 -394.529003) (xy 277.415643 -394.575516) (xy 277.439315 -394.626013)
			(xy 277.455383 -394.67942) (xy 277.463503 -394.734596) (xy 277.464012 -394.762482) (xy 279.240486 -394.762482)
			(xy 279.244557 -394.70686) (xy 279.256683 -394.652423) (xy 279.276606 -394.600332) (xy 279.303902 -394.551697)
			(xy 279.337988 -394.507554) (xy 279.378137 -394.468845) (xy 279.423495 -394.436394) (xy 279.473095 -394.410893)
			(xy 279.525879 -394.392886) (xy 279.580722 -394.382756) (xy 279.636456 -394.380719) (xy 279.691893 -394.386819)
			(xy 279.74585 -394.400925) (xy 279.797179 -394.422737) (xy 279.844785 -394.451791) (xy 279.887653 -394.487466)
			(xy 279.92487 -394.529003) (xy 279.955643 -394.575516) (xy 279.979315 -394.626013) (xy 279.995383 -394.67942)
			(xy 280.003503 -394.734596) (xy 280.004012 -394.762482) (xy 280.003503 -394.790368) (xy 279.995383 -394.845544)
			(xy 279.979315 -394.898951) (xy 279.955643 -394.949448) (xy 279.92487 -394.995961) (xy 279.887653 -395.037498)
			(xy 279.844785 -395.073173) (xy 279.797179 -395.102227) (xy 279.74585 -395.124039) (xy 279.691893 -395.138145)
			(xy 279.636456 -395.144245) (xy 279.580722 -395.142208) (xy 279.525879 -395.132078) (xy 279.473095 -395.114071)
			(xy 279.423495 -395.08857) (xy 279.378137 -395.056119) (xy 279.337988 -395.01741) (xy 279.303902 -394.973267)
			(xy 279.276606 -394.924632) (xy 279.256683 -394.872541) (xy 279.244557 -394.818104) (xy 279.240486 -394.762482)
			(xy 277.464012 -394.762482) (xy 277.463503 -394.790368) (xy 277.455383 -394.845544) (xy 277.439315 -394.898951)
			(xy 277.415643 -394.949448) (xy 277.38487 -394.995961) (xy 277.347653 -395.037498) (xy 277.304785 -395.073173)
			(xy 277.257179 -395.102227) (xy 277.20585 -395.124039) (xy 277.151893 -395.138145) (xy 277.096456 -395.144245)
			(xy 277.040722 -395.142208) (xy 276.985879 -395.132078) (xy 276.933095 -395.114071) (xy 276.883495 -395.08857)
			(xy 276.838137 -395.056119) (xy 276.797988 -395.01741) (xy 276.763902 -394.973267) (xy 276.736606 -394.924632)
			(xy 276.716683 -394.872541) (xy 276.704557 -394.818104) (xy 276.700486 -394.762482) (xy 273.633692 -394.762482)
			(xy 273.633692 -395.6431) (xy 273.633269 -395.65317) (xy 273.625553 -395.671774) (xy 273.618706 -395.679168)
			(xy 272.727674 -396.5702) (xy 276.876508 -396.5702) (xy 276.880579 -396.514578) (xy 276.892705 -396.460141)
			(xy 276.912628 -396.40805) (xy 276.939924 -396.359415) (xy 276.97401 -396.315272) (xy 277.014159 -396.276563)
			(xy 277.059517 -396.244112) (xy 277.109117 -396.218611) (xy 277.161901 -396.200604) (xy 277.216744 -396.190474)
			(xy 277.272478 -396.188437) (xy 277.327915 -396.194537) (xy 277.381872 -396.208643) (xy 277.433201 -396.230455)
			(xy 277.480807 -396.259509) (xy 277.523675 -396.295184) (xy 277.560892 -396.336721) (xy 277.591665 -396.383234)
			(xy 277.615337 -396.433731) (xy 277.631405 -396.487138) (xy 277.638134 -396.532862) (xy 278.858216 -396.532862)
			(xy 278.862287 -396.47724) (xy 278.874413 -396.422803) (xy 278.894336 -396.370712) (xy 278.921632 -396.322077)
			(xy 278.955718 -396.277934) (xy 278.995867 -396.239225) (xy 279.041225 -396.206774) (xy 279.090825 -396.181273)
			(xy 279.143609 -396.163266) (xy 279.198452 -396.153136) (xy 279.254186 -396.151099) (xy 279.309623 -396.157199)
			(xy 279.36358 -396.171305) (xy 279.414909 -396.193117) (xy 279.462515 -396.222171) (xy 279.505383 -396.257846)
			(xy 279.5426 -396.299383) (xy 279.573373 -396.345896) (xy 279.597045 -396.396393) (xy 279.613113 -396.4498)
			(xy 279.621233 -396.504976) (xy 279.621742 -396.532862) (xy 279.621233 -396.560748) (xy 279.613113 -396.615924)
			(xy 279.597045 -396.669331) (xy 279.573373 -396.719828) (xy 279.5426 -396.766341) (xy 279.505383 -396.807878)
			(xy 279.462515 -396.843553) (xy 279.414909 -396.872607) (xy 279.36358 -396.894419) (xy 279.309623 -396.908525)
			(xy 279.254186 -396.914625) (xy 279.198452 -396.912588) (xy 279.143609 -396.902458) (xy 279.090825 -396.884451)
			(xy 279.041225 -396.85895) (xy 278.995867 -396.826499) (xy 278.955718 -396.78779) (xy 278.921632 -396.743647)
			(xy 278.894336 -396.695012) (xy 278.874413 -396.642921) (xy 278.862287 -396.588484) (xy 278.858216 -396.532862)
			(xy 277.638134 -396.532862) (xy 277.639525 -396.542314) (xy 277.640034 -396.5702) (xy 277.639525 -396.598086)
			(xy 277.631405 -396.653262) (xy 277.615337 -396.706669) (xy 277.591665 -396.757166) (xy 277.560892 -396.803679)
			(xy 277.523675 -396.845216) (xy 277.480807 -396.880891) (xy 277.433201 -396.909945) (xy 277.381872 -396.931757)
			(xy 277.327915 -396.945863) (xy 277.272478 -396.951963) (xy 277.216744 -396.949926) (xy 277.161901 -396.939796)
			(xy 277.109117 -396.921789) (xy 277.059517 -396.896288) (xy 277.014159 -396.863837) (xy 276.97401 -396.825128)
			(xy 276.939924 -396.780985) (xy 276.912628 -396.73235) (xy 276.892705 -396.680259) (xy 276.880579 -396.625822)
			(xy 276.876508 -396.5702) (xy 272.727674 -396.5702) (xy 271.364202 -397.933672) (xy 279.755598 -397.933672)
			(xy 279.759669 -397.87805) (xy 279.771795 -397.823613) (xy 279.791718 -397.771522) (xy 279.819014 -397.722887)
			(xy 279.8531 -397.678744) (xy 279.893249 -397.640035) (xy 279.938607 -397.607584) (xy 279.988207 -397.582083)
			(xy 280.040991 -397.564076) (xy 280.095834 -397.553946) (xy 280.151568 -397.551909) (xy 280.207005 -397.558009)
			(xy 280.260962 -397.572115) (xy 280.312291 -397.593927) (xy 280.359897 -397.622981) (xy 280.402765 -397.658656)
			(xy 280.439982 -397.700193) (xy 280.470755 -397.746706) (xy 280.494427 -397.797203) (xy 280.510495 -397.85061)
			(xy 280.518615 -397.905786) (xy 280.519124 -397.933672) (xy 280.518615 -397.961558) (xy 280.510495 -398.016734)
			(xy 280.494427 -398.070141) (xy 280.470755 -398.120638) (xy 280.439982 -398.167151) (xy 280.402765 -398.208688)
			(xy 280.359897 -398.244363) (xy 280.312291 -398.273417) (xy 280.260962 -398.295229) (xy 280.207005 -398.309335)
			(xy 280.151568 -398.315435) (xy 280.095834 -398.313398) (xy 280.040991 -398.303268) (xy 279.988207 -398.285261)
			(xy 279.938607 -398.25976) (xy 279.893249 -398.227309) (xy 279.8531 -398.1886) (xy 279.819014 -398.144457)
			(xy 279.791718 -398.095822) (xy 279.771795 -398.043731) (xy 279.759669 -397.989294) (xy 279.755598 -397.933672)
			(xy 271.364202 -397.933672) (xy 270.642588 -398.655286) (xy 270.635189 -398.662132) (xy 270.616591 -398.669864)
			(xy 270.60652 -398.670272) (xy 266.490196 -398.670272) (xy 266.480127 -398.669848) (xy 266.461526 -398.662129)
			(xy 266.454128 -398.655286) (xy 265.255248 -397.456406) (xy 265.251438 -397.453866) (xy 265.168904 -397.397403)
			(xy 265.007689 -397.279048) (xy 264.85109 -397.154649) (xy 264.699334 -397.024385) (xy 264.552641 -396.888446)
			(xy 264.411224 -396.747027) (xy 264.275285 -396.600333) (xy 264.145023 -396.448576) (xy 264.020625 -396.291976)
			(xy 263.902271 -396.130759) (xy 263.845802 -396.04823) (xy 263.843262 -396.04442) (xy 260.179312 -392.38047)
			(xy 260.171918 -392.373614) (xy 260.153319 -392.365864) (xy 260.143244 -392.365484) (xy 254.991616 -392.365484)
			(xy 254.981552 -392.365922) (xy 254.962968 -392.373656) (xy 254.955548 -392.38047) (xy 254.616204 -392.719814)
			(xy 254.60936 -392.727213) (xy 254.60163 -392.745811) (xy 254.601218 -392.755882) (xy 254.601218 -398.261586)
			(xy 254.60078 -398.27165) (xy 254.593045 -398.290233) (xy 254.586232 -398.297654) (xy 253.591568 -399.292318)
			(xy 253.584172 -399.299168) (xy 253.565573 -399.306904) (xy 253.5555 -399.307304) (xy 245.784878 -399.307304)
			(xy 245.77481 -399.307731) (xy 245.756211 -399.315452) (xy 245.74881 -399.32229) (xy 245.100348 -399.970752)
			(xy 245.093505 -399.978151) (xy 245.085782 -399.99675) (xy 245.085362 -400.00682) (xy 245.085362 -401.132802)
			(xy 245.084938 -401.142871) (xy 245.077219 -401.161472) (xy 245.070376 -401.16887) (xy 245.066058 -401.173188)
			(xy 277.12035 -401.173188) (xy 277.120836 -401.145937) (xy 277.128592 -401.091989) (xy 277.143947 -401.039694)
			(xy 277.166589 -400.990117) (xy 277.196055 -400.944267) (xy 277.231746 -400.903076) (xy 277.272937 -400.867385)
			(xy 277.318787 -400.837919) (xy 277.368364 -400.815277) (xy 277.420659 -400.799922) (xy 277.474607 -400.792166)
			(xy 277.529109 -400.792166) (xy 277.583057 -400.799922) (xy 277.635352 -400.815277) (xy 277.684929 -400.837919)
			(xy 277.730779 -400.867385) (xy 277.77197 -400.903076) (xy 277.807661 -400.944267) (xy 277.837127 -400.990117)
			(xy 277.859769 -401.039694) (xy 277.875124 -401.091989) (xy 277.88288 -401.145937) (xy 277.882895 -401.146772)
			(xy 279.138886 -401.146772) (xy 279.142957 -401.09115) (xy 279.155083 -401.036713) (xy 279.175006 -400.984622)
			(xy 279.202302 -400.935987) (xy 279.236388 -400.891844) (xy 279.276537 -400.853135) (xy 279.321895 -400.820684)
			(xy 279.371495 -400.795183) (xy 279.424279 -400.777176) (xy 279.479122 -400.767046) (xy 279.534856 -400.765009)
			(xy 279.590293 -400.771109) (xy 279.64425 -400.785215) (xy 279.695579 -400.807027) (xy 279.743185 -400.836081)
			(xy 279.786053 -400.871756) (xy 279.82327 -400.913293) (xy 279.854043 -400.959806) (xy 279.877715 -401.010303)
			(xy 279.893783 -401.06371) (xy 279.901903 -401.118886) (xy 279.902412 -401.146772) (xy 279.901903 -401.174658)
			(xy 279.893783 -401.229834) (xy 279.877715 -401.283241) (xy 279.854043 -401.333738) (xy 279.82327 -401.380251)
			(xy 279.786053 -401.421788) (xy 279.743185 -401.457463) (xy 279.695579 -401.486517) (xy 279.64425 -401.508329)
			(xy 279.590293 -401.522435) (xy 279.534856 -401.528535) (xy 279.479122 -401.526498) (xy 279.424279 -401.516368)
			(xy 279.371495 -401.498361) (xy 279.321895 -401.47286) (xy 279.276537 -401.440409) (xy 279.236388 -401.4017)
			(xy 279.202302 -401.357557) (xy 279.175006 -401.308922) (xy 279.155083 -401.256831) (xy 279.142957 -401.202394)
			(xy 279.138886 -401.146772) (xy 277.882895 -401.146772) (xy 277.883366 -401.173188) (xy 277.882782 -401.204)
			(xy 277.872891 -401.264824) (xy 277.853365 -401.323272) (xy 277.824709 -401.377827) (xy 277.806658 -401.402804)
			(xy 277.79821 -401.41486) (xy 277.787947 -401.442437) (xy 277.785972 -401.471796) (xy 277.79245 -401.5005)
			(xy 277.806842 -401.526165) (xy 277.827953 -401.546663) (xy 277.854033 -401.56029) (xy 277.86838 -401.563586)
			(xy 277.894092 -401.569098) (xy 277.943829 -401.586165) (xy 277.990751 -401.609903) (xy 278.033966 -401.63986)
			(xy 278.072657 -401.675471) (xy 278.10609 -401.716058) (xy 278.133631 -401.760853) (xy 278.154757 -401.809006)
			(xy 278.169069 -401.859605) (xy 278.176294 -401.91169) (xy 278.176736 -401.937982) (xy 278.17625 -401.965233)
			(xy 278.168494 -402.019181) (xy 278.153139 -402.071476) (xy 278.130497 -402.121053) (xy 278.101031 -402.166903)
			(xy 278.06534 -402.208094) (xy 278.024149 -402.243785) (xy 277.978299 -402.273251) (xy 277.928722 -402.295893)
			(xy 277.876427 -402.311248) (xy 277.822479 -402.319004) (xy 277.767977 -402.319004) (xy 277.714029 -402.311248)
			(xy 277.661734 -402.295893) (xy 277.612157 -402.273251) (xy 277.566307 -402.243785) (xy 277.525116 -402.208094)
			(xy 277.489425 -402.166903) (xy 277.459959 -402.121053) (xy 277.437317 -402.071476) (xy 277.421962 -402.019181)
			(xy 277.414206 -401.965233) (xy 277.41372 -401.937982) (xy 277.414291 -401.90717) (xy 277.424186 -401.846345)
			(xy 277.443716 -401.787898) (xy 277.472376 -401.733343) (xy 277.490428 -401.708366) (xy 277.498921 -401.696339)
			(xy 277.509183 -401.668752) (xy 277.511153 -401.639385) (xy 277.504669 -401.610674) (xy 277.490269 -401.585004)
			(xy 277.469147 -401.564505) (xy 277.443058 -401.550878) (xy 277.428706 -401.547584) (xy 277.402985 -401.542111)
			(xy 277.353246 -401.52504) (xy 277.306323 -401.501298) (xy 277.263107 -401.471336) (xy 277.224416 -401.435721)
			(xy 277.190984 -401.39513) (xy 277.163445 -401.35033) (xy 277.142321 -401.302173) (xy 277.128012 -401.25157)
			(xy 277.12079 -401.199481) (xy 277.12035 -401.173188) (xy 245.066058 -401.173188) (xy 244.047772 -402.191474)
			(xy 244.040373 -402.198319) (xy 244.021775 -402.206047) (xy 244.011704 -402.20646) (xy 239.48898 -402.20646)
			(xy 239.478913 -402.206888) (xy 239.460319 -402.214615) (xy 239.452912 -402.221446) (xy 238.291878 -403.38248)
			(xy 238.285036 -403.389879) (xy 238.277318 -403.408478) (xy 238.276892 -403.418548) (xy 238.276892 -403.46249)
			(xy 275.581108 -403.46249) (xy 275.585179 -403.406868) (xy 275.597305 -403.352431) (xy 275.617228 -403.30034)
			(xy 275.644524 -403.251705) (xy 275.67861 -403.207562) (xy 275.718759 -403.168853) (xy 275.764117 -403.136402)
			(xy 275.813717 -403.110901) (xy 275.866501 -403.092894) (xy 275.921344 -403.082764) (xy 275.977078 -403.080727)
			(xy 276.032515 -403.086827) (xy 276.086472 -403.100933) (xy 276.137801 -403.122745) (xy 276.185407 -403.151799)
			(xy 276.228275 -403.187474) (xy 276.265492 -403.229011) (xy 276.296265 -403.275524) (xy 276.319937 -403.326021)
			(xy 276.336005 -403.379428) (xy 276.344125 -403.434604) (xy 276.344634 -403.46249) (xy 276.597108 -403.46249)
			(xy 276.601179 -403.406868) (xy 276.613305 -403.352431) (xy 276.633228 -403.30034) (xy 276.660524 -403.251705)
			(xy 276.69461 -403.207562) (xy 276.734759 -403.168853) (xy 276.780117 -403.136402) (xy 276.829717 -403.110901)
			(xy 276.882501 -403.092894) (xy 276.937344 -403.082764) (xy 276.993078 -403.080727) (xy 277.048515 -403.086827)
			(xy 277.102472 -403.100933) (xy 277.153801 -403.122745) (xy 277.201407 -403.151799) (xy 277.244275 -403.187474)
			(xy 277.281492 -403.229011) (xy 277.312265 -403.275524) (xy 277.335937 -403.326021) (xy 277.352005 -403.379428)
			(xy 277.360125 -403.434604) (xy 277.360634 -403.46249) (xy 277.360125 -403.490376) (xy 277.352005 -403.545552)
			(xy 277.335937 -403.598959) (xy 277.312265 -403.649456) (xy 277.281492 -403.695969) (xy 277.244275 -403.737506)
			(xy 277.201407 -403.773181) (xy 277.153801 -403.802235) (xy 277.102472 -403.824047) (xy 277.048515 -403.838153)
			(xy 276.993078 -403.844253) (xy 276.937344 -403.842216) (xy 276.882501 -403.832086) (xy 276.829717 -403.814079)
			(xy 276.780117 -403.788578) (xy 276.734759 -403.756127) (xy 276.69461 -403.717418) (xy 276.660524 -403.673275)
			(xy 276.633228 -403.62464) (xy 276.613305 -403.572549) (xy 276.601179 -403.518112) (xy 276.597108 -403.46249)
			(xy 276.344634 -403.46249) (xy 276.344125 -403.490376) (xy 276.336005 -403.545552) (xy 276.319937 -403.598959)
			(xy 276.296265 -403.649456) (xy 276.265492 -403.695969) (xy 276.228275 -403.737506) (xy 276.185407 -403.773181)
			(xy 276.137801 -403.802235) (xy 276.086472 -403.824047) (xy 276.032515 -403.838153) (xy 275.977078 -403.844253)
			(xy 275.921344 -403.842216) (xy 275.866501 -403.832086) (xy 275.813717 -403.814079) (xy 275.764117 -403.788578)
			(xy 275.718759 -403.756127) (xy 275.67861 -403.717418) (xy 275.644524 -403.673275) (xy 275.617228 -403.62464)
			(xy 275.597305 -403.572549) (xy 275.585179 -403.518112) (xy 275.581108 -403.46249) (xy 238.276892 -403.46249)
			(xy 238.276892 -403.97049) (xy 278.636984 -403.97049) (xy 278.637515 -403.944067) (xy 278.644823 -403.891728)
			(xy 278.659285 -403.840899) (xy 278.680623 -403.792552) (xy 278.708429 -403.747612) (xy 278.74217 -403.70694)
			(xy 278.781203 -403.671314) (xy 278.824778 -403.641415) (xy 278.872062 -403.617816) (xy 278.922151 -403.600969)
			(xy 278.974086 -403.591195) (xy 279.000458 -403.58949) (xy 279.015759 -403.588239) (xy 279.04459 -403.577725)
			(xy 279.069008 -403.559138) (xy 279.08682 -403.534149) (xy 279.096425 -403.505003) (xy 279.096959 -403.474319)
			(xy 279.093168 -403.459442) (xy 279.085948 -403.43317) (xy 279.078177 -403.379242) (xy 279.077674 -403.352)
			(xy 279.07816 -403.324749) (xy 279.085916 -403.270801) (xy 279.101271 -403.218506) (xy 279.123913 -403.168929)
			(xy 279.153379 -403.123079) (xy 279.18907 -403.081888) (xy 279.230261 -403.046197) (xy 279.276111 -403.016731)
			(xy 279.325688 -402.994089) (xy 279.377983 -402.978734) (xy 279.431931 -402.970978) (xy 279.486433 -402.970978)
			(xy 279.540381 -402.978734) (xy 279.592676 -402.994089) (xy 279.642253 -403.016731) (xy 279.688103 -403.046197)
			(xy 279.729294 -403.081888) (xy 279.764985 -403.123079) (xy 279.794451 -403.168929) (xy 279.817093 -403.218506)
			(xy 279.832448 -403.270801) (xy 279.840204 -403.324749) (xy 279.840613 -403.347682) (xy 280.093164 -403.347682)
			(xy 280.097235 -403.29206) (xy 280.109361 -403.237623) (xy 280.129284 -403.185532) (xy 280.15658 -403.136897)
			(xy 280.190666 -403.092754) (xy 280.230815 -403.054045) (xy 280.276173 -403.021594) (xy 280.325773 -402.996093)
			(xy 280.378557 -402.978086) (xy 280.4334 -402.967956) (xy 280.489134 -402.965919) (xy 280.544571 -402.972019)
			(xy 280.598528 -402.986125) (xy 280.649857 -403.007937) (xy 280.697463 -403.036991) (xy 280.740331 -403.072666)
			(xy 280.777548 -403.114203) (xy 280.808321 -403.160716) (xy 280.831993 -403.211213) (xy 280.848061 -403.26462)
			(xy 280.856181 -403.319796) (xy 280.85669 -403.347682) (xy 280.856181 -403.375568) (xy 280.848061 -403.430744)
			(xy 280.831993 -403.484151) (xy 280.808321 -403.534648) (xy 280.777548 -403.581161) (xy 280.740331 -403.622698)
			(xy 280.697463 -403.658373) (xy 280.649857 -403.687427) (xy 280.598528 -403.709239) (xy 280.544571 -403.723345)
			(xy 280.489134 -403.729445) (xy 280.4334 -403.727408) (xy 280.378557 -403.717278) (xy 280.325773 -403.699271)
			(xy 280.276173 -403.67377) (xy 280.230815 -403.641319) (xy 280.190666 -403.60261) (xy 280.15658 -403.558467)
			(xy 280.129284 -403.509832) (xy 280.109361 -403.457741) (xy 280.097235 -403.403304) (xy 280.093164 -403.347682)
			(xy 279.840613 -403.347682) (xy 279.84069 -403.352) (xy 279.840174 -403.378424) (xy 279.832867 -403.430764)
			(xy 279.818405 -403.481595) (xy 279.797067 -403.529944) (xy 279.76926 -403.574885) (xy 279.735516 -403.615558)
			(xy 279.696482 -403.651184) (xy 279.652904 -403.681082) (xy 279.605617 -403.70468) (xy 279.555526 -403.721526)
			(xy 279.503589 -403.731297) (xy 279.477216 -403.733) (xy 279.461915 -403.734244) (xy 279.433087 -403.744763)
			(xy 279.40867 -403.763352) (xy 279.39086 -403.788342) (xy 279.381255 -403.817488) (xy 279.380718 -403.84817)
			(xy 279.384506 -403.863048) (xy 279.391723 -403.889321) (xy 279.399497 -403.943248) (xy 279.4 -403.97049)
			(xy 279.399514 -403.997741) (xy 279.391758 -404.051689) (xy 279.376403 -404.103984) (xy 279.353761 -404.153561)
			(xy 279.324295 -404.199411) (xy 279.288604 -404.240602) (xy 279.247413 -404.276293) (xy 279.201563 -404.305759)
			(xy 279.151986 -404.328401) (xy 279.099691 -404.343756) (xy 279.045743 -404.351512) (xy 278.991241 -404.351512)
			(xy 278.937293 -404.343756) (xy 278.884998 -404.328401) (xy 278.835421 -404.305759) (xy 278.789571 -404.276293)
			(xy 278.74838 -404.240602) (xy 278.712689 -404.199411) (xy 278.683223 -404.153561) (xy 278.660581 -404.103984)
			(xy 278.645226 -404.051689) (xy 278.63747 -403.997741) (xy 278.636984 -403.97049) (xy 238.276892 -403.97049)
			(xy 238.276892 -404.674324) (xy 274.928582 -404.674324) (xy 274.932653 -404.618702) (xy 274.944779 -404.564265)
			(xy 274.964702 -404.512174) (xy 274.991998 -404.463539) (xy 275.026084 -404.419396) (xy 275.066233 -404.380687)
			(xy 275.111591 -404.348236) (xy 275.161191 -404.322735) (xy 275.213975 -404.304728) (xy 275.268818 -404.294598)
			(xy 275.324552 -404.292561) (xy 275.379989 -404.298661) (xy 275.433946 -404.312767) (xy 275.485275 -404.334579)
			(xy 275.532881 -404.363633) (xy 275.575749 -404.399308) (xy 275.612966 -404.440845) (xy 275.643739 -404.487358)
			(xy 275.667411 -404.537855) (xy 275.683479 -404.591262) (xy 275.691599 -404.646438) (xy 275.692108 -404.674324)
			(xy 275.691599 -404.70221) (xy 275.683479 -404.757386) (xy 275.667411 -404.810793) (xy 275.643739 -404.86129)
			(xy 275.612966 -404.907803) (xy 275.575749 -404.94934) (xy 275.532881 -404.985015) (xy 275.485275 -405.014069)
			(xy 275.433946 -405.035881) (xy 275.379989 -405.049987) (xy 275.324552 -405.056087) (xy 275.268818 -405.05405)
			(xy 275.213975 -405.04392) (xy 275.161191 -405.025913) (xy 275.111591 -405.000412) (xy 275.066233 -404.967961)
			(xy 275.026084 -404.929252) (xy 274.991998 -404.885109) (xy 274.964702 -404.836474) (xy 274.944779 -404.784383)
			(xy 274.932653 -404.729946) (xy 274.928582 -404.674324) (xy 238.276892 -404.674324) (xy 238.276892 -406.147016)
			(xy 275.691598 -406.147016) (xy 275.695669 -406.091394) (xy 275.707795 -406.036957) (xy 275.727718 -405.984866)
			(xy 275.755014 -405.936231) (xy 275.7891 -405.892088) (xy 275.829249 -405.853379) (xy 275.874607 -405.820928)
			(xy 275.924207 -405.795427) (xy 275.976991 -405.77742) (xy 276.031834 -405.76729) (xy 276.087568 -405.765253)
			(xy 276.143005 -405.771353) (xy 276.196962 -405.785459) (xy 276.248291 -405.807271) (xy 276.295897 -405.836325)
			(xy 276.338765 -405.872) (xy 276.375982 -405.913537) (xy 276.406755 -405.96005) (xy 276.430427 -406.010547)
			(xy 276.446495 -406.063954) (xy 276.454615 -406.11913) (xy 276.455124 -406.147016) (xy 276.454615 -406.174902)
			(xy 276.453107 -406.185151) (xy 276.708593 -406.185151) (xy 276.708593 -406.130649) (xy 276.71635 -406.076702)
			(xy 276.731705 -406.024408) (xy 276.754347 -405.974832) (xy 276.783813 -405.928983) (xy 276.819505 -405.887794)
			(xy 276.860695 -405.852104) (xy 276.906546 -405.822639) (xy 276.956123 -405.8) (xy 277.008418 -405.784646)
			(xy 277.062365 -405.776892) (xy 277.089616 -405.77643) (xy 277.118436 -405.776938) (xy 277.175418 -405.785624)
			(xy 277.230446 -405.802782) (xy 277.282267 -405.828021) (xy 277.329703 -405.860766) (xy 277.371675 -405.900274)
			(xy 277.407227 -405.945644) (xy 277.421848 -405.970486) (xy 277.427436 -405.980392) (xy 277.445724 -405.9936)
			(xy 277.544784 -406.011634) (xy 277.566628 -406.006046) (xy 277.575518 -405.99868) (xy 277.596164 -405.982058)
			(xy 277.641186 -405.954089) (xy 277.689649 -405.932626) (xy 277.740618 -405.918084) (xy 277.793111 -405.910743)
			(xy 277.819612 -405.910288) (xy 277.846862 -405.910783) (xy 277.900808 -405.91854) (xy 277.953101 -405.933896)
			(xy 278.002676 -405.956538) (xy 278.048525 -405.986004) (xy 278.089713 -406.021695) (xy 278.125403 -406.062885)
			(xy 278.154868 -406.108734) (xy 278.177508 -406.15831) (xy 278.192862 -406.210603) (xy 278.200618 -406.26455)
			(xy 278.200618 -406.31905) (xy 278.192862 -406.372997) (xy 278.177508 -406.42529) (xy 278.154868 -406.474866)
			(xy 278.125403 -406.520715) (xy 278.089713 -406.561905) (xy 278.048525 -406.597596) (xy 278.002676 -406.627062)
			(xy 277.953101 -406.649704) (xy 277.900808 -406.66506) (xy 277.846862 -406.672817) (xy 277.819612 -406.673304)
			(xy 277.790794 -406.672757) (xy 277.733814 -406.664075) (xy 277.678788 -406.646923) (xy 277.626967 -406.621691)
			(xy 277.579531 -406.588952) (xy 277.537558 -406.549451) (xy 277.502003 -406.504087) (xy 277.48738 -406.479248)
			(xy 277.481792 -406.469342) (xy 277.463504 -406.456134) (xy 277.364444 -406.4381) (xy 277.3426 -406.443688)
			(xy 277.33371 -406.451054) (xy 277.313058 -406.467668) (xy 277.268037 -406.495637) (xy 277.219575 -406.517101)
			(xy 277.168608 -406.531645) (xy 277.116117 -406.538989) (xy 277.089616 -406.539446) (xy 277.062365 -406.538908)
			(xy 277.008418 -406.531154) (xy 276.956123 -406.5158) (xy 276.906546 -406.493161) (xy 276.860695 -406.463696)
			(xy 276.819505 -406.428006) (xy 276.783813 -406.386817) (xy 276.754347 -406.340968) (xy 276.731705 -406.291392)
			(xy 276.71635 -406.239098) (xy 276.708593 -406.185151) (xy 276.453107 -406.185151) (xy 276.446495 -406.230078)
			(xy 276.430427 -406.283485) (xy 276.406755 -406.333982) (xy 276.375982 -406.380495) (xy 276.338765 -406.422032)
			(xy 276.295897 -406.457707) (xy 276.248291 -406.486761) (xy 276.196962 -406.508573) (xy 276.143005 -406.522679)
			(xy 276.087568 -406.528779) (xy 276.031834 -406.526742) (xy 275.976991 -406.516612) (xy 275.924207 -406.498605)
			(xy 275.874607 -406.473104) (xy 275.829249 -406.440653) (xy 275.7891 -406.401944) (xy 275.755014 -406.357801)
			(xy 275.727718 -406.309166) (xy 275.707795 -406.257075) (xy 275.695669 -406.202638) (xy 275.691598 -406.147016)
			(xy 238.276892 -406.147016) (xy 238.276892 -406.551892) (xy 274.490686 -406.551892) (xy 274.494757 -406.49627)
			(xy 274.506883 -406.441833) (xy 274.526806 -406.389742) (xy 274.554102 -406.341107) (xy 274.588188 -406.296964)
			(xy 274.628337 -406.258255) (xy 274.673695 -406.225804) (xy 274.723295 -406.200303) (xy 274.776079 -406.182296)
			(xy 274.830922 -406.172166) (xy 274.886656 -406.170129) (xy 274.942093 -406.176229) (xy 274.99605 -406.190335)
			(xy 275.047379 -406.212147) (xy 275.094985 -406.241201) (xy 275.137853 -406.276876) (xy 275.17507 -406.318413)
			(xy 275.205843 -406.364926) (xy 275.229515 -406.415423) (xy 275.245583 -406.46883) (xy 275.253703 -406.524006)
			(xy 275.254212 -406.551892) (xy 275.253703 -406.579778) (xy 275.245583 -406.634954) (xy 275.229515 -406.688361)
			(xy 275.205843 -406.738858) (xy 275.17507 -406.785371) (xy 275.137853 -406.826908) (xy 275.094985 -406.862583)
			(xy 275.047379 -406.891637) (xy 274.99605 -406.913449) (xy 274.942093 -406.927555) (xy 274.886656 -406.933655)
			(xy 274.830922 -406.931618) (xy 274.776079 -406.921488) (xy 274.723295 -406.903481) (xy 274.673695 -406.87798)
			(xy 274.628337 -406.845529) (xy 274.588188 -406.80682) (xy 274.554102 -406.762677) (xy 274.526806 -406.714042)
			(xy 274.506883 -406.661951) (xy 274.494757 -406.607514) (xy 274.490686 -406.551892) (xy 238.276892 -406.551892)
			(xy 238.276892 -406.943052) (xy 278.739598 -406.943052) (xy 278.743669 -406.88743) (xy 278.755795 -406.832993)
			(xy 278.775718 -406.780902) (xy 278.803014 -406.732267) (xy 278.8371 -406.688124) (xy 278.877249 -406.649415)
			(xy 278.922607 -406.616964) (xy 278.972207 -406.591463) (xy 279.024991 -406.573456) (xy 279.079834 -406.563326)
			(xy 279.135568 -406.561289) (xy 279.191005 -406.567389) (xy 279.244962 -406.581495) (xy 279.296291 -406.603307)
			(xy 279.343897 -406.632361) (xy 279.386765 -406.668036) (xy 279.423982 -406.709573) (xy 279.454755 -406.756086)
			(xy 279.478427 -406.806583) (xy 279.494495 -406.85999) (xy 279.502615 -406.915166) (xy 279.503124 -406.943052)
			(xy 279.502615 -406.970938) (xy 279.494495 -407.026114) (xy 279.478427 -407.079521) (xy 279.454755 -407.130018)
			(xy 279.423982 -407.176531) (xy 279.386765 -407.218068) (xy 279.343897 -407.253743) (xy 279.296291 -407.282797)
			(xy 279.244962 -407.304609) (xy 279.205567 -407.314908) (xy 280.953462 -407.314908) (xy 280.957533 -407.259286)
			(xy 280.969659 -407.204849) (xy 280.989582 -407.152758) (xy 281.016878 -407.104123) (xy 281.050964 -407.05998)
			(xy 281.091113 -407.021271) (xy 281.136471 -406.98882) (xy 281.186071 -406.963319) (xy 281.238855 -406.945312)
			(xy 281.293698 -406.935182) (xy 281.349432 -406.933145) (xy 281.404869 -406.939245) (xy 281.458826 -406.953351)
			(xy 281.510155 -406.975163) (xy 281.557761 -407.004217) (xy 281.600629 -407.039892) (xy 281.637846 -407.081429)
			(xy 281.668619 -407.127942) (xy 281.692291 -407.178439) (xy 281.708359 -407.231846) (xy 281.716479 -407.287022)
			(xy 281.716988 -407.314908) (xy 281.716479 -407.342794) (xy 281.708359 -407.39797) (xy 281.692291 -407.451377)
			(xy 281.668619 -407.501874) (xy 281.637846 -407.548387) (xy 281.600629 -407.589924) (xy 281.557761 -407.625599)
			(xy 281.510155 -407.654653) (xy 281.458826 -407.676465) (xy 281.404869 -407.690571) (xy 281.349432 -407.696671)
			(xy 281.293698 -407.694634) (xy 281.238855 -407.684504) (xy 281.186071 -407.666497) (xy 281.136471 -407.640996)
			(xy 281.091113 -407.608545) (xy 281.050964 -407.569836) (xy 281.016878 -407.525693) (xy 280.989582 -407.477058)
			(xy 280.969659 -407.424967) (xy 280.957533 -407.37053) (xy 280.953462 -407.314908) (xy 279.205567 -407.314908)
			(xy 279.191005 -407.318715) (xy 279.135568 -407.324815) (xy 279.079834 -407.322778) (xy 279.024991 -407.312648)
			(xy 278.972207 -407.294641) (xy 278.922607 -407.26914) (xy 278.877249 -407.236689) (xy 278.8371 -407.19798)
			(xy 278.803014 -407.153837) (xy 278.775718 -407.105202) (xy 278.755795 -407.053111) (xy 278.743669 -406.998674)
			(xy 278.739598 -406.943052) (xy 238.276892 -406.943052) (xy 238.276892 -408.165046) (xy 275.975316 -408.165046)
			(xy 275.979387 -408.109424) (xy 275.991513 -408.054987) (xy 276.011436 -408.002896) (xy 276.038732 -407.954261)
			(xy 276.072818 -407.910118) (xy 276.112967 -407.871409) (xy 276.158325 -407.838958) (xy 276.207925 -407.813457)
			(xy 276.260709 -407.79545) (xy 276.315552 -407.78532) (xy 276.371286 -407.783283) (xy 276.426723 -407.789383)
			(xy 276.48068 -407.803489) (xy 276.532009 -407.825301) (xy 276.579615 -407.854355) (xy 276.622483 -407.89003)
			(xy 276.6597 -407.931567) (xy 276.690473 -407.97808) (xy 276.714145 -408.028577) (xy 276.730213 -408.081984)
			(xy 276.738333 -408.13716) (xy 276.738842 -408.165046) (xy 276.738333 -408.192932) (xy 276.730213 -408.248108)
			(xy 276.714145 -408.301515) (xy 276.690473 -408.352012) (xy 276.6597 -408.398525) (xy 276.622483 -408.440062)
			(xy 276.579615 -408.475737) (xy 276.532009 -408.504791) (xy 276.48068 -408.526603) (xy 276.426723 -408.540709)
			(xy 276.371286 -408.546809) (xy 276.315552 -408.544772) (xy 276.260709 -408.534642) (xy 276.207925 -408.516635)
			(xy 276.158325 -408.491134) (xy 276.112967 -408.458683) (xy 276.072818 -408.419974) (xy 276.038732 -408.375831)
			(xy 276.011436 -408.327196) (xy 275.991513 -408.275105) (xy 275.979387 -408.220668) (xy 275.975316 -408.165046)
			(xy 238.276892 -408.165046) (xy 238.276892 -410.136086) (xy 279.512266 -410.136086) (xy 279.516337 -410.080464)
			(xy 279.528463 -410.026027) (xy 279.548386 -409.973936) (xy 279.575682 -409.925301) (xy 279.609768 -409.881158)
			(xy 279.649917 -409.842449) (xy 279.695275 -409.809998) (xy 279.744875 -409.784497) (xy 279.797659 -409.76649)
			(xy 279.852502 -409.75636) (xy 279.908236 -409.754323) (xy 279.963673 -409.760423) (xy 280.01763 -409.774529)
			(xy 280.068959 -409.796341) (xy 280.116565 -409.825395) (xy 280.159433 -409.86107) (xy 280.19665 -409.902607)
			(xy 280.227423 -409.94912) (xy 280.251095 -409.999617) (xy 280.267163 -410.053024) (xy 280.275283 -410.1082)
			(xy 280.275792 -410.136086) (xy 280.275283 -410.163972) (xy 280.267163 -410.219148) (xy 280.251095 -410.272555)
			(xy 280.227423 -410.323052) (xy 280.19665 -410.369565) (xy 280.159433 -410.411102) (xy 280.116565 -410.446777)
			(xy 280.068959 -410.475831) (xy 280.01763 -410.497643) (xy 279.963673 -410.511749) (xy 279.908236 -410.517849)
			(xy 279.852502 -410.515812) (xy 279.797659 -410.505682) (xy 279.744875 -410.487675) (xy 279.695275 -410.462174)
			(xy 279.649917 -410.429723) (xy 279.609768 -410.391014) (xy 279.575682 -410.346871) (xy 279.548386 -410.298236)
			(xy 279.528463 -410.246145) (xy 279.516337 -410.191708) (xy 279.512266 -410.136086) (xy 238.276892 -410.136086)
			(xy 238.276892 -413.657288) (xy 238.277312 -413.667359) (xy 238.285023 -413.685968) (xy 238.291878 -413.693356)
			(xy 238.371634 -413.773112) (xy 275.328378 -413.773112) (xy 275.332449 -413.71749) (xy 275.344575 -413.663053)
			(xy 275.364498 -413.610962) (xy 275.391794 -413.562327) (xy 275.42588 -413.518184) (xy 275.466029 -413.479475)
			(xy 275.511387 -413.447024) (xy 275.560987 -413.421523) (xy 275.613771 -413.403516) (xy 275.668614 -413.393386)
			(xy 275.724348 -413.391349) (xy 275.779785 -413.397449) (xy 275.833742 -413.411555) (xy 275.885071 -413.433367)
			(xy 275.932677 -413.462421) (xy 275.975545 -413.498096) (xy 276.012762 -413.539633) (xy 276.043535 -413.586146)
			(xy 276.044141 -413.587438) (xy 276.501604 -413.587438) (xy 276.505675 -413.531816) (xy 276.517801 -413.477379)
			(xy 276.537724 -413.425288) (xy 276.56502 -413.376653) (xy 276.599106 -413.33251) (xy 276.639255 -413.293801)
			(xy 276.684613 -413.26135) (xy 276.734213 -413.235849) (xy 276.786997 -413.217842) (xy 276.84184 -413.207712)
			(xy 276.897574 -413.205675) (xy 276.953011 -413.211775) (xy 277.006968 -413.225881) (xy 277.058297 -413.247693)
			(xy 277.105903 -413.276747) (xy 277.148771 -413.312422) (xy 277.185988 -413.353959) (xy 277.216761 -413.400472)
			(xy 277.240433 -413.450969) (xy 277.251535 -413.48787) (xy 278.240996 -413.48787) (xy 278.245067 -413.432248)
			(xy 278.257193 -413.377811) (xy 278.277116 -413.32572) (xy 278.304412 -413.277085) (xy 278.338498 -413.232942)
			(xy 278.378647 -413.194233) (xy 278.424005 -413.161782) (xy 278.473605 -413.136281) (xy 278.526389 -413.118274)
			(xy 278.581232 -413.108144) (xy 278.636966 -413.106107) (xy 278.692403 -413.112207) (xy 278.74636 -413.126313)
			(xy 278.797689 -413.148125) (xy 278.845295 -413.177179) (xy 278.888163 -413.212854) (xy 278.92538 -413.254391)
			(xy 278.956153 -413.300904) (xy 278.979825 -413.351401) (xy 278.995893 -413.404808) (xy 279.004013 -413.459984)
			(xy 279.004522 -413.48787) (xy 279.004013 -413.515756) (xy 278.995893 -413.570932) (xy 278.979825 -413.624339)
			(xy 278.956153 -413.674836) (xy 278.92538 -413.721349) (xy 278.888163 -413.762886) (xy 278.845295 -413.798561)
			(xy 278.797689 -413.827615) (xy 278.74636 -413.849427) (xy 278.692403 -413.863533) (xy 278.636966 -413.869633)
			(xy 278.581232 -413.867596) (xy 278.526389 -413.857466) (xy 278.473605 -413.839459) (xy 278.424005 -413.813958)
			(xy 278.378647 -413.781507) (xy 278.338498 -413.742798) (xy 278.304412 -413.698655) (xy 278.277116 -413.65002)
			(xy 278.257193 -413.597929) (xy 278.245067 -413.543492) (xy 278.240996 -413.48787) (xy 277.251535 -413.48787)
			(xy 277.256501 -413.504376) (xy 277.264621 -413.559552) (xy 277.26513 -413.587438) (xy 277.264621 -413.615324)
			(xy 277.256501 -413.6705) (xy 277.240433 -413.723907) (xy 277.216761 -413.774404) (xy 277.185988 -413.820917)
			(xy 277.148771 -413.862454) (xy 277.127327 -413.8803) (xy 280.408378 -413.8803) (xy 280.412449 -413.824678)
			(xy 280.424575 -413.770241) (xy 280.444498 -413.71815) (xy 280.471794 -413.669515) (xy 280.50588 -413.625372)
			(xy 280.546029 -413.586663) (xy 280.591387 -413.554212) (xy 280.640987 -413.528711) (xy 280.693771 -413.510704)
			(xy 280.748614 -413.500574) (xy 280.804348 -413.498537) (xy 280.859785 -413.504637) (xy 280.913742 -413.518743)
			(xy 280.965071 -413.540555) (xy 281.012677 -413.569609) (xy 281.055545 -413.605284) (xy 281.092762 -413.646821)
			(xy 281.123535 -413.693334) (xy 281.147207 -413.743831) (xy 281.163275 -413.797238) (xy 281.171395 -413.852414)
			(xy 281.171904 -413.8803) (xy 281.171395 -413.908186) (xy 281.163275 -413.963362) (xy 281.147207 -414.016769)
			(xy 281.123535 -414.067266) (xy 281.092762 -414.113779) (xy 281.055545 -414.155316) (xy 281.012677 -414.190991)
			(xy 280.965071 -414.220045) (xy 280.913742 -414.241857) (xy 280.859785 -414.255963) (xy 280.804348 -414.262063)
			(xy 280.748614 -414.260026) (xy 280.693771 -414.249896) (xy 280.640987 -414.231889) (xy 280.591387 -414.206388)
			(xy 280.546029 -414.173937) (xy 280.50588 -414.135228) (xy 280.471794 -414.091085) (xy 280.444498 -414.04245)
			(xy 280.424575 -413.990359) (xy 280.412449 -413.935922) (xy 280.408378 -413.8803) (xy 277.127327 -413.8803)
			(xy 277.105903 -413.898129) (xy 277.058297 -413.927183) (xy 277.006968 -413.948995) (xy 276.953011 -413.963101)
			(xy 276.897574 -413.969201) (xy 276.84184 -413.967164) (xy 276.786997 -413.957034) (xy 276.734213 -413.939027)
			(xy 276.684613 -413.913526) (xy 276.639255 -413.881075) (xy 276.599106 -413.842366) (xy 276.56502 -413.798223)
			(xy 276.537724 -413.749588) (xy 276.517801 -413.697497) (xy 276.505675 -413.64306) (xy 276.501604 -413.587438)
			(xy 276.044141 -413.587438) (xy 276.067207 -413.636643) (xy 276.083275 -413.69005) (xy 276.091395 -413.745226)
			(xy 276.091904 -413.773112) (xy 276.091395 -413.800998) (xy 276.083275 -413.856174) (xy 276.067207 -413.909581)
			(xy 276.043535 -413.960078) (xy 276.012762 -414.006591) (xy 275.975545 -414.048128) (xy 275.932677 -414.083803)
			(xy 275.885071 -414.112857) (xy 275.833742 -414.134669) (xy 275.779785 -414.148775) (xy 275.724348 -414.154875)
			(xy 275.668614 -414.152838) (xy 275.613771 -414.142708) (xy 275.560987 -414.124701) (xy 275.511387 -414.0992)
			(xy 275.466029 -414.066749) (xy 275.42588 -414.02804) (xy 275.391794 -413.983897) (xy 275.364498 -413.935262)
			(xy 275.344575 -413.883171) (xy 275.332449 -413.828734) (xy 275.328378 -413.773112) (xy 238.371634 -413.773112)
			(xy 239.233964 -414.635442) (xy 239.241363 -414.642285) (xy 239.259962 -414.650005) (xy 239.270032 -414.650428)
			(xy 263.550146 -414.650428) (xy 263.560213 -414.649997) (xy 263.578808 -414.642274) (xy 263.586214 -414.635442)
			(xy 272.908522 -414.635442) (xy 272.918589 -414.63587) (xy 272.937184 -414.643595) (xy 272.94459 -414.650428)
			(xy 274.400264 -416.106102) (xy 276.344378 -416.106102) (xy 276.348449 -416.05048) (xy 276.360575 -415.996043)
			(xy 276.380498 -415.943952) (xy 276.407794 -415.895317) (xy 276.44188 -415.851174) (xy 276.482029 -415.812465)
			(xy 276.527387 -415.780014) (xy 276.576987 -415.754513) (xy 276.629771 -415.736506) (xy 276.684614 -415.726376)
			(xy 276.740348 -415.724339) (xy 276.795785 -415.730439) (xy 276.849742 -415.744545) (xy 276.901071 -415.766357)
			(xy 276.948677 -415.795411) (xy 276.991545 -415.831086) (xy 277.028762 -415.872623) (xy 277.059535 -415.919136)
			(xy 277.083207 -415.969633) (xy 277.099275 -416.02304) (xy 277.107395 -416.078216) (xy 277.107904 -416.106102)
			(xy 277.360378 -416.106102) (xy 277.364449 -416.05048) (xy 277.376575 -415.996043) (xy 277.396498 -415.943952)
			(xy 277.423794 -415.895317) (xy 277.45788 -415.851174) (xy 277.498029 -415.812465) (xy 277.543387 -415.780014)
			(xy 277.592987 -415.754513) (xy 277.645771 -415.736506) (xy 277.700614 -415.726376) (xy 277.756348 -415.724339)
			(xy 277.811785 -415.730439) (xy 277.865742 -415.744545) (xy 277.917071 -415.766357) (xy 277.964677 -415.795411)
			(xy 278.007545 -415.831086) (xy 278.044762 -415.872623) (xy 278.075535 -415.919136) (xy 278.099207 -415.969633)
			(xy 278.105113 -415.989262) (xy 278.376378 -415.989262) (xy 278.380449 -415.93364) (xy 278.392575 -415.879203)
			(xy 278.412498 -415.827112) (xy 278.439794 -415.778477) (xy 278.47388 -415.734334) (xy 278.514029 -415.695625)
			(xy 278.559387 -415.663174) (xy 278.608987 -415.637673) (xy 278.661771 -415.619666) (xy 278.716614 -415.609536)
			(xy 278.772348 -415.607499) (xy 278.827785 -415.613599) (xy 278.881742 -415.627705) (xy 278.933071 -415.649517)
			(xy 278.980677 -415.678571) (xy 279.023545 -415.714246) (xy 279.060762 -415.755783) (xy 279.091535 -415.802296)
			(xy 279.115207 -415.852793) (xy 279.131275 -415.9062) (xy 279.139395 -415.961376) (xy 279.139904 -415.989262)
			(xy 279.139593 -416.00628) (xy 279.392378 -416.00628) (xy 279.396449 -415.950658) (xy 279.408575 -415.896221)
			(xy 279.428498 -415.84413) (xy 279.455794 -415.795495) (xy 279.48988 -415.751352) (xy 279.530029 -415.712643)
			(xy 279.575387 -415.680192) (xy 279.624987 -415.654691) (xy 279.677771 -415.636684) (xy 279.732614 -415.626554)
			(xy 279.788348 -415.624517) (xy 279.843785 -415.630617) (xy 279.897742 -415.644723) (xy 279.949071 -415.666535)
			(xy 279.996677 -415.695589) (xy 280.039545 -415.731264) (xy 280.076762 -415.772801) (xy 280.107535 -415.819314)
			(xy 280.131207 -415.869811) (xy 280.147275 -415.923218) (xy 280.155395 -415.978394) (xy 280.155904 -416.00628)
			(xy 280.155395 -416.034166) (xy 280.147275 -416.089342) (xy 280.131207 -416.142749) (xy 280.123024 -416.160204)
			(xy 280.408378 -416.160204) (xy 280.412449 -416.104582) (xy 280.424575 -416.050145) (xy 280.444498 -415.998054)
			(xy 280.471794 -415.949419) (xy 280.50588 -415.905276) (xy 280.546029 -415.866567) (xy 280.591387 -415.834116)
			(xy 280.640987 -415.808615) (xy 280.693771 -415.790608) (xy 280.748614 -415.780478) (xy 280.804348 -415.778441)
			(xy 280.859785 -415.784541) (xy 280.913742 -415.798647) (xy 280.965071 -415.820459) (xy 281.012677 -415.849513)
			(xy 281.055545 -415.885188) (xy 281.092762 -415.926725) (xy 281.123535 -415.973238) (xy 281.147207 -416.023735)
			(xy 281.163275 -416.077142) (xy 281.171395 -416.132318) (xy 281.171904 -416.160204) (xy 281.171395 -416.18809)
			(xy 281.163275 -416.243266) (xy 281.147207 -416.296673) (xy 281.123535 -416.34717) (xy 281.092762 -416.393683)
			(xy 281.055545 -416.43522) (xy 281.012677 -416.470895) (xy 280.965071 -416.499949) (xy 280.913742 -416.521761)
			(xy 280.859785 -416.535867) (xy 280.804348 -416.541967) (xy 280.748614 -416.53993) (xy 280.693771 -416.5298)
			(xy 280.640987 -416.511793) (xy 280.591387 -416.486292) (xy 280.546029 -416.453841) (xy 280.50588 -416.415132)
			(xy 280.471794 -416.370989) (xy 280.444498 -416.322354) (xy 280.424575 -416.270263) (xy 280.412449 -416.215826)
			(xy 280.408378 -416.160204) (xy 280.123024 -416.160204) (xy 280.107535 -416.193246) (xy 280.076762 -416.239759)
			(xy 280.039545 -416.281296) (xy 279.996677 -416.316971) (xy 279.949071 -416.346025) (xy 279.897742 -416.367837)
			(xy 279.843785 -416.381943) (xy 279.788348 -416.388043) (xy 279.732614 -416.386006) (xy 279.677771 -416.375876)
			(xy 279.624987 -416.357869) (xy 279.575387 -416.332368) (xy 279.530029 -416.299917) (xy 279.48988 -416.261208)
			(xy 279.455794 -416.217065) (xy 279.428498 -416.16843) (xy 279.408575 -416.116339) (xy 279.396449 -416.061902)
			(xy 279.392378 -416.00628) (xy 279.139593 -416.00628) (xy 279.139395 -416.017148) (xy 279.131275 -416.072324)
			(xy 279.115207 -416.125731) (xy 279.091535 -416.176228) (xy 279.060762 -416.222741) (xy 279.023545 -416.264278)
			(xy 278.980677 -416.299953) (xy 278.933071 -416.329007) (xy 278.881742 -416.350819) (xy 278.827785 -416.364925)
			(xy 278.772348 -416.371025) (xy 278.716614 -416.368988) (xy 278.661771 -416.358858) (xy 278.608987 -416.340851)
			(xy 278.559387 -416.31535) (xy 278.514029 -416.282899) (xy 278.47388 -416.24419) (xy 278.439794 -416.200047)
			(xy 278.412498 -416.151412) (xy 278.392575 -416.099321) (xy 278.380449 -416.044884) (xy 278.376378 -415.989262)
			(xy 278.105113 -415.989262) (xy 278.115275 -416.02304) (xy 278.123395 -416.078216) (xy 278.123904 -416.106102)
			(xy 278.123395 -416.133988) (xy 278.115275 -416.189164) (xy 278.099207 -416.242571) (xy 278.075535 -416.293068)
			(xy 278.044762 -416.339581) (xy 278.007545 -416.381118) (xy 277.964677 -416.416793) (xy 277.917071 -416.445847)
			(xy 277.865742 -416.467659) (xy 277.811785 -416.481765) (xy 277.756348 -416.487865) (xy 277.700614 -416.485828)
			(xy 277.645771 -416.475698) (xy 277.592987 -416.457691) (xy 277.543387 -416.43219) (xy 277.498029 -416.399739)
			(xy 277.45788 -416.36103) (xy 277.423794 -416.316887) (xy 277.396498 -416.268252) (xy 277.376575 -416.216161)
			(xy 277.364449 -416.161724) (xy 277.360378 -416.106102) (xy 277.107904 -416.106102) (xy 277.107395 -416.133988)
			(xy 277.099275 -416.189164) (xy 277.083207 -416.242571) (xy 277.059535 -416.293068) (xy 277.028762 -416.339581)
			(xy 276.991545 -416.381118) (xy 276.948677 -416.416793) (xy 276.901071 -416.445847) (xy 276.849742 -416.467659)
			(xy 276.795785 -416.481765) (xy 276.740348 -416.487865) (xy 276.684614 -416.485828) (xy 276.629771 -416.475698)
			(xy 276.576987 -416.457691) (xy 276.527387 -416.43219) (xy 276.482029 -416.399739) (xy 276.44188 -416.36103)
			(xy 276.407794 -416.316887) (xy 276.380498 -416.268252) (xy 276.360575 -416.216161) (xy 276.348449 -416.161724)
			(xy 276.344378 -416.106102) (xy 274.400264 -416.106102) (xy 275.039328 -416.745166) (xy 275.046726 -416.752012)
			(xy 275.065325 -416.759741) (xy 275.075396 -416.760152)
		)
		(stroke
			(width 0)
			(type solid)
		)
		(fill yes)
		(layer "In15.Cu")
		(net "GND")
	)
	(gr_poly
		(pts
			(xy 148.753068 -142.497302) (xy 148.763133 -142.496866) (xy 148.781719 -142.489135) (xy 148.789136 -142.482316)
			(xy 149.572726 -141.698726) (xy 149.596304 -141.675816) (xy 149.647718 -141.634843) (xy 149.703396 -141.599882)
			(xy 149.762637 -141.571373) (xy 149.824697 -141.549675) (xy 149.888796 -141.53506) (xy 149.954128 -141.527712)
			(xy 149.987 -141.527276) (xy 151.475948 -141.527276) (xy 151.485939 -141.526747) (xy 151.504383 -141.519045)
			(xy 151.511762 -141.51229) (xy 152.152096 -140.87221) (xy 152.158296 -140.865418) (xy 152.165807 -140.848646)
			(xy 152.166894 -140.830301) (xy 152.164542 -140.82141) (xy 152.13457 -140.722096) (xy 152.113742 -140.7033)
			(xy 152.099772 -140.700506) (xy 152.071281 -140.694293) (xy 152.016475 -140.67438) (xy 151.965336 -140.646361)
			(xy 151.919056 -140.610888) (xy 151.878712 -140.568787) (xy 151.845242 -140.521038) (xy 151.819426 -140.468752)
			(xy 151.801866 -140.413148) (xy 151.79297 -140.355519) (xy 151.792432 -140.326364) (xy 151.792898 -140.299114)
			(xy 151.800659 -140.245169) (xy 151.816019 -140.192878) (xy 151.838664 -140.143305) (xy 151.868133 -140.097459)
			(xy 151.903828 -140.056274) (xy 151.94502 -140.020588) (xy 151.990871 -139.991127) (xy 152.040449 -139.968492)
			(xy 152.092743 -139.953143) (xy 152.14669 -139.945392) (xy 152.17394 -139.944856) (xy 152.203099 -139.945405)
			(xy 152.260737 -139.954275) (xy 152.316354 -139.971818) (xy 152.368651 -139.997623) (xy 152.416409 -140.031091)
			(xy 152.458514 -140.071439) (xy 152.493986 -140.117728) (xy 152.521996 -140.168878) (xy 152.541892 -140.223697)
			(xy 152.548082 -140.252196) (xy 152.550876 -140.266166) (xy 152.569672 -140.286994) (xy 152.668986 -140.316966)
			(xy 152.677877 -140.319304) (xy 152.696214 -140.318197) (xy 152.712989 -140.310709) (xy 152.719786 -140.30452)
			(xy 157.802326 -135.221726) (xy 157.825904 -135.198816) (xy 157.877318 -135.157843) (xy 157.932996 -135.122882)
			(xy 157.992237 -135.094373) (xy 158.054297 -135.072675) (xy 158.118396 -135.05806) (xy 158.183728 -135.050712)
			(xy 158.2166 -135.050276) (xy 159.862774 -135.050276) (xy 159.872763 -135.049743) (xy 159.8912 -135.042033)
			(xy 159.898588 -135.03529) (xy 160.499298 -134.43458) (xy 160.52285 -134.411629) (xy 160.574247 -134.3706)
			(xy 160.629916 -134.335587) (xy 160.689158 -134.307032) (xy 160.751226 -134.285294) (xy 160.815339 -134.270647)
			(xy 160.88069 -134.263276) (xy 160.913572 -134.262876) (xy 161.403792 -134.262876) (xy 161.436668 -134.263358)
			(xy 161.502003 -134.270756) (xy 161.5661 -134.285417) (xy 161.628155 -134.307156) (xy 161.687389 -134.335699)
			(xy 161.743058 -134.37069) (xy 161.794464 -134.411688) (xy 161.818066 -134.43458) (xy 162.279838 -134.896352)
			(xy 169.739056 -134.896352) (xy 169.739056 -134.032752) (xy 169.739546 -134.002768) (xy 169.747374 -133.943312)
			(xy 169.762895 -133.885387) (xy 169.785844 -133.829983) (xy 169.815828 -133.778049) (xy 169.852334 -133.730473)
			(xy 169.894739 -133.688068) (xy 169.942315 -133.651562) (xy 169.994249 -133.621578) (xy 170.049653 -133.598629)
			(xy 170.107578 -133.583108) (xy 170.167034 -133.57528) (xy 170.227002 -133.57528) (xy 170.286458 -133.583108)
			(xy 170.344383 -133.598629) (xy 170.399787 -133.621578) (xy 170.451721 -133.651562) (xy 170.499297 -133.688068)
			(xy 170.541702 -133.730473) (xy 170.578208 -133.778049) (xy 170.608192 -133.829983) (xy 170.631141 -133.885387)
			(xy 170.646662 -133.943312) (xy 170.65449 -134.002768) (xy 170.65498 -134.032752) (xy 170.65498 -134.896352)
			(xy 170.65449 -134.926336) (xy 170.646662 -134.985792) (xy 170.631141 -135.043717) (xy 170.608192 -135.099121)
			(xy 170.578208 -135.151055) (xy 170.541702 -135.198631) (xy 170.499297 -135.241036) (xy 170.451721 -135.277542)
			(xy 170.399787 -135.307526) (xy 170.344383 -135.330475) (xy 170.286458 -135.345996) (xy 170.227002 -135.353824)
			(xy 170.167034 -135.353824) (xy 170.107578 -135.345996) (xy 170.049653 -135.330475) (xy 169.994249 -135.307526)
			(xy 169.942315 -135.277542) (xy 169.894739 -135.241036) (xy 169.852334 -135.198631) (xy 169.815828 -135.151055)
			(xy 169.785844 -135.099121) (xy 169.762895 -135.043717) (xy 169.747374 -134.985792) (xy 169.739546 -134.926336)
			(xy 169.739056 -134.896352) (xy 162.279838 -134.896352) (xy 162.444176 -135.06069) (xy 162.451525 -135.06749)
			(xy 162.469988 -135.075196) (xy 162.47999 -135.075676) (xy 164.8714 -135.075676) (xy 164.904274 -135.076104)
			(xy 164.969611 -135.083436) (xy 165.033716 -135.09804) (xy 165.095782 -135.119734) (xy 165.155027 -135.148243)
			(xy 165.210705 -135.18321) (xy 165.262115 -135.224194) (xy 165.285674 -135.247126) (xy 167.258238 -137.21969)
			(xy 167.265585 -137.226496) (xy 167.284047 -137.234216) (xy 167.294052 -137.234676) (xy 167.992806 -137.234676)
			(xy 168.003311 -137.234162) (xy 168.022576 -137.225775) (xy 168.036893 -137.210397) (xy 168.040812 -137.20064)
			(xy 168.077896 -137.094976) (xy 168.069006 -137.063734) (xy 168.05656 -137.053574) (xy 168.03399 -137.034914)
			(xy 167.99331 -136.992786) (xy 167.958337 -136.945812) (xy 167.929643 -136.89476) (xy 167.907696 -136.840465)
			(xy 167.892857 -136.783813) (xy 167.885366 -136.725731) (xy 167.884856 -136.69645) (xy 167.884856 -135.83285)
			(xy 167.885346 -135.802866) (xy 167.893174 -135.74341) (xy 167.908695 -135.685485) (xy 167.931644 -135.630081)
			(xy 167.961628 -135.578147) (xy 167.998134 -135.530571) (xy 168.040539 -135.488166) (xy 168.088115 -135.45166)
			(xy 168.140049 -135.421676) (xy 168.195453 -135.398727) (xy 168.253378 -135.383206) (xy 168.312834 -135.375378)
			(xy 168.372802 -135.375378) (xy 168.432258 -135.383206) (xy 168.490183 -135.398727) (xy 168.545587 -135.421676)
			(xy 168.597521 -135.45166) (xy 168.645097 -135.488166) (xy 168.687502 -135.530571) (xy 168.724008 -135.578147)
			(xy 168.753992 -135.630081) (xy 168.776941 -135.685485) (xy 168.792462 -135.74341) (xy 168.80029 -135.802866)
			(xy 168.80078 -135.83285) (xy 168.80078 -136.69645) (xy 168.800298 -136.725732) (xy 168.792798 -136.783814)
			(xy 168.77795 -136.840465) (xy 168.755999 -136.89476) (xy 168.727302 -136.945811) (xy 168.692329 -136.992786)
			(xy 168.65165 -137.034917) (xy 168.629076 -137.053574) (xy 168.61663 -137.063734) (xy 168.60774 -137.094976)
			(xy 168.644824 -137.20064) (xy 168.648767 -137.210393) (xy 168.663052 -137.225806) (xy 168.682322 -137.234189)
			(xy 168.69283 -137.234676) (xy 169.713402 -137.234676) (xy 169.723389 -137.234138) (xy 169.741818 -137.226421)
			(xy 169.749216 -137.21969) (xy 171.74718 -135.221726) (xy 171.770759 -135.198818) (xy 171.822174 -135.15785)
			(xy 171.877853 -135.122894) (xy 171.937094 -135.094391) (xy 171.999154 -135.072699) (xy 172.063252 -135.05809)
			(xy 172.128583 -135.050747) (xy 172.161454 -135.050276) (xy 173.022768 -135.050276) (xy 173.03263 -135.04977)
			(xy 173.05087 -135.042253) (xy 173.064943 -135.028427) (xy 173.06925 -135.019542) (xy 173.112684 -134.920482)
			(xy 173.107604 -134.89051) (xy 173.09719 -134.879588) (xy 173.078165 -134.858283) (xy 173.046007 -134.811082)
			(xy 173.021239 -134.759616) (xy 173.004414 -134.705036) (xy 172.995906 -134.648558) (xy 172.995336 -134.62)
			(xy 172.995822 -134.592749) (xy 173.003578 -134.538801) (xy 173.018933 -134.486506) (xy 173.041575 -134.436929)
			(xy 173.071041 -134.391079) (xy 173.106732 -134.349888) (xy 173.147923 -134.314197) (xy 173.193773 -134.284731)
			(xy 173.24335 -134.262089) (xy 173.295645 -134.246734) (xy 173.349593 -134.238978) (xy 173.404095 -134.238978)
			(xy 173.458043 -134.246734) (xy 173.510338 -134.262089) (xy 173.559915 -134.284731) (xy 173.605765 -134.314197)
			(xy 173.646956 -134.349888) (xy 173.682647 -134.391079) (xy 173.712113 -134.436929) (xy 173.734755 -134.486506)
			(xy 173.75011 -134.538801) (xy 173.757866 -134.592749) (xy 173.758352 -134.62) (xy 173.757818 -134.648559)
			(xy 173.749306 -134.705039) (xy 173.732471 -134.75962) (xy 173.70769 -134.811082) (xy 173.675517 -134.858276)
			(xy 173.656498 -134.879588) (xy 173.646084 -134.89051) (xy 173.641004 -134.920482) (xy 173.684438 -135.019542)
			(xy 173.688749 -135.028428) (xy 173.702804 -135.042275) (xy 173.721055 -135.049773) (xy 173.73092 -135.050276)
			(xy 177.765202 -135.050276) (xy 177.775246 -135.049851) (xy 177.793797 -135.042142) (xy 177.80797 -135.027905)
			(xy 177.812192 -135.01878) (xy 177.818034 -135.004302) (xy 177.812192 -134.974584) (xy 172.66539 -129.827782)
			(xy 172.657995 -129.820928) (xy 172.639396 -129.813185) (xy 172.629322 -129.812796) (xy 166.280338 -129.812796)
			(xy 166.256262 -129.812361) (xy 166.20865 -129.805159) (xy 166.162649 -129.790926) (xy 166.119289 -129.769982)
			(xy 166.079545 -129.742796) (xy 166.061644 -129.72669) (xy 166.05377 -129.720594) (xy 166.037551 -129.71028)
			(xy 166.007375 -129.686472) (xy 165.993572 -129.673096) (xy 165.789102 -129.468626) (xy 165.781758 -129.461812)
			(xy 165.763296 -129.454075) (xy 165.753288 -129.45364) (xy 165.212522 -129.45364) (xy 165.202534 -129.454175)
			(xy 165.1841 -129.461887) (xy 165.176708 -129.468626) (xy 164.929566 -129.715768) (xy 164.910775 -129.733857)
			(xy 164.868565 -129.764493) (xy 164.822081 -129.788146) (xy 164.772468 -129.804234) (xy 164.720948 -129.81236)
			(xy 164.69487 -129.812796) (xy 153.300684 -129.812796) (xy 153.274606 -129.812333) (xy 153.223085 -129.804217)
			(xy 153.173469 -129.788141) (xy 153.126978 -129.764499) (xy 153.08476 -129.733876) (xy 153.065988 -129.715768)
			(xy 151.912574 -128.562354) (xy 151.901906 -128.556004) (xy 151.896064 -128.553972) (xy 151.870504 -128.545538)
			(xy 151.821865 -128.522489) (xy 151.776948 -128.492834) (xy 151.736644 -128.457161) (xy 151.701753 -128.416178)
			(xy 151.672967 -128.370699) (xy 151.650857 -128.321627) (xy 151.635862 -128.269934) (xy 151.62828 -128.216648)
			(xy 151.62784 -128.189736) (xy 151.628301 -128.162483) (xy 151.636054 -128.10853) (xy 151.651407 -128.056231)
			(xy 151.674049 -128.006649) (xy 151.703516 -127.960795) (xy 151.739211 -127.919602) (xy 151.780405 -127.883909)
			(xy 151.82626 -127.854443) (xy 151.875842 -127.831803) (xy 151.928142 -127.816451) (xy 151.982095 -127.8087)
			(xy 152.009348 -127.808228) (xy 152.036262 -127.808687) (xy 152.089555 -127.816248) (xy 152.141256 -127.831228)
			(xy 152.190336 -127.853329) (xy 152.235822 -127.882111) (xy 152.276808 -127.917003) (xy 152.312482 -127.957312)
			(xy 152.342133 -128.002236) (xy 152.365172 -128.050883) (xy 152.373584 -128.076452) (xy 152.375616 -128.082294)
			(xy 152.381966 -128.092962) (xy 152.490678 -128.201674) (xy 183.60593 -128.201674) (xy 183.610001 -128.146052)
			(xy 183.622127 -128.091615) (xy 183.64205 -128.039524) (xy 183.669346 -127.990889) (xy 183.703432 -127.946746)
			(xy 183.743581 -127.908037) (xy 183.788939 -127.875586) (xy 183.838539 -127.850085) (xy 183.891323 -127.832078)
			(xy 183.946166 -127.821948) (xy 184.0019 -127.819911) (xy 184.057337 -127.826011) (xy 184.111294 -127.840117)
			(xy 184.162623 -127.861929) (xy 184.210229 -127.890983) (xy 184.253097 -127.926658) (xy 184.290314 -127.968195)
			(xy 184.321087 -128.014708) (xy 184.344759 -128.065205) (xy 184.360827 -128.118612) (xy 184.368947 -128.173788)
			(xy 184.369456 -128.201674) (xy 184.368947 -128.22956) (xy 184.360827 -128.284736) (xy 184.344759 -128.338143)
			(xy 184.321087 -128.38864) (xy 184.290314 -128.435153) (xy 184.253097 -128.47669) (xy 184.210229 -128.512365)
			(xy 184.162623 -128.541419) (xy 184.111294 -128.563231) (xy 184.057337 -128.577337) (xy 184.0019 -128.583437)
			(xy 183.946166 -128.5814) (xy 183.891323 -128.57127) (xy 183.838539 -128.553263) (xy 183.788939 -128.527762)
			(xy 183.743581 -128.495311) (xy 183.703432 -128.456602) (xy 183.669346 -128.412459) (xy 183.64205 -128.363824)
			(xy 183.622127 -128.311733) (xy 183.610001 -128.257296) (xy 183.60593 -128.201674) (xy 152.490678 -128.201674)
			(xy 153.423366 -129.134362) (xy 153.430713 -129.141166) (xy 153.449176 -129.148881) (xy 153.45918 -129.149348)
			(xy 164.536374 -129.149348) (xy 164.546362 -129.148814) (xy 164.564796 -129.141101) (xy 164.572188 -129.134362)
			(xy 164.81933 -128.88722) (xy 164.838123 -128.869138) (xy 164.880336 -128.838515) (xy 164.926822 -128.814875)
			(xy 164.976434 -128.798802) (xy 165.02795 -128.790691) (xy 165.054026 -128.790192) (xy 165.911784 -128.790192)
			(xy 165.93786 -128.79066) (xy 165.989376 -128.798785) (xy 166.038986 -128.814869) (xy 166.085469 -128.838516)
			(xy 166.127681 -128.869143) (xy 166.14648 -128.88722) (xy 166.35095 -129.09169) (xy 166.358297 -129.098494)
			(xy 166.37676 -129.10621) (xy 166.386764 -129.106676) (xy 172.7454 -129.106676) (xy 172.773766 -129.107231)
			(xy 172.829678 -129.116841) (xy 172.883137 -129.13583) (xy 172.932582 -129.163645) (xy 172.95495 -129.181098)
			(xy 172.958297 -129.183737) (xy 172.965704 -129.18795) (xy 172.969682 -129.18948) (xy 172.991265 -129.197858)
			(xy 173.031968 -129.219917) (xy 173.069093 -129.247579) (xy 173.08576 -129.263648) (xy 174.599295 -130.777234)
			(xy 182.69966 -130.777234) (xy 182.69966 -129.913634) (xy 182.70015 -129.883666) (xy 182.707973 -129.824244)
			(xy 182.723486 -129.766351) (xy 182.746422 -129.710978) (xy 182.776389 -129.659072) (xy 182.812876 -129.611522)
			(xy 182.855256 -129.569142) (xy 182.902806 -129.532655) (xy 182.954712 -129.502688) (xy 183.010085 -129.479752)
			(xy 183.067978 -129.464239) (xy 183.1274 -129.456416) (xy 183.187336 -129.456416) (xy 183.246758 -129.464239)
			(xy 183.304651 -129.479752) (xy 183.360024 -129.502688) (xy 183.41193 -129.532655) (xy 183.45948 -129.569142)
			(xy 183.50186 -129.611522) (xy 183.538347 -129.659072) (xy 183.568314 -129.710978) (xy 183.59125 -129.766351)
			(xy 183.606763 -129.824244) (xy 183.614586 -129.883666) (xy 183.615076 -129.913634) (xy 183.615076 -130.769106)
			(xy 197.174612 -130.769106) (xy 197.174612 -129.905506) (xy 197.175102 -129.875538) (xy 197.182925 -129.816116)
			(xy 197.198438 -129.758223) (xy 197.221374 -129.70285) (xy 197.251341 -129.650944) (xy 197.287828 -129.603394)
			(xy 197.330208 -129.561014) (xy 197.377758 -129.524527) (xy 197.429664 -129.49456) (xy 197.485037 -129.471624)
			(xy 197.54293 -129.456111) (xy 197.602352 -129.448288) (xy 197.662288 -129.448288) (xy 197.72171 -129.456111)
			(xy 197.779603 -129.471624) (xy 197.834976 -129.49456) (xy 197.886882 -129.524527) (xy 197.934432 -129.561014)
			(xy 197.976812 -129.603394) (xy 198.013299 -129.650944) (xy 198.043266 -129.70285) (xy 198.066202 -129.758223)
			(xy 198.081715 -129.816116) (xy 198.089538 -129.875538) (xy 198.090028 -129.905506) (xy 198.090028 -130.769106)
			(xy 198.089538 -130.799074) (xy 198.081715 -130.858496) (xy 198.066202 -130.916389) (xy 198.043266 -130.971762)
			(xy 198.013299 -131.023668) (xy 197.976812 -131.071218) (xy 197.934432 -131.113598) (xy 197.886882 -131.150085)
			(xy 197.834976 -131.180052) (xy 197.779603 -131.202988) (xy 197.72171 -131.218501) (xy 197.662288 -131.226324)
			(xy 197.602352 -131.226324) (xy 197.54293 -131.218501) (xy 197.485037 -131.202988) (xy 197.429664 -131.180052)
			(xy 197.377758 -131.150085) (xy 197.330208 -131.113598) (xy 197.287828 -131.071218) (xy 197.251341 -131.023668)
			(xy 197.221374 -130.971762) (xy 197.198438 -130.916389) (xy 197.182925 -130.858496) (xy 197.175102 -130.799074)
			(xy 197.174612 -130.769106) (xy 183.615076 -130.769106) (xy 183.615076 -130.777234) (xy 183.614586 -130.807202)
			(xy 183.606763 -130.866624) (xy 183.59125 -130.924517) (xy 183.568314 -130.97989) (xy 183.538347 -131.031796)
			(xy 183.50186 -131.079346) (xy 183.45948 -131.121726) (xy 183.41193 -131.158213) (xy 183.360024 -131.18818)
			(xy 183.304651 -131.211116) (xy 183.246758 -131.226629) (xy 183.187336 -131.234452) (xy 183.1274 -131.234452)
			(xy 183.067978 -131.226629) (xy 183.010085 -131.211116) (xy 182.954712 -131.18818) (xy 182.902806 -131.158213)
			(xy 182.855256 -131.121726) (xy 182.812876 -131.079346) (xy 182.776389 -131.031796) (xy 182.746422 -130.97989)
			(xy 182.723486 -130.924517) (xy 182.707973 -130.866624) (xy 182.70015 -130.807202) (xy 182.69966 -130.777234)
			(xy 174.599295 -130.777234) (xy 176.399332 -132.577332) (xy 180.84546 -132.577332) (xy 180.84546 -131.713732)
			(xy 180.84595 -131.683764) (xy 180.853773 -131.624342) (xy 180.869286 -131.566449) (xy 180.892222 -131.511076)
			(xy 180.922189 -131.45917) (xy 180.958676 -131.41162) (xy 181.001056 -131.36924) (xy 181.048606 -131.332753)
			(xy 181.100512 -131.302786) (xy 181.155885 -131.27985) (xy 181.213778 -131.264337) (xy 181.2732 -131.256514)
			(xy 181.333136 -131.256514) (xy 181.392558 -131.264337) (xy 181.450451 -131.27985) (xy 181.505824 -131.302786)
			(xy 181.55773 -131.332753) (xy 181.60528 -131.36924) (xy 181.64766 -131.41162) (xy 181.684147 -131.45917)
			(xy 181.714114 -131.511076) (xy 181.73705 -131.566449) (xy 181.752563 -131.624342) (xy 181.760386 -131.683764)
			(xy 181.760876 -131.713732) (xy 181.760876 -132.575808) (xy 199.81672 -132.575808) (xy 199.81672 -131.712208)
			(xy 199.81721 -131.68224) (xy 199.825033 -131.622818) (xy 199.840546 -131.564925) (xy 199.863482 -131.509552)
			(xy 199.893449 -131.457646) (xy 199.929936 -131.410096) (xy 199.972316 -131.367716) (xy 200.019866 -131.331229)
			(xy 200.071772 -131.301262) (xy 200.127145 -131.278326) (xy 200.185038 -131.262813) (xy 200.24446 -131.25499)
			(xy 200.304396 -131.25499) (xy 200.363818 -131.262813) (xy 200.421711 -131.278326) (xy 200.477084 -131.301262)
			(xy 200.52899 -131.331229) (xy 200.57654 -131.367716) (xy 200.61892 -131.410096) (xy 200.655407 -131.457646)
			(xy 200.685374 -131.509552) (xy 200.70831 -131.564925) (xy 200.723823 -131.622818) (xy 200.731646 -131.68224)
			(xy 200.732136 -131.712208) (xy 200.732136 -132.575808) (xy 200.731646 -132.605776) (xy 200.723823 -132.665198)
			(xy 200.70831 -132.723091) (xy 200.685374 -132.778464) (xy 200.655407 -132.83037) (xy 200.61892 -132.87792)
			(xy 200.57654 -132.9203) (xy 200.52899 -132.956787) (xy 200.477084 -132.986754) (xy 200.421711 -133.00969)
			(xy 200.363818 -133.025203) (xy 200.304396 -133.033026) (xy 200.24446 -133.033026) (xy 200.185038 -133.025203)
			(xy 200.127145 -133.00969) (xy 200.071772 -132.986754) (xy 200.019866 -132.956787) (xy 199.972316 -132.9203)
			(xy 199.929936 -132.87792) (xy 199.893449 -132.83037) (xy 199.863482 -132.778464) (xy 199.840546 -132.723091)
			(xy 199.825033 -132.665198) (xy 199.81721 -132.605776) (xy 199.81672 -132.575808) (xy 181.760876 -132.575808)
			(xy 181.760876 -132.577332) (xy 181.760386 -132.6073) (xy 181.752563 -132.666722) (xy 181.73705 -132.724615)
			(xy 181.714114 -132.779988) (xy 181.684147 -132.831894) (xy 181.64766 -132.879444) (xy 181.60528 -132.921824)
			(xy 181.55773 -132.958311) (xy 181.505824 -132.988278) (xy 181.450451 -133.011214) (xy 181.392558 -133.026727)
			(xy 181.333136 -133.03455) (xy 181.2732 -133.03455) (xy 181.213778 -133.026727) (xy 181.155885 -133.011214)
			(xy 181.100512 -132.988278) (xy 181.048606 -132.958311) (xy 181.001056 -132.921824) (xy 180.958676 -132.879444)
			(xy 180.922189 -132.831894) (xy 180.892222 -132.779988) (xy 180.869286 -132.724615) (xy 180.853773 -132.666722)
			(xy 180.84595 -132.6073) (xy 180.84546 -132.577332) (xy 176.399332 -132.577332) (xy 178.199116 -134.377176)
			(xy 182.69966 -134.377176) (xy 182.69966 -133.513576) (xy 182.70015 -133.483608) (xy 182.707973 -133.424186)
			(xy 182.723486 -133.366293) (xy 182.746422 -133.31092) (xy 182.776389 -133.259014) (xy 182.812876 -133.211464)
			(xy 182.855256 -133.169084) (xy 182.902806 -133.132597) (xy 182.954712 -133.10263) (xy 183.010085 -133.079694)
			(xy 183.067978 -133.064181) (xy 183.1274 -133.056358) (xy 183.187336 -133.056358) (xy 183.246758 -133.064181)
			(xy 183.304651 -133.079694) (xy 183.360024 -133.10263) (xy 183.41193 -133.132597) (xy 183.45948 -133.169084)
			(xy 183.50186 -133.211464) (xy 183.538347 -133.259014) (xy 183.568314 -133.31092) (xy 183.59125 -133.366293)
			(xy 183.606763 -133.424186) (xy 183.614586 -133.483608) (xy 183.615076 -133.513576) (xy 183.615076 -134.369302)
			(xy 197.174612 -134.369302) (xy 197.174612 -133.505702) (xy 197.175102 -133.475734) (xy 197.182925 -133.416312)
			(xy 197.198438 -133.358419) (xy 197.221374 -133.303046) (xy 197.251341 -133.25114) (xy 197.287828 -133.20359)
			(xy 197.330208 -133.16121) (xy 197.377758 -133.124723) (xy 197.429664 -133.094756) (xy 197.485037 -133.07182)
			(xy 197.54293 -133.056307) (xy 197.602352 -133.048484) (xy 197.662288 -133.048484) (xy 197.72171 -133.056307)
			(xy 197.779603 -133.07182) (xy 197.834976 -133.094756) (xy 197.886882 -133.124723) (xy 197.934432 -133.16121)
			(xy 197.976812 -133.20359) (xy 198.013299 -133.25114) (xy 198.043266 -133.303046) (xy 198.066202 -133.358419)
			(xy 198.081715 -133.416312) (xy 198.089538 -133.475734) (xy 198.090028 -133.505702) (xy 198.090028 -134.369302)
			(xy 198.089538 -134.39927) (xy 198.081715 -134.458692) (xy 198.066202 -134.516585) (xy 198.043266 -134.571958)
			(xy 198.013299 -134.623864) (xy 197.976812 -134.671414) (xy 197.934432 -134.713794) (xy 197.886882 -134.750281)
			(xy 197.834976 -134.780248) (xy 197.779603 -134.803184) (xy 197.72171 -134.818697) (xy 197.662288 -134.82652)
			(xy 197.602352 -134.82652) (xy 197.54293 -134.818697) (xy 197.485037 -134.803184) (xy 197.429664 -134.780248)
			(xy 197.377758 -134.750281) (xy 197.330208 -134.713794) (xy 197.287828 -134.671414) (xy 197.251341 -134.623864)
			(xy 197.221374 -134.571958) (xy 197.198438 -134.516585) (xy 197.182925 -134.458692) (xy 197.175102 -134.39927)
			(xy 197.174612 -134.369302) (xy 183.615076 -134.369302) (xy 183.615076 -134.377176) (xy 183.614586 -134.407144)
			(xy 183.606763 -134.466566) (xy 183.59125 -134.524459) (xy 183.568314 -134.579832) (xy 183.538347 -134.631738)
			(xy 183.50186 -134.679288) (xy 183.45948 -134.721668) (xy 183.41193 -134.758155) (xy 183.360024 -134.788122)
			(xy 183.304651 -134.811058) (xy 183.246758 -134.826571) (xy 183.187336 -134.834394) (xy 183.1274 -134.834394)
			(xy 183.067978 -134.826571) (xy 183.010085 -134.811058) (xy 182.954712 -134.788122) (xy 182.902806 -134.758155)
			(xy 182.855256 -134.721668) (xy 182.812876 -134.679288) (xy 182.776389 -134.631738) (xy 182.746422 -134.579832)
			(xy 182.723486 -134.524459) (xy 182.707973 -134.466566) (xy 182.70015 -134.407144) (xy 182.69966 -134.377176)
			(xy 178.199116 -134.377176) (xy 179.999153 -136.177274) (xy 180.84546 -136.177274) (xy 180.84546 -135.313674)
			(xy 180.84595 -135.283706) (xy 180.853773 -135.224284) (xy 180.869286 -135.166391) (xy 180.892222 -135.111018)
			(xy 180.922189 -135.059112) (xy 180.958676 -135.011562) (xy 181.001056 -134.969182) (xy 181.048606 -134.932695)
			(xy 181.100512 -134.902728) (xy 181.155885 -134.879792) (xy 181.213778 -134.864279) (xy 181.2732 -134.856456)
			(xy 181.333136 -134.856456) (xy 181.392558 -134.864279) (xy 181.450451 -134.879792) (xy 181.505824 -134.902728)
			(xy 181.55773 -134.932695) (xy 181.60528 -134.969182) (xy 181.64766 -135.011562) (xy 181.684147 -135.059112)
			(xy 181.714114 -135.111018) (xy 181.73705 -135.166391) (xy 181.752563 -135.224284) (xy 181.760386 -135.283706)
			(xy 181.760876 -135.313674) (xy 181.760876 -136.17575) (xy 199.81672 -136.17575) (xy 199.81672 -135.31215)
			(xy 199.81721 -135.282182) (xy 199.825033 -135.22276) (xy 199.840546 -135.164867) (xy 199.863482 -135.109494)
			(xy 199.893449 -135.057588) (xy 199.929936 -135.010038) (xy 199.972316 -134.967658) (xy 200.019866 -134.931171)
			(xy 200.071772 -134.901204) (xy 200.127145 -134.878268) (xy 200.185038 -134.862755) (xy 200.24446 -134.854932)
			(xy 200.304396 -134.854932) (xy 200.363818 -134.862755) (xy 200.421711 -134.878268) (xy 200.477084 -134.901204)
			(xy 200.52899 -134.931171) (xy 200.57654 -134.967658) (xy 200.61892 -135.010038) (xy 200.655407 -135.057588)
			(xy 200.685374 -135.109494) (xy 200.70831 -135.164867) (xy 200.723823 -135.22276) (xy 200.731646 -135.282182)
			(xy 200.732136 -135.31215) (xy 200.732136 -136.17575) (xy 200.731646 -136.205718) (xy 200.723823 -136.26514)
			(xy 200.70831 -136.323033) (xy 200.685374 -136.378406) (xy 200.655407 -136.430312) (xy 200.61892 -136.477862)
			(xy 200.57654 -136.520242) (xy 200.52899 -136.556729) (xy 200.477084 -136.586696) (xy 200.421711 -136.609632)
			(xy 200.363818 -136.625145) (xy 200.304396 -136.632968) (xy 200.24446 -136.632968) (xy 200.185038 -136.625145)
			(xy 200.127145 -136.609632) (xy 200.071772 -136.586696) (xy 200.019866 -136.556729) (xy 199.972316 -136.520242)
			(xy 199.929936 -136.477862) (xy 199.893449 -136.430312) (xy 199.863482 -136.378406) (xy 199.840546 -136.323033)
			(xy 199.825033 -136.26514) (xy 199.81721 -136.205718) (xy 199.81672 -136.17575) (xy 181.760876 -136.17575)
			(xy 181.760876 -136.177274) (xy 181.760386 -136.207242) (xy 181.752563 -136.266664) (xy 181.73705 -136.324557)
			(xy 181.714114 -136.37993) (xy 181.684147 -136.431836) (xy 181.64766 -136.479386) (xy 181.60528 -136.521766)
			(xy 181.55773 -136.558253) (xy 181.505824 -136.58822) (xy 181.450451 -136.611156) (xy 181.392558 -136.626669)
			(xy 181.333136 -136.634492) (xy 181.2732 -136.634492) (xy 181.213778 -136.626669) (xy 181.155885 -136.611156)
			(xy 181.100512 -136.58822) (xy 181.048606 -136.558253) (xy 181.001056 -136.521766) (xy 180.958676 -136.479386)
			(xy 180.922189 -136.431836) (xy 180.892222 -136.37993) (xy 180.869286 -136.324557) (xy 180.853773 -136.266664)
			(xy 180.84595 -136.207242) (xy 180.84546 -136.177274) (xy 179.999153 -136.177274) (xy 180.609748 -136.78789)
			(xy 180.617095 -136.794694) (xy 180.635558 -136.802411) (xy 180.645562 -136.802876) (xy 195.808854 -136.802876)
			(xy 195.833561 -136.803307) (xy 195.882432 -136.810597) (xy 195.929679 -136.825066) (xy 195.974251 -136.846393)
			(xy 196.015161 -136.874105) (xy 196.033644 -136.890506) (xy 196.04355 -136.897618) (xy 196.063198 -136.908849)
			(xy 196.099407 -136.935998) (xy 196.115686 -136.95172) (xy 196.149962 -136.98601) (xy 196.657466 -136.98601)
			(xy 196.661537 -136.930388) (xy 196.673663 -136.875951) (xy 196.693586 -136.82386) (xy 196.720882 -136.775225)
			(xy 196.754968 -136.731082) (xy 196.795117 -136.692373) (xy 196.840475 -136.659922) (xy 196.890075 -136.634421)
			(xy 196.942859 -136.616414) (xy 196.997702 -136.606284) (xy 197.053436 -136.604247) (xy 197.108873 -136.610347)
			(xy 197.16283 -136.624453) (xy 197.214159 -136.646265) (xy 197.261765 -136.675319) (xy 197.304633 -136.710994)
			(xy 197.34185 -136.752531) (xy 197.372623 -136.799044) (xy 197.396295 -136.849541) (xy 197.412363 -136.902948)
			(xy 197.420483 -136.958124) (xy 197.420992 -136.98601) (xy 197.420483 -137.013896) (xy 197.412363 -137.069072)
			(xy 197.396295 -137.122479) (xy 197.372623 -137.172976) (xy 197.34185 -137.219489) (xy 197.304633 -137.261026)
			(xy 197.261765 -137.296701) (xy 197.214159 -137.325755) (xy 197.16283 -137.347567) (xy 197.108873 -137.361673)
			(xy 197.053436 -137.367773) (xy 196.997702 -137.365736) (xy 196.942859 -137.355606) (xy 196.890075 -137.337599)
			(xy 196.840475 -137.312098) (xy 196.795117 -137.279647) (xy 196.754968 -137.240938) (xy 196.720882 -137.196795)
			(xy 196.693586 -137.14816) (xy 196.673663 -137.096069) (xy 196.661537 -137.041632) (xy 196.657466 -136.98601)
			(xy 196.149962 -136.98601) (xy 196.757036 -137.593324) (xy 196.764448 -137.6) (xy 196.782885 -137.607565)
			(xy 196.79285 -137.608056) (xy 207.43799 -137.608056) (xy 207.447957 -137.607582) (xy 207.466397 -137.600009)
			(xy 207.473804 -137.593324) (xy 209.760566 -135.306562) (xy 209.766916 -135.296402) (xy 209.768694 -135.29056)
			(xy 209.777297 -135.265268) (xy 209.800585 -135.217188) (xy 209.830355 -135.172828) (xy 209.866025 -135.133057)
			(xy 209.906895 -135.098652) (xy 209.952166 -135.070287) (xy 210.000952 -135.048518) (xy 210.052299 -135.033769)
			(xy 210.105202 -135.02633) (xy 210.131914 -135.025892) (xy 210.155072 -135.026233) (xy 210.201046 -135.031839)
			(xy 210.223608 -135.037068) (xy 210.229704 -135.038592) (xy 210.2358 -135.038592) (xy 210.245821 -135.038172)
			(xy 210.264336 -135.030502) (xy 210.278507 -135.01633) (xy 210.286174 -134.997813) (xy 210.2866 -134.987792)
			(xy 210.2866 -134.952994) (xy 210.286176 -134.942924) (xy 210.27846 -134.924321) (xy 210.271614 -134.916926)
			(xy 202.797156 -127.442468) (xy 202.774208 -127.418915) (xy 202.733183 -127.367517) (xy 202.698174 -127.311847)
			(xy 202.669624 -127.252604) (xy 202.647891 -127.190537) (xy 202.633248 -127.126424) (xy 202.625881 -127.061075)
			(xy 202.625452 -127.028194) (xy 202.625452 -116.495322) (xy 202.624962 -116.485362) (xy 202.617366 -116.466945)
			(xy 202.61072 -116.459508) (xy 202.439524 -116.288312) (xy 202.432116 -116.281623) (xy 202.41368 -116.27403)
			(xy 202.40371 -116.27358) (xy 192.954402 -116.27358) (xy 192.921526 -116.273098) (xy 192.856191 -116.265699)
			(xy 192.792093 -116.251039) (xy 192.730037 -116.229302) (xy 192.670802 -116.20076) (xy 192.615131 -116.165771)
			(xy 192.563723 -116.124775) (xy 192.540128 -116.101876) (xy 191.743076 -115.30457) (xy 191.735768 -115.297892)
			(xy 191.717547 -115.290203) (xy 191.697771 -115.289984) (xy 191.679383 -115.297265) (xy 191.671956 -115.303808)
			(xy 191.624458 -115.349274) (xy 191.616584 -115.3668) (xy 191.616076 -115.37696) (xy 191.61451 -115.403444)
			(xy 191.604965 -115.45563) (xy 191.58828 -115.50599) (xy 191.564777 -115.553552) (xy 191.534909 -115.597397)
			(xy 191.499253 -115.63668) (xy 191.458496 -115.670642) (xy 191.413426 -115.698629) (xy 191.364913 -115.720098)
			(xy 191.313892 -115.734638) (xy 191.261348 -115.741966) (xy 191.234822 -115.742466) (xy 191.207454 -115.741989)
			(xy 191.153282 -115.734154) (xy 191.100785 -115.718658) (xy 191.051043 -115.695817) (xy 191.005076 -115.666101)
			(xy 190.984124 -115.648486) (xy 190.977012 -115.64239) (xy 190.960248 -115.63604) (xy 190.874396 -115.63604)
			(xy 190.857632 -115.64239) (xy 190.85052 -115.648486) (xy 190.829589 -115.66613) (xy 190.783624 -115.695859)
			(xy 190.733877 -115.718706) (xy 190.681373 -115.734199) (xy 190.627193 -115.742021) (xy 190.599822 -115.742466)
			(xy 190.573298 -115.742005) (xy 190.520764 -115.734648) (xy 190.469754 -115.720087) (xy 190.421253 -115.698602)
			(xy 190.376194 -115.670607) (xy 190.335446 -115.636642) (xy 190.299794 -115.597361) (xy 190.269926 -115.553522)
			(xy 190.246416 -115.505969) (xy 190.229718 -115.455618) (xy 190.220154 -115.40344) (xy 190.218568 -115.37696)
			(xy 190.21806 -115.3668) (xy 190.210186 -115.349274) (xy 190.15202 -115.293648) (xy 190.144701 -115.287259)
			(xy 190.126675 -115.280059) (xy 190.116968 -115.279678) (xy 188.00699 -115.279678) (xy 187.997003 -115.280217)
			(xy 187.978571 -115.28793) (xy 187.971176 -115.294664) (xy 187.537852 -115.727988) (xy 187.514683 -115.750514)
			(xy 187.464158 -115.790803) (xy 187.409439 -115.825182) (xy 187.351216 -115.853219) (xy 187.29022 -115.874561)
			(xy 187.227217 -115.888939) (xy 187.163001 -115.896173) (xy 187.13069 -115.896644) (xy 185.298334 -115.896644)
			(xy 185.266021 -115.896193) (xy 185.201802 -115.888961) (xy 185.138796 -115.874585) (xy 185.077796 -115.853244)
			(xy 185.019569 -115.825208) (xy 184.964846 -115.790829) (xy 184.914317 -115.75054) (xy 184.891172 -115.727988)
			(xy 184.457848 -115.294664) (xy 184.45045 -115.287819) (xy 184.431851 -115.280093) (xy 184.42178 -115.279678)
			(xy 183.823102 -115.279678) (xy 183.794146 -115.305586) (xy 183.792114 -115.325144) (xy 183.788734 -115.35295)
			(xy 183.77487 -115.407219) (xy 183.753219 -115.458878) (xy 183.724249 -115.506816) (xy 183.68858 -115.550002)
			(xy 183.64698 -115.58751) (xy 183.600343 -115.618531) (xy 183.549671 -115.6424) (xy 183.496054 -115.658604)
			(xy 183.440644 -115.666794) (xy 183.384632 -115.666794) (xy 183.329222 -115.658604) (xy 183.275605 -115.6424)
			(xy 183.224933 -115.618531) (xy 183.178296 -115.58751) (xy 183.136696 -115.550002) (xy 183.101027 -115.506816)
			(xy 183.072057 -115.458878) (xy 183.050406 -115.407219) (xy 183.036542 -115.35295) (xy 183.033162 -115.325144)
			(xy 183.03113 -115.305586) (xy 183.002174 -115.279678) (xy 154.782012 -115.279678) (xy 154.75458 -115.301776)
			(xy 154.750516 -115.319302) (xy 154.744011 -115.345904) (xy 154.724414 -115.39704) (xy 154.697713 -115.444852)
			(xy 154.664456 -115.488359) (xy 154.625324 -115.526669) (xy 154.581121 -115.558996) (xy 154.532753 -115.584676)
			(xy 154.481212 -115.603183) (xy 154.427556 -115.614137) (xy 154.40025 -115.616228) (xy 154.389393 -115.617274)
			(xy 154.370031 -115.62727) (xy 154.362912 -115.635532) (xy 154.309318 -115.703858) (xy 154.303984 -115.72494)
			(xy 154.306016 -115.735608) (xy 154.308847 -115.752356) (xy 154.311903 -115.786188) (xy 154.312112 -115.803172)
			(xy 154.312112 -115.803934) (xy 154.311851 -115.819174) (xy 171.947076 -115.819174) (xy 171.951147 -115.763552)
			(xy 171.963273 -115.709115) (xy 171.983196 -115.657024) (xy 172.010492 -115.608389) (xy 172.044578 -115.564246)
			(xy 172.084727 -115.525537) (xy 172.130085 -115.493086) (xy 172.179685 -115.467585) (xy 172.232469 -115.449578)
			(xy 172.287312 -115.439448) (xy 172.343046 -115.437411) (xy 172.398483 -115.443511) (xy 172.45244 -115.457617)
			(xy 172.503769 -115.479429) (xy 172.551375 -115.508483) (xy 172.594243 -115.544158) (xy 172.63146 -115.585695)
			(xy 172.662233 -115.632208) (xy 172.685905 -115.682705) (xy 172.701973 -115.736112) (xy 172.710093 -115.791288)
			(xy 172.710602 -115.819174) (xy 172.710093 -115.84706) (xy 172.701973 -115.902236) (xy 172.699911 -115.90909)
			(xy 180.121304 -115.90909) (xy 180.125375 -115.853468) (xy 180.137501 -115.799031) (xy 180.157424 -115.74694)
			(xy 180.18472 -115.698305) (xy 180.218806 -115.654162) (xy 180.258955 -115.615453) (xy 180.304313 -115.583002)
			(xy 180.353913 -115.557501) (xy 180.406697 -115.539494) (xy 180.46154 -115.529364) (xy 180.517274 -115.527327)
			(xy 180.572711 -115.533427) (xy 180.626668 -115.547533) (xy 180.677997 -115.569345) (xy 180.725603 -115.598399)
			(xy 180.768471 -115.634074) (xy 180.805688 -115.675611) (xy 180.836461 -115.722124) (xy 180.860133 -115.772621)
			(xy 180.876201 -115.826028) (xy 180.884321 -115.881204) (xy 180.88483 -115.90909) (xy 180.884321 -115.936976)
			(xy 180.876201 -115.992152) (xy 180.860133 -116.045559) (xy 180.836461 -116.096056) (xy 180.805688 -116.142569)
			(xy 180.768471 -116.184106) (xy 180.725603 -116.219781) (xy 180.677997 -116.248835) (xy 180.626668 -116.270647)
			(xy 180.572711 -116.284753) (xy 180.517274 -116.290853) (xy 180.46154 -116.288816) (xy 180.406697 -116.278686)
			(xy 180.353913 -116.260679) (xy 180.304313 -116.235178) (xy 180.258955 -116.202727) (xy 180.218806 -116.164018)
			(xy 180.18472 -116.119875) (xy 180.157424 -116.07124) (xy 180.137501 -116.019149) (xy 180.125375 -115.964712)
			(xy 180.121304 -115.90909) (xy 172.699911 -115.90909) (xy 172.685905 -115.955643) (xy 172.662233 -116.00614)
			(xy 172.63146 -116.052653) (xy 172.594243 -116.09419) (xy 172.551375 -116.129865) (xy 172.503769 -116.158919)
			(xy 172.45244 -116.180731) (xy 172.398483 -116.194837) (xy 172.343046 -116.200937) (xy 172.287312 -116.1989)
			(xy 172.232469 -116.18877) (xy 172.179685 -116.170763) (xy 172.130085 -116.145262) (xy 172.084727 -116.112811)
			(xy 172.044578 -116.074102) (xy 172.010492 -116.029959) (xy 171.983196 -115.981324) (xy 171.963273 -115.929233)
			(xy 171.951147 -115.874796) (xy 171.947076 -115.819174) (xy 154.311851 -115.819174) (xy 154.311649 -115.83092)
			(xy 154.304048 -115.884354) (xy 154.288988 -115.936182) (xy 154.26677 -115.985369) (xy 154.237839 -116.030931)
			(xy 154.202772 -116.071958) (xy 154.16227 -116.107631) (xy 154.117143 -116.137237) (xy 154.09291 -116.14912)
			(xy 154.08275 -116.153946) (xy 154.068526 -116.170964) (xy 154.045158 -116.256054) (xy 154.043865 -116.261482)
			(xy 154.043359 -116.272627) (xy 154.044142 -116.278152) (xy 154.04592 -116.289074) (xy 154.052016 -116.298218)
			(xy 154.067602 -116.322055) (xy 154.092285 -116.373378) (xy 154.109052 -116.427804) (xy 154.112028 -116.44757)
			(xy 182.256936 -116.44757) (xy 182.261007 -116.391948) (xy 182.273133 -116.337511) (xy 182.293056 -116.28542)
			(xy 182.320352 -116.236785) (xy 182.354438 -116.192642) (xy 182.394587 -116.153933) (xy 182.439945 -116.121482)
			(xy 182.489545 -116.095981) (xy 182.542329 -116.077974) (xy 182.597172 -116.067844) (xy 182.652906 -116.065807)
			(xy 182.708343 -116.071907) (xy 182.7623 -116.086013) (xy 182.813629 -116.107825) (xy 182.861235 -116.136879)
			(xy 182.904103 -116.172554) (xy 182.94132 -116.214091) (xy 182.972093 -116.260604) (xy 182.995765 -116.311101)
			(xy 183.011833 -116.364508) (xy 183.019953 -116.419684) (xy 183.020462 -116.44757) (xy 183.019953 -116.475456)
			(xy 183.019683 -116.477288) (xy 187.404246 -116.477288) (xy 187.408317 -116.421666) (xy 187.420443 -116.367229)
			(xy 187.440366 -116.315138) (xy 187.467662 -116.266503) (xy 187.501748 -116.22236) (xy 187.541897 -116.183651)
			(xy 187.587255 -116.1512) (xy 187.636855 -116.125699) (xy 187.689639 -116.107692) (xy 187.744482 -116.097562)
			(xy 187.800216 -116.095525) (xy 187.855653 -116.101625) (xy 187.90961 -116.115731) (xy 187.960939 -116.137543)
			(xy 188.008545 -116.166597) (xy 188.051413 -116.202272) (xy 188.08863 -116.243809) (xy 188.119403 -116.290322)
			(xy 188.143075 -116.340819) (xy 188.159143 -116.394226) (xy 188.167263 -116.449402) (xy 188.167772 -116.477288)
			(xy 188.167263 -116.505174) (xy 188.159143 -116.56035) (xy 188.143075 -116.613757) (xy 188.119403 -116.664254)
			(xy 188.08863 -116.710767) (xy 188.051413 -116.752304) (xy 188.008545 -116.787979) (xy 187.960939 -116.817033)
			(xy 187.90961 -116.838845) (xy 187.855653 -116.852951) (xy 187.800216 -116.859051) (xy 187.744482 -116.857014)
			(xy 187.689639 -116.846884) (xy 187.636855 -116.828877) (xy 187.587255 -116.803376) (xy 187.541897 -116.770925)
			(xy 187.501748 -116.732216) (xy 187.467662 -116.688073) (xy 187.440366 -116.639438) (xy 187.420443 -116.587347)
			(xy 187.408317 -116.53291) (xy 187.404246 -116.477288) (xy 183.019683 -116.477288) (xy 183.011833 -116.530632)
			(xy 182.995765 -116.584039) (xy 182.972093 -116.634536) (xy 182.94132 -116.681049) (xy 182.904103 -116.722586)
			(xy 182.861235 -116.758261) (xy 182.813629 -116.787315) (xy 182.7623 -116.809127) (xy 182.708343 -116.823233)
			(xy 182.652906 -116.829333) (xy 182.597172 -116.827296) (xy 182.542329 -116.817166) (xy 182.489545 -116.799159)
			(xy 182.439945 -116.773658) (xy 182.394587 -116.741207) (xy 182.354438 -116.702498) (xy 182.320352 -116.658355)
			(xy 182.293056 -116.60972) (xy 182.273133 -116.557629) (xy 182.261007 -116.503192) (xy 182.256936 -116.44757)
			(xy 154.112028 -116.44757) (xy 154.117531 -116.484119) (xy 154.118056 -116.512594) (xy 154.117571 -116.539847)
			(xy 154.109815 -116.593798) (xy 154.094461 -116.646096) (xy 154.071821 -116.695677) (xy 154.042355 -116.741532)
			(xy 154.006665 -116.782726) (xy 153.965475 -116.818423) (xy 153.919624 -116.847895) (xy 153.870047 -116.870542)
			(xy 153.817751 -116.885904) (xy 153.763801 -116.893667) (xy 153.736548 -116.894102) (xy 153.736294 -116.894102)
			(xy 153.710828 -116.893659) (xy 153.660354 -116.886843) (xy 153.611234 -116.873374) (xy 153.564344 -116.85349)
			(xy 153.520514 -116.827545) (xy 153.480526 -116.796) (xy 153.462482 -116.778024) (xy 153.45537 -116.770912)
			(xy 153.428192 -116.75872) (xy 153.423295 -116.756684) (xy 153.41292 -116.754497) (xy 153.407618 -116.754402)
			(xy 153.354278 -116.754402) (xy 153.348981 -116.754544) (xy 153.338614 -116.756727) (xy 153.333704 -116.75872)
			(xy 153.306526 -116.770912) (xy 153.299414 -116.778024) (xy 153.281378 -116.796041) (xy 153.241352 -116.827614)
			(xy 153.197478 -116.853575) (xy 153.150536 -116.873459) (xy 153.101364 -116.886914) (xy 153.050838 -116.893698)
			(xy 153.025348 -116.894102) (xy 153.015696 -116.894102) (xy 152.988898 -116.892971) (xy 152.935996 -116.884122)
			(xy 152.884855 -116.867949) (xy 152.836485 -116.84477) (xy 152.791839 -116.815044) (xy 152.751798 -116.779356)
			(xy 152.717152 -116.73841) (xy 152.688584 -116.693014) (xy 152.666657 -116.644064) (xy 152.651804 -116.592525)
			(xy 152.644318 -116.539413) (xy 152.64384 -116.512594) (xy 152.64384 -116.502688) (xy 152.644348 -116.493036)
			(xy 152.636982 -116.473478) (xy 152.578816 -116.413788) (xy 152.57399 -116.40947) (xy 152.567368 -116.40463)
			(xy 152.551951 -116.399056) (xy 152.543764 -116.398548) (xy 152.49017 -116.398548) (xy 152.480186 -116.399092)
			(xy 152.461766 -116.406819) (xy 152.454356 -116.413534) (xy 152.380442 -116.487448) (xy 152.362257 -116.504908)
			(xy 152.321461 -116.53452) (xy 152.276544 -116.557405) (xy 152.228608 -116.573004) (xy 152.178825 -116.580933)
			(xy 152.15362 -116.581428) (xy 141.84503 -116.581428) (xy 141.836195 -116.581804) (xy 141.819563 -116.587769)
			(xy 141.812518 -116.593112) (xy 141.81074 -116.594636) (xy 140.75791 -117.647466) (xy 140.750544 -117.654578)
			(xy 140.742924 -117.673374) (xy 140.742924 -117.7544) (xy 153.187906 -117.7544) (xy 153.191977 -117.698778)
			(xy 153.204103 -117.644341) (xy 153.224026 -117.59225) (xy 153.251322 -117.543615) (xy 153.285408 -117.499472)
			(xy 153.325557 -117.460763) (xy 153.370915 -117.428312) (xy 153.420515 -117.402811) (xy 153.473299 -117.384804)
			(xy 153.528142 -117.374674) (xy 153.583876 -117.372637) (xy 153.639313 -117.378737) (xy 153.69327 -117.392843)
			(xy 153.744599 -117.414655) (xy 153.792205 -117.443709) (xy 153.835073 -117.479384) (xy 153.87229 -117.520921)
			(xy 153.903063 -117.567434) (xy 153.926735 -117.617931) (xy 153.942803 -117.671338) (xy 153.950504 -117.723666)
			(xy 185.789568 -117.723666) (xy 185.793639 -117.668044) (xy 185.805765 -117.613607) (xy 185.825688 -117.561516)
			(xy 185.852984 -117.512881) (xy 185.88707 -117.468738) (xy 185.927219 -117.430029) (xy 185.972577 -117.397578)
			(xy 186.022177 -117.372077) (xy 186.074961 -117.35407) (xy 186.129804 -117.34394) (xy 186.185538 -117.341903)
			(xy 186.240975 -117.348003) (xy 186.294932 -117.362109) (xy 186.346261 -117.383921) (xy 186.393867 -117.412975)
			(xy 186.436735 -117.44865) (xy 186.473952 -117.490187) (xy 186.504725 -117.5367) (xy 186.528397 -117.587197)
			(xy 186.544465 -117.640604) (xy 186.552585 -117.69578) (xy 186.553094 -117.723666) (xy 186.552585 -117.751552)
			(xy 186.55153 -117.758718) (xy 190.574676 -117.758718) (xy 190.574676 -116.895118) (xy 190.575166 -116.865134)
			(xy 190.582994 -116.805678) (xy 190.598515 -116.747753) (xy 190.621464 -116.692349) (xy 190.651448 -116.640415)
			(xy 190.687954 -116.592839) (xy 190.730359 -116.550434) (xy 190.777935 -116.513928) (xy 190.829869 -116.483944)
			(xy 190.885273 -116.460995) (xy 190.943198 -116.445474) (xy 191.002654 -116.437646) (xy 191.062622 -116.437646)
			(xy 191.122078 -116.445474) (xy 191.180003 -116.460995) (xy 191.235407 -116.483944) (xy 191.287341 -116.513928)
			(xy 191.334917 -116.550434) (xy 191.377322 -116.592839) (xy 191.413828 -116.640415) (xy 191.443812 -116.692349)
			(xy 191.466761 -116.747753) (xy 191.482282 -116.805678) (xy 191.49011 -116.865134) (xy 191.4906 -116.895118)
			(xy 191.4906 -117.758718) (xy 191.49011 -117.788702) (xy 191.482282 -117.848158) (xy 191.466761 -117.906083)
			(xy 191.443812 -117.961487) (xy 191.413828 -118.013421) (xy 191.377322 -118.060997) (xy 191.334917 -118.103402)
			(xy 191.287341 -118.139908) (xy 191.235407 -118.169892) (xy 191.180003 -118.192841) (xy 191.122078 -118.208362)
			(xy 191.062622 -118.21619) (xy 191.002654 -118.21619) (xy 190.943198 -118.208362) (xy 190.885273 -118.192841)
			(xy 190.829869 -118.169892) (xy 190.777935 -118.139908) (xy 190.730359 -118.103402) (xy 190.687954 -118.060997)
			(xy 190.651448 -118.013421) (xy 190.621464 -117.961487) (xy 190.598515 -117.906083) (xy 190.582994 -117.848158)
			(xy 190.575166 -117.788702) (xy 190.574676 -117.758718) (xy 186.55153 -117.758718) (xy 186.544465 -117.806728)
			(xy 186.528397 -117.860135) (xy 186.504725 -117.910632) (xy 186.473952 -117.957145) (xy 186.436735 -117.998682)
			(xy 186.393867 -118.034357) (xy 186.346261 -118.063411) (xy 186.294932 -118.085223) (xy 186.240975 -118.099329)
			(xy 186.185538 -118.105429) (xy 186.129804 -118.103392) (xy 186.074961 -118.093262) (xy 186.022177 -118.075255)
			(xy 185.972577 -118.049754) (xy 185.927219 -118.017303) (xy 185.88707 -117.978594) (xy 185.852984 -117.934451)
			(xy 185.825688 -117.885816) (xy 185.805765 -117.833725) (xy 185.793639 -117.779288) (xy 185.789568 -117.723666)
			(xy 153.950504 -117.723666) (xy 153.950923 -117.726514) (xy 153.951432 -117.7544) (xy 153.950923 -117.782286)
			(xy 153.942803 -117.837462) (xy 153.926735 -117.890869) (xy 153.903063 -117.941366) (xy 153.87229 -117.987879)
			(xy 153.835073 -118.029416) (xy 153.792205 -118.065091) (xy 153.744599 -118.094145) (xy 153.69327 -118.115957)
			(xy 153.639313 -118.130063) (xy 153.583876 -118.136163) (xy 153.528142 -118.134126) (xy 153.473299 -118.123996)
			(xy 153.420515 -118.105989) (xy 153.370915 -118.080488) (xy 153.325557 -118.048037) (xy 153.285408 -118.009328)
			(xy 153.251322 -117.965185) (xy 153.224026 -117.91655) (xy 153.204103 -117.864459) (xy 153.191977 -117.810022)
			(xy 153.187906 -117.7544) (xy 140.742924 -117.7544) (xy 140.742924 -118.265194) (xy 171.12818 -118.265194)
			(xy 171.132251 -118.209572) (xy 171.144377 -118.155135) (xy 171.1643 -118.103044) (xy 171.191596 -118.054409)
			(xy 171.225682 -118.010266) (xy 171.265831 -117.971557) (xy 171.311189 -117.939106) (xy 171.360789 -117.913605)
			(xy 171.413573 -117.895598) (xy 171.468416 -117.885468) (xy 171.52415 -117.883431) (xy 171.579587 -117.889531)
			(xy 171.633544 -117.903637) (xy 171.684873 -117.925449) (xy 171.732479 -117.954503) (xy 171.775347 -117.990178)
			(xy 171.812564 -118.031715) (xy 171.843337 -118.078228) (xy 171.867009 -118.128725) (xy 171.883077 -118.182132)
			(xy 171.891197 -118.237308) (xy 171.891706 -118.265194) (xy 171.891197 -118.29308) (xy 171.88547 -118.331996)
			(xy 178.995576 -118.331996) (xy 178.999647 -118.276374) (xy 179.011773 -118.221937) (xy 179.031696 -118.169846)
			(xy 179.058992 -118.121211) (xy 179.093078 -118.077068) (xy 179.133227 -118.038359) (xy 179.178585 -118.005908)
			(xy 179.228185 -117.980407) (xy 179.280969 -117.9624) (xy 179.335812 -117.95227) (xy 179.391546 -117.950233)
			(xy 179.446983 -117.956333) (xy 179.50094 -117.970439) (xy 179.552269 -117.992251) (xy 179.599875 -118.021305)
			(xy 179.642743 -118.05698) (xy 179.67996 -118.098517) (xy 179.710733 -118.14503) (xy 179.734405 -118.195527)
			(xy 179.750473 -118.248934) (xy 179.758593 -118.30411) (xy 179.759102 -118.331996) (xy 179.758593 -118.359882)
			(xy 179.750473 -118.415058) (xy 179.734405 -118.468465) (xy 179.710733 -118.518962) (xy 179.67996 -118.565475)
			(xy 179.642743 -118.607012) (xy 179.599875 -118.642687) (xy 179.552269 -118.671741) (xy 179.50094 -118.693553)
			(xy 179.446983 -118.707659) (xy 179.391546 -118.713759) (xy 179.335812 -118.711722) (xy 179.280969 -118.701592)
			(xy 179.228185 -118.683585) (xy 179.178585 -118.658084) (xy 179.133227 -118.625633) (xy 179.093078 -118.586924)
			(xy 179.058992 -118.542781) (xy 179.031696 -118.494146) (xy 179.011773 -118.442055) (xy 178.999647 -118.387618)
			(xy 178.995576 -118.331996) (xy 171.88547 -118.331996) (xy 171.883077 -118.348256) (xy 171.867009 -118.401663)
			(xy 171.843337 -118.45216) (xy 171.812564 -118.498673) (xy 171.775347 -118.54021) (xy 171.732479 -118.575885)
			(xy 171.684873 -118.604939) (xy 171.633544 -118.626751) (xy 171.579587 -118.640857) (xy 171.52415 -118.646957)
			(xy 171.468416 -118.64492) (xy 171.413573 -118.63479) (xy 171.360789 -118.616783) (xy 171.311189 -118.591282)
			(xy 171.265831 -118.558831) (xy 171.225682 -118.520122) (xy 171.191596 -118.475979) (xy 171.1643 -118.427344)
			(xy 171.144377 -118.375253) (xy 171.132251 -118.320816) (xy 171.12818 -118.265194) (xy 140.742924 -118.265194)
			(xy 140.742924 -120.087898) (xy 150.767796 -120.087898) (xy 150.767796 -119.224298) (xy 150.768286 -119.194314)
			(xy 150.776114 -119.134858) (xy 150.791635 -119.076933) (xy 150.814584 -119.021529) (xy 150.844568 -118.969595)
			(xy 150.881074 -118.922019) (xy 150.923479 -118.879614) (xy 150.971055 -118.843108) (xy 151.022989 -118.813124)
			(xy 151.078393 -118.790175) (xy 151.136318 -118.774654) (xy 151.195774 -118.766826) (xy 151.255742 -118.766826)
			(xy 151.315198 -118.774654) (xy 151.373123 -118.790175) (xy 151.428527 -118.813124) (xy 151.480461 -118.843108)
			(xy 151.528037 -118.879614) (xy 151.570442 -118.922019) (xy 151.606948 -118.969595) (xy 151.636932 -119.021529)
			(xy 151.659881 -119.076933) (xy 151.675402 -119.134858) (xy 151.68323 -119.194314) (xy 151.68372 -119.224298)
			(xy 151.68372 -120.086374) (xy 169.739056 -120.086374) (xy 169.739056 -119.222774) (xy 169.739546 -119.19279)
			(xy 169.747374 -119.133334) (xy 169.762895 -119.075409) (xy 169.785844 -119.020005) (xy 169.815828 -118.968071)
			(xy 169.852334 -118.920495) (xy 169.894739 -118.87809) (xy 169.942315 -118.841584) (xy 169.994249 -118.8116)
			(xy 170.049653 -118.788651) (xy 170.107578 -118.77313) (xy 170.167034 -118.765302) (xy 170.227002 -118.765302)
			(xy 170.286458 -118.77313) (xy 170.344383 -118.788651) (xy 170.399787 -118.8116) (xy 170.451721 -118.841584)
			(xy 170.499297 -118.87809) (xy 170.541702 -118.920495) (xy 170.578208 -118.968071) (xy 170.608192 -119.020005)
			(xy 170.631141 -119.075409) (xy 170.646662 -119.133334) (xy 170.65449 -119.19279) (xy 170.65498 -119.222774)
			(xy 170.65498 -119.567198) (xy 182.69966 -119.567198) (xy 182.69966 -118.703598) (xy 182.70015 -118.67363)
			(xy 182.707973 -118.614208) (xy 182.723486 -118.556315) (xy 182.746422 -118.500942) (xy 182.776389 -118.449036)
			(xy 182.812876 -118.401486) (xy 182.855256 -118.359106) (xy 182.902806 -118.322619) (xy 182.954712 -118.292652)
			(xy 183.010085 -118.269716) (xy 183.067978 -118.254203) (xy 183.1274 -118.24638) (xy 183.187336 -118.24638)
			(xy 183.246758 -118.254203) (xy 183.304651 -118.269716) (xy 183.360024 -118.292652) (xy 183.41193 -118.322619)
			(xy 183.45948 -118.359106) (xy 183.50186 -118.401486) (xy 183.538347 -118.449036) (xy 183.568314 -118.500942)
			(xy 183.59125 -118.556315) (xy 183.606763 -118.614208) (xy 183.614586 -118.67363) (xy 183.615076 -118.703598)
			(xy 183.615076 -118.711218) (xy 185.909202 -118.711218) (xy 185.913273 -118.655596) (xy 185.925399 -118.601159)
			(xy 185.945322 -118.549068) (xy 185.972618 -118.500433) (xy 186.006704 -118.45629) (xy 186.046853 -118.417581)
			(xy 186.092211 -118.38513) (xy 186.141811 -118.359629) (xy 186.194595 -118.341622) (xy 186.249438 -118.331492)
			(xy 186.305172 -118.329455) (xy 186.360609 -118.335555) (xy 186.414566 -118.349661) (xy 186.465895 -118.371473)
			(xy 186.513501 -118.400527) (xy 186.556369 -118.436202) (xy 186.593586 -118.477739) (xy 186.624359 -118.524252)
			(xy 186.648031 -118.574749) (xy 186.664099 -118.628156) (xy 186.672219 -118.683332) (xy 186.672728 -118.711218)
			(xy 186.672219 -118.739104) (xy 186.664099 -118.79428) (xy 186.648031 -118.847687) (xy 186.624359 -118.898184)
			(xy 186.593586 -118.944697) (xy 186.556369 -118.986234) (xy 186.513501 -119.021909) (xy 186.465895 -119.050963)
			(xy 186.414566 -119.072775) (xy 186.360609 -119.086881) (xy 186.305172 -119.092981) (xy 186.249438 -119.090944)
			(xy 186.194595 -119.080814) (xy 186.141811 -119.062807) (xy 186.092211 -119.037306) (xy 186.046853 -119.004855)
			(xy 186.006704 -118.966146) (xy 185.972618 -118.922003) (xy 185.945322 -118.873368) (xy 185.925399 -118.821277)
			(xy 185.913273 -118.76684) (xy 185.909202 -118.711218) (xy 183.615076 -118.711218) (xy 183.615076 -119.559324)
			(xy 197.174612 -119.559324) (xy 197.174612 -118.695724) (xy 197.175102 -118.665756) (xy 197.182925 -118.606334)
			(xy 197.198438 -118.548441) (xy 197.221374 -118.493068) (xy 197.251341 -118.441162) (xy 197.287828 -118.393612)
			(xy 197.330208 -118.351232) (xy 197.377758 -118.314745) (xy 197.429664 -118.284778) (xy 197.485037 -118.261842)
			(xy 197.54293 -118.246329) (xy 197.602352 -118.238506) (xy 197.662288 -118.238506) (xy 197.72171 -118.246329)
			(xy 197.779603 -118.261842) (xy 197.834976 -118.284778) (xy 197.886882 -118.314745) (xy 197.934432 -118.351232)
			(xy 197.976812 -118.393612) (xy 198.013299 -118.441162) (xy 198.043266 -118.493068) (xy 198.066202 -118.548441)
			(xy 198.081715 -118.606334) (xy 198.089538 -118.665756) (xy 198.090028 -118.695724) (xy 198.090028 -119.559324)
			(xy 198.089538 -119.589292) (xy 198.081715 -119.648714) (xy 198.066202 -119.706607) (xy 198.043266 -119.76198)
			(xy 198.013299 -119.813886) (xy 197.976812 -119.861436) (xy 197.934432 -119.903816) (xy 197.886882 -119.940303)
			(xy 197.834976 -119.97027) (xy 197.779603 -119.993206) (xy 197.72171 -120.008719) (xy 197.662288 -120.016542)
			(xy 197.602352 -120.016542) (xy 197.54293 -120.008719) (xy 197.485037 -119.993206) (xy 197.429664 -119.97027)
			(xy 197.377758 -119.940303) (xy 197.330208 -119.903816) (xy 197.287828 -119.861436) (xy 197.251341 -119.813886)
			(xy 197.221374 -119.76198) (xy 197.198438 -119.706607) (xy 197.182925 -119.648714) (xy 197.175102 -119.589292)
			(xy 197.174612 -119.559324) (xy 183.615076 -119.559324) (xy 183.615076 -119.567198) (xy 183.614586 -119.597166)
			(xy 183.606763 -119.656588) (xy 183.59125 -119.714481) (xy 183.568314 -119.769854) (xy 183.538347 -119.82176)
			(xy 183.50186 -119.86931) (xy 183.45948 -119.91169) (xy 183.41193 -119.948177) (xy 183.360024 -119.978144)
			(xy 183.304651 -120.00108) (xy 183.246758 -120.016593) (xy 183.187336 -120.024416) (xy 183.1274 -120.024416)
			(xy 183.067978 -120.016593) (xy 183.010085 -120.00108) (xy 182.954712 -119.978144) (xy 182.902806 -119.948177)
			(xy 182.855256 -119.91169) (xy 182.812876 -119.86931) (xy 182.776389 -119.82176) (xy 182.746422 -119.769854)
			(xy 182.723486 -119.714481) (xy 182.707973 -119.656588) (xy 182.70015 -119.597166) (xy 182.69966 -119.567198)
			(xy 170.65498 -119.567198) (xy 170.65498 -120.086374) (xy 170.65449 -120.116358) (xy 170.646662 -120.175814)
			(xy 170.631141 -120.233739) (xy 170.608192 -120.289143) (xy 170.578208 -120.341077) (xy 170.541702 -120.388653)
			(xy 170.499297 -120.431058) (xy 170.451721 -120.467564) (xy 170.399787 -120.497548) (xy 170.344383 -120.520497)
			(xy 170.286458 -120.536018) (xy 170.227002 -120.543846) (xy 170.167034 -120.543846) (xy 170.107578 -120.536018)
			(xy 170.049653 -120.520497) (xy 169.994249 -120.497548) (xy 169.942315 -120.467564) (xy 169.894739 -120.431058)
			(xy 169.852334 -120.388653) (xy 169.815828 -120.341077) (xy 169.785844 -120.289143) (xy 169.762895 -120.233739)
			(xy 169.747374 -120.175814) (xy 169.739546 -120.116358) (xy 169.739056 -120.086374) (xy 151.68372 -120.086374)
			(xy 151.68372 -120.087898) (xy 151.68323 -120.117882) (xy 151.675402 -120.177338) (xy 151.659881 -120.235263)
			(xy 151.636932 -120.290667) (xy 151.606948 -120.342601) (xy 151.570442 -120.390177) (xy 151.528037 -120.432582)
			(xy 151.480461 -120.469088) (xy 151.428527 -120.499072) (xy 151.373123 -120.522021) (xy 151.315198 -120.537542)
			(xy 151.255742 -120.54537) (xy 151.195774 -120.54537) (xy 151.136318 -120.537542) (xy 151.078393 -120.522021)
			(xy 151.022989 -120.499072) (xy 150.971055 -120.469088) (xy 150.923479 -120.432582) (xy 150.881074 -120.390177)
			(xy 150.844568 -120.342601) (xy 150.814584 -120.290667) (xy 150.791635 -120.235263) (xy 150.776114 -120.177338)
			(xy 150.768286 -120.117882) (xy 150.767796 -120.087898) (xy 140.742924 -120.087898) (xy 140.742924 -121.894346)
			(xy 153.409904 -121.894346) (xy 153.409904 -121.030746) (xy 153.410394 -121.000762) (xy 153.418222 -120.941306)
			(xy 153.433743 -120.883381) (xy 153.456692 -120.827977) (xy 153.486676 -120.776043) (xy 153.523182 -120.728467)
			(xy 153.565587 -120.686062) (xy 153.613163 -120.649556) (xy 153.665097 -120.619572) (xy 153.720501 -120.596623)
			(xy 153.778426 -120.581102) (xy 153.837882 -120.573274) (xy 153.89785 -120.573274) (xy 153.957306 -120.581102)
			(xy 154.015231 -120.596623) (xy 154.070635 -120.619572) (xy 154.122569 -120.649556) (xy 154.170145 -120.686062)
			(xy 154.21255 -120.728467) (xy 154.249056 -120.776043) (xy 154.27904 -120.827977) (xy 154.301989 -120.883381)
			(xy 154.31751 -120.941306) (xy 154.325338 -121.000762) (xy 154.325828 -121.030746) (xy 154.325828 -121.886472)
			(xy 167.884856 -121.886472) (xy 167.884856 -121.022872) (xy 167.885346 -120.992888) (xy 167.893174 -120.933432)
			(xy 167.908695 -120.875507) (xy 167.931644 -120.820103) (xy 167.961628 -120.768169) (xy 167.998134 -120.720593)
			(xy 168.040539 -120.678188) (xy 168.088115 -120.641682) (xy 168.140049 -120.611698) (xy 168.195453 -120.588749)
			(xy 168.253378 -120.573228) (xy 168.312834 -120.5654) (xy 168.372802 -120.5654) (xy 168.432258 -120.573228)
			(xy 168.490183 -120.588749) (xy 168.545587 -120.611698) (xy 168.597521 -120.641682) (xy 168.645097 -120.678188)
			(xy 168.687502 -120.720593) (xy 168.724008 -120.768169) (xy 168.753992 -120.820103) (xy 168.776941 -120.875507)
			(xy 168.792462 -120.933432) (xy 168.80029 -120.992888) (xy 168.80078 -121.022872) (xy 168.80078 -121.367296)
			(xy 180.84546 -121.367296) (xy 180.84546 -120.503696) (xy 180.84595 -120.473728) (xy 180.853773 -120.414306)
			(xy 180.869286 -120.356413) (xy 180.892222 -120.30104) (xy 180.922189 -120.249134) (xy 180.958676 -120.201584)
			(xy 181.001056 -120.159204) (xy 181.048606 -120.122717) (xy 181.100512 -120.09275) (xy 181.155885 -120.069814)
			(xy 181.213778 -120.054301) (xy 181.2732 -120.046478) (xy 181.333136 -120.046478) (xy 181.392558 -120.054301)
			(xy 181.450451 -120.069814) (xy 181.505824 -120.09275) (xy 181.55773 -120.122717) (xy 181.60528 -120.159204)
			(xy 181.64766 -120.201584) (xy 181.684147 -120.249134) (xy 181.714114 -120.30104) (xy 181.73705 -120.356413)
			(xy 181.752563 -120.414306) (xy 181.760386 -120.473728) (xy 181.760876 -120.503696) (xy 181.760876 -121.365772)
			(xy 199.81672 -121.365772) (xy 199.81672 -120.502172) (xy 199.81721 -120.472204) (xy 199.825033 -120.412782)
			(xy 199.840546 -120.354889) (xy 199.863482 -120.299516) (xy 199.893449 -120.24761) (xy 199.929936 -120.20006)
			(xy 199.972316 -120.15768) (xy 200.019866 -120.121193) (xy 200.071772 -120.091226) (xy 200.127145 -120.06829)
			(xy 200.185038 -120.052777) (xy 200.24446 -120.044954) (xy 200.304396 -120.044954) (xy 200.363818 -120.052777)
			(xy 200.421711 -120.06829) (xy 200.477084 -120.091226) (xy 200.52899 -120.121193) (xy 200.57654 -120.15768)
			(xy 200.61892 -120.20006) (xy 200.655407 -120.24761) (xy 200.685374 -120.299516) (xy 200.70831 -120.354889)
			(xy 200.723823 -120.412782) (xy 200.731646 -120.472204) (xy 200.732136 -120.502172) (xy 200.732136 -121.365772)
			(xy 200.731646 -121.39574) (xy 200.723823 -121.455162) (xy 200.70831 -121.513055) (xy 200.685374 -121.568428)
			(xy 200.655407 -121.620334) (xy 200.61892 -121.667884) (xy 200.57654 -121.710264) (xy 200.52899 -121.746751)
			(xy 200.477084 -121.776718) (xy 200.421711 -121.799654) (xy 200.363818 -121.815167) (xy 200.304396 -121.82299)
			(xy 200.24446 -121.82299) (xy 200.185038 -121.815167) (xy 200.127145 -121.799654) (xy 200.071772 -121.776718)
			(xy 200.019866 -121.746751) (xy 199.972316 -121.710264) (xy 199.929936 -121.667884) (xy 199.893449 -121.620334)
			(xy 199.863482 -121.568428) (xy 199.840546 -121.513055) (xy 199.825033 -121.455162) (xy 199.81721 -121.39574)
			(xy 199.81672 -121.365772) (xy 181.760876 -121.365772) (xy 181.760876 -121.367296) (xy 181.760386 -121.397264)
			(xy 181.752563 -121.456686) (xy 181.73705 -121.514579) (xy 181.714114 -121.569952) (xy 181.684147 -121.621858)
			(xy 181.64766 -121.669408) (xy 181.60528 -121.711788) (xy 181.55773 -121.748275) (xy 181.505824 -121.778242)
			(xy 181.450451 -121.801178) (xy 181.392558 -121.816691) (xy 181.333136 -121.824514) (xy 181.2732 -121.824514)
			(xy 181.213778 -121.816691) (xy 181.155885 -121.801178) (xy 181.100512 -121.778242) (xy 181.048606 -121.748275)
			(xy 181.001056 -121.711788) (xy 180.958676 -121.669408) (xy 180.922189 -121.621858) (xy 180.892222 -121.569952)
			(xy 180.869286 -121.514579) (xy 180.853773 -121.456686) (xy 180.84595 -121.397264) (xy 180.84546 -121.367296)
			(xy 168.80078 -121.367296) (xy 168.80078 -121.886472) (xy 168.80029 -121.916456) (xy 168.792462 -121.975912)
			(xy 168.776941 -122.033837) (xy 168.753992 -122.089241) (xy 168.724008 -122.141175) (xy 168.687502 -122.188751)
			(xy 168.645097 -122.231156) (xy 168.597521 -122.267662) (xy 168.545587 -122.297646) (xy 168.490183 -122.320595)
			(xy 168.432258 -122.336116) (xy 168.372802 -122.343944) (xy 168.312834 -122.343944) (xy 168.253378 -122.336116)
			(xy 168.195453 -122.320595) (xy 168.140049 -122.297646) (xy 168.088115 -122.267662) (xy 168.040539 -122.231156)
			(xy 167.998134 -122.188751) (xy 167.961628 -122.141175) (xy 167.931644 -122.089241) (xy 167.908695 -122.033837)
			(xy 167.893174 -121.975912) (xy 167.885346 -121.916456) (xy 167.884856 -121.886472) (xy 154.325828 -121.886472)
			(xy 154.325828 -121.894346) (xy 154.325338 -121.92433) (xy 154.31751 -121.983786) (xy 154.301989 -122.041711)
			(xy 154.27904 -122.097115) (xy 154.249056 -122.149049) (xy 154.21255 -122.196625) (xy 154.170145 -122.23903)
			(xy 154.122569 -122.275536) (xy 154.070635 -122.30552) (xy 154.015231 -122.328469) (xy 153.957306 -122.34399)
			(xy 153.89785 -122.351818) (xy 153.837882 -122.351818) (xy 153.778426 -122.34399) (xy 153.720501 -122.328469)
			(xy 153.665097 -122.30552) (xy 153.613163 -122.275536) (xy 153.565587 -122.23903) (xy 153.523182 -122.196625)
			(xy 153.486676 -122.149049) (xy 153.456692 -122.097115) (xy 153.433743 -122.041711) (xy 153.418222 -121.983786)
			(xy 153.410394 -121.92433) (xy 153.409904 -121.894346) (xy 140.742924 -121.894346) (xy 140.742924 -123.68784)
			(xy 150.767796 -123.68784) (xy 150.767796 -122.82424) (xy 150.768286 -122.794256) (xy 150.776114 -122.7348)
			(xy 150.791635 -122.676875) (xy 150.814584 -122.621471) (xy 150.844568 -122.569537) (xy 150.881074 -122.521961)
			(xy 150.923479 -122.479556) (xy 150.971055 -122.44305) (xy 151.022989 -122.413066) (xy 151.078393 -122.390117)
			(xy 151.136318 -122.374596) (xy 151.195774 -122.366768) (xy 151.255742 -122.366768) (xy 151.315198 -122.374596)
			(xy 151.373123 -122.390117) (xy 151.428527 -122.413066) (xy 151.480461 -122.44305) (xy 151.528037 -122.479556)
			(xy 151.570442 -122.521961) (xy 151.606948 -122.569537) (xy 151.636932 -122.621471) (xy 151.659881 -122.676875)
			(xy 151.675402 -122.7348) (xy 151.68323 -122.794256) (xy 151.68372 -122.82424) (xy 151.68372 -123.686316)
			(xy 169.739056 -123.686316) (xy 169.739056 -122.822716) (xy 169.739546 -122.792732) (xy 169.747374 -122.733276)
			(xy 169.762895 -122.675351) (xy 169.785844 -122.619947) (xy 169.815828 -122.568013) (xy 169.852334 -122.520437)
			(xy 169.894739 -122.478032) (xy 169.942315 -122.441526) (xy 169.994249 -122.411542) (xy 170.049653 -122.388593)
			(xy 170.107578 -122.373072) (xy 170.167034 -122.365244) (xy 170.227002 -122.365244) (xy 170.286458 -122.373072)
			(xy 170.344383 -122.388593) (xy 170.399787 -122.411542) (xy 170.451721 -122.441526) (xy 170.499297 -122.478032)
			(xy 170.541702 -122.520437) (xy 170.578208 -122.568013) (xy 170.608192 -122.619947) (xy 170.631141 -122.675351)
			(xy 170.646662 -122.733276) (xy 170.65449 -122.792732) (xy 170.65498 -122.822716) (xy 170.65498 -123.16714)
			(xy 182.69966 -123.16714) (xy 182.69966 -122.30354) (xy 182.70015 -122.273572) (xy 182.707973 -122.21415)
			(xy 182.723486 -122.156257) (xy 182.746422 -122.100884) (xy 182.776389 -122.048978) (xy 182.812876 -122.001428)
			(xy 182.855256 -121.959048) (xy 182.902806 -121.922561) (xy 182.954712 -121.892594) (xy 183.010085 -121.869658)
			(xy 183.067978 -121.854145) (xy 183.1274 -121.846322) (xy 183.187336 -121.846322) (xy 183.246758 -121.854145)
			(xy 183.304651 -121.869658) (xy 183.360024 -121.892594) (xy 183.41193 -121.922561) (xy 183.45948 -121.959048)
			(xy 183.50186 -122.001428) (xy 183.538347 -122.048978) (xy 183.568314 -122.100884) (xy 183.59125 -122.156257)
			(xy 183.606763 -122.21415) (xy 183.614586 -122.273572) (xy 183.615076 -122.30354) (xy 183.615076 -123.159266)
			(xy 197.174612 -123.159266) (xy 197.174612 -122.295666) (xy 197.175102 -122.265698) (xy 197.182925 -122.206276)
			(xy 197.198438 -122.148383) (xy 197.221374 -122.09301) (xy 197.251341 -122.041104) (xy 197.287828 -121.993554)
			(xy 197.330208 -121.951174) (xy 197.377758 -121.914687) (xy 197.429664 -121.88472) (xy 197.485037 -121.861784)
			(xy 197.54293 -121.846271) (xy 197.602352 -121.838448) (xy 197.662288 -121.838448) (xy 197.72171 -121.846271)
			(xy 197.779603 -121.861784) (xy 197.834976 -121.88472) (xy 197.886882 -121.914687) (xy 197.934432 -121.951174)
			(xy 197.976812 -121.993554) (xy 198.013299 -122.041104) (xy 198.043266 -122.09301) (xy 198.066202 -122.148383)
			(xy 198.081715 -122.206276) (xy 198.089538 -122.265698) (xy 198.090028 -122.295666) (xy 198.090028 -123.159266)
			(xy 198.089538 -123.189234) (xy 198.081715 -123.248656) (xy 198.066202 -123.306549) (xy 198.043266 -123.361922)
			(xy 198.013299 -123.413828) (xy 197.976812 -123.461378) (xy 197.934432 -123.503758) (xy 197.886882 -123.540245)
			(xy 197.834976 -123.570212) (xy 197.779603 -123.593148) (xy 197.72171 -123.608661) (xy 197.662288 -123.616484)
			(xy 197.602352 -123.616484) (xy 197.54293 -123.608661) (xy 197.485037 -123.593148) (xy 197.429664 -123.570212)
			(xy 197.377758 -123.540245) (xy 197.330208 -123.503758) (xy 197.287828 -123.461378) (xy 197.251341 -123.413828)
			(xy 197.221374 -123.361922) (xy 197.198438 -123.306549) (xy 197.182925 -123.248656) (xy 197.175102 -123.189234)
			(xy 197.174612 -123.159266) (xy 183.615076 -123.159266) (xy 183.615076 -123.16714) (xy 183.614586 -123.197108)
			(xy 183.606763 -123.25653) (xy 183.59125 -123.314423) (xy 183.568314 -123.369796) (xy 183.538347 -123.421702)
			(xy 183.50186 -123.469252) (xy 183.45948 -123.511632) (xy 183.41193 -123.548119) (xy 183.360024 -123.578086)
			(xy 183.304651 -123.601022) (xy 183.246758 -123.616535) (xy 183.187336 -123.624358) (xy 183.1274 -123.624358)
			(xy 183.067978 -123.616535) (xy 183.010085 -123.601022) (xy 182.954712 -123.578086) (xy 182.902806 -123.548119)
			(xy 182.855256 -123.511632) (xy 182.812876 -123.469252) (xy 182.776389 -123.421702) (xy 182.746422 -123.369796)
			(xy 182.723486 -123.314423) (xy 182.707973 -123.25653) (xy 182.70015 -123.197108) (xy 182.69966 -123.16714)
			(xy 170.65498 -123.16714) (xy 170.65498 -123.686316) (xy 170.65449 -123.7163) (xy 170.646662 -123.775756)
			(xy 170.631141 -123.833681) (xy 170.608192 -123.889085) (xy 170.578208 -123.941019) (xy 170.541702 -123.988595)
			(xy 170.499297 -124.031) (xy 170.451721 -124.067506) (xy 170.399787 -124.09749) (xy 170.344383 -124.120439)
			(xy 170.286458 -124.13596) (xy 170.227002 -124.143788) (xy 170.167034 -124.143788) (xy 170.107578 -124.13596)
			(xy 170.049653 -124.120439) (xy 169.994249 -124.09749) (xy 169.942315 -124.067506) (xy 169.894739 -124.031)
			(xy 169.852334 -123.988595) (xy 169.815828 -123.941019) (xy 169.785844 -123.889085) (xy 169.762895 -123.833681)
			(xy 169.747374 -123.775756) (xy 169.739546 -123.7163) (xy 169.739056 -123.686316) (xy 151.68372 -123.686316)
			(xy 151.68372 -123.68784) (xy 151.68323 -123.717824) (xy 151.675402 -123.77728) (xy 151.659881 -123.835205)
			(xy 151.636932 -123.890609) (xy 151.606948 -123.942543) (xy 151.570442 -123.990119) (xy 151.528037 -124.032524)
			(xy 151.480461 -124.06903) (xy 151.428527 -124.099014) (xy 151.373123 -124.121963) (xy 151.315198 -124.137484)
			(xy 151.255742 -124.145312) (xy 151.195774 -124.145312) (xy 151.136318 -124.137484) (xy 151.078393 -124.121963)
			(xy 151.022989 -124.099014) (xy 150.971055 -124.06903) (xy 150.923479 -124.032524) (xy 150.881074 -123.990119)
			(xy 150.844568 -123.942543) (xy 150.814584 -123.890609) (xy 150.791635 -123.835205) (xy 150.776114 -123.77728)
			(xy 150.768286 -123.717824) (xy 150.767796 -123.68784) (xy 140.742924 -123.68784) (xy 140.742924 -125.494542)
			(xy 153.409904 -125.494542) (xy 153.409904 -124.630942) (xy 153.410394 -124.600958) (xy 153.418222 -124.541502)
			(xy 153.433743 -124.483577) (xy 153.456692 -124.428173) (xy 153.486676 -124.376239) (xy 153.523182 -124.328663)
			(xy 153.565587 -124.286258) (xy 153.613163 -124.249752) (xy 153.665097 -124.219768) (xy 153.720501 -124.196819)
			(xy 153.778426 -124.181298) (xy 153.837882 -124.17347) (xy 153.89785 -124.17347) (xy 153.957306 -124.181298)
			(xy 154.015231 -124.196819) (xy 154.070635 -124.219768) (xy 154.122569 -124.249752) (xy 154.170145 -124.286258)
			(xy 154.21255 -124.328663) (xy 154.249056 -124.376239) (xy 154.27904 -124.428173) (xy 154.301989 -124.483577)
			(xy 154.31751 -124.541502) (xy 154.325338 -124.600958) (xy 154.325828 -124.630942) (xy 154.325828 -125.486414)
			(xy 167.884856 -125.486414) (xy 167.884856 -124.622814) (xy 167.885346 -124.59283) (xy 167.893174 -124.533374)
			(xy 167.908695 -124.475449) (xy 167.931644 -124.420045) (xy 167.961628 -124.368111) (xy 167.998134 -124.320535)
			(xy 168.040539 -124.27813) (xy 168.088115 -124.241624) (xy 168.140049 -124.21164) (xy 168.195453 -124.188691)
			(xy 168.253378 -124.17317) (xy 168.312834 -124.165342) (xy 168.372802 -124.165342) (xy 168.432258 -124.17317)
			(xy 168.490183 -124.188691) (xy 168.545587 -124.21164) (xy 168.597521 -124.241624) (xy 168.645097 -124.27813)
			(xy 168.687502 -124.320535) (xy 168.724008 -124.368111) (xy 168.753992 -124.420045) (xy 168.776941 -124.475449)
			(xy 168.792462 -124.533374) (xy 168.80029 -124.59283) (xy 168.80078 -124.622814) (xy 168.80078 -124.967238)
			(xy 180.84546 -124.967238) (xy 180.84546 -124.103638) (xy 180.84595 -124.07367) (xy 180.853773 -124.014248)
			(xy 180.869286 -123.956355) (xy 180.892222 -123.900982) (xy 180.922189 -123.849076) (xy 180.958676 -123.801526)
			(xy 181.001056 -123.759146) (xy 181.048606 -123.722659) (xy 181.100512 -123.692692) (xy 181.155885 -123.669756)
			(xy 181.213778 -123.654243) (xy 181.2732 -123.64642) (xy 181.333136 -123.64642) (xy 181.392558 -123.654243)
			(xy 181.450451 -123.669756) (xy 181.505824 -123.692692) (xy 181.55773 -123.722659) (xy 181.60528 -123.759146)
			(xy 181.64766 -123.801526) (xy 181.684147 -123.849076) (xy 181.714114 -123.900982) (xy 181.73705 -123.956355)
			(xy 181.752563 -124.014248) (xy 181.760386 -124.07367) (xy 181.760876 -124.103638) (xy 181.760876 -124.965714)
			(xy 199.81672 -124.965714) (xy 199.81672 -124.102114) (xy 199.81721 -124.072146) (xy 199.825033 -124.012724)
			(xy 199.840546 -123.954831) (xy 199.863482 -123.899458) (xy 199.893449 -123.847552) (xy 199.929936 -123.800002)
			(xy 199.972316 -123.757622) (xy 200.019866 -123.721135) (xy 200.071772 -123.691168) (xy 200.127145 -123.668232)
			(xy 200.185038 -123.652719) (xy 200.24446 -123.644896) (xy 200.304396 -123.644896) (xy 200.363818 -123.652719)
			(xy 200.421711 -123.668232) (xy 200.477084 -123.691168) (xy 200.52899 -123.721135) (xy 200.57654 -123.757622)
			(xy 200.61892 -123.800002) (xy 200.655407 -123.847552) (xy 200.685374 -123.899458) (xy 200.70831 -123.954831)
			(xy 200.723823 -124.012724) (xy 200.731646 -124.072146) (xy 200.732136 -124.102114) (xy 200.732136 -124.965714)
			(xy 200.731646 -124.995682) (xy 200.723823 -125.055104) (xy 200.70831 -125.112997) (xy 200.685374 -125.16837)
			(xy 200.655407 -125.220276) (xy 200.61892 -125.267826) (xy 200.57654 -125.310206) (xy 200.52899 -125.346693)
			(xy 200.477084 -125.37666) (xy 200.421711 -125.399596) (xy 200.363818 -125.415109) (xy 200.304396 -125.422932)
			(xy 200.24446 -125.422932) (xy 200.185038 -125.415109) (xy 200.127145 -125.399596) (xy 200.071772 -125.37666)
			(xy 200.019866 -125.346693) (xy 199.972316 -125.310206) (xy 199.929936 -125.267826) (xy 199.893449 -125.220276)
			(xy 199.863482 -125.16837) (xy 199.840546 -125.112997) (xy 199.825033 -125.055104) (xy 199.81721 -124.995682)
			(xy 199.81672 -124.965714) (xy 181.760876 -124.965714) (xy 181.760876 -124.967238) (xy 181.760386 -124.997206)
			(xy 181.752563 -125.056628) (xy 181.73705 -125.114521) (xy 181.714114 -125.169894) (xy 181.684147 -125.2218)
			(xy 181.64766 -125.26935) (xy 181.60528 -125.31173) (xy 181.55773 -125.348217) (xy 181.505824 -125.378184)
			(xy 181.450451 -125.40112) (xy 181.392558 -125.416633) (xy 181.333136 -125.424456) (xy 181.2732 -125.424456)
			(xy 181.213778 -125.416633) (xy 181.155885 -125.40112) (xy 181.100512 -125.378184) (xy 181.048606 -125.348217)
			(xy 181.001056 -125.31173) (xy 180.958676 -125.26935) (xy 180.922189 -125.2218) (xy 180.892222 -125.169894)
			(xy 180.869286 -125.114521) (xy 180.853773 -125.056628) (xy 180.84595 -124.997206) (xy 180.84546 -124.967238)
			(xy 168.80078 -124.967238) (xy 168.80078 -125.486414) (xy 168.80029 -125.516398) (xy 168.792462 -125.575854)
			(xy 168.776941 -125.633779) (xy 168.753992 -125.689183) (xy 168.724008 -125.741117) (xy 168.687502 -125.788693)
			(xy 168.645097 -125.831098) (xy 168.597521 -125.867604) (xy 168.545587 -125.897588) (xy 168.490183 -125.920537)
			(xy 168.432258 -125.936058) (xy 168.372802 -125.943886) (xy 168.312834 -125.943886) (xy 168.253378 -125.936058)
			(xy 168.195453 -125.920537) (xy 168.140049 -125.897588) (xy 168.088115 -125.867604) (xy 168.040539 -125.831098)
			(xy 167.998134 -125.788693) (xy 167.961628 -125.741117) (xy 167.931644 -125.689183) (xy 167.908695 -125.633779)
			(xy 167.893174 -125.575854) (xy 167.885346 -125.516398) (xy 167.884856 -125.486414) (xy 154.325828 -125.486414)
			(xy 154.325828 -125.494542) (xy 154.325338 -125.524526) (xy 154.31751 -125.583982) (xy 154.301989 -125.641907)
			(xy 154.27904 -125.697311) (xy 154.249056 -125.749245) (xy 154.21255 -125.796821) (xy 154.170145 -125.839226)
			(xy 154.122569 -125.875732) (xy 154.070635 -125.905716) (xy 154.015231 -125.928665) (xy 153.957306 -125.944186)
			(xy 153.89785 -125.952014) (xy 153.837882 -125.952014) (xy 153.778426 -125.944186) (xy 153.720501 -125.928665)
			(xy 153.665097 -125.905716) (xy 153.613163 -125.875732) (xy 153.565587 -125.839226) (xy 153.523182 -125.796821)
			(xy 153.486676 -125.749245) (xy 153.456692 -125.697311) (xy 153.433743 -125.641907) (xy 153.418222 -125.583982)
			(xy 153.410394 -125.524526) (xy 153.409904 -125.494542) (xy 140.742924 -125.494542) (xy 140.742924 -131.297934)
			(xy 150.767796 -131.297934) (xy 150.767796 -130.434334) (xy 150.768286 -130.40435) (xy 150.776114 -130.344894)
			(xy 150.791635 -130.286969) (xy 150.814584 -130.231565) (xy 150.844568 -130.179631) (xy 150.881074 -130.132055)
			(xy 150.923479 -130.08965) (xy 150.971055 -130.053144) (xy 151.022989 -130.02316) (xy 151.078393 -130.000211)
			(xy 151.136318 -129.98469) (xy 151.195774 -129.976862) (xy 151.255742 -129.976862) (xy 151.315198 -129.98469)
			(xy 151.373123 -130.000211) (xy 151.428527 -130.02316) (xy 151.480461 -130.053144) (xy 151.528037 -130.08965)
			(xy 151.570442 -130.132055) (xy 151.606948 -130.179631) (xy 151.636932 -130.231565) (xy 151.659881 -130.286969)
			(xy 151.675402 -130.344894) (xy 151.68323 -130.40435) (xy 151.68372 -130.434334) (xy 151.68372 -131.29641)
			(xy 169.739056 -131.29641) (xy 169.739056 -130.43281) (xy 169.739546 -130.402826) (xy 169.747374 -130.34337)
			(xy 169.762895 -130.285445) (xy 169.785844 -130.230041) (xy 169.815828 -130.178107) (xy 169.852334 -130.130531)
			(xy 169.894739 -130.088126) (xy 169.942315 -130.05162) (xy 169.994249 -130.021636) (xy 170.049653 -129.998687)
			(xy 170.107578 -129.983166) (xy 170.167034 -129.975338) (xy 170.227002 -129.975338) (xy 170.286458 -129.983166)
			(xy 170.344383 -129.998687) (xy 170.399787 -130.021636) (xy 170.451721 -130.05162) (xy 170.499297 -130.088126)
			(xy 170.541702 -130.130531) (xy 170.578208 -130.178107) (xy 170.608192 -130.230041) (xy 170.631141 -130.285445)
			(xy 170.646662 -130.34337) (xy 170.65449 -130.402826) (xy 170.65498 -130.43281) (xy 170.65498 -131.29641)
			(xy 170.65449 -131.326394) (xy 170.646662 -131.38585) (xy 170.631141 -131.443775) (xy 170.608192 -131.499179)
			(xy 170.578208 -131.551113) (xy 170.541702 -131.598689) (xy 170.499297 -131.641094) (xy 170.451721 -131.6776)
			(xy 170.399787 -131.707584) (xy 170.344383 -131.730533) (xy 170.286458 -131.746054) (xy 170.227002 -131.753882)
			(xy 170.167034 -131.753882) (xy 170.107578 -131.746054) (xy 170.049653 -131.730533) (xy 169.994249 -131.707584)
			(xy 169.942315 -131.6776) (xy 169.894739 -131.641094) (xy 169.852334 -131.598689) (xy 169.815828 -131.551113)
			(xy 169.785844 -131.499179) (xy 169.762895 -131.443775) (xy 169.747374 -131.38585) (xy 169.739546 -131.326394)
			(xy 169.739056 -131.29641) (xy 151.68372 -131.29641) (xy 151.68372 -131.297934) (xy 151.68323 -131.327918)
			(xy 151.675402 -131.387374) (xy 151.659881 -131.445299) (xy 151.636932 -131.500703) (xy 151.606948 -131.552637)
			(xy 151.570442 -131.600213) (xy 151.528037 -131.642618) (xy 151.480461 -131.679124) (xy 151.428527 -131.709108)
			(xy 151.373123 -131.732057) (xy 151.315198 -131.747578) (xy 151.255742 -131.755406) (xy 151.195774 -131.755406)
			(xy 151.136318 -131.747578) (xy 151.078393 -131.732057) (xy 151.022989 -131.709108) (xy 150.971055 -131.679124)
			(xy 150.923479 -131.642618) (xy 150.881074 -131.600213) (xy 150.844568 -131.552637) (xy 150.814584 -131.500703)
			(xy 150.791635 -131.445299) (xy 150.776114 -131.387374) (xy 150.768286 -131.327918) (xy 150.767796 -131.297934)
			(xy 140.742924 -131.297934) (xy 140.742924 -133.104382) (xy 153.409904 -133.104382) (xy 153.409904 -132.240782)
			(xy 153.410394 -132.210798) (xy 153.418222 -132.151342) (xy 153.433743 -132.093417) (xy 153.456692 -132.038013)
			(xy 153.486676 -131.986079) (xy 153.523182 -131.938503) (xy 153.565587 -131.896098) (xy 153.613163 -131.859592)
			(xy 153.665097 -131.829608) (xy 153.720501 -131.806659) (xy 153.778426 -131.791138) (xy 153.837882 -131.78331)
			(xy 153.89785 -131.78331) (xy 153.957306 -131.791138) (xy 154.015231 -131.806659) (xy 154.070635 -131.829608)
			(xy 154.122569 -131.859592) (xy 154.170145 -131.896098) (xy 154.21255 -131.938503) (xy 154.249056 -131.986079)
			(xy 154.27904 -132.038013) (xy 154.301989 -132.093417) (xy 154.31751 -132.151342) (xy 154.325338 -132.210798)
			(xy 154.325828 -132.240782) (xy 154.325828 -133.096508) (xy 167.884856 -133.096508) (xy 167.884856 -132.232908)
			(xy 167.885346 -132.202924) (xy 167.893174 -132.143468) (xy 167.908695 -132.085543) (xy 167.931644 -132.030139)
			(xy 167.961628 -131.978205) (xy 167.998134 -131.930629) (xy 168.040539 -131.888224) (xy 168.088115 -131.851718)
			(xy 168.140049 -131.821734) (xy 168.195453 -131.798785) (xy 168.253378 -131.783264) (xy 168.312834 -131.775436)
			(xy 168.372802 -131.775436) (xy 168.432258 -131.783264) (xy 168.490183 -131.798785) (xy 168.545587 -131.821734)
			(xy 168.597521 -131.851718) (xy 168.645097 -131.888224) (xy 168.687502 -131.930629) (xy 168.724008 -131.978205)
			(xy 168.753992 -132.030139) (xy 168.776941 -132.085543) (xy 168.792462 -132.143468) (xy 168.80029 -132.202924)
			(xy 168.80078 -132.232908) (xy 168.80078 -133.096508) (xy 168.80029 -133.126492) (xy 168.792462 -133.185948)
			(xy 168.776941 -133.243873) (xy 168.753992 -133.299277) (xy 168.724008 -133.351211) (xy 168.687502 -133.398787)
			(xy 168.645097 -133.441192) (xy 168.597521 -133.477698) (xy 168.545587 -133.507682) (xy 168.490183 -133.530631)
			(xy 168.432258 -133.546152) (xy 168.372802 -133.55398) (xy 168.312834 -133.55398) (xy 168.253378 -133.546152)
			(xy 168.195453 -133.530631) (xy 168.140049 -133.507682) (xy 168.088115 -133.477698) (xy 168.040539 -133.441192)
			(xy 167.998134 -133.398787) (xy 167.961628 -133.351211) (xy 167.931644 -133.299277) (xy 167.908695 -133.243873)
			(xy 167.893174 -133.185948) (xy 167.885346 -133.126492) (xy 167.884856 -133.096508) (xy 154.325828 -133.096508)
			(xy 154.325828 -133.104382) (xy 154.325338 -133.134366) (xy 154.31751 -133.193822) (xy 154.301989 -133.251747)
			(xy 154.27904 -133.307151) (xy 154.249056 -133.359085) (xy 154.21255 -133.406661) (xy 154.170145 -133.449066)
			(xy 154.122569 -133.485572) (xy 154.070635 -133.515556) (xy 154.015231 -133.538505) (xy 153.957306 -133.554026)
			(xy 153.89785 -133.561854) (xy 153.837882 -133.561854) (xy 153.778426 -133.554026) (xy 153.720501 -133.538505)
			(xy 153.665097 -133.515556) (xy 153.613163 -133.485572) (xy 153.565587 -133.449066) (xy 153.523182 -133.406661)
			(xy 153.486676 -133.359085) (xy 153.456692 -133.307151) (xy 153.433743 -133.251747) (xy 153.418222 -133.193822)
			(xy 153.410394 -133.134366) (xy 153.409904 -133.104382) (xy 140.742924 -133.104382) (xy 140.742924 -134.897876)
			(xy 150.767796 -134.897876) (xy 150.767796 -134.034276) (xy 150.768286 -134.004292) (xy 150.776114 -133.944836)
			(xy 150.791635 -133.886911) (xy 150.814584 -133.831507) (xy 150.844568 -133.779573) (xy 150.881074 -133.731997)
			(xy 150.923479 -133.689592) (xy 150.971055 -133.653086) (xy 151.022989 -133.623102) (xy 151.078393 -133.600153)
			(xy 151.136318 -133.584632) (xy 151.195774 -133.576804) (xy 151.255742 -133.576804) (xy 151.315198 -133.584632)
			(xy 151.373123 -133.600153) (xy 151.428527 -133.623102) (xy 151.480461 -133.653086) (xy 151.528037 -133.689592)
			(xy 151.570442 -133.731997) (xy 151.606948 -133.779573) (xy 151.636932 -133.831507) (xy 151.659881 -133.886911)
			(xy 151.675402 -133.944836) (xy 151.68323 -134.004292) (xy 151.68372 -134.034276) (xy 151.68372 -134.897876)
			(xy 151.68323 -134.92786) (xy 151.675402 -134.987316) (xy 151.659881 -135.045241) (xy 151.636932 -135.100645)
			(xy 151.606948 -135.152579) (xy 151.570442 -135.200155) (xy 151.528037 -135.24256) (xy 151.480461 -135.279066)
			(xy 151.428527 -135.30905) (xy 151.373123 -135.331999) (xy 151.315198 -135.34752) (xy 151.255742 -135.355348)
			(xy 151.195774 -135.355348) (xy 151.136318 -135.34752) (xy 151.078393 -135.331999) (xy 151.022989 -135.30905)
			(xy 150.971055 -135.279066) (xy 150.923479 -135.24256) (xy 150.881074 -135.200155) (xy 150.844568 -135.152579)
			(xy 150.814584 -135.100645) (xy 150.791635 -135.045241) (xy 150.776114 -134.987316) (xy 150.768286 -134.92786)
			(xy 150.767796 -134.897876) (xy 140.742924 -134.897876) (xy 140.742924 -136.704324) (xy 153.409904 -136.704324)
			(xy 153.409904 -135.840724) (xy 153.410394 -135.81074) (xy 153.418222 -135.751284) (xy 153.433743 -135.693359)
			(xy 153.456692 -135.637955) (xy 153.486676 -135.586021) (xy 153.523182 -135.538445) (xy 153.565587 -135.49604)
			(xy 153.613163 -135.459534) (xy 153.665097 -135.42955) (xy 153.720501 -135.406601) (xy 153.778426 -135.39108)
			(xy 153.837882 -135.383252) (xy 153.89785 -135.383252) (xy 153.957306 -135.39108) (xy 154.015231 -135.406601)
			(xy 154.070635 -135.42955) (xy 154.122569 -135.459534) (xy 154.170145 -135.49604) (xy 154.21255 -135.538445)
			(xy 154.249056 -135.586021) (xy 154.27904 -135.637955) (xy 154.301989 -135.693359) (xy 154.31751 -135.751284)
			(xy 154.325338 -135.81074) (xy 154.325828 -135.840724) (xy 154.325828 -136.704324) (xy 154.325338 -136.734308)
			(xy 154.31751 -136.793764) (xy 154.301989 -136.851689) (xy 154.27904 -136.907093) (xy 154.249056 -136.959027)
			(xy 154.21255 -137.006603) (xy 154.170145 -137.049008) (xy 154.122569 -137.085514) (xy 154.070635 -137.115498)
			(xy 154.015231 -137.138447) (xy 153.957306 -137.153968) (xy 153.89785 -137.161796) (xy 153.837882 -137.161796)
			(xy 153.778426 -137.153968) (xy 153.720501 -137.138447) (xy 153.665097 -137.115498) (xy 153.613163 -137.085514)
			(xy 153.565587 -137.049008) (xy 153.523182 -137.006603) (xy 153.486676 -136.959027) (xy 153.456692 -136.907093)
			(xy 153.433743 -136.851689) (xy 153.418222 -136.793764) (xy 153.410394 -136.734308) (xy 153.409904 -136.704324)
			(xy 140.742924 -136.704324) (xy 140.742924 -141.588998) (xy 140.743381 -141.598876) (xy 140.750822 -141.617178)
			(xy 140.757402 -141.624558) (xy 140.757656 -141.624812) (xy 141.61516 -142.482316) (xy 141.615668 -142.482824)
			(xy 141.623049 -142.489407) (xy 141.641348 -142.496856) (xy 141.651228 -142.497302)
		)
		(stroke
			(width 0)
			(type solid)
		)
		(fill yes)
		(layer "In15.Cu")
		(net "GND")
	)
	(gr_poly
		(pts
			(xy 24.677116 -416.740848) (xy 24.686994 -416.74039) (xy 24.705298 -416.732952) (xy 24.712676 -416.72637)
			(xy 24.71293 -416.726116) (xy 25.503886 -415.93516) (xy 25.504394 -415.934652) (xy 25.510973 -415.927269)
			(xy 25.518419 -415.908971) (xy 25.518872 -415.899092) (xy 25.518872 -395.849856) (xy 25.511252 -395.83106)
			(xy 25.503886 -395.823948) (xy 18.725134 -389.045196) (xy 18.718285 -389.037799) (xy 18.710546 -389.019201)
			(xy 18.710148 -389.009128) (xy 18.710148 -386.396738) (xy 18.708878 -386.385816) (xy 18.707862 -386.380482)
			(xy 18.596102 -386.112004) (xy 18.577893 -386.066533) (xy 18.549458 -385.972794) (xy 18.530359 -385.876718)
			(xy 18.524982 -385.828032) (xy 18.375884 -384.312922) (xy 18.375388 -384.308519) (xy 18.373091 -384.299962)
			(xy 18.371312 -384.295904) (xy 18.367502 -384.28803) (xy 14.162786 -380.083314) (xy 14.155944 -380.075915)
			(xy 14.148227 -380.057316) (xy 14.1478 -380.047246) (xy 14.1478 -378.83211) (xy 14.146022 -378.82576)
			(xy 14.139959 -378.80151) (xy 14.133455 -378.751948) (xy 14.133068 -378.726954) (xy 14.133068 -378.724922)
			(xy 14.133446 -378.699928) (xy 14.139951 -378.650365) (xy 14.146022 -378.626116) (xy 14.1478 -378.619766)
			(xy 14.1478 -376.182636) (xy 14.147292 -376.17908) (xy 14.1455 -376.16569) (xy 14.143592 -376.138741)
			(xy 14.143482 -376.125232) (xy 14.143603 -376.111724) (xy 14.14551 -376.084775) (xy 14.147292 -376.071384)
			(xy 14.1478 -376.067828) (xy 14.1478 -353.63658) (xy 14.147292 -353.62896) (xy 14.141704 -353.59213)
			(xy 14.136705 -353.556016) (xy 14.131365 -353.483299) (xy 14.131036 -353.446842) (xy 14.131036 -341.745062)
			(xy 14.131589 -341.700683) (xy 14.139601 -341.612287) (xy 14.147038 -341.568532) (xy 14.1478 -341.56396)
			(xy 14.1478 -339.861906) (xy 14.148222 -339.851835) (xy 14.155935 -339.833229) (xy 14.162786 -339.825838)
			(xy 21.909024 -332.0796) (xy 21.909532 -332.079092) (xy 21.916123 -332.071714) (xy 21.923593 -332.053415)
			(xy 21.92401 -332.043532) (xy 21.92401 -323.677788) (xy 21.91639 -323.658992) (xy 21.909024 -323.65188)
			(xy 17.067276 -318.810132) (xy 17.060432 -318.802733) (xy 17.052711 -318.784134) (xy 17.05229 -318.774064)
			(xy 17.05229 -308.14645) (xy 17.050004 -308.133496) (xy 17.047718 -308.125114) (xy 17.040606 -308.105302)
			(xy 17.035526 -308.098952) (xy 17.018227 -308.076341) (xy 16.989823 -308.027004) (xy 16.96907 -307.973992)
			(xy 16.95643 -307.918483) (xy 16.952184 -307.861713) (xy 16.956427 -307.804942) (xy 16.969063 -307.749432)
			(xy 16.989812 -307.696419) (xy 17.018213 -307.64708) (xy 17.035526 -307.62448) (xy 17.040606 -307.61813)
			(xy 17.049242 -307.594) (xy 17.05229 -307.585618) (xy 17.05229 -302.768508) (xy 17.052193 -302.763348)
			(xy 17.050138 -302.753236) (xy 17.048226 -302.748442) (xy 17.014628 -302.669259) (xy 16.95456 -302.508059)
			(xy 16.902771 -302.344012) (xy 16.859397 -302.177541) (xy 16.82455 -302.00908) (xy 16.798319 -301.839063)
			(xy 16.780774 -301.667932) (xy 16.771959 -301.49613) (xy 16.771366 -301.410116) (xy 16.771934 -301.324101)
			(xy 16.780739 -301.152297) (xy 16.798279 -300.981164) (xy 16.824508 -300.811145) (xy 16.859357 -300.642683)
			(xy 16.902738 -300.476212) (xy 16.954537 -300.312166) (xy 17.01462 -300.15097) (xy 17.048226 -300.07179)
			(xy 17.05229 -300.062138) (xy 17.05229 -299.834808) (xy 17.04467 -299.816012) (xy 17.037304 -299.8089)
			(xy 16.176752 -298.948348) (xy 16.16964 -298.940982) (xy 16.150844 -298.933362) (xy 3.736086 -298.933362)
			(xy 3.71729 -298.940982) (xy 3.710178 -298.948348) (xy 3.692398 -298.966128) (xy 3.685003 -298.972982)
			(xy 3.666404 -298.980727) (xy 3.65633 -298.981114) (xy 2.06248 -298.981114) (xy 2.043684 -298.988734)
			(xy 2.036572 -298.9961) (xy 1.34747 -299.685202) (xy 1.340104 -299.692314) (xy 1.332484 -299.71111)
			(xy 1.332484 -304.457354) (xy 7.652256 -304.457354) (xy 7.656327 -304.401732) (xy 7.668453 -304.347295)
			(xy 7.688376 -304.295204) (xy 7.715672 -304.246569) (xy 7.749758 -304.202426) (xy 7.789907 -304.163717)
			(xy 7.835265 -304.131266) (xy 7.884865 -304.105765) (xy 7.937649 -304.087758) (xy 7.992492 -304.077628)
			(xy 8.048226 -304.075591) (xy 8.103663 -304.081691) (xy 8.15762 -304.095797) (xy 8.208949 -304.117609)
			(xy 8.256555 -304.146663) (xy 8.299423 -304.182338) (xy 8.33664 -304.223875) (xy 8.367413 -304.270388)
			(xy 8.391085 -304.320885) (xy 8.407153 -304.374292) (xy 8.415273 -304.429468) (xy 8.415782 -304.457354)
			(xy 8.415273 -304.48524) (xy 8.41306 -304.50028) (xy 14.926308 -304.50028) (xy 14.930379 -304.444658)
			(xy 14.942505 -304.390221) (xy 14.962428 -304.33813) (xy 14.989724 -304.289495) (xy 15.02381 -304.245352)
			(xy 15.063959 -304.206643) (xy 15.109317 -304.174192) (xy 15.158917 -304.148691) (xy 15.211701 -304.130684)
			(xy 15.266544 -304.120554) (xy 15.322278 -304.118517) (xy 15.377715 -304.124617) (xy 15.431672 -304.138723)
			(xy 15.483001 -304.160535) (xy 15.530607 -304.189589) (xy 15.573475 -304.225264) (xy 15.610692 -304.266801)
			(xy 15.641465 -304.313314) (xy 15.665137 -304.363811) (xy 15.681205 -304.417218) (xy 15.689325 -304.472394)
			(xy 15.689834 -304.50028) (xy 15.689325 -304.528166) (xy 15.681205 -304.583342) (xy 15.665137 -304.636749)
			(xy 15.641465 -304.687246) (xy 15.610692 -304.733759) (xy 15.573475 -304.775296) (xy 15.530607 -304.810971)
			(xy 15.483001 -304.840025) (xy 15.431672 -304.861837) (xy 15.377715 -304.875943) (xy 15.322278 -304.882043)
			(xy 15.266544 -304.880006) (xy 15.211701 -304.869876) (xy 15.158917 -304.851869) (xy 15.109317 -304.826368)
			(xy 15.063959 -304.793917) (xy 15.02381 -304.755208) (xy 14.989724 -304.711065) (xy 14.962428 -304.66243)
			(xy 14.942505 -304.610339) (xy 14.930379 -304.555902) (xy 14.926308 -304.50028) (xy 8.41306 -304.50028)
			(xy 8.407153 -304.540416) (xy 8.391085 -304.593823) (xy 8.367413 -304.64432) (xy 8.33664 -304.690833)
			(xy 8.299423 -304.73237) (xy 8.256555 -304.768045) (xy 8.208949 -304.797099) (xy 8.15762 -304.818911)
			(xy 8.103663 -304.833017) (xy 8.048226 -304.839117) (xy 7.992492 -304.83708) (xy 7.937649 -304.82695)
			(xy 7.884865 -304.808943) (xy 7.835265 -304.783442) (xy 7.789907 -304.750991) (xy 7.749758 -304.712282)
			(xy 7.715672 -304.668139) (xy 7.688376 -304.619504) (xy 7.668453 -304.567413) (xy 7.656327 -304.512976)
			(xy 7.652256 -304.457354) (xy 1.332484 -304.457354) (xy 1.332484 -305.159664) (xy 12.577824 -305.159664)
			(xy 12.581895 -305.104042) (xy 12.594021 -305.049605) (xy 12.613944 -304.997514) (xy 12.64124 -304.948879)
			(xy 12.675326 -304.904736) (xy 12.715475 -304.866027) (xy 12.760833 -304.833576) (xy 12.810433 -304.808075)
			(xy 12.863217 -304.790068) (xy 12.91806 -304.779938) (xy 12.973794 -304.777901) (xy 13.029231 -304.784001)
			(xy 13.083188 -304.798107) (xy 13.134517 -304.819919) (xy 13.182123 -304.848973) (xy 13.224991 -304.884648)
			(xy 13.262208 -304.926185) (xy 13.292981 -304.972698) (xy 13.316653 -305.023195) (xy 13.332721 -305.076602)
			(xy 13.340841 -305.131778) (xy 13.34135 -305.159664) (xy 13.340841 -305.18755) (xy 13.332721 -305.242726)
			(xy 13.316653 -305.296133) (xy 13.292981 -305.34663) (xy 13.262208 -305.393143) (xy 13.224991 -305.43468)
			(xy 13.182123 -305.470355) (xy 13.134517 -305.499409) (xy 13.083188 -305.521221) (xy 13.029231 -305.535327)
			(xy 12.973794 -305.541427) (xy 12.91806 -305.53939) (xy 12.863217 -305.52926) (xy 12.810433 -305.511253)
			(xy 12.760833 -305.485752) (xy 12.715475 -305.453301) (xy 12.675326 -305.414592) (xy 12.64124 -305.370449)
			(xy 12.613944 -305.321814) (xy 12.594021 -305.269723) (xy 12.581895 -305.215286) (xy 12.577824 -305.159664)
			(xy 1.332484 -305.159664) (xy 1.332484 -306.115466) (xy 13.635734 -306.115466) (xy 13.639805 -306.059844)
			(xy 13.651931 -306.005407) (xy 13.671854 -305.953316) (xy 13.69915 -305.904681) (xy 13.733236 -305.860538)
			(xy 13.773385 -305.821829) (xy 13.818743 -305.789378) (xy 13.868343 -305.763877) (xy 13.921127 -305.74587)
			(xy 13.97597 -305.73574) (xy 14.031704 -305.733703) (xy 14.087141 -305.739803) (xy 14.141098 -305.753909)
			(xy 14.192427 -305.775721) (xy 14.240033 -305.804775) (xy 14.282901 -305.84045) (xy 14.320118 -305.881987)
			(xy 14.350891 -305.9285) (xy 14.374563 -305.978997) (xy 14.390631 -306.032404) (xy 14.398751 -306.08758)
			(xy 14.39926 -306.115466) (xy 14.398751 -306.143352) (xy 14.390631 -306.198528) (xy 14.374563 -306.251935)
			(xy 14.350891 -306.302432) (xy 14.320118 -306.348945) (xy 14.282901 -306.390482) (xy 14.240033 -306.426157)
			(xy 14.192427 -306.455211) (xy 14.141098 -306.477023) (xy 14.087141 -306.491129) (xy 14.031704 -306.497229)
			(xy 13.97597 -306.495192) (xy 13.921127 -306.485062) (xy 13.868343 -306.467055) (xy 13.818743 -306.441554)
			(xy 13.773385 -306.409103) (xy 13.733236 -306.370394) (xy 13.69915 -306.326251) (xy 13.671854 -306.277616)
			(xy 13.651931 -306.225525) (xy 13.639805 -306.171088) (xy 13.635734 -306.115466) (xy 1.332484 -306.115466)
			(xy 1.332484 -306.731416) (xy 15.643858 -306.731416) (xy 15.647929 -306.675794) (xy 15.660055 -306.621357)
			(xy 15.679978 -306.569266) (xy 15.707274 -306.520631) (xy 15.74136 -306.476488) (xy 15.781509 -306.437779)
			(xy 15.826867 -306.405328) (xy 15.876467 -306.379827) (xy 15.929251 -306.36182) (xy 15.984094 -306.35169)
			(xy 16.039828 -306.349653) (xy 16.095265 -306.355753) (xy 16.149222 -306.369859) (xy 16.200551 -306.391671)
			(xy 16.248157 -306.420725) (xy 16.291025 -306.4564) (xy 16.328242 -306.497937) (xy 16.359015 -306.54445)
			(xy 16.382687 -306.594947) (xy 16.398755 -306.648354) (xy 16.406875 -306.70353) (xy 16.407384 -306.731416)
			(xy 16.406875 -306.759302) (xy 16.398755 -306.814478) (xy 16.382687 -306.867885) (xy 16.359015 -306.918382)
			(xy 16.328242 -306.964895) (xy 16.291025 -307.006432) (xy 16.248157 -307.042107) (xy 16.200551 -307.071161)
			(xy 16.149222 -307.092973) (xy 16.095265 -307.107079) (xy 16.039828 -307.113179) (xy 15.984094 -307.111142)
			(xy 15.929251 -307.101012) (xy 15.876467 -307.083005) (xy 15.826867 -307.057504) (xy 15.781509 -307.025053)
			(xy 15.74136 -306.986344) (xy 15.707274 -306.942201) (xy 15.679978 -306.893566) (xy 15.660055 -306.841475)
			(xy 15.647929 -306.787038) (xy 15.643858 -306.731416) (xy 1.332484 -306.731416) (xy 1.332484 -307.621686)
			(xy 12.02385 -307.621686) (xy 12.027921 -307.566064) (xy 12.040047 -307.511627) (xy 12.05997 -307.459536)
			(xy 12.087266 -307.410901) (xy 12.121352 -307.366758) (xy 12.161501 -307.328049) (xy 12.206859 -307.295598)
			(xy 12.256459 -307.270097) (xy 12.309243 -307.25209) (xy 12.364086 -307.24196) (xy 12.41982 -307.239923)
			(xy 12.475257 -307.246023) (xy 12.529214 -307.260129) (xy 12.580543 -307.281941) (xy 12.628149 -307.310995)
			(xy 12.671017 -307.34667) (xy 12.708234 -307.388207) (xy 12.739007 -307.43472) (xy 12.750091 -307.458364)
			(xy 13.739366 -307.458364) (xy 13.743437 -307.402742) (xy 13.755563 -307.348305) (xy 13.775486 -307.296214)
			(xy 13.802782 -307.247579) (xy 13.836868 -307.203436) (xy 13.877017 -307.164727) (xy 13.922375 -307.132276)
			(xy 13.971975 -307.106775) (xy 14.024759 -307.088768) (xy 14.079602 -307.078638) (xy 14.135336 -307.076601)
			(xy 14.190773 -307.082701) (xy 14.24473 -307.096807) (xy 14.296059 -307.118619) (xy 14.343665 -307.147673)
			(xy 14.386533 -307.183348) (xy 14.42375 -307.224885) (xy 14.454523 -307.271398) (xy 14.478195 -307.321895)
			(xy 14.494263 -307.375302) (xy 14.502383 -307.430478) (xy 14.502892 -307.458364) (xy 14.502383 -307.48625)
			(xy 14.494263 -307.541426) (xy 14.478195 -307.594833) (xy 14.454523 -307.64533) (xy 14.42375 -307.691843)
			(xy 14.386533 -307.73338) (xy 14.343665 -307.769055) (xy 14.296059 -307.798109) (xy 14.24473 -307.819921)
			(xy 14.190773 -307.834027) (xy 14.135336 -307.840127) (xy 14.079602 -307.83809) (xy 14.024759 -307.82796)
			(xy 13.971975 -307.809953) (xy 13.922375 -307.784452) (xy 13.877017 -307.752001) (xy 13.836868 -307.713292)
			(xy 13.802782 -307.669149) (xy 13.775486 -307.620514) (xy 13.755563 -307.568423) (xy 13.743437 -307.513986)
			(xy 13.739366 -307.458364) (xy 12.750091 -307.458364) (xy 12.762679 -307.485217) (xy 12.778747 -307.538624)
			(xy 12.786867 -307.5938) (xy 12.787376 -307.621686) (xy 12.786867 -307.649572) (xy 12.778747 -307.704748)
			(xy 12.762679 -307.758155) (xy 12.739007 -307.808652) (xy 12.708234 -307.855165) (xy 12.671017 -307.896702)
			(xy 12.628149 -307.932377) (xy 12.580543 -307.961431) (xy 12.529214 -307.983243) (xy 12.475257 -307.997349)
			(xy 12.41982 -308.003449) (xy 12.364086 -308.001412) (xy 12.309243 -307.991282) (xy 12.256459 -307.973275)
			(xy 12.206859 -307.947774) (xy 12.161501 -307.915323) (xy 12.121352 -307.876614) (xy 12.087266 -307.832471)
			(xy 12.05997 -307.783836) (xy 12.040047 -307.731745) (xy 12.027921 -307.677308) (xy 12.02385 -307.621686)
			(xy 1.332484 -307.621686) (xy 1.332484 -308.929024) (xy 13.201648 -308.929024) (xy 13.205719 -308.873402)
			(xy 13.217845 -308.818965) (xy 13.237768 -308.766874) (xy 13.265064 -308.718239) (xy 13.29915 -308.674096)
			(xy 13.339299 -308.635387) (xy 13.384657 -308.602936) (xy 13.434257 -308.577435) (xy 13.487041 -308.559428)
			(xy 13.541884 -308.549298) (xy 13.597618 -308.547261) (xy 13.653055 -308.553361) (xy 13.707012 -308.567467)
			(xy 13.758341 -308.589279) (xy 13.805947 -308.618333) (xy 13.848815 -308.654008) (xy 13.886032 -308.695545)
			(xy 13.916805 -308.742058) (xy 13.940477 -308.792555) (xy 13.956545 -308.845962) (xy 13.964665 -308.901138)
			(xy 13.965174 -308.929024) (xy 13.964665 -308.95691) (xy 13.956545 -309.012086) (xy 13.940477 -309.065493)
			(xy 13.916805 -309.11599) (xy 13.886032 -309.162503) (xy 13.848815 -309.20404) (xy 13.805947 -309.239715)
			(xy 13.758341 -309.268769) (xy 13.707012 -309.290581) (xy 13.653055 -309.304687) (xy 13.597618 -309.310787)
			(xy 13.541884 -309.30875) (xy 13.487041 -309.29862) (xy 13.434257 -309.280613) (xy 13.384657 -309.255112)
			(xy 13.339299 -309.222661) (xy 13.29915 -309.183952) (xy 13.265064 -309.139809) (xy 13.237768 -309.091174)
			(xy 13.217845 -309.039083) (xy 13.205719 -308.984646) (xy 13.201648 -308.929024) (xy 1.332484 -308.929024)
			(xy 1.332484 -318.52997) (xy 10.590784 -318.52997) (xy 10.591212 -318.502598) (xy 10.599036 -318.448417)
			(xy 10.614533 -318.395912) (xy 10.637383 -318.346166) (xy 10.667118 -318.300202) (xy 10.684764 -318.279272)
			(xy 10.69086 -318.27216) (xy 10.69721 -318.255142) (xy 10.69721 -318.169798) (xy 10.69086 -318.15278)
			(xy 10.684764 -318.145668) (xy 10.667138 -318.124726) (xy 10.637425 -318.078755) (xy 10.614587 -318.02901)
			(xy 10.599093 -317.976512) (xy 10.591261 -317.922338) (xy 10.590784 -317.89497) (xy 10.59125 -317.867718)
			(xy 10.59901 -317.81377) (xy 10.614369 -317.761476) (xy 10.637013 -317.711899) (xy 10.666482 -317.666049)
			(xy 10.702175 -317.624859) (xy 10.743367 -317.589168) (xy 10.789218 -317.559702) (xy 10.838796 -317.537061)
			(xy 10.891092 -317.521706) (xy 10.94504 -317.513948) (xy 10.972292 -317.513462) (xy 10.999663 -317.513918)
			(xy 11.053843 -317.521736) (xy 11.106347 -317.537226) (xy 11.156093 -317.560071) (xy 11.202059 -317.589799)
			(xy 11.22299 -317.607442) (xy 11.230102 -317.613538) (xy 11.24712 -317.619888) (xy 11.332464 -317.619888)
			(xy 11.349482 -317.613538) (xy 11.356594 -317.607442) (xy 11.377527 -317.589801) (xy 11.423495 -317.560077)
			(xy 11.473241 -317.537231) (xy 11.525743 -317.521735) (xy 11.579921 -317.513906) (xy 11.634663 -317.513906)
			(xy 11.688841 -317.521735) (xy 11.741343 -317.537231) (xy 11.791089 -317.560077) (xy 11.837057 -317.589801)
			(xy 11.85799 -317.607442) (xy 11.865102 -317.613538) (xy 11.88212 -317.619888) (xy 11.967464 -317.619888)
			(xy 11.984482 -317.613538) (xy 11.991594 -317.607442) (xy 12.012523 -317.589799) (xy 12.058496 -317.560086)
			(xy 12.108244 -317.53725) (xy 12.160746 -317.52176) (xy 12.214922 -317.513934) (xy 12.242292 -317.513462)
			(xy 12.269542 -317.513985) (xy 12.323487 -317.52174) (xy 12.375779 -317.537092) (xy 12.425354 -317.55973)
			(xy 12.471203 -317.589193) (xy 12.512393 -317.624881) (xy 12.548084 -317.666067) (xy 12.577551 -317.711913)
			(xy 12.600194 -317.761486) (xy 12.615552 -317.813776) (xy 12.623312 -317.86772) (xy 12.6238 -317.89497)
			(xy 12.623316 -317.92234) (xy 12.615503 -317.976518) (xy 12.600018 -318.029021) (xy 12.57718 -318.078768)
			(xy 12.547459 -318.124736) (xy 12.52982 -318.145668) (xy 12.523724 -318.15278) (xy 12.517374 -318.169798)
			(xy 12.517374 -318.255142) (xy 12.523724 -318.27216) (xy 12.52982 -318.279272) (xy 12.547463 -318.300201)
			(xy 12.577173 -318.346175) (xy 12.600008 -318.395923) (xy 12.615498 -318.448425) (xy 12.623326 -318.502601)
			(xy 12.6238 -318.52997) (xy 12.623317 -318.557222) (xy 12.615564 -318.611173) (xy 12.600211 -318.663471)
			(xy 12.577571 -318.713052) (xy 12.548106 -318.758905) (xy 12.512414 -318.800099) (xy 12.471223 -318.835793)
			(xy 12.425371 -318.865261) (xy 12.375792 -318.887903) (xy 12.323495 -318.903259) (xy 12.269544 -318.911015)
			(xy 12.242292 -318.911478) (xy 12.214921 -318.911022) (xy 12.160742 -318.903203) (xy 12.108238 -318.887711)
			(xy 12.058491 -318.864867) (xy 12.012525 -318.83514) (xy 11.991594 -318.817498) (xy 11.984482 -318.811402)
			(xy 11.967464 -318.805052) (xy 11.88212 -318.805052) (xy 11.865102 -318.811402) (xy 11.85799 -318.817498)
			(xy 11.837057 -318.835139) (xy 11.791089 -318.864863) (xy 11.741343 -318.887709) (xy 11.688841 -318.903205)
			(xy 11.634663 -318.911034) (xy 11.579921 -318.911034) (xy 11.525743 -318.903205) (xy 11.473241 -318.887709)
			(xy 11.423495 -318.864863) (xy 11.377527 -318.835139) (xy 11.356594 -318.817498) (xy 11.349482 -318.811402)
			(xy 11.332464 -318.805052) (xy 11.24712 -318.805052) (xy 11.230102 -318.811402) (xy 11.22299 -318.817498)
			(xy 11.202072 -318.835155) (xy 11.156096 -318.864864) (xy 11.106344 -318.887697) (xy 11.053841 -318.903184)
			(xy 10.999662 -318.911007) (xy 10.972292 -318.911478) (xy 10.945038 -318.911052) (xy 10.891084 -318.903293)
			(xy 10.838783 -318.887935) (xy 10.789201 -318.865289) (xy 10.743347 -318.835817) (xy 10.702153 -318.80012)
			(xy 10.66646 -318.758923) (xy 10.636993 -318.713065) (xy 10.614352 -318.663481) (xy 10.598999 -318.611179)
			(xy 10.591245 -318.557224) (xy 10.590784 -318.52997) (xy 1.332484 -318.52997) (xy 1.332484 -323.153278)
			(xy 14.462504 -323.153278) (xy 14.466575 -323.097656) (xy 14.478701 -323.043219) (xy 14.498624 -322.991128)
			(xy 14.52592 -322.942493) (xy 14.560006 -322.89835) (xy 14.600155 -322.859641) (xy 14.645513 -322.82719)
			(xy 14.695113 -322.801689) (xy 14.747897 -322.783682) (xy 14.80274 -322.773552) (xy 14.858474 -322.771515)
			(xy 14.913911 -322.777615) (xy 14.967868 -322.791721) (xy 15.019197 -322.813533) (xy 15.066803 -322.842587)
			(xy 15.109671 -322.878262) (xy 15.146888 -322.919799) (xy 15.177661 -322.966312) (xy 15.201333 -323.016809)
			(xy 15.217401 -323.070216) (xy 15.225521 -323.125392) (xy 15.22603 -323.153278) (xy 15.225521 -323.181164)
			(xy 15.217401 -323.23634) (xy 15.201333 -323.289747) (xy 15.177661 -323.340244) (xy 15.146888 -323.386757)
			(xy 15.109671 -323.428294) (xy 15.066803 -323.463969) (xy 15.019197 -323.493023) (xy 14.967868 -323.514835)
			(xy 14.913911 -323.528941) (xy 14.858474 -323.535041) (xy 14.80274 -323.533004) (xy 14.747897 -323.522874)
			(xy 14.695113 -323.504867) (xy 14.645513 -323.479366) (xy 14.600155 -323.446915) (xy 14.560006 -323.408206)
			(xy 14.52592 -323.364063) (xy 14.498624 -323.315428) (xy 14.478701 -323.263337) (xy 14.466575 -323.2089)
			(xy 14.462504 -323.153278) (xy 1.332484 -323.153278) (xy 1.332484 -341.292688) (xy 11.713716 -341.292688)
			(xy 11.717787 -341.237066) (xy 11.729913 -341.182629) (xy 11.749836 -341.130538) (xy 11.777132 -341.081903)
			(xy 11.811218 -341.03776) (xy 11.851367 -340.999051) (xy 11.896725 -340.9666) (xy 11.946325 -340.941099)
			(xy 11.999109 -340.923092) (xy 12.053952 -340.912962) (xy 12.109686 -340.910925) (xy 12.165123 -340.917025)
			(xy 12.21908 -340.931131) (xy 12.270409 -340.952943) (xy 12.318015 -340.981997) (xy 12.360883 -341.017672)
			(xy 12.3981 -341.059209) (xy 12.428873 -341.105722) (xy 12.452545 -341.156219) (xy 12.468613 -341.209626)
			(xy 12.476733 -341.264802) (xy 12.477242 -341.292688) (xy 12.476733 -341.320574) (xy 12.468613 -341.37575)
			(xy 12.452545 -341.429157) (xy 12.428873 -341.479654) (xy 12.3981 -341.526167) (xy 12.360883 -341.567704)
			(xy 12.318015 -341.603379) (xy 12.270409 -341.632433) (xy 12.21908 -341.654245) (xy 12.165123 -341.668351)
			(xy 12.109686 -341.674451) (xy 12.053952 -341.672414) (xy 11.999109 -341.662284) (xy 11.946325 -341.644277)
			(xy 11.896725 -341.618776) (xy 11.851367 -341.586325) (xy 11.811218 -341.547616) (xy 11.777132 -341.503473)
			(xy 11.749836 -341.454838) (xy 11.729913 -341.402747) (xy 11.717787 -341.34831) (xy 11.713716 -341.292688)
			(xy 1.332484 -341.292688) (xy 1.332484 -348.976496) (xy 4.708641 -348.976496) (xy 4.708641 -348.847356)
			(xy 4.716591 -348.718461) (xy 4.732461 -348.590301) (xy 4.75619 -348.46336) (xy 4.787689 -348.338121)
			(xy 4.826838 -348.215058) (xy 4.873489 -348.094639) (xy 4.927464 -347.97732) (xy 4.988559 -347.863546)
			(xy 5.056542 -347.753749) (xy 5.131156 -347.648346) (xy 5.212117 -347.547736) (xy 5.299117 -347.452301)
			(xy 5.391828 -347.362402) (xy 5.489898 -347.278381) (xy 5.592953 -347.200557) (xy 5.700604 -347.129225)
			(xy 5.812443 -347.064655) (xy 5.928044 -347.007093) (xy 6.046969 -346.956756) (xy 6.168768 -346.913836)
			(xy 6.292978 -346.878495) (xy 6.419127 -346.850868) (xy 6.546739 -346.831059) (xy 6.675328 -346.819143)
			(xy 6.804406 -346.815167) (xy 6.933484 -346.819143) (xy 7.062073 -346.831059) (xy 7.189685 -346.850868)
			(xy 7.315834 -346.878495) (xy 7.440044 -346.913836) (xy 7.561843 -346.956756) (xy 7.680768 -347.007093)
			(xy 7.796369 -347.064655) (xy 7.908208 -347.129225) (xy 8.015859 -347.200557) (xy 8.118914 -347.278381)
			(xy 8.216984 -347.362402) (xy 8.309695 -347.452301) (xy 8.396695 -347.547736) (xy 8.477656 -347.648346)
			(xy 8.55227 -347.753749) (xy 8.620253 -347.863546) (xy 8.681348 -347.97732) (xy 8.735323 -348.094639)
			(xy 8.781974 -348.215058) (xy 8.821123 -348.338121) (xy 8.852622 -348.46336) (xy 8.876351 -348.590301)
			(xy 8.892221 -348.718461) (xy 8.900171 -348.847356) (xy 8.900668 -348.911926) (xy 8.900171 -348.976496)
			(xy 8.892221 -349.105391) (xy 8.876351 -349.233551) (xy 8.852622 -349.360492) (xy 8.821123 -349.485731)
			(xy 8.781974 -349.608794) (xy 8.735323 -349.729213) (xy 8.681348 -349.846532) (xy 8.620253 -349.960306)
			(xy 8.55227 -350.070103) (xy 8.477656 -350.175506) (xy 8.396695 -350.276116) (xy 8.309695 -350.371551)
			(xy 8.216984 -350.46145) (xy 8.118914 -350.545471) (xy 8.015859 -350.623295) (xy 7.908208 -350.694627)
			(xy 7.796369 -350.759197) (xy 7.680768 -350.816759) (xy 7.561843 -350.867096) (xy 7.440044 -350.910016)
			(xy 7.315834 -350.945357) (xy 7.189685 -350.972984) (xy 7.062073 -350.992793) (xy 6.933484 -351.004709)
			(xy 6.804406 -351.008686) (xy 6.675328 -351.004709) (xy 6.546739 -350.992793) (xy 6.419127 -350.972984)
			(xy 6.292978 -350.945357) (xy 6.168768 -350.910016) (xy 6.046969 -350.867096) (xy 5.928044 -350.816759)
			(xy 5.812443 -350.759197) (xy 5.700604 -350.694627) (xy 5.592953 -350.623295) (xy 5.489898 -350.545471)
			(xy 5.391828 -350.46145) (xy 5.299117 -350.371551) (xy 5.212117 -350.276116) (xy 5.131156 -350.175506)
			(xy 5.056542 -350.070103) (xy 4.988559 -349.960306) (xy 4.927464 -349.846532) (xy 4.873489 -349.729213)
			(xy 4.826838 -349.608794) (xy 4.787689 -349.485731) (xy 4.75619 -349.360492) (xy 4.732461 -349.233551)
			(xy 4.716591 -349.105391) (xy 4.708641 -348.976496) (xy 1.332484 -348.976496) (xy 1.332484 -365.288322)
			(xy 2.818128 -365.288322) (xy 2.822199 -365.2327) (xy 2.834325 -365.178263) (xy 2.854248 -365.126172)
			(xy 2.881544 -365.077537) (xy 2.91563 -365.033394) (xy 2.955779 -364.994685) (xy 3.001137 -364.962234)
			(xy 3.050737 -364.936733) (xy 3.103521 -364.918726) (xy 3.158364 -364.908596) (xy 3.214098 -364.906559)
			(xy 3.269535 -364.912659) (xy 3.323492 -364.926765) (xy 3.374821 -364.948577) (xy 3.422427 -364.977631)
			(xy 3.465295 -365.013306) (xy 3.502512 -365.054843) (xy 3.533285 -365.101356) (xy 3.556957 -365.151853)
			(xy 3.573025 -365.20526) (xy 3.581145 -365.260436) (xy 3.581654 -365.288322) (xy 3.581145 -365.316208)
			(xy 3.573025 -365.371384) (xy 3.56676 -365.392208) (xy 7.202932 -365.392208) (xy 7.203418 -365.364957)
			(xy 7.211174 -365.311009) (xy 7.226529 -365.258714) (xy 7.249171 -365.209137) (xy 7.278637 -365.163287)
			(xy 7.314328 -365.122096) (xy 7.355519 -365.086405) (xy 7.401369 -365.056939) (xy 7.450946 -365.034297)
			(xy 7.503241 -365.018942) (xy 7.557189 -365.011186) (xy 7.611691 -365.011186) (xy 7.665639 -365.018942)
			(xy 7.717934 -365.034297) (xy 7.767511 -365.056939) (xy 7.813361 -365.086405) (xy 7.854552 -365.122096)
			(xy 7.890243 -365.163287) (xy 7.919709 -365.209137) (xy 7.942351 -365.258714) (xy 7.957706 -365.311009)
			(xy 7.965462 -365.364957) (xy 7.965948 -365.392208) (xy 7.965512 -365.418628) (xy 7.958226 -365.470963)
			(xy 7.94378 -365.521791) (xy 7.922453 -365.570135) (xy 7.894652 -365.61507) (xy 7.86091 -365.655735)
			(xy 7.821875 -365.691348) (xy 7.80034 -365.70666) (xy 7.788863 -365.715046) (xy 7.770739 -365.736932)
			(xy 7.759346 -365.762963) (xy 7.755566 -365.791126) (xy 7.759691 -365.819241) (xy 7.771402 -365.845131)
			(xy 7.789793 -365.866792) (xy 7.801356 -365.875062) (xy 7.823355 -365.890327) (xy 7.863301 -365.925982)
			(xy 7.897866 -365.966875) (xy 7.926371 -366.012201) (xy 7.948254 -366.061069) (xy 7.963087 -366.112518)
			(xy 7.970576 -366.165536) (xy 7.971028 -366.192308) (xy 7.970542 -366.219559) (xy 7.962786 -366.273507)
			(xy 7.947431 -366.325802) (xy 7.924789 -366.375379) (xy 7.895323 -366.421229) (xy 7.859632 -366.46242)
			(xy 7.818441 -366.498111) (xy 7.772591 -366.527577) (xy 7.723014 -366.550219) (xy 7.670719 -366.565574)
			(xy 7.616771 -366.57333) (xy 7.562269 -366.57333) (xy 7.508321 -366.565574) (xy 7.456026 -366.550219)
			(xy 7.406449 -366.527577) (xy 7.360599 -366.498111) (xy 7.319408 -366.46242) (xy 7.283717 -366.421229)
			(xy 7.254251 -366.375379) (xy 7.231609 -366.325802) (xy 7.216254 -366.273507) (xy 7.208498 -366.219559)
			(xy 7.208012 -366.192308) (xy 7.208434 -366.165887) (xy 7.215719 -366.11355) (xy 7.230165 -366.062722)
			(xy 7.251495 -366.014376) (xy 7.279298 -365.969441) (xy 7.313043 -365.928777) (xy 7.352082 -365.893166)
			(xy 7.37362 -365.877856) (xy 7.385086 -365.869453) (xy 7.403216 -365.847574) (xy 7.414615 -365.821545)
			(xy 7.418399 -365.793383) (xy 7.414275 -365.765268) (xy 7.402562 -365.739379) (xy 7.384168 -365.717721)
			(xy 7.372604 -365.709454) (xy 7.350584 -365.694217) (xy 7.31064 -365.658556) (xy 7.276077 -365.617658)
			(xy 7.247575 -365.572327) (xy 7.225695 -365.523455) (xy 7.210867 -365.472002) (xy 7.203382 -365.418981)
			(xy 7.202932 -365.392208) (xy 3.56676 -365.392208) (xy 3.556957 -365.424791) (xy 3.533285 -365.475288)
			(xy 3.502512 -365.521801) (xy 3.465295 -365.563338) (xy 3.422427 -365.599013) (xy 3.374821 -365.628067)
			(xy 3.323492 -365.649879) (xy 3.269535 -365.663985) (xy 3.214098 -365.670085) (xy 3.158364 -365.668048)
			(xy 3.103521 -365.657918) (xy 3.050737 -365.639911) (xy 3.001137 -365.61441) (xy 2.955779 -365.581959)
			(xy 2.91563 -365.54325) (xy 2.881544 -365.499107) (xy 2.854248 -365.450472) (xy 2.834325 -365.398381)
			(xy 2.822199 -365.343944) (xy 2.818128 -365.288322) (xy 1.332484 -365.288322) (xy 1.332484 -368.23269)
			(xy 5.613144 -368.23269) (xy 5.617215 -368.177068) (xy 5.629341 -368.122631) (xy 5.649264 -368.07054)
			(xy 5.67656 -368.021905) (xy 5.710646 -367.977762) (xy 5.750795 -367.939053) (xy 5.796153 -367.906602)
			(xy 5.845753 -367.881101) (xy 5.898537 -367.863094) (xy 5.95338 -367.852964) (xy 6.009114 -367.850927)
			(xy 6.064551 -367.857027) (xy 6.118508 -367.871133) (xy 6.169837 -367.892945) (xy 6.217443 -367.921999)
			(xy 6.260311 -367.957674) (xy 6.297528 -367.999211) (xy 6.328301 -368.045724) (xy 6.351973 -368.096221)
			(xy 6.368041 -368.149628) (xy 6.376161 -368.204804) (xy 6.37667 -368.23269) (xy 6.376161 -368.260576)
			(xy 6.368041 -368.315752) (xy 6.351973 -368.369159) (xy 6.328301 -368.419656) (xy 6.297528 -368.466169)
			(xy 6.260311 -368.507706) (xy 6.217443 -368.543381) (xy 6.169837 -368.572435) (xy 6.118508 -368.594247)
			(xy 6.064551 -368.608353) (xy 6.009114 -368.614453) (xy 5.95338 -368.612416) (xy 5.898537 -368.602286)
			(xy 5.845753 -368.584279) (xy 5.796153 -368.558778) (xy 5.750795 -368.526327) (xy 5.710646 -368.487618)
			(xy 5.67656 -368.443475) (xy 5.649264 -368.39484) (xy 5.629341 -368.342749) (xy 5.617215 -368.288312)
			(xy 5.613144 -368.23269) (xy 1.332484 -368.23269) (xy 1.332484 -372.100847) (xy 8.642336 -372.100847)
			(xy 8.642336 -372.040913) (xy 8.650159 -371.981491) (xy 8.665671 -371.923598) (xy 8.688607 -371.868226)
			(xy 8.718575 -371.81632) (xy 8.755061 -371.768771) (xy 8.797441 -371.726391) (xy 8.84499 -371.689905)
			(xy 8.896896 -371.659937) (xy 8.952268 -371.637001) (xy 9.010161 -371.621489) (xy 9.069583 -371.613666)
			(xy 9.09955 -371.613176) (xy 9.96315 -371.613176) (xy 9.993118 -371.613658) (xy 10.052541 -371.621481)
			(xy 10.110435 -371.636994) (xy 10.165808 -371.65993) (xy 10.217714 -371.689898) (xy 10.265264 -371.726385)
			(xy 10.307645 -371.768766) (xy 10.344132 -371.816316) (xy 10.3741 -371.868222) (xy 10.397036 -371.923595)
			(xy 10.412549 -371.981489) (xy 10.420372 -372.040912) (xy 10.420372 -372.100848) (xy 10.412549 -372.160271)
			(xy 10.397036 -372.218165) (xy 10.3741 -372.273538) (xy 10.344132 -372.325444) (xy 10.307645 -372.372994)
			(xy 10.265264 -372.415375) (xy 10.217714 -372.451862) (xy 10.165808 -372.48183) (xy 10.110435 -372.504766)
			(xy 10.052541 -372.520279) (xy 9.993118 -372.528102) (xy 9.96315 -372.528592) (xy 9.09955 -372.528592)
			(xy 9.069583 -372.528094) (xy 9.010161 -372.520271) (xy 8.952268 -372.504759) (xy 8.896896 -372.481823)
			(xy 8.84499 -372.451855) (xy 8.797441 -372.415369) (xy 8.755061 -372.372989) (xy 8.718575 -372.32544)
			(xy 8.688607 -372.273534) (xy 8.665671 -372.218162) (xy 8.650159 -372.160269) (xy 8.642336 -372.100847)
			(xy 1.332484 -372.100847) (xy 1.332484 -372.921784) (xy 3.759198 -372.921784) (xy 3.763269 -372.866162)
			(xy 3.775395 -372.811725) (xy 3.795318 -372.759634) (xy 3.822614 -372.710999) (xy 3.8567 -372.666856)
			(xy 3.896849 -372.628147) (xy 3.942207 -372.595696) (xy 3.991807 -372.570195) (xy 4.044591 -372.552188)
			(xy 4.099434 -372.542058) (xy 4.155168 -372.540021) (xy 4.210605 -372.546121) (xy 4.264562 -372.560227)
			(xy 4.315891 -372.582039) (xy 4.363497 -372.611093) (xy 4.406365 -372.646768) (xy 4.443582 -372.688305)
			(xy 4.474355 -372.734818) (xy 4.498027 -372.785315) (xy 4.514095 -372.838722) (xy 4.522215 -372.893898)
			(xy 4.522724 -372.921784) (xy 4.522215 -372.94967) (xy 4.514095 -373.004846) (xy 4.498027 -373.058253)
			(xy 4.474355 -373.10875) (xy 4.443582 -373.155263) (xy 4.406365 -373.1968) (xy 4.363497 -373.232475)
			(xy 4.315891 -373.261529) (xy 4.264562 -373.283341) (xy 4.210605 -373.297447) (xy 4.155168 -373.303547)
			(xy 4.099434 -373.30151) (xy 4.044591 -373.29138) (xy 3.991807 -373.273373) (xy 3.942207 -373.247872)
			(xy 3.896849 -373.215421) (xy 3.8567 -373.176712) (xy 3.822614 -373.132569) (xy 3.795318 -373.083934)
			(xy 3.775395 -373.031843) (xy 3.763269 -372.977406) (xy 3.759198 -372.921784) (xy 1.332484 -372.921784)
			(xy 1.332484 -379.540516) (xy 2.180588 -379.540516) (xy 2.184659 -379.484894) (xy 2.196785 -379.430457)
			(xy 2.216708 -379.378366) (xy 2.244004 -379.329731) (xy 2.27809 -379.285588) (xy 2.318239 -379.246879)
			(xy 2.363597 -379.214428) (xy 2.413197 -379.188927) (xy 2.465981 -379.17092) (xy 2.520824 -379.16079)
			(xy 2.576558 -379.158753) (xy 2.631995 -379.164853) (xy 2.685952 -379.178959) (xy 2.737281 -379.200771)
			(xy 2.784887 -379.229825) (xy 2.827755 -379.2655) (xy 2.864972 -379.307037) (xy 2.895745 -379.35355)
			(xy 2.919417 -379.404047) (xy 2.935485 -379.457454) (xy 2.943605 -379.51263) (xy 2.944114 -379.540516)
			(xy 3.653788 -379.540516) (xy 3.657859 -379.484894) (xy 3.669985 -379.430457) (xy 3.689908 -379.378366)
			(xy 3.717204 -379.329731) (xy 3.75129 -379.285588) (xy 3.791439 -379.246879) (xy 3.836797 -379.214428)
			(xy 3.886397 -379.188927) (xy 3.939181 -379.17092) (xy 3.994024 -379.16079) (xy 4.049758 -379.158753)
			(xy 4.105195 -379.164853) (xy 4.159152 -379.178959) (xy 4.210481 -379.200771) (xy 4.258087 -379.229825)
			(xy 4.300955 -379.2655) (xy 4.338172 -379.307037) (xy 4.368945 -379.35355) (xy 4.392617 -379.404047)
			(xy 4.408685 -379.457454) (xy 4.416805 -379.51263) (xy 4.417314 -379.540516) (xy 4.416805 -379.568402)
			(xy 4.408685 -379.623578) (xy 4.392617 -379.676985) (xy 4.368945 -379.727482) (xy 4.338172 -379.773995)
			(xy 4.300955 -379.815532) (xy 4.258087 -379.851207) (xy 4.210481 -379.880261) (xy 4.159152 -379.902073)
			(xy 4.105195 -379.916179) (xy 4.049758 -379.922279) (xy 3.994024 -379.920242) (xy 3.939181 -379.910112)
			(xy 3.886397 -379.892105) (xy 3.836797 -379.866604) (xy 3.791439 -379.834153) (xy 3.75129 -379.795444)
			(xy 3.717204 -379.751301) (xy 3.689908 -379.702666) (xy 3.669985 -379.650575) (xy 3.657859 -379.596138)
			(xy 3.653788 -379.540516) (xy 2.944114 -379.540516) (xy 2.943605 -379.568402) (xy 2.935485 -379.623578)
			(xy 2.919417 -379.676985) (xy 2.895745 -379.727482) (xy 2.864972 -379.773995) (xy 2.827755 -379.815532)
			(xy 2.784887 -379.851207) (xy 2.737281 -379.880261) (xy 2.685952 -379.902073) (xy 2.631995 -379.916179)
			(xy 2.576558 -379.922279) (xy 2.520824 -379.920242) (xy 2.465981 -379.910112) (xy 2.413197 -379.892105)
			(xy 2.363597 -379.866604) (xy 2.318239 -379.834153) (xy 2.27809 -379.795444) (xy 2.244004 -379.751301)
			(xy 2.216708 -379.702666) (xy 2.196785 -379.650575) (xy 2.184659 -379.596138) (xy 2.180588 -379.540516)
			(xy 1.332484 -379.540516) (xy 1.332484 -380.905766) (xy 1.332484 -380.907544) (xy 1.333569 -380.920041)
			(xy 1.346089 -380.941744) (xy 1.35636 -380.948946) (xy 1.42113 -380.989332) (xy 1.427234 -380.992841)
			(xy 1.440764 -380.99672) (xy 1.4478 -380.996952) (xy 1.467866 -380.996952) (xy 1.47337 -380.99683)
			(xy 1.484131 -380.994523) (xy 1.489202 -380.99238) (xy 1.514245 -380.981348) (xy 1.566701 -380.965767)
			(xy 1.620846 -380.957846) (xy 1.648206 -380.957328) (xy 1.675457 -380.957814) (xy 1.729405 -380.96557)
			(xy 1.7817 -380.980925) (xy 1.831277 -381.003567) (xy 1.877127 -381.033033) (xy 1.918318 -381.068724)
			(xy 1.954009 -381.109915) (xy 1.983475 -381.155765) (xy 2.006117 -381.205342) (xy 2.021472 -381.257637)
			(xy 2.029228 -381.311585) (xy 2.029228 -381.348742) (xy 8.047988 -381.348742) (xy 8.052059 -381.29312)
			(xy 8.064185 -381.238683) (xy 8.084108 -381.186592) (xy 8.111404 -381.137957) (xy 8.14549 -381.093814)
			(xy 8.185639 -381.055105) (xy 8.230997 -381.022654) (xy 8.280597 -380.997153) (xy 8.333381 -380.979146)
			(xy 8.388224 -380.969016) (xy 8.443958 -380.966979) (xy 8.499395 -380.973079) (xy 8.553352 -380.987185)
			(xy 8.604681 -381.008997) (xy 8.652287 -381.038051) (xy 8.695155 -381.073726) (xy 8.732372 -381.115263)
			(xy 8.763145 -381.161776) (xy 8.786817 -381.212273) (xy 8.802885 -381.26568) (xy 8.811005 -381.320856)
			(xy 8.811458 -381.345694) (xy 9.548112 -381.345694) (xy 9.552183 -381.290072) (xy 9.564309 -381.235635)
			(xy 9.584232 -381.183544) (xy 9.611528 -381.134909) (xy 9.645614 -381.090766) (xy 9.685763 -381.052057)
			(xy 9.731121 -381.019606) (xy 9.780721 -380.994105) (xy 9.833505 -380.976098) (xy 9.888348 -380.965968)
			(xy 9.944082 -380.963931) (xy 9.999519 -380.970031) (xy 10.053476 -380.984137) (xy 10.104805 -381.005949)
			(xy 10.152411 -381.035003) (xy 10.195279 -381.070678) (xy 10.232496 -381.112215) (xy 10.263269 -381.158728)
			(xy 10.286941 -381.209225) (xy 10.303009 -381.262632) (xy 10.311129 -381.317808) (xy 10.311638 -381.345694)
			(xy 10.311517 -381.352298) (xy 11.832588 -381.352298) (xy 11.836659 -381.296676) (xy 11.848785 -381.242239)
			(xy 11.868708 -381.190148) (xy 11.896004 -381.141513) (xy 11.93009 -381.09737) (xy 11.970239 -381.058661)
			(xy 12.015597 -381.02621) (xy 12.065197 -381.000709) (xy 12.117981 -380.982702) (xy 12.172824 -380.972572)
			(xy 12.228558 -380.970535) (xy 12.283995 -380.976635) (xy 12.337952 -380.990741) (xy 12.389281 -381.012553)
			(xy 12.436887 -381.041607) (xy 12.479755 -381.077282) (xy 12.516972 -381.118819) (xy 12.547745 -381.165332)
			(xy 12.571417 -381.215829) (xy 12.587485 -381.269236) (xy 12.595605 -381.324412) (xy 12.596114 -381.352298)
			(xy 12.595605 -381.380184) (xy 12.590812 -381.41275) (xy 13.548104 -381.41275) (xy 13.552175 -381.357128)
			(xy 13.564301 -381.302691) (xy 13.584224 -381.2506) (xy 13.61152 -381.201965) (xy 13.645606 -381.157822)
			(xy 13.685755 -381.119113) (xy 13.731113 -381.086662) (xy 13.780713 -381.061161) (xy 13.833497 -381.043154)
			(xy 13.88834 -381.033024) (xy 13.944074 -381.030987) (xy 13.999511 -381.037087) (xy 14.053468 -381.051193)
			(xy 14.104797 -381.073005) (xy 14.152403 -381.102059) (xy 14.195271 -381.137734) (xy 14.232488 -381.179271)
			(xy 14.263261 -381.225784) (xy 14.286933 -381.276281) (xy 14.303001 -381.329688) (xy 14.311121 -381.384864)
			(xy 14.31163 -381.41275) (xy 14.311121 -381.440636) (xy 14.303001 -381.495812) (xy 14.286933 -381.549219)
			(xy 14.263261 -381.599716) (xy 14.232488 -381.646229) (xy 14.195271 -381.687766) (xy 14.152403 -381.723441)
			(xy 14.104797 -381.752495) (xy 14.053468 -381.774307) (xy 13.999511 -381.788413) (xy 13.944074 -381.794513)
			(xy 13.88834 -381.792476) (xy 13.833497 -381.782346) (xy 13.780713 -381.764339) (xy 13.731113 -381.738838)
			(xy 13.685755 -381.706387) (xy 13.645606 -381.667678) (xy 13.61152 -381.623535) (xy 13.584224 -381.5749)
			(xy 13.564301 -381.522809) (xy 13.552175 -381.468372) (xy 13.548104 -381.41275) (xy 12.590812 -381.41275)
			(xy 12.587485 -381.43536) (xy 12.571417 -381.488767) (xy 12.547745 -381.539264) (xy 12.516972 -381.585777)
			(xy 12.479755 -381.627314) (xy 12.436887 -381.662989) (xy 12.389281 -381.692043) (xy 12.337952 -381.713855)
			(xy 12.283995 -381.727961) (xy 12.228558 -381.734061) (xy 12.172824 -381.732024) (xy 12.117981 -381.721894)
			(xy 12.065197 -381.703887) (xy 12.015597 -381.678386) (xy 11.970239 -381.645935) (xy 11.93009 -381.607226)
			(xy 11.896004 -381.563083) (xy 11.868708 -381.514448) (xy 11.848785 -381.462357) (xy 11.836659 -381.40792)
			(xy 11.832588 -381.352298) (xy 10.311517 -381.352298) (xy 10.311129 -381.37358) (xy 10.303009 -381.428756)
			(xy 10.286941 -381.482163) (xy 10.263269 -381.53266) (xy 10.232496 -381.579173) (xy 10.195279 -381.62071)
			(xy 10.152411 -381.656385) (xy 10.104805 -381.685439) (xy 10.053476 -381.707251) (xy 9.999519 -381.721357)
			(xy 9.944082 -381.727457) (xy 9.888348 -381.72542) (xy 9.833505 -381.71529) (xy 9.780721 -381.697283)
			(xy 9.731121 -381.671782) (xy 9.685763 -381.639331) (xy 9.645614 -381.600622) (xy 9.611528 -381.556479)
			(xy 9.584232 -381.507844) (xy 9.564309 -381.455753) (xy 9.552183 -381.401316) (xy 9.548112 -381.345694)
			(xy 8.811458 -381.345694) (xy 8.811514 -381.348742) (xy 8.811005 -381.376628) (xy 8.802885 -381.431804)
			(xy 8.786817 -381.485211) (xy 8.763145 -381.535708) (xy 8.732372 -381.582221) (xy 8.695155 -381.623758)
			(xy 8.652287 -381.659433) (xy 8.604681 -381.688487) (xy 8.553352 -381.710299) (xy 8.499395 -381.724405)
			(xy 8.443958 -381.730505) (xy 8.388224 -381.728468) (xy 8.333381 -381.718338) (xy 8.280597 -381.700331)
			(xy 8.230997 -381.67483) (xy 8.185639 -381.642379) (xy 8.14549 -381.60367) (xy 8.111404 -381.559527)
			(xy 8.084108 -381.510892) (xy 8.064185 -381.458801) (xy 8.052059 -381.404364) (xy 8.047988 -381.348742)
			(xy 2.029228 -381.348742) (xy 2.029228 -381.366087) (xy 2.021472 -381.420035) (xy 2.006117 -381.47233)
			(xy 1.983475 -381.521907) (xy 1.954009 -381.567757) (xy 1.918318 -381.608948) (xy 1.877127 -381.644639)
			(xy 1.831277 -381.674105) (xy 1.7817 -381.696747) (xy 1.729405 -381.712102) (xy 1.675457 -381.719858)
			(xy 1.648206 -381.720344) (xy 1.618981 -381.71976) (xy 1.561218 -381.710806) (xy 1.505491 -381.693166)
			(xy 1.479042 -381.68072) (xy 1.467104 -381.674878) (xy 1.440942 -381.676148) (xy 1.35636 -381.728472)
			(xy 1.350972 -381.732121) (xy 1.342106 -381.741642) (xy 1.338834 -381.747268) (xy 1.335898 -381.752933)
			(xy 1.332681 -381.765275) (xy 1.332484 -381.771652) (xy 1.332484 -383.246884) (xy 4.633212 -383.246884)
			(xy 4.637283 -383.191262) (xy 4.649409 -383.136825) (xy 4.669332 -383.084734) (xy 4.696628 -383.036099)
			(xy 4.730714 -382.991956) (xy 4.770863 -382.953247) (xy 4.816221 -382.920796) (xy 4.865821 -382.895295)
			(xy 4.918605 -382.877288) (xy 4.973448 -382.867158) (xy 5.029182 -382.865121) (xy 5.084619 -382.871221)
			(xy 5.138576 -382.885327) (xy 5.189905 -382.907139) (xy 5.237511 -382.936193) (xy 5.280379 -382.971868)
			(xy 5.317596 -383.013405) (xy 5.348369 -383.059918) (xy 5.372041 -383.110415) (xy 5.388109 -383.163822)
			(xy 5.396229 -383.218998) (xy 5.396738 -383.246884) (xy 5.396229 -383.27477) (xy 5.388109 -383.329946)
			(xy 5.372041 -383.383353) (xy 5.348369 -383.43385) (xy 5.317596 -383.480363) (xy 5.280379 -383.5219)
			(xy 5.237511 -383.557575) (xy 5.189905 -383.586629) (xy 5.138576 -383.608441) (xy 5.084619 -383.622547)
			(xy 5.029182 -383.628647) (xy 4.973448 -383.62661) (xy 4.918605 -383.61648) (xy 4.865821 -383.598473)
			(xy 4.816221 -383.572972) (xy 4.770863 -383.540521) (xy 4.730714 -383.501812) (xy 4.696628 -383.457669)
			(xy 4.669332 -383.409034) (xy 4.649409 -383.356943) (xy 4.637283 -383.302506) (xy 4.633212 -383.246884)
			(xy 1.332484 -383.246884) (xy 1.332484 -384.746754) (xy 14.91564 -384.746754) (xy 14.919711 -384.691132)
			(xy 14.931837 -384.636695) (xy 14.95176 -384.584604) (xy 14.979056 -384.535969) (xy 15.013142 -384.491826)
			(xy 15.053291 -384.453117) (xy 15.098649 -384.420666) (xy 15.148249 -384.395165) (xy 15.201033 -384.377158)
			(xy 15.255876 -384.367028) (xy 15.31161 -384.364991) (xy 15.367047 -384.371091) (xy 15.421004 -384.385197)
			(xy 15.472333 -384.407009) (xy 15.519939 -384.436063) (xy 15.562807 -384.471738) (xy 15.600024 -384.513275)
			(xy 15.630797 -384.559788) (xy 15.654469 -384.610285) (xy 15.670537 -384.663692) (xy 15.678657 -384.718868)
			(xy 15.679166 -384.746754) (xy 15.678657 -384.77464) (xy 15.670537 -384.829816) (xy 15.654469 -384.883223)
			(xy 15.630797 -384.93372) (xy 15.600024 -384.980233) (xy 15.562807 -385.02177) (xy 15.519939 -385.057445)
			(xy 15.472333 -385.086499) (xy 15.421004 -385.108311) (xy 15.367047 -385.122417) (xy 15.31161 -385.128517)
			(xy 15.255876 -385.12648) (xy 15.201033 -385.11635) (xy 15.148249 -385.098343) (xy 15.098649 -385.072842)
			(xy 15.053291 -385.040391) (xy 15.013142 -385.001682) (xy 14.979056 -384.957539) (xy 14.95176 -384.908904)
			(xy 14.931837 -384.856813) (xy 14.919711 -384.802376) (xy 14.91564 -384.746754) (xy 1.332484 -384.746754)
			(xy 1.332484 -386.246878) (xy 4.662168 -386.246878) (xy 4.666239 -386.191256) (xy 4.678365 -386.136819)
			(xy 4.698288 -386.084728) (xy 4.725584 -386.036093) (xy 4.75967 -385.99195) (xy 4.799819 -385.953241)
			(xy 4.845177 -385.92079) (xy 4.894777 -385.895289) (xy 4.947561 -385.877282) (xy 5.002404 -385.867152)
			(xy 5.058138 -385.865115) (xy 5.113575 -385.871215) (xy 5.167532 -385.885321) (xy 5.218861 -385.907133)
			(xy 5.266467 -385.936187) (xy 5.309335 -385.971862) (xy 5.346552 -386.013399) (xy 5.377325 -386.059912)
			(xy 5.400997 -386.110409) (xy 5.417065 -386.163816) (xy 5.425185 -386.218992) (xy 5.425694 -386.246878)
			(xy 5.425185 -386.274764) (xy 5.417065 -386.32994) (xy 5.400997 -386.383347) (xy 5.377325 -386.433844)
			(xy 5.346552 -386.480357) (xy 5.309335 -386.521894) (xy 5.266467 -386.557569) (xy 5.218861 -386.586623)
			(xy 5.167532 -386.608435) (xy 5.113575 -386.622541) (xy 5.058138 -386.628641) (xy 5.002404 -386.626604)
			(xy 4.947561 -386.616474) (xy 4.894777 -386.598467) (xy 4.845177 -386.572966) (xy 4.799819 -386.540515)
			(xy 4.75967 -386.501806) (xy 4.725584 -386.457663) (xy 4.698288 -386.409028) (xy 4.678365 -386.356937)
			(xy 4.666239 -386.3025) (xy 4.662168 -386.246878) (xy 1.332484 -386.246878) (xy 1.332484 -388.37489)
			(xy 1.56972 -388.37489) (xy 1.56972 -387.51129) (xy 1.57021 -387.481322) (xy 1.578033 -387.4219)
			(xy 1.593546 -387.364007) (xy 1.616482 -387.308634) (xy 1.646449 -387.256728) (xy 1.682936 -387.209178)
			(xy 1.725316 -387.166798) (xy 1.772866 -387.130311) (xy 1.824772 -387.100344) (xy 1.880145 -387.077408)
			(xy 1.938038 -387.061895) (xy 1.99746 -387.054072) (xy 2.057396 -387.054072) (xy 2.116818 -387.061895)
			(xy 2.174711 -387.077408) (xy 2.230084 -387.100344) (xy 2.28199 -387.130311) (xy 2.32954 -387.166798)
			(xy 2.37192 -387.209178) (xy 2.408407 -387.256728) (xy 2.438374 -387.308634) (xy 2.46131 -387.364007)
			(xy 2.476823 -387.4219) (xy 2.484646 -387.481322) (xy 2.485136 -387.51129) (xy 2.485136 -388.21233)
			(xy 14.92834 -388.21233) (xy 14.932411 -388.156708) (xy 14.944537 -388.102271) (xy 14.96446 -388.05018)
			(xy 14.991756 -388.001545) (xy 15.025842 -387.957402) (xy 15.065991 -387.918693) (xy 15.111349 -387.886242)
			(xy 15.160949 -387.860741) (xy 15.213733 -387.842734) (xy 15.268576 -387.832604) (xy 15.32431 -387.830567)
			(xy 15.379747 -387.836667) (xy 15.433704 -387.850773) (xy 15.485033 -387.872585) (xy 15.532639 -387.901639)
			(xy 15.575507 -387.937314) (xy 15.612724 -387.978851) (xy 15.643497 -388.025364) (xy 15.667169 -388.075861)
			(xy 15.683237 -388.129268) (xy 15.691357 -388.184444) (xy 15.691866 -388.21233) (xy 15.691357 -388.240216)
			(xy 15.683237 -388.295392) (xy 15.667169 -388.348799) (xy 15.643497 -388.399296) (xy 15.612724 -388.445809)
			(xy 15.575507 -388.487346) (xy 15.532639 -388.523021) (xy 15.485033 -388.552075) (xy 15.433704 -388.573887)
			(xy 15.379747 -388.587993) (xy 15.32431 -388.594093) (xy 15.268576 -388.592056) (xy 15.213733 -388.581926)
			(xy 15.160949 -388.563919) (xy 15.111349 -388.538418) (xy 15.065991 -388.505967) (xy 15.025842 -388.467258)
			(xy 14.991756 -388.423115) (xy 14.96446 -388.37448) (xy 14.944537 -388.322389) (xy 14.932411 -388.267952)
			(xy 14.92834 -388.21233) (xy 2.485136 -388.21233) (xy 2.485136 -388.37489) (xy 2.484646 -388.404858)
			(xy 2.476823 -388.46428) (xy 2.46131 -388.522173) (xy 2.438374 -388.577546) (xy 2.408407 -388.629452)
			(xy 2.37192 -388.677002) (xy 2.32954 -388.719382) (xy 2.293879 -388.746746) (xy 4.630672 -388.746746)
			(xy 4.634743 -388.691124) (xy 4.646869 -388.636687) (xy 4.666792 -388.584596) (xy 4.694088 -388.535961)
			(xy 4.728174 -388.491818) (xy 4.768323 -388.453109) (xy 4.813681 -388.420658) (xy 4.863281 -388.395157)
			(xy 4.916065 -388.37715) (xy 4.970908 -388.36702) (xy 5.026642 -388.364983) (xy 5.082079 -388.371083)
			(xy 5.136036 -388.385189) (xy 5.187365 -388.407001) (xy 5.234971 -388.436055) (xy 5.277839 -388.47173)
			(xy 5.315056 -388.513267) (xy 5.345829 -388.55978) (xy 5.369501 -388.610277) (xy 5.385569 -388.663684)
			(xy 5.393689 -388.71886) (xy 5.394198 -388.746746) (xy 5.393689 -388.774632) (xy 5.385569 -388.829808)
			(xy 5.369501 -388.883215) (xy 5.345829 -388.933712) (xy 5.315056 -388.980225) (xy 5.277839 -389.021762)
			(xy 5.234971 -389.057437) (xy 5.187365 -389.086491) (xy 5.136036 -389.108303) (xy 5.082079 -389.122409)
			(xy 5.026642 -389.128509) (xy 4.970908 -389.126472) (xy 4.916065 -389.116342) (xy 4.863281 -389.098335)
			(xy 4.813681 -389.072834) (xy 4.768323 -389.040383) (xy 4.728174 -389.001674) (xy 4.694088 -388.957531)
			(xy 4.666792 -388.908896) (xy 4.646869 -388.856805) (xy 4.634743 -388.802368) (xy 4.630672 -388.746746)
			(xy 2.293879 -388.746746) (xy 2.28199 -388.755869) (xy 2.230084 -388.785836) (xy 2.174711 -388.808772)
			(xy 2.116818 -388.824285) (xy 2.057396 -388.832108) (xy 1.99746 -388.832108) (xy 1.938038 -388.824285)
			(xy 1.880145 -388.808772) (xy 1.824772 -388.785836) (xy 1.772866 -388.755869) (xy 1.725316 -388.719382)
			(xy 1.682936 -388.677002) (xy 1.646449 -388.629452) (xy 1.616482 -388.577546) (xy 1.593546 -388.522173)
			(xy 1.578033 -388.46428) (xy 1.57021 -388.404858) (xy 1.56972 -388.37489) (xy 1.332484 -388.37489)
			(xy 1.332484 -389.720836) (xy 4.413248 -389.720836) (xy 4.417319 -389.665214) (xy 4.429445 -389.610777)
			(xy 4.449368 -389.558686) (xy 4.476664 -389.510051) (xy 4.51075 -389.465908) (xy 4.550899 -389.427199)
			(xy 4.596257 -389.394748) (xy 4.645857 -389.369247) (xy 4.698641 -389.35124) (xy 4.753484 -389.34111)
			(xy 4.809218 -389.339073) (xy 4.864655 -389.345173) (xy 4.918612 -389.359279) (xy 4.969941 -389.381091)
			(xy 5.017547 -389.410145) (xy 5.060415 -389.44582) (xy 5.097632 -389.487357) (xy 5.128405 -389.53387)
			(xy 5.152077 -389.584367) (xy 5.168145 -389.637774) (xy 5.176265 -389.69295) (xy 5.176774 -389.720836)
			(xy 5.176301 -389.746744) (xy 14.934944 -389.746744) (xy 14.939015 -389.691122) (xy 14.951141 -389.636685)
			(xy 14.971064 -389.584594) (xy 14.99836 -389.535959) (xy 15.032446 -389.491816) (xy 15.072595 -389.453107)
			(xy 15.117953 -389.420656) (xy 15.167553 -389.395155) (xy 15.220337 -389.377148) (xy 15.27518 -389.367018)
			(xy 15.330914 -389.364981) (xy 15.386351 -389.371081) (xy 15.440308 -389.385187) (xy 15.491637 -389.406999)
			(xy 15.539243 -389.436053) (xy 15.582111 -389.471728) (xy 15.619328 -389.513265) (xy 15.650101 -389.559778)
			(xy 15.673773 -389.610275) (xy 15.689841 -389.663682) (xy 15.697961 -389.718858) (xy 15.69847 -389.746744)
			(xy 15.697961 -389.77463) (xy 15.689841 -389.829806) (xy 15.673773 -389.883213) (xy 15.650101 -389.93371)
			(xy 15.619328 -389.980223) (xy 15.582111 -390.02176) (xy 15.539243 -390.057435) (xy 15.491637 -390.086489)
			(xy 15.440308 -390.108301) (xy 15.386351 -390.122407) (xy 15.330914 -390.128507) (xy 15.27518 -390.12647)
			(xy 15.220337 -390.11634) (xy 15.167553 -390.098333) (xy 15.117953 -390.072832) (xy 15.072595 -390.040381)
			(xy 15.032446 -390.001672) (xy 14.99836 -389.957529) (xy 14.971064 -389.908894) (xy 14.951141 -389.856803)
			(xy 14.939015 -389.802366) (xy 14.934944 -389.746744) (xy 5.176301 -389.746744) (xy 5.176265 -389.748722)
			(xy 5.168145 -389.803898) (xy 5.152077 -389.857305) (xy 5.128405 -389.907802) (xy 5.097632 -389.954315)
			(xy 5.060415 -389.995852) (xy 5.017547 -390.031527) (xy 4.969941 -390.060581) (xy 4.918612 -390.082393)
			(xy 4.864655 -390.096499) (xy 4.809218 -390.102599) (xy 4.753484 -390.100562) (xy 4.698641 -390.090432)
			(xy 4.645857 -390.072425) (xy 4.596257 -390.046924) (xy 4.550899 -390.014473) (xy 4.51075 -389.975764)
			(xy 4.476664 -389.931621) (xy 4.449368 -389.882986) (xy 4.429445 -389.830895) (xy 4.417319 -389.776458)
			(xy 4.413248 -389.720836) (xy 1.332484 -389.720836) (xy 1.332484 -390.439402) (xy 1.332672 -390.445697)
			(xy 1.335756 -390.457903) (xy 1.33858 -390.463532) (xy 1.342924 -390.470894) (xy 1.355509 -390.482445)
			(xy 1.363218 -390.486138) (xy 1.448816 -390.522968) (xy 1.457999 -390.526427) (xy 1.477601 -390.526855)
			(xy 1.495937 -390.51991) (xy 1.503426 -390.51357) (xy 1.50368 -390.513316) (xy 1.525037 -390.493922)
			(xy 1.572501 -390.461132) (xy 1.624358 -390.435858) (xy 1.679428 -390.418673) (xy 1.736456 -390.409971)
			(xy 1.7653 -390.40943) (xy 1.765554 -390.40943) (xy 1.792805 -390.409916) (xy 1.846753 -390.417672)
			(xy 1.899048 -390.433027) (xy 1.948625 -390.455669) (xy 1.994475 -390.485135) (xy 2.035666 -390.520826)
			(xy 2.071357 -390.562017) (xy 2.100823 -390.607867) (xy 2.123465 -390.657444) (xy 2.13882 -390.709739)
			(xy 2.146576 -390.763687) (xy 2.146576 -390.818189) (xy 2.13882 -390.872137) (xy 2.123465 -390.924432)
			(xy 2.100823 -390.974009) (xy 2.071357 -391.019859) (xy 2.035666 -391.06105) (xy 1.994475 -391.096741)
			(xy 1.948625 -391.126207) (xy 1.899048 -391.148849) (xy 1.846753 -391.164204) (xy 1.792805 -391.17196)
			(xy 1.765554 -391.172446) (xy 1.7653 -391.172446) (xy 1.736454 -391.17192) (xy 1.679419 -391.163234)
			(xy 1.624344 -391.146054) (xy 1.572486 -391.120772) (xy 1.52503 -391.087965) (xy 1.50368 -391.06856)
			(xy 1.503426 -391.068306) (xy 1.495929 -391.061975) (xy 1.477599 -391.055023) (xy 1.457999 -391.055451)
			(xy 1.448816 -391.058908) (xy 1.363218 -391.095738) (xy 1.355494 -391.099408) (xy 1.342905 -391.110966)
			(xy 1.33858 -391.118344) (xy 1.335753 -391.123972) (xy 1.332664 -391.136179) (xy 1.332484 -391.142474)
			(xy 1.332484 -391.614914) (xy 13.80693 -391.614914) (xy 13.811001 -391.559292) (xy 13.823127 -391.504855)
			(xy 13.84305 -391.452764) (xy 13.870346 -391.404129) (xy 13.904432 -391.359986) (xy 13.944581 -391.321277)
			(xy 13.989939 -391.288826) (xy 14.039539 -391.263325) (xy 14.092323 -391.245318) (xy 14.147166 -391.235188)
			(xy 14.2029 -391.233151) (xy 14.258337 -391.239251) (xy 14.312294 -391.253357) (xy 14.363623 -391.275169)
			(xy 14.411229 -391.304223) (xy 14.454097 -391.339898) (xy 14.491314 -391.381435) (xy 14.522087 -391.427948)
			(xy 14.545759 -391.478445) (xy 14.561827 -391.531852) (xy 14.569947 -391.587028) (xy 14.570456 -391.614914)
			(xy 14.569947 -391.6428) (xy 14.566986 -391.66292) (xy 16.249394 -391.66292) (xy 16.253465 -391.607298)
			(xy 16.265591 -391.552861) (xy 16.285514 -391.50077) (xy 16.31281 -391.452135) (xy 16.346896 -391.407992)
			(xy 16.387045 -391.369283) (xy 16.432403 -391.336832) (xy 16.482003 -391.311331) (xy 16.534787 -391.293324)
			(xy 16.58963 -391.283194) (xy 16.645364 -391.281157) (xy 16.700801 -391.287257) (xy 16.754758 -391.301363)
			(xy 16.806087 -391.323175) (xy 16.853693 -391.352229) (xy 16.896561 -391.387904) (xy 16.933778 -391.429441)
			(xy 16.964551 -391.475954) (xy 16.988223 -391.526451) (xy 17.004291 -391.579858) (xy 17.012411 -391.635034)
			(xy 17.01292 -391.66292) (xy 17.012411 -391.690806) (xy 17.004291 -391.745982) (xy 16.988223 -391.799389)
			(xy 16.964551 -391.849886) (xy 16.933778 -391.896399) (xy 16.896561 -391.937936) (xy 16.853693 -391.973611)
			(xy 16.806087 -392.002665) (xy 16.754758 -392.024477) (xy 16.700801 -392.038583) (xy 16.645364 -392.044683)
			(xy 16.58963 -392.042646) (xy 16.534787 -392.032516) (xy 16.482003 -392.014509) (xy 16.432403 -391.989008)
			(xy 16.387045 -391.956557) (xy 16.346896 -391.917848) (xy 16.31281 -391.873705) (xy 16.285514 -391.82507)
			(xy 16.265591 -391.772979) (xy 16.253465 -391.718542) (xy 16.249394 -391.66292) (xy 14.566986 -391.66292)
			(xy 14.561827 -391.697976) (xy 14.545759 -391.751383) (xy 14.522087 -391.80188) (xy 14.491314 -391.848393)
			(xy 14.454097 -391.88993) (xy 14.411229 -391.925605) (xy 14.363623 -391.954659) (xy 14.312294 -391.976471)
			(xy 14.258337 -391.990577) (xy 14.2029 -391.996677) (xy 14.147166 -391.99464) (xy 14.092323 -391.98451)
			(xy 14.039539 -391.966503) (xy 13.989939 -391.941002) (xy 13.944581 -391.908551) (xy 13.904432 -391.869842)
			(xy 13.870346 -391.825699) (xy 13.84305 -391.777064) (xy 13.823127 -391.724973) (xy 13.811001 -391.670536)
			(xy 13.80693 -391.614914) (xy 1.332484 -391.614914) (xy 1.332484 -394.48232) (xy 2.2512 -394.48232)
			(xy 2.255271 -394.426698) (xy 2.267397 -394.372261) (xy 2.28732 -394.32017) (xy 2.314616 -394.271535)
			(xy 2.348702 -394.227392) (xy 2.388851 -394.188683) (xy 2.434209 -394.156232) (xy 2.483809 -394.130731)
			(xy 2.536593 -394.112724) (xy 2.591436 -394.102594) (xy 2.64717 -394.100557) (xy 2.702607 -394.106657)
			(xy 2.756564 -394.120763) (xy 2.807893 -394.142575) (xy 2.855499 -394.171629) (xy 2.898367 -394.207304)
			(xy 2.935584 -394.248841) (xy 2.966357 -394.295354) (xy 2.990029 -394.345851) (xy 3.006097 -394.399258)
			(xy 3.014217 -394.454434) (xy 3.014726 -394.48232) (xy 3.014217 -394.510206) (xy 3.006097 -394.565382)
			(xy 2.990029 -394.618789) (xy 2.966357 -394.669286) (xy 2.935584 -394.715799) (xy 2.900811 -394.754608)
			(xy 5.302756 -394.754608) (xy 5.306827 -394.698986) (xy 5.318953 -394.644549) (xy 5.338876 -394.592458)
			(xy 5.366172 -394.543823) (xy 5.400258 -394.49968) (xy 5.440407 -394.460971) (xy 5.485765 -394.42852)
			(xy 5.535365 -394.403019) (xy 5.588149 -394.385012) (xy 5.642992 -394.374882) (xy 5.698726 -394.372845)
			(xy 5.754163 -394.378945) (xy 5.80812 -394.393051) (xy 5.859449 -394.414863) (xy 5.907055 -394.443917)
			(xy 5.949923 -394.479592) (xy 5.98714 -394.521129) (xy 6.017913 -394.567642) (xy 6.041585 -394.618139)
			(xy 6.057653 -394.671546) (xy 6.065773 -394.726722) (xy 6.066282 -394.754608) (xy 6.066212 -394.758418)
			(xy 6.280656 -394.758418) (xy 6.284727 -394.702796) (xy 6.296853 -394.648359) (xy 6.316776 -394.596268)
			(xy 6.344072 -394.547633) (xy 6.378158 -394.50349) (xy 6.418307 -394.464781) (xy 6.463665 -394.43233)
			(xy 6.513265 -394.406829) (xy 6.566049 -394.388822) (xy 6.620892 -394.378692) (xy 6.676626 -394.376655)
			(xy 6.732063 -394.382755) (xy 6.78602 -394.396861) (xy 6.837349 -394.418673) (xy 6.884955 -394.447727)
			(xy 6.927823 -394.483402) (xy 6.96504 -394.524939) (xy 6.995813 -394.571452) (xy 7.019485 -394.621949)
			(xy 7.035553 -394.675356) (xy 7.043673 -394.730532) (xy 7.044182 -394.758418) (xy 7.043673 -394.786304)
			(xy 7.035553 -394.84148) (xy 7.019485 -394.894887) (xy 6.995813 -394.945384) (xy 6.96504 -394.991897)
			(xy 6.927823 -395.033434) (xy 6.884955 -395.069109) (xy 6.837349 -395.098163) (xy 6.78602 -395.119975)
			(xy 6.732063 -395.134081) (xy 6.676626 -395.140181) (xy 6.620892 -395.138144) (xy 6.566049 -395.128014)
			(xy 6.513265 -395.110007) (xy 6.463665 -395.084506) (xy 6.418307 -395.052055) (xy 6.378158 -395.013346)
			(xy 6.344072 -394.969203) (xy 6.316776 -394.920568) (xy 6.296853 -394.868477) (xy 6.284727 -394.81404)
			(xy 6.280656 -394.758418) (xy 6.066212 -394.758418) (xy 6.065773 -394.782494) (xy 6.057653 -394.83767)
			(xy 6.041585 -394.891077) (xy 6.017913 -394.941574) (xy 5.98714 -394.988087) (xy 5.949923 -395.029624)
			(xy 5.907055 -395.065299) (xy 5.859449 -395.094353) (xy 5.80812 -395.116165) (xy 5.754163 -395.130271)
			(xy 5.698726 -395.136371) (xy 5.642992 -395.134334) (xy 5.588149 -395.124204) (xy 5.535365 -395.106197)
			(xy 5.485765 -395.080696) (xy 5.440407 -395.048245) (xy 5.400258 -395.009536) (xy 5.366172 -394.965393)
			(xy 5.338876 -394.916758) (xy 5.318953 -394.864667) (xy 5.306827 -394.81023) (xy 5.302756 -394.754608)
			(xy 2.900811 -394.754608) (xy 2.898367 -394.757336) (xy 2.855499 -394.793011) (xy 2.807893 -394.822065)
			(xy 2.756564 -394.843877) (xy 2.702607 -394.857983) (xy 2.64717 -394.864083) (xy 2.591436 -394.862046)
			(xy 2.536593 -394.851916) (xy 2.483809 -394.833909) (xy 2.434209 -394.808408) (xy 2.388851 -394.775957)
			(xy 2.348702 -394.737248) (xy 2.314616 -394.693105) (xy 2.28732 -394.64447) (xy 2.267397 -394.592379)
			(xy 2.255271 -394.537942) (xy 2.2512 -394.48232) (xy 1.332484 -394.48232) (xy 1.332484 -395.206728)
			(xy 10.019536 -395.206728) (xy 10.023607 -395.151106) (xy 10.035733 -395.096669) (xy 10.055656 -395.044578)
			(xy 10.082952 -394.995943) (xy 10.117038 -394.9518) (xy 10.157187 -394.913091) (xy 10.202545 -394.88064)
			(xy 10.252145 -394.855139) (xy 10.304929 -394.837132) (xy 10.359772 -394.827002) (xy 10.415506 -394.824965)
			(xy 10.470943 -394.831065) (xy 10.5249 -394.845171) (xy 10.576229 -394.866983) (xy 10.623835 -394.896037)
			(xy 10.666703 -394.931712) (xy 10.70392 -394.973249) (xy 10.734693 -395.019762) (xy 10.758365 -395.070259)
			(xy 10.774433 -395.123666) (xy 10.782553 -395.178842) (xy 10.78302 -395.204442) (xy 11.574778 -395.204442)
			(xy 11.578849 -395.14882) (xy 11.590975 -395.094383) (xy 11.610898 -395.042292) (xy 11.638194 -394.993657)
			(xy 11.67228 -394.949514) (xy 11.712429 -394.910805) (xy 11.757787 -394.878354) (xy 11.807387 -394.852853)
			(xy 11.860171 -394.834846) (xy 11.915014 -394.824716) (xy 11.970748 -394.822679) (xy 12.026185 -394.828779)
			(xy 12.080142 -394.842885) (xy 12.131471 -394.864697) (xy 12.179077 -394.893751) (xy 12.221945 -394.929426)
			(xy 12.259162 -394.970963) (xy 12.289935 -395.017476) (xy 12.313607 -395.067973) (xy 12.329675 -395.12138)
			(xy 12.337795 -395.176556) (xy 12.338151 -395.19606) (xy 15.04772 -395.19606) (xy 15.051791 -395.140438)
			(xy 15.063917 -395.086001) (xy 15.08384 -395.03391) (xy 15.111136 -394.985275) (xy 15.145222 -394.941132)
			(xy 15.185371 -394.902423) (xy 15.230729 -394.869972) (xy 15.280329 -394.844471) (xy 15.333113 -394.826464)
			(xy 15.387956 -394.816334) (xy 15.44369 -394.814297) (xy 15.499127 -394.820397) (xy 15.553084 -394.834503)
			(xy 15.604413 -394.856315) (xy 15.652019 -394.885369) (xy 15.694887 -394.921044) (xy 15.732104 -394.962581)
			(xy 15.762877 -395.009094) (xy 15.786549 -395.059591) (xy 15.802617 -395.112998) (xy 15.810737 -395.168174)
			(xy 15.811246 -395.19606) (xy 16.06372 -395.19606) (xy 16.067791 -395.140438) (xy 16.079917 -395.086001)
			(xy 16.09984 -395.03391) (xy 16.127136 -394.985275) (xy 16.161222 -394.941132) (xy 16.201371 -394.902423)
			(xy 16.246729 -394.869972) (xy 16.296329 -394.844471) (xy 16.349113 -394.826464) (xy 16.403956 -394.816334)
			(xy 16.45969 -394.814297) (xy 16.515127 -394.820397) (xy 16.569084 -394.834503) (xy 16.620413 -394.856315)
			(xy 16.668019 -394.885369) (xy 16.710887 -394.921044) (xy 16.748104 -394.962581) (xy 16.778877 -395.009094)
			(xy 16.802549 -395.059591) (xy 16.818617 -395.112998) (xy 16.826737 -395.168174) (xy 16.827246 -395.19606)
			(xy 16.826737 -395.223946) (xy 16.818617 -395.279122) (xy 16.802549 -395.332529) (xy 16.778877 -395.383026)
			(xy 16.748104 -395.429539) (xy 16.710887 -395.471076) (xy 16.668019 -395.506751) (xy 16.620413 -395.535805)
			(xy 16.569084 -395.557617) (xy 16.515127 -395.571723) (xy 16.45969 -395.577823) (xy 16.403956 -395.575786)
			(xy 16.349113 -395.565656) (xy 16.296329 -395.547649) (xy 16.246729 -395.522148) (xy 16.201371 -395.489697)
			(xy 16.161222 -395.450988) (xy 16.127136 -395.406845) (xy 16.09984 -395.35821) (xy 16.079917 -395.306119)
			(xy 16.067791 -395.251682) (xy 16.06372 -395.19606) (xy 15.811246 -395.19606) (xy 15.810737 -395.223946)
			(xy 15.802617 -395.279122) (xy 15.786549 -395.332529) (xy 15.762877 -395.383026) (xy 15.732104 -395.429539)
			(xy 15.694887 -395.471076) (xy 15.652019 -395.506751) (xy 15.604413 -395.535805) (xy 15.553084 -395.557617)
			(xy 15.499127 -395.571723) (xy 15.44369 -395.577823) (xy 15.387956 -395.575786) (xy 15.333113 -395.565656)
			(xy 15.280329 -395.547649) (xy 15.230729 -395.522148) (xy 15.185371 -395.489697) (xy 15.145222 -395.450988)
			(xy 15.111136 -395.406845) (xy 15.08384 -395.35821) (xy 15.063917 -395.306119) (xy 15.051791 -395.251682)
			(xy 15.04772 -395.19606) (xy 12.338151 -395.19606) (xy 12.338304 -395.204442) (xy 12.337795 -395.232328)
			(xy 12.329675 -395.287504) (xy 12.313607 -395.340911) (xy 12.289935 -395.391408) (xy 12.259162 -395.437921)
			(xy 12.221945 -395.479458) (xy 12.179077 -395.515133) (xy 12.131471 -395.544187) (xy 12.080142 -395.565999)
			(xy 12.026185 -395.580105) (xy 11.970748 -395.586205) (xy 11.915014 -395.584168) (xy 11.860171 -395.574038)
			(xy 11.807387 -395.556031) (xy 11.757787 -395.53053) (xy 11.712429 -395.498079) (xy 11.67228 -395.45937)
			(xy 11.638194 -395.415227) (xy 11.610898 -395.366592) (xy 11.590975 -395.314501) (xy 11.578849 -395.260064)
			(xy 11.574778 -395.204442) (xy 10.78302 -395.204442) (xy 10.783062 -395.206728) (xy 10.782553 -395.234614)
			(xy 10.774433 -395.28979) (xy 10.758365 -395.343197) (xy 10.734693 -395.393694) (xy 10.70392 -395.440207)
			(xy 10.666703 -395.481744) (xy 10.623835 -395.517419) (xy 10.576229 -395.546473) (xy 10.5249 -395.568285)
			(xy 10.470943 -395.582391) (xy 10.415506 -395.588491) (xy 10.359772 -395.586454) (xy 10.304929 -395.576324)
			(xy 10.252145 -395.558317) (xy 10.202545 -395.532816) (xy 10.157187 -395.500365) (xy 10.117038 -395.461656)
			(xy 10.082952 -395.417513) (xy 10.055656 -395.368878) (xy 10.035733 -395.316787) (xy 10.023607 -395.26235)
			(xy 10.019536 -395.206728) (xy 1.332484 -395.206728) (xy 1.332484 -398.164722) (xy 3.141726 -398.164722)
			(xy 3.141726 -398.035362) (xy 3.149849 -397.906256) (xy 3.166062 -397.777916) (xy 3.190302 -397.650846)
			(xy 3.222472 -397.52555) (xy 3.262447 -397.40252) (xy 3.310068 -397.282244) (xy 3.365147 -397.165195)
			(xy 3.427467 -397.051835) (xy 3.496782 -396.942612) (xy 3.572818 -396.837957) (xy 3.655276 -396.738283)
			(xy 3.743829 -396.643983) (xy 3.838129 -396.55543) (xy 3.937803 -396.472972) (xy 4.042458 -396.396936)
			(xy 4.151681 -396.327621) (xy 4.265041 -396.265301) (xy 4.38209 -396.210222) (xy 4.502366 -396.162601)
			(xy 4.625396 -396.122626) (xy 4.750692 -396.090456) (xy 4.877762 -396.066216) (xy 5.006102 -396.050003)
			(xy 5.135208 -396.04188) (xy 5.199888 -396.041372) (xy 6.800088 -396.041372) (xy 6.864769 -396.041866)
			(xy 6.993875 -396.049988) (xy 7.122217 -396.066201) (xy 7.249287 -396.090441) (xy 7.374584 -396.122612)
			(xy 7.497614 -396.162587) (xy 7.617892 -396.210208) (xy 7.734942 -396.265287) (xy 7.848302 -396.327608)
			(xy 7.957526 -396.396923) (xy 8.062181 -396.47296) (xy 8.161856 -396.555418) (xy 8.256157 -396.643972)
			(xy 8.344711 -396.738272) (xy 8.427169 -396.837947) (xy 8.503206 -396.942603) (xy 8.572521 -397.051826)
			(xy 8.634842 -397.165187) (xy 8.689921 -397.282236) (xy 8.737543 -397.402514) (xy 8.777518 -397.525544)
			(xy 8.809688 -397.650841) (xy 8.833928 -397.777911) (xy 8.850142 -397.906253) (xy 8.858264 -398.035359)
			(xy 8.858264 -398.164721) (xy 8.850142 -398.293827) (xy 8.833928 -398.422169) (xy 8.809688 -398.549239)
			(xy 8.777518 -398.674536) (xy 8.737543 -398.797566) (xy 8.689921 -398.917844) (xy 8.634842 -399.034893)
			(xy 8.572521 -399.148254) (xy 8.503206 -399.257477) (xy 8.427169 -399.362133) (xy 8.344711 -399.461808)
			(xy 8.256157 -399.556108) (xy 8.161856 -399.644662) (xy 8.062181 -399.72712) (xy 7.957526 -399.803157)
			(xy 7.848302 -399.872472) (xy 7.734942 -399.934793) (xy 7.617892 -399.989872) (xy 7.497614 -400.037493)
			(xy 7.374584 -400.077468) (xy 7.249287 -400.109639) (xy 7.122217 -400.133879) (xy 6.993875 -400.150092)
			(xy 6.864769 -400.158214) (xy 6.800088 -400.158712) (xy 5.199888 -400.158712) (xy 5.135208 -400.158204)
			(xy 5.006102 -400.150081) (xy 4.877762 -400.133868) (xy 4.750692 -400.109628) (xy 4.625396 -400.077458)
			(xy 4.502366 -400.037483) (xy 4.38209 -399.989862) (xy 4.265041 -399.934783) (xy 4.151681 -399.872463)
			(xy 4.042458 -399.803148) (xy 3.937803 -399.727112) (xy 3.838129 -399.644654) (xy 3.743829 -399.556101)
			(xy 3.655276 -399.461801) (xy 3.572818 -399.362127) (xy 3.496782 -399.257472) (xy 3.427467 -399.148249)
			(xy 3.365147 -399.034889) (xy 3.310068 -398.91784) (xy 3.262447 -398.797564) (xy 3.222472 -398.674534)
			(xy 3.190302 -398.549238) (xy 3.166062 -398.422168) (xy 3.149849 -398.293828) (xy 3.141726 -398.164722)
			(xy 1.332484 -398.164722) (xy 1.332484 -402.232191) (xy 13.656034 -402.232191) (xy 13.656034 -402.177689)
			(xy 13.66379 -402.123741) (xy 13.679145 -402.071446) (xy 13.701786 -402.021868) (xy 13.731253 -401.976018)
			(xy 13.766944 -401.934827) (xy 13.808134 -401.899135) (xy 13.853985 -401.869668) (xy 13.903562 -401.847027)
			(xy 13.955857 -401.831671) (xy 14.009805 -401.823914) (xy 14.037056 -401.823428) (xy 14.063373 -401.823855)
			(xy 14.115509 -401.831079) (xy 14.166158 -401.845397) (xy 14.21436 -401.866536) (xy 14.259201 -401.894096)
			(xy 14.299831 -401.927555) (xy 14.31798 -401.946618) (xy 14.325505 -401.954016) (xy 14.344782 -401.962542)
			(xy 14.355318 -401.963128) (xy 14.429994 -401.963128) (xy 14.440544 -401.962601) (xy 14.459839 -401.954063)
			(xy 14.467332 -401.946618) (xy 14.485455 -401.927527) (xy 14.526077 -401.894049) (xy 14.57092 -401.86648)
			(xy 14.61913 -401.845343) (xy 14.66979 -401.831041) (xy 14.721936 -401.823847) (xy 14.748256 -401.823428)
			(xy 14.774573 -401.823855) (xy 14.826709 -401.831079) (xy 14.877358 -401.845397) (xy 14.92556 -401.866536)
			(xy 14.970401 -401.894096) (xy 15.011031 -401.927555) (xy 15.02918 -401.946618) (xy 15.036705 -401.954016)
			(xy 15.055982 -401.962542) (xy 15.066518 -401.963128) (xy 15.141194 -401.963128) (xy 15.151744 -401.962601)
			(xy 15.171039 -401.954063) (xy 15.178532 -401.946618) (xy 15.196655 -401.927527) (xy 15.237277 -401.894049)
			(xy 15.28212 -401.86648) (xy 15.33033 -401.845343) (xy 15.38099 -401.831041) (xy 15.433136 -401.823847)
			(xy 15.459456 -401.823428) (xy 15.486709 -401.823899) (xy 15.54066 -401.831655) (xy 15.592957 -401.847011)
			(xy 15.642537 -401.869653) (xy 15.688391 -401.899121) (xy 15.729583 -401.934814) (xy 15.765277 -401.976006)
			(xy 15.794745 -402.021859) (xy 15.817388 -402.071439) (xy 15.832744 -402.123737) (xy 15.840501 -402.177687)
			(xy 15.840501 -402.232193) (xy 15.832744 -402.286143) (xy 15.817388 -402.338441) (xy 15.794745 -402.388021)
			(xy 15.765277 -402.433874) (xy 15.729583 -402.475066) (xy 15.688391 -402.510759) (xy 15.642537 -402.540227)
			(xy 15.592957 -402.562869) (xy 15.54066 -402.578225) (xy 15.486709 -402.585981) (xy 15.459456 -402.586444)
			(xy 15.43314 -402.585986) (xy 15.381007 -402.578765) (xy 15.33036 -402.564452) (xy 15.282158 -402.543318)
			(xy 15.237316 -402.515765) (xy 15.196683 -402.482313) (xy 15.178532 -402.463254) (xy 15.170993 -402.455873)
			(xy 15.151727 -402.447335) (xy 15.141194 -402.446744) (xy 15.066518 -402.446744) (xy 15.055966 -402.447256)
			(xy 15.03667 -402.455802) (xy 15.02918 -402.463254) (xy 15.011046 -402.482334) (xy 14.970426 -402.515814)
			(xy 14.925586 -402.543386) (xy 14.877378 -402.564524) (xy 14.82672 -402.578828) (xy 14.774576 -402.586025)
			(xy 14.748256 -402.586444) (xy 14.72194 -402.585986) (xy 14.669807 -402.578765) (xy 14.61916 -402.564452)
			(xy 14.570958 -402.543318) (xy 14.526116 -402.515765) (xy 14.485483 -402.482313) (xy 14.467332 -402.463254)
			(xy 14.459793 -402.455873) (xy 14.440527 -402.447335) (xy 14.429994 -402.446744) (xy 14.355318 -402.446744)
			(xy 14.344766 -402.447256) (xy 14.32547 -402.455802) (xy 14.31798 -402.463254) (xy 14.299846 -402.482334)
			(xy 14.259226 -402.515814) (xy 14.214386 -402.543386) (xy 14.166178 -402.564524) (xy 14.11552 -402.578828)
			(xy 14.063376 -402.586025) (xy 14.037056 -402.586444) (xy 14.009805 -402.585966) (xy 13.955857 -402.578209)
			(xy 13.903562 -402.562853) (xy 13.853985 -402.540212) (xy 13.808134 -402.510745) (xy 13.766944 -402.475053)
			(xy 13.731253 -402.433862) (xy 13.701786 -402.388012) (xy 13.679145 -402.338434) (xy 13.66379 -402.286139)
			(xy 13.656034 -402.232191) (xy 1.332484 -402.232191) (xy 1.332484 -404.501858) (xy 17.351246 -404.501858)
			(xy 17.355317 -404.446236) (xy 17.367443 -404.391799) (xy 17.387366 -404.339708) (xy 17.414662 -404.291073)
			(xy 17.448748 -404.24693) (xy 17.488897 -404.208221) (xy 17.534255 -404.17577) (xy 17.583855 -404.150269)
			(xy 17.636639 -404.132262) (xy 17.691482 -404.122132) (xy 17.747216 -404.120095) (xy 17.802653 -404.126195)
			(xy 17.85661 -404.140301) (xy 17.907939 -404.162113) (xy 17.955545 -404.191167) (xy 17.998413 -404.226842)
			(xy 18.03563 -404.268379) (xy 18.066403 -404.314892) (xy 18.090075 -404.365389) (xy 18.106143 -404.418796)
			(xy 18.114263 -404.473972) (xy 18.114772 -404.501858) (xy 18.114263 -404.529744) (xy 18.106143 -404.58492)
			(xy 18.094299 -404.624286) (xy 18.644868 -404.624286) (xy 18.648939 -404.568664) (xy 18.661065 -404.514227)
			(xy 18.680988 -404.462136) (xy 18.708284 -404.413501) (xy 18.74237 -404.369358) (xy 18.782519 -404.330649)
			(xy 18.827877 -404.298198) (xy 18.877477 -404.272697) (xy 18.930261 -404.25469) (xy 18.985104 -404.24456)
			(xy 19.040838 -404.242523) (xy 19.096275 -404.248623) (xy 19.150232 -404.262729) (xy 19.201561 -404.284541)
			(xy 19.249167 -404.313595) (xy 19.292035 -404.34927) (xy 19.329252 -404.390807) (xy 19.360025 -404.43732)
			(xy 19.383697 -404.487817) (xy 19.399765 -404.541224) (xy 19.407885 -404.5964) (xy 19.408394 -404.624286)
			(xy 19.407885 -404.652172) (xy 19.399765 -404.707348) (xy 19.383697 -404.760755) (xy 19.360025 -404.811252)
			(xy 19.329252 -404.857765) (xy 19.292035 -404.899302) (xy 19.249167 -404.934977) (xy 19.201561 -404.964031)
			(xy 19.150232 -404.985843) (xy 19.096275 -404.999949) (xy 19.040838 -405.006049) (xy 18.985104 -405.004012)
			(xy 18.930261 -404.993882) (xy 18.877477 -404.975875) (xy 18.827877 -404.950374) (xy 18.782519 -404.917923)
			(xy 18.74237 -404.879214) (xy 18.708284 -404.835071) (xy 18.680988 -404.786436) (xy 18.661065 -404.734345)
			(xy 18.648939 -404.679908) (xy 18.644868 -404.624286) (xy 18.094299 -404.624286) (xy 18.090075 -404.638327)
			(xy 18.066403 -404.688824) (xy 18.03563 -404.735337) (xy 17.998413 -404.776874) (xy 17.955545 -404.812549)
			(xy 17.907939 -404.841603) (xy 17.85661 -404.863415) (xy 17.802653 -404.877521) (xy 17.747216 -404.883621)
			(xy 17.691482 -404.881584) (xy 17.636639 -404.871454) (xy 17.583855 -404.853447) (xy 17.534255 -404.827946)
			(xy 17.488897 -404.795495) (xy 17.448748 -404.756786) (xy 17.414662 -404.712643) (xy 17.387366 -404.664008)
			(xy 17.367443 -404.611917) (xy 17.355317 -404.55748) (xy 17.351246 -404.501858) (xy 1.332484 -404.501858)
			(xy 1.332484 -410.248608) (xy 14.998698 -410.248608) (xy 15.002769 -410.192986) (xy 15.014895 -410.138549)
			(xy 15.034818 -410.086458) (xy 15.062114 -410.037823) (xy 15.0962 -409.99368) (xy 15.136349 -409.954971)
			(xy 15.181707 -409.92252) (xy 15.231307 -409.897019) (xy 15.284091 -409.879012) (xy 15.338934 -409.868882)
			(xy 15.394668 -409.866845) (xy 15.450105 -409.872945) (xy 15.504062 -409.887051) (xy 15.555391 -409.908863)
			(xy 15.602997 -409.937917) (xy 15.645865 -409.973592) (xy 15.683082 -410.015129) (xy 15.713855 -410.061642)
			(xy 15.737527 -410.112139) (xy 15.753595 -410.165546) (xy 15.761715 -410.220722) (xy 15.762224 -410.248608)
			(xy 15.761715 -410.276494) (xy 15.753595 -410.33167) (xy 15.737527 -410.385077) (xy 15.713855 -410.435574)
			(xy 15.683082 -410.482087) (xy 15.645865 -410.523624) (xy 15.602997 -410.559299) (xy 15.555391 -410.588353)
			(xy 15.504062 -410.610165) (xy 15.450105 -410.624271) (xy 15.394668 -410.630371) (xy 15.338934 -410.628334)
			(xy 15.284091 -410.618204) (xy 15.231307 -410.600197) (xy 15.181707 -410.574696) (xy 15.136349 -410.542245)
			(xy 15.0962 -410.503536) (xy 15.062114 -410.459393) (xy 15.034818 -410.410758) (xy 15.014895 -410.358667)
			(xy 15.002769 -410.30423) (xy 14.998698 -410.248608) (xy 1.332484 -410.248608) (xy 1.332484 -412.752286)
			(xy 17.883122 -412.752286) (xy 17.887193 -412.696664) (xy 17.899319 -412.642227) (xy 17.919242 -412.590136)
			(xy 17.946538 -412.541501) (xy 17.980624 -412.497358) (xy 18.020773 -412.458649) (xy 18.066131 -412.426198)
			(xy 18.115731 -412.400697) (xy 18.168515 -412.38269) (xy 18.223358 -412.37256) (xy 18.279092 -412.370523)
			(xy 18.334529 -412.376623) (xy 18.388486 -412.390729) (xy 18.439815 -412.412541) (xy 18.487421 -412.441595)
			(xy 18.530289 -412.47727) (xy 18.567506 -412.518807) (xy 18.598279 -412.56532) (xy 18.621951 -412.615817)
			(xy 18.638019 -412.669224) (xy 18.646139 -412.7244) (xy 18.646648 -412.752286) (xy 18.646139 -412.780172)
			(xy 18.638019 -412.835348) (xy 18.621951 -412.888755) (xy 18.598527 -412.938722) (xy 19.503896 -412.938722)
			(xy 19.507967 -412.8831) (xy 19.520093 -412.828663) (xy 19.540016 -412.776572) (xy 19.567312 -412.727937)
			(xy 19.601398 -412.683794) (xy 19.641547 -412.645085) (xy 19.686905 -412.612634) (xy 19.736505 -412.587133)
			(xy 19.789289 -412.569126) (xy 19.844132 -412.558996) (xy 19.899866 -412.556959) (xy 19.955303 -412.563059)
			(xy 20.00926 -412.577165) (xy 20.060589 -412.598977) (xy 20.108195 -412.628031) (xy 20.151063 -412.663706)
			(xy 20.1683 -412.682944) (xy 20.874988 -412.682944) (xy 20.879059 -412.627322) (xy 20.891185 -412.572885)
			(xy 20.911108 -412.520794) (xy 20.938404 -412.472159) (xy 20.97249 -412.428016) (xy 21.012639 -412.389307)
			(xy 21.057997 -412.356856) (xy 21.107597 -412.331355) (xy 21.160381 -412.313348) (xy 21.215224 -412.303218)
			(xy 21.270958 -412.301181) (xy 21.326395 -412.307281) (xy 21.380352 -412.321387) (xy 21.431681 -412.343199)
			(xy 21.479287 -412.372253) (xy 21.522155 -412.407928) (xy 21.559372 -412.449465) (xy 21.590145 -412.495978)
			(xy 21.613817 -412.546475) (xy 21.629885 -412.599882) (xy 21.638005 -412.655058) (xy 21.638514 -412.682944)
			(xy 21.638005 -412.71083) (xy 21.629885 -412.766006) (xy 21.613817 -412.819413) (xy 21.590145 -412.86991)
			(xy 21.559372 -412.916423) (xy 21.522155 -412.95796) (xy 21.479287 -412.993635) (xy 21.431681 -413.022689)
			(xy 21.380352 -413.044501) (xy 21.326395 -413.058607) (xy 21.270958 -413.064707) (xy 21.215224 -413.06267)
			(xy 21.160381 -413.05254) (xy 21.107597 -413.034533) (xy 21.057997 -413.009032) (xy 21.012639 -412.976581)
			(xy 20.97249 -412.937872) (xy 20.938404 -412.893729) (xy 20.911108 -412.845094) (xy 20.891185 -412.793003)
			(xy 20.879059 -412.738566) (xy 20.874988 -412.682944) (xy 20.1683 -412.682944) (xy 20.18828 -412.705243)
			(xy 20.219053 -412.751756) (xy 20.242725 -412.802253) (xy 20.258793 -412.85566) (xy 20.266913 -412.910836)
			(xy 20.267422 -412.938722) (xy 20.266913 -412.966608) (xy 20.258793 -413.021784) (xy 20.242725 -413.075191)
			(xy 20.219053 -413.125688) (xy 20.18828 -413.172201) (xy 20.151063 -413.213738) (xy 20.108195 -413.249413)
			(xy 20.060589 -413.278467) (xy 20.00926 -413.300279) (xy 19.955303 -413.314385) (xy 19.899866 -413.320485)
			(xy 19.844132 -413.318448) (xy 19.789289 -413.308318) (xy 19.736505 -413.290311) (xy 19.686905 -413.26481)
			(xy 19.641547 -413.232359) (xy 19.601398 -413.19365) (xy 19.567312 -413.149507) (xy 19.540016 -413.100872)
			(xy 19.520093 -413.048781) (xy 19.507967 -412.994344) (xy 19.503896 -412.938722) (xy 18.598527 -412.938722)
			(xy 18.598279 -412.939252) (xy 18.567506 -412.985765) (xy 18.530289 -413.027302) (xy 18.487421 -413.062977)
			(xy 18.439815 -413.092031) (xy 18.388486 -413.113843) (xy 18.334529 -413.127949) (xy 18.279092 -413.134049)
			(xy 18.223358 -413.132012) (xy 18.168515 -413.121882) (xy 18.115731 -413.103875) (xy 18.066131 -413.078374)
			(xy 18.020773 -413.045923) (xy 17.980624 -413.007214) (xy 17.946538 -412.963071) (xy 17.919242 -412.914436)
			(xy 17.899319 -412.862345) (xy 17.887193 -412.807908) (xy 17.883122 -412.752286) (xy 1.332484 -412.752286)
			(xy 1.332484 -414.967166) (xy 1.332952 -414.97704) (xy 1.336382 -414.985454) (xy 17.471896 -414.985454)
			(xy 17.475967 -414.929832) (xy 17.488093 -414.875395) (xy 17.508016 -414.823304) (xy 17.535312 -414.774669)
			(xy 17.569398 -414.730526) (xy 17.609547 -414.691817) (xy 17.654905 -414.659366) (xy 17.704505 -414.633865)
			(xy 17.757289 -414.615858) (xy 17.812132 -414.605728) (xy 17.867866 -414.603691) (xy 17.923303 -414.609791)
			(xy 17.97726 -414.623897) (xy 18.028589 -414.645709) (xy 18.076195 -414.674763) (xy 18.119063 -414.710438)
			(xy 18.15628 -414.751975) (xy 18.187053 -414.798488) (xy 18.210725 -414.848985) (xy 18.226793 -414.902392)
			(xy 18.234913 -414.957568) (xy 18.235422 -414.985454) (xy 19.503896 -414.985454) (xy 19.507967 -414.929832)
			(xy 19.520093 -414.875395) (xy 19.540016 -414.823304) (xy 19.567312 -414.774669) (xy 19.601398 -414.730526)
			(xy 19.641547 -414.691817) (xy 19.686905 -414.659366) (xy 19.736505 -414.633865) (xy 19.789289 -414.615858)
			(xy 19.844132 -414.605728) (xy 19.899866 -414.603691) (xy 19.955303 -414.609791) (xy 20.00926 -414.623897)
			(xy 20.060589 -414.645709) (xy 20.108195 -414.674763) (xy 20.151063 -414.710438) (xy 20.18828 -414.751975)
			(xy 20.219053 -414.798488) (xy 20.242725 -414.848985) (xy 20.258793 -414.902392) (xy 20.266913 -414.957568)
			(xy 20.267422 -414.985454) (xy 20.519896 -414.985454) (xy 20.523967 -414.929832) (xy 20.536093 -414.875395)
			(xy 20.556016 -414.823304) (xy 20.583312 -414.774669) (xy 20.617398 -414.730526) (xy 20.657547 -414.691817)
			(xy 20.702905 -414.659366) (xy 20.752505 -414.633865) (xy 20.805289 -414.615858) (xy 20.860132 -414.605728)
			(xy 20.915866 -414.603691) (xy 20.971303 -414.609791) (xy 21.02526 -414.623897) (xy 21.076589 -414.645709)
			(xy 21.124195 -414.674763) (xy 21.167063 -414.710438) (xy 21.20428 -414.751975) (xy 21.235053 -414.798488)
			(xy 21.258725 -414.848985) (xy 21.274793 -414.902392) (xy 21.282913 -414.957568) (xy 21.283422 -414.985454)
			(xy 21.282913 -415.01334) (xy 21.274793 -415.068516) (xy 21.258725 -415.121923) (xy 21.235053 -415.17242)
			(xy 21.20428 -415.218933) (xy 21.167063 -415.26047) (xy 21.124195 -415.296145) (xy 21.076589 -415.325199)
			(xy 21.02526 -415.347011) (xy 20.971303 -415.361117) (xy 20.915866 -415.367217) (xy 20.860132 -415.36518)
			(xy 20.805289 -415.35505) (xy 20.752505 -415.337043) (xy 20.702905 -415.311542) (xy 20.657547 -415.279091)
			(xy 20.617398 -415.240382) (xy 20.583312 -415.196239) (xy 20.556016 -415.147604) (xy 20.536093 -415.095513)
			(xy 20.523967 -415.041076) (xy 20.519896 -414.985454) (xy 20.267422 -414.985454) (xy 20.266913 -415.01334)
			(xy 20.258793 -415.068516) (xy 20.242725 -415.121923) (xy 20.219053 -415.17242) (xy 20.18828 -415.218933)
			(xy 20.151063 -415.26047) (xy 20.108195 -415.296145) (xy 20.060589 -415.325199) (xy 20.00926 -415.347011)
			(xy 19.955303 -415.361117) (xy 19.899866 -415.367217) (xy 19.844132 -415.36518) (xy 19.789289 -415.35505)
			(xy 19.736505 -415.337043) (xy 19.686905 -415.311542) (xy 19.641547 -415.279091) (xy 19.601398 -415.240382)
			(xy 19.567312 -415.196239) (xy 19.540016 -415.147604) (xy 19.520093 -415.095513) (xy 19.507967 -415.041076)
			(xy 19.503896 -414.985454) (xy 18.235422 -414.985454) (xy 18.234913 -415.01334) (xy 18.226793 -415.068516)
			(xy 18.210725 -415.121923) (xy 18.187053 -415.17242) (xy 18.15628 -415.218933) (xy 18.119063 -415.26047)
			(xy 18.076195 -415.296145) (xy 18.028589 -415.325199) (xy 17.97726 -415.347011) (xy 17.923303 -415.361117)
			(xy 17.867866 -415.367217) (xy 17.812132 -415.36518) (xy 17.757289 -415.35505) (xy 17.704505 -415.337043)
			(xy 17.654905 -415.311542) (xy 17.609547 -415.279091) (xy 17.569398 -415.240382) (xy 17.535312 -415.196239)
			(xy 17.508016 -415.147604) (xy 17.488093 -415.095513) (xy 17.475967 -415.041076) (xy 17.471896 -414.985454)
			(xy 1.336382 -414.985454) (xy 1.340406 -414.995327) (xy 1.346962 -415.002726) (xy 1.347216 -415.00298)
			(xy 3.070098 -416.725862) (xy 3.070606 -416.72637) (xy 3.077986 -416.732958) (xy 3.096284 -416.740423)
			(xy 3.106166 -416.740848)
		)
		(stroke
			(width 0)
			(type solid)
		)
		(fill yes)
		(layer "In15.Cu")
		(net "GND")
	)
	(gr_poly
		(pts
			(xy 101.178106 -366.26165) (xy 101.190354 -366.260924) (xy 101.212101 -366.249645) (xy 101.219762 -366.24006)
			(xy 101.236355 -366.217372) (xy 101.275115 -366.176667) (xy 101.319428 -366.142088) (xy 101.368335 -366.114386)
			(xy 101.420777 -366.094159) (xy 101.475619 -366.081845) (xy 101.531674 -366.07771) (xy 101.587729 -366.081845)
			(xy 101.642571 -366.094159) (xy 101.695013 -366.114386) (xy 101.74392 -366.142088) (xy 101.788233 -366.176667)
			(xy 101.826993 -366.217372) (xy 101.843586 -366.24006) (xy 101.85121 -366.249687) (xy 101.87298 -366.260963)
			(xy 101.885242 -366.26165) (xy 104.415844 -366.26165) (xy 104.42591 -366.261217) (xy 104.444498 -366.253486)
			(xy 104.451912 -366.246664) (xy 106.705146 -363.99343) (xy 106.711952 -363.986084) (xy 106.719667 -363.96762)
			(xy 106.720132 -363.957616) (xy 106.72445 -363.330998) (xy 106.726228 -363.276134) (xy 106.895138 -360.541062)
			(xy 106.876342 -360.512868) (xy 106.860086 -360.507026) (xy 106.835424 -360.498048) (xy 106.788633 -360.474274)
			(xy 106.745546 -360.444307) (xy 106.706977 -360.408711) (xy 106.673656 -360.368161) (xy 106.646214 -360.323423)
			(xy 106.625168 -360.275344) (xy 106.610917 -360.224832) (xy 106.603731 -360.172842) (xy 106.603292 -360.1466)
			(xy 106.603827 -360.117683) (xy 106.612561 -360.060512) (xy 106.629829 -360.005316) (xy 106.655233 -359.953361)
			(xy 106.688193 -359.905837) (xy 106.707686 -359.884472) (xy 106.714036 -359.877614) (xy 106.721148 -359.86085)
			(xy 106.724704 -359.775252) (xy 106.718862 -359.758234) (xy 106.71302 -359.750868) (xy 106.697129 -359.730446)
			(xy 106.670421 -359.686126) (xy 106.649952 -359.638601) (xy 106.636098 -359.588745) (xy 106.629114 -359.537473)
			(xy 106.628692 -359.5116) (xy 106.62916 -359.484995) (xy 106.636564 -359.432303) (xy 106.651215 -359.381149)
			(xy 106.672829 -359.332527) (xy 106.700987 -359.287378) (xy 106.735142 -359.246577) (xy 106.774634 -359.210915)
			(xy 106.818696 -359.181085) (xy 106.866474 -359.157663) (xy 106.917042 -359.141104) (xy 106.943144 -359.135934)
			(xy 106.96067 -359.132886) (xy 106.983784 -359.106978) (xy 107.17149 -356.06482) (xy 107.160568 -356.041452)
			(xy 107.1499 -356.033832) (xy 107.129242 -356.018401) (xy 107.091873 -355.982872) (xy 107.059631 -355.942632)
			(xy 107.033103 -355.898416) (xy 107.012774 -355.851029) (xy 106.999013 -355.801336) (xy 106.992072 -355.750242)
			(xy 106.991658 -355.72446) (xy 106.992205 -355.695318) (xy 107.001058 -355.637709) (xy 107.018568 -355.582117)
			(xy 107.044327 -355.529833) (xy 107.077737 -355.482074) (xy 107.11802 -355.439951) (xy 107.164239 -355.404442)
			(xy 107.189524 -355.389942) (xy 107.201208 -355.383592) (xy 107.214924 -355.362002) (xy 107.222036 -355.246178)
			(xy 107.215432 -355.227128) (xy 107.208574 -355.219508) (xy 107.190359 -355.198403) (xy 107.159615 -355.1519)
			(xy 107.135968 -355.101417) (xy 107.119922 -355.048029) (xy 107.111821 -354.992874) (xy 107.111292 -354.965)
			(xy 107.111772 -354.937848) (xy 107.119476 -354.884094) (xy 107.134728 -354.831976) (xy 107.157221 -354.78255)
			(xy 107.186498 -354.736814) (xy 107.221967 -354.695695) (xy 107.242102 -354.677472) (xy 107.249976 -354.670614)
			(xy 107.258866 -354.65258) (xy 107.269534 -354.480368) (xy 107.26293 -354.461826) (xy 107.256326 -354.453952)
			(xy 107.238643 -354.433009) (xy 107.208843 -354.387008) (xy 107.185939 -354.337213) (xy 107.170402 -354.284651)
			(xy 107.162552 -354.230405) (xy 107.162092 -354.203) (xy 107.162543 -354.176235) (xy 107.170022 -354.123229)
			(xy 107.184834 -354.071788) (xy 107.206687 -354.022922) (xy 107.235154 -353.977587) (xy 107.269675 -353.936675)
			(xy 107.289346 -353.91852) (xy 107.296966 -353.911662) (xy 107.305602 -353.893882) (xy 107.328716 -353.51847)
			(xy 107.328832 -353.508546) (xy 107.322435 -353.489777) (xy 107.309432 -353.474807) (xy 107.300776 -353.469956)
			(xy 107.203748 -353.421188) (xy 107.173268 -353.424998) (xy 107.161584 -353.434904) (xy 107.140819 -353.451901)
			(xy 107.095423 -353.48051) (xy 107.046464 -353.502475) (xy 106.994911 -353.517361) (xy 106.94178 -353.524875)
			(xy 106.91495 -353.525328) (xy 106.8877 -353.524839) (xy 106.833755 -353.517076) (xy 106.781463 -353.501716)
			(xy 106.731889 -353.479071) (xy 106.686043 -353.449601) (xy 106.644857 -353.413908) (xy 106.609169 -353.372717)
			(xy 106.579705 -353.326867) (xy 106.557067 -353.27729) (xy 106.541713 -353.224997) (xy 106.533958 -353.17105)
			(xy 106.533958 -353.11655) (xy 106.541713 -353.062603) (xy 106.557067 -353.01031) (xy 106.579705 -352.960733)
			(xy 106.609169 -352.914883) (xy 106.644857 -352.873692) (xy 106.686043 -352.837999) (xy 106.731889 -352.808529)
			(xy 106.781463 -352.785884) (xy 106.833755 -352.770524) (xy 106.8877 -352.762761) (xy 106.91495 -352.762312)
			(xy 106.941246 -352.762756) (xy 106.993339 -352.76999) (xy 107.043944 -352.784312) (xy 107.092101 -352.805452)
			(xy 107.136897 -352.833008) (xy 107.177481 -352.866458) (xy 107.19562 -352.885502) (xy 107.206034 -352.896678)
			(xy 107.235498 -352.904044) (xy 107.338114 -352.867722) (xy 107.347356 -352.863951) (xy 107.362209 -352.85065)
			(xy 107.370872 -352.832691) (xy 107.371896 -352.822764) (xy 107.738926 -346.879164) (xy 107.738926 -346.73667)
			(xy 107.738516 -346.727901) (xy 107.732547 -346.711406) (xy 107.727242 -346.704412) (xy 107.710884 -346.683823)
			(xy 107.683381 -346.639004) (xy 107.662291 -346.590834) (xy 107.648012 -346.540225) (xy 107.640816 -346.488135)
			(xy 107.640374 -346.461842) (xy 107.640798 -346.435549) (xy 107.647991 -346.383457) (xy 107.662273 -346.332847)
			(xy 107.683374 -346.28468) (xy 107.710894 -346.23987) (xy 107.727242 -346.219272) (xy 107.732579 -346.212294)
			(xy 107.738567 -346.195791) (xy 107.738926 -346.187014) (xy 107.738926 -339.949282) (xy 107.738435 -339.939275)
			(xy 107.730774 -339.920785) (xy 107.716622 -339.906631) (xy 107.698133 -339.898966) (xy 107.688126 -339.898482)
			(xy 67.155822 -339.898482) (xy 67.152079 -339.898564) (xy 67.144682 -339.899715) (xy 67.14109 -339.900768)
			(xy 65.316608 -340.454234) (xy 65.311782 -340.455758) (xy 61.68009 -341.9602) (xy 61.669538 -341.965272)
			(xy 61.654183 -341.982914) (xy 61.64816 -342.005513) (xy 61.649864 -342.017096) (xy 61.65342 -342.034876)
			(xy 61.68136 -342.057736) (xy 62.235842 -342.057736) (xy 62.26311 -342.058225) (xy 62.317089 -342.065992)
			(xy 62.369414 -342.081361) (xy 62.419019 -342.10402) (xy 62.464895 -342.133507) (xy 62.506107 -342.169222)
			(xy 62.541818 -342.210439) (xy 62.571301 -342.256318) (xy 62.593954 -342.305926) (xy 62.609317 -342.358252)
			(xy 62.617078 -342.412232) (xy 62.617078 -342.466768) (xy 62.617078 -342.466771) (xy 64.099899 -342.466771)
			(xy 64.099899 -342.412229) (xy 64.107662 -342.358241) (xy 64.123028 -342.305908) (xy 64.145686 -342.256295)
			(xy 64.175174 -342.210411) (xy 64.210892 -342.16919) (xy 64.252112 -342.133473) (xy 64.297997 -342.103985)
			(xy 64.34761 -342.081327) (xy 64.399943 -342.065961) (xy 64.453931 -342.058199) (xy 64.481202 -342.057736)
			(xy 65.344802 -342.057736) (xy 65.372071 -342.058227) (xy 65.426054 -342.065988) (xy 65.478383 -342.081354)
			(xy 65.527993 -342.10401) (xy 65.573873 -342.133496) (xy 65.615091 -342.169211) (xy 65.650805 -342.210428)
			(xy 65.680291 -342.256309) (xy 65.702947 -342.305919) (xy 65.718312 -342.358248) (xy 65.726074 -342.412231)
			(xy 65.726074 -342.466768) (xy 67.208922 -342.466768) (xy 67.208922 -342.412232) (xy 67.216683 -342.358252)
			(xy 67.232047 -342.305925) (xy 67.2547 -342.256317) (xy 67.284183 -342.210438) (xy 67.319894 -342.169221)
			(xy 67.361107 -342.133505) (xy 67.406984 -342.104018) (xy 67.456589 -342.08136) (xy 67.508914 -342.065991)
			(xy 67.562894 -342.058225) (xy 67.590162 -342.057736) (xy 68.453762 -342.057736) (xy 68.481035 -342.058201)
			(xy 68.535025 -342.065959) (xy 68.587362 -342.081321) (xy 68.63698 -342.103977) (xy 68.682868 -342.133463)
			(xy 68.724093 -342.16918) (xy 68.759814 -342.210401) (xy 68.789305 -342.256287) (xy 68.811965 -342.305902)
			(xy 68.827333 -342.358237) (xy 68.835096 -342.412227) (xy 68.835096 -342.466772) (xy 70.3178 -342.466772)
			(xy 70.3178 -342.412228) (xy 70.325562 -342.358239) (xy 70.34093 -342.305904) (xy 70.363589 -342.256289)
			(xy 70.393079 -342.210404) (xy 70.428799 -342.169183) (xy 70.470022 -342.133466) (xy 70.515909 -342.103979)
			(xy 70.565525 -342.081322) (xy 70.61786 -342.065958) (xy 70.67185 -342.058198) (xy 70.699122 -342.057736)
			(xy 71.562722 -342.057736) (xy 71.58999 -342.058228) (xy 71.643971 -342.065992) (xy 71.696298 -342.081359)
			(xy 71.745905 -342.104017) (xy 71.791783 -342.133503) (xy 71.832998 -342.169218) (xy 71.86871 -342.210435)
			(xy 71.898194 -342.256314) (xy 71.920848 -342.305923) (xy 71.936213 -342.35825) (xy 71.943974 -342.412232)
			(xy 71.943974 -342.466768) (xy 71.943974 -342.466769) (xy 73.426822 -342.466769) (xy 73.426822 -342.412231)
			(xy 73.434584 -342.358249) (xy 73.449948 -342.305921) (xy 73.472603 -342.256311) (xy 73.502087 -342.210431)
			(xy 73.537801 -342.169214) (xy 73.579017 -342.133498) (xy 73.624896 -342.104012) (xy 73.674504 -342.081354)
			(xy 73.726831 -342.065987) (xy 73.780813 -342.058224) (xy 73.808082 -342.057736) (xy 74.671682 -342.057736)
			(xy 74.698954 -342.058202) (xy 74.752942 -342.065962) (xy 74.805277 -342.081327) (xy 74.854892 -342.103983)
			(xy 74.900778 -342.13347) (xy 74.942 -342.169188) (xy 74.977719 -342.210408) (xy 75.007208 -342.256292)
			(xy 75.029867 -342.305906) (xy 75.045234 -342.35824) (xy 75.052996 -342.412228) (xy 75.052996 -342.466772)
			(xy 75.052996 -342.466773) (xy 76.5357 -342.466773) (xy 76.5357 -342.412227) (xy 76.543463 -342.358236)
			(xy 76.558831 -342.3059) (xy 76.581492 -342.256284) (xy 76.610984 -342.210398) (xy 76.646706 -342.169176)
			(xy 76.687931 -342.133459) (xy 76.73382 -342.103972) (xy 76.783439 -342.081317) (xy 76.835777 -342.065954)
			(xy 76.889769 -342.058197) (xy 76.917042 -342.057736) (xy 77.780642 -342.057736) (xy 77.807909 -342.058229)
			(xy 77.861888 -342.065996) (xy 77.914212 -342.081365) (xy 77.963817 -342.104023) (xy 78.009692 -342.13351)
			(xy 78.050905 -342.169225) (xy 78.086615 -342.210441) (xy 78.116097 -342.25632) (xy 78.13875 -342.305927)
			(xy 78.154113 -342.358253) (xy 78.161874 -342.412233) (xy 78.161874 -342.466767) (xy 78.161873 -342.466771)
			(xy 79.644699 -342.466771) (xy 79.644699 -342.412229) (xy 79.652462 -342.358241) (xy 79.667828 -342.305908)
			(xy 79.690486 -342.256295) (xy 79.719974 -342.210411) (xy 79.755692 -342.16919) (xy 79.796912 -342.133473)
			(xy 79.842797 -342.103985) (xy 79.89241 -342.081327) (xy 79.944743 -342.065961) (xy 79.998731 -342.058199)
			(xy 80.026002 -342.057736) (xy 80.889602 -342.057736) (xy 80.916871 -342.058227) (xy 80.970854 -342.065988)
			(xy 81.023183 -342.081354) (xy 81.072793 -342.10401) (xy 81.118673 -342.133496) (xy 81.159891 -342.169211)
			(xy 81.195605 -342.210428) (xy 81.225091 -342.256309) (xy 81.247747 -342.305919) (xy 81.263112 -342.358248)
			(xy 81.270874 -342.412231) (xy 81.270874 -342.466768) (xy 82.753722 -342.466768) (xy 82.753722 -342.412232)
			(xy 82.761483 -342.358252) (xy 82.776847 -342.305925) (xy 82.7995 -342.256317) (xy 82.828983 -342.210438)
			(xy 82.864694 -342.169221) (xy 82.905907 -342.133505) (xy 82.951784 -342.104018) (xy 83.001389 -342.08136)
			(xy 83.053714 -342.065991) (xy 83.107694 -342.058225) (xy 83.134962 -342.057736) (xy 83.998562 -342.057736)
			(xy 84.025835 -342.058201) (xy 84.079825 -342.065959) (xy 84.132162 -342.081321) (xy 84.18178 -342.103977)
			(xy 84.227668 -342.133463) (xy 84.268893 -342.16918) (xy 84.304614 -342.210401) (xy 84.334105 -342.256287)
			(xy 84.356765 -342.305902) (xy 84.372133 -342.358237) (xy 84.379896 -342.412227) (xy 84.379896 -342.466772)
			(xy 85.8626 -342.466772) (xy 85.8626 -342.412228) (xy 85.870362 -342.358239) (xy 85.88573 -342.305904)
			(xy 85.908389 -342.256289) (xy 85.937879 -342.210404) (xy 85.973599 -342.169183) (xy 86.014822 -342.133466)
			(xy 86.060709 -342.103979) (xy 86.110325 -342.081322) (xy 86.16266 -342.065958) (xy 86.21665 -342.058198)
			(xy 86.243922 -342.057736) (xy 87.107522 -342.057736) (xy 87.13479 -342.058228) (xy 87.188771 -342.065992)
			(xy 87.241098 -342.081359) (xy 87.290705 -342.104017) (xy 87.336583 -342.133503) (xy 87.377798 -342.169218)
			(xy 87.41351 -342.210435) (xy 87.442994 -342.256314) (xy 87.465648 -342.305923) (xy 87.481013 -342.35825)
			(xy 87.488774 -342.412232) (xy 87.488774 -342.466768) (xy 87.488774 -342.466769) (xy 88.971622 -342.466769)
			(xy 88.971622 -342.412231) (xy 88.979384 -342.358249) (xy 88.994748 -342.305921) (xy 89.017403 -342.256311)
			(xy 89.046887 -342.210431) (xy 89.082601 -342.169214) (xy 89.123817 -342.133498) (xy 89.169696 -342.104012)
			(xy 89.219304 -342.081354) (xy 89.271631 -342.065987) (xy 89.325613 -342.058224) (xy 89.352882 -342.057736)
			(xy 90.216482 -342.057736) (xy 90.243754 -342.058202) (xy 90.297742 -342.065962) (xy 90.350077 -342.081327)
			(xy 90.399692 -342.103983) (xy 90.445578 -342.13347) (xy 90.4868 -342.169188) (xy 90.522519 -342.210408)
			(xy 90.552008 -342.256292) (xy 90.574667 -342.305906) (xy 90.590034 -342.35824) (xy 90.597796 -342.412228)
			(xy 90.597796 -342.466772) (xy 90.597796 -342.466773) (xy 92.0805 -342.466773) (xy 92.0805 -342.412227)
			(xy 92.088263 -342.358236) (xy 92.103631 -342.3059) (xy 92.126292 -342.256284) (xy 92.155784 -342.210398)
			(xy 92.191506 -342.169176) (xy 92.232731 -342.133459) (xy 92.27862 -342.103972) (xy 92.328239 -342.081317)
			(xy 92.380577 -342.065954) (xy 92.434569 -342.058197) (xy 92.461842 -342.057736) (xy 93.325442 -342.057736)
			(xy 93.352709 -342.058229) (xy 93.406688 -342.065996) (xy 93.459012 -342.081365) (xy 93.508617 -342.104023)
			(xy 93.554492 -342.13351) (xy 93.595705 -342.169225) (xy 93.631415 -342.210441) (xy 93.660897 -342.25632)
			(xy 93.68355 -342.305927) (xy 93.698913 -342.358253) (xy 93.706674 -342.412233) (xy 93.706674 -342.466767)
			(xy 93.698913 -342.520747) (xy 93.68355 -342.573073) (xy 93.660897 -342.62268) (xy 93.631415 -342.668559)
			(xy 93.60914 -342.694268) (xy 102.35157 -342.694268) (xy 102.35157 -342.634332) (xy 102.359393 -342.574909)
			(xy 102.374905 -342.517016) (xy 102.397841 -342.461642) (xy 102.427809 -342.409736) (xy 102.464294 -342.362185)
			(xy 102.506675 -342.319804) (xy 102.554224 -342.283316) (xy 102.60613 -342.253347) (xy 102.661502 -342.23041)
			(xy 102.719395 -342.214896) (xy 102.778818 -342.207071) (xy 102.808786 -342.20658) (xy 103.672386 -342.20658)
			(xy 103.702355 -342.207072) (xy 103.76178 -342.214894) (xy 103.819676 -342.230405) (xy 103.875051 -342.253341)
			(xy 103.926959 -342.283309) (xy 103.974512 -342.319796) (xy 104.016895 -342.362178) (xy 104.053383 -342.409729)
			(xy 104.083352 -342.461636) (xy 104.10629 -342.517011) (xy 104.121803 -342.574906) (xy 104.129627 -342.634331)
			(xy 104.129627 -342.694269) (xy 104.121803 -342.753694) (xy 104.10629 -342.811589) (xy 104.083352 -342.866964)
			(xy 104.053383 -342.918871) (xy 104.016895 -342.966422) (xy 103.974512 -343.008804) (xy 103.926959 -343.045291)
			(xy 103.875051 -343.075259) (xy 103.819676 -343.098195) (xy 103.76178 -343.113706) (xy 103.702355 -343.121528)
			(xy 103.672386 -343.121996) (xy 102.808786 -343.121996) (xy 102.778818 -343.121529) (xy 102.719395 -343.113704)
			(xy 102.661502 -343.09819) (xy 102.60613 -343.075253) (xy 102.554224 -343.045284) (xy 102.506675 -343.008796)
			(xy 102.464294 -342.966415) (xy 102.427809 -342.918864) (xy 102.397841 -342.866958) (xy 102.374905 -342.811584)
			(xy 102.359393 -342.753691) (xy 102.35157 -342.694268) (xy 93.60914 -342.694268) (xy 93.595705 -342.709775)
			(xy 93.554492 -342.74549) (xy 93.508617 -342.774977) (xy 93.459012 -342.797635) (xy 93.406688 -342.813004)
			(xy 93.352709 -342.820771) (xy 93.325442 -342.82126) (xy 92.461842 -342.82126) (xy 92.434569 -342.820803)
			(xy 92.380577 -342.813046) (xy 92.328239 -342.797683) (xy 92.278621 -342.775028) (xy 92.232731 -342.745541)
			(xy 92.191506 -342.709824) (xy 92.155784 -342.668602) (xy 92.126292 -342.622716) (xy 92.103631 -342.5731)
			(xy 92.088263 -342.520764) (xy 92.0805 -342.466773) (xy 90.597796 -342.466773) (xy 90.590034 -342.52076)
			(xy 90.574667 -342.573094) (xy 90.552008 -342.622708) (xy 90.522519 -342.668592) (xy 90.4868 -342.709812)
			(xy 90.445578 -342.74553) (xy 90.399692 -342.775017) (xy 90.350077 -342.797673) (xy 90.297742 -342.813038)
			(xy 90.243754 -342.820798) (xy 90.216482 -342.82126) (xy 89.352882 -342.82126) (xy 89.325613 -342.820776)
			(xy 89.271631 -342.813013) (xy 89.219304 -342.797646) (xy 89.169696 -342.774988) (xy 89.123817 -342.745502)
			(xy 89.082601 -342.709786) (xy 89.046887 -342.668569) (xy 89.017403 -342.622689) (xy 88.994748 -342.573079)
			(xy 88.979384 -342.520751) (xy 88.971622 -342.466769) (xy 87.488774 -342.466769) (xy 87.481013 -342.52075)
			(xy 87.465648 -342.573077) (xy 87.442994 -342.622686) (xy 87.41351 -342.668565) (xy 87.377798 -342.709782)
			(xy 87.336583 -342.745497) (xy 87.290705 -342.774983) (xy 87.241098 -342.797641) (xy 87.188771 -342.813008)
			(xy 87.13479 -342.820772) (xy 87.107522 -342.82126) (xy 86.243922 -342.82126) (xy 86.21665 -342.820802)
			(xy 86.16266 -342.813042) (xy 86.110325 -342.797678) (xy 86.060709 -342.775021) (xy 86.014822 -342.745534)
			(xy 85.973599 -342.709817) (xy 85.937879 -342.668596) (xy 85.908389 -342.622711) (xy 85.88573 -342.573096)
			(xy 85.870362 -342.520761) (xy 85.8626 -342.466772) (xy 84.379896 -342.466772) (xy 84.379896 -342.466773)
			(xy 84.372133 -342.520763) (xy 84.356765 -342.573098) (xy 84.334105 -342.622713) (xy 84.304614 -342.668599)
			(xy 84.268893 -342.70982) (xy 84.227668 -342.745537) (xy 84.18178 -342.775023) (xy 84.132162 -342.797679)
			(xy 84.079825 -342.813041) (xy 84.025835 -342.820799) (xy 83.998562 -342.82126) (xy 83.134962 -342.82126)
			(xy 83.107694 -342.820775) (xy 83.053714 -342.813009) (xy 83.001389 -342.79764) (xy 82.951784 -342.774982)
			(xy 82.905907 -342.745495) (xy 82.864694 -342.709779) (xy 82.828983 -342.668562) (xy 82.7995 -342.622683)
			(xy 82.776847 -342.573075) (xy 82.761483 -342.520748) (xy 82.753722 -342.466768) (xy 81.270874 -342.466768)
			(xy 81.270874 -342.466769) (xy 81.263112 -342.520752) (xy 81.247747 -342.573081) (xy 81.225091 -342.622691)
			(xy 81.195605 -342.668572) (xy 81.159891 -342.709789) (xy 81.118673 -342.745504) (xy 81.072793 -342.77499)
			(xy 81.023183 -342.797646) (xy 80.970854 -342.813012) (xy 80.916871 -342.820773) (xy 80.889602 -342.82126)
			(xy 80.026002 -342.82126) (xy 79.998731 -342.820801) (xy 79.944743 -342.813039) (xy 79.89241 -342.797673)
			(xy 79.842797 -342.775015) (xy 79.796912 -342.745527) (xy 79.755692 -342.70981) (xy 79.719974 -342.668589)
			(xy 79.690486 -342.622705) (xy 79.667828 -342.573092) (xy 79.652462 -342.520759) (xy 79.644699 -342.466771)
			(xy 78.161873 -342.466771) (xy 78.154113 -342.520747) (xy 78.13875 -342.573073) (xy 78.116097 -342.62268)
			(xy 78.086615 -342.668559) (xy 78.050905 -342.709775) (xy 78.009692 -342.74549) (xy 77.963817 -342.774977)
			(xy 77.914212 -342.797635) (xy 77.861888 -342.813004) (xy 77.807909 -342.820771) (xy 77.780642 -342.82126)
			(xy 76.917042 -342.82126) (xy 76.889769 -342.820803) (xy 76.835777 -342.813046) (xy 76.783439 -342.797683)
			(xy 76.733821 -342.775028) (xy 76.687931 -342.745541) (xy 76.646706 -342.709824) (xy 76.610984 -342.668602)
			(xy 76.581492 -342.622716) (xy 76.558831 -342.5731) (xy 76.543463 -342.520764) (xy 76.5357 -342.466773)
			(xy 75.052996 -342.466773) (xy 75.045234 -342.52076) (xy 75.029867 -342.573094) (xy 75.007208 -342.622708)
			(xy 74.977719 -342.668592) (xy 74.942 -342.709812) (xy 74.900778 -342.74553) (xy 74.854892 -342.775017)
			(xy 74.805277 -342.797673) (xy 74.752942 -342.813038) (xy 74.698954 -342.820798) (xy 74.671682 -342.82126)
			(xy 73.808082 -342.82126) (xy 73.780813 -342.820776) (xy 73.726831 -342.813013) (xy 73.674504 -342.797646)
			(xy 73.624896 -342.774988) (xy 73.579017 -342.745502) (xy 73.537801 -342.709786) (xy 73.502087 -342.668569)
			(xy 73.472603 -342.622689) (xy 73.449948 -342.573079) (xy 73.434584 -342.520751) (xy 73.426822 -342.466769)
			(xy 71.943974 -342.466769) (xy 71.936213 -342.52075) (xy 71.920848 -342.573077) (xy 71.898194 -342.622686)
			(xy 71.86871 -342.668565) (xy 71.832998 -342.709782) (xy 71.791783 -342.745497) (xy 71.745905 -342.774983)
			(xy 71.696298 -342.797641) (xy 71.643971 -342.813008) (xy 71.58999 -342.820772) (xy 71.562722 -342.82126)
			(xy 70.699122 -342.82126) (xy 70.67185 -342.820802) (xy 70.61786 -342.813042) (xy 70.565525 -342.797678)
			(xy 70.515909 -342.775021) (xy 70.470022 -342.745534) (xy 70.428799 -342.709817) (xy 70.393079 -342.668596)
			(xy 70.363589 -342.622711) (xy 70.34093 -342.573096) (xy 70.325562 -342.520761) (xy 70.3178 -342.466772)
			(xy 68.835096 -342.466772) (xy 68.835096 -342.466773) (xy 68.827333 -342.520763) (xy 68.811965 -342.573098)
			(xy 68.789305 -342.622713) (xy 68.759814 -342.668599) (xy 68.724093 -342.70982) (xy 68.682868 -342.745537)
			(xy 68.63698 -342.775023) (xy 68.587362 -342.797679) (xy 68.535025 -342.813041) (xy 68.481035 -342.820799)
			(xy 68.453762 -342.82126) (xy 67.590162 -342.82126) (xy 67.562894 -342.820775) (xy 67.508914 -342.813009)
			(xy 67.456589 -342.79764) (xy 67.406984 -342.774982) (xy 67.361107 -342.745495) (xy 67.319894 -342.709779)
			(xy 67.284183 -342.668562) (xy 67.2547 -342.622683) (xy 67.232047 -342.573075) (xy 67.216683 -342.520748)
			(xy 67.208922 -342.466768) (xy 65.726074 -342.466768) (xy 65.726074 -342.466769) (xy 65.718312 -342.520752)
			(xy 65.702947 -342.573081) (xy 65.680291 -342.622691) (xy 65.650805 -342.668572) (xy 65.615091 -342.709789)
			(xy 65.573873 -342.745504) (xy 65.527993 -342.77499) (xy 65.478383 -342.797646) (xy 65.426054 -342.813012)
			(xy 65.372071 -342.820773) (xy 65.344802 -342.82126) (xy 64.481202 -342.82126) (xy 64.453931 -342.820801)
			(xy 64.399943 -342.813039) (xy 64.34761 -342.797673) (xy 64.297997 -342.775015) (xy 64.252112 -342.745527)
			(xy 64.210892 -342.70981) (xy 64.175174 -342.668589) (xy 64.145686 -342.622705) (xy 64.123028 -342.573092)
			(xy 64.107662 -342.520759) (xy 64.099899 -342.466771) (xy 62.617078 -342.466771) (xy 62.609317 -342.520748)
			(xy 62.593954 -342.573074) (xy 62.571301 -342.622682) (xy 62.541818 -342.668561) (xy 62.506107 -342.709778)
			(xy 62.464895 -342.745493) (xy 62.419019 -342.77498) (xy 62.369414 -342.797639) (xy 62.317089 -342.813008)
			(xy 62.26311 -342.820775) (xy 62.235842 -342.82126) (xy 61.372242 -342.82126) (xy 61.340456 -342.820579)
			(xy 61.277774 -342.809976) (xy 61.247528 -342.800178) (xy 61.23559 -342.796114) (xy 61.21146 -342.79967)
			(xy 61.13399 -342.854788) (xy 61.12449 -342.862408) (xy 61.113365 -342.88403) (xy 61.112654 -342.89619)
			(xy 61.112654 -343.446862) (xy 101.207568 -343.446862) (xy 101.211639 -343.39124) (xy 101.223765 -343.336803)
			(xy 101.243688 -343.284712) (xy 101.270984 -343.236077) (xy 101.30507 -343.191934) (xy 101.345219 -343.153225)
			(xy 101.390577 -343.120774) (xy 101.440177 -343.095273) (xy 101.492961 -343.077266) (xy 101.547804 -343.067136)
			(xy 101.603538 -343.065099) (xy 101.658975 -343.071199) (xy 101.712932 -343.085305) (xy 101.764261 -343.107117)
			(xy 101.811867 -343.136171) (xy 101.854735 -343.171846) (xy 101.891952 -343.213383) (xy 101.922725 -343.259896)
			(xy 101.946397 -343.310393) (xy 101.962465 -343.3638) (xy 101.970585 -343.418976) (xy 101.971094 -343.446862)
			(xy 101.970585 -343.474748) (xy 101.962465 -343.529924) (xy 101.946397 -343.583331) (xy 101.922725 -343.633828)
			(xy 101.891952 -343.680341) (xy 101.854735 -343.721878) (xy 101.811867 -343.757553) (xy 101.764261 -343.786607)
			(xy 101.712932 -343.808419) (xy 101.658975 -343.822525) (xy 101.603538 -343.828625) (xy 101.547804 -343.826588)
			(xy 101.492961 -343.816458) (xy 101.440177 -343.798451) (xy 101.390577 -343.77295) (xy 101.345219 -343.740499)
			(xy 101.30507 -343.70179) (xy 101.270984 -343.657647) (xy 101.243688 -343.609012) (xy 101.223765 -343.556921)
			(xy 101.211639 -343.502484) (xy 101.207568 -343.446862) (xy 61.112654 -343.446862) (xy 61.112654 -345.008454)
			(xy 61.113358 -345.020609) (xy 61.124511 -345.042211) (xy 61.13399 -345.049856) (xy 61.21146 -345.104974)
			(xy 61.23559 -345.10853) (xy 61.247528 -345.104466) (xy 61.277766 -345.094638) (xy 61.340454 -345.084046)
			(xy 61.372242 -345.083384) (xy 62.235842 -345.083384) (xy 62.263106 -345.083873) (xy 62.317079 -345.091639)
			(xy 62.369397 -345.107006) (xy 62.418996 -345.129662) (xy 62.464866 -345.159145) (xy 62.506074 -345.194856)
			(xy 62.54178 -345.236068) (xy 62.571258 -345.281941) (xy 62.593909 -345.331543) (xy 62.60927 -345.383862)
			(xy 62.61703 -345.437836) (xy 62.61703 -345.492364) (xy 62.617029 -345.492368) (xy 64.099947 -345.492368)
			(xy 64.099947 -345.437832) (xy 64.107709 -345.383852) (xy 64.123073 -345.331525) (xy 64.145728 -345.281918)
			(xy 64.175212 -345.23604) (xy 64.210926 -345.194824) (xy 64.252141 -345.159111) (xy 64.29802 -345.129627)
			(xy 64.347627 -345.106972) (xy 64.399954 -345.091608) (xy 64.453934 -345.083847) (xy 64.481202 -345.083384)
			(xy 65.344802 -345.083384) (xy 65.372075 -345.083779) (xy 65.426064 -345.091542) (xy 65.4784 -345.106909)
			(xy 65.528016 -345.129568) (xy 65.573902 -345.159057) (xy 65.615124 -345.194777) (xy 65.650844 -345.236)
			(xy 65.680333 -345.281886) (xy 65.702992 -345.331502) (xy 65.718359 -345.383838) (xy 65.726121 -345.437827)
			(xy 65.726121 -345.492364) (xy 67.20897 -345.492364) (xy 67.20897 -345.437836) (xy 67.21673 -345.383862)
			(xy 67.232092 -345.331542) (xy 67.254742 -345.28194) (xy 67.284221 -345.236066) (xy 67.319928 -345.194855)
			(xy 67.361136 -345.159144) (xy 67.407007 -345.12966) (xy 67.456606 -345.107005) (xy 67.508925 -345.091638)
			(xy 67.562898 -345.083873) (xy 67.590162 -345.083384) (xy 68.453762 -345.083384) (xy 68.481038 -345.083753)
			(xy 68.535036 -345.091512) (xy 68.587379 -345.106877) (xy 68.637003 -345.129535) (xy 68.682897 -345.159025)
			(xy 68.724127 -345.194747) (xy 68.759852 -345.235973) (xy 68.789347 -345.281864) (xy 68.81201 -345.331485)
			(xy 68.82738 -345.383827) (xy 68.835144 -345.437824) (xy 68.835144 -345.492369) (xy 70.317847 -345.492369)
			(xy 70.317847 -345.437831) (xy 70.325609 -345.383849) (xy 70.340975 -345.331521) (xy 70.363631 -345.281912)
			(xy 70.393117 -345.236033) (xy 70.428833 -345.194817) (xy 70.470051 -345.159104) (xy 70.515932 -345.129621)
			(xy 70.565541 -345.106967) (xy 70.617871 -345.091605) (xy 70.671853 -345.083846) (xy 70.699122 -345.083384)
			(xy 71.562722 -345.083384) (xy 71.589994 -345.08378) (xy 71.643981 -345.091545) (xy 71.696315 -345.106914)
			(xy 71.745928 -345.129574) (xy 71.791812 -345.159064) (xy 71.833032 -345.194784) (xy 71.868749 -345.236006)
			(xy 71.898236 -345.281891) (xy 71.920893 -345.331506) (xy 71.936259 -345.38384) (xy 71.944022 -345.437828)
			(xy 71.944022 -345.492365) (xy 73.42687 -345.492365) (xy 73.42687 -345.437835) (xy 73.434631 -345.383859)
			(xy 73.449993 -345.331537) (xy 73.472645 -345.281934) (xy 73.502126 -345.23606) (xy 73.537835 -345.194848)
			(xy 73.579045 -345.159137) (xy 73.624919 -345.129654) (xy 73.674521 -345.106999) (xy 73.726842 -345.091634)
			(xy 73.780817 -345.083872) (xy 73.808082 -345.083384) (xy 74.671682 -345.083384) (xy 74.698957 -345.083754)
			(xy 74.752952 -345.091515) (xy 74.805294 -345.106882) (xy 74.854915 -345.129541) (xy 74.900806 -345.159032)
			(xy 74.942034 -345.194754) (xy 74.977757 -345.235979) (xy 75.00725 -345.281869) (xy 75.029912 -345.33149)
			(xy 75.045281 -345.38383) (xy 75.053044 -345.437825) (xy 75.053044 -345.49237) (xy 76.535748 -345.49237)
			(xy 76.535748 -345.43783) (xy 76.54351 -345.383846) (xy 76.558876 -345.331517) (xy 76.581534 -345.281907)
			(xy 76.611022 -345.236026) (xy 76.64674 -345.19481) (xy 76.68796 -345.159097) (xy 76.733844 -345.129614)
			(xy 76.783456 -345.106962) (xy 76.835787 -345.091601) (xy 76.889772 -345.083845) (xy 76.917042 -345.083384)
			(xy 77.780642 -345.083384) (xy 77.807913 -345.083781) (xy 77.861898 -345.091549) (xy 77.914229 -345.10692)
			(xy 77.96384 -345.129581) (xy 78.009721 -345.159072) (xy 78.050939 -345.194791) (xy 78.086654 -345.236013)
			(xy 78.116139 -345.281897) (xy 78.138795 -345.33151) (xy 78.15416 -345.383843) (xy 78.161922 -345.437829)
			(xy 78.161922 -345.492368) (xy 79.644747 -345.492368) (xy 79.644747 -345.437832) (xy 79.652509 -345.383852)
			(xy 79.667873 -345.331525) (xy 79.690528 -345.281918) (xy 79.720012 -345.23604) (xy 79.755726 -345.194824)
			(xy 79.796941 -345.159111) (xy 79.84282 -345.129627) (xy 79.892427 -345.106972) (xy 79.944754 -345.091608)
			(xy 79.998734 -345.083847) (xy 80.026002 -345.083384) (xy 80.889602 -345.083384) (xy 80.916875 -345.083779)
			(xy 80.970864 -345.091542) (xy 81.0232 -345.106909) (xy 81.072816 -345.129568) (xy 81.118702 -345.159057)
			(xy 81.159924 -345.194777) (xy 81.195644 -345.236) (xy 81.225133 -345.281886) (xy 81.247792 -345.331502)
			(xy 81.263159 -345.383838) (xy 81.270921 -345.437827) (xy 81.270921 -345.492364) (xy 82.75377 -345.492364)
			(xy 82.75377 -345.437836) (xy 82.76153 -345.383862) (xy 82.776892 -345.331542) (xy 82.799542 -345.28194)
			(xy 82.829021 -345.236066) (xy 82.864728 -345.194855) (xy 82.905936 -345.159144) (xy 82.951807 -345.12966)
			(xy 83.001406 -345.107005) (xy 83.053725 -345.091638) (xy 83.107698 -345.083873) (xy 83.134962 -345.083384)
			(xy 83.998562 -345.083384) (xy 84.025838 -345.083753) (xy 84.079836 -345.091512) (xy 84.132179 -345.106877)
			(xy 84.181803 -345.129535) (xy 84.227697 -345.159025) (xy 84.268927 -345.194747) (xy 84.304652 -345.235973)
			(xy 84.334147 -345.281864) (xy 84.35681 -345.331485) (xy 84.37218 -345.383827) (xy 84.379944 -345.437824)
			(xy 84.379944 -345.492369) (xy 85.862647 -345.492369) (xy 85.862647 -345.437831) (xy 85.870409 -345.383849)
			(xy 85.885775 -345.331521) (xy 85.908431 -345.281912) (xy 85.937917 -345.236033) (xy 85.973633 -345.194817)
			(xy 86.014851 -345.159104) (xy 86.060732 -345.129621) (xy 86.110341 -345.106967) (xy 86.162671 -345.091605)
			(xy 86.216653 -345.083846) (xy 86.243922 -345.083384) (xy 87.107522 -345.083384) (xy 87.134794 -345.08378)
			(xy 87.188781 -345.091545) (xy 87.241115 -345.106914) (xy 87.290728 -345.129574) (xy 87.336612 -345.159064)
			(xy 87.377832 -345.194784) (xy 87.413549 -345.236006) (xy 87.443036 -345.281891) (xy 87.465693 -345.331506)
			(xy 87.481059 -345.38384) (xy 87.488822 -345.437828) (xy 87.488822 -345.492365) (xy 88.97167 -345.492365)
			(xy 88.97167 -345.437835) (xy 88.979431 -345.383859) (xy 88.994793 -345.331537) (xy 89.017445 -345.281934)
			(xy 89.046926 -345.23606) (xy 89.082635 -345.194848) (xy 89.123845 -345.159137) (xy 89.169719 -345.129654)
			(xy 89.219321 -345.106999) (xy 89.271642 -345.091634) (xy 89.325617 -345.083872) (xy 89.352882 -345.083384)
			(xy 90.216482 -345.083384) (xy 90.243757 -345.083754) (xy 90.297752 -345.091515) (xy 90.350094 -345.106882)
			(xy 90.399715 -345.129541) (xy 90.445606 -345.159032) (xy 90.486834 -345.194754) (xy 90.522557 -345.235979)
			(xy 90.55205 -345.281869) (xy 90.574712 -345.33149) (xy 90.590081 -345.38383) (xy 90.597844 -345.437825)
			(xy 90.597844 -345.49237) (xy 92.080548 -345.49237) (xy 92.080548 -345.43783) (xy 92.08831 -345.383846)
			(xy 92.103676 -345.331517) (xy 92.126334 -345.281907) (xy 92.155822 -345.236026) (xy 92.19154 -345.19481)
			(xy 92.23276 -345.159097) (xy 92.278644 -345.129614) (xy 92.328256 -345.106962) (xy 92.380587 -345.091601)
			(xy 92.434572 -345.083845) (xy 92.461842 -345.083384) (xy 93.325442 -345.083384) (xy 93.352713 -345.083781)
			(xy 93.406698 -345.091549) (xy 93.459029 -345.10692) (xy 93.50864 -345.129581) (xy 93.554521 -345.159072)
			(xy 93.595739 -345.194791) (xy 93.625314 -345.228926) (xy 105.613452 -345.228926) (xy 105.617523 -345.173304)
			(xy 105.629649 -345.118867) (xy 105.649572 -345.066776) (xy 105.676868 -345.018141) (xy 105.710954 -344.973998)
			(xy 105.751103 -344.935289) (xy 105.796461 -344.902838) (xy 105.846061 -344.877337) (xy 105.898845 -344.85933)
			(xy 105.953688 -344.8492) (xy 106.009422 -344.847163) (xy 106.064859 -344.853263) (xy 106.118816 -344.867369)
			(xy 106.170145 -344.889181) (xy 106.217751 -344.918235) (xy 106.260619 -344.95391) (xy 106.297836 -344.995447)
			(xy 106.328609 -345.04196) (xy 106.352281 -345.092457) (xy 106.368349 -345.145864) (xy 106.376469 -345.20104)
			(xy 106.376978 -345.228926) (xy 106.376469 -345.256812) (xy 106.368349 -345.311988) (xy 106.352281 -345.365395)
			(xy 106.328609 -345.415892) (xy 106.297836 -345.462405) (xy 106.260619 -345.503942) (xy 106.217751 -345.539617)
			(xy 106.170145 -345.568671) (xy 106.118816 -345.590483) (xy 106.064859 -345.604589) (xy 106.009422 -345.610689)
			(xy 105.953688 -345.608652) (xy 105.898845 -345.598522) (xy 105.846061 -345.580515) (xy 105.796461 -345.555014)
			(xy 105.751103 -345.522563) (xy 105.710954 -345.483854) (xy 105.676868 -345.439711) (xy 105.649572 -345.391076)
			(xy 105.629649 -345.338985) (xy 105.617523 -345.284548) (xy 105.613452 -345.228926) (xy 93.625314 -345.228926)
			(xy 93.631454 -345.236013) (xy 93.660939 -345.281897) (xy 93.683595 -345.33151) (xy 93.69896 -345.383843)
			(xy 93.706722 -345.437829) (xy 93.706722 -345.492371) (xy 93.69896 -345.546357) (xy 93.683595 -345.59869)
			(xy 93.660939 -345.648303) (xy 93.631454 -345.694187) (xy 93.595739 -345.735409) (xy 93.554521 -345.771128)
			(xy 93.50864 -345.800619) (xy 93.459029 -345.82328) (xy 93.406698 -345.838651) (xy 93.352713 -345.846419)
			(xy 93.325442 -345.846908) (xy 92.461842 -345.846908) (xy 92.434572 -345.846355) (xy 92.380587 -345.838599)
			(xy 92.328256 -345.823238) (xy 92.278643 -345.800586) (xy 92.23276 -345.771103) (xy 92.19154 -345.73539)
			(xy 92.155822 -345.694174) (xy 92.126334 -345.648293) (xy 92.103676 -345.598683) (xy 92.08831 -345.546354)
			(xy 92.080548 -345.49237) (xy 90.597844 -345.49237) (xy 90.597844 -345.492375) (xy 90.590081 -345.54637)
			(xy 90.574712 -345.59871) (xy 90.55205 -345.648331) (xy 90.522557 -345.694221) (xy 90.486834 -345.735446)
			(xy 90.445606 -345.771168) (xy 90.399715 -345.800659) (xy 90.350094 -345.823318) (xy 90.297752 -345.838685)
			(xy 90.243757 -345.846446) (xy 90.216482 -345.846908) (xy 89.352882 -345.846908) (xy 89.325617 -345.846328)
			(xy 89.271642 -345.838566) (xy 89.219321 -345.823201) (xy 89.169719 -345.800546) (xy 89.123845 -345.771063)
			(xy 89.082635 -345.735352) (xy 89.046926 -345.69414) (xy 89.017445 -345.648266) (xy 88.994793 -345.598663)
			(xy 88.979431 -345.546341) (xy 88.97167 -345.492365) (xy 87.488822 -345.492365) (xy 87.488822 -345.492372)
			(xy 87.481059 -345.54636) (xy 87.465693 -345.598694) (xy 87.443036 -345.648309) (xy 87.413549 -345.694194)
			(xy 87.377832 -345.735416) (xy 87.336612 -345.771136) (xy 87.290728 -345.800626) (xy 87.241115 -345.823286)
			(xy 87.188781 -345.838655) (xy 87.134794 -345.84642) (xy 87.107522 -345.846908) (xy 86.243922 -345.846908)
			(xy 86.216653 -345.846354) (xy 86.16267 -345.838595) (xy 86.110341 -345.823233) (xy 86.060732 -345.800579)
			(xy 86.014851 -345.771096) (xy 85.973633 -345.735383) (xy 85.937917 -345.694167) (xy 85.908431 -345.648288)
			(xy 85.885775 -345.598679) (xy 85.870409 -345.546351) (xy 85.862647 -345.492369) (xy 84.379944 -345.492369)
			(xy 84.379944 -345.492376) (xy 84.37218 -345.546373) (xy 84.35681 -345.598715) (xy 84.334147 -345.648336)
			(xy 84.304652 -345.694227) (xy 84.268927 -345.735453) (xy 84.227697 -345.771175) (xy 84.181803 -345.800665)
			(xy 84.132179 -345.823323) (xy 84.079836 -345.838688) (xy 84.025838 -345.846447) (xy 83.998562 -345.846908)
			(xy 83.134962 -345.846908) (xy 83.107698 -345.846327) (xy 83.053725 -345.838562) (xy 83.001406 -345.823195)
			(xy 82.951807 -345.80054) (xy 82.905936 -345.771056) (xy 82.864728 -345.735345) (xy 82.829021 -345.694134)
			(xy 82.799542 -345.64826) (xy 82.776892 -345.598658) (xy 82.76153 -345.546338) (xy 82.75377 -345.492364)
			(xy 81.270921 -345.492364) (xy 81.270921 -345.492373) (xy 81.263159 -345.546362) (xy 81.247792 -345.598698)
			(xy 81.225133 -345.648314) (xy 81.195644 -345.6942) (xy 81.159924 -345.735423) (xy 81.118702 -345.771143)
			(xy 81.072816 -345.800632) (xy 81.0232 -345.823291) (xy 80.970864 -345.838658) (xy 80.916875 -345.846421)
			(xy 80.889602 -345.846908) (xy 80.026002 -345.846908) (xy 79.998734 -345.846353) (xy 79.944754 -345.838592)
			(xy 79.892427 -345.823228) (xy 79.84282 -345.800573) (xy 79.796941 -345.771089) (xy 79.755726 -345.735376)
			(xy 79.720012 -345.69416) (xy 79.690528 -345.648282) (xy 79.667873 -345.598675) (xy 79.652509 -345.546348)
			(xy 79.644747 -345.492368) (xy 78.161922 -345.492368) (xy 78.161922 -345.492371) (xy 78.15416 -345.546357)
			(xy 78.138795 -345.59869) (xy 78.116139 -345.648303) (xy 78.086654 -345.694187) (xy 78.050939 -345.735409)
			(xy 78.009721 -345.771128) (xy 77.96384 -345.800619) (xy 77.914229 -345.82328) (xy 77.861898 -345.838651)
			(xy 77.807913 -345.846419) (xy 77.780642 -345.846908) (xy 76.917042 -345.846908) (xy 76.889772 -345.846355)
			(xy 76.835787 -345.838599) (xy 76.783456 -345.823238) (xy 76.733843 -345.800586) (xy 76.68796 -345.771103)
			(xy 76.64674 -345.73539) (xy 76.611022 -345.694174) (xy 76.581534 -345.648293) (xy 76.558876 -345.598683)
			(xy 76.54351 -345.546354) (xy 76.535748 -345.49237) (xy 75.053044 -345.49237) (xy 75.053044 -345.492375)
			(xy 75.045281 -345.54637) (xy 75.029912 -345.59871) (xy 75.00725 -345.648331) (xy 74.977757 -345.694221)
			(xy 74.942034 -345.735446) (xy 74.900806 -345.771168) (xy 74.854915 -345.800659) (xy 74.805294 -345.823318)
			(xy 74.752952 -345.838685) (xy 74.698957 -345.846446) (xy 74.671682 -345.846908) (xy 73.808082 -345.846908)
			(xy 73.780817 -345.846328) (xy 73.726842 -345.838566) (xy 73.674521 -345.823201) (xy 73.624919 -345.800546)
			(xy 73.579045 -345.771063) (xy 73.537835 -345.735352) (xy 73.502126 -345.69414) (xy 73.472645 -345.648266)
			(xy 73.449993 -345.598663) (xy 73.434631 -345.546341) (xy 73.42687 -345.492365) (xy 71.944022 -345.492365)
			(xy 71.944022 -345.492372) (xy 71.936259 -345.54636) (xy 71.920893 -345.598694) (xy 71.898236 -345.648309)
			(xy 71.868749 -345.694194) (xy 71.833032 -345.735416) (xy 71.791812 -345.771136) (xy 71.745928 -345.800626)
			(xy 71.696315 -345.823286) (xy 71.643981 -345.838655) (xy 71.589994 -345.84642) (xy 71.562722 -345.846908)
			(xy 70.699122 -345.846908) (xy 70.671853 -345.846354) (xy 70.61787 -345.838595) (xy 70.565541 -345.823233)
			(xy 70.515932 -345.800579) (xy 70.470051 -345.771096) (xy 70.428833 -345.735383) (xy 70.393117 -345.694167)
			(xy 70.363631 -345.648288) (xy 70.340975 -345.598679) (xy 70.325609 -345.546351) (xy 70.317847 -345.492369)
			(xy 68.835144 -345.492369) (xy 68.835144 -345.492376) (xy 68.82738 -345.546373) (xy 68.81201 -345.598715)
			(xy 68.789347 -345.648336) (xy 68.759852 -345.694227) (xy 68.724127 -345.735453) (xy 68.682897 -345.771175)
			(xy 68.637003 -345.800665) (xy 68.587379 -345.823323) (xy 68.535036 -345.838688) (xy 68.481038 -345.846447)
			(xy 68.453762 -345.846908) (xy 67.590162 -345.846908) (xy 67.562898 -345.846327) (xy 67.508925 -345.838562)
			(xy 67.456606 -345.823195) (xy 67.407007 -345.80054) (xy 67.361136 -345.771056) (xy 67.319928 -345.735345)
			(xy 67.284221 -345.694134) (xy 67.254742 -345.64826) (xy 67.232092 -345.598658) (xy 67.21673 -345.546338)
			(xy 67.20897 -345.492364) (xy 65.726121 -345.492364) (xy 65.726121 -345.492373) (xy 65.718359 -345.546362)
			(xy 65.702992 -345.598698) (xy 65.680333 -345.648314) (xy 65.650844 -345.6942) (xy 65.615124 -345.735423)
			(xy 65.573902 -345.771143) (xy 65.528016 -345.800632) (xy 65.4784 -345.823291) (xy 65.426064 -345.838658)
			(xy 65.372075 -345.846421) (xy 65.344802 -345.846908) (xy 64.481202 -345.846908) (xy 64.453934 -345.846353)
			(xy 64.399954 -345.838592) (xy 64.347627 -345.823228) (xy 64.29802 -345.800573) (xy 64.252141 -345.771089)
			(xy 64.210926 -345.735376) (xy 64.175212 -345.69416) (xy 64.145728 -345.648282) (xy 64.123073 -345.598675)
			(xy 64.107709 -345.546348) (xy 64.099947 -345.492368) (xy 62.617029 -345.492368) (xy 62.60927 -345.546338)
			(xy 62.593909 -345.598657) (xy 62.571258 -345.648259) (xy 62.54178 -345.694132) (xy 62.506074 -345.735344)
			(xy 62.464866 -345.771055) (xy 62.418996 -345.800538) (xy 62.369397 -345.823194) (xy 62.317079 -345.838561)
			(xy 62.263106 -345.846327) (xy 62.235842 -345.846908) (xy 61.372242 -345.846908) (xy 61.342585 -345.846348)
			(xy 61.283986 -345.837172) (xy 61.227513 -345.819036) (xy 61.174529 -345.792377) (xy 61.126311 -345.757836)
			(xy 61.10478 -345.737434) (xy 61.08954 -345.722448) (xy 61.048138 -345.722702) (xy 60.187586 -346.583254)
			(xy 99.245418 -346.583254) (xy 99.249489 -346.527632) (xy 99.261615 -346.473195) (xy 99.281538 -346.421104)
			(xy 99.308834 -346.372469) (xy 99.34292 -346.328326) (xy 99.383069 -346.289617) (xy 99.428427 -346.257166)
			(xy 99.478027 -346.231665) (xy 99.530811 -346.213658) (xy 99.585654 -346.203528) (xy 99.641388 -346.201491)
			(xy 99.696825 -346.207591) (xy 99.750782 -346.221697) (xy 99.802111 -346.243509) (xy 99.849717 -346.272563)
			(xy 99.892585 -346.308238) (xy 99.929802 -346.349775) (xy 99.960575 -346.396288) (xy 99.984247 -346.446785)
			(xy 100.000315 -346.500192) (xy 100.008435 -346.555368) (xy 100.008944 -346.583254) (xy 100.008435 -346.61114)
			(xy 100.000315 -346.666316) (xy 99.984247 -346.719723) (xy 99.960575 -346.77022) (xy 99.929802 -346.816733)
			(xy 99.892585 -346.85827) (xy 99.849717 -346.893945) (xy 99.802111 -346.922999) (xy 99.750782 -346.944811)
			(xy 99.696825 -346.958917) (xy 99.641388 -346.965017) (xy 99.585654 -346.96298) (xy 99.530811 -346.95285)
			(xy 99.478027 -346.934843) (xy 99.428427 -346.909342) (xy 99.383069 -346.876891) (xy 99.34292 -346.838182)
			(xy 99.308834 -346.794039) (xy 99.281538 -346.745404) (xy 99.261615 -346.693313) (xy 99.249489 -346.638876)
			(xy 99.245418 -346.583254) (xy 60.187586 -346.583254) (xy 59.044078 -347.726762) (xy 59.040579 -347.730367)
			(xy 59.034941 -347.738681) (xy 59.032902 -347.743272) (xy 58.979219 -347.873066) (xy 99.245418 -347.873066)
			(xy 99.249489 -347.817444) (xy 99.261615 -347.763007) (xy 99.281538 -347.710916) (xy 99.308834 -347.662281)
			(xy 99.34292 -347.618138) (xy 99.383069 -347.579429) (xy 99.428427 -347.546978) (xy 99.478027 -347.521477)
			(xy 99.530811 -347.50347) (xy 99.585654 -347.49334) (xy 99.641388 -347.491303) (xy 99.696825 -347.497403)
			(xy 99.750782 -347.511509) (xy 99.802111 -347.533321) (xy 99.849717 -347.562375) (xy 99.892585 -347.59805)
			(xy 99.929802 -347.639587) (xy 99.960575 -347.6861) (xy 99.984247 -347.736597) (xy 100.000315 -347.790004)
			(xy 100.008435 -347.84518) (xy 100.008944 -347.873066) (xy 100.008435 -347.900952) (xy 100.000315 -347.956128)
			(xy 99.984247 -348.009535) (xy 99.960575 -348.060032) (xy 99.929802 -348.106545) (xy 99.892585 -348.148082)
			(xy 99.849717 -348.183757) (xy 99.802111 -348.212811) (xy 99.750782 -348.234623) (xy 99.696825 -348.248729)
			(xy 99.641388 -348.254829) (xy 99.585654 -348.252792) (xy 99.530811 -348.242662) (xy 99.478027 -348.224655)
			(xy 99.428427 -348.199154) (xy 99.383069 -348.166703) (xy 99.34292 -348.127994) (xy 99.308834 -348.083851)
			(xy 99.281538 -348.035216) (xy 99.261615 -347.983125) (xy 99.249489 -347.928688) (xy 99.245418 -347.873066)
			(xy 58.979219 -347.873066) (xy 58.975752 -347.881448) (xy 58.973982 -347.886076) (xy 58.972072 -347.895798)
			(xy 58.971942 -347.900752) (xy 58.971942 -348.613074) (xy 60.990892 -348.613074) (xy 60.990892 -348.558526)
			(xy 60.998655 -348.504534) (xy 61.014024 -348.452197) (xy 61.036685 -348.40258) (xy 61.066177 -348.356693)
			(xy 61.1019 -348.315471) (xy 61.143127 -348.279752) (xy 61.189017 -348.250265) (xy 61.238636 -348.227609)
			(xy 61.290976 -348.212246) (xy 61.344968 -348.204489) (xy 61.372242 -348.204028) (xy 62.235842 -348.204028)
			(xy 62.263109 -348.204537) (xy 62.317086 -348.212304) (xy 62.369409 -348.227672) (xy 62.419013 -348.25033)
			(xy 62.464887 -348.279816) (xy 62.506099 -348.315531) (xy 62.541809 -348.356746) (xy 62.57129 -348.402624)
			(xy 62.593943 -348.45223) (xy 62.609305 -348.504555) (xy 62.617066 -348.558533) (xy 62.617066 -348.613067)
			(xy 62.617065 -348.613072) (xy 64.099892 -348.613072) (xy 64.099892 -348.558528) (xy 64.107654 -348.50454)
			(xy 64.123021 -348.452206) (xy 64.145679 -348.402591) (xy 64.175168 -348.356706) (xy 64.210886 -348.315485)
			(xy 64.252108 -348.279766) (xy 64.297993 -348.250278) (xy 64.347607 -348.22762) (xy 64.399942 -348.212253)
			(xy 64.45393 -348.204491) (xy 64.481202 -348.204028) (xy 65.344802 -348.204028) (xy 65.372071 -348.204535)
			(xy 65.426053 -348.212296) (xy 65.47838 -348.227661) (xy 65.527989 -348.250317) (xy 65.573869 -348.279802)
			(xy 65.615085 -348.315517) (xy 65.650799 -348.356733) (xy 65.680284 -348.402613) (xy 65.702939 -348.452221)
			(xy 65.718304 -348.504549) (xy 65.726066 -348.558531) (xy 65.726066 -348.613068) (xy 67.208914 -348.613068)
			(xy 67.208914 -348.558532) (xy 67.216675 -348.50455) (xy 67.232039 -348.452222) (xy 67.254693 -348.402613)
			(xy 67.284176 -348.356733) (xy 67.319888 -348.315515) (xy 67.361102 -348.279799) (xy 67.40698 -348.250311)
			(xy 67.456586 -348.227652) (xy 67.508913 -348.212283) (xy 67.562894 -348.204517) (xy 67.590162 -348.204028)
			(xy 68.453762 -348.204028) (xy 68.481034 -348.204509) (xy 68.535024 -348.212266) (xy 68.58736 -348.227629)
			(xy 68.636976 -348.250284) (xy 68.682863 -348.27977) (xy 68.724087 -348.315486) (xy 68.759808 -348.356706)
			(xy 68.789298 -348.40259) (xy 68.811958 -348.452205) (xy 68.827326 -348.504539) (xy 68.835088 -348.558528)
			(xy 68.835088 -348.613072) (xy 68.835088 -348.613073) (xy 70.317792 -348.613073) (xy 70.317792 -348.558527)
			(xy 70.325554 -348.504537) (xy 70.340922 -348.452201) (xy 70.363582 -348.402585) (xy 70.393072 -348.356699)
			(xy 70.428793 -348.315478) (xy 70.470017 -348.279759) (xy 70.515905 -348.250271) (xy 70.565522 -348.227615)
			(xy 70.617859 -348.21225) (xy 70.671849 -348.20449) (xy 70.699122 -348.204028) (xy 71.562722 -348.204028)
			(xy 71.58999 -348.204536) (xy 71.643969 -348.2123) (xy 71.696295 -348.227667) (xy 71.745901 -348.250324)
			(xy 71.791778 -348.279809) (xy 71.832992 -348.315524) (xy 71.868704 -348.35674) (xy 71.898187 -348.402618)
			(xy 71.920841 -348.452226) (xy 71.936205 -348.504552) (xy 71.943966 -348.558532) (xy 71.943966 -348.613068)
			(xy 71.943966 -348.613069) (xy 73.426814 -348.613069) (xy 73.426814 -348.558531) (xy 73.434576 -348.504547)
			(xy 73.449941 -348.452218) (xy 73.472596 -348.402608) (xy 73.502081 -348.356726) (xy 73.537795 -348.315508)
			(xy 73.579012 -348.279792) (xy 73.624892 -348.250305) (xy 73.674501 -348.227647) (xy 73.72683 -348.21228)
			(xy 73.780813 -348.204516) (xy 73.808082 -348.204028) (xy 74.671682 -348.204028) (xy 74.698953 -348.20451)
			(xy 74.752941 -348.21227) (xy 74.805274 -348.227634) (xy 74.854888 -348.25029) (xy 74.900773 -348.279777)
			(xy 74.941994 -348.315493) (xy 74.977712 -348.356713) (xy 75.007201 -348.402596) (xy 75.029859 -348.452209)
			(xy 75.045226 -348.504542) (xy 75.052988 -348.558529) (xy 75.052988 -348.613071) (xy 75.052988 -348.613074)
			(xy 76.535692 -348.613074) (xy 76.535692 -348.558526) (xy 76.543455 -348.504534) (xy 76.558824 -348.452197)
			(xy 76.581485 -348.40258) (xy 76.610977 -348.356693) (xy 76.6467 -348.315471) (xy 76.687927 -348.279752)
			(xy 76.733817 -348.250265) (xy 76.783436 -348.227609) (xy 76.835776 -348.212246) (xy 76.889768 -348.204489)
			(xy 76.917042 -348.204028) (xy 77.780642 -348.204028) (xy 77.807909 -348.204537) (xy 77.861886 -348.212304)
			(xy 77.914209 -348.227672) (xy 77.963813 -348.25033) (xy 78.009687 -348.279816) (xy 78.050899 -348.315531)
			(xy 78.086609 -348.356746) (xy 78.11609 -348.402624) (xy 78.138743 -348.45223) (xy 78.154105 -348.504555)
			(xy 78.161866 -348.558533) (xy 78.161866 -348.613067) (xy 78.161865 -348.613072) (xy 79.644692 -348.613072)
			(xy 79.644692 -348.558528) (xy 79.652454 -348.50454) (xy 79.667821 -348.452206) (xy 79.690479 -348.402591)
			(xy 79.719968 -348.356706) (xy 79.755686 -348.315485) (xy 79.796908 -348.279766) (xy 79.842793 -348.250278)
			(xy 79.892407 -348.22762) (xy 79.944742 -348.212253) (xy 79.99873 -348.204491) (xy 80.026002 -348.204028)
			(xy 80.889602 -348.204028) (xy 80.916871 -348.204535) (xy 80.970853 -348.212296) (xy 81.02318 -348.227661)
			(xy 81.072789 -348.250317) (xy 81.118669 -348.279802) (xy 81.159885 -348.315517) (xy 81.195599 -348.356733)
			(xy 81.225084 -348.402613) (xy 81.247739 -348.452221) (xy 81.263104 -348.504549) (xy 81.270866 -348.558531)
			(xy 81.270866 -348.613068) (xy 82.753714 -348.613068) (xy 82.753714 -348.558532) (xy 82.761475 -348.50455)
			(xy 82.776839 -348.452222) (xy 82.799493 -348.402613) (xy 82.828976 -348.356733) (xy 82.864688 -348.315515)
			(xy 82.905902 -348.279799) (xy 82.95178 -348.250311) (xy 83.001386 -348.227652) (xy 83.053713 -348.212283)
			(xy 83.107694 -348.204517) (xy 83.134962 -348.204028) (xy 83.998562 -348.204028) (xy 84.025834 -348.204509)
			(xy 84.079824 -348.212266) (xy 84.13216 -348.227629) (xy 84.181776 -348.250284) (xy 84.227663 -348.27977)
			(xy 84.268887 -348.315486) (xy 84.304608 -348.356706) (xy 84.334098 -348.40259) (xy 84.356758 -348.452205)
			(xy 84.372126 -348.504539) (xy 84.379888 -348.558528) (xy 84.379888 -348.613072) (xy 84.379888 -348.613073)
			(xy 85.862592 -348.613073) (xy 85.862592 -348.558527) (xy 85.870354 -348.504537) (xy 85.885722 -348.452201)
			(xy 85.908382 -348.402585) (xy 85.937872 -348.356699) (xy 85.973593 -348.315478) (xy 86.014817 -348.279759)
			(xy 86.060705 -348.250271) (xy 86.110322 -348.227615) (xy 86.162659 -348.21225) (xy 86.216649 -348.20449)
			(xy 86.243922 -348.204028) (xy 87.107522 -348.204028) (xy 87.13479 -348.204536) (xy 87.188769 -348.2123)
			(xy 87.241095 -348.227667) (xy 87.290701 -348.250324) (xy 87.336578 -348.279809) (xy 87.377792 -348.315524)
			(xy 87.413504 -348.35674) (xy 87.442987 -348.402618) (xy 87.465641 -348.452226) (xy 87.481005 -348.504552)
			(xy 87.488766 -348.558532) (xy 87.488766 -348.613068) (xy 87.488766 -348.613069) (xy 88.971614 -348.613069)
			(xy 88.971614 -348.558531) (xy 88.979376 -348.504547) (xy 88.994741 -348.452218) (xy 89.017396 -348.402608)
			(xy 89.046881 -348.356726) (xy 89.082595 -348.315508) (xy 89.123812 -348.279792) (xy 89.169692 -348.250305)
			(xy 89.219301 -348.227647) (xy 89.27163 -348.21228) (xy 89.325613 -348.204516) (xy 89.352882 -348.204028)
			(xy 90.216482 -348.204028) (xy 90.243753 -348.20451) (xy 90.297741 -348.21227) (xy 90.350074 -348.227634)
			(xy 90.399688 -348.25029) (xy 90.445573 -348.279777) (xy 90.486794 -348.315493) (xy 90.522512 -348.356713)
			(xy 90.552001 -348.402596) (xy 90.574659 -348.452209) (xy 90.590026 -348.504542) (xy 90.597788 -348.558529)
			(xy 90.597788 -348.613071) (xy 90.597788 -348.613074) (xy 92.080492 -348.613074) (xy 92.080492 -348.558526)
			(xy 92.088255 -348.504534) (xy 92.103624 -348.452197) (xy 92.126285 -348.40258) (xy 92.155777 -348.356693)
			(xy 92.1915 -348.315471) (xy 92.232727 -348.279752) (xy 92.278617 -348.250265) (xy 92.328236 -348.227609)
			(xy 92.380576 -348.212246) (xy 92.434568 -348.204489) (xy 92.461842 -348.204028) (xy 93.325442 -348.204028)
			(xy 93.352709 -348.204537) (xy 93.406686 -348.212304) (xy 93.459009 -348.227672) (xy 93.508613 -348.25033)
			(xy 93.554487 -348.279816) (xy 93.595699 -348.315531) (xy 93.631409 -348.356746) (xy 93.66089 -348.402624)
			(xy 93.662683 -348.406551) (xy 105.290366 -348.406551) (xy 105.290366 -348.352049) (xy 105.298122 -348.298103)
			(xy 105.313475 -348.245809) (xy 105.336115 -348.196233) (xy 105.365579 -348.150383) (xy 105.401268 -348.109192)
			(xy 105.442455 -348.073499) (xy 105.488303 -348.044031) (xy 105.537877 -348.021387) (xy 105.59017 -348.006029)
			(xy 105.644115 -347.998268) (xy 105.671366 -347.99778) (xy 105.700106 -347.998269) (xy 105.756935 -348.006901)
			(xy 105.811826 -348.023959) (xy 105.863537 -348.049058) (xy 105.910898 -348.08163) (xy 105.932224 -348.100904)
			(xy 105.939336 -348.107508) (xy 105.956862 -348.11462) (xy 106.045254 -348.115128) (xy 106.06278 -348.10827)
			(xy 106.070146 -348.10192) (xy 106.091316 -348.083296) (xy 106.138126 -348.051863) (xy 106.189051 -348.027659)
			(xy 106.242983 -348.011211) (xy 106.298748 -348.002877) (xy 106.32694 -348.002352) (xy 106.354186 -348.002921)
			(xy 106.408124 -348.010681) (xy 106.460409 -348.026038) (xy 106.509976 -348.048679) (xy 106.555816 -348.078143)
			(xy 106.596997 -348.113831) (xy 106.632681 -348.155016) (xy 106.66214 -348.20086) (xy 106.684776 -348.250429)
			(xy 106.700127 -348.302715) (xy 106.707882 -348.356653) (xy 106.707882 -348.411147) (xy 106.700127 -348.465085)
			(xy 106.684776 -348.517371) (xy 106.66214 -348.56694) (xy 106.632681 -348.612784) (xy 106.596997 -348.653969)
			(xy 106.555816 -348.689657) (xy 106.509976 -348.719121) (xy 106.460409 -348.741762) (xy 106.408124 -348.757119)
			(xy 106.354186 -348.764879) (xy 106.32694 -348.765368) (xy 106.298201 -348.764863) (xy 106.241373 -348.756233)
			(xy 106.186483 -348.739177) (xy 106.134772 -348.714082) (xy 106.087409 -348.681515) (xy 106.066082 -348.662244)
			(xy 106.05897 -348.65564) (xy 106.041444 -348.648528) (xy 105.953052 -348.64802) (xy 105.935526 -348.654878)
			(xy 105.92816 -348.661228) (xy 105.906994 -348.679857) (xy 105.860182 -348.711288) (xy 105.809256 -348.73549)
			(xy 105.755323 -348.751936) (xy 105.699558 -348.76027) (xy 105.671366 -348.760796) (xy 105.644115 -348.760332)
			(xy 105.59017 -348.752571) (xy 105.537877 -348.737213) (xy 105.488303 -348.714569) (xy 105.442455 -348.685101)
			(xy 105.401268 -348.649408) (xy 105.365579 -348.608217) (xy 105.336115 -348.562367) (xy 105.313475 -348.512791)
			(xy 105.298122 -348.460497) (xy 105.290366 -348.406551) (xy 93.662683 -348.406551) (xy 93.683543 -348.45223)
			(xy 93.698905 -348.504555) (xy 93.706666 -348.558533) (xy 93.706666 -348.613067) (xy 93.698905 -348.667045)
			(xy 93.683543 -348.71937) (xy 93.66089 -348.768976) (xy 93.631409 -348.814854) (xy 93.595699 -348.856069)
			(xy 93.554487 -348.891784) (xy 93.508613 -348.92127) (xy 93.459009 -348.943928) (xy 93.406686 -348.959296)
			(xy 93.352709 -348.967063) (xy 93.325442 -348.967552) (xy 92.461842 -348.967552) (xy 92.434568 -348.967111)
			(xy 92.380576 -348.959354) (xy 92.328236 -348.943991) (xy 92.278617 -348.921335) (xy 92.232727 -348.891848)
			(xy 92.1915 -348.856129) (xy 92.155777 -348.814907) (xy 92.126285 -348.76902) (xy 92.103624 -348.719403)
			(xy 92.088255 -348.667066) (xy 92.080492 -348.613074) (xy 90.597788 -348.613074) (xy 90.590026 -348.667058)
			(xy 90.574659 -348.719391) (xy 90.552001 -348.769004) (xy 90.522512 -348.814887) (xy 90.486794 -348.856107)
			(xy 90.445573 -348.891823) (xy 90.399688 -348.92131) (xy 90.350074 -348.943966) (xy 90.297741 -348.95933)
			(xy 90.243753 -348.96709) (xy 90.216482 -348.967552) (xy 89.352882 -348.967552) (xy 89.325613 -348.967084)
			(xy 89.27163 -348.95932) (xy 89.219301 -348.943953) (xy 89.169692 -348.921295) (xy 89.123812 -348.891808)
			(xy 89.082595 -348.856092) (xy 89.046881 -348.814874) (xy 89.017396 -348.768992) (xy 88.994741 -348.719382)
			(xy 88.979376 -348.667053) (xy 88.971614 -348.613069) (xy 87.488766 -348.613069) (xy 87.481005 -348.667048)
			(xy 87.465641 -348.719374) (xy 87.442987 -348.768982) (xy 87.413504 -348.81486) (xy 87.377792 -348.856076)
			(xy 87.336578 -348.891791) (xy 87.290701 -348.921276) (xy 87.241095 -348.943933) (xy 87.188769 -348.9593)
			(xy 87.13479 -348.967064) (xy 87.107522 -348.967552) (xy 86.243922 -348.967552) (xy 86.216649 -348.96711)
			(xy 86.162659 -348.95935) (xy 86.110322 -348.943985) (xy 86.060705 -348.921329) (xy 86.014817 -348.891841)
			(xy 85.973593 -348.856122) (xy 85.937872 -348.814901) (xy 85.908382 -348.769015) (xy 85.885722 -348.719399)
			(xy 85.870354 -348.667063) (xy 85.862592 -348.613073) (xy 84.379888 -348.613073) (xy 84.372126 -348.667061)
			(xy 84.356758 -348.719395) (xy 84.334098 -348.76901) (xy 84.304608 -348.814894) (xy 84.268887 -348.856114)
			(xy 84.227663 -348.89183) (xy 84.181776 -348.921316) (xy 84.13216 -348.943971) (xy 84.079824 -348.959334)
			(xy 84.025834 -348.967091) (xy 83.998562 -348.967552) (xy 83.134962 -348.967552) (xy 83.107694 -348.967083)
			(xy 83.053713 -348.959317) (xy 83.001386 -348.943948) (xy 82.95178 -348.921289) (xy 82.905902 -348.891801)
			(xy 82.864688 -348.856085) (xy 82.828976 -348.814867) (xy 82.799493 -348.768987) (xy 82.776839 -348.719378)
			(xy 82.761475 -348.66705) (xy 82.753714 -348.613068) (xy 81.270866 -348.613068) (xy 81.270866 -348.613069)
			(xy 81.263104 -348.667051) (xy 81.247739 -348.719379) (xy 81.225084 -348.768987) (xy 81.195599 -348.814867)
			(xy 81.159885 -348.856083) (xy 81.118669 -348.891798) (xy 81.072789 -348.921283) (xy 81.02318 -348.943939)
			(xy 80.970853 -348.959304) (xy 80.916871 -348.967065) (xy 80.889602 -348.967552) (xy 80.026002 -348.967552)
			(xy 79.99873 -348.967109) (xy 79.944742 -348.959347) (xy 79.892407 -348.94398) (xy 79.842793 -348.921322)
			(xy 79.796908 -348.891834) (xy 79.755686 -348.856115) (xy 79.719968 -348.814894) (xy 79.690479 -348.769009)
			(xy 79.667821 -348.719394) (xy 79.652454 -348.66706) (xy 79.644692 -348.613072) (xy 78.161865 -348.613072)
			(xy 78.154105 -348.667045) (xy 78.138743 -348.71937) (xy 78.11609 -348.768976) (xy 78.086609 -348.814854)
			(xy 78.050899 -348.856069) (xy 78.009687 -348.891784) (xy 77.963813 -348.92127) (xy 77.914209 -348.943928)
			(xy 77.861886 -348.959296) (xy 77.807909 -348.967063) (xy 77.780642 -348.967552) (xy 76.917042 -348.967552)
			(xy 76.889768 -348.967111) (xy 76.835776 -348.959354) (xy 76.783436 -348.943991) (xy 76.733817 -348.921335)
			(xy 76.687927 -348.891848) (xy 76.6467 -348.856129) (xy 76.610977 -348.814907) (xy 76.581485 -348.76902)
			(xy 76.558824 -348.719403) (xy 76.543455 -348.667066) (xy 76.535692 -348.613074) (xy 75.052988 -348.613074)
			(xy 75.045226 -348.667058) (xy 75.029859 -348.719391) (xy 75.007201 -348.769004) (xy 74.977712 -348.814887)
			(xy 74.941994 -348.856107) (xy 74.900773 -348.891823) (xy 74.854888 -348.92131) (xy 74.805274 -348.943966)
			(xy 74.752941 -348.95933) (xy 74.698953 -348.96709) (xy 74.671682 -348.967552) (xy 73.808082 -348.967552)
			(xy 73.780813 -348.967084) (xy 73.72683 -348.95932) (xy 73.674501 -348.943953) (xy 73.624892 -348.921295)
			(xy 73.579012 -348.891808) (xy 73.537795 -348.856092) (xy 73.502081 -348.814874) (xy 73.472596 -348.768992)
			(xy 73.449941 -348.719382) (xy 73.434576 -348.667053) (xy 73.426814 -348.613069) (xy 71.943966 -348.613069)
			(xy 71.936205 -348.667048) (xy 71.920841 -348.719374) (xy 71.898187 -348.768982) (xy 71.868704 -348.81486)
			(xy 71.832992 -348.856076) (xy 71.791778 -348.891791) (xy 71.745901 -348.921276) (xy 71.696295 -348.943933)
			(xy 71.643969 -348.9593) (xy 71.58999 -348.967064) (xy 71.562722 -348.967552) (xy 70.699122 -348.967552)
			(xy 70.671849 -348.96711) (xy 70.617859 -348.95935) (xy 70.565522 -348.943985) (xy 70.515905 -348.921329)
			(xy 70.470017 -348.891841) (xy 70.428793 -348.856122) (xy 70.393072 -348.814901) (xy 70.363582 -348.769015)
			(xy 70.340922 -348.719399) (xy 70.325554 -348.667063) (xy 70.317792 -348.613073) (xy 68.835088 -348.613073)
			(xy 68.827326 -348.667061) (xy 68.811958 -348.719395) (xy 68.789298 -348.76901) (xy 68.759808 -348.814894)
			(xy 68.724087 -348.856114) (xy 68.682863 -348.89183) (xy 68.636976 -348.921316) (xy 68.58736 -348.943971)
			(xy 68.535024 -348.959334) (xy 68.481034 -348.967091) (xy 68.453762 -348.967552) (xy 67.590162 -348.967552)
			(xy 67.562894 -348.967083) (xy 67.508913 -348.959317) (xy 67.456586 -348.943948) (xy 67.40698 -348.921289)
			(xy 67.361102 -348.891801) (xy 67.319888 -348.856085) (xy 67.284176 -348.814867) (xy 67.254693 -348.768987)
			(xy 67.232039 -348.719378) (xy 67.216675 -348.66705) (xy 67.208914 -348.613068) (xy 65.726066 -348.613068)
			(xy 65.726066 -348.613069) (xy 65.718304 -348.667051) (xy 65.702939 -348.719379) (xy 65.680284 -348.768987)
			(xy 65.650799 -348.814867) (xy 65.615085 -348.856083) (xy 65.573869 -348.891798) (xy 65.527989 -348.921283)
			(xy 65.47838 -348.943939) (xy 65.426053 -348.959304) (xy 65.372071 -348.967065) (xy 65.344802 -348.967552)
			(xy 64.481202 -348.967552) (xy 64.45393 -348.967109) (xy 64.399942 -348.959347) (xy 64.347607 -348.94398)
			(xy 64.297993 -348.921322) (xy 64.252108 -348.891834) (xy 64.210886 -348.856115) (xy 64.175168 -348.814894)
			(xy 64.145679 -348.769009) (xy 64.123021 -348.719394) (xy 64.107654 -348.66706) (xy 64.099892 -348.613072)
			(xy 62.617065 -348.613072) (xy 62.609305 -348.667045) (xy 62.593943 -348.71937) (xy 62.57129 -348.768976)
			(xy 62.541809 -348.814854) (xy 62.506099 -348.856069) (xy 62.464887 -348.891784) (xy 62.419013 -348.92127)
			(xy 62.369409 -348.943928) (xy 62.317086 -348.959296) (xy 62.263109 -348.967063) (xy 62.235842 -348.967552)
			(xy 61.372242 -348.967552) (xy 61.344968 -348.967111) (xy 61.290976 -348.959354) (xy 61.238636 -348.943991)
			(xy 61.189017 -348.921335) (xy 61.143127 -348.891848) (xy 61.1019 -348.856129) (xy 61.066177 -348.814907)
			(xy 61.036685 -348.76902) (xy 61.014024 -348.719403) (xy 60.998655 -348.667066) (xy 60.990892 -348.613074)
			(xy 58.971942 -348.613074) (xy 58.971942 -351.63867) (xy 60.99094 -351.63867) (xy 60.99094 -351.58413)
			(xy 60.998702 -351.530145) (xy 61.014069 -351.477814) (xy 61.036727 -351.428203) (xy 61.066216 -351.382322)
			(xy 61.101934 -351.341105) (xy 61.143155 -351.305391) (xy 61.18904 -351.275907) (xy 61.238653 -351.253254)
			(xy 61.290986 -351.237893) (xy 61.344972 -351.230137) (xy 61.372242 -351.229676) (xy 62.235842 -351.229676)
			(xy 62.263112 -351.230089) (xy 62.317097 -351.237857) (xy 62.369426 -351.253227) (xy 62.419036 -351.275888)
			(xy 62.464916 -351.305378) (xy 62.506133 -351.341097) (xy 62.541847 -351.382317) (xy 62.571332 -351.428201)
			(xy 62.593988 -351.477813) (xy 62.609352 -351.530145) (xy 62.617114 -351.58413) (xy 62.617114 -351.638668)
			(xy 64.099939 -351.638668) (xy 64.099939 -351.584132) (xy 64.107701 -351.53015) (xy 64.123066 -351.477822)
			(xy 64.145721 -351.428214) (xy 64.175206 -351.382335) (xy 64.21092 -351.341119) (xy 64.252136 -351.305405)
			(xy 64.298016 -351.27592) (xy 64.347624 -351.253265) (xy 64.399952 -351.2379) (xy 64.453934 -351.230139)
			(xy 64.481202 -351.229676) (xy 65.344802 -351.229676) (xy 65.372074 -351.230087) (xy 65.426063 -351.237849)
			(xy 65.478397 -351.253216) (xy 65.528012 -351.275875) (xy 65.573897 -351.305364) (xy 65.615119 -351.341083)
			(xy 65.650837 -351.382304) (xy 65.680326 -351.42819) (xy 65.702984 -351.477805) (xy 65.718351 -351.530139)
			(xy 65.726113 -351.584128) (xy 65.726113 -351.638665) (xy 67.208962 -351.638665) (xy 67.208962 -351.584135)
			(xy 67.216722 -351.53016) (xy 67.232084 -351.477839) (xy 67.254735 -351.428236) (xy 67.284215 -351.382362)
			(xy 67.319922 -351.341149) (xy 67.361131 -351.305437) (xy 67.407003 -351.275953) (xy 67.456603 -351.253297)
			(xy 67.508923 -351.23793) (xy 67.562897 -351.230165) (xy 67.590162 -351.229676) (xy 68.453762 -351.229676)
			(xy 68.481037 -351.230061) (xy 68.535034 -351.23782) (xy 68.587376 -351.253184) (xy 68.636999 -351.275842)
			(xy 68.682892 -351.305331) (xy 68.724121 -351.341052) (xy 68.759846 -351.382277) (xy 68.78934 -351.428167)
			(xy 68.812003 -351.477788) (xy 68.827372 -351.530129) (xy 68.835136 -351.584125) (xy 68.835136 -351.638669)
			(xy 70.317839 -351.638669) (xy 70.317839 -351.584131) (xy 70.325601 -351.530147) (xy 70.340967 -351.477818)
			(xy 70.363624 -351.428208) (xy 70.393111 -351.382328) (xy 70.428827 -351.341112) (xy 70.470046 -351.305398)
			(xy 70.515928 -351.275914) (xy 70.565539 -351.25326) (xy 70.617869 -351.237897) (xy 70.671853 -351.230138)
			(xy 70.699122 -351.229676) (xy 71.562722 -351.229676) (xy 71.589993 -351.230088) (xy 71.64398 -351.237853)
			(xy 71.696312 -351.253222) (xy 71.745924 -351.275881) (xy 71.791807 -351.305371) (xy 71.833026 -351.34109)
			(xy 71.868742 -351.382311) (xy 71.898229 -351.428195) (xy 71.920886 -351.477809) (xy 71.936252 -351.530142)
			(xy 71.944014 -351.584129) (xy 71.944014 -351.638666) (xy 73.426862 -351.638666) (xy 73.426862 -351.584134)
			(xy 73.434623 -351.530158) (xy 73.449986 -351.477835) (xy 73.472638 -351.428231) (xy 73.50212 -351.382355)
			(xy 73.537829 -351.341142) (xy 73.579041 -351.30543) (xy 73.624915 -351.275947) (xy 73.674518 -351.253292)
			(xy 73.72684 -351.237927) (xy 73.780816 -351.230164) (xy 73.808082 -351.229676) (xy 74.671682 -351.229676)
			(xy 74.698957 -351.230062) (xy 74.752951 -351.237823) (xy 74.805291 -351.253189) (xy 74.854911 -351.275848)
			(xy 74.900802 -351.305338) (xy 74.942028 -351.341059) (xy 74.977751 -351.382284) (xy 75.007243 -351.428173)
			(xy 75.029904 -351.477792) (xy 75.045273 -351.530132) (xy 75.053036 -351.584125) (xy 75.053036 -351.63867)
			(xy 76.53574 -351.63867) (xy 76.53574 -351.58413) (xy 76.543502 -351.530145) (xy 76.558869 -351.477814)
			(xy 76.581527 -351.428203) (xy 76.611016 -351.382322) (xy 76.646734 -351.341105) (xy 76.687955 -351.305391)
			(xy 76.73384 -351.275907) (xy 76.783453 -351.253254) (xy 76.835786 -351.237893) (xy 76.889772 -351.230137)
			(xy 76.917042 -351.229676) (xy 77.780642 -351.229676) (xy 77.807912 -351.230089) (xy 77.861897 -351.237857)
			(xy 77.914226 -351.253227) (xy 77.963836 -351.275888) (xy 78.009716 -351.305378) (xy 78.050933 -351.341097)
			(xy 78.086647 -351.382317) (xy 78.116132 -351.428201) (xy 78.138788 -351.477813) (xy 78.154152 -351.530145)
			(xy 78.161914 -351.58413) (xy 78.161914 -351.638668) (xy 79.644739 -351.638668) (xy 79.644739 -351.584132)
			(xy 79.652501 -351.53015) (xy 79.667866 -351.477822) (xy 79.690521 -351.428214) (xy 79.720006 -351.382335)
			(xy 79.75572 -351.341119) (xy 79.796936 -351.305405) (xy 79.842816 -351.27592) (xy 79.892424 -351.253265)
			(xy 79.944752 -351.2379) (xy 79.998734 -351.230139) (xy 80.026002 -351.229676) (xy 80.889602 -351.229676)
			(xy 80.916874 -351.230087) (xy 80.970863 -351.237849) (xy 81.023197 -351.253216) (xy 81.072812 -351.275875)
			(xy 81.118697 -351.305364) (xy 81.159919 -351.341083) (xy 81.195637 -351.382304) (xy 81.225126 -351.42819)
			(xy 81.247784 -351.477805) (xy 81.263151 -351.530139) (xy 81.270913 -351.584128) (xy 81.270913 -351.638665)
			(xy 82.753762 -351.638665) (xy 82.753762 -351.584135) (xy 82.761522 -351.53016) (xy 82.776884 -351.477839)
			(xy 82.799535 -351.428236) (xy 82.829015 -351.382362) (xy 82.864722 -351.341149) (xy 82.905931 -351.305437)
			(xy 82.951803 -351.275953) (xy 83.001403 -351.253297) (xy 83.053723 -351.23793) (xy 83.107697 -351.230165)
			(xy 83.134962 -351.229676) (xy 83.998562 -351.229676) (xy 84.025837 -351.230061) (xy 84.079834 -351.23782)
			(xy 84.132176 -351.253184) (xy 84.181799 -351.275842) (xy 84.227692 -351.305331) (xy 84.268921 -351.341052)
			(xy 84.304646 -351.382277) (xy 84.33414 -351.428167) (xy 84.356803 -351.477788) (xy 84.372172 -351.530129)
			(xy 84.379936 -351.584125) (xy 84.379936 -351.638669) (xy 85.862639 -351.638669) (xy 85.862639 -351.584131)
			(xy 85.870401 -351.530147) (xy 85.885767 -351.477818) (xy 85.908424 -351.428208) (xy 85.937911 -351.382328)
			(xy 85.973627 -351.341112) (xy 86.014846 -351.305398) (xy 86.060728 -351.275914) (xy 86.110339 -351.25326)
			(xy 86.162669 -351.237897) (xy 86.216653 -351.230138) (xy 86.243922 -351.229676) (xy 87.107522 -351.229676)
			(xy 87.134793 -351.230088) (xy 87.18878 -351.237853) (xy 87.241112 -351.253222) (xy 87.290724 -351.275881)
			(xy 87.336607 -351.305371) (xy 87.377826 -351.34109) (xy 87.413542 -351.382311) (xy 87.443029 -351.428195)
			(xy 87.465686 -351.477809) (xy 87.481052 -351.530142) (xy 87.488814 -351.584129) (xy 87.488814 -351.638666)
			(xy 88.971662 -351.638666) (xy 88.971662 -351.584134) (xy 88.979423 -351.530158) (xy 88.994786 -351.477835)
			(xy 89.017438 -351.428231) (xy 89.04692 -351.382355) (xy 89.082629 -351.341142) (xy 89.123841 -351.30543)
			(xy 89.169715 -351.275947) (xy 89.219318 -351.253292) (xy 89.27164 -351.237927) (xy 89.325616 -351.230164)
			(xy 89.352882 -351.229676) (xy 90.216482 -351.229676) (xy 90.243757 -351.230062) (xy 90.297751 -351.237823)
			(xy 90.350091 -351.253189) (xy 90.399711 -351.275848) (xy 90.445602 -351.305338) (xy 90.486828 -351.341059)
			(xy 90.522551 -351.382284) (xy 90.552043 -351.428173) (xy 90.574704 -351.477792) (xy 90.590073 -351.530132)
			(xy 90.597836 -351.584125) (xy 90.597836 -351.63867) (xy 92.08054 -351.63867) (xy 92.08054 -351.58413)
			(xy 92.088302 -351.530145) (xy 92.103669 -351.477814) (xy 92.126327 -351.428203) (xy 92.155816 -351.382322)
			(xy 92.191534 -351.341105) (xy 92.232755 -351.305391) (xy 92.27864 -351.275907) (xy 92.328253 -351.253254)
			(xy 92.380586 -351.237893) (xy 92.434572 -351.230137) (xy 92.461842 -351.229676) (xy 93.325442 -351.229676)
			(xy 93.352712 -351.230089) (xy 93.406697 -351.237857) (xy 93.459026 -351.253227) (xy 93.508636 -351.275888)
			(xy 93.554516 -351.305378) (xy 93.595733 -351.341097) (xy 93.631447 -351.382317) (xy 93.645329 -351.40392)
			(xy 99.12426 -351.40392) (xy 99.128331 -351.348298) (xy 99.140457 -351.293861) (xy 99.16038 -351.24177)
			(xy 99.187676 -351.193135) (xy 99.221762 -351.148992) (xy 99.261911 -351.110283) (xy 99.307269 -351.077832)
			(xy 99.356869 -351.052331) (xy 99.409653 -351.034324) (xy 99.464496 -351.024194) (xy 99.52023 -351.022157)
			(xy 99.575667 -351.028257) (xy 99.629624 -351.042363) (xy 99.680953 -351.064175) (xy 99.728559 -351.093229)
			(xy 99.771427 -351.128904) (xy 99.808644 -351.170441) (xy 99.839417 -351.216954) (xy 99.863089 -351.267451)
			(xy 99.879157 -351.320858) (xy 99.887277 -351.376034) (xy 99.887786 -351.40392) (xy 99.887277 -351.431806)
			(xy 99.879157 -351.486982) (xy 99.871134 -351.513648) (xy 106.459526 -351.513648) (xy 106.463597 -351.458026)
			(xy 106.475723 -351.403589) (xy 106.495646 -351.351498) (xy 106.522942 -351.302863) (xy 106.557028 -351.25872)
			(xy 106.597177 -351.220011) (xy 106.642535 -351.18756) (xy 106.692135 -351.162059) (xy 106.744919 -351.144052)
			(xy 106.799762 -351.133922) (xy 106.855496 -351.131885) (xy 106.910933 -351.137985) (xy 106.96489 -351.152091)
			(xy 107.016219 -351.173903) (xy 107.063825 -351.202957) (xy 107.106693 -351.238632) (xy 107.14391 -351.280169)
			(xy 107.174683 -351.326682) (xy 107.198355 -351.377179) (xy 107.214423 -351.430586) (xy 107.222543 -351.485762)
			(xy 107.223052 -351.513648) (xy 107.222543 -351.541534) (xy 107.214423 -351.59671) (xy 107.198355 -351.650117)
			(xy 107.174683 -351.700614) (xy 107.14391 -351.747127) (xy 107.106693 -351.788664) (xy 107.063825 -351.824339)
			(xy 107.016219 -351.853393) (xy 106.96489 -351.875205) (xy 106.910933 -351.889311) (xy 106.855496 -351.895411)
			(xy 106.799762 -351.893374) (xy 106.744919 -351.883244) (xy 106.692135 -351.865237) (xy 106.642535 -351.839736)
			(xy 106.597177 -351.807285) (xy 106.557028 -351.768576) (xy 106.522942 -351.724433) (xy 106.495646 -351.675798)
			(xy 106.475723 -351.623707) (xy 106.463597 -351.56927) (xy 106.459526 -351.513648) (xy 99.871134 -351.513648)
			(xy 99.863089 -351.540389) (xy 99.839417 -351.590886) (xy 99.808644 -351.637399) (xy 99.771427 -351.678936)
			(xy 99.728559 -351.714611) (xy 99.680953 -351.743665) (xy 99.629624 -351.765477) (xy 99.575667 -351.779583)
			(xy 99.52023 -351.785683) (xy 99.464496 -351.783646) (xy 99.409653 -351.773516) (xy 99.356869 -351.755509)
			(xy 99.307269 -351.730008) (xy 99.261911 -351.697557) (xy 99.221762 -351.658848) (xy 99.187676 -351.614705)
			(xy 99.16038 -351.56607) (xy 99.140457 -351.513979) (xy 99.128331 -351.459542) (xy 99.12426 -351.40392)
			(xy 93.645329 -351.40392) (xy 93.660932 -351.428201) (xy 93.683588 -351.477813) (xy 93.698952 -351.530145)
			(xy 93.706714 -351.58413) (xy 93.706714 -351.63867) (xy 93.698952 -351.692655) (xy 93.683588 -351.744987)
			(xy 93.660932 -351.794599) (xy 93.631447 -351.840483) (xy 93.595733 -351.881703) (xy 93.554516 -351.917422)
			(xy 93.508636 -351.946912) (xy 93.459026 -351.969573) (xy 93.406697 -351.984943) (xy 93.352712 -351.992711)
			(xy 93.325442 -351.9932) (xy 92.461842 -351.9932) (xy 92.434572 -351.992663) (xy 92.380586 -351.984907)
			(xy 92.328253 -351.969546) (xy 92.27864 -351.946893) (xy 92.232755 -351.917409) (xy 92.191534 -351.881695)
			(xy 92.155816 -351.840478) (xy 92.126327 -351.794597) (xy 92.103669 -351.744986) (xy 92.088302 -351.692655)
			(xy 92.08054 -351.63867) (xy 90.597836 -351.63867) (xy 90.597836 -351.638675) (xy 90.590073 -351.692668)
			(xy 90.574704 -351.745008) (xy 90.552043 -351.794627) (xy 90.522551 -351.840516) (xy 90.486828 -351.881741)
			(xy 90.445602 -351.917462) (xy 90.399711 -351.946952) (xy 90.350091 -351.969611) (xy 90.297751 -351.984977)
			(xy 90.243757 -351.992738) (xy 90.216482 -351.9932) (xy 89.352882 -351.9932) (xy 89.325616 -351.992636)
			(xy 89.27164 -351.984873) (xy 89.219318 -351.969508) (xy 89.169715 -351.946853) (xy 89.123841 -351.91737)
			(xy 89.082629 -351.881658) (xy 89.04692 -351.840445) (xy 89.017438 -351.794569) (xy 88.994786 -351.744965)
			(xy 88.979423 -351.692642) (xy 88.971662 -351.638666) (xy 87.488814 -351.638666) (xy 87.488814 -351.638671)
			(xy 87.481052 -351.692658) (xy 87.465686 -351.744991) (xy 87.443029 -351.794605) (xy 87.413542 -351.840489)
			(xy 87.377826 -351.88171) (xy 87.336607 -351.917429) (xy 87.290724 -351.946919) (xy 87.241112 -351.969578)
			(xy 87.18878 -351.984947) (xy 87.134793 -351.992712) (xy 87.107522 -351.9932) (xy 86.243922 -351.9932)
			(xy 86.216653 -351.992662) (xy 86.162669 -351.984903) (xy 86.110339 -351.96954) (xy 86.060728 -351.946886)
			(xy 86.014846 -351.917402) (xy 85.973627 -351.881688) (xy 85.937911 -351.840472) (xy 85.908424 -351.794592)
			(xy 85.885767 -351.744982) (xy 85.870401 -351.692653) (xy 85.862639 -351.638669) (xy 84.379936 -351.638669)
			(xy 84.379936 -351.638675) (xy 84.372172 -351.692671) (xy 84.356803 -351.745012) (xy 84.33414 -351.794633)
			(xy 84.304646 -351.840523) (xy 84.268921 -351.881748) (xy 84.227692 -351.917469) (xy 84.181799 -351.946958)
			(xy 84.132176 -351.969616) (xy 84.079834 -351.98498) (xy 84.025837 -351.992739) (xy 83.998562 -351.9932)
			(xy 83.134962 -351.9932) (xy 83.107697 -351.992635) (xy 83.053723 -351.98487) (xy 83.001403 -351.969503)
			(xy 82.951803 -351.946847) (xy 82.905931 -351.917363) (xy 82.864722 -351.881651) (xy 82.829015 -351.840438)
			(xy 82.799535 -351.794564) (xy 82.776884 -351.744961) (xy 82.761522 -351.69264) (xy 82.753762 -351.638665)
			(xy 81.270913 -351.638665) (xy 81.270913 -351.638672) (xy 81.263151 -351.692661) (xy 81.247784 -351.744995)
			(xy 81.225126 -351.79461) (xy 81.195637 -351.840496) (xy 81.159919 -351.881717) (xy 81.118697 -351.917436)
			(xy 81.072812 -351.946925) (xy 81.023197 -351.969584) (xy 80.970863 -351.984951) (xy 80.916874 -351.992713)
			(xy 80.889602 -351.9932) (xy 80.026002 -351.9932) (xy 79.998734 -351.992661) (xy 79.944752 -351.9849)
			(xy 79.892424 -351.969535) (xy 79.842816 -351.94688) (xy 79.796936 -351.917395) (xy 79.75572 -351.881681)
			(xy 79.720006 -351.840465) (xy 79.690521 -351.794586) (xy 79.667866 -351.744978) (xy 79.652501 -351.69265)
			(xy 79.644739 -351.638668) (xy 78.161914 -351.638668) (xy 78.161914 -351.63867) (xy 78.154152 -351.692655)
			(xy 78.138788 -351.744987) (xy 78.116132 -351.794599) (xy 78.086647 -351.840483) (xy 78.050933 -351.881703)
			(xy 78.009716 -351.917422) (xy 77.963836 -351.946912) (xy 77.914226 -351.969573) (xy 77.861897 -351.984943)
			(xy 77.807912 -351.992711) (xy 77.780642 -351.9932) (xy 76.917042 -351.9932) (xy 76.889772 -351.992663)
			(xy 76.835786 -351.984907) (xy 76.783453 -351.969546) (xy 76.73384 -351.946893) (xy 76.687955 -351.917409)
			(xy 76.646734 -351.881695) (xy 76.611016 -351.840478) (xy 76.581527 -351.794597) (xy 76.558869 -351.744986)
			(xy 76.543502 -351.692655) (xy 76.53574 -351.63867) (xy 75.053036 -351.63867) (xy 75.053036 -351.638675)
			(xy 75.045273 -351.692668) (xy 75.029904 -351.745008) (xy 75.007243 -351.794627) (xy 74.977751 -351.840516)
			(xy 74.942028 -351.881741) (xy 74.900802 -351.917462) (xy 74.854911 -351.946952) (xy 74.805291 -351.969611)
			(xy 74.752951 -351.984977) (xy 74.698957 -351.992738) (xy 74.671682 -351.9932) (xy 73.808082 -351.9932)
			(xy 73.780816 -351.992636) (xy 73.72684 -351.984873) (xy 73.674518 -351.969508) (xy 73.624915 -351.946853)
			(xy 73.579041 -351.91737) (xy 73.537829 -351.881658) (xy 73.50212 -351.840445) (xy 73.472638 -351.794569)
			(xy 73.449986 -351.744965) (xy 73.434623 -351.692642) (xy 73.426862 -351.638666) (xy 71.944014 -351.638666)
			(xy 71.944014 -351.638671) (xy 71.936252 -351.692658) (xy 71.920886 -351.744991) (xy 71.898229 -351.794605)
			(xy 71.868742 -351.840489) (xy 71.833026 -351.88171) (xy 71.791807 -351.917429) (xy 71.745924 -351.946919)
			(xy 71.696312 -351.969578) (xy 71.64398 -351.984947) (xy 71.589993 -351.992712) (xy 71.562722 -351.9932)
			(xy 70.699122 -351.9932) (xy 70.671853 -351.992662) (xy 70.617869 -351.984903) (xy 70.565539 -351.96954)
			(xy 70.515928 -351.946886) (xy 70.470046 -351.917402) (xy 70.428827 -351.881688) (xy 70.393111 -351.840472)
			(xy 70.363624 -351.794592) (xy 70.340967 -351.744982) (xy 70.325601 -351.692653) (xy 70.317839 -351.638669)
			(xy 68.835136 -351.638669) (xy 68.835136 -351.638675) (xy 68.827372 -351.692671) (xy 68.812003 -351.745012)
			(xy 68.78934 -351.794633) (xy 68.759846 -351.840523) (xy 68.724121 -351.881748) (xy 68.682892 -351.917469)
			(xy 68.636999 -351.946958) (xy 68.587376 -351.969616) (xy 68.535034 -351.98498) (xy 68.481037 -351.992739)
			(xy 68.453762 -351.9932) (xy 67.590162 -351.9932) (xy 67.562897 -351.992635) (xy 67.508923 -351.98487)
			(xy 67.456603 -351.969503) (xy 67.407003 -351.946847) (xy 67.361131 -351.917363) (xy 67.319922 -351.881651)
			(xy 67.284215 -351.840438) (xy 67.254735 -351.794564) (xy 67.232084 -351.744961) (xy 67.216722 -351.69264)
			(xy 67.208962 -351.638665) (xy 65.726113 -351.638665) (xy 65.726113 -351.638672) (xy 65.718351 -351.692661)
			(xy 65.702984 -351.744995) (xy 65.680326 -351.79461) (xy 65.650837 -351.840496) (xy 65.615119 -351.881717)
			(xy 65.573897 -351.917436) (xy 65.528012 -351.946925) (xy 65.478397 -351.969584) (xy 65.426063 -351.984951)
			(xy 65.372074 -351.992713) (xy 65.344802 -351.9932) (xy 64.481202 -351.9932) (xy 64.453934 -351.992661)
			(xy 64.399952 -351.9849) (xy 64.347624 -351.969535) (xy 64.298016 -351.94688) (xy 64.252136 -351.917395)
			(xy 64.21092 -351.881681) (xy 64.175206 -351.840465) (xy 64.145721 -351.794586) (xy 64.123066 -351.744978)
			(xy 64.107701 -351.69265) (xy 64.099939 -351.638668) (xy 62.617114 -351.638668) (xy 62.617114 -351.63867)
			(xy 62.609352 -351.692655) (xy 62.593988 -351.744987) (xy 62.571332 -351.794599) (xy 62.541847 -351.840483)
			(xy 62.506133 -351.881703) (xy 62.464916 -351.917422) (xy 62.419036 -351.946912) (xy 62.369426 -351.969573)
			(xy 62.317097 -351.984943) (xy 62.263112 -351.992711) (xy 62.235842 -351.9932) (xy 61.372242 -351.9932)
			(xy 61.344972 -351.992663) (xy 61.290986 -351.984907) (xy 61.238653 -351.969546) (xy 61.18904 -351.946893)
			(xy 61.143155 -351.917409) (xy 61.101934 -351.881695) (xy 61.066216 -351.840478) (xy 61.036727 -351.794597)
			(xy 61.014069 -351.744986) (xy 60.998702 -351.692655) (xy 60.99094 -351.63867) (xy 58.971942 -351.63867)
			(xy 58.971942 -353.042474) (xy 99.14839 -353.042474) (xy 99.152461 -352.986852) (xy 99.164587 -352.932415)
			(xy 99.18451 -352.880324) (xy 99.211806 -352.831689) (xy 99.245892 -352.787546) (xy 99.286041 -352.748837)
			(xy 99.331399 -352.716386) (xy 99.380999 -352.690885) (xy 99.433783 -352.672878) (xy 99.488626 -352.662748)
			(xy 99.54436 -352.660711) (xy 99.599797 -352.666811) (xy 99.653754 -352.680917) (xy 99.705083 -352.702729)
			(xy 99.752689 -352.731783) (xy 99.795557 -352.767458) (xy 99.832774 -352.808995) (xy 99.863547 -352.855508)
			(xy 99.887219 -352.906005) (xy 99.903287 -352.959412) (xy 99.91125 -353.013518) (xy 100.143562 -353.013518)
			(xy 100.147633 -352.957896) (xy 100.159759 -352.903459) (xy 100.179682 -352.851368) (xy 100.206978 -352.802733)
			(xy 100.241064 -352.75859) (xy 100.281213 -352.719881) (xy 100.326571 -352.68743) (xy 100.376171 -352.661929)
			(xy 100.428955 -352.643922) (xy 100.483798 -352.633792) (xy 100.539532 -352.631755) (xy 100.594969 -352.637855)
			(xy 100.648926 -352.651961) (xy 100.700255 -352.673773) (xy 100.747861 -352.702827) (xy 100.790729 -352.738502)
			(xy 100.827946 -352.780039) (xy 100.858719 -352.826552) (xy 100.882391 -352.877049) (xy 100.898459 -352.930456)
			(xy 100.906579 -352.985632) (xy 100.907088 -353.013518) (xy 100.906579 -353.041404) (xy 100.898459 -353.09658)
			(xy 100.882391 -353.149987) (xy 100.858719 -353.200484) (xy 100.827946 -353.246997) (xy 100.790729 -353.288534)
			(xy 100.747861 -353.324209) (xy 100.700255 -353.353263) (xy 100.648926 -353.375075) (xy 100.594969 -353.389181)
			(xy 100.539532 -353.395281) (xy 100.483798 -353.393244) (xy 100.428955 -353.383114) (xy 100.376171 -353.365107)
			(xy 100.326571 -353.339606) (xy 100.281213 -353.307155) (xy 100.241064 -353.268446) (xy 100.206978 -353.224303)
			(xy 100.179682 -353.175668) (xy 100.159759 -353.123577) (xy 100.147633 -353.06914) (xy 100.143562 -353.013518)
			(xy 99.91125 -353.013518) (xy 99.911407 -353.014588) (xy 99.911916 -353.042474) (xy 99.911407 -353.07036)
			(xy 99.903287 -353.125536) (xy 99.887219 -353.178943) (xy 99.863547 -353.22944) (xy 99.832774 -353.275953)
			(xy 99.795557 -353.31749) (xy 99.752689 -353.353165) (xy 99.705083 -353.382219) (xy 99.653754 -353.404031)
			(xy 99.599797 -353.418137) (xy 99.54436 -353.424237) (xy 99.488626 -353.4222) (xy 99.433783 -353.41207)
			(xy 99.380999 -353.394063) (xy 99.331399 -353.368562) (xy 99.286041 -353.336111) (xy 99.245892 -353.297402)
			(xy 99.211806 -353.253259) (xy 99.18451 -353.204624) (xy 99.164587 -353.152533) (xy 99.152461 -353.098096)
			(xy 99.14839 -353.042474) (xy 58.971942 -353.042474) (xy 58.971942 -354.33127) (xy 58.971505 -354.341333)
			(xy 58.963766 -354.359914) (xy 58.956956 -354.367338) (xy 58.564922 -354.759372) (xy 64.099884 -354.759372)
			(xy 64.099884 -354.704828) (xy 64.107646 -354.650838) (xy 64.123013 -354.598503) (xy 64.145672 -354.548887)
			(xy 64.175161 -354.503001) (xy 64.210881 -354.461779) (xy 64.252103 -354.42606) (xy 64.297989 -354.396571)
			(xy 64.347605 -354.373912) (xy 64.39994 -354.358546) (xy 64.45393 -354.350783) (xy 64.481202 -354.35032)
			(xy 65.344802 -354.35032) (xy 65.37207 -354.350843) (xy 65.426051 -354.358604) (xy 65.478378 -354.373969)
			(xy 65.527985 -354.396624) (xy 65.573864 -354.426109) (xy 65.615079 -354.461822) (xy 65.650793 -354.503038)
			(xy 65.680277 -354.548917) (xy 65.702932 -354.598524) (xy 65.718296 -354.650851) (xy 65.726058 -354.704832)
			(xy 65.726058 -354.759368) (xy 65.726058 -354.759369) (xy 67.208906 -354.759369) (xy 67.208906 -354.704831)
			(xy 67.216667 -354.650848) (xy 67.232032 -354.598519) (xy 67.254686 -354.548909) (xy 67.28417 -354.503028)
			(xy 67.319883 -354.46181) (xy 67.361098 -354.426093) (xy 67.406976 -354.396604) (xy 67.456584 -354.373945)
			(xy 67.508911 -354.358575) (xy 67.562893 -354.350809) (xy 67.590162 -354.35032) (xy 68.453762 -354.35032)
			(xy 68.481033 -354.350817) (xy 68.535022 -354.358574) (xy 68.587357 -354.373936) (xy 68.636972 -354.396591)
			(xy 68.682859 -354.426076) (xy 68.724081 -354.461792) (xy 68.759801 -354.503011) (xy 68.789291 -354.548894)
			(xy 68.81195 -354.598508) (xy 68.827318 -354.650841) (xy 68.83508 -354.704829) (xy 68.83508 -354.759371)
			(xy 68.83508 -354.759373) (xy 70.317784 -354.759373) (xy 70.317784 -354.704827) (xy 70.325547 -354.650835)
			(xy 70.340915 -354.598498) (xy 70.363575 -354.548882) (xy 70.393066 -354.502995) (xy 70.428788 -354.461772)
			(xy 70.470012 -354.426053) (xy 70.515901 -354.396564) (xy 70.565519 -354.373907) (xy 70.617857 -354.358542)
			(xy 70.671849 -354.350782) (xy 70.699122 -354.35032) (xy 71.562722 -354.35032) (xy 71.589989 -354.350844)
			(xy 71.643968 -354.358608) (xy 71.696292 -354.373974) (xy 71.745897 -354.396631) (xy 71.791773 -354.426116)
			(xy 71.832986 -354.461829) (xy 71.868697 -354.503044) (xy 71.89818 -354.548922) (xy 71.920833 -354.598528)
			(xy 71.936197 -354.650854) (xy 71.943958 -354.704833) (xy 71.943958 -354.759367) (xy 71.943958 -354.75937)
			(xy 73.426806 -354.75937) (xy 73.426806 -354.70483) (xy 73.434568 -354.650846) (xy 73.449933 -354.598515)
			(xy 73.472589 -354.548904) (xy 73.502075 -354.503022) (xy 73.53779 -354.461802) (xy 73.579007 -354.426085)
			(xy 73.624888 -354.396598) (xy 73.674498 -354.373939) (xy 73.726828 -354.358572) (xy 73.780812 -354.350808)
			(xy 73.808082 -354.35032) (xy 74.671682 -354.35032) (xy 74.698953 -354.350818) (xy 74.752939 -354.358578)
			(xy 74.805271 -354.373942) (xy 74.854884 -354.396597) (xy 74.900768 -354.426083) (xy 74.941988 -354.461799)
			(xy 74.977706 -354.503018) (xy 75.007194 -354.5489) (xy 75.029852 -354.598512) (xy 75.045218 -354.650844)
			(xy 75.052981 -354.704829) (xy 75.052981 -354.759371) (xy 75.052981 -354.759374) (xy 76.535684 -354.759374)
			(xy 76.535684 -354.704826) (xy 76.543447 -354.650833) (xy 76.558816 -354.598494) (xy 76.581478 -354.548876)
			(xy 76.610971 -354.502988) (xy 76.646695 -354.461765) (xy 76.687922 -354.426046) (xy 76.733813 -354.396558)
			(xy 76.783434 -354.373902) (xy 76.835774 -354.358538) (xy 76.889768 -354.350781) (xy 76.917042 -354.35032)
			(xy 77.780642 -354.35032) (xy 77.807908 -354.350845) (xy 77.861885 -354.358611) (xy 77.914207 -354.37398)
			(xy 77.963809 -354.396637) (xy 78.009683 -354.426123) (xy 78.050893 -354.461836) (xy 78.086602 -354.503051)
			(xy 78.116083 -354.548928) (xy 78.138735 -354.598533) (xy 78.154098 -354.650856) (xy 78.161858 -354.704834)
			(xy 78.161858 -354.759366) (xy 78.161857 -354.759372) (xy 79.644684 -354.759372) (xy 79.644684 -354.704828)
			(xy 79.652446 -354.650838) (xy 79.667813 -354.598503) (xy 79.690472 -354.548887) (xy 79.719961 -354.503001)
			(xy 79.755681 -354.461779) (xy 79.796903 -354.42606) (xy 79.842789 -354.396571) (xy 79.892405 -354.373912)
			(xy 79.94474 -354.358546) (xy 79.99873 -354.350783) (xy 80.026002 -354.35032) (xy 80.889602 -354.35032)
			(xy 80.91687 -354.350843) (xy 80.970851 -354.358604) (xy 81.023178 -354.373969) (xy 81.072785 -354.396624)
			(xy 81.118664 -354.426109) (xy 81.159879 -354.461822) (xy 81.195593 -354.503038) (xy 81.225077 -354.548917)
			(xy 81.247732 -354.598524) (xy 81.263096 -354.650851) (xy 81.270858 -354.704832) (xy 81.270858 -354.759368)
			(xy 81.270858 -354.759369) (xy 82.753706 -354.759369) (xy 82.753706 -354.704831) (xy 82.761467 -354.650848)
			(xy 82.776832 -354.598519) (xy 82.799486 -354.548909) (xy 82.82897 -354.503028) (xy 82.864683 -354.46181)
			(xy 82.905898 -354.426093) (xy 82.951776 -354.396604) (xy 83.001384 -354.373945) (xy 83.053711 -354.358575)
			(xy 83.107693 -354.350809) (xy 83.134962 -354.35032) (xy 83.998562 -354.35032) (xy 84.025833 -354.350817)
			(xy 84.079822 -354.358574) (xy 84.132157 -354.373936) (xy 84.181772 -354.396591) (xy 84.227659 -354.426076)
			(xy 84.268881 -354.461792) (xy 84.304601 -354.503011) (xy 84.334091 -354.548894) (xy 84.35675 -354.598508)
			(xy 84.372118 -354.650841) (xy 84.37988 -354.704829) (xy 84.37988 -354.759371) (xy 84.37988 -354.759373)
			(xy 85.862584 -354.759373) (xy 85.862584 -354.704827) (xy 85.870347 -354.650835) (xy 85.885715 -354.598498)
			(xy 85.908375 -354.548882) (xy 85.937866 -354.502995) (xy 85.973588 -354.461772) (xy 86.014812 -354.426053)
			(xy 86.060701 -354.396564) (xy 86.110319 -354.373907) (xy 86.162657 -354.358542) (xy 86.216649 -354.350782)
			(xy 86.243922 -354.35032) (xy 87.107522 -354.35032) (xy 87.134789 -354.350844) (xy 87.188768 -354.358608)
			(xy 87.241092 -354.373974) (xy 87.290697 -354.396631) (xy 87.336573 -354.426116) (xy 87.377786 -354.461829)
			(xy 87.413497 -354.503044) (xy 87.44298 -354.548922) (xy 87.465633 -354.598528) (xy 87.480997 -354.650854)
			(xy 87.488758 -354.704833) (xy 87.488758 -354.759367) (xy 87.488758 -354.75937) (xy 88.971606 -354.75937)
			(xy 88.971606 -354.70483) (xy 88.979368 -354.650846) (xy 88.994733 -354.598515) (xy 89.017389 -354.548904)
			(xy 89.046875 -354.503022) (xy 89.08259 -354.461802) (xy 89.123807 -354.426085) (xy 89.169688 -354.396598)
			(xy 89.219298 -354.373939) (xy 89.271628 -354.358572) (xy 89.325612 -354.350808) (xy 89.352882 -354.35032)
			(xy 90.216482 -354.35032) (xy 90.243753 -354.350818) (xy 90.297739 -354.358578) (xy 90.350071 -354.373942)
			(xy 90.399684 -354.396597) (xy 90.445568 -354.426083) (xy 90.486788 -354.461799) (xy 90.522506 -354.503018)
			(xy 90.551994 -354.5489) (xy 90.574652 -354.598512) (xy 90.590018 -354.650844) (xy 90.597781 -354.704829)
			(xy 90.597781 -354.759371) (xy 90.597781 -354.759374) (xy 92.080484 -354.759374) (xy 92.080484 -354.704826)
			(xy 92.088247 -354.650833) (xy 92.103616 -354.598494) (xy 92.126278 -354.548876) (xy 92.155771 -354.502988)
			(xy 92.191495 -354.461765) (xy 92.232722 -354.426046) (xy 92.278613 -354.396558) (xy 92.328234 -354.373902)
			(xy 92.380574 -354.358538) (xy 92.434568 -354.350781) (xy 92.461842 -354.35032) (xy 93.325442 -354.35032)
			(xy 93.352708 -354.350845) (xy 93.406685 -354.358611) (xy 93.459007 -354.37398) (xy 93.508609 -354.396637)
			(xy 93.554483 -354.426123) (xy 93.595693 -354.461836) (xy 93.631402 -354.503051) (xy 93.632822 -354.50526)
			(xy 99.97643 -354.50526) (xy 99.980501 -354.449638) (xy 99.992627 -354.395201) (xy 100.01255 -354.34311)
			(xy 100.039846 -354.294475) (xy 100.073932 -354.250332) (xy 100.114081 -354.211623) (xy 100.159439 -354.179172)
			(xy 100.209039 -354.153671) (xy 100.261823 -354.135664) (xy 100.316666 -354.125534) (xy 100.3724 -354.123497)
			(xy 100.427837 -354.129597) (xy 100.453087 -354.136198) (xy 105.899202 -354.136198) (xy 105.903273 -354.080576)
			(xy 105.915399 -354.026139) (xy 105.935322 -353.974048) (xy 105.962618 -353.925413) (xy 105.996704 -353.88127)
			(xy 106.036853 -353.842561) (xy 106.082211 -353.81011) (xy 106.131811 -353.784609) (xy 106.184595 -353.766602)
			(xy 106.239438 -353.756472) (xy 106.295172 -353.754435) (xy 106.350609 -353.760535) (xy 106.404566 -353.774641)
			(xy 106.455895 -353.796453) (xy 106.503501 -353.825507) (xy 106.546369 -353.861182) (xy 106.583586 -353.902719)
			(xy 106.614359 -353.949232) (xy 106.638031 -353.999729) (xy 106.654099 -354.053136) (xy 106.662219 -354.108312)
			(xy 106.662728 -354.136198) (xy 106.662219 -354.164084) (xy 106.654099 -354.21926) (xy 106.638031 -354.272667)
			(xy 106.614359 -354.323164) (xy 106.583586 -354.369677) (xy 106.546369 -354.411214) (xy 106.503501 -354.446889)
			(xy 106.455895 -354.475943) (xy 106.404566 -354.497755) (xy 106.350609 -354.511861) (xy 106.295172 -354.517961)
			(xy 106.239438 -354.515924) (xy 106.184595 -354.505794) (xy 106.131811 -354.487787) (xy 106.082211 -354.462286)
			(xy 106.036853 -354.429835) (xy 105.996704 -354.391126) (xy 105.962618 -354.346983) (xy 105.935322 -354.298348)
			(xy 105.915399 -354.246257) (xy 105.903273 -354.19182) (xy 105.899202 -354.136198) (xy 100.453087 -354.136198)
			(xy 100.481794 -354.143703) (xy 100.533123 -354.165515) (xy 100.580729 -354.194569) (xy 100.623597 -354.230244)
			(xy 100.660814 -354.271781) (xy 100.691587 -354.318294) (xy 100.715259 -354.368791) (xy 100.731327 -354.422198)
			(xy 100.739447 -354.477374) (xy 100.739956 -354.50526) (xy 100.739447 -354.533146) (xy 100.731327 -354.588322)
			(xy 100.715259 -354.641729) (xy 100.691587 -354.692226) (xy 100.660814 -354.738739) (xy 100.623597 -354.780276)
			(xy 100.580729 -354.815951) (xy 100.533123 -354.845005) (xy 100.481794 -354.866817) (xy 100.427837 -354.880923)
			(xy 100.3724 -354.887023) (xy 100.316666 -354.884986) (xy 100.261823 -354.874856) (xy 100.209039 -354.856849)
			(xy 100.159439 -354.831348) (xy 100.114081 -354.798897) (xy 100.073932 -354.760188) (xy 100.039846 -354.716045)
			(xy 100.01255 -354.66741) (xy 99.992627 -354.615319) (xy 99.980501 -354.560882) (xy 99.97643 -354.50526)
			(xy 93.632822 -354.50526) (xy 93.660883 -354.548928) (xy 93.683535 -354.598533) (xy 93.698898 -354.650856)
			(xy 93.706658 -354.704834) (xy 93.706658 -354.759366) (xy 93.698898 -354.813344) (xy 93.683535 -354.865667)
			(xy 93.660883 -354.915272) (xy 93.631402 -354.961149) (xy 93.595693 -355.002364) (xy 93.554483 -355.038077)
			(xy 93.508609 -355.067563) (xy 93.459007 -355.09022) (xy 93.406685 -355.105589) (xy 93.352708 -355.113355)
			(xy 93.325442 -355.113844) (xy 92.461842 -355.113844) (xy 92.434568 -355.113419) (xy 92.380574 -355.105662)
			(xy 92.328234 -355.090298) (xy 92.278613 -355.067642) (xy 92.232722 -355.038154) (xy 92.191495 -355.002435)
			(xy 92.155771 -354.961212) (xy 92.126278 -354.915324) (xy 92.103616 -354.865706) (xy 92.088247 -354.813367)
			(xy 92.080484 -354.759374) (xy 90.597781 -354.759374) (xy 90.590018 -354.813356) (xy 90.574652 -354.865688)
			(xy 90.551994 -354.9153) (xy 90.522506 -354.961182) (xy 90.486788 -355.002401) (xy 90.445568 -355.038117)
			(xy 90.399684 -355.067603) (xy 90.350071 -355.090258) (xy 90.297739 -355.105622) (xy 90.243753 -355.113382)
			(xy 90.216482 -355.113844) (xy 89.352882 -355.113844) (xy 89.325612 -355.113392) (xy 89.271628 -355.105628)
			(xy 89.219298 -355.090261) (xy 89.169688 -355.067602) (xy 89.123807 -355.038115) (xy 89.08259 -355.002398)
			(xy 89.046875 -354.961178) (xy 89.017389 -354.915296) (xy 88.994733 -354.865685) (xy 88.979368 -354.813354)
			(xy 88.971606 -354.75937) (xy 87.488758 -354.75937) (xy 87.480997 -354.813346) (xy 87.465633 -354.865672)
			(xy 87.44298 -354.915278) (xy 87.413497 -354.961156) (xy 87.377786 -355.002371) (xy 87.336573 -355.038084)
			(xy 87.290697 -355.067569) (xy 87.241092 -355.090226) (xy 87.188768 -355.105592) (xy 87.134789 -355.113356)
			(xy 87.107522 -355.113844) (xy 86.243922 -355.113844) (xy 86.216649 -355.113418) (xy 86.162657 -355.105658)
			(xy 86.110319 -355.090293) (xy 86.060701 -355.067636) (xy 86.014812 -355.038147) (xy 85.973588 -355.002428)
			(xy 85.937866 -354.961205) (xy 85.908375 -354.915318) (xy 85.885715 -354.865702) (xy 85.870347 -354.813365)
			(xy 85.862584 -354.759373) (xy 84.37988 -354.759373) (xy 84.372118 -354.813359) (xy 84.35675 -354.865692)
			(xy 84.334091 -354.915306) (xy 84.304601 -354.961189) (xy 84.268881 -355.002408) (xy 84.227659 -355.038124)
			(xy 84.181772 -355.067609) (xy 84.132157 -355.090264) (xy 84.079822 -355.105626) (xy 84.025833 -355.113383)
			(xy 83.998562 -355.113844) (xy 83.134962 -355.113844) (xy 83.107693 -355.113391) (xy 83.053711 -355.105625)
			(xy 83.001384 -355.090255) (xy 82.951776 -355.067596) (xy 82.905898 -355.038107) (xy 82.864683 -355.00239)
			(xy 82.82897 -354.961172) (xy 82.799486 -354.915291) (xy 82.776832 -354.865681) (xy 82.761467 -354.813352)
			(xy 82.753706 -354.759369) (xy 81.270858 -354.759369) (xy 81.263096 -354.813349) (xy 81.247732 -354.865676)
			(xy 81.225077 -354.915283) (xy 81.195593 -354.961162) (xy 81.159879 -355.002378) (xy 81.118664 -355.038091)
			(xy 81.072785 -355.067576) (xy 81.023178 -355.090231) (xy 80.970851 -355.105596) (xy 80.91687 -355.113357)
			(xy 80.889602 -355.113844) (xy 80.026002 -355.113844) (xy 79.99873 -355.113417) (xy 79.94474 -355.105654)
			(xy 79.892405 -355.090288) (xy 79.842789 -355.067629) (xy 79.796903 -355.03814) (xy 79.755681 -355.002421)
			(xy 79.719961 -354.961199) (xy 79.690472 -354.915313) (xy 79.667813 -354.865697) (xy 79.652446 -354.813362)
			(xy 79.644684 -354.759372) (xy 78.161857 -354.759372) (xy 78.154098 -354.813344) (xy 78.138735 -354.865667)
			(xy 78.116083 -354.915272) (xy 78.086602 -354.961149) (xy 78.050893 -355.002364) (xy 78.009683 -355.038077)
			(xy 77.963809 -355.067563) (xy 77.914207 -355.09022) (xy 77.861885 -355.105589) (xy 77.807908 -355.113355)
			(xy 77.780642 -355.113844) (xy 76.917042 -355.113844) (xy 76.889768 -355.113419) (xy 76.835774 -355.105662)
			(xy 76.783434 -355.090298) (xy 76.733813 -355.067642) (xy 76.687922 -355.038154) (xy 76.646695 -355.002435)
			(xy 76.610971 -354.961212) (xy 76.581478 -354.915324) (xy 76.558816 -354.865706) (xy 76.543447 -354.813367)
			(xy 76.535684 -354.759374) (xy 75.052981 -354.759374) (xy 75.045218 -354.813356) (xy 75.029852 -354.865688)
			(xy 75.007194 -354.9153) (xy 74.977706 -354.961182) (xy 74.941988 -355.002401) (xy 74.900768 -355.038117)
			(xy 74.854884 -355.067603) (xy 74.805271 -355.090258) (xy 74.752939 -355.105622) (xy 74.698953 -355.113382)
			(xy 74.671682 -355.113844) (xy 73.808082 -355.113844) (xy 73.780812 -355.113392) (xy 73.726828 -355.105628)
			(xy 73.674498 -355.090261) (xy 73.624888 -355.067602) (xy 73.579007 -355.038115) (xy 73.53779 -355.002398)
			(xy 73.502075 -354.961178) (xy 73.472589 -354.915296) (xy 73.449933 -354.865685) (xy 73.434568 -354.813354)
			(xy 73.426806 -354.75937) (xy 71.943958 -354.75937) (xy 71.936197 -354.813346) (xy 71.920833 -354.865672)
			(xy 71.89818 -354.915278) (xy 71.868697 -354.961156) (xy 71.832986 -355.002371) (xy 71.791773 -355.038084)
			(xy 71.745897 -355.067569) (xy 71.696292 -355.090226) (xy 71.643968 -355.105592) (xy 71.589989 -355.113356)
			(xy 71.562722 -355.113844) (xy 70.699122 -355.113844) (xy 70.671849 -355.113418) (xy 70.617857 -355.105658)
			(xy 70.565519 -355.090293) (xy 70.515901 -355.067636) (xy 70.470012 -355.038147) (xy 70.428788 -355.002428)
			(xy 70.393066 -354.961205) (xy 70.363575 -354.915318) (xy 70.340915 -354.865702) (xy 70.325547 -354.813365)
			(xy 70.317784 -354.759373) (xy 68.83508 -354.759373) (xy 68.827318 -354.813359) (xy 68.81195 -354.865692)
			(xy 68.789291 -354.915306) (xy 68.759801 -354.961189) (xy 68.724081 -355.002408) (xy 68.682859 -355.038124)
			(xy 68.636972 -355.067609) (xy 68.587357 -355.090264) (xy 68.535022 -355.105626) (xy 68.481033 -355.113383)
			(xy 68.453762 -355.113844) (xy 67.590162 -355.113844) (xy 67.562893 -355.113391) (xy 67.508911 -355.105625)
			(xy 67.456584 -355.090255) (xy 67.406976 -355.067596) (xy 67.361098 -355.038107) (xy 67.319883 -355.00239)
			(xy 67.28417 -354.961172) (xy 67.254686 -354.915291) (xy 67.232032 -354.865681) (xy 67.216667 -354.813352)
			(xy 67.208906 -354.759369) (xy 65.726058 -354.759369) (xy 65.718296 -354.813349) (xy 65.702932 -354.865676)
			(xy 65.680277 -354.915283) (xy 65.650793 -354.961162) (xy 65.615079 -355.002378) (xy 65.573864 -355.038091)
			(xy 65.527985 -355.067576) (xy 65.478378 -355.090231) (xy 65.426051 -355.105596) (xy 65.37207 -355.113357)
			(xy 65.344802 -355.113844) (xy 64.481202 -355.113844) (xy 64.45393 -355.113417) (xy 64.39994 -355.105654)
			(xy 64.347605 -355.090288) (xy 64.297989 -355.067629) (xy 64.252103 -355.03814) (xy 64.210881 -355.002421)
			(xy 64.175161 -354.961199) (xy 64.145672 -354.915313) (xy 64.123013 -354.865697) (xy 64.107646 -354.813362)
			(xy 64.099884 -354.759372) (xy 58.564922 -354.759372) (xy 57.807352 -355.516942) (xy 57.799954 -355.523787)
			(xy 57.781355 -355.531513) (xy 57.771284 -355.531928) (xy 57.591452 -355.531928) (xy 57.581453 -355.532425)
			(xy 57.562982 -355.540094) (xy 57.559216 -355.543866) (xy 100.796342 -355.543866) (xy 100.800413 -355.488244)
			(xy 100.812539 -355.433807) (xy 100.832462 -355.381716) (xy 100.859758 -355.333081) (xy 100.893844 -355.288938)
			(xy 100.933993 -355.250229) (xy 100.979351 -355.217778) (xy 101.028951 -355.192277) (xy 101.081735 -355.17427)
			(xy 101.136578 -355.16414) (xy 101.192312 -355.162103) (xy 101.247749 -355.168203) (xy 101.301706 -355.182309)
			(xy 101.353035 -355.204121) (xy 101.400641 -355.233175) (xy 101.443509 -355.26885) (xy 101.480726 -355.310387)
			(xy 101.483114 -355.313996) (xy 106.055922 -355.313996) (xy 106.056408 -355.286745) (xy 106.064164 -355.232797)
			(xy 106.079519 -355.180502) (xy 106.102161 -355.130925) (xy 106.131627 -355.085075) (xy 106.167318 -355.043884)
			(xy 106.208509 -355.008193) (xy 106.254359 -354.978727) (xy 106.303936 -354.956085) (xy 106.356231 -354.94073)
			(xy 106.410179 -354.932974) (xy 106.464681 -354.932974) (xy 106.518629 -354.94073) (xy 106.570924 -354.956085)
			(xy 106.620501 -354.978727) (xy 106.666351 -355.008193) (xy 106.707542 -355.043884) (xy 106.743233 -355.085075)
			(xy 106.772699 -355.130925) (xy 106.795341 -355.180502) (xy 106.810696 -355.232797) (xy 106.818452 -355.286745)
			(xy 106.818938 -355.313996) (xy 106.818455 -355.342566) (xy 106.809941 -355.399069) (xy 106.793088 -355.453667)
			(xy 106.768274 -355.505138) (xy 106.736054 -355.552329) (xy 106.697152 -355.594181) (xy 106.652438 -355.629757)
			(xy 106.62793 -355.64445) (xy 106.616417 -355.651599) (xy 106.59736 -355.670853) (xy 106.58403 -355.694437)
			(xy 106.577363 -355.720694) (xy 106.577827 -355.747781) (xy 106.585391 -355.773795) (xy 106.599522 -355.796908)
			(xy 106.619228 -355.815497) (xy 106.630978 -355.82225) (xy 106.65669 -355.836645) (xy 106.703806 -355.872029)
			(xy 106.744919 -355.914239) (xy 106.779048 -355.962272) (xy 106.805383 -356.014982) (xy 106.823295 -356.071117)
			(xy 106.832359 -356.129338) (xy 106.832908 -356.1588) (xy 106.832422 -356.186051) (xy 106.824666 -356.239999)
			(xy 106.809311 -356.292294) (xy 106.786669 -356.341871) (xy 106.757203 -356.387721) (xy 106.721512 -356.428912)
			(xy 106.680321 -356.464603) (xy 106.634471 -356.494069) (xy 106.584894 -356.516711) (xy 106.532599 -356.532066)
			(xy 106.478651 -356.539822) (xy 106.424149 -356.539822) (xy 106.370201 -356.532066) (xy 106.317906 -356.516711)
			(xy 106.268329 -356.494069) (xy 106.222479 -356.464603) (xy 106.181288 -356.428912) (xy 106.145597 -356.387721)
			(xy 106.116131 -356.341871) (xy 106.093489 -356.292294) (xy 106.078134 -356.239999) (xy 106.070378 -356.186051)
			(xy 106.069892 -356.1588) (xy 106.070357 -356.130229) (xy 106.078872 -356.073725) (xy 106.095727 -356.019125)
			(xy 106.120544 -355.967654) (xy 106.152767 -355.920463) (xy 106.191673 -355.878612) (xy 106.236391 -355.843038)
			(xy 106.2609 -355.828346) (xy 106.272424 -355.821209) (xy 106.291495 -355.801958) (xy 106.304835 -355.778371)
			(xy 106.311507 -355.752107) (xy 106.311041 -355.725013) (xy 106.303471 -355.698994) (xy 106.289329 -355.67588)
			(xy 106.269608 -355.657295) (xy 106.257852 -355.650546) (xy 106.232122 -355.636182) (xy 106.185009 -355.60079)
			(xy 106.1439 -355.558573) (xy 106.109774 -355.510535) (xy 106.083443 -355.45782) (xy 106.065533 -355.401683)
			(xy 106.05647 -355.343459) (xy 106.055922 -355.313996) (xy 101.483114 -355.313996) (xy 101.511499 -355.3569)
			(xy 101.535171 -355.407397) (xy 101.551239 -355.460804) (xy 101.559359 -355.51598) (xy 101.559868 -355.543866)
			(xy 101.559359 -355.571752) (xy 101.551239 -355.626928) (xy 101.535171 -355.680335) (xy 101.511499 -355.730832)
			(xy 101.480726 -355.777345) (xy 101.443509 -355.818882) (xy 101.400641 -355.854557) (xy 101.353035 -355.883611)
			(xy 101.301706 -355.905423) (xy 101.247749 -355.919529) (xy 101.192312 -355.925629) (xy 101.136578 -355.923592)
			(xy 101.081735 -355.913462) (xy 101.028951 -355.895455) (xy 100.979351 -355.869954) (xy 100.933993 -355.837503)
			(xy 100.893844 -355.798794) (xy 100.859758 -355.754651) (xy 100.832462 -355.706016) (xy 100.812539 -355.653925)
			(xy 100.800413 -355.599488) (xy 100.796342 -355.543866) (xy 57.559216 -355.543866) (xy 57.548851 -355.554246)
			(xy 57.54121 -355.572728) (xy 57.540652 -355.582728) (xy 57.540652 -356.221284) (xy 103.80167 -356.221284)
			(xy 103.805741 -356.165662) (xy 103.817867 -356.111225) (xy 103.83779 -356.059134) (xy 103.865086 -356.010499)
			(xy 103.899172 -355.966356) (xy 103.939321 -355.927647) (xy 103.984679 -355.895196) (xy 104.034279 -355.869695)
			(xy 104.087063 -355.851688) (xy 104.141906 -355.841558) (xy 104.19764 -355.839521) (xy 104.253077 -355.845621)
			(xy 104.307034 -355.859727) (xy 104.358363 -355.881539) (xy 104.405969 -355.910593) (xy 104.448837 -355.946268)
			(xy 104.486054 -355.987805) (xy 104.516827 -356.034318) (xy 104.540499 -356.084815) (xy 104.556567 -356.138222)
			(xy 104.564687 -356.193398) (xy 104.565196 -356.221284) (xy 104.564687 -356.24917) (xy 104.556567 -356.304346)
			(xy 104.540499 -356.357753) (xy 104.516827 -356.40825) (xy 104.486054 -356.454763) (xy 104.448837 -356.4963)
			(xy 104.405969 -356.531975) (xy 104.358363 -356.561029) (xy 104.307034 -356.582841) (xy 104.253077 -356.596947)
			(xy 104.19764 -356.603047) (xy 104.141906 -356.60101) (xy 104.087063 -356.59088) (xy 104.034279 -356.572873)
			(xy 103.984679 -356.547372) (xy 103.939321 -356.514921) (xy 103.899172 -356.476212) (xy 103.865086 -356.432069)
			(xy 103.83779 -356.383434) (xy 103.817867 -356.331343) (xy 103.805741 -356.276906) (xy 103.80167 -356.221284)
			(xy 57.540652 -356.221284) (xy 57.540652 -357.784969) (xy 64.099931 -357.784969) (xy 64.099931 -357.730431)
			(xy 64.107693 -357.676448) (xy 64.123058 -357.62412) (xy 64.145714 -357.57451) (xy 64.1752 -357.52863)
			(xy 64.210914 -357.487413) (xy 64.252132 -357.451698) (xy 64.298012 -357.422213) (xy 64.347621 -357.399557)
			(xy 64.39995 -357.384193) (xy 64.453933 -357.376431) (xy 64.481202 -357.375968) (xy 65.344802 -357.375968)
			(xy 65.372073 -357.376395) (xy 65.426061 -357.384157) (xy 65.478394 -357.399524) (xy 65.528008 -357.422182)
			(xy 65.573893 -357.45167) (xy 65.615113 -357.487388) (xy 65.650831 -357.528609) (xy 65.680319 -357.574493)
			(xy 65.702977 -357.624107) (xy 65.718343 -357.676441) (xy 65.726106 -357.730429) (xy 65.726106 -357.784966)
			(xy 67.208954 -357.784966) (xy 67.208954 -357.730435) (xy 67.216714 -357.676458) (xy 67.232077 -357.624136)
			(xy 67.254728 -357.574532) (xy 67.284208 -357.528657) (xy 67.319917 -357.487443) (xy 67.361126 -357.451731)
			(xy 67.406999 -357.422246) (xy 67.4566 -357.39959) (xy 67.508921 -357.384222) (xy 67.562897 -357.376457)
			(xy 67.590162 -357.375968) (xy 68.453762 -357.375968) (xy 68.481037 -357.376369) (xy 68.535032 -357.384127)
			(xy 68.587373 -357.399491) (xy 68.636995 -357.422149) (xy 68.682887 -357.451638) (xy 68.724115 -357.487358)
			(xy 68.75984 -357.528582) (xy 68.789333 -357.574471) (xy 68.811995 -357.624091) (xy 68.827365 -357.676431)
			(xy 68.835128 -357.730425) (xy 68.835128 -357.78497) (xy 70.317831 -357.78497) (xy 70.317831 -357.73043)
			(xy 70.325594 -357.676446) (xy 70.34096 -357.624115) (xy 70.363617 -357.574505) (xy 70.393105 -357.528623)
			(xy 70.428822 -357.487406) (xy 70.470041 -357.451691) (xy 70.515924 -357.422207) (xy 70.565536 -357.399552)
			(xy 70.617867 -357.384189) (xy 70.671852 -357.37643) (xy 70.699122 -357.375968) (xy 71.562722 -357.375968)
			(xy 71.589992 -357.376396) (xy 71.643978 -357.384161) (xy 71.696309 -357.399529) (xy 71.74592 -357.422189)
			(xy 71.791802 -357.451677) (xy 71.83302 -357.487395) (xy 71.868736 -357.528616) (xy 71.898222 -357.574499)
			(xy 71.920878 -357.624112) (xy 71.936244 -357.676444) (xy 71.944006 -357.730429) (xy 71.944006 -357.784966)
			(xy 73.426854 -357.784966) (xy 73.426854 -357.730434) (xy 73.434615 -357.676456) (xy 73.449978 -357.624132)
			(xy 73.472631 -357.574527) (xy 73.502113 -357.52865) (xy 73.537824 -357.487436) (xy 73.579036 -357.451724)
			(xy 73.624911 -357.42224) (xy 73.674515 -357.399584) (xy 73.726838 -357.384219) (xy 73.780816 -357.376456)
			(xy 73.808082 -357.375968) (xy 74.671682 -357.375968) (xy 74.698956 -357.37637) (xy 74.752949 -357.384131)
			(xy 74.805288 -357.399497) (xy 74.854907 -357.422155) (xy 74.900797 -357.451645) (xy 74.942022 -357.487365)
			(xy 74.977744 -357.528589) (xy 75.007236 -357.574477) (xy 75.029897 -357.624095) (xy 75.045265 -357.676433)
			(xy 75.053028 -357.730426) (xy 75.053028 -357.784971) (xy 76.535732 -357.784971) (xy 76.535732 -357.730429)
			(xy 76.543494 -357.676443) (xy 76.558861 -357.624111) (xy 76.58152 -357.574499) (xy 76.611009 -357.528617)
			(xy 76.646729 -357.487399) (xy 76.687951 -357.451684) (xy 76.733836 -357.4222) (xy 76.78345 -357.399547)
			(xy 76.835784 -357.384185) (xy 76.889771 -357.376429) (xy 76.917042 -357.375968) (xy 77.780642 -357.375968)
			(xy 77.807912 -357.376397) (xy 77.861895 -357.384165) (xy 77.914223 -357.399535) (xy 77.963832 -357.422195)
			(xy 78.009711 -357.451684) (xy 78.050927 -357.487402) (xy 78.086641 -357.528622) (xy 78.116125 -357.574505)
			(xy 78.13878 -357.624116) (xy 78.154144 -357.676446) (xy 78.161906 -357.73043) (xy 78.161906 -357.784969)
			(xy 79.644731 -357.784969) (xy 79.644731 -357.730431) (xy 79.652493 -357.676448) (xy 79.667858 -357.62412)
			(xy 79.690514 -357.57451) (xy 79.72 -357.52863) (xy 79.755714 -357.487413) (xy 79.796932 -357.451698)
			(xy 79.842812 -357.422213) (xy 79.892421 -357.399557) (xy 79.94475 -357.384193) (xy 79.998733 -357.376431)
			(xy 80.026002 -357.375968) (xy 80.889602 -357.375968) (xy 80.916873 -357.376395) (xy 80.970861 -357.384157)
			(xy 81.023194 -357.399524) (xy 81.072808 -357.422182) (xy 81.118693 -357.45167) (xy 81.159913 -357.487388)
			(xy 81.195631 -357.528609) (xy 81.225119 -357.574493) (xy 81.247777 -357.624107) (xy 81.263143 -357.676441)
			(xy 81.270906 -357.730429) (xy 81.270906 -357.784966) (xy 82.753754 -357.784966) (xy 82.753754 -357.730435)
			(xy 82.761514 -357.676458) (xy 82.776877 -357.624136) (xy 82.799528 -357.574532) (xy 82.829008 -357.528657)
			(xy 82.864717 -357.487443) (xy 82.905926 -357.451731) (xy 82.951799 -357.422246) (xy 83.0014 -357.39959)
			(xy 83.053721 -357.384222) (xy 83.107697 -357.376457) (xy 83.134962 -357.375968) (xy 83.998562 -357.375968)
			(xy 84.025837 -357.376369) (xy 84.079832 -357.384127) (xy 84.132173 -357.399491) (xy 84.181795 -357.422149)
			(xy 84.227687 -357.451638) (xy 84.268915 -357.487358) (xy 84.30464 -357.528582) (xy 84.334133 -357.574471)
			(xy 84.356795 -357.624091) (xy 84.372165 -357.676431) (xy 84.379928 -357.730425) (xy 84.379928 -357.78497)
			(xy 85.862631 -357.78497) (xy 85.862631 -357.73043) (xy 85.870394 -357.676446) (xy 85.88576 -357.624115)
			(xy 85.908417 -357.574505) (xy 85.937905 -357.528623) (xy 85.973622 -357.487406) (xy 86.014841 -357.451691)
			(xy 86.060724 -357.422207) (xy 86.110336 -357.399552) (xy 86.162667 -357.384189) (xy 86.216652 -357.37643)
			(xy 86.243922 -357.375968) (xy 87.107522 -357.375968) (xy 87.134792 -357.376396) (xy 87.188778 -357.384161)
			(xy 87.241109 -357.399529) (xy 87.29072 -357.422189) (xy 87.336602 -357.451677) (xy 87.37782 -357.487395)
			(xy 87.413536 -357.528616) (xy 87.443022 -357.574499) (xy 87.465678 -357.624112) (xy 87.481044 -357.676444)
			(xy 87.488806 -357.730429) (xy 87.488806 -357.784966) (xy 88.971654 -357.784966) (xy 88.971654 -357.730434)
			(xy 88.979415 -357.676456) (xy 88.994778 -357.624132) (xy 89.017431 -357.574527) (xy 89.046913 -357.52865)
			(xy 89.082624 -357.487436) (xy 89.123836 -357.451724) (xy 89.169711 -357.42224) (xy 89.219315 -357.399584)
			(xy 89.271638 -357.384219) (xy 89.325616 -357.376456) (xy 89.352882 -357.375968) (xy 90.216482 -357.375968)
			(xy 90.243756 -357.37637) (xy 90.297749 -357.384131) (xy 90.350088 -357.399497) (xy 90.399707 -357.422155)
			(xy 90.445597 -357.451645) (xy 90.486822 -357.487365) (xy 90.522544 -357.528589) (xy 90.552036 -357.574477)
			(xy 90.574697 -357.624095) (xy 90.590065 -357.676433) (xy 90.597828 -357.730426) (xy 90.597828 -357.784971)
			(xy 92.080532 -357.784971) (xy 92.080532 -357.730429) (xy 92.088294 -357.676443) (xy 92.103661 -357.624111)
			(xy 92.12632 -357.574499) (xy 92.155809 -357.528617) (xy 92.191529 -357.487399) (xy 92.232751 -357.451684)
			(xy 92.278636 -357.4222) (xy 92.32825 -357.399547) (xy 92.380584 -357.384185) (xy 92.434571 -357.376429)
			(xy 92.461842 -357.375968) (xy 93.325442 -357.375968) (xy 93.352712 -357.376397) (xy 93.406695 -357.384165)
			(xy 93.459023 -357.399535) (xy 93.508632 -357.422195) (xy 93.554511 -357.451684) (xy 93.595727 -357.487402)
			(xy 93.631441 -357.528622) (xy 93.660925 -357.574505) (xy 93.68358 -357.624116) (xy 93.698944 -357.676446)
			(xy 93.706706 -357.73043) (xy 93.706706 -357.78497) (xy 93.698944 -357.838954) (xy 93.68358 -357.891284)
			(xy 93.660925 -357.940895) (xy 93.631441 -357.986778) (xy 93.595727 -358.027998) (xy 93.554511 -358.063716)
			(xy 93.508632 -358.093205) (xy 93.459023 -358.115865) (xy 93.406695 -358.131235) (xy 93.352712 -358.139003)
			(xy 93.325442 -358.139492) (xy 92.461842 -358.139492) (xy 92.434571 -358.138971) (xy 92.380584 -358.131215)
			(xy 92.32825 -358.115853) (xy 92.278636 -358.0932) (xy 92.23275 -358.063716) (xy 92.191529 -358.028001)
			(xy 92.155809 -357.986783) (xy 92.12632 -357.940901) (xy 92.103661 -357.891289) (xy 92.088294 -357.838957)
			(xy 92.080532 -357.784971) (xy 90.597828 -357.784971) (xy 90.597828 -357.784974) (xy 90.590065 -357.838967)
			(xy 90.574697 -357.891305) (xy 90.552036 -357.940923) (xy 90.522544 -357.986811) (xy 90.486822 -358.028035)
			(xy 90.445597 -358.063755) (xy 90.399707 -358.093245) (xy 90.350088 -358.115903) (xy 90.297749 -358.131269)
			(xy 90.243756 -358.13903) (xy 90.216482 -358.139492) (xy 89.352882 -358.139492) (xy 89.325616 -358.138944)
			(xy 89.271638 -358.131181) (xy 89.219315 -358.115816) (xy 89.169711 -358.09316) (xy 89.123836 -358.063676)
			(xy 89.082624 -358.027964) (xy 89.046913 -357.98675) (xy 89.017431 -357.940873) (xy 88.994778 -357.891268)
			(xy 88.979415 -357.838944) (xy 88.971654 -357.784966) (xy 87.488806 -357.784966) (xy 87.488806 -357.784971)
			(xy 87.481044 -357.838956) (xy 87.465678 -357.891288) (xy 87.443022 -357.940901) (xy 87.413536 -357.986784)
			(xy 87.37782 -358.028005) (xy 87.336602 -358.063723) (xy 87.29072 -358.093211) (xy 87.241109 -358.115871)
			(xy 87.188778 -358.131239) (xy 87.134792 -358.139004) (xy 87.107522 -358.139492) (xy 86.243922 -358.139492)
			(xy 86.216652 -358.13897) (xy 86.162667 -358.131211) (xy 86.110336 -358.115848) (xy 86.060724 -358.093193)
			(xy 86.014841 -358.063709) (xy 85.973622 -358.027994) (xy 85.937905 -357.986777) (xy 85.908417 -357.940895)
			(xy 85.88576 -357.891285) (xy 85.870394 -357.838954) (xy 85.862631 -357.78497) (xy 84.379928 -357.78497)
			(xy 84.379928 -357.784975) (xy 84.372165 -357.838969) (xy 84.356795 -357.891309) (xy 84.334133 -357.940929)
			(xy 84.30464 -357.986818) (xy 84.268915 -358.028042) (xy 84.227687 -358.063762) (xy 84.181795 -358.093251)
			(xy 84.132173 -358.115908) (xy 84.079832 -358.131273) (xy 84.025837 -358.139031) (xy 83.998562 -358.139492)
			(xy 83.134962 -358.139492) (xy 83.107697 -358.138943) (xy 83.053721 -358.131178) (xy 83.0014 -358.11581)
			(xy 82.951799 -358.093154) (xy 82.905926 -358.063669) (xy 82.864717 -358.027957) (xy 82.829008 -357.986743)
			(xy 82.799528 -357.940868) (xy 82.776877 -357.891264) (xy 82.761514 -357.838942) (xy 82.753754 -357.784966)
			(xy 81.270906 -357.784966) (xy 81.270906 -357.784971) (xy 81.263143 -357.838959) (xy 81.247777 -357.891293)
			(xy 81.225119 -357.940907) (xy 81.195631 -357.986791) (xy 81.159913 -358.028012) (xy 81.118693 -358.06373)
			(xy 81.072808 -358.093218) (xy 81.023194 -358.115876) (xy 80.970861 -358.131243) (xy 80.916873 -358.139005)
			(xy 80.889602 -358.139492) (xy 80.026002 -358.139492) (xy 79.998733 -358.138969) (xy 79.94475 -358.131207)
			(xy 79.892421 -358.115843) (xy 79.842812 -358.093187) (xy 79.796932 -358.063702) (xy 79.755714 -358.027987)
			(xy 79.72 -357.98677) (xy 79.690514 -357.94089) (xy 79.667858 -357.89128) (xy 79.652493 -357.838952)
			(xy 79.644731 -357.784969) (xy 78.161906 -357.784969) (xy 78.161906 -357.78497) (xy 78.154144 -357.838954)
			(xy 78.13878 -357.891284) (xy 78.116125 -357.940895) (xy 78.086641 -357.986778) (xy 78.050927 -358.027998)
			(xy 78.009711 -358.063716) (xy 77.963832 -358.093205) (xy 77.914223 -358.115865) (xy 77.861895 -358.131235)
			(xy 77.807912 -358.139003) (xy 77.780642 -358.139492) (xy 76.917042 -358.139492) (xy 76.889771 -358.138971)
			(xy 76.835784 -358.131215) (xy 76.78345 -358.115853) (xy 76.733836 -358.0932) (xy 76.68795 -358.063716)
			(xy 76.646729 -358.028001) (xy 76.611009 -357.986783) (xy 76.58152 -357.940901) (xy 76.558861 -357.891289)
			(xy 76.543494 -357.838957) (xy 76.535732 -357.784971) (xy 75.053028 -357.784971) (xy 75.053028 -357.784974)
			(xy 75.045265 -357.838967) (xy 75.029897 -357.891305) (xy 75.007236 -357.940923) (xy 74.977744 -357.986811)
			(xy 74.942022 -358.028035) (xy 74.900797 -358.063755) (xy 74.854907 -358.093245) (xy 74.805288 -358.115903)
			(xy 74.752949 -358.131269) (xy 74.698956 -358.13903) (xy 74.671682 -358.139492) (xy 73.808082 -358.139492)
			(xy 73.780816 -358.138944) (xy 73.726838 -358.131181) (xy 73.674515 -358.115816) (xy 73.624911 -358.09316)
			(xy 73.579036 -358.063676) (xy 73.537824 -358.027964) (xy 73.502113 -357.98675) (xy 73.472631 -357.940873)
			(xy 73.449978 -357.891268) (xy 73.434615 -357.838944) (xy 73.426854 -357.784966) (xy 71.944006 -357.784966)
			(xy 71.944006 -357.784971) (xy 71.936244 -357.838956) (xy 71.920878 -357.891288) (xy 71.898222 -357.940901)
			(xy 71.868736 -357.986784) (xy 71.83302 -358.028005) (xy 71.791802 -358.063723) (xy 71.74592 -358.093211)
			(xy 71.696309 -358.115871) (xy 71.643978 -358.131239) (xy 71.589992 -358.139004) (xy 71.562722 -358.139492)
			(xy 70.699122 -358.139492) (xy 70.671852 -358.13897) (xy 70.617867 -358.131211) (xy 70.565536 -358.115848)
			(xy 70.515924 -358.093193) (xy 70.470041 -358.063709) (xy 70.428822 -358.027994) (xy 70.393105 -357.986777)
			(xy 70.363617 -357.940895) (xy 70.34096 -357.891285) (xy 70.325594 -357.838954) (xy 70.317831 -357.78497)
			(xy 68.835128 -357.78497) (xy 68.835128 -357.784975) (xy 68.827365 -357.838969) (xy 68.811995 -357.891309)
			(xy 68.789333 -357.940929) (xy 68.75984 -357.986818) (xy 68.724115 -358.028042) (xy 68.682887 -358.063762)
			(xy 68.636995 -358.093251) (xy 68.587373 -358.115908) (xy 68.535032 -358.131273) (xy 68.481037 -358.139031)
			(xy 68.453762 -358.139492) (xy 67.590162 -358.139492) (xy 67.562897 -358.138943) (xy 67.508921 -358.131178)
			(xy 67.4566 -358.11581) (xy 67.406999 -358.093154) (xy 67.361126 -358.063669) (xy 67.319917 -358.027957)
			(xy 67.284208 -357.986743) (xy 67.254728 -357.940868) (xy 67.232077 -357.891264) (xy 67.216714 -357.838942)
			(xy 67.208954 -357.784966) (xy 65.726106 -357.784966) (xy 65.726106 -357.784971) (xy 65.718343 -357.838959)
			(xy 65.702977 -357.891293) (xy 65.680319 -357.940907) (xy 65.650831 -357.986791) (xy 65.615113 -358.028012)
			(xy 65.573893 -358.06373) (xy 65.528008 -358.093218) (xy 65.478394 -358.115876) (xy 65.426061 -358.131243)
			(xy 65.372073 -358.139005) (xy 65.344802 -358.139492) (xy 64.481202 -358.139492) (xy 64.453933 -358.138969)
			(xy 64.39995 -358.131207) (xy 64.347621 -358.115843) (xy 64.298012 -358.093187) (xy 64.252132 -358.063702)
			(xy 64.210914 -358.027987) (xy 64.1752 -357.98677) (xy 64.145714 -357.94089) (xy 64.123058 -357.89128)
			(xy 64.107693 -357.838952) (xy 64.099931 -357.784969) (xy 57.540652 -357.784969) (xy 57.540652 -360.017783)
			(xy 101.774757 -360.017783) (xy 101.774757 -359.957817) (xy 101.782584 -359.898365) (xy 101.798104 -359.840443)
			(xy 101.821052 -359.785042) (xy 101.851035 -359.733111) (xy 101.88754 -359.685538) (xy 101.929942 -359.643136)
			(xy 101.977516 -359.606632) (xy 102.029448 -359.57665) (xy 102.084849 -359.553703) (xy 102.142771 -359.538183)
			(xy 102.202223 -359.530357) (xy 102.232206 -359.529888) (xy 103.095806 -359.529888) (xy 103.125793 -359.530279)
			(xy 103.185255 -359.538108) (xy 103.243186 -359.553631) (xy 103.298595 -359.576583) (xy 103.350534 -359.60657)
			(xy 103.398115 -359.643081) (xy 103.440523 -359.68549) (xy 103.477033 -359.733071) (xy 103.50702 -359.785011)
			(xy 103.529971 -359.84042) (xy 103.545494 -359.898351) (xy 103.553322 -359.957813) (xy 103.553322 -360.017787)
			(xy 103.545494 -360.077249) (xy 103.529971 -360.13518) (xy 103.50702 -360.190589) (xy 103.477033 -360.242529)
			(xy 103.440523 -360.29011) (xy 103.398115 -360.332519) (xy 103.350534 -360.36903) (xy 103.298595 -360.399017)
			(xy 103.243186 -360.421969) (xy 103.185255 -360.437492) (xy 103.125793 -360.445321) (xy 103.095806 -360.445812)
			(xy 102.232206 -360.445812) (xy 102.202223 -360.445243) (xy 102.142771 -360.437417) (xy 102.084849 -360.421897)
			(xy 102.029448 -360.39895) (xy 101.977516 -360.368968) (xy 101.929942 -360.332464) (xy 101.88754 -360.290062)
			(xy 101.851035 -360.242489) (xy 101.821052 -360.190558) (xy 101.798104 -360.135157) (xy 101.782584 -360.077235)
			(xy 101.774757 -360.017783) (xy 57.540652 -360.017783) (xy 57.540652 -361.5944) (xy 99.489292 -361.5944)
			(xy 99.493275 -361.541253) (xy 99.505134 -361.489292) (xy 99.524605 -361.43968) (xy 99.551252 -361.393523)
			(xy 99.58448 -361.351854) (xy 99.623548 -361.315602) (xy 99.667582 -361.285577) (xy 99.7156 -361.26245)
			(xy 99.766527 -361.246738) (xy 99.819228 -361.238791) (xy 99.845876 -361.238292) (xy 99.872284 -361.238789)
			(xy 99.924522 -361.246586) (xy 99.975035 -361.262015) (xy 100.022714 -361.284735) (xy 100.066515 -361.314249)
			(xy 100.105476 -361.349909) (xy 100.122482 -361.370118) (xy 100.130063 -361.378668) (xy 100.150689 -361.388452)
			(xy 100.162106 -361.388914) (xy 100.240846 -361.388914) (xy 100.252228 -361.388292) (xy 100.272798 -361.378547)
			(xy 100.28047 -361.370118) (xy 100.297489 -361.349919) (xy 100.336446 -361.314256) (xy 100.380244 -361.284738)
			(xy 100.427921 -361.262012) (xy 100.478432 -361.246578) (xy 100.530668 -361.238773) (xy 100.557076 -361.238292)
			(xy 100.583728 -361.238764) (xy 100.636438 -361.246705) (xy 100.687375 -361.262414) (xy 100.735402 -361.28554)
			(xy 100.779446 -361.315565) (xy 100.818522 -361.35182) (xy 100.851758 -361.393494) (xy 100.878411 -361.439657)
			(xy 100.897886 -361.489276) (xy 100.909748 -361.541244) (xy 100.913732 -361.5944) (xy 100.909748 -361.647556)
			(xy 100.897886 -361.699524) (xy 100.878411 -361.749143) (xy 100.851758 -361.795306) (xy 100.818522 -361.83698)
			(xy 100.779446 -361.873235) (xy 100.735402 -361.90326) (xy 100.687375 -361.926386) (xy 100.636438 -361.942095)
			(xy 100.583728 -361.950036) (xy 100.557076 -361.950508) (xy 100.530667 -361.950046) (xy 100.478427 -361.942241)
			(xy 100.427914 -361.926806) (xy 100.380234 -361.904079) (xy 100.336434 -361.874559) (xy 100.297475 -361.838894)
			(xy 100.28047 -361.818682) (xy 100.272909 -361.81011) (xy 100.252268 -361.800338) (xy 100.240846 -361.799886)
			(xy 100.162106 -361.799886) (xy 100.150721 -361.80048) (xy 100.130151 -361.810245) (xy 100.122482 -361.818682)
			(xy 100.105489 -361.838904) (xy 100.066527 -361.874566) (xy 100.022724 -361.904081) (xy 99.975041 -361.926803)
			(xy 99.924526 -361.942232) (xy 99.872286 -361.95003) (xy 99.845876 -361.950508) (xy 99.819228 -361.950009)
			(xy 99.766527 -361.942062) (xy 99.7156 -361.92635) (xy 99.667582 -361.903223) (xy 99.623548 -361.873198)
			(xy 99.58448 -361.836946) (xy 99.551252 -361.795277) (xy 99.524605 -361.74912) (xy 99.505134 -361.699508)
			(xy 99.493275 -361.647547) (xy 99.489292 -361.5944) (xy 57.540652 -361.5944) (xy 57.540652 -363.506258)
			(xy 57.541087 -363.516322) (xy 57.548822 -363.534907) (xy 57.555638 -363.542326) (xy 60.259976 -366.246664)
			(xy 60.267377 -366.253502) (xy 60.285976 -366.261215) (xy 60.296044 -366.26165)
		)
		(stroke
			(width 0)
			(type solid)
		)
		(fill yes)
		(layer "In15.Cu")
		(net "GND")
	)
	(gr_poly
		(pts
			(xy 193.28384 -414.117282) (xy 193.297456 -414.116843) (xy 193.323718 -414.109639) (xy 193.347143 -414.095752)
			(xy 193.366067 -414.07617) (xy 193.379146 -414.052285) (xy 193.38545 -414.025792) (xy 193.384532 -413.998576)
			(xy 193.380868 -413.985456) (xy 193.372706 -413.957652) (xy 193.363902 -413.900381) (xy 193.363342 -413.87141)
			(xy 193.363828 -413.844141) (xy 193.37159 -413.790157) (xy 193.386955 -413.737827) (xy 193.409612 -413.688217)
			(xy 193.439098 -413.642336) (xy 193.474813 -413.601119) (xy 193.51603 -413.565404) (xy 193.561911 -413.535918)
			(xy 193.611521 -413.513261) (xy 193.663851 -413.497896) (xy 193.717835 -413.490134) (xy 193.772373 -413.490134)
			(xy 193.826357 -413.497896) (xy 193.878687 -413.513261) (xy 193.928297 -413.535918) (xy 193.974178 -413.565404)
			(xy 194.015395 -413.601119) (xy 194.05111 -413.642336) (xy 194.080596 -413.688217) (xy 194.103253 -413.737827)
			(xy 194.118618 -413.790157) (xy 194.12638 -413.844141) (xy 194.126866 -413.87141) (xy 194.12631 -413.900382)
			(xy 194.117508 -413.957654) (xy 194.10934 -413.985456) (xy 194.105701 -413.998585) (xy 194.104757 -414.025804)
			(xy 194.111045 -414.052303) (xy 194.12412 -414.076194) (xy 194.143047 -414.095777) (xy 194.166481 -414.109655)
			(xy 194.19275 -414.116841) (xy 194.206368 -414.117282) (xy 203.125578 -414.117282) (xy 203.13396 -414.11652)
			(xy 203.141568 -414.115011) (xy 203.155411 -414.108034) (xy 203.161138 -414.102804) (xy 203.785724 -413.478218)
			(xy 203.792566 -413.470819) (xy 203.800282 -413.45222) (xy 203.80071 -413.44215) (xy 203.80071 -396.301214)
			(xy 203.800152 -396.290589) (xy 203.791535 -396.271163) (xy 203.775806 -396.256873) (xy 203.765912 -396.252954)
			(xy 203.674218 -396.222728) (xy 203.664001 -396.21991) (xy 203.642924 -396.221891) (xy 203.624406 -396.232152)
			(xy 203.617576 -396.240254) (xy 203.617576 -396.240508) (xy 203.55628 -396.321997) (xy 203.428229 -396.480719)
			(xy 203.294121 -396.634357) (xy 203.154157 -396.78268) (xy 203.008548 -396.925465) (xy 202.857512 -397.062497)
			(xy 202.701277 -397.19357) (xy 202.540077 -397.318488) (xy 202.374156 -397.437061) (xy 202.203762 -397.549112)
			(xy 202.029151 -397.654473) (xy 201.850587 -397.752984) (xy 201.668338 -397.844498) (xy 201.482677 -397.928877)
			(xy 201.293885 -398.005995) (xy 201.102245 -398.075735) (xy 200.908045 -398.137992) (xy 200.711577 -398.192673)
			(xy 200.513137 -398.239695) (xy 200.313023 -398.278988) (xy 200.111535 -398.310493) (xy 199.908978 -398.334163)
			(xy 199.705656 -398.349961) (xy 199.501874 -398.357864) (xy 199.399906 -398.35836) (xy 199.297931 -398.357866)
			(xy 199.094134 -398.349957) (xy 198.890797 -398.334152) (xy 198.688226 -398.310475) (xy 198.486725 -398.278961)
			(xy 198.286597 -398.239657) (xy 198.088145 -398.192623) (xy 197.891665 -398.137929) (xy 197.697453 -398.075657)
			(xy 197.505803 -398.005902) (xy 197.317001 -397.928768) (xy 197.131332 -397.844371) (xy 196.949076 -397.752838)
			(xy 196.770505 -397.654307) (xy 196.59589 -397.548926) (xy 196.425492 -397.436853) (xy 196.259568 -397.318258)
			(xy 196.098367 -397.193317) (xy 195.942132 -397.062221) (xy 195.791098 -396.925164) (xy 195.645492 -396.782355)
			(xy 195.505533 -396.634007) (xy 195.371431 -396.480343) (xy 195.243388 -396.321595) (xy 195.121598 -396.158002)
			(xy 195.006242 -395.989809) (xy 194.897495 -395.81727) (xy 194.79552 -395.640644) (xy 194.70047 -395.460196)
			(xy 194.612489 -395.276199) (xy 194.531708 -395.088928) (xy 194.45825 -394.898666) (xy 194.392224 -394.705699)
			(xy 194.333731 -394.510317) (xy 194.282857 -394.312813) (xy 194.23968 -394.113486) (xy 194.204264 -393.912634)
			(xy 194.176664 -393.71056) (xy 194.156919 -393.507567) (xy 194.14506 -393.303962) (xy 194.141105 -393.10005)
			(xy 194.14506 -392.896138) (xy 194.156919 -392.692533) (xy 194.176664 -392.48954) (xy 194.204264 -392.287466)
			(xy 194.23968 -392.086614) (xy 194.282857 -391.887287) (xy 194.333731 -391.689783) (xy 194.392224 -391.494401)
			(xy 194.45825 -391.301434) (xy 194.531708 -391.111172) (xy 194.612489 -390.923901) (xy 194.70047 -390.739904)
			(xy 194.79552 -390.559456) (xy 194.897495 -390.38283) (xy 195.006242 -390.210291) (xy 195.121598 -390.042098)
			(xy 195.243388 -389.878505) (xy 195.371431 -389.719757) (xy 195.505533 -389.566093) (xy 195.645492 -389.417745)
			(xy 195.791098 -389.274936) (xy 195.942132 -389.137879) (xy 196.098367 -389.006783) (xy 196.259568 -388.881842)
			(xy 196.425492 -388.763247) (xy 196.59589 -388.651174) (xy 196.770505 -388.545793) (xy 196.949076 -388.447262)
			(xy 197.131332 -388.355729) (xy 197.317001 -388.271332) (xy 197.505803 -388.194198) (xy 197.697453 -388.124443)
			(xy 197.891665 -388.062171) (xy 198.088145 -388.007477) (xy 198.286597 -387.960443) (xy 198.486725 -387.921139)
			(xy 198.688226 -387.889625) (xy 198.890797 -387.865948) (xy 199.094134 -387.850143) (xy 199.297931 -387.842234)
			(xy 199.399906 -387.841744) (xy 199.501874 -387.842238) (xy 199.705656 -387.850145) (xy 199.908978 -387.865946)
			(xy 200.111535 -387.889618) (xy 200.313022 -387.921125) (xy 200.513136 -387.96042) (xy 200.711576 -388.007444)
			(xy 200.908043 -388.062125) (xy 201.102243 -388.124383) (xy 201.293884 -388.194122) (xy 201.482676 -388.271239)
			(xy 201.668337 -388.355618) (xy 201.850587 -388.44713) (xy 202.029152 -388.54564) (xy 202.203764 -388.650999)
			(xy 202.37416 -388.763047) (xy 202.540083 -388.881618) (xy 202.701285 -389.006532) (xy 202.857523 -389.137602)
			(xy 203.008562 -389.274631) (xy 203.154175 -389.417412) (xy 203.294143 -389.565732) (xy 203.428255 -389.719366)
			(xy 203.556311 -389.878084) (xy 203.617576 -389.959596) (xy 203.617576 -389.95985) (xy 203.624384 -389.967985)
			(xy 203.642896 -389.978295) (xy 203.663997 -389.980222) (xy 203.674218 -389.977376) (xy 203.765912 -389.94715)
			(xy 203.77584 -389.943291) (xy 203.791592 -389.928991) (xy 203.800185 -389.909529) (xy 203.80071 -389.89889)
			(xy 203.80071 -376.042428) (xy 203.800037 -376.03036) (xy 203.789026 -376.008882) (xy 203.779628 -376.00128)
			(xy 203.712318 -375.95302) (xy 203.707318 -375.949664) (xy 203.696153 -375.94516) (xy 203.69022 -375.94413)
			(xy 203.682346 -375.94286) (xy 203.669646 -375.945146) (xy 203.665582 -375.946416) (xy 203.636038 -375.955769)
			(xy 203.574899 -375.965859) (xy 203.543916 -375.966482) (xy 203.516664 -375.96602) (xy 203.462715 -375.958265)
			(xy 203.410419 -375.942912) (xy 203.36084 -375.920272) (xy 203.314988 -375.890806) (xy 203.273797 -375.855115)
			(xy 203.238104 -375.813925) (xy 203.208636 -375.768074) (xy 203.185994 -375.718496) (xy 203.170638 -375.6662)
			(xy 203.162881 -375.612252) (xy 203.162881 -375.557748) (xy 203.170638 -375.5038) (xy 203.185994 -375.451504)
			(xy 203.208636 -375.401926) (xy 203.238104 -375.356075) (xy 203.273797 -375.314885) (xy 203.314988 -375.279194)
			(xy 203.36084 -375.249728) (xy 203.410419 -375.227088) (xy 203.462715 -375.211735) (xy 203.516664 -375.20398)
			(xy 203.543916 -375.203466) (xy 203.573162 -375.204058) (xy 203.630951 -375.213122) (xy 203.658978 -375.2215)
			(xy 203.666598 -375.223786) (xy 203.666852 -375.223786) (xy 203.678536 -375.227596) (xy 203.702412 -375.22404)
			(xy 203.779628 -375.168668) (xy 203.789017 -375.16106) (xy 203.800024 -375.139584) (xy 203.80071 -375.12752)
			(xy 203.80071 -372.661688) (xy 203.800329 -372.652262) (xy 203.793503 -372.634688) (xy 203.780779 -372.620777)
			(xy 203.772516 -372.616222) (xy 203.765912 -372.61292) (xy 203.762356 -372.611904) (xy 203.735695 -372.602614)
			(xy 203.685239 -372.577288) (xy 203.639067 -372.5448) (xy 203.598191 -372.505859) (xy 203.563502 -372.461317)
			(xy 203.53576 -372.412148) (xy 203.51557 -372.359425) (xy 203.503375 -372.304302) (xy 203.49944 -372.247983)
			(xy 203.503852 -372.1917) (xy 203.516513 -372.136682) (xy 203.537149 -372.084132) (xy 203.565306 -372.035199)
			(xy 203.600371 -371.990953) (xy 203.641576 -371.952359) (xy 203.68802 -371.920263) (xy 203.73869 -371.895365)
			(xy 203.765404 -371.886226) (xy 203.781406 -371.881146) (xy 203.80071 -371.854476) (xy 203.80071 -371.690392)
			(xy 203.79309 -371.671596) (xy 203.785724 -371.664484) (xy 203.405994 -371.284754) (xy 203.399155 -371.277353)
			(xy 203.391439 -371.258755) (xy 203.391008 -371.248686) (xy 203.391008 -370.748814) (xy 203.391008 -370.74729)
			(xy 203.390255 -370.737194) (xy 203.381878 -370.718782) (xy 203.367056 -370.705015) (xy 203.357734 -370.701062)
			(xy 203.331982 -370.692751) (xy 203.282943 -370.669874) (xy 203.237628 -370.640299) (xy 203.196945 -370.60462)
			(xy 203.161709 -370.563551) (xy 203.132629 -370.517917) (xy 203.110286 -370.468633) (xy 203.095129 -370.416686)
			(xy 203.087462 -370.36312) (xy 203.08697 -370.336064) (xy 203.087478 -370.315744) (xy 203.087986 -370.304822)
			(xy 203.080366 -370.28501) (xy 203.011532 -370.216176) (xy 202.99172 -370.208556) (xy 202.980798 -370.209064)
			(xy 202.960478 -370.209572) (xy 202.93323 -370.209084) (xy 202.87929 -370.201326) (xy 202.827003 -370.18597)
			(xy 202.777433 -370.16333) (xy 202.73159 -370.133866) (xy 202.690406 -370.098178) (xy 202.654721 -370.056992)
			(xy 202.625259 -370.011147) (xy 202.602622 -369.961576) (xy 202.587269 -369.909288) (xy 202.579514 -369.855348)
			(xy 202.579514 -369.800852) (xy 202.587269 -369.746912) (xy 202.602622 -369.694624) (xy 202.625259 -369.645053)
			(xy 202.654721 -369.599208) (xy 202.690406 -369.558022) (xy 202.73159 -369.522334) (xy 202.777433 -369.49287)
			(xy 202.827003 -369.47023) (xy 202.87929 -369.454874) (xy 202.93323 -369.447116) (xy 202.960478 -369.446556)
			(xy 202.989075 -369.447064) (xy 203.045628 -369.455598) (xy 203.100273 -369.472477) (xy 203.151788 -369.497323)
			(xy 203.199017 -369.52958) (xy 203.22032 -369.548664) (xy 203.231496 -369.559078) (xy 203.261214 -369.564158)
			(xy 203.360528 -369.520724) (xy 203.369355 -369.516364) (xy 203.383086 -369.502283) (xy 203.390524 -369.484075)
			(xy 203.391008 -369.474242) (xy 203.391008 -368.439954) (xy 203.390557 -368.430112) (xy 203.383137 -368.41188)
			(xy 203.369376 -368.397806) (xy 203.360528 -368.393472) (xy 203.261214 -368.350038) (xy 203.231496 -368.355118)
			(xy 203.22032 -368.365532) (xy 203.199022 -368.38462) (xy 203.151784 -368.416859) (xy 203.100267 -368.441693)
			(xy 203.045623 -368.458569) (xy 202.989073 -368.467108) (xy 202.960478 -368.46764) (xy 202.933225 -368.467153)
			(xy 202.879276 -368.459393) (xy 202.826979 -368.444035) (xy 202.777401 -368.42139) (xy 202.731549 -368.391921)
			(xy 202.690358 -368.356226) (xy 202.654666 -368.315033) (xy 202.625199 -368.26918) (xy 202.602558 -368.2196)
			(xy 202.587202 -368.167303) (xy 202.579446 -368.113353) (xy 202.579446 -368.058847) (xy 202.587202 -368.004897)
			(xy 202.602558 -367.9526) (xy 202.625199 -367.90302) (xy 202.654666 -367.857167) (xy 202.690358 -367.815974)
			(xy 202.731549 -367.780279) (xy 202.777401 -367.75081) (xy 202.826979 -367.728165) (xy 202.879276 -367.712807)
			(xy 202.933225 -367.705047) (xy 202.960478 -367.704624) (xy 202.980798 -367.705132) (xy 202.991432 -367.705132)
			(xy 203.011265 -367.697531) (xy 203.019152 -367.6904) (xy 203.072746 -367.636806) (xy 203.079835 -367.628892)
			(xy 203.087437 -367.609078) (xy 203.087478 -367.598452) (xy 203.08697 -367.578132) (xy 203.087431 -367.550877)
			(xy 203.095184 -367.496921) (xy 203.110537 -367.444618) (xy 203.133177 -367.395033) (xy 203.162644 -367.349174)
			(xy 203.198337 -367.307976) (xy 203.239531 -367.272276) (xy 203.285385 -367.242803) (xy 203.334968 -367.220156)
			(xy 203.387269 -367.204795) (xy 203.441223 -367.197034) (xy 203.468478 -367.196624) (xy 203.483848 -367.196743)
			(xy 203.514493 -367.199157) (xy 203.529692 -367.20145) (xy 203.541884 -367.203482) (xy 203.564998 -367.196116)
			(xy 204.311504 -366.44961) (xy 204.314298 -366.446562) (xy 204.319802 -366.439515) (xy 204.325931 -366.422731)
			(xy 204.326236 -366.413796) (xy 204.317346 -366.385094) (xy 204.301456 -366.364671) (xy 204.27475 -366.32035)
			(xy 204.254282 -366.272826) (xy 204.240428 -366.22297) (xy 204.233442 -366.171699) (xy 204.233018 -366.145826)
			(xy 204.233504 -366.118575) (xy 204.24126 -366.064627) (xy 204.256615 -366.012332) (xy 204.279257 -365.962755)
			(xy 204.308723 -365.916905) (xy 204.344414 -365.875714) (xy 204.385605 -365.840023) (xy 204.431455 -365.810557)
			(xy 204.481032 -365.787915) (xy 204.533327 -365.77256) (xy 204.587275 -365.764804) (xy 204.641777 -365.764804)
			(xy 204.695725 -365.77256) (xy 204.74802 -365.787915) (xy 204.797597 -365.810557) (xy 204.843447 -365.840023)
			(xy 204.884638 -365.875714) (xy 204.920329 -365.916905) (xy 204.931962 -365.935006) (xy 209.473798 -365.935006)
			(xy 209.477869 -365.879384) (xy 209.489995 -365.824947) (xy 209.509918 -365.772856) (xy 209.537214 -365.724221)
			(xy 209.5713 -365.680078) (xy 209.611449 -365.641369) (xy 209.656807 -365.608918) (xy 209.706407 -365.583417)
			(xy 209.759191 -365.56541) (xy 209.814034 -365.55528) (xy 209.869768 -365.553243) (xy 209.925205 -365.559343)
			(xy 209.979162 -365.573449) (xy 210.030491 -365.595261) (xy 210.078097 -365.624315) (xy 210.120965 -365.65999)
			(xy 210.158182 -365.701527) (xy 210.188955 -365.74804) (xy 210.212627 -365.798537) (xy 210.228695 -365.851944)
			(xy 210.236815 -365.90712) (xy 210.237324 -365.935006) (xy 210.236815 -365.962892) (xy 210.228695 -366.018068)
			(xy 210.212627 -366.071475) (xy 210.188955 -366.121972) (xy 210.158182 -366.168485) (xy 210.120965 -366.210022)
			(xy 210.078097 -366.245697) (xy 210.030491 -366.274751) (xy 209.979162 -366.296563) (xy 209.925205 -366.310669)
			(xy 209.869768 -366.316769) (xy 209.814034 -366.314732) (xy 209.759191 -366.304602) (xy 209.706407 -366.286595)
			(xy 209.656807 -366.261094) (xy 209.611449 -366.228643) (xy 209.5713 -366.189934) (xy 209.537214 -366.145791)
			(xy 209.509918 -366.097156) (xy 209.489995 -366.045065) (xy 209.477869 -365.990628) (xy 209.473798 -365.935006)
			(xy 204.931962 -365.935006) (xy 204.949795 -365.962755) (xy 204.972437 -366.012332) (xy 204.987792 -366.064627)
			(xy 204.995548 -366.118575) (xy 204.996034 -366.145826) (xy 204.995546 -366.172947) (xy 204.987829 -366.226638)
			(xy 204.972571 -366.27869) (xy 204.961744 -366.30356) (xy 204.95641 -366.315498) (xy 204.958188 -366.341152)
			(xy 205.011528 -366.42421) (xy 205.016381 -366.431171) (xy 205.029706 -366.441665) (xy 205.045721 -366.447249)
			(xy 205.0542 -366.447578) (xy 212.212682 -366.447578) (xy 212.22524 -366.44694) (xy 212.247379 -366.435087)
			(xy 212.254846 -366.424972) (xy 212.258656 -366.41913) (xy 212.291168 -366.329468) (xy 212.29258 -366.32529)
			(xy 212.294117 -366.316605) (xy 212.294216 -366.312196) (xy 212.294216 -366.293908) (xy 212.284818 -366.273842)
			(xy 212.276182 -366.266476) (xy 212.255451 -366.248273) (xy 212.218935 -366.206919) (xy 212.188756 -366.160736)
			(xy 212.165543 -366.110688) (xy 212.149782 -366.057819) (xy 212.141801 -366.00323) (xy 212.141308 -365.975646)
			(xy 212.141768 -365.948391) (xy 212.14952 -365.894436) (xy 212.164872 -365.842134) (xy 212.187512 -365.792549)
			(xy 212.216979 -365.746691) (xy 212.252673 -365.705494) (xy 212.293867 -365.669797) (xy 212.339723 -365.640327)
			(xy 212.389306 -365.617683) (xy 212.441607 -365.602326) (xy 212.495561 -365.59457) (xy 212.522816 -365.594138)
			(xy 212.552063 -365.594672) (xy 212.609868 -365.603613) (xy 212.665629 -365.621283) (xy 212.718034 -365.647266)
			(xy 212.765854 -365.680951) (xy 212.807964 -365.721549) (xy 212.826092 -365.744506) (xy 212.828124 -365.747046)
			(xy 212.833712 -365.752634) (xy 212.841055 -365.75945) (xy 212.859518 -365.767188) (xy 212.869526 -365.76762)
			(xy 212.950044 -365.768128) (xy 212.96187 -365.767586) (xy 212.983075 -365.757129) (xy 212.990684 -365.748062)
			(xy 212.990938 -365.747808) (xy 212.99297 -365.745268) (xy 213.011142 -365.72258) (xy 213.053198 -365.682456)
			(xy 213.100857 -365.64918) (xy 213.153014 -365.623522) (xy 213.208461 -365.606079) (xy 213.265913 -365.597253)
			(xy 213.294976 -365.596678) (xy 213.32223 -365.597139) (xy 213.376185 -365.604893) (xy 213.428486 -365.620247)
			(xy 213.47807 -365.642888) (xy 213.523928 -365.672355) (xy 213.565124 -365.708049) (xy 213.600822 -365.749242)
			(xy 213.630294 -365.795096) (xy 213.65294 -365.844678) (xy 213.668299 -365.896978) (xy 213.676058 -365.950932)
			(xy 213.676484 -365.978186) (xy 213.67604 -366.004879) (xy 213.668609 -366.057744) (xy 213.653889 -366.109059)
			(xy 213.632168 -366.157825) (xy 213.603868 -366.203092) (xy 213.569541 -366.243977) (xy 213.549992 -366.262158)
			(xy 213.542118 -366.269016) (xy 213.53145 -366.292384) (xy 213.527755 -366.301626) (xy 213.526956 -366.321494)
			(xy 213.529926 -366.330992) (xy 213.560406 -366.414304) (xy 213.564412 -366.423842) (xy 213.5786 -366.43887)
			(xy 213.597571 -366.44707) (xy 213.607904 -366.447578) (xy 223.523048 -366.447578) (xy 223.533366 -366.447033)
			(xy 223.552299 -366.438804) (xy 223.566484 -366.423807) (xy 223.570546 -366.414304) (xy 223.601026 -366.330992)
			(xy 223.604087 -366.321504) (xy 223.603311 -366.301597) (xy 223.599502 -366.292384) (xy 223.588834 -366.269016)
			(xy 223.58096 -366.262158) (xy 223.561417 -366.243973) (xy 223.527094 -366.203087) (xy 223.498798 -366.15782)
			(xy 223.47708 -366.109055) (xy 223.462362 -366.057741) (xy 223.454932 -366.004877) (xy 223.454468 -365.978186)
			(xy 223.454954 -365.950935) (xy 223.46271 -365.896987) (xy 223.478065 -365.844692) (xy 223.500707 -365.795115)
			(xy 223.530173 -365.749265) (xy 223.565864 -365.708074) (xy 223.607055 -365.672383) (xy 223.652905 -365.642917)
			(xy 223.702482 -365.620275) (xy 223.754777 -365.60492) (xy 223.808725 -365.597164) (xy 223.863227 -365.597164)
			(xy 223.917175 -365.60492) (xy 223.96947 -365.620275) (xy 224.019047 -365.642917) (xy 224.064897 -365.672383)
			(xy 224.106088 -365.708074) (xy 224.141779 -365.749265) (xy 224.171245 -365.795115) (xy 224.193887 -365.844692)
			(xy 224.209242 -365.896987) (xy 224.216998 -365.950935) (xy 224.217484 -365.978186) (xy 224.21704 -366.004879)
			(xy 224.209609 -366.057744) (xy 224.194889 -366.109059) (xy 224.173168 -366.157825) (xy 224.144868 -366.203092)
			(xy 224.110541 -366.243977) (xy 224.090992 -366.262158) (xy 224.083118 -366.269016) (xy 224.07245 -366.292384)
			(xy 224.068755 -366.301626) (xy 224.067956 -366.321494) (xy 224.070926 -366.330992) (xy 224.101406 -366.414304)
			(xy 224.105412 -366.423842) (xy 224.1196 -366.43887) (xy 224.138571 -366.44707) (xy 224.148904 -366.447578)
			(xy 226.317048 -366.447578) (xy 226.327366 -366.447033) (xy 226.346299 -366.438804) (xy 226.360484 -366.423807)
			(xy 226.364546 -366.414304) (xy 226.395026 -366.330992) (xy 226.398087 -366.321504) (xy 226.397311 -366.301597)
			(xy 226.393502 -366.292384) (xy 226.382834 -366.269016) (xy 226.37496 -366.262158) (xy 226.355417 -366.243973)
			(xy 226.321094 -366.203087) (xy 226.292798 -366.15782) (xy 226.27108 -366.109055) (xy 226.256362 -366.057741)
			(xy 226.248932 -366.004877) (xy 226.248468 -365.978186) (xy 226.248954 -365.950935) (xy 226.25671 -365.896987)
			(xy 226.272065 -365.844692) (xy 226.294707 -365.795115) (xy 226.324173 -365.749265) (xy 226.359864 -365.708074)
			(xy 226.401055 -365.672383) (xy 226.446905 -365.642917) (xy 226.496482 -365.620275) (xy 226.548777 -365.60492)
			(xy 226.602725 -365.597164) (xy 226.657227 -365.597164) (xy 226.711175 -365.60492) (xy 226.76347 -365.620275)
			(xy 226.813047 -365.642917) (xy 226.858897 -365.672383) (xy 226.900088 -365.708074) (xy 226.935779 -365.749265)
			(xy 226.965245 -365.795115) (xy 226.987887 -365.844692) (xy 227.003242 -365.896987) (xy 227.010998 -365.950935)
			(xy 227.011484 -365.978186) (xy 227.01104 -366.004879) (xy 227.003609 -366.057744) (xy 226.988889 -366.109059)
			(xy 226.967168 -366.157825) (xy 226.938868 -366.203092) (xy 226.904541 -366.243977) (xy 226.884992 -366.262158)
			(xy 226.877118 -366.269016) (xy 226.86645 -366.292384) (xy 226.862755 -366.301626) (xy 226.861956 -366.321494)
			(xy 226.864926 -366.330992) (xy 226.895406 -366.414304) (xy 226.899412 -366.423842) (xy 226.9136 -366.43887)
			(xy 226.932571 -366.44707) (xy 226.942904 -366.447578) (xy 241.868706 -366.447578) (xy 241.875818 -366.445546)
			(xy 241.902379 -366.438101) (xy 241.956951 -366.430068) (xy 241.98453 -366.429544) (xy 242.012108 -366.430084)
			(xy 242.06668 -366.438111) (xy 242.093242 -366.445546) (xy 242.100354 -366.447578) (xy 265.636502 -366.447578)
			(xy 265.646572 -366.447154) (xy 265.665173 -366.439437) (xy 265.67257 -366.432592) (xy 266.33932 -365.765842)
			(xy 266.346166 -365.758444) (xy 266.353892 -365.739845) (xy 266.354306 -365.729774) (xy 266.354306 -362.117132)
			(xy 266.349988 -362.113068) (xy 266.349988 -357.99649) (xy 266.349563 -357.986421) (xy 266.341844 -357.96782)
			(xy 266.335002 -357.960422) (xy 265.284204 -356.909624) (xy 265.277092 -356.902258) (xy 265.258296 -356.894638)
			(xy 253.260098 -356.894638) (xy 253.241302 -356.902258) (xy 253.23419 -356.909624) (xy 252.95987 -357.183944)
			(xy 252.953023 -357.191341) (xy 252.945293 -357.20994) (xy 252.944884 -357.220012) (xy 252.944884 -358.53751)
			(xy 252.944459 -358.547579) (xy 252.93674 -358.566179) (xy 252.929898 -358.573578) (xy 251.742448 -359.761028)
			(xy 251.73505 -359.767874) (xy 251.716451 -359.775601) (xy 251.70638 -359.776014) (xy 246.78767 -359.776014)
			(xy 246.768874 -359.783634) (xy 246.761762 -359.791) (xy 245.756938 -360.795824) (xy 245.74954 -360.802669)
			(xy 245.730941 -360.810393) (xy 245.72087 -360.81081) (xy 237.704376 -360.81081) (xy 237.703614 -360.810048)
			(xy 237.550452 -360.810048) (xy 237.531656 -360.817668) (xy 237.524544 -360.825034) (xy 236.442758 -361.90682)
			(xy 236.435361 -361.913669) (xy 236.416762 -361.9214) (xy 236.40669 -361.921806) (xy 206.635604 -361.921806)
			(xy 206.610966 -361.9373) (xy 206.604616 -361.950762) (xy 206.576422 -362.00969) (xy 206.574101 -362.014853)
			(xy 206.571541 -362.025877) (xy 206.571342 -362.031534) (xy 206.571342 -362.07827) (xy 206.576422 -362.093256)
			(xy 206.581248 -362.100114) (xy 206.598795 -362.124876) (xy 206.626658 -362.178788) (xy 206.645654 -362.236425)
			(xy 206.655306 -362.296339) (xy 206.655924 -362.326682) (xy 206.655438 -362.353933) (xy 206.647682 -362.407881)
			(xy 206.632327 -362.460176) (xy 206.609685 -362.509753) (xy 206.580219 -362.555603) (xy 206.544528 -362.596794)
			(xy 206.503337 -362.632485) (xy 206.457487 -362.661951) (xy 206.40791 -362.684593) (xy 206.355615 -362.699948)
			(xy 206.301667 -362.707704) (xy 206.247165 -362.707704) (xy 206.193217 -362.699948) (xy 206.140922 -362.684593)
			(xy 206.091345 -362.661951) (xy 206.045495 -362.632485) (xy 206.004304 -362.596794) (xy 205.968613 -362.555603)
			(xy 205.939147 -362.509753) (xy 205.916505 -362.460176) (xy 205.90115 -362.407881) (xy 205.893394 -362.353933)
			(xy 205.892908 -362.326682) (xy 205.893344 -362.300776) (xy 205.90036 -362.249441) (xy 205.914262 -362.199529)
			(xy 205.934792 -362.151959) (xy 205.961574 -362.107605) (xy 205.97749 -362.08716) (xy 205.986888 -362.075476)
			(xy 205.99019 -362.04652) (xy 205.944216 -361.950762) (xy 205.937866 -361.9373) (xy 205.913228 -361.921806)
			(xy 203.67879 -361.921806) (xy 203.668289 -361.922322) (xy 203.649038 -361.930717) (xy 203.634743 -361.946103)
			(xy 203.630784 -361.955842) (xy 203.593954 -362.06176) (xy 203.602844 -362.093002) (xy 203.615544 -362.102908)
			(xy 203.63767 -362.121105) (xy 203.676736 -362.163007) (xy 203.709099 -362.210277) (xy 203.734031 -362.261855)
			(xy 203.750972 -362.31658) (xy 203.759541 -362.373222) (xy 203.76007 -362.401866) (xy 203.759584 -362.429117)
			(xy 203.751828 -362.483065) (xy 203.736473 -362.53536) (xy 203.713831 -362.584937) (xy 203.684365 -362.630787)
			(xy 203.648674 -362.671978) (xy 203.607483 -362.707669) (xy 203.561633 -362.737135) (xy 203.512056 -362.759777)
			(xy 203.459761 -362.775132) (xy 203.405813 -362.782888) (xy 203.351311 -362.782888) (xy 203.297363 -362.775132)
			(xy 203.245068 -362.759777) (xy 203.195491 -362.737135) (xy 203.149641 -362.707669) (xy 203.10845 -362.671978)
			(xy 203.072759 -362.630787) (xy 203.043293 -362.584937) (xy 203.020651 -362.53536) (xy 203.005296 -362.483065)
			(xy 202.99754 -362.429117) (xy 202.997054 -362.401866) (xy 202.997563 -362.373219) (xy 203.006122 -362.316569)
			(xy 203.023057 -362.261836) (xy 203.047987 -362.210251) (xy 203.080352 -362.162975) (xy 203.119423 -362.121071)
			(xy 203.14158 -362.102908) (xy 203.15428 -362.093002) (xy 203.16317 -362.06176) (xy 203.12634 -361.955842)
			(xy 203.122398 -361.946084) (xy 203.108115 -361.930659) (xy 203.088846 -361.922256) (xy 203.078334 -361.921806)
			(xy 200.034144 -361.921806) (xy 200.012046 -361.93349) (xy 200.004934 -361.944158) (xy 199.957944 -362.013246)
			(xy 199.951594 -362.025692) (xy 199.949308 -362.036868) (xy 199.948038 -362.049314) (xy 199.950832 -362.05668)
			(xy 199.951086 -362.057188) (xy 199.952864 -362.06176) (xy 199.961362 -362.084194) (xy 199.973336 -362.130648)
			(xy 199.979401 -362.178236) (xy 199.979788 -362.202222) (xy 199.9793 -362.229472) (xy 199.971541 -362.283416)
			(xy 199.956184 -362.335707) (xy 199.933541 -362.38528) (xy 199.904074 -362.431126) (xy 199.868382 -362.472312)
			(xy 199.827192 -362.507999) (xy 199.781343 -362.537461) (xy 199.731767 -362.560099) (xy 199.679475 -362.57545)
			(xy 199.62553 -362.583203) (xy 199.59828 -362.58373) (xy 199.570534 -362.583238) (xy 199.515626 -362.575212)
			(xy 199.462458 -362.559319) (xy 199.412154 -362.535894) (xy 199.365772 -362.505429) (xy 199.324291 -362.468569)
			(xy 199.288587 -362.426089) (xy 199.259411 -362.378886) (xy 199.237379 -362.327955) (xy 199.229726 -362.301282)
			(xy 199.226932 -362.291376) (xy 199.21474 -362.275374) (xy 199.134222 -362.2294) (xy 199.114156 -362.22686)
			(xy 199.10425 -362.229654) (xy 199.078984 -362.23628) (xy 199.027242 -362.243415) (xy 199.001126 -362.243878)
			(xy 198.973874 -362.243417) (xy 198.919925 -362.235663) (xy 198.867628 -362.220311) (xy 198.818048 -362.197671)
			(xy 198.772195 -362.168206) (xy 198.731003 -362.132516) (xy 198.695309 -362.091325) (xy 198.665841 -362.045475)
			(xy 198.643199 -361.995897) (xy 198.627842 -361.943601) (xy 198.620085 -361.889652) (xy 198.620085 -361.835148)
			(xy 198.627842 -361.781199) (xy 198.643199 -361.728903) (xy 198.665841 -361.679325) (xy 198.695309 -361.633475)
			(xy 198.731003 -361.592284) (xy 198.772195 -361.556594) (xy 198.818048 -361.527129) (xy 198.867628 -361.504489)
			(xy 198.919925 -361.489137) (xy 198.973874 -361.481383) (xy 199.001126 -361.480862) (xy 199.033784 -361.481531)
			(xy 199.098149 -361.492643) (xy 199.129142 -361.50296) (xy 199.129396 -361.50296) (xy 199.138782 -361.505717)
			(xy 199.158299 -361.504692) (xy 199.176018 -361.496444) (xy 199.189367 -361.482169) (xy 199.196411 -361.463937)
			(xy 199.196126 -361.444395) (xy 199.188555 -361.426377) (xy 199.181974 -361.41914) (xy 199.083168 -361.320334)
			(xy 199.078342 -361.315254) (xy 190.56477 -361.315254) (xy 189.290452 -362.589572) (xy 200.18832 -362.589572)
			(xy 200.192391 -362.53395) (xy 200.204517 -362.479513) (xy 200.22444 -362.427422) (xy 200.251736 -362.378787)
			(xy 200.285822 -362.334644) (xy 200.325971 -362.295935) (xy 200.371329 -362.263484) (xy 200.420929 -362.237983)
			(xy 200.473713 -362.219976) (xy 200.528556 -362.209846) (xy 200.58429 -362.207809) (xy 200.639727 -362.213909)
			(xy 200.693684 -362.228015) (xy 200.745013 -362.249827) (xy 200.792619 -362.278881) (xy 200.835487 -362.314556)
			(xy 200.872704 -362.356093) (xy 200.903477 -362.402606) (xy 200.927149 -362.453103) (xy 200.943217 -362.50651)
			(xy 200.951337 -362.561686) (xy 200.951846 -362.589572) (xy 200.951337 -362.617458) (xy 200.943217 -362.672634)
			(xy 200.927149 -362.726041) (xy 200.903477 -362.776538) (xy 200.872704 -362.823051) (xy 200.835487 -362.864588)
			(xy 200.792619 -362.900263) (xy 200.745013 -362.929317) (xy 200.693684 -362.951129) (xy 200.639727 -362.965235)
			(xy 200.58429 -362.971335) (xy 200.528556 -362.969298) (xy 200.473713 -362.959168) (xy 200.420929 -362.941161)
			(xy 200.371329 -362.91566) (xy 200.325971 -362.883209) (xy 200.285822 -362.8445) (xy 200.251736 -362.800357)
			(xy 200.22444 -362.751722) (xy 200.204517 -362.699631) (xy 200.192391 -362.645194) (xy 200.18832 -362.589572)
			(xy 189.290452 -362.589572) (xy 188.872114 -363.00791) (xy 201.156568 -363.00791) (xy 201.160639 -362.952288)
			(xy 201.172765 -362.897851) (xy 201.192688 -362.84576) (xy 201.219984 -362.797125) (xy 201.25407 -362.752982)
			(xy 201.294219 -362.714273) (xy 201.339577 -362.681822) (xy 201.389177 -362.656321) (xy 201.441961 -362.638314)
			(xy 201.496804 -362.628184) (xy 201.552538 -362.626147) (xy 201.607975 -362.632247) (xy 201.661932 -362.646353)
			(xy 201.713261 -362.668165) (xy 201.760867 -362.697219) (xy 201.803735 -362.732894) (xy 201.840952 -362.774431)
			(xy 201.871725 -362.820944) (xy 201.895397 -362.871441) (xy 201.911465 -362.924848) (xy 201.919585 -362.980024)
			(xy 201.920094 -363.00791) (xy 201.919585 -363.035796) (xy 201.911465 -363.090972) (xy 201.895397 -363.144379)
			(xy 201.871725 -363.194876) (xy 201.840952 -363.241389) (xy 201.803735 -363.282926) (xy 201.760867 -363.318601)
			(xy 201.713261 -363.347655) (xy 201.661932 -363.369467) (xy 201.607975 -363.383573) (xy 201.552538 -363.389673)
			(xy 201.496804 -363.387636) (xy 201.441961 -363.377506) (xy 201.389177 -363.359499) (xy 201.339577 -363.333998)
			(xy 201.294219 -363.301547) (xy 201.25407 -363.262838) (xy 201.219984 -363.218695) (xy 201.192688 -363.17006)
			(xy 201.172765 -363.117969) (xy 201.160639 -363.063532) (xy 201.156568 -363.00791) (xy 188.872114 -363.00791)
			(xy 188.296296 -363.583728) (xy 197.166228 -363.583728) (xy 197.170299 -363.528106) (xy 197.182425 -363.473669)
			(xy 197.202348 -363.421578) (xy 197.229644 -363.372943) (xy 197.26373 -363.3288) (xy 197.303879 -363.290091)
			(xy 197.349237 -363.25764) (xy 197.398837 -363.232139) (xy 197.451621 -363.214132) (xy 197.506464 -363.204002)
			(xy 197.562198 -363.201965) (xy 197.617635 -363.208065) (xy 197.671592 -363.222171) (xy 197.722921 -363.243983)
			(xy 197.770527 -363.273037) (xy 197.813395 -363.308712) (xy 197.850612 -363.350249) (xy 197.881385 -363.396762)
			(xy 197.905057 -363.447259) (xy 197.921125 -363.500666) (xy 197.929245 -363.555842) (xy 197.929754 -363.583728)
			(xy 197.929245 -363.611614) (xy 197.92434 -363.644942) (xy 202.462636 -363.644942) (xy 202.466707 -363.58932)
			(xy 202.478833 -363.534883) (xy 202.498756 -363.482792) (xy 202.526052 -363.434157) (xy 202.560138 -363.390014)
			(xy 202.600287 -363.351305) (xy 202.645645 -363.318854) (xy 202.695245 -363.293353) (xy 202.748029 -363.275346)
			(xy 202.802872 -363.265216) (xy 202.858606 -363.263179) (xy 202.914043 -363.269279) (xy 202.968 -363.283385)
			(xy 203.019329 -363.305197) (xy 203.066935 -363.334251) (xy 203.109803 -363.369926) (xy 203.14702 -363.411463)
			(xy 203.177793 -363.457976) (xy 203.201465 -363.508473) (xy 203.217533 -363.56188) (xy 203.225653 -363.617056)
			(xy 203.226162 -363.644942) (xy 203.225653 -363.672828) (xy 203.217533 -363.728004) (xy 203.201465 -363.781411)
			(xy 203.177793 -363.831908) (xy 203.14702 -363.878421) (xy 203.109803 -363.919958) (xy 203.066935 -363.955633)
			(xy 203.019329 -363.984687) (xy 202.968 -364.006499) (xy 202.914043 -364.020605) (xy 202.858606 -364.026705)
			(xy 202.802872 -364.024668) (xy 202.748029 -364.014538) (xy 202.695245 -363.996531) (xy 202.645645 -363.97103)
			(xy 202.600287 -363.938579) (xy 202.560138 -363.89987) (xy 202.526052 -363.855727) (xy 202.498756 -363.807092)
			(xy 202.478833 -363.755001) (xy 202.466707 -363.700564) (xy 202.462636 -363.644942) (xy 197.92434 -363.644942)
			(xy 197.921125 -363.66679) (xy 197.905057 -363.720197) (xy 197.881385 -363.770694) (xy 197.850612 -363.817207)
			(xy 197.813395 -363.858744) (xy 197.770527 -363.894419) (xy 197.722921 -363.923473) (xy 197.671592 -363.945285)
			(xy 197.617635 -363.959391) (xy 197.562198 -363.965491) (xy 197.506464 -363.963454) (xy 197.451621 -363.953324)
			(xy 197.398837 -363.935317) (xy 197.349237 -363.909816) (xy 197.303879 -363.877365) (xy 197.26373 -363.838656)
			(xy 197.229644 -363.794513) (xy 197.202348 -363.745878) (xy 197.182425 -363.693787) (xy 197.170299 -363.63935)
			(xy 197.166228 -363.583728) (xy 188.296296 -363.583728) (xy 187.694824 -364.1852) (xy 199.46188 -364.1852)
			(xy 199.465951 -364.129578) (xy 199.478077 -364.075141) (xy 199.498 -364.02305) (xy 199.525296 -363.974415)
			(xy 199.559382 -363.930272) (xy 199.599531 -363.891563) (xy 199.644889 -363.859112) (xy 199.694489 -363.833611)
			(xy 199.747273 -363.815604) (xy 199.802116 -363.805474) (xy 199.85785 -363.803437) (xy 199.913287 -363.809537)
			(xy 199.967244 -363.823643) (xy 200.018573 -363.845455) (xy 200.066179 -363.874509) (xy 200.109047 -363.910184)
			(xy 200.146264 -363.951721) (xy 200.177037 -363.998234) (xy 200.200709 -364.048731) (xy 200.216777 -364.102138)
			(xy 200.224897 -364.157314) (xy 200.225406 -364.1852) (xy 200.224897 -364.213086) (xy 200.216777 -364.268262)
			(xy 200.200709 -364.321669) (xy 200.177037 -364.372166) (xy 200.146264 -364.418679) (xy 200.109047 -364.460216)
			(xy 200.066179 -364.495891) (xy 200.018573 -364.524945) (xy 199.967244 -364.546757) (xy 199.913287 -364.560863)
			(xy 199.85785 -364.566963) (xy 199.802116 -364.564926) (xy 199.747273 -364.554796) (xy 199.694489 -364.536789)
			(xy 199.644889 -364.511288) (xy 199.599531 -364.478837) (xy 199.559382 -364.440128) (xy 199.525296 -364.395985)
			(xy 199.498 -364.34735) (xy 199.478077 -364.295259) (xy 199.465951 -364.240822) (xy 199.46188 -364.1852)
			(xy 187.694824 -364.1852) (xy 187.280296 -364.599728) (xy 197.166228 -364.599728) (xy 197.170299 -364.544106)
			(xy 197.182425 -364.489669) (xy 197.202348 -364.437578) (xy 197.229644 -364.388943) (xy 197.26373 -364.3448)
			(xy 197.303879 -364.306091) (xy 197.349237 -364.27364) (xy 197.398837 -364.248139) (xy 197.451621 -364.230132)
			(xy 197.506464 -364.220002) (xy 197.562198 -364.217965) (xy 197.617635 -364.224065) (xy 197.671592 -364.238171)
			(xy 197.722921 -364.259983) (xy 197.770527 -364.289037) (xy 197.813395 -364.324712) (xy 197.850612 -364.366249)
			(xy 197.881385 -364.412762) (xy 197.905057 -364.463259) (xy 197.921125 -364.516666) (xy 197.929245 -364.571842)
			(xy 197.929754 -364.599728) (xy 197.929245 -364.627614) (xy 197.921125 -364.68279) (xy 197.905057 -364.736197)
			(xy 197.881385 -364.786694) (xy 197.850612 -364.833207) (xy 197.813395 -364.874744) (xy 197.770527 -364.910419)
			(xy 197.722921 -364.939473) (xy 197.671592 -364.961285) (xy 197.617635 -364.975391) (xy 197.562198 -364.981491)
			(xy 197.506464 -364.979454) (xy 197.451621 -364.969324) (xy 197.398837 -364.951317) (xy 197.349237 -364.925816)
			(xy 197.303879 -364.893365) (xy 197.26373 -364.854656) (xy 197.229644 -364.810513) (xy 197.202348 -364.761878)
			(xy 197.182425 -364.709787) (xy 197.170299 -364.65535) (xy 197.166228 -364.599728) (xy 187.280296 -364.599728)
			(xy 186.762072 -365.117952) (xy 194.110065 -365.117952) (xy 194.110065 -365.063448) (xy 194.117822 -365.009498)
			(xy 194.133178 -364.957201) (xy 194.15582 -364.907622) (xy 194.185287 -364.86177) (xy 194.22098 -364.820579)
			(xy 194.262172 -364.784886) (xy 194.308024 -364.755419) (xy 194.357603 -364.732777) (xy 194.4099 -364.717422)
			(xy 194.46385 -364.709665) (xy 194.491102 -364.709202) (xy 194.517968 -364.709649) (xy 194.571169 -364.717189)
			(xy 194.622786 -364.732119) (xy 194.671797 -364.754143) (xy 194.717233 -364.782827) (xy 194.758194 -364.817602)
			(xy 194.793871 -364.857781) (xy 194.823558 -364.902568) (xy 194.835526 -364.926626) (xy 194.842292 -364.939646)
			(xy 194.861922 -364.961438) (xy 194.886936 -364.976752) (xy 194.915271 -364.984326) (xy 194.94459 -364.983533)
			(xy 194.972474 -364.974441) (xy 194.996625 -364.957798) (xy 195.006214 -364.946692) (xy 195.024426 -364.92493)
			(xy 195.066198 -364.886523) (xy 195.113199 -364.854729) (xy 195.164393 -364.830249) (xy 195.218648 -364.813626)
			(xy 195.274767 -364.805224) (xy 195.30314 -364.804706) (xy 195.33039 -364.805167) (xy 195.384336 -364.812928)
			(xy 195.436628 -364.828287) (xy 195.486202 -364.850931) (xy 195.532049 -364.8804) (xy 195.573236 -364.916093)
			(xy 195.608924 -364.957283) (xy 195.638388 -365.003134) (xy 195.654486 -365.038386) (xy 201.228958 -365.038386)
			(xy 201.233029 -364.982764) (xy 201.245155 -364.928327) (xy 201.265078 -364.876236) (xy 201.292374 -364.827601)
			(xy 201.32646 -364.783458) (xy 201.366609 -364.744749) (xy 201.411967 -364.712298) (xy 201.461567 -364.686797)
			(xy 201.514351 -364.66879) (xy 201.569194 -364.65866) (xy 201.624928 -364.656623) (xy 201.680365 -364.662723)
			(xy 201.734322 -364.676829) (xy 201.785651 -364.698641) (xy 201.833257 -364.727695) (xy 201.876125 -364.76337)
			(xy 201.913342 -364.804907) (xy 201.944115 -364.85142) (xy 201.967787 -364.901917) (xy 201.983855 -364.955324)
			(xy 201.991975 -365.0105) (xy 201.992484 -365.038386) (xy 201.991975 -365.066272) (xy 201.983855 -365.121448)
			(xy 201.967787 -365.174855) (xy 201.944115 -365.225352) (xy 201.913342 -365.271865) (xy 201.876125 -365.313402)
			(xy 201.867805 -365.320326) (xy 214.325706 -365.320326) (xy 214.329777 -365.264704) (xy 214.341903 -365.210267)
			(xy 214.361826 -365.158176) (xy 214.389122 -365.109541) (xy 214.423208 -365.065398) (xy 214.463357 -365.026689)
			(xy 214.508715 -364.994238) (xy 214.558315 -364.968737) (xy 214.611099 -364.95073) (xy 214.665942 -364.9406)
			(xy 214.721676 -364.938563) (xy 214.777113 -364.944663) (xy 214.83107 -364.958769) (xy 214.882399 -364.980581)
			(xy 214.930005 -365.009635) (xy 214.972873 -365.04531) (xy 215.01009 -365.086847) (xy 215.040863 -365.13336)
			(xy 215.064535 -365.183857) (xy 215.080603 -365.237264) (xy 215.088723 -365.29244) (xy 215.089232 -365.320326)
			(xy 215.088723 -365.348212) (xy 215.080603 -365.403388) (xy 215.064535 -365.456795) (xy 215.040863 -365.507292)
			(xy 215.01009 -365.553805) (xy 214.972873 -365.595342) (xy 214.930005 -365.631017) (xy 214.882399 -365.660071)
			(xy 214.83107 -365.681883) (xy 214.777113 -365.695989) (xy 214.721676 -365.702089) (xy 214.665942 -365.700052)
			(xy 214.611099 -365.689922) (xy 214.558315 -365.671915) (xy 214.508715 -365.646414) (xy 214.463357 -365.613963)
			(xy 214.423208 -365.575254) (xy 214.389122 -365.531111) (xy 214.361826 -365.482476) (xy 214.341903 -365.430385)
			(xy 214.329777 -365.375948) (xy 214.325706 -365.320326) (xy 201.867805 -365.320326) (xy 201.833257 -365.349077)
			(xy 201.785651 -365.378131) (xy 201.734322 -365.399943) (xy 201.680365 -365.414049) (xy 201.624928 -365.420149)
			(xy 201.569194 -365.418112) (xy 201.514351 -365.407982) (xy 201.461567 -365.389975) (xy 201.411967 -365.364474)
			(xy 201.366609 -365.332023) (xy 201.32646 -365.293314) (xy 201.292374 -365.249171) (xy 201.265078 -365.200536)
			(xy 201.245155 -365.148445) (xy 201.233029 -365.094008) (xy 201.228958 -365.038386) (xy 195.654486 -365.038386)
			(xy 195.661027 -365.05271) (xy 195.676381 -365.105003) (xy 195.684136 -365.15895) (xy 195.684136 -365.21345)
			(xy 195.676381 -365.267397) (xy 195.661027 -365.31969) (xy 195.638388 -365.369266) (xy 195.608924 -365.415117)
			(xy 195.573236 -365.456307) (xy 195.532049 -365.492) (xy 195.486202 -365.521469) (xy 195.436628 -365.544113)
			(xy 195.384336 -365.559472) (xy 195.33039 -365.567233) (xy 195.30314 -365.567722) (xy 195.276276 -365.567226)
			(xy 195.223077 -365.559693) (xy 195.171463 -365.544769) (xy 195.122453 -365.522751) (xy 195.077017 -365.494074)
			(xy 195.036054 -365.459306) (xy 195.000375 -365.419134) (xy 194.970686 -365.374353) (xy 194.958716 -365.350298)
			(xy 194.951897 -365.337311) (xy 194.932271 -365.315537) (xy 194.907268 -365.300233) (xy 194.878948 -365.292662)
			(xy 194.849644 -365.293446) (xy 194.82177 -365.302521) (xy 194.797621 -365.319139) (xy 194.788028 -365.330232)
			(xy 194.769799 -365.351979) (xy 194.72803 -365.390387) (xy 194.681032 -365.422182) (xy 194.629842 -365.446663)
			(xy 194.57559 -365.463291) (xy 194.519473 -365.471698) (xy 194.491102 -365.472218) (xy 194.46385 -365.471735)
			(xy 194.4099 -365.463978) (xy 194.357603 -365.448623) (xy 194.308024 -365.425981) (xy 194.262172 -365.396514)
			(xy 194.22098 -365.360821) (xy 194.185287 -365.31963) (xy 194.15582 -365.273778) (xy 194.133178 -365.224199)
			(xy 194.117822 -365.171902) (xy 194.110065 -365.117952) (xy 186.762072 -365.117952) (xy 186.44743 -365.432594)
			(xy 185.043826 -365.432594) (xy 185.034645 -365.440237) (xy 185.023938 -365.46156) (xy 185.023252 -365.473488)
			(xy 185.023252 -365.830104) (xy 192.759074 -365.830104) (xy 192.763145 -365.774482) (xy 192.775271 -365.720045)
			(xy 192.795194 -365.667954) (xy 192.82249 -365.619319) (xy 192.856576 -365.575176) (xy 192.896725 -365.536467)
			(xy 192.942083 -365.504016) (xy 192.991683 -365.478515) (xy 193.044467 -365.460508) (xy 193.09931 -365.450378)
			(xy 193.155044 -365.448341) (xy 193.210481 -365.454441) (xy 193.264438 -365.468547) (xy 193.315767 -365.490359)
			(xy 193.363373 -365.519413) (xy 193.406241 -365.555088) (xy 193.443458 -365.596625) (xy 193.474231 -365.643138)
			(xy 193.497903 -365.693635) (xy 193.513971 -365.747042) (xy 193.522091 -365.802218) (xy 193.5226 -365.830104)
			(xy 193.522091 -365.85799) (xy 193.513971 -365.913166) (xy 193.497903 -365.966573) (xy 193.474231 -366.01707)
			(xy 193.443458 -366.063583) (xy 193.406241 -366.10512) (xy 193.363373 -366.140795) (xy 193.315767 -366.169849)
			(xy 193.264438 -366.191661) (xy 193.210481 -366.205767) (xy 193.155044 -366.211867) (xy 193.09931 -366.20983)
			(xy 193.044467 -366.1997) (xy 192.991683 -366.181693) (xy 192.942083 -366.156192) (xy 192.896725 -366.123741)
			(xy 192.856576 -366.085032) (xy 192.82249 -366.040889) (xy 192.795194 -365.992254) (xy 192.775271 -365.940163)
			(xy 192.763145 -365.885726) (xy 192.759074 -365.830104) (xy 185.023252 -365.830104) (xy 185.023252 -366.655096)
			(xy 191.396872 -366.655096) (xy 191.400943 -366.599474) (xy 191.413069 -366.545037) (xy 191.432992 -366.492946)
			(xy 191.460288 -366.444311) (xy 191.494374 -366.400168) (xy 191.534523 -366.361459) (xy 191.579881 -366.329008)
			(xy 191.629481 -366.303507) (xy 191.682265 -366.2855) (xy 191.737108 -366.27537) (xy 191.792842 -366.273333)
			(xy 191.848279 -366.279433) (xy 191.902236 -366.293539) (xy 191.953565 -366.315351) (xy 191.988349 -366.33658)
			(xy 197.005448 -366.33658) (xy 197.005908 -366.31057) (xy 197.012979 -366.259032) (xy 197.026987 -366.208932)
			(xy 197.047672 -366.161201) (xy 197.07465 -366.116722) (xy 197.107422 -366.076322) (xy 197.145379 -366.040749)
			(xy 197.187817 -366.010663) (xy 197.21068 -365.998252) (xy 197.22084 -365.992918) (xy 197.234302 -365.975392)
			(xy 197.253606 -365.888524) (xy 197.255522 -365.877633) (xy 197.250909 -365.85603) (xy 197.244716 -365.846868)
			(xy 197.244462 -365.846614) (xy 197.226193 -365.821546) (xy 197.197163 -365.766734) (xy 197.177374 -365.70795)
			(xy 197.167345 -365.646741) (xy 197.166738 -365.615728) (xy 197.167224 -365.588477) (xy 197.17498 -365.534529)
			(xy 197.190335 -365.482234) (xy 197.212977 -365.432657) (xy 197.242443 -365.386807) (xy 197.278134 -365.345616)
			(xy 197.319325 -365.309925) (xy 197.365175 -365.280459) (xy 197.414752 -365.257817) (xy 197.467047 -365.242462)
			(xy 197.520995 -365.234706) (xy 197.575497 -365.234706) (xy 197.629445 -365.242462) (xy 197.68174 -365.257817)
			(xy 197.731317 -365.280459) (xy 197.777167 -365.309925) (xy 197.818358 -365.345616) (xy 197.854049 -365.386807)
			(xy 197.883515 -365.432657) (xy 197.906157 -365.482234) (xy 197.921512 -365.534529) (xy 197.929268 -365.588477)
			(xy 197.929754 -365.615728) (xy 197.929299 -365.641739) (xy 197.922228 -365.693277) (xy 197.908219 -365.743376)
			(xy 197.887533 -365.791108) (xy 197.860554 -365.835586) (xy 197.827781 -365.875986) (xy 197.789824 -365.911559)
			(xy 197.747385 -365.941645) (xy 197.724522 -365.954056) (xy 197.714362 -365.95939) (xy 197.7009 -365.976916)
			(xy 197.681596 -366.063784) (xy 197.679674 -366.074675) (xy 197.684292 -366.096278) (xy 197.690486 -366.10544)
			(xy 197.69074 -366.105694) (xy 197.709013 -366.130759) (xy 197.738042 -366.185573) (xy 197.75783 -366.244357)
			(xy 197.767858 -366.305567) (xy 197.768464 -366.33658) (xy 197.767978 -366.363831) (xy 197.760222 -366.417779)
			(xy 197.744867 -366.470074) (xy 197.737846 -366.485447) (xy 199.693324 -366.485447) (xy 199.693324 -366.430953)
			(xy 199.701079 -366.377014) (xy 199.716431 -366.324728) (xy 199.739068 -366.275158) (xy 199.768528 -366.229314)
			(xy 199.804213 -366.18813) (xy 199.845395 -366.152443) (xy 199.891237 -366.122979) (xy 199.940805 -366.100339)
			(xy 199.993091 -366.084984) (xy 200.047029 -366.077226) (xy 200.074276 -366.076738) (xy 200.099405 -366.077117)
			(xy 200.149228 -366.083724) (xy 200.197752 -366.096816) (xy 200.244138 -366.116164) (xy 200.287582 -366.141433)
			(xy 200.307702 -366.156494) (xy 200.315165 -366.161733) (xy 200.332568 -366.167124) (xy 200.350761 -366.166132)
			(xy 200.359264 -366.162844) (xy 200.440798 -366.127284) (xy 200.444455 -366.125537) (xy 200.45122 -366.121075)
			(xy 200.45426 -366.118394) (xy 200.462134 -366.109504) (xy 200.470008 -366.098074) (xy 200.471278 -366.084358)
			(xy 200.474123 -366.05607) (xy 200.487093 -366.000718) (xy 200.508134 -365.947904) (xy 200.53678 -365.898798)
			(xy 200.572398 -365.854487) (xy 200.614197 -365.815953) (xy 200.661252 -365.784049) (xy 200.712521 -365.759482)
			(xy 200.766869 -365.742796) (xy 200.82309 -365.734361) (xy 200.851516 -365.733838) (xy 200.880176 -365.734359)
			(xy 200.93685 -365.742944) (xy 200.991605 -365.759903) (xy 201.04321 -365.784856) (xy 201.090505 -365.817241)
			(xy 201.132428 -365.856332) (xy 201.168038 -365.901249) (xy 201.182732 -365.925862) (xy 201.189336 -365.937546)
			(xy 201.211942 -365.951008) (xy 201.325226 -365.954564) (xy 201.34834 -365.942372) (xy 201.355706 -365.931196)
			(xy 201.370883 -365.908897) (xy 201.406561 -365.86844) (xy 201.447584 -365.833414) (xy 201.493133 -365.804518)
			(xy 201.542299 -365.782329) (xy 201.594101 -365.76729) (xy 201.647505 -365.759699) (xy 201.674476 -365.759238)
			(xy 201.701733 -365.759607) (xy 201.755693 -365.767362) (xy 201.808 -365.782718) (xy 201.85759 -365.805362)
			(xy 201.903451 -365.834833) (xy 201.944652 -365.870531) (xy 201.980352 -365.911729) (xy 202.006902 -365.95304)
			(xy 202.97216 -365.95304) (xy 202.976231 -365.897418) (xy 202.988357 -365.842981) (xy 203.00828 -365.79089)
			(xy 203.035576 -365.742255) (xy 203.069662 -365.698112) (xy 203.109811 -365.659403) (xy 203.155169 -365.626952)
			(xy 203.204769 -365.601451) (xy 203.257553 -365.583444) (xy 203.312396 -365.573314) (xy 203.36813 -365.571277)
			(xy 203.423567 -365.577377) (xy 203.477524 -365.591483) (xy 203.528853 -365.613295) (xy 203.576459 -365.642349)
			(xy 203.619327 -365.678024) (xy 203.656544 -365.719561) (xy 203.687317 -365.766074) (xy 203.710989 -365.816571)
			(xy 203.727057 -365.869978) (xy 203.735177 -365.925154) (xy 203.735686 -365.95304) (xy 203.735177 -365.980926)
			(xy 203.727057 -366.036102) (xy 203.710989 -366.089509) (xy 203.687317 -366.140006) (xy 203.656544 -366.186519)
			(xy 203.619327 -366.228056) (xy 203.576459 -366.263731) (xy 203.528853 -366.292785) (xy 203.477524 -366.314597)
			(xy 203.423567 -366.328703) (xy 203.36813 -366.334803) (xy 203.312396 -366.332766) (xy 203.257553 -366.322636)
			(xy 203.204769 -366.304629) (xy 203.155169 -366.279128) (xy 203.109811 -366.246677) (xy 203.069662 -366.207968)
			(xy 203.035576 -366.163825) (xy 203.00828 -366.11519) (xy 202.988357 -366.063099) (xy 202.976231 -366.008662)
			(xy 202.97216 -365.95304) (xy 202.006902 -365.95304) (xy 202.009826 -365.957589) (xy 202.032473 -366.007177)
			(xy 202.047832 -366.059483) (xy 202.055591 -366.113443) (xy 202.055591 -366.167957) (xy 202.047832 -366.221917)
			(xy 202.032473 -366.274223) (xy 202.009826 -366.323811) (xy 201.980352 -366.369671) (xy 201.944652 -366.410869)
			(xy 201.903451 -366.446567) (xy 201.85759 -366.476038) (xy 201.808 -366.498682) (xy 201.755693 -366.514038)
			(xy 201.701733 -366.521793) (xy 201.674476 -366.522254) (xy 201.645815 -366.521743) (xy 201.58914 -366.513157)
			(xy 201.534386 -366.496196) (xy 201.482781 -366.471242) (xy 201.435486 -366.438855) (xy 201.393562 -366.399763)
			(xy 201.357953 -366.354843) (xy 201.34326 -366.33023) (xy 201.336656 -366.318546) (xy 201.31405 -366.305084)
			(xy 201.200766 -366.301528) (xy 201.177652 -366.31372) (xy 201.170286 -366.324896) (xy 201.155046 -366.347151)
			(xy 201.119379 -366.387609) (xy 201.078368 -366.422638) (xy 201.032829 -366.451539) (xy 200.983673 -366.473736)
			(xy 200.93188 -366.488785) (xy 200.878484 -366.496386) (xy 200.851516 -366.496854) (xy 200.826386 -366.496481)
			(xy 200.776563 -366.489872) (xy 200.728039 -366.47678) (xy 200.681654 -366.457431) (xy 200.63821 -366.432159)
			(xy 200.61809 -366.417098) (xy 200.610631 -366.411853) (xy 200.593225 -366.406464) (xy 200.575032 -366.407458)
			(xy 200.566528 -366.410748) (xy 200.484994 -366.446308) (xy 200.481337 -366.448055) (xy 200.474572 -366.452517)
			(xy 200.471532 -366.455198) (xy 200.463658 -366.464088) (xy 200.455784 -366.475518) (xy 200.454514 -366.489234)
			(xy 200.45167 -366.517522) (xy 200.438701 -366.572875) (xy 200.41766 -366.625689) (xy 200.389014 -366.674796)
			(xy 200.353397 -366.719108) (xy 200.311597 -366.757642) (xy 200.264542 -366.789546) (xy 200.213272 -366.814112)
			(xy 200.158924 -366.830797) (xy 200.102702 -366.839232) (xy 200.074276 -366.839754) (xy 200.047029 -366.839174)
			(xy 199.993091 -366.831416) (xy 199.940805 -366.816061) (xy 199.891237 -366.793421) (xy 199.845395 -366.763957)
			(xy 199.804213 -366.72827) (xy 199.768528 -366.687086) (xy 199.739068 -366.641242) (xy 199.716431 -366.591672)
			(xy 199.701079 -366.539386) (xy 199.693324 -366.485447) (xy 197.737846 -366.485447) (xy 197.722225 -366.519651)
			(xy 197.692759 -366.565501) (xy 197.657068 -366.606692) (xy 197.615877 -366.642383) (xy 197.570027 -366.671849)
			(xy 197.52045 -366.694491) (xy 197.468155 -366.709846) (xy 197.414207 -366.717602) (xy 197.359705 -366.717602)
			(xy 197.305757 -366.709846) (xy 197.253462 -366.694491) (xy 197.203885 -366.671849) (xy 197.158035 -366.642383)
			(xy 197.116844 -366.606692) (xy 197.081153 -366.565501) (xy 197.051687 -366.519651) (xy 197.029045 -366.470074)
			(xy 197.01369 -366.417779) (xy 197.005934 -366.363831) (xy 197.005448 -366.33658) (xy 191.988349 -366.33658)
			(xy 192.001171 -366.344405) (xy 192.044039 -366.38008) (xy 192.081256 -366.421617) (xy 192.112029 -366.46813)
			(xy 192.135701 -366.518627) (xy 192.151769 -366.572034) (xy 192.159889 -366.62721) (xy 192.160398 -366.655096)
			(xy 192.159889 -366.682982) (xy 192.151769 -366.738158) (xy 192.135701 -366.791565) (xy 192.112029 -366.842062)
			(xy 192.081256 -366.888575) (xy 192.044039 -366.930112) (xy 192.001171 -366.965787) (xy 191.953565 -366.994841)
			(xy 191.902236 -367.016653) (xy 191.848279 -367.030759) (xy 191.792842 -367.036859) (xy 191.737108 -367.034822)
			(xy 191.682265 -367.024692) (xy 191.629481 -367.006685) (xy 191.579881 -366.981184) (xy 191.534523 -366.948733)
			(xy 191.494374 -366.910024) (xy 191.460288 -366.865881) (xy 191.432992 -366.817246) (xy 191.413069 -366.765155)
			(xy 191.400943 -366.710718) (xy 191.396872 -366.655096) (xy 185.023252 -366.655096) (xy 185.023252 -367.216182)
			(xy 188.252352 -367.216182) (xy 188.256423 -367.16056) (xy 188.268549 -367.106123) (xy 188.288472 -367.054032)
			(xy 188.315768 -367.005397) (xy 188.349854 -366.961254) (xy 188.390003 -366.922545) (xy 188.435361 -366.890094)
			(xy 188.484961 -366.864593) (xy 188.537745 -366.846586) (xy 188.592588 -366.836456) (xy 188.648322 -366.834419)
			(xy 188.703759 -366.840519) (xy 188.757716 -366.854625) (xy 188.809045 -366.876437) (xy 188.856651 -366.905491)
			(xy 188.899519 -366.941166) (xy 188.936736 -366.982703) (xy 188.967509 -367.029216) (xy 188.991181 -367.079713)
			(xy 189.007249 -367.13312) (xy 189.015369 -367.188296) (xy 189.015878 -367.216182) (xy 189.015369 -367.244068)
			(xy 189.007249 -367.299244) (xy 188.993724 -367.344198) (xy 197.042022 -367.344198) (xy 197.046093 -367.288576)
			(xy 197.058219 -367.234139) (xy 197.078142 -367.182048) (xy 197.105438 -367.133413) (xy 197.139524 -367.08927)
			(xy 197.179673 -367.050561) (xy 197.225031 -367.01811) (xy 197.274631 -366.992609) (xy 197.327415 -366.974602)
			(xy 197.382258 -366.964472) (xy 197.437992 -366.962435) (xy 197.493429 -366.968535) (xy 197.547386 -366.982641)
			(xy 197.598715 -367.004453) (xy 197.646321 -367.033507) (xy 197.689189 -367.069182) (xy 197.726406 -367.110719)
			(xy 197.757179 -367.157232) (xy 197.780851 -367.207729) (xy 197.796919 -367.261136) (xy 197.805039 -367.316312)
			(xy 197.805548 -367.344198) (xy 197.805039 -367.372084) (xy 197.796919 -367.42726) (xy 197.780851 -367.480667)
			(xy 197.757179 -367.531164) (xy 197.726406 -367.577677) (xy 197.689189 -367.619214) (xy 197.646321 -367.654889)
			(xy 197.598715 -367.683943) (xy 197.547386 -367.705755) (xy 197.493429 -367.719861) (xy 197.437992 -367.725961)
			(xy 197.382258 -367.723924) (xy 197.327415 -367.713794) (xy 197.274631 -367.695787) (xy 197.225031 -367.670286)
			(xy 197.179673 -367.637835) (xy 197.139524 -367.599126) (xy 197.105438 -367.554983) (xy 197.078142 -367.506348)
			(xy 197.058219 -367.454257) (xy 197.046093 -367.39982) (xy 197.042022 -367.344198) (xy 188.993724 -367.344198)
			(xy 188.991181 -367.352651) (xy 188.967509 -367.403148) (xy 188.936736 -367.449661) (xy 188.899519 -367.491198)
			(xy 188.856651 -367.526873) (xy 188.809045 -367.555927) (xy 188.757716 -367.577739) (xy 188.703759 -367.591845)
			(xy 188.648322 -367.597945) (xy 188.592588 -367.595908) (xy 188.537745 -367.585778) (xy 188.484961 -367.567771)
			(xy 188.435361 -367.54227) (xy 188.390003 -367.509819) (xy 188.349854 -367.47111) (xy 188.315768 -367.426967)
			(xy 188.288472 -367.378332) (xy 188.268549 -367.326241) (xy 188.256423 -367.271804) (xy 188.252352 -367.216182)
			(xy 185.023252 -367.216182) (xy 185.023252 -367.76533) (xy 200.369676 -367.76533) (xy 200.373747 -367.709708)
			(xy 200.385873 -367.655271) (xy 200.405796 -367.60318) (xy 200.433092 -367.554545) (xy 200.467178 -367.510402)
			(xy 200.507327 -367.471693) (xy 200.552685 -367.439242) (xy 200.602285 -367.413741) (xy 200.655069 -367.395734)
			(xy 200.709912 -367.385604) (xy 200.765646 -367.383567) (xy 200.821083 -367.389667) (xy 200.87504 -367.403773)
			(xy 200.926369 -367.425585) (xy 200.973975 -367.454639) (xy 201.016843 -367.490314) (xy 201.05406 -367.531851)
			(xy 201.084833 -367.578364) (xy 201.108505 -367.628861) (xy 201.124573 -367.682268) (xy 201.132693 -367.737444)
			(xy 201.133202 -367.76533) (xy 201.132693 -367.793216) (xy 201.124573 -367.848392) (xy 201.108505 -367.901799)
			(xy 201.084833 -367.952296) (xy 201.05406 -367.998809) (xy 201.016843 -368.040346) (xy 200.973975 -368.076021)
			(xy 200.926369 -368.105075) (xy 200.87504 -368.126887) (xy 200.821083 -368.140993) (xy 200.765646 -368.147093)
			(xy 200.709912 -368.145056) (xy 200.655069 -368.134926) (xy 200.602285 -368.116919) (xy 200.552685 -368.091418)
			(xy 200.507327 -368.058967) (xy 200.467178 -368.020258) (xy 200.433092 -367.976115) (xy 200.405796 -367.92748)
			(xy 200.385873 -367.875389) (xy 200.373747 -367.820952) (xy 200.369676 -367.76533) (xy 185.023252 -367.76533)
			(xy 185.023252 -368.349022) (xy 197.160132 -368.349022) (xy 197.164203 -368.2934) (xy 197.176329 -368.238963)
			(xy 197.196252 -368.186872) (xy 197.223548 -368.138237) (xy 197.257634 -368.094094) (xy 197.297783 -368.055385)
			(xy 197.343141 -368.022934) (xy 197.392741 -367.997433) (xy 197.445525 -367.979426) (xy 197.500368 -367.969296)
			(xy 197.556102 -367.967259) (xy 197.611539 -367.973359) (xy 197.665496 -367.987465) (xy 197.716825 -368.009277)
			(xy 197.764431 -368.038331) (xy 197.807299 -368.074006) (xy 197.844516 -368.115543) (xy 197.875289 -368.162056)
			(xy 197.898961 -368.212553) (xy 197.915029 -368.26596) (xy 197.923149 -368.321136) (xy 197.923658 -368.349022)
			(xy 197.923149 -368.376908) (xy 197.915029 -368.432084) (xy 197.898961 -368.485491) (xy 197.876609 -368.533172)
			(xy 201.113134 -368.533172) (xy 201.117205 -368.47755) (xy 201.129331 -368.423113) (xy 201.149254 -368.371022)
			(xy 201.17655 -368.322387) (xy 201.210636 -368.278244) (xy 201.250785 -368.239535) (xy 201.296143 -368.207084)
			(xy 201.345743 -368.181583) (xy 201.398527 -368.163576) (xy 201.45337 -368.153446) (xy 201.509104 -368.151409)
			(xy 201.564541 -368.157509) (xy 201.618498 -368.171615) (xy 201.669827 -368.193427) (xy 201.717433 -368.222481)
			(xy 201.760301 -368.258156) (xy 201.797518 -368.299693) (xy 201.828291 -368.346206) (xy 201.851963 -368.396703)
			(xy 201.868031 -368.45011) (xy 201.876151 -368.505286) (xy 201.87666 -368.533172) (xy 201.876151 -368.561058)
			(xy 201.868031 -368.616234) (xy 201.851963 -368.669641) (xy 201.828291 -368.720138) (xy 201.797518 -368.766651)
			(xy 201.760301 -368.808188) (xy 201.717433 -368.843863) (xy 201.669827 -368.872917) (xy 201.618498 -368.894729)
			(xy 201.564541 -368.908835) (xy 201.509104 -368.914935) (xy 201.45337 -368.912898) (xy 201.398527 -368.902768)
			(xy 201.345743 -368.884761) (xy 201.296143 -368.85926) (xy 201.250785 -368.826809) (xy 201.210636 -368.7881)
			(xy 201.17655 -368.743957) (xy 201.149254 -368.695322) (xy 201.129331 -368.643231) (xy 201.117205 -368.588794)
			(xy 201.113134 -368.533172) (xy 197.876609 -368.533172) (xy 197.875289 -368.535988) (xy 197.844516 -368.582501)
			(xy 197.807299 -368.624038) (xy 197.764431 -368.659713) (xy 197.716825 -368.688767) (xy 197.665496 -368.710579)
			(xy 197.611539 -368.724685) (xy 197.556102 -368.730785) (xy 197.500368 -368.728748) (xy 197.445525 -368.718618)
			(xy 197.392741 -368.700611) (xy 197.343141 -368.67511) (xy 197.297783 -368.642659) (xy 197.257634 -368.60395)
			(xy 197.223548 -368.559807) (xy 197.196252 -368.511172) (xy 197.176329 -368.459081) (xy 197.164203 -368.404644)
			(xy 197.160132 -368.349022) (xy 185.023252 -368.349022) (xy 185.023252 -369.139724) (xy 194.89623 -369.139724)
			(xy 194.900301 -369.084102) (xy 194.912427 -369.029665) (xy 194.93235 -368.977574) (xy 194.959646 -368.928939)
			(xy 194.993732 -368.884796) (xy 195.033881 -368.846087) (xy 195.079239 -368.813636) (xy 195.128839 -368.788135)
			(xy 195.181623 -368.770128) (xy 195.236466 -368.759998) (xy 195.2922 -368.757961) (xy 195.347637 -368.764061)
			(xy 195.401594 -368.778167) (xy 195.452923 -368.799979) (xy 195.500529 -368.829033) (xy 195.543397 -368.864708)
			(xy 195.580614 -368.906245) (xy 195.611387 -368.952758) (xy 195.635059 -369.003255) (xy 195.637679 -369.011962)
			(xy 199.412096 -369.011962) (xy 199.416167 -368.95634) (xy 199.428293 -368.901903) (xy 199.448216 -368.849812)
			(xy 199.475512 -368.801177) (xy 199.509598 -368.757034) (xy 199.549747 -368.718325) (xy 199.595105 -368.685874)
			(xy 199.644705 -368.660373) (xy 199.697489 -368.642366) (xy 199.752332 -368.632236) (xy 199.808066 -368.630199)
			(xy 199.863503 -368.636299) (xy 199.91746 -368.650405) (xy 199.968789 -368.672217) (xy 200.016395 -368.701271)
			(xy 200.059263 -368.736946) (xy 200.09648 -368.778483) (xy 200.127253 -368.824996) (xy 200.150925 -368.875493)
			(xy 200.166993 -368.9289) (xy 200.175113 -368.984076) (xy 200.175622 -369.011962) (xy 200.175113 -369.039848)
			(xy 200.166993 -369.095024) (xy 200.150925 -369.148431) (xy 200.127253 -369.198928) (xy 200.09648 -369.245441)
			(xy 200.059263 -369.286978) (xy 200.016395 -369.322653) (xy 199.968789 -369.351707) (xy 199.91746 -369.373519)
			(xy 199.863503 -369.387625) (xy 199.808066 -369.393725) (xy 199.752332 -369.391688) (xy 199.697489 -369.381558)
			(xy 199.644705 -369.363551) (xy 199.595105 -369.33805) (xy 199.549747 -369.305599) (xy 199.509598 -369.26689)
			(xy 199.475512 -369.222747) (xy 199.448216 -369.174112) (xy 199.428293 -369.122021) (xy 199.416167 -369.067584)
			(xy 199.412096 -369.011962) (xy 195.637679 -369.011962) (xy 195.651127 -369.056662) (xy 195.659247 -369.111838)
			(xy 195.659756 -369.139724) (xy 195.659247 -369.16761) (xy 195.651127 -369.222786) (xy 195.635059 -369.276193)
			(xy 195.611387 -369.32669) (xy 195.580614 -369.373203) (xy 195.543397 -369.41474) (xy 195.500529 -369.450415)
			(xy 195.452923 -369.479469) (xy 195.401594 -369.501281) (xy 195.347637 -369.515387) (xy 195.2922 -369.521487)
			(xy 195.236466 -369.51945) (xy 195.181623 -369.50932) (xy 195.128839 -369.491313) (xy 195.079239 -369.465812)
			(xy 195.033881 -369.433361) (xy 194.993732 -369.394652) (xy 194.959646 -369.350509) (xy 194.93235 -369.301874)
			(xy 194.912427 -369.249783) (xy 194.900301 -369.195346) (xy 194.89623 -369.139724) (xy 185.023252 -369.139724)
			(xy 185.023252 -369.609624) (xy 197.338694 -369.609624) (xy 197.342765 -369.554002) (xy 197.354891 -369.499565)
			(xy 197.374814 -369.447474) (xy 197.40211 -369.398839) (xy 197.436196 -369.354696) (xy 197.476345 -369.315987)
			(xy 197.521703 -369.283536) (xy 197.571303 -369.258035) (xy 197.624087 -369.240028) (xy 197.67893 -369.229898)
			(xy 197.734664 -369.227861) (xy 197.790101 -369.233961) (xy 197.844058 -369.248067) (xy 197.895387 -369.269879)
			(xy 197.942993 -369.298933) (xy 197.985861 -369.334608) (xy 198.023078 -369.376145) (xy 198.053851 -369.422658)
			(xy 198.077523 -369.473155) (xy 198.093591 -369.526562) (xy 198.101711 -369.581738) (xy 198.10222 -369.609624)
			(xy 198.101711 -369.63751) (xy 198.093591 -369.692686) (xy 198.077523 -369.746093) (xy 198.077318 -369.74653)
			(xy 200.529188 -369.74653) (xy 200.533259 -369.690908) (xy 200.545385 -369.636471) (xy 200.565308 -369.58438)
			(xy 200.592604 -369.535745) (xy 200.62669 -369.491602) (xy 200.666839 -369.452893) (xy 200.712197 -369.420442)
			(xy 200.761797 -369.394941) (xy 200.814581 -369.376934) (xy 200.869424 -369.366804) (xy 200.925158 -369.364767)
			(xy 200.980595 -369.370867) (xy 201.034552 -369.384973) (xy 201.085881 -369.406785) (xy 201.133487 -369.435839)
			(xy 201.176355 -369.471514) (xy 201.213572 -369.513051) (xy 201.244345 -369.559564) (xy 201.268017 -369.610061)
			(xy 201.284085 -369.663468) (xy 201.292205 -369.718644) (xy 201.292714 -369.74653) (xy 201.292205 -369.774416)
			(xy 201.284085 -369.829592) (xy 201.268017 -369.882999) (xy 201.244345 -369.933496) (xy 201.213572 -369.980009)
			(xy 201.176355 -370.021546) (xy 201.133487 -370.057221) (xy 201.085881 -370.086275) (xy 201.034552 -370.108087)
			(xy 200.980595 -370.122193) (xy 200.925158 -370.128293) (xy 200.869424 -370.126256) (xy 200.814581 -370.116126)
			(xy 200.761797 -370.098119) (xy 200.712197 -370.072618) (xy 200.666839 -370.040167) (xy 200.62669 -370.001458)
			(xy 200.592604 -369.957315) (xy 200.565308 -369.90868) (xy 200.545385 -369.856589) (xy 200.533259 -369.802152)
			(xy 200.529188 -369.74653) (xy 198.077318 -369.74653) (xy 198.053851 -369.79659) (xy 198.023078 -369.843103)
			(xy 197.985861 -369.88464) (xy 197.942993 -369.920315) (xy 197.895387 -369.949369) (xy 197.844058 -369.971181)
			(xy 197.790101 -369.985287) (xy 197.734664 -369.991387) (xy 197.67893 -369.98935) (xy 197.624087 -369.97922)
			(xy 197.571303 -369.961213) (xy 197.521703 -369.935712) (xy 197.476345 -369.903261) (xy 197.436196 -369.864552)
			(xy 197.40211 -369.820409) (xy 197.374814 -369.771774) (xy 197.354891 -369.719683) (xy 197.342765 -369.665246)
			(xy 197.338694 -369.609624) (xy 185.023252 -369.609624) (xy 185.023252 -370.529358) (xy 189.975488 -370.529358)
			(xy 189.979559 -370.473736) (xy 189.991685 -370.419299) (xy 190.011608 -370.367208) (xy 190.038904 -370.318573)
			(xy 190.07299 -370.27443) (xy 190.113139 -370.235721) (xy 190.158497 -370.20327) (xy 190.208097 -370.177769)
			(xy 190.260881 -370.159762) (xy 190.315724 -370.149632) (xy 190.371458 -370.147595) (xy 190.426895 -370.153695)
			(xy 190.480852 -370.167801) (xy 190.532181 -370.189613) (xy 190.579787 -370.218667) (xy 190.622655 -370.254342)
			(xy 190.659872 -370.295879) (xy 190.690645 -370.342392) (xy 190.714317 -370.392889) (xy 190.730385 -370.446296)
			(xy 190.738505 -370.501472) (xy 190.739014 -370.529358) (xy 190.738505 -370.557244) (xy 190.730385 -370.61242)
			(xy 190.714317 -370.665827) (xy 190.690645 -370.716324) (xy 190.659872 -370.762837) (xy 190.622655 -370.804374)
			(xy 190.579787 -370.840049) (xy 190.534919 -370.867432) (xy 198.657208 -370.867432) (xy 198.661281 -370.811773)
			(xy 198.673416 -370.7573) (xy 198.693352 -370.705174) (xy 198.720666 -370.656506) (xy 198.754774 -370.612334)
			(xy 198.794951 -370.573599) (xy 198.840339 -370.541127) (xy 198.889971 -370.515609) (xy 198.942791 -370.49759)
			(xy 198.99767 -370.487453) (xy 199.053441 -370.485415) (xy 199.108915 -370.491518) (xy 199.162908 -370.505634)
			(xy 199.214271 -370.527461) (xy 199.261909 -370.556534) (xy 199.304805 -370.592233) (xy 199.342047 -370.633797)
			(xy 199.372841 -370.680341) (xy 199.396529 -370.730872) (xy 199.412607 -370.784314) (xy 199.420733 -370.839528)
			(xy 199.421242 -370.867432) (xy 199.420733 -370.895336) (xy 199.412607 -370.95055) (xy 199.405136 -370.975382)
			(xy 199.52538 -370.975382) (xy 199.529453 -370.919723) (xy 199.541588 -370.86525) (xy 199.561524 -370.813124)
			(xy 199.588838 -370.764456) (xy 199.622946 -370.720284) (xy 199.663123 -370.681549) (xy 199.708511 -370.649077)
			(xy 199.758143 -370.623559) (xy 199.810963 -370.60554) (xy 199.865842 -370.595403) (xy 199.921613 -370.593365)
			(xy 199.977087 -370.599468) (xy 200.03108 -370.613584) (xy 200.082443 -370.635411) (xy 200.130081 -370.664484)
			(xy 200.172977 -370.700183) (xy 200.210219 -370.741747) (xy 200.241013 -370.788291) (xy 200.264701 -370.838822)
			(xy 200.280779 -370.892264) (xy 200.288905 -370.947478) (xy 200.289414 -370.975382) (xy 200.288905 -371.003286)
			(xy 200.280779 -371.0585) (xy 200.264701 -371.111942) (xy 200.241013 -371.162473) (xy 200.210219 -371.209017)
			(xy 200.172977 -371.250581) (xy 200.130081 -371.28628) (xy 200.082443 -371.315353) (xy 200.03108 -371.33718)
			(xy 199.977087 -371.351296) (xy 199.921613 -371.357399) (xy 199.865842 -371.355361) (xy 199.810963 -371.345224)
			(xy 199.758143 -371.327205) (xy 199.708511 -371.301687) (xy 199.663123 -371.269215) (xy 199.622946 -371.23048)
			(xy 199.588838 -371.186308) (xy 199.561524 -371.13764) (xy 199.541588 -371.085514) (xy 199.529453 -371.031041)
			(xy 199.52538 -370.975382) (xy 199.405136 -370.975382) (xy 199.396529 -371.003992) (xy 199.372841 -371.054523)
			(xy 199.342047 -371.101067) (xy 199.304805 -371.142631) (xy 199.261909 -371.17833) (xy 199.214271 -371.207403)
			(xy 199.162908 -371.22923) (xy 199.108915 -371.243346) (xy 199.053441 -371.249449) (xy 198.99767 -371.247411)
			(xy 198.942791 -371.237274) (xy 198.889971 -371.219255) (xy 198.840339 -371.193737) (xy 198.794951 -371.161265)
			(xy 198.754774 -371.12253) (xy 198.720666 -371.078358) (xy 198.693352 -371.02969) (xy 198.673416 -370.977564)
			(xy 198.661281 -370.923091) (xy 198.657208 -370.867432) (xy 190.534919 -370.867432) (xy 190.532181 -370.869103)
			(xy 190.480852 -370.890915) (xy 190.426895 -370.905021) (xy 190.371458 -370.911121) (xy 190.315724 -370.909084)
			(xy 190.260881 -370.898954) (xy 190.208097 -370.880947) (xy 190.158497 -370.855446) (xy 190.113139 -370.822995)
			(xy 190.07299 -370.784286) (xy 190.038904 -370.740143) (xy 190.011608 -370.691508) (xy 189.991685 -370.639417)
			(xy 189.979559 -370.58498) (xy 189.975488 -370.529358) (xy 185.023252 -370.529358) (xy 185.023252 -371.718586)
			(xy 200.352912 -371.718586) (xy 200.356985 -371.662927) (xy 200.36912 -371.608454) (xy 200.389056 -371.556328)
			(xy 200.41637 -371.50766) (xy 200.450478 -371.463488) (xy 200.490655 -371.424753) (xy 200.536043 -371.392281)
			(xy 200.585675 -371.366763) (xy 200.638495 -371.348744) (xy 200.693374 -371.338607) (xy 200.749145 -371.336569)
			(xy 200.804619 -371.342672) (xy 200.858612 -371.356788) (xy 200.909975 -371.378615) (xy 200.957613 -371.407688)
			(xy 201.000509 -371.443387) (xy 201.037751 -371.484951) (xy 201.068545 -371.531495) (xy 201.092233 -371.582026)
			(xy 201.108311 -371.635468) (xy 201.116437 -371.690682) (xy 201.116946 -371.718586) (xy 201.116437 -371.74649)
			(xy 201.108311 -371.801704) (xy 201.092233 -371.855146) (xy 201.070638 -371.901212) (xy 201.294998 -371.901212)
			(xy 201.299071 -371.845553) (xy 201.311206 -371.79108) (xy 201.331142 -371.738954) (xy 201.358456 -371.690286)
			(xy 201.392564 -371.646114) (xy 201.432741 -371.607379) (xy 201.478129 -371.574907) (xy 201.527761 -371.549389)
			(xy 201.580581 -371.53137) (xy 201.63546 -371.521233) (xy 201.691231 -371.519195) (xy 201.746705 -371.525298)
			(xy 201.800698 -371.539414) (xy 201.852061 -371.561241) (xy 201.899699 -371.590314) (xy 201.942595 -371.626013)
			(xy 201.979837 -371.667577) (xy 202.010631 -371.714121) (xy 202.034319 -371.764652) (xy 202.050397 -371.818094)
			(xy 202.058523 -371.873308) (xy 202.059032 -371.901212) (xy 202.058523 -371.929116) (xy 202.050397 -371.98433)
			(xy 202.034319 -372.037772) (xy 202.010631 -372.088303) (xy 201.979837 -372.134847) (xy 201.942595 -372.176411)
			(xy 201.899699 -372.21211) (xy 201.852061 -372.241183) (xy 201.800698 -372.26301) (xy 201.746705 -372.277126)
			(xy 201.691231 -372.283229) (xy 201.63546 -372.281191) (xy 201.580581 -372.271054) (xy 201.527761 -372.253035)
			(xy 201.478129 -372.227517) (xy 201.432741 -372.195045) (xy 201.392564 -372.15631) (xy 201.358456 -372.112138)
			(xy 201.331142 -372.06347) (xy 201.311206 -372.011344) (xy 201.299071 -371.956871) (xy 201.294998 -371.901212)
			(xy 201.070638 -371.901212) (xy 201.068545 -371.905677) (xy 201.037751 -371.952221) (xy 201.000509 -371.993785)
			(xy 200.957613 -372.029484) (xy 200.909975 -372.058557) (xy 200.858612 -372.080384) (xy 200.804619 -372.0945)
			(xy 200.749145 -372.100603) (xy 200.693374 -372.098565) (xy 200.638495 -372.088428) (xy 200.585675 -372.070409)
			(xy 200.536043 -372.044891) (xy 200.490655 -372.012419) (xy 200.450478 -371.973684) (xy 200.41637 -371.929512)
			(xy 200.389056 -371.880844) (xy 200.36912 -371.828718) (xy 200.356985 -371.774245) (xy 200.352912 -371.718586)
			(xy 185.023252 -371.718586) (xy 185.023252 -372.890034) (xy 201.22337 -372.890034) (xy 201.227443 -372.834375)
			(xy 201.239578 -372.779902) (xy 201.259514 -372.727776) (xy 201.286828 -372.679108) (xy 201.320936 -372.634936)
			(xy 201.361113 -372.596201) (xy 201.406501 -372.563729) (xy 201.456133 -372.538211) (xy 201.508953 -372.520192)
			(xy 201.563832 -372.510055) (xy 201.619603 -372.508017) (xy 201.675077 -372.51412) (xy 201.72907 -372.528236)
			(xy 201.780433 -372.550063) (xy 201.828071 -372.579136) (xy 201.870967 -372.614835) (xy 201.908209 -372.656399)
			(xy 201.939003 -372.702943) (xy 201.962691 -372.753474) (xy 201.978769 -372.806916) (xy 201.983974 -372.842282)
			(xy 202.07732 -372.842282) (xy 202.077806 -372.815013) (xy 202.085568 -372.761029) (xy 202.100933 -372.708699)
			(xy 202.12359 -372.659089) (xy 202.153076 -372.613208) (xy 202.188791 -372.571991) (xy 202.230008 -372.536276)
			(xy 202.275889 -372.50679) (xy 202.325499 -372.484133) (xy 202.377829 -372.468768) (xy 202.431813 -372.461006)
			(xy 202.486351 -372.461006) (xy 202.540335 -372.468768) (xy 202.592665 -372.484133) (xy 202.642275 -372.50679)
			(xy 202.688156 -372.536276) (xy 202.729373 -372.571991) (xy 202.765088 -372.613208) (xy 202.794574 -372.659089)
			(xy 202.817231 -372.708699) (xy 202.832596 -372.761029) (xy 202.840358 -372.815013) (xy 202.840844 -372.842282)
			(xy 202.840338 -372.870015) (xy 202.832313 -372.924897) (xy 202.816431 -372.97804) (xy 202.793024 -373.028325)
			(xy 202.762586 -373.074693) (xy 202.725759 -373.116168) (xy 202.683316 -373.151876) (xy 202.659996 -373.166894)
			(xy 202.64849 -373.174561) (xy 202.629729 -373.194852) (xy 202.617105 -373.219436) (xy 202.611545 -373.246506)
			(xy 202.613457 -373.274075) (xy 202.622701 -373.300119) (xy 202.638597 -373.322724) (xy 202.65998 -373.340232)
			(xy 202.672442 -373.346218) (xy 202.697498 -373.357765) (xy 202.74426 -373.387041) (xy 202.78632 -373.422744)
			(xy 202.822801 -373.464132) (xy 202.852943 -373.51034) (xy 202.876118 -373.560406) (xy 202.891844 -373.613288)
			(xy 202.899791 -373.667883) (xy 202.90028 -373.695468) (xy 202.899794 -373.722719) (xy 202.892038 -373.776667)
			(xy 202.876683 -373.828962) (xy 202.854041 -373.878539) (xy 202.824575 -373.924389) (xy 202.788884 -373.96558)
			(xy 202.747693 -374.001271) (xy 202.701843 -374.030737) (xy 202.652266 -374.053379) (xy 202.599971 -374.068734)
			(xy 202.546023 -374.07649) (xy 202.491521 -374.07649) (xy 202.437573 -374.068734) (xy 202.385278 -374.053379)
			(xy 202.335701 -374.030737) (xy 202.289851 -374.001271) (xy 202.24866 -373.96558) (xy 202.212969 -373.924389)
			(xy 202.183503 -373.878539) (xy 202.160861 -373.828962) (xy 202.145506 -373.776667) (xy 202.13775 -373.722719)
			(xy 202.137264 -373.695468) (xy 202.137745 -373.66776) (xy 202.145753 -373.612927) (xy 202.161612 -373.55983)
			(xy 202.184987 -373.509587) (xy 202.215386 -373.463254) (xy 202.25217 -373.421808) (xy 202.294564 -373.386121)
			(xy 202.317858 -373.37111) (xy 202.329368 -373.363445) (xy 202.348138 -373.343156) (xy 202.360768 -373.318572)
			(xy 202.366332 -373.291498) (xy 202.36442 -373.263925) (xy 202.355173 -373.237878) (xy 202.339269 -373.215272)
			(xy 202.317878 -373.197769) (xy 202.305412 -373.191786) (xy 202.280314 -373.180268) (xy 202.2335 -373.150978)
			(xy 202.191393 -373.115251) (xy 202.154871 -373.073831) (xy 202.124696 -373.027583) (xy 202.101497 -372.977471)
			(xy 202.085758 -372.924539) (xy 202.077806 -372.869893) (xy 202.07732 -372.842282) (xy 201.983974 -372.842282)
			(xy 201.986895 -372.86213) (xy 201.987404 -372.890034) (xy 201.986895 -372.917938) (xy 201.978769 -372.973152)
			(xy 201.962691 -373.026594) (xy 201.939003 -373.077125) (xy 201.908209 -373.123669) (xy 201.870967 -373.165233)
			(xy 201.828071 -373.200932) (xy 201.780433 -373.230005) (xy 201.72907 -373.251832) (xy 201.675077 -373.265948)
			(xy 201.619603 -373.272051) (xy 201.563832 -373.270013) (xy 201.508953 -373.259876) (xy 201.456133 -373.241857)
			(xy 201.406501 -373.216339) (xy 201.361113 -373.183867) (xy 201.320936 -373.145132) (xy 201.286828 -373.10096)
			(xy 201.259514 -373.052292) (xy 201.239578 -373.000166) (xy 201.227443 -372.945693) (xy 201.22337 -372.890034)
			(xy 185.023252 -372.890034) (xy 185.023252 -378.70003) (xy 190.444636 -378.70003) (xy 190.448637 -378.494991)
			(xy 190.460635 -378.290263) (xy 190.480612 -378.08616) (xy 190.508537 -377.882992) (xy 190.544367 -377.681068)
			(xy 190.588049 -377.480695) (xy 190.639515 -377.28218) (xy 190.698687 -377.085823) (xy 190.765475 -376.891925)
			(xy 190.839777 -376.70078) (xy 190.92148 -376.51268) (xy 191.010461 -376.327911) (xy 191.106582 -376.146754)
			(xy 191.209698 -375.969485) (xy 191.319652 -375.796375) (xy 191.436277 -375.627686) (xy 191.559394 -375.463676)
			(xy 191.688817 -375.304594) (xy 191.824347 -375.150683) (xy 191.96578 -375.002177) (xy 192.112899 -374.859302)
			(xy 192.26548 -374.722277) (xy 192.423292 -374.591308) (xy 192.586093 -374.466597) (xy 192.753636 -374.348332)
			(xy 192.925665 -374.236694) (xy 193.10192 -374.131853) (xy 193.28213 -374.033969) (xy 193.466022 -373.94319)
			(xy 193.653317 -373.859656) (xy 193.843727 -373.783492) (xy 194.036965 -373.714815) (xy 194.232735 -373.65373)
			(xy 194.430739 -373.60033) (xy 194.630675 -373.554696) (xy 194.83224 -373.516897) (xy 195.035126 -373.486991)
			(xy 195.239025 -373.465024) (xy 195.443625 -373.451029) (xy 195.648616 -373.445028) (xy 195.853685 -373.447028)
			(xy 196.058519 -373.457029) (xy 196.262807 -373.475013) (xy 196.466239 -373.500955) (xy 196.668503 -373.534813)
			(xy 196.869292 -373.576538) (xy 197.0683 -373.626064) (xy 197.265224 -373.683318) (xy 197.459765 -373.748211)
			(xy 197.651626 -373.820645) (xy 197.840514 -373.900509) (xy 198.026143 -373.987683) (xy 198.208229 -374.082032)
			(xy 198.386495 -374.183414) (xy 198.56067 -374.291674) (xy 198.730489 -374.406647) (xy 198.895692 -374.528158)
			(xy 199.056029 -374.656022) (xy 199.211255 -374.790045) (xy 199.249777 -374.826022) (xy 202.643738 -374.826022)
			(xy 202.647809 -374.7704) (xy 202.659935 -374.715963) (xy 202.679858 -374.663872) (xy 202.707154 -374.615237)
			(xy 202.74124 -374.571094) (xy 202.781389 -374.532385) (xy 202.826747 -374.499934) (xy 202.876347 -374.474433)
			(xy 202.929131 -374.456426) (xy 202.983974 -374.446296) (xy 203.039708 -374.444259) (xy 203.095145 -374.450359)
			(xy 203.149102 -374.464465) (xy 203.200431 -374.486277) (xy 203.248037 -374.515331) (xy 203.290905 -374.551006)
			(xy 203.328122 -374.592543) (xy 203.358895 -374.639056) (xy 203.382567 -374.689553) (xy 203.398635 -374.74296)
			(xy 203.406755 -374.798136) (xy 203.407264 -374.826022) (xy 203.406755 -374.853908) (xy 203.398635 -374.909084)
			(xy 203.382567 -374.962491) (xy 203.358895 -375.012988) (xy 203.328122 -375.059501) (xy 203.290905 -375.101038)
			(xy 203.248037 -375.136713) (xy 203.200431 -375.165767) (xy 203.149102 -375.187579) (xy 203.095145 -375.201685)
			(xy 203.039708 -375.207785) (xy 202.983974 -375.205748) (xy 202.929131 -375.195618) (xy 202.876347 -375.177611)
			(xy 202.826747 -375.15211) (xy 202.781389 -375.119659) (xy 202.74124 -375.08095) (xy 202.707154 -375.036807)
			(xy 202.679858 -374.988172) (xy 202.659935 -374.936081) (xy 202.647809 -374.881644) (xy 202.643738 -374.826022)
			(xy 199.249777 -374.826022) (xy 199.361134 -374.930022) (xy 199.505437 -375.07574) (xy 199.643945 -375.226977)
			(xy 199.776447 -375.383504) (xy 199.902741 -375.54508) (xy 200.022634 -375.711461) (xy 200.135945 -375.882393)
			(xy 200.242501 -376.057616) (xy 200.342138 -376.236863) (xy 200.434707 -376.419861) (xy 200.520065 -376.606332)
			(xy 200.598083 -376.79599) (xy 200.668641 -376.988548) (xy 200.731633 -377.183713) (xy 200.786963 -377.381187)
			(xy 200.834546 -377.580669) (xy 200.874309 -377.781855) (xy 200.906193 -377.98444) (xy 200.930148 -378.188114)
			(xy 200.946139 -378.392568) (xy 200.95414 -378.597491) (xy 200.95464 -378.70003) (xy 200.95414 -378.802569)
			(xy 200.946139 -379.007492) (xy 200.930148 -379.211946) (xy 200.906193 -379.41562) (xy 200.874309 -379.618205)
			(xy 200.834546 -379.819391) (xy 200.786963 -380.018873) (xy 200.731633 -380.216347) (xy 200.668641 -380.411512)
			(xy 200.598083 -380.60407) (xy 200.520065 -380.793728) (xy 200.434707 -380.980199) (xy 200.342138 -381.163197)
			(xy 200.242501 -381.342444) (xy 200.135945 -381.517667) (xy 200.022634 -381.688599) (xy 199.902741 -381.85498)
			(xy 199.776447 -382.016556) (xy 199.643945 -382.173083) (xy 199.505437 -382.32432) (xy 199.361134 -382.470038)
			(xy 199.211255 -382.610015) (xy 199.056029 -382.744038) (xy 198.895692 -382.871902) (xy 198.730489 -382.993413)
			(xy 198.56067 -383.108386) (xy 198.386495 -383.216646) (xy 198.208229 -383.318028) (xy 198.026143 -383.412377)
			(xy 197.840514 -383.499551) (xy 197.651626 -383.579415) (xy 197.459765 -383.651849) (xy 197.265224 -383.716742)
			(xy 197.0683 -383.773996) (xy 196.869292 -383.823522) (xy 196.668503 -383.865247) (xy 196.466239 -383.899105)
			(xy 196.262807 -383.925047) (xy 196.058519 -383.943031) (xy 195.853685 -383.953032) (xy 195.648616 -383.955032)
			(xy 195.443625 -383.949031) (xy 195.239025 -383.935036) (xy 195.035126 -383.913069) (xy 194.83224 -383.883163)
			(xy 194.630675 -383.845364) (xy 194.430739 -383.79973) (xy 194.232735 -383.74633) (xy 194.036965 -383.685245)
			(xy 193.843727 -383.616568) (xy 193.653317 -383.540404) (xy 193.466022 -383.45687) (xy 193.28213 -383.366091)
			(xy 193.10192 -383.268207) (xy 192.925665 -383.163366) (xy 192.753636 -383.051728) (xy 192.586093 -382.933463)
			(xy 192.423292 -382.808752) (xy 192.26548 -382.677783) (xy 192.112899 -382.540758) (xy 191.96578 -382.397883)
			(xy 191.824347 -382.249377) (xy 191.688817 -382.095466) (xy 191.559394 -381.936384) (xy 191.436277 -381.772374)
			(xy 191.319652 -381.603685) (xy 191.209698 -381.430575) (xy 191.106582 -381.253306) (xy 191.010461 -381.072149)
			(xy 190.92148 -380.88738) (xy 190.839777 -380.69928) (xy 190.765475 -380.508135) (xy 190.698687 -380.314237)
			(xy 190.639515 -380.11788) (xy 190.588049 -379.919365) (xy 190.544367 -379.718992) (xy 190.508537 -379.517068)
			(xy 190.480612 -379.3139) (xy 190.460635 -379.109797) (xy 190.448637 -378.905069) (xy 190.444636 -378.70003)
			(xy 185.023252 -378.70003) (xy 185.023252 -387.124702) (xy 187.712602 -387.124702) (xy 187.716673 -387.06908)
			(xy 187.728799 -387.014643) (xy 187.748722 -386.962552) (xy 187.776018 -386.913917) (xy 187.810104 -386.869774)
			(xy 187.850253 -386.831065) (xy 187.895611 -386.798614) (xy 187.945211 -386.773113) (xy 187.997995 -386.755106)
			(xy 188.052838 -386.744976) (xy 188.108572 -386.742939) (xy 188.164009 -386.749039) (xy 188.217966 -386.763145)
			(xy 188.269295 -386.784957) (xy 188.316901 -386.814011) (xy 188.359769 -386.849686) (xy 188.396986 -386.891223)
			(xy 188.427759 -386.937736) (xy 188.451431 -386.988233) (xy 188.467499 -387.04164) (xy 188.475619 -387.096816)
			(xy 188.476128 -387.124702) (xy 188.475619 -387.152588) (xy 188.467499 -387.207764) (xy 188.451431 -387.261171)
			(xy 188.427759 -387.311668) (xy 188.396986 -387.358181) (xy 188.359769 -387.399718) (xy 188.316901 -387.435393)
			(xy 188.269295 -387.464447) (xy 188.217966 -387.486259) (xy 188.164009 -387.500365) (xy 188.108572 -387.506465)
			(xy 188.052838 -387.504428) (xy 187.997995 -387.494298) (xy 187.945211 -387.476291) (xy 187.895611 -387.45079)
			(xy 187.850253 -387.418339) (xy 187.810104 -387.37963) (xy 187.776018 -387.335487) (xy 187.748722 -387.286852)
			(xy 187.728799 -387.234761) (xy 187.716673 -387.180324) (xy 187.712602 -387.124702) (xy 185.023252 -387.124702)
			(xy 185.023252 -401.65909) (xy 190.407542 -401.65909) (xy 190.411613 -401.603468) (xy 190.423739 -401.549031)
			(xy 190.443662 -401.49694) (xy 190.470958 -401.448305) (xy 190.505044 -401.404162) (xy 190.545193 -401.365453)
			(xy 190.590551 -401.333002) (xy 190.640151 -401.307501) (xy 190.692935 -401.289494) (xy 190.747778 -401.279364)
			(xy 190.803512 -401.277327) (xy 190.858949 -401.283427) (xy 190.912906 -401.297533) (xy 190.964235 -401.319345)
			(xy 191.011841 -401.348399) (xy 191.054709 -401.384074) (xy 191.091926 -401.425611) (xy 191.122699 -401.472124)
			(xy 191.146371 -401.522621) (xy 191.162439 -401.576028) (xy 191.170559 -401.631204) (xy 191.171068 -401.65909)
			(xy 191.170559 -401.686976) (xy 191.162439 -401.742152) (xy 191.146371 -401.795559) (xy 191.122699 -401.846056)
			(xy 191.091926 -401.892569) (xy 191.054709 -401.934106) (xy 191.011841 -401.969781) (xy 190.964235 -401.998835)
			(xy 190.912906 -402.020647) (xy 190.858949 -402.034753) (xy 190.803512 -402.040853) (xy 190.747778 -402.038816)
			(xy 190.692935 -402.028686) (xy 190.640151 -402.010679) (xy 190.590551 -401.985178) (xy 190.545193 -401.952727)
			(xy 190.505044 -401.914018) (xy 190.470958 -401.869875) (xy 190.443662 -401.82124) (xy 190.423739 -401.769149)
			(xy 190.411613 -401.714712) (xy 190.407542 -401.65909) (xy 185.023252 -401.65909) (xy 185.023252 -402.263102)
			(xy 194.29171 -402.263102) (xy 194.295783 -402.207443) (xy 194.307918 -402.15297) (xy 194.327854 -402.100844)
			(xy 194.355168 -402.052176) (xy 194.389276 -402.008004) (xy 194.429453 -401.969269) (xy 194.474841 -401.936797)
			(xy 194.524473 -401.911279) (xy 194.577293 -401.89326) (xy 194.632172 -401.883123) (xy 194.687943 -401.881085)
			(xy 194.743417 -401.887188) (xy 194.79741 -401.901304) (xy 194.848773 -401.923131) (xy 194.896411 -401.952204)
			(xy 194.939307 -401.987903) (xy 194.976549 -402.029467) (xy 195.007343 -402.076011) (xy 195.031031 -402.126542)
			(xy 195.047109 -402.179984) (xy 195.053361 -402.222462) (xy 198.023478 -402.222462) (xy 198.027549 -402.16684)
			(xy 198.039675 -402.112403) (xy 198.059598 -402.060312) (xy 198.086894 -402.011677) (xy 198.12098 -401.967534)
			(xy 198.161129 -401.928825) (xy 198.206487 -401.896374) (xy 198.256087 -401.870873) (xy 198.308871 -401.852866)
			(xy 198.363714 -401.842736) (xy 198.419448 -401.840699) (xy 198.474885 -401.846799) (xy 198.528842 -401.860905)
			(xy 198.580171 -401.882717) (xy 198.627777 -401.911771) (xy 198.670645 -401.947446) (xy 198.707862 -401.988983)
			(xy 198.738635 -402.035496) (xy 198.762307 -402.085993) (xy 198.778375 -402.1394) (xy 198.786495 -402.194576)
			(xy 198.787004 -402.222462) (xy 198.786495 -402.250348) (xy 198.778375 -402.305524) (xy 198.762307 -402.358931)
			(xy 198.738635 -402.409428) (xy 198.707862 -402.455941) (xy 198.670645 -402.497478) (xy 198.627777 -402.533153)
			(xy 198.580171 -402.562207) (xy 198.528842 -402.584019) (xy 198.474885 -402.598125) (xy 198.419448 -402.604225)
			(xy 198.363714 -402.602188) (xy 198.308871 -402.592058) (xy 198.256087 -402.574051) (xy 198.206487 -402.54855)
			(xy 198.161129 -402.516099) (xy 198.12098 -402.47739) (xy 198.086894 -402.433247) (xy 198.059598 -402.384612)
			(xy 198.039675 -402.332521) (xy 198.027549 -402.278084) (xy 198.023478 -402.222462) (xy 195.053361 -402.222462)
			(xy 195.055235 -402.235198) (xy 195.055744 -402.263102) (xy 195.055235 -402.291006) (xy 195.047109 -402.34622)
			(xy 195.031031 -402.399662) (xy 195.007343 -402.450193) (xy 194.976549 -402.496737) (xy 194.939307 -402.538301)
			(xy 194.896411 -402.574) (xy 194.848773 -402.603073) (xy 194.79741 -402.6249) (xy 194.743417 -402.639016)
			(xy 194.687943 -402.645119) (xy 194.632172 -402.643081) (xy 194.577293 -402.632944) (xy 194.524473 -402.614925)
			(xy 194.474841 -402.589407) (xy 194.429453 -402.556935) (xy 194.389276 -402.5182) (xy 194.355168 -402.474028)
			(xy 194.327854 -402.42536) (xy 194.307918 -402.373234) (xy 194.295783 -402.318761) (xy 194.29171 -402.263102)
			(xy 185.023252 -402.263102) (xy 185.023252 -403.06879) (xy 187.740542 -403.06879) (xy 187.744613 -403.013168)
			(xy 187.756739 -402.958731) (xy 187.776662 -402.90664) (xy 187.803958 -402.858005) (xy 187.838044 -402.813862)
			(xy 187.878193 -402.775153) (xy 187.923551 -402.742702) (xy 187.973151 -402.717201) (xy 188.025935 -402.699194)
			(xy 188.080778 -402.689064) (xy 188.136512 -402.687027) (xy 188.191949 -402.693127) (xy 188.245906 -402.707233)
			(xy 188.297235 -402.729045) (xy 188.344841 -402.758099) (xy 188.387709 -402.793774) (xy 188.424926 -402.835311)
			(xy 188.455699 -402.881824) (xy 188.479371 -402.932321) (xy 188.495439 -402.985728) (xy 188.503559 -403.040904)
			(xy 188.504068 -403.06879) (xy 188.503559 -403.096676) (xy 188.495439 -403.151852) (xy 188.479371 -403.205259)
			(xy 188.455699 -403.255756) (xy 188.424926 -403.302269) (xy 188.387709 -403.343806) (xy 188.344841 -403.379481)
			(xy 188.297235 -403.408535) (xy 188.245906 -403.430347) (xy 188.191949 -403.444453) (xy 188.136512 -403.450553)
			(xy 188.080778 -403.448516) (xy 188.025935 -403.438386) (xy 187.973151 -403.420379) (xy 187.923551 -403.394878)
			(xy 187.878193 -403.362427) (xy 187.838044 -403.323718) (xy 187.803958 -403.279575) (xy 187.776662 -403.23094)
			(xy 187.756739 -403.178849) (xy 187.744613 -403.124412) (xy 187.740542 -403.06879) (xy 185.023252 -403.06879)
			(xy 185.023252 -403.991318) (xy 190.063626 -403.991318) (xy 190.067697 -403.935696) (xy 190.079823 -403.881259)
			(xy 190.099746 -403.829168) (xy 190.127042 -403.780533) (xy 190.161128 -403.73639) (xy 190.201277 -403.697681)
			(xy 190.246635 -403.66523) (xy 190.296235 -403.639729) (xy 190.349019 -403.621722) (xy 190.403862 -403.611592)
			(xy 190.459596 -403.609555) (xy 190.515033 -403.615655) (xy 190.56899 -403.629761) (xy 190.620319 -403.651573)
			(xy 190.667925 -403.680627) (xy 190.710793 -403.716302) (xy 190.74801 -403.757839) (xy 190.778783 -403.804352)
			(xy 190.802455 -403.854849) (xy 190.818523 -403.908256) (xy 190.826643 -403.963432) (xy 190.827152 -403.991318)
			(xy 190.826643 -404.019204) (xy 190.818523 -404.07438) (xy 190.816996 -404.079456) (xy 192.60769 -404.079456)
			(xy 192.611761 -404.023834) (xy 192.623887 -403.969397) (xy 192.64381 -403.917306) (xy 192.671106 -403.868671)
			(xy 192.705192 -403.824528) (xy 192.745341 -403.785819) (xy 192.790699 -403.753368) (xy 192.840299 -403.727867)
			(xy 192.893083 -403.70986) (xy 192.947926 -403.69973) (xy 193.00366 -403.697693) (xy 193.059097 -403.703793)
			(xy 193.113054 -403.717899) (xy 193.164383 -403.739711) (xy 193.211989 -403.768765) (xy 193.254857 -403.80444)
			(xy 193.292074 -403.845977) (xy 193.322847 -403.89249) (xy 193.329763 -403.907244) (xy 193.55765 -403.907244)
			(xy 193.561721 -403.851622) (xy 193.573847 -403.797185) (xy 193.59377 -403.745094) (xy 193.621066 -403.696459)
			(xy 193.655152 -403.652316) (xy 193.695301 -403.613607) (xy 193.740659 -403.581156) (xy 193.790259 -403.555655)
			(xy 193.843043 -403.537648) (xy 193.897886 -403.527518) (xy 193.95362 -403.525481) (xy 194.009057 -403.531581)
			(xy 194.063014 -403.545687) (xy 194.114343 -403.567499) (xy 194.161949 -403.596553) (xy 194.204817 -403.632228)
			(xy 194.242034 -403.673765) (xy 194.272807 -403.720278) (xy 194.296479 -403.770775) (xy 194.312547 -403.824182)
			(xy 194.320667 -403.879358) (xy 194.321176 -403.907244) (xy 194.320667 -403.93513) (xy 194.312547 -403.990306)
			(xy 194.296479 -404.043713) (xy 194.272807 -404.09421) (xy 194.242034 -404.140723) (xy 194.204817 -404.18226)
			(xy 194.161949 -404.217935) (xy 194.114343 -404.246989) (xy 194.063014 -404.268801) (xy 194.009057 -404.282907)
			(xy 193.95362 -404.289007) (xy 193.897886 -404.28697) (xy 193.843043 -404.27684) (xy 193.790259 -404.258833)
			(xy 193.740659 -404.233332) (xy 193.695301 -404.200881) (xy 193.655152 -404.162172) (xy 193.621066 -404.118029)
			(xy 193.59377 -404.069394) (xy 193.573847 -404.017303) (xy 193.561721 -403.962866) (xy 193.55765 -403.907244)
			(xy 193.329763 -403.907244) (xy 193.346519 -403.942987) (xy 193.362587 -403.996394) (xy 193.370707 -404.05157)
			(xy 193.371216 -404.079456) (xy 193.370707 -404.107342) (xy 193.362587 -404.162518) (xy 193.346519 -404.215925)
			(xy 193.322847 -404.266422) (xy 193.292074 -404.312935) (xy 193.254857 -404.354472) (xy 193.211989 -404.390147)
			(xy 193.164383 -404.419201) (xy 193.113054 -404.441013) (xy 193.059097 -404.455119) (xy 193.00366 -404.461219)
			(xy 192.947926 -404.459182) (xy 192.893083 -404.449052) (xy 192.840299 -404.431045) (xy 192.790699 -404.405544)
			(xy 192.745341 -404.373093) (xy 192.705192 -404.334384) (xy 192.671106 -404.290241) (xy 192.64381 -404.241606)
			(xy 192.623887 -404.189515) (xy 192.611761 -404.135078) (xy 192.60769 -404.079456) (xy 190.816996 -404.079456)
			(xy 190.802455 -404.127787) (xy 190.778783 -404.178284) (xy 190.74801 -404.224797) (xy 190.710793 -404.266334)
			(xy 190.667925 -404.302009) (xy 190.620319 -404.331063) (xy 190.56899 -404.352875) (xy 190.515033 -404.366981)
			(xy 190.459596 -404.373081) (xy 190.403862 -404.371044) (xy 190.349019 -404.360914) (xy 190.296235 -404.342907)
			(xy 190.246635 -404.317406) (xy 190.201277 -404.284955) (xy 190.161128 -404.246246) (xy 190.127042 -404.202103)
			(xy 190.099746 -404.153468) (xy 190.079823 -404.101377) (xy 190.067697 -404.04694) (xy 190.063626 -403.991318)
			(xy 185.023252 -403.991318) (xy 185.023252 -404.770844) (xy 199.62952 -404.770844) (xy 199.633591 -404.715222)
			(xy 199.645717 -404.660785) (xy 199.66564 -404.608694) (xy 199.692936 -404.560059) (xy 199.727022 -404.515916)
			(xy 199.767171 -404.477207) (xy 199.812529 -404.444756) (xy 199.862129 -404.419255) (xy 199.914913 -404.401248)
			(xy 199.969756 -404.391118) (xy 200.02549 -404.389081) (xy 200.080927 -404.395181) (xy 200.134884 -404.409287)
			(xy 200.186213 -404.431099) (xy 200.233819 -404.460153) (xy 200.276687 -404.495828) (xy 200.313904 -404.537365)
			(xy 200.344677 -404.583878) (xy 200.368349 -404.634375) (xy 200.384417 -404.687782) (xy 200.392537 -404.742958)
			(xy 200.393046 -404.770844) (xy 200.392537 -404.79873) (xy 200.39208 -404.801832) (xy 200.686922 -404.801832)
			(xy 200.690993 -404.74621) (xy 200.703119 -404.691773) (xy 200.723042 -404.639682) (xy 200.750338 -404.591047)
			(xy 200.784424 -404.546904) (xy 200.824573 -404.508195) (xy 200.869931 -404.475744) (xy 200.919531 -404.450243)
			(xy 200.972315 -404.432236) (xy 201.027158 -404.422106) (xy 201.082892 -404.420069) (xy 201.138329 -404.426169)
			(xy 201.192286 -404.440275) (xy 201.243615 -404.462087) (xy 201.291221 -404.491141) (xy 201.334089 -404.526816)
			(xy 201.371306 -404.568353) (xy 201.402079 -404.614866) (xy 201.425751 -404.665363) (xy 201.441819 -404.71877)
			(xy 201.449939 -404.773946) (xy 201.450448 -404.801832) (xy 201.449939 -404.829718) (xy 201.441819 -404.884894)
			(xy 201.425751 -404.938301) (xy 201.402079 -404.988798) (xy 201.371306 -405.035311) (xy 201.334089 -405.076848)
			(xy 201.291221 -405.112523) (xy 201.243615 -405.141577) (xy 201.192286 -405.163389) (xy 201.138329 -405.177495)
			(xy 201.082892 -405.183595) (xy 201.027158 -405.181558) (xy 200.972315 -405.171428) (xy 200.919531 -405.153421)
			(xy 200.869931 -405.12792) (xy 200.824573 -405.095469) (xy 200.784424 -405.05676) (xy 200.750338 -405.012617)
			(xy 200.723042 -404.963982) (xy 200.703119 -404.911891) (xy 200.690993 -404.857454) (xy 200.686922 -404.801832)
			(xy 200.39208 -404.801832) (xy 200.384417 -404.853906) (xy 200.368349 -404.907313) (xy 200.344677 -404.95781)
			(xy 200.313904 -405.004323) (xy 200.276687 -405.04586) (xy 200.233819 -405.081535) (xy 200.186213 -405.110589)
			(xy 200.134884 -405.132401) (xy 200.080927 -405.146507) (xy 200.02549 -405.152607) (xy 199.969756 -405.15057)
			(xy 199.914913 -405.14044) (xy 199.862129 -405.122433) (xy 199.812529 -405.096932) (xy 199.767171 -405.064481)
			(xy 199.727022 -405.025772) (xy 199.692936 -404.981629) (xy 199.66564 -404.932994) (xy 199.645717 -404.880903)
			(xy 199.633591 -404.826466) (xy 199.62952 -404.770844) (xy 185.023252 -404.770844) (xy 185.023252 -405.18461)
			(xy 196.984364 -405.18461) (xy 196.988435 -405.128988) (xy 197.000561 -405.074551) (xy 197.020484 -405.02246)
			(xy 197.04778 -404.973825) (xy 197.081866 -404.929682) (xy 197.122015 -404.890973) (xy 197.167373 -404.858522)
			(xy 197.216973 -404.833021) (xy 197.269757 -404.815014) (xy 197.3246 -404.804884) (xy 197.380334 -404.802847)
			(xy 197.435771 -404.808947) (xy 197.489728 -404.823053) (xy 197.541057 -404.844865) (xy 197.588663 -404.873919)
			(xy 197.631531 -404.909594) (xy 197.668748 -404.951131) (xy 197.699521 -404.997644) (xy 197.723193 -405.048141)
			(xy 197.739261 -405.101548) (xy 197.747381 -405.156724) (xy 197.74789 -405.18461) (xy 197.747709 -405.194516)
			(xy 198.019922 -405.194516) (xy 198.023993 -405.138894) (xy 198.036119 -405.084457) (xy 198.056042 -405.032366)
			(xy 198.083338 -404.983731) (xy 198.117424 -404.939588) (xy 198.157573 -404.900879) (xy 198.202931 -404.868428)
			(xy 198.252531 -404.842927) (xy 198.305315 -404.82492) (xy 198.360158 -404.81479) (xy 198.415892 -404.812753)
			(xy 198.471329 -404.818853) (xy 198.525286 -404.832959) (xy 198.576615 -404.854771) (xy 198.624221 -404.883825)
			(xy 198.667089 -404.9195) (xy 198.704306 -404.961037) (xy 198.735079 -405.00755) (xy 198.758751 -405.058047)
			(xy 198.774819 -405.111454) (xy 198.782939 -405.16663) (xy 198.783448 -405.194516) (xy 198.782939 -405.222402)
			(xy 198.774819 -405.277578) (xy 198.758751 -405.330985) (xy 198.735079 -405.381482) (xy 198.704306 -405.427995)
			(xy 198.667089 -405.469532) (xy 198.624221 -405.505207) (xy 198.576615 -405.534261) (xy 198.525286 -405.556073)
			(xy 198.471329 -405.570179) (xy 198.415892 -405.576279) (xy 198.360158 -405.574242) (xy 198.305315 -405.564112)
			(xy 198.252531 -405.546105) (xy 198.202931 -405.520604) (xy 198.157573 -405.488153) (xy 198.117424 -405.449444)
			(xy 198.083338 -405.405301) (xy 198.056042 -405.356666) (xy 198.036119 -405.304575) (xy 198.023993 -405.250138)
			(xy 198.019922 -405.194516) (xy 197.747709 -405.194516) (xy 197.747381 -405.212496) (xy 197.739261 -405.267672)
			(xy 197.723193 -405.321079) (xy 197.699521 -405.371576) (xy 197.668748 -405.418089) (xy 197.631531 -405.459626)
			(xy 197.588663 -405.495301) (xy 197.541057 -405.524355) (xy 197.489728 -405.546167) (xy 197.435771 -405.560273)
			(xy 197.380334 -405.566373) (xy 197.3246 -405.564336) (xy 197.269757 -405.554206) (xy 197.216973 -405.536199)
			(xy 197.167373 -405.510698) (xy 197.122015 -405.478247) (xy 197.081866 -405.439538) (xy 197.04778 -405.395395)
			(xy 197.020484 -405.34676) (xy 197.000561 -405.294669) (xy 196.988435 -405.240232) (xy 196.984364 -405.18461)
			(xy 185.023252 -405.18461) (xy 185.023252 -405.857964) (xy 187.266832 -405.857964) (xy 187.270903 -405.802342)
			(xy 187.283029 -405.747905) (xy 187.302952 -405.695814) (xy 187.330248 -405.647179) (xy 187.364334 -405.603036)
			(xy 187.404483 -405.564327) (xy 187.449841 -405.531876) (xy 187.499441 -405.506375) (xy 187.552225 -405.488368)
			(xy 187.607068 -405.478238) (xy 187.662802 -405.476201) (xy 187.718239 -405.482301) (xy 187.772196 -405.496407)
			(xy 187.823525 -405.518219) (xy 187.871131 -405.547273) (xy 187.913999 -405.582948) (xy 187.951216 -405.624485)
			(xy 187.981989 -405.670998) (xy 188.005661 -405.721495) (xy 188.021729 -405.774902) (xy 188.029849 -405.830078)
			(xy 188.030358 -405.857964) (xy 188.029849 -405.88585) (xy 188.021729 -405.941026) (xy 188.005661 -405.994433)
			(xy 187.981989 -406.04493) (xy 187.951216 -406.091443) (xy 187.913999 -406.13298) (xy 187.871131 -406.168655)
			(xy 187.839997 -406.187656) (xy 194.514722 -406.187656) (xy 194.518793 -406.132034) (xy 194.530919 -406.077597)
			(xy 194.550842 -406.025506) (xy 194.578138 -405.976871) (xy 194.612224 -405.932728) (xy 194.652373 -405.894019)
			(xy 194.697731 -405.861568) (xy 194.747331 -405.836067) (xy 194.800115 -405.81806) (xy 194.854958 -405.80793)
			(xy 194.910692 -405.805893) (xy 194.966129 -405.811993) (xy 195.020086 -405.826099) (xy 195.071415 -405.847911)
			(xy 195.119021 -405.876965) (xy 195.161889 -405.91264) (xy 195.199106 -405.954177) (xy 195.229879 -406.00069)
			(xy 195.253551 -406.051187) (xy 195.269619 -406.104594) (xy 195.277739 -406.15977) (xy 195.278248 -406.187656)
			(xy 195.277739 -406.215542) (xy 195.269619 -406.270718) (xy 195.253551 -406.324125) (xy 195.229879 -406.374622)
			(xy 195.199106 -406.421135) (xy 195.161889 -406.462672) (xy 195.119021 -406.498347) (xy 195.071415 -406.527401)
			(xy 195.020086 -406.549213) (xy 194.966129 -406.563319) (xy 194.910692 -406.569419) (xy 194.854958 -406.567382)
			(xy 194.800115 -406.557252) (xy 194.747331 -406.539245) (xy 194.697731 -406.513744) (xy 194.652373 -406.481293)
			(xy 194.612224 -406.442584) (xy 194.578138 -406.398441) (xy 194.550842 -406.349806) (xy 194.530919 -406.297715)
			(xy 194.518793 -406.243278) (xy 194.514722 -406.187656) (xy 187.839997 -406.187656) (xy 187.823525 -406.197709)
			(xy 187.772196 -406.219521) (xy 187.718239 -406.233627) (xy 187.662802 -406.239727) (xy 187.607068 -406.23769)
			(xy 187.552225 -406.22756) (xy 187.499441 -406.209553) (xy 187.449841 -406.184052) (xy 187.404483 -406.151601)
			(xy 187.364334 -406.112892) (xy 187.330248 -406.068749) (xy 187.302952 -406.020114) (xy 187.283029 -405.968023)
			(xy 187.270903 -405.913586) (xy 187.266832 -405.857964) (xy 185.023252 -405.857964) (xy 185.023252 -406.99436)
			(xy 187.04255 -406.99436) (xy 187.046621 -406.938738) (xy 187.058747 -406.884301) (xy 187.07867 -406.83221)
			(xy 187.105966 -406.783575) (xy 187.140052 -406.739432) (xy 187.180201 -406.700723) (xy 187.225559 -406.668272)
			(xy 187.275159 -406.642771) (xy 187.327943 -406.624764) (xy 187.382786 -406.614634) (xy 187.43852 -406.612597)
			(xy 187.493957 -406.618697) (xy 187.547914 -406.632803) (xy 187.599243 -406.654615) (xy 187.60323 -406.657048)
			(xy 196.381114 -406.657048) (xy 196.385185 -406.601426) (xy 196.397311 -406.546989) (xy 196.417234 -406.494898)
			(xy 196.44453 -406.446263) (xy 196.478616 -406.40212) (xy 196.518765 -406.363411) (xy 196.564123 -406.33096)
			(xy 196.613723 -406.305459) (xy 196.666507 -406.287452) (xy 196.72135 -406.277322) (xy 196.777084 -406.275285)
			(xy 196.832521 -406.281385) (xy 196.886478 -406.295491) (xy 196.937807 -406.317303) (xy 196.985413 -406.346357)
			(xy 197.028281 -406.382032) (xy 197.065498 -406.423569) (xy 197.096271 -406.470082) (xy 197.115571 -406.511252)
			(xy 198.765666 -406.511252) (xy 198.769737 -406.45563) (xy 198.781863 -406.401193) (xy 198.801786 -406.349102)
			(xy 198.829082 -406.300467) (xy 198.863168 -406.256324) (xy 198.903317 -406.217615) (xy 198.948675 -406.185164)
			(xy 198.998275 -406.159663) (xy 199.051059 -406.141656) (xy 199.105902 -406.131526) (xy 199.161636 -406.129489)
			(xy 199.217073 -406.135589) (xy 199.27103 -406.149695) (xy 199.322359 -406.171507) (xy 199.369965 -406.200561)
			(xy 199.412833 -406.236236) (xy 199.45005 -406.277773) (xy 199.480823 -406.324286) (xy 199.504495 -406.374783)
			(xy 199.520563 -406.42819) (xy 199.528683 -406.483366) (xy 199.529192 -406.511252) (xy 199.528683 -406.539138)
			(xy 199.520563 -406.594314) (xy 199.504495 -406.647721) (xy 199.480823 -406.698218) (xy 199.45005 -406.744731)
			(xy 199.412833 -406.786268) (xy 199.369965 -406.821943) (xy 199.322359 -406.850997) (xy 199.27103 -406.872809)
			(xy 199.217073 -406.886915) (xy 199.161636 -406.893015) (xy 199.105902 -406.890978) (xy 199.051059 -406.880848)
			(xy 198.998275 -406.862841) (xy 198.948675 -406.83734) (xy 198.903317 -406.804889) (xy 198.863168 -406.76618)
			(xy 198.829082 -406.722037) (xy 198.801786 -406.673402) (xy 198.781863 -406.621311) (xy 198.769737 -406.566874)
			(xy 198.765666 -406.511252) (xy 197.115571 -406.511252) (xy 197.119943 -406.520579) (xy 197.136011 -406.573986)
			(xy 197.144131 -406.629162) (xy 197.14464 -406.657048) (xy 197.144131 -406.684934) (xy 197.136011 -406.74011)
			(xy 197.119943 -406.793517) (xy 197.096271 -406.844014) (xy 197.065498 -406.890527) (xy 197.028281 -406.932064)
			(xy 196.985413 -406.967739) (xy 196.937807 -406.996793) (xy 196.886478 -407.018605) (xy 196.832521 -407.032711)
			(xy 196.777084 -407.038811) (xy 196.72135 -407.036774) (xy 196.666507 -407.026644) (xy 196.613723 -407.008637)
			(xy 196.564123 -406.983136) (xy 196.518765 -406.950685) (xy 196.478616 -406.911976) (xy 196.44453 -406.867833)
			(xy 196.417234 -406.819198) (xy 196.397311 -406.767107) (xy 196.385185 -406.71267) (xy 196.381114 -406.657048)
			(xy 187.60323 -406.657048) (xy 187.646849 -406.683669) (xy 187.689717 -406.719344) (xy 187.726934 -406.760881)
			(xy 187.757707 -406.807394) (xy 187.781379 -406.857891) (xy 187.797447 -406.911298) (xy 187.805567 -406.966474)
			(xy 187.806076 -406.99436) (xy 187.805567 -407.022246) (xy 187.797447 -407.077422) (xy 187.78461 -407.12009)
			(xy 198.130412 -407.12009) (xy 198.134483 -407.064468) (xy 198.146609 -407.010031) (xy 198.166532 -406.95794)
			(xy 198.193828 -406.909305) (xy 198.227914 -406.865162) (xy 198.268063 -406.826453) (xy 198.313421 -406.794002)
			(xy 198.363021 -406.768501) (xy 198.415805 -406.750494) (xy 198.470648 -406.740364) (xy 198.526382 -406.738327)
			(xy 198.581819 -406.744427) (xy 198.635776 -406.758533) (xy 198.687105 -406.780345) (xy 198.734711 -406.809399)
			(xy 198.777579 -406.845074) (xy 198.814796 -406.886611) (xy 198.845569 -406.933124) (xy 198.869241 -406.983621)
			(xy 198.885309 -407.037028) (xy 198.893429 -407.092204) (xy 198.893938 -407.12009) (xy 198.893429 -407.147976)
			(xy 198.885309 -407.203152) (xy 198.869241 -407.256559) (xy 198.845569 -407.307056) (xy 198.814796 -407.353569)
			(xy 198.777579 -407.395106) (xy 198.734711 -407.430781) (xy 198.687105 -407.459835) (xy 198.635776 -407.481647)
			(xy 198.581819 -407.495753) (xy 198.526382 -407.501853) (xy 198.470648 -407.499816) (xy 198.415805 -407.489686)
			(xy 198.363021 -407.471679) (xy 198.313421 -407.446178) (xy 198.268063 -407.413727) (xy 198.227914 -407.375018)
			(xy 198.193828 -407.330875) (xy 198.166532 -407.28224) (xy 198.146609 -407.230149) (xy 198.134483 -407.175712)
			(xy 198.130412 -407.12009) (xy 187.78461 -407.12009) (xy 187.781379 -407.130829) (xy 187.757707 -407.181326)
			(xy 187.726934 -407.227839) (xy 187.689717 -407.269376) (xy 187.646849 -407.305051) (xy 187.599243 -407.334105)
			(xy 187.547914 -407.355917) (xy 187.493957 -407.370023) (xy 187.43852 -407.376123) (xy 187.382786 -407.374086)
			(xy 187.327943 -407.363956) (xy 187.275159 -407.345949) (xy 187.225559 -407.320448) (xy 187.180201 -407.287997)
			(xy 187.140052 -407.249288) (xy 187.105966 -407.205145) (xy 187.07867 -407.15651) (xy 187.058747 -407.104419)
			(xy 187.046621 -407.049982) (xy 187.04255 -406.99436) (xy 185.023252 -406.99436) (xy 185.023252 -407.4414)
			(xy 185.755532 -407.4414) (xy 185.759603 -407.385778) (xy 185.771729 -407.331341) (xy 185.791652 -407.27925)
			(xy 185.818948 -407.230615) (xy 185.853034 -407.186472) (xy 185.893183 -407.147763) (xy 185.938541 -407.115312)
			(xy 185.988141 -407.089811) (xy 186.040925 -407.071804) (xy 186.095768 -407.061674) (xy 186.151502 -407.059637)
			(xy 186.206939 -407.065737) (xy 186.260896 -407.079843) (xy 186.312225 -407.101655) (xy 186.359831 -407.130709)
			(xy 186.402699 -407.166384) (xy 186.439916 -407.207921) (xy 186.470689 -407.254434) (xy 186.494361 -407.304931)
			(xy 186.510429 -407.358338) (xy 186.518549 -407.413514) (xy 186.519058 -407.4414) (xy 186.518549 -407.469286)
			(xy 186.510429 -407.524462) (xy 186.494361 -407.577869) (xy 186.470689 -407.628366) (xy 186.439916 -407.674879)
			(xy 186.402699 -407.716416) (xy 186.359831 -407.752091) (xy 186.312225 -407.781145) (xy 186.260896 -407.802957)
			(xy 186.206939 -407.817063) (xy 186.151502 -407.823163) (xy 186.095768 -407.821126) (xy 186.040925 -407.810996)
			(xy 185.988141 -407.792989) (xy 185.938541 -407.767488) (xy 185.893183 -407.735037) (xy 185.853034 -407.696328)
			(xy 185.818948 -407.652185) (xy 185.791652 -407.60355) (xy 185.771729 -407.551459) (xy 185.759603 -407.497022)
			(xy 185.755532 -407.4414) (xy 185.023252 -407.4414) (xy 185.023252 -408.592274) (xy 190.042798 -408.592274)
			(xy 190.046869 -408.536652) (xy 190.058995 -408.482215) (xy 190.078918 -408.430124) (xy 190.106214 -408.381489)
			(xy 190.1403 -408.337346) (xy 190.180449 -408.298637) (xy 190.225807 -408.266186) (xy 190.275407 -408.240685)
			(xy 190.328191 -408.222678) (xy 190.383034 -408.212548) (xy 190.438768 -408.210511) (xy 190.494205 -408.216611)
			(xy 190.548162 -408.230717) (xy 190.599491 -408.252529) (xy 190.647097 -408.281583) (xy 190.689965 -408.317258)
			(xy 190.727182 -408.358795) (xy 190.757955 -408.405308) (xy 190.781627 -408.455805) (xy 190.797695 -408.509212)
			(xy 190.805815 -408.564388) (xy 190.806324 -408.592274) (xy 190.805815 -408.62016) (xy 190.797695 -408.675336)
			(xy 190.781627 -408.728743) (xy 190.757955 -408.77924) (xy 190.727182 -408.825753) (xy 190.689965 -408.86729)
			(xy 190.647097 -408.902965) (xy 190.599491 -408.932019) (xy 190.548162 -408.953831) (xy 190.520426 -408.961082)
			(xy 194.781676 -408.961082) (xy 194.785747 -408.90546) (xy 194.797873 -408.851023) (xy 194.817796 -408.798932)
			(xy 194.845092 -408.750297) (xy 194.879178 -408.706154) (xy 194.919327 -408.667445) (xy 194.964685 -408.634994)
			(xy 195.014285 -408.609493) (xy 195.067069 -408.591486) (xy 195.121912 -408.581356) (xy 195.177646 -408.579319)
			(xy 195.233083 -408.585419) (xy 195.28704 -408.599525) (xy 195.338369 -408.621337) (xy 195.385975 -408.650391)
			(xy 195.42327 -408.681428) (xy 196.990968 -408.681428) (xy 196.995039 -408.625806) (xy 197.007165 -408.571369)
			(xy 197.027088 -408.519278) (xy 197.054384 -408.470643) (xy 197.08847 -408.4265) (xy 197.128619 -408.387791)
			(xy 197.173977 -408.35534) (xy 197.223577 -408.329839) (xy 197.276361 -408.311832) (xy 197.331204 -408.301702)
			(xy 197.386938 -408.299665) (xy 197.442375 -408.305765) (xy 197.496332 -408.319871) (xy 197.547661 -408.341683)
			(xy 197.595267 -408.370737) (xy 197.638135 -408.406412) (xy 197.675352 -408.447949) (xy 197.706125 -408.494462)
			(xy 197.729797 -408.544959) (xy 197.745865 -408.598366) (xy 197.753985 -408.653542) (xy 197.754494 -408.681428)
			(xy 197.753985 -408.709314) (xy 197.745865 -408.76449) (xy 197.729797 -408.817897) (xy 197.706125 -408.868394)
			(xy 197.675352 -408.914907) (xy 197.638135 -408.956444) (xy 197.595267 -408.992119) (xy 197.547661 -409.021173)
			(xy 197.496332 -409.042985) (xy 197.442375 -409.057091) (xy 197.386938 -409.063191) (xy 197.331204 -409.061154)
			(xy 197.276361 -409.051024) (xy 197.223577 -409.033017) (xy 197.173977 -409.007516) (xy 197.128619 -408.975065)
			(xy 197.08847 -408.936356) (xy 197.054384 -408.892213) (xy 197.027088 -408.843578) (xy 197.007165 -408.791487)
			(xy 196.995039 -408.73705) (xy 196.990968 -408.681428) (xy 195.42327 -408.681428) (xy 195.428843 -408.686066)
			(xy 195.46606 -408.727603) (xy 195.496833 -408.774116) (xy 195.520505 -408.824613) (xy 195.536573 -408.87802)
			(xy 195.544693 -408.933196) (xy 195.545202 -408.961082) (xy 195.544693 -408.988968) (xy 195.536573 -409.044144)
			(xy 195.520505 -409.097551) (xy 195.496833 -409.148048) (xy 195.46606 -409.194561) (xy 195.428843 -409.236098)
			(xy 195.385975 -409.271773) (xy 195.338369 -409.300827) (xy 195.28704 -409.322639) (xy 195.233083 -409.336745)
			(xy 195.177646 -409.342845) (xy 195.121912 -409.340808) (xy 195.067069 -409.330678) (xy 195.014285 -409.312671)
			(xy 194.964685 -409.28717) (xy 194.919327 -409.254719) (xy 194.879178 -409.21601) (xy 194.845092 -409.171867)
			(xy 194.817796 -409.123232) (xy 194.797873 -409.071141) (xy 194.785747 -409.016704) (xy 194.781676 -408.961082)
			(xy 190.520426 -408.961082) (xy 190.494205 -408.967937) (xy 190.438768 -408.974037) (xy 190.383034 -408.972)
			(xy 190.328191 -408.96187) (xy 190.275407 -408.943863) (xy 190.225807 -408.918362) (xy 190.180449 -408.885911)
			(xy 190.1403 -408.847202) (xy 190.106214 -408.803059) (xy 190.078918 -408.754424) (xy 190.058995 -408.702333)
			(xy 190.046869 -408.647896) (xy 190.042798 -408.592274) (xy 185.023252 -408.592274) (xy 185.023252 -409.420568)
			(xy 186.579 -409.420568) (xy 186.583071 -409.364946) (xy 186.595197 -409.310509) (xy 186.61512 -409.258418)
			(xy 186.642416 -409.209783) (xy 186.676502 -409.16564) (xy 186.716651 -409.126931) (xy 186.762009 -409.09448)
			(xy 186.811609 -409.068979) (xy 186.864393 -409.050972) (xy 186.919236 -409.040842) (xy 186.97497 -409.038805)
			(xy 187.030407 -409.044905) (xy 187.084364 -409.059011) (xy 187.135693 -409.080823) (xy 187.183299 -409.109877)
			(xy 187.226167 -409.145552) (xy 187.263384 -409.187089) (xy 187.294157 -409.233602) (xy 187.317829 -409.284099)
			(xy 187.333897 -409.337506) (xy 187.342017 -409.392682) (xy 187.342526 -409.420568) (xy 187.342017 -409.448454)
			(xy 187.333897 -409.50363) (xy 187.317829 -409.557037) (xy 187.294157 -409.607534) (xy 187.263384 -409.654047)
			(xy 187.226167 -409.695584) (xy 187.183299 -409.731259) (xy 187.135693 -409.760313) (xy 187.084364 -409.782125)
			(xy 187.030407 -409.796231) (xy 186.97497 -409.802331) (xy 186.919236 -409.800294) (xy 186.864393 -409.790164)
			(xy 186.811609 -409.772157) (xy 186.762009 -409.746656) (xy 186.716651 -409.714205) (xy 186.676502 -409.675496)
			(xy 186.642416 -409.631353) (xy 186.61512 -409.582718) (xy 186.595197 -409.530627) (xy 186.583071 -409.47619)
			(xy 186.579 -409.420568) (xy 185.023252 -409.420568) (xy 185.023252 -411.03804) (xy 185.614054 -411.03804)
			(xy 185.618125 -410.982418) (xy 185.630251 -410.927981) (xy 185.650174 -410.87589) (xy 185.67747 -410.827255)
			(xy 185.711556 -410.783112) (xy 185.751705 -410.744403) (xy 185.797063 -410.711952) (xy 185.846663 -410.686451)
			(xy 185.899447 -410.668444) (xy 185.95429 -410.658314) (xy 186.010024 -410.656277) (xy 186.065461 -410.662377)
			(xy 186.119418 -410.676483) (xy 186.170747 -410.698295) (xy 186.207196 -410.72054) (xy 186.530994 -410.72054)
			(xy 186.535065 -410.664918) (xy 186.547191 -410.610481) (xy 186.567114 -410.55839) (xy 186.59441 -410.509755)
			(xy 186.628496 -410.465612) (xy 186.668645 -410.426903) (xy 186.714003 -410.394452) (xy 186.763603 -410.368951)
			(xy 186.816387 -410.350944) (xy 186.87123 -410.340814) (xy 186.926964 -410.338777) (xy 186.982401 -410.344877)
			(xy 187.036358 -410.358983) (xy 187.087687 -410.380795) (xy 187.135293 -410.409849) (xy 187.178161 -410.445524)
			(xy 187.215378 -410.487061) (xy 187.246151 -410.533574) (xy 187.269823 -410.584071) (xy 187.285891 -410.637478)
			(xy 187.294011 -410.692654) (xy 187.29452 -410.72054) (xy 187.294011 -410.748426) (xy 187.285891 -410.803602)
			(xy 187.269823 -410.857009) (xy 187.250567 -410.898086) (xy 189.844424 -410.898086) (xy 189.848497 -410.842427)
			(xy 189.860632 -410.787954) (xy 189.880568 -410.735828) (xy 189.907882 -410.68716) (xy 189.94199 -410.642988)
			(xy 189.982167 -410.604253) (xy 190.027555 -410.571781) (xy 190.077187 -410.546263) (xy 190.130007 -410.528244)
			(xy 190.184886 -410.518107) (xy 190.240657 -410.516069) (xy 190.296131 -410.522172) (xy 190.350124 -410.536288)
			(xy 190.401487 -410.558115) (xy 190.449125 -410.587188) (xy 190.492021 -410.622887) (xy 190.529263 -410.664451)
			(xy 190.550744 -410.696918) (xy 191.733424 -410.696918) (xy 191.733876 -410.670314) (xy 191.741256 -410.617621)
			(xy 191.755889 -410.566465) (xy 191.777491 -410.517839) (xy 191.805642 -410.472689) (xy 191.839796 -410.43189)
			(xy 191.87929 -410.396235) (xy 191.901064 -410.380942) (xy 191.912579 -410.372649) (xy 191.93079 -410.350899)
			(xy 191.942309 -410.324975) (xy 191.946247 -410.296882) (xy 191.942299 -410.26879) (xy 191.93077 -410.242871)
			(xy 191.912552 -410.221127) (xy 191.901064 -410.212794) (xy 191.879287 -410.197507) (xy 191.839807 -410.161841)
			(xy 191.805664 -410.121036) (xy 191.777519 -410.075885) (xy 191.755917 -410.027262) (xy 191.741279 -409.97611)
			(xy 191.733886 -409.923421) (xy 191.733424 -409.896818) (xy 191.73391 -409.869567) (xy 191.741666 -409.815619)
			(xy 191.757021 -409.763324) (xy 191.779663 -409.713747) (xy 191.809129 -409.667897) (xy 191.84482 -409.626706)
			(xy 191.886011 -409.591015) (xy 191.931861 -409.561549) (xy 191.981438 -409.538907) (xy 192.033733 -409.523552)
			(xy 192.087681 -409.515796) (xy 192.142183 -409.515796) (xy 192.196131 -409.523552) (xy 192.248426 -409.538907)
			(xy 192.298003 -409.561549) (xy 192.343853 -409.591015) (xy 192.385044 -409.626706) (xy 192.420735 -409.667897)
			(xy 192.450201 -409.713747) (xy 192.472843 -409.763324) (xy 192.488198 -409.815619) (xy 192.495954 -409.869567)
			(xy 192.49644 -409.896818) (xy 192.496031 -409.923424) (xy 192.488646 -409.97612) (xy 192.474006 -410.027277)
			(xy 192.452398 -410.075903) (xy 192.42424 -410.121053) (xy 192.390078 -410.161851) (xy 192.350578 -410.197503)
			(xy 192.3288 -410.212794) (xy 192.317351 -410.221168) (xy 192.299148 -410.242903) (xy 192.28763 -410.268808)
			(xy 192.283686 -410.296882) (xy 192.28762 -410.324958) (xy 192.299129 -410.350867) (xy 192.317324 -410.372608)
			(xy 192.3288 -410.380942) (xy 192.350561 -410.396249) (xy 192.390039 -410.431915) (xy 192.424181 -410.472717)
			(xy 192.452327 -410.517865) (xy 192.473931 -410.566483) (xy 192.488574 -410.617631) (xy 192.495973 -410.670317)
			(xy 192.49644 -410.696918) (xy 195.549264 -410.696918) (xy 195.553335 -410.641296) (xy 195.565461 -410.586859)
			(xy 195.585384 -410.534768) (xy 195.61268 -410.486133) (xy 195.646766 -410.44199) (xy 195.686915 -410.403281)
			(xy 195.732273 -410.37083) (xy 195.781873 -410.345329) (xy 195.834657 -410.327322) (xy 195.8895 -410.317192)
			(xy 195.945234 -410.315155) (xy 196.000671 -410.321255) (xy 196.054628 -410.335361) (xy 196.105957 -410.357173)
			(xy 196.153563 -410.386227) (xy 196.196431 -410.421902) (xy 196.233648 -410.463439) (xy 196.264421 -410.509952)
			(xy 196.288093 -410.560449) (xy 196.304161 -410.613856) (xy 196.312281 -410.669032) (xy 196.31279 -410.696918)
			(xy 196.312281 -410.724804) (xy 196.304161 -410.77998) (xy 196.288093 -410.833387) (xy 196.264421 -410.883884)
			(xy 196.233648 -410.930397) (xy 196.196431 -410.971934) (xy 196.153563 -411.007609) (xy 196.105957 -411.036663)
			(xy 196.054628 -411.058475) (xy 196.000671 -411.072581) (xy 195.945234 -411.078681) (xy 195.8895 -411.076644)
			(xy 195.834657 -411.066514) (xy 195.781873 -411.048507) (xy 195.732273 -411.023006) (xy 195.686915 -410.990555)
			(xy 195.646766 -410.951846) (xy 195.61268 -410.907703) (xy 195.585384 -410.859068) (xy 195.565461 -410.806977)
			(xy 195.553335 -410.75254) (xy 195.549264 -410.696918) (xy 192.49644 -410.696918) (xy 192.495954 -410.724169)
			(xy 192.488198 -410.778117) (xy 192.472843 -410.830412) (xy 192.450201 -410.879989) (xy 192.420735 -410.925839)
			(xy 192.385044 -410.96703) (xy 192.343853 -411.002721) (xy 192.298003 -411.032187) (xy 192.248426 -411.054829)
			(xy 192.196131 -411.070184) (xy 192.142183 -411.07794) (xy 192.087681 -411.07794) (xy 192.033733 -411.070184)
			(xy 191.981438 -411.054829) (xy 191.931861 -411.032187) (xy 191.886011 -411.002721) (xy 191.84482 -410.96703)
			(xy 191.809129 -410.925839) (xy 191.779663 -410.879989) (xy 191.757021 -410.830412) (xy 191.741666 -410.778117)
			(xy 191.73391 -410.724169) (xy 191.733424 -410.696918) (xy 190.550744 -410.696918) (xy 190.560057 -410.710995)
			(xy 190.583745 -410.761526) (xy 190.599823 -410.814968) (xy 190.607949 -410.870182) (xy 190.608458 -410.898086)
			(xy 190.607949 -410.92599) (xy 190.599823 -410.981204) (xy 190.583745 -411.034646) (xy 190.560057 -411.085177)
			(xy 190.529263 -411.131721) (xy 190.492021 -411.173285) (xy 190.449125 -411.208984) (xy 190.401487 -411.238057)
			(xy 190.350124 -411.259884) (xy 190.296131 -411.274) (xy 190.240657 -411.280103) (xy 190.184886 -411.278065)
			(xy 190.130007 -411.267928) (xy 190.077187 -411.249909) (xy 190.027555 -411.224391) (xy 189.982167 -411.191919)
			(xy 189.94199 -411.153184) (xy 189.907882 -411.109012) (xy 189.880568 -411.060344) (xy 189.860632 -411.008218)
			(xy 189.848497 -410.953745) (xy 189.844424 -410.898086) (xy 187.250567 -410.898086) (xy 187.246151 -410.907506)
			(xy 187.215378 -410.954019) (xy 187.178161 -410.995556) (xy 187.135293 -411.031231) (xy 187.087687 -411.060285)
			(xy 187.036358 -411.082097) (xy 186.982401 -411.096203) (xy 186.926964 -411.102303) (xy 186.87123 -411.100266)
			(xy 186.816387 -411.090136) (xy 186.763603 -411.072129) (xy 186.714003 -411.046628) (xy 186.668645 -411.014177)
			(xy 186.628496 -410.975468) (xy 186.59441 -410.931325) (xy 186.567114 -410.88269) (xy 186.547191 -410.830599)
			(xy 186.535065 -410.776162) (xy 186.530994 -410.72054) (xy 186.207196 -410.72054) (xy 186.218353 -410.727349)
			(xy 186.261221 -410.763024) (xy 186.298438 -410.804561) (xy 186.329211 -410.851074) (xy 186.352883 -410.901571)
			(xy 186.368951 -410.954978) (xy 186.377071 -411.010154) (xy 186.37758 -411.03804) (xy 186.377071 -411.065926)
			(xy 186.368951 -411.121102) (xy 186.352883 -411.174509) (xy 186.329211 -411.225006) (xy 186.298438 -411.271519)
			(xy 186.261221 -411.313056) (xy 186.253817 -411.319218) (xy 193.336162 -411.319218) (xy 193.340235 -411.263559)
			(xy 193.35237 -411.209086) (xy 193.372306 -411.15696) (xy 193.39962 -411.108292) (xy 193.433728 -411.06412)
			(xy 193.473905 -411.025385) (xy 193.519293 -410.992913) (xy 193.568925 -410.967395) (xy 193.621745 -410.949376)
			(xy 193.676624 -410.939239) (xy 193.732395 -410.937201) (xy 193.787869 -410.943304) (xy 193.841862 -410.95742)
			(xy 193.893225 -410.979247) (xy 193.940863 -411.00832) (xy 193.983759 -411.044019) (xy 194.021001 -411.085583)
			(xy 194.051795 -411.132127) (xy 194.075483 -411.182658) (xy 194.091561 -411.2361) (xy 194.099687 -411.291314)
			(xy 194.100196 -411.319218) (xy 194.099687 -411.347122) (xy 194.091561 -411.402336) (xy 194.075483 -411.455778)
			(xy 194.051795 -411.506309) (xy 194.050884 -411.507686) (xy 198.319134 -411.507686) (xy 198.323207 -411.452027)
			(xy 198.335342 -411.397554) (xy 198.355278 -411.345428) (xy 198.382592 -411.29676) (xy 198.4167 -411.252588)
			(xy 198.456877 -411.213853) (xy 198.502265 -411.181381) (xy 198.551897 -411.155863) (xy 198.604717 -411.137844)
			(xy 198.659596 -411.127707) (xy 198.715367 -411.125669) (xy 198.770841 -411.131772) (xy 198.824834 -411.145888)
			(xy 198.876197 -411.167715) (xy 198.923835 -411.196788) (xy 198.966731 -411.232487) (xy 199.003973 -411.274051)
			(xy 199.034767 -411.320595) (xy 199.058455 -411.371126) (xy 199.074533 -411.424568) (xy 199.082659 -411.479782)
			(xy 199.083168 -411.507686) (xy 199.082659 -411.53559) (xy 199.074533 -411.590804) (xy 199.058455 -411.644246)
			(xy 199.034767 -411.694777) (xy 199.003973 -411.741321) (xy 198.966731 -411.782885) (xy 198.923835 -411.818584)
			(xy 198.876197 -411.847657) (xy 198.824834 -411.869484) (xy 198.770841 -411.8836) (xy 198.715367 -411.889703)
			(xy 198.659596 -411.887665) (xy 198.604717 -411.877528) (xy 198.551897 -411.859509) (xy 198.502265 -411.833991)
			(xy 198.456877 -411.801519) (xy 198.4167 -411.762784) (xy 198.382592 -411.718612) (xy 198.355278 -411.669944)
			(xy 198.335342 -411.617818) (xy 198.323207 -411.563345) (xy 198.319134 -411.507686) (xy 194.050884 -411.507686)
			(xy 194.021001 -411.552853) (xy 193.983759 -411.594417) (xy 193.940863 -411.630116) (xy 193.893225 -411.659189)
			(xy 193.841862 -411.681016) (xy 193.787869 -411.695132) (xy 193.732395 -411.701235) (xy 193.676624 -411.699197)
			(xy 193.621745 -411.68906) (xy 193.568925 -411.671041) (xy 193.519293 -411.645523) (xy 193.473905 -411.613051)
			(xy 193.433728 -411.574316) (xy 193.39962 -411.530144) (xy 193.372306 -411.481476) (xy 193.35237 -411.42935)
			(xy 193.340235 -411.374877) (xy 193.336162 -411.319218) (xy 186.253817 -411.319218) (xy 186.218353 -411.348731)
			(xy 186.170747 -411.377785) (xy 186.119418 -411.399597) (xy 186.065461 -411.413703) (xy 186.010024 -411.419803)
			(xy 185.95429 -411.417766) (xy 185.899447 -411.407636) (xy 185.846663 -411.389629) (xy 185.797063 -411.364128)
			(xy 185.751705 -411.331677) (xy 185.711556 -411.292968) (xy 185.67747 -411.248825) (xy 185.650174 -411.20019)
			(xy 185.630251 -411.148099) (xy 185.618125 -411.093662) (xy 185.614054 -411.03804) (xy 185.023252 -411.03804)
			(xy 185.023252 -411.99181) (xy 188.011052 -411.99181) (xy 188.015123 -411.936188) (xy 188.027249 -411.881751)
			(xy 188.047172 -411.82966) (xy 188.074468 -411.781025) (xy 188.108554 -411.736882) (xy 188.148703 -411.698173)
			(xy 188.194061 -411.665722) (xy 188.243661 -411.640221) (xy 188.296445 -411.622214) (xy 188.351288 -411.612084)
			(xy 188.407022 -411.610047) (xy 188.462459 -411.616147) (xy 188.516416 -411.630253) (xy 188.567745 -411.652065)
			(xy 188.615351 -411.681119) (xy 188.658219 -411.716794) (xy 188.695436 -411.758331) (xy 188.726209 -411.804844)
			(xy 188.749881 -411.855341) (xy 188.765949 -411.908748) (xy 188.774069 -411.963924) (xy 188.774578 -411.99181)
			(xy 188.774069 -412.019696) (xy 188.765949 -412.074872) (xy 188.750437 -412.12643) (xy 197.241158 -412.12643)
			(xy 197.245231 -412.070771) (xy 197.257366 -412.016298) (xy 197.277302 -411.964172) (xy 197.304616 -411.915504)
			(xy 197.338724 -411.871332) (xy 197.378901 -411.832597) (xy 197.424289 -411.800125) (xy 197.473921 -411.774607)
			(xy 197.526741 -411.756588) (xy 197.58162 -411.746451) (xy 197.637391 -411.744413) (xy 197.692865 -411.750516)
			(xy 197.746858 -411.764632) (xy 197.798221 -411.786459) (xy 197.845859 -411.815532) (xy 197.888755 -411.851231)
			(xy 197.925997 -411.892795) (xy 197.956791 -411.939339) (xy 197.980479 -411.98987) (xy 197.996557 -412.043312)
			(xy 198.004683 -412.098526) (xy 198.005192 -412.12643) (xy 198.004683 -412.154334) (xy 197.996557 -412.209548)
			(xy 197.980479 -412.26299) (xy 197.956791 -412.313521) (xy 197.925997 -412.360065) (xy 197.888755 -412.401629)
			(xy 197.845859 -412.437328) (xy 197.798221 -412.466401) (xy 197.746858 -412.488228) (xy 197.692865 -412.502344)
			(xy 197.637391 -412.508447) (xy 197.58162 -412.506409) (xy 197.526741 -412.496272) (xy 197.473921 -412.478253)
			(xy 197.424289 -412.452735) (xy 197.378901 -412.420263) (xy 197.338724 -412.381528) (xy 197.304616 -412.337356)
			(xy 197.277302 -412.288688) (xy 197.257366 -412.236562) (xy 197.245231 -412.182089) (xy 197.241158 -412.12643)
			(xy 188.750437 -412.12643) (xy 188.749881 -412.128279) (xy 188.726209 -412.178776) (xy 188.695436 -412.225289)
			(xy 188.658219 -412.266826) (xy 188.615351 -412.302501) (xy 188.567745 -412.331555) (xy 188.516416 -412.353367)
			(xy 188.462459 -412.367473) (xy 188.407022 -412.373573) (xy 188.351288 -412.371536) (xy 188.296445 -412.361406)
			(xy 188.243661 -412.343399) (xy 188.194061 -412.317898) (xy 188.148703 -412.285447) (xy 188.108554 -412.246738)
			(xy 188.074468 -412.202595) (xy 188.047172 -412.15396) (xy 188.027249 -412.101869) (xy 188.015123 -412.047432)
			(xy 188.011052 -411.99181) (xy 185.023252 -411.99181) (xy 185.023252 -412.349442) (xy 185.024005 -412.362106)
			(xy 185.036139 -412.38435) (xy 185.046366 -412.39186) (xy 185.117232 -412.438342) (xy 185.125951 -412.443501)
			(xy 185.145857 -412.447174) (xy 185.15584 -412.445454) (xy 185.161174 -412.444438) (xy 185.165746 -412.442406)
			(xy 185.189913 -412.432301) (xy 185.240324 -412.418065) (xy 185.292209 -412.410865) (xy 185.3184 -412.410402)
			(xy 185.34565 -412.410888) (xy 185.399597 -412.418645) (xy 185.45189 -412.433999) (xy 185.501466 -412.45664)
			(xy 185.547315 -412.486105) (xy 185.588504 -412.521796) (xy 185.624195 -412.562985) (xy 185.65366 -412.608834)
			(xy 185.676301 -412.65841) (xy 185.691655 -412.710703) (xy 185.699412 -412.76465) (xy 185.699412 -412.81915)
			(xy 185.691655 -412.873097) (xy 185.676301 -412.92539) (xy 185.65366 -412.974966) (xy 185.624195 -413.020815)
			(xy 185.588504 -413.062004) (xy 185.547315 -413.097695) (xy 185.501466 -413.12716) (xy 185.45189 -413.149801)
			(xy 185.399597 -413.165155) (xy 185.34565 -413.172912) (xy 185.3184 -413.173418) (xy 185.292166 -413.172981)
			(xy 185.240194 -413.165788) (xy 185.189698 -413.151536) (xy 185.165492 -413.141414) (xy 185.153554 -413.13608)
			(xy 185.128154 -413.138112) (xy 185.046366 -413.19196) (xy 185.035444 -413.199072) (xy 185.023252 -413.221424)
			(xy 185.023252 -413.249872) (xy 185.02369 -413.259935) (xy 185.031428 -413.278516) (xy 185.038238 -413.28594)
			(xy 185.231532 -413.479234) (xy 189.505588 -413.479234) (xy 189.509661 -413.423575) (xy 189.521796 -413.369102)
			(xy 189.541732 -413.316976) (xy 189.569046 -413.268308) (xy 189.603154 -413.224136) (xy 189.643331 -413.185401)
			(xy 189.688719 -413.152929) (xy 189.738351 -413.127411) (xy 189.791171 -413.109392) (xy 189.84605 -413.099255)
			(xy 189.901821 -413.097217) (xy 189.957295 -413.10332) (xy 190.011288 -413.117436) (xy 190.062651 -413.139263)
			(xy 190.110289 -413.168336) (xy 190.153185 -413.204035) (xy 190.190427 -413.245599) (xy 190.221221 -413.292143)
			(xy 190.244909 -413.342674) (xy 190.260987 -413.396116) (xy 190.269113 -413.45133) (xy 190.269622 -413.479234)
			(xy 190.663828 -413.479234) (xy 190.667901 -413.423575) (xy 190.680036 -413.369102) (xy 190.699972 -413.316976)
			(xy 190.727286 -413.268308) (xy 190.761394 -413.224136) (xy 190.801571 -413.185401) (xy 190.846959 -413.152929)
			(xy 190.896591 -413.127411) (xy 190.949411 -413.109392) (xy 191.00429 -413.099255) (xy 191.060061 -413.097217)
			(xy 191.115535 -413.10332) (xy 191.169528 -413.117436) (xy 191.220891 -413.139263) (xy 191.268529 -413.168336)
			(xy 191.311425 -413.204035) (xy 191.348667 -413.245599) (xy 191.379461 -413.292143) (xy 191.403149 -413.342674)
			(xy 191.409617 -413.364172) (xy 196.168516 -413.364172) (xy 196.172589 -413.308513) (xy 196.184724 -413.25404)
			(xy 196.20466 -413.201914) (xy 196.231974 -413.153246) (xy 196.266082 -413.109074) (xy 196.306259 -413.070339)
			(xy 196.351647 -413.037867) (xy 196.401279 -413.012349) (xy 196.454099 -412.99433) (xy 196.508978 -412.984193)
			(xy 196.564749 -412.982155) (xy 196.620223 -412.988258) (xy 196.674216 -413.002374) (xy 196.725579 -413.024201)
			(xy 196.773217 -413.053274) (xy 196.816113 -413.088973) (xy 196.853355 -413.130537) (xy 196.884149 -413.177081)
			(xy 196.907837 -413.227612) (xy 196.923915 -413.281054) (xy 196.932041 -413.336268) (xy 196.93255 -413.364172)
			(xy 197.32066 -413.364172) (xy 197.324733 -413.308513) (xy 197.336868 -413.25404) (xy 197.356804 -413.201914)
			(xy 197.384118 -413.153246) (xy 197.418226 -413.109074) (xy 197.458403 -413.070339) (xy 197.503791 -413.037867)
			(xy 197.553423 -413.012349) (xy 197.606243 -412.99433) (xy 197.661122 -412.984193) (xy 197.716893 -412.982155)
			(xy 197.772367 -412.988258) (xy 197.82636 -413.002374) (xy 197.877723 -413.024201) (xy 197.925361 -413.053274)
			(xy 197.968257 -413.088973) (xy 198.005499 -413.130537) (xy 198.036293 -413.177081) (xy 198.059981 -413.227612)
			(xy 198.076059 -413.281054) (xy 198.084185 -413.336268) (xy 198.084694 -413.364172) (xy 198.084185 -413.392076)
			(xy 198.076059 -413.44729) (xy 198.059981 -413.500732) (xy 198.036293 -413.551263) (xy 198.005499 -413.597807)
			(xy 197.968257 -413.639371) (xy 197.925361 -413.67507) (xy 197.877723 -413.704143) (xy 197.82636 -413.72597)
			(xy 197.772367 -413.740086) (xy 197.716893 -413.746189) (xy 197.661122 -413.744151) (xy 197.606243 -413.734014)
			(xy 197.553423 -413.715995) (xy 197.503791 -413.690477) (xy 197.458403 -413.658005) (xy 197.418226 -413.61927)
			(xy 197.384118 -413.575098) (xy 197.356804 -413.52643) (xy 197.336868 -413.474304) (xy 197.324733 -413.419831)
			(xy 197.32066 -413.364172) (xy 196.93255 -413.364172) (xy 196.932041 -413.392076) (xy 196.923915 -413.44729)
			(xy 196.907837 -413.500732) (xy 196.884149 -413.551263) (xy 196.853355 -413.597807) (xy 196.816113 -413.639371)
			(xy 196.773217 -413.67507) (xy 196.725579 -413.704143) (xy 196.674216 -413.72597) (xy 196.620223 -413.740086)
			(xy 196.564749 -413.746189) (xy 196.508978 -413.744151) (xy 196.454099 -413.734014) (xy 196.401279 -413.715995)
			(xy 196.351647 -413.690477) (xy 196.306259 -413.658005) (xy 196.266082 -413.61927) (xy 196.231974 -413.575098)
			(xy 196.20466 -413.52643) (xy 196.184724 -413.474304) (xy 196.172589 -413.419831) (xy 196.168516 -413.364172)
			(xy 191.409617 -413.364172) (xy 191.419227 -413.396116) (xy 191.427353 -413.45133) (xy 191.427862 -413.479234)
			(xy 191.427353 -413.507138) (xy 191.419227 -413.562352) (xy 191.403149 -413.615794) (xy 191.379461 -413.666325)
			(xy 191.348667 -413.712869) (xy 191.311425 -413.754433) (xy 191.268529 -413.790132) (xy 191.220891 -413.819205)
			(xy 191.169528 -413.841032) (xy 191.115535 -413.855148) (xy 191.060061 -413.861251) (xy 191.00429 -413.859213)
			(xy 190.949411 -413.849076) (xy 190.896591 -413.831057) (xy 190.846959 -413.805539) (xy 190.801571 -413.773067)
			(xy 190.761394 -413.734332) (xy 190.727286 -413.69016) (xy 190.699972 -413.641492) (xy 190.680036 -413.589366)
			(xy 190.667901 -413.534893) (xy 190.663828 -413.479234) (xy 190.269622 -413.479234) (xy 190.269113 -413.507138)
			(xy 190.260987 -413.562352) (xy 190.244909 -413.615794) (xy 190.221221 -413.666325) (xy 190.190427 -413.712869)
			(xy 190.153185 -413.754433) (xy 190.110289 -413.790132) (xy 190.062651 -413.819205) (xy 190.011288 -413.841032)
			(xy 189.957295 -413.855148) (xy 189.901821 -413.861251) (xy 189.84605 -413.859213) (xy 189.791171 -413.849076)
			(xy 189.738351 -413.831057) (xy 189.688719 -413.805539) (xy 189.643331 -413.773067) (xy 189.603154 -413.734332)
			(xy 189.569046 -413.69016) (xy 189.541732 -413.641492) (xy 189.521796 -413.589366) (xy 189.509661 -413.534893)
			(xy 189.505588 -413.479234) (xy 185.231532 -413.479234) (xy 185.854594 -414.102296) (xy 185.861992 -414.109144)
			(xy 185.88059 -414.116881) (xy 185.890662 -414.117282)
		)
		(stroke
			(width 0)
			(type solid)
		)
		(fill yes)
		(layer "In15.Cu")
		(net "P12V_AUX")
	)
	(gr_poly
		(pts
			(xy 91.273122 -175.078898) (xy 91.283077 -175.078366) (xy 91.301461 -175.070707) (xy 91.315576 -175.056657)
			(xy 91.319858 -175.047656) (xy 91.323401 -175.038213) (xy 91.323496 -175.018061) (xy 91.315772 -174.999448)
			(xy 91.308936 -174.99203) (xy 86.572852 -170.255946) (xy 86.565453 -170.249102) (xy 86.546854 -170.241378)
			(xy 86.536784 -170.24096) (xy 52.510182 -170.24096) (xy 52.504031 -170.241135) (xy 52.49209 -170.244101)
			(xy 52.48656 -170.246802) (xy 52.459032 -170.260637) (xy 52.400619 -170.280213) (xy 52.339817 -170.29014)
			(xy 52.309014 -170.290744) (xy 52.281758 -170.290282) (xy 52.2278 -170.282526) (xy 52.175496 -170.26717)
			(xy 52.125909 -170.244526) (xy 52.08005 -170.215055) (xy 52.038852 -170.179358) (xy 52.003153 -170.138161)
			(xy 51.973681 -170.092303) (xy 51.951035 -170.042717) (xy 51.935677 -169.990413) (xy 51.927919 -169.936456)
			(xy 51.927919 -169.881944) (xy 51.935677 -169.827987) (xy 51.951035 -169.775683) (xy 51.973681 -169.726097)
			(xy 52.003153 -169.680239) (xy 52.038852 -169.639042) (xy 52.08005 -169.603345) (xy 52.125909 -169.573874)
			(xy 52.175496 -169.55123) (xy 52.2278 -169.535874) (xy 52.281758 -169.528118) (xy 52.309014 -169.527728)
			(xy 52.339816 -169.528341) (xy 52.400613 -169.53828) (xy 52.459026 -169.557849) (xy 52.48656 -169.57167)
			(xy 52.49209 -169.57437) (xy 52.504031 -169.577331) (xy 52.510182 -169.577512) (xy 86.278212 -169.577512)
			(xy 86.288257 -169.577086) (xy 86.306809 -169.569377) (xy 86.320988 -169.555144) (xy 86.325202 -169.546016)
			(xy 86.331298 -169.531792) (xy 86.325202 -169.50182) (xy 83.87588 -167.052498) (xy 83.86848 -167.045655)
			(xy 83.849882 -167.037928) (xy 83.839812 -167.037512) (xy 63.726568 -167.037512) (xy 63.720701 -167.037674)
			(xy 63.70928 -167.040363) (xy 63.703962 -167.042846) (xy 63.703454 -167.0431) (xy 63.675926 -167.056934)
			(xy 63.617512 -167.07651) (xy 63.556711 -167.086436) (xy 63.525908 -167.087042) (xy 63.498652 -167.08658)
			(xy 63.444696 -167.078823) (xy 63.392392 -167.063466) (xy 63.342807 -167.040822) (xy 63.296948 -167.011352)
			(xy 63.255751 -166.975655) (xy 63.220053 -166.934458) (xy 63.190582 -166.888601) (xy 63.167937 -166.839015)
			(xy 63.152579 -166.786712) (xy 63.144821 -166.732756) (xy 63.144821 -166.678244) (xy 63.152579 -166.624288)
			(xy 63.167937 -166.571985) (xy 63.190582 -166.522399) (xy 63.220053 -166.476542) (xy 63.255751 -166.435345)
			(xy 63.296948 -166.399648) (xy 63.342807 -166.370178) (xy 63.392392 -166.347534) (xy 63.444696 -166.332177)
			(xy 63.498652 -166.32442) (xy 63.525908 -166.324026) (xy 63.556612 -166.324665) (xy 63.617221 -166.334546)
			(xy 63.675465 -166.354004) (xy 63.702946 -166.367714) (xy 63.703962 -166.368222) (xy 63.709296 -166.371016)
			(xy 63.720472 -166.373556) (xy 83.998308 -166.373556) (xy 84.009484 -166.37381) (xy 84.025232 -166.374318)
			(xy 84.051648 -166.357808) (xy 84.09559 -166.256716) (xy 84.099258 -166.24722) (xy 84.099523 -166.226883)
			(xy 84.091836 -166.208052) (xy 84.084922 -166.200582) (xy 83.59013 -165.70579) (xy 83.582732 -165.698945)
			(xy 83.564133 -165.691222) (xy 83.554062 -165.690804) (xy 56.896 -165.690804) (xy 56.862845 -165.69034)
			(xy 56.796951 -165.68292) (xy 56.732302 -165.668174) (xy 56.669708 -165.646286) (xy 56.609957 -165.617531)
			(xy 56.553799 -165.582272) (xy 56.501939 -165.540949) (xy 56.47817 -165.51783) (xy 53.45557 -162.49523)
			(xy 53.43246 -162.471452) (xy 53.391128 -162.419599) (xy 53.355861 -162.363444) (xy 53.327102 -162.303694)
			(xy 53.305214 -162.241101) (xy 53.290471 -162.17645) (xy 53.283058 -162.110555) (xy 53.282596 -162.0774)
			(xy 53.282596 -158.318454) (xy 53.282257 -158.309845) (xy 53.276566 -158.293595) (xy 53.265836 -158.28013)
			(xy 53.25872 -158.275274) (xy 53.185314 -158.229554) (xy 53.1779 -158.225351) (xy 53.161274 -158.221646)
			(xy 53.144353 -158.223597) (xy 53.136546 -158.227014) (xy 53.136292 -158.227014) (xy 53.110125 -158.239173)
			(xy 53.055045 -158.256353) (xy 52.998008 -158.265062) (xy 52.96916 -158.265622) (xy 52.94191 -158.265133)
			(xy 52.887964 -158.257372) (xy 52.835672 -158.242013) (xy 52.786098 -158.219369) (xy 52.740251 -158.1899)
			(xy 52.699064 -158.154207) (xy 52.663376 -158.113017) (xy 52.633912 -158.067166) (xy 52.611273 -158.01759)
			(xy 52.595919 -157.965297) (xy 52.588164 -157.91135) (xy 52.588164 -157.85685) (xy 52.595919 -157.802903)
			(xy 52.611273 -157.75061) (xy 52.633912 -157.701034) (xy 52.663376 -157.655183) (xy 52.699064 -157.613993)
			(xy 52.740251 -157.5783) (xy 52.786098 -157.548831) (xy 52.835672 -157.526187) (xy 52.887964 -157.510828)
			(xy 52.94191 -157.503067) (xy 52.96916 -157.502606) (xy 52.997969 -157.503148) (xy 53.054924 -157.511857)
			(xy 53.109917 -157.529052) (xy 53.136038 -157.541214) (xy 53.136546 -157.541214) (xy 53.144354 -157.544629)
			(xy 53.161274 -157.546587) (xy 53.177895 -157.54287) (xy 53.185314 -157.538674) (xy 53.25872 -157.492954)
			(xy 53.265865 -157.48812) (xy 53.276649 -157.474671) (xy 53.282327 -157.458395) (xy 53.282596 -157.449774)
			(xy 53.282596 -157.022546) (xy 53.282112 -157.011554) (xy 53.27302 -156.991545) (xy 53.26507 -156.983938)
			(xy 53.198014 -156.92628) (xy 53.176932 -156.920184) (xy 53.16601 -156.921962) (xy 53.152057 -156.923893)
			(xy 53.123961 -156.92593) (xy 53.109876 -156.926026) (xy 53.082625 -156.925539) (xy 53.028677 -156.917779)
			(xy 52.976383 -156.902421) (xy 52.926806 -156.879777) (xy 52.880956 -156.850309) (xy 52.839767 -156.814616)
			(xy 52.804077 -156.773424) (xy 52.774611 -156.727573) (xy 52.751971 -156.677995) (xy 52.736616 -156.6257)
			(xy 52.72886 -156.571751) (xy 52.72886 -156.517249) (xy 52.736616 -156.4633) (xy 52.751971 -156.411005)
			(xy 52.774611 -156.361427) (xy 52.804077 -156.315576) (xy 52.839767 -156.274384) (xy 52.880956 -156.238691)
			(xy 52.926806 -156.209223) (xy 52.976383 -156.186579) (xy 53.028677 -156.171221) (xy 53.082625 -156.163461)
			(xy 53.109876 -156.16301) (xy 53.123961 -156.163122) (xy 53.152056 -156.165156) (xy 53.16601 -156.167074)
			(xy 53.176932 -156.168852) (xy 53.198014 -156.162756) (xy 53.26507 -156.105098) (xy 53.273014 -156.097491)
			(xy 53.282086 -156.077478) (xy 53.282596 -156.06649) (xy 53.282596 -155.438348) (xy 53.28216 -155.427533)
			(xy 53.273344 -155.407788) (xy 53.265578 -155.400248) (xy 53.208936 -155.349702) (xy 53.200571 -155.342929)
			(xy 53.18005 -155.336497) (xy 53.169312 -155.337256) (xy 53.158555 -155.338428) (xy 53.136952 -155.339701)
			(xy 53.126132 -155.339796) (xy 53.098879 -155.339335) (xy 53.044926 -155.331582) (xy 52.992626 -155.316229)
			(xy 52.943043 -155.293589) (xy 52.897187 -155.264123) (xy 52.855992 -155.22843) (xy 52.820296 -155.187238)
			(xy 52.790826 -155.141385) (xy 52.768182 -155.091804) (xy 52.752825 -155.039505) (xy 52.745067 -154.985553)
			(xy 52.745067 -154.931047) (xy 52.752825 -154.877095) (xy 52.768182 -154.824796) (xy 52.790826 -154.775215)
			(xy 52.820296 -154.729362) (xy 52.855992 -154.68817) (xy 52.897187 -154.652477) (xy 52.943043 -154.623011)
			(xy 52.992626 -154.600371) (xy 53.044926 -154.585018) (xy 53.098879 -154.577265) (xy 53.126132 -154.57678)
			(xy 53.136952 -154.576877) (xy 53.158555 -154.578146) (xy 53.169312 -154.57932) (xy 53.180234 -154.58059)
			(xy 53.200554 -154.573986) (xy 53.265578 -154.516328) (xy 53.273315 -154.508765) (xy 53.282149 -154.489036)
			(xy 53.282596 -154.478228) (xy 53.282596 -153.894028) (xy 53.28211 -153.883931) (xy 53.274236 -153.865328)
			(xy 53.25981 -153.851189) (xy 53.250592 -153.847038) (xy 53.148738 -153.806144) (xy 53.118258 -153.812748)
			(xy 53.10759 -153.823924) (xy 53.089527 -153.842169) (xy 53.049355 -153.874141) (xy 53.005262 -153.900443)
			(xy 52.958042 -153.920599) (xy 52.908548 -153.934247) (xy 52.857671 -153.941139) (xy 52.832 -153.941526)
			(xy 52.804747 -153.94104) (xy 52.750797 -153.933283) (xy 52.6985 -153.917927) (xy 52.64892 -153.895285)
			(xy 52.603068 -153.865818) (xy 52.561876 -153.830124) (xy 52.526182 -153.788932) (xy 52.496715 -153.74308)
			(xy 52.474073 -153.6935) (xy 52.458717 -153.641203) (xy 52.45096 -153.587253) (xy 52.45096 -153.532747)
			(xy 52.458717 -153.478797) (xy 52.474073 -153.4265) (xy 52.496715 -153.37692) (xy 52.526182 -153.331068)
			(xy 52.561876 -153.289876) (xy 52.603068 -153.254182) (xy 52.64892 -153.224715) (xy 52.6985 -153.202073)
			(xy 52.750797 -153.186717) (xy 52.804747 -153.17896) (xy 52.832 -153.17851) (xy 52.85767 -153.178927)
			(xy 52.908547 -153.185809) (xy 52.958042 -153.199449) (xy 53.005262 -153.2196) (xy 53.049354 -153.245899)
			(xy 53.089523 -153.277871) (xy 53.10759 -153.296112) (xy 53.118258 -153.307288) (xy 53.148738 -153.313892)
			(xy 53.250592 -153.272998) (xy 53.25982 -153.268862) (xy 53.274259 -153.254728) (xy 53.28211 -153.23611)
			(xy 53.282596 -153.226008) (xy 53.282596 -151.68626) (xy 53.282239 -151.677563) (xy 53.276412 -151.661173)
			(xy 53.265442 -151.647674) (xy 53.258212 -151.642826) (xy 53.18379 -151.597614) (xy 53.176244 -151.593461)
			(xy 53.159391 -151.589955) (xy 53.142326 -151.592212) (xy 53.134514 -151.595836) (xy 53.13426 -151.595836)
			(xy 53.107019 -151.609271) (xy 53.049336 -151.628284) (xy 52.989368 -151.637912) (xy 52.959 -151.638508)
			(xy 52.931749 -151.638022) (xy 52.877801 -151.630266) (xy 52.825506 -151.614911) (xy 52.775929 -151.592269)
			(xy 52.730079 -151.562803) (xy 52.688888 -151.527112) (xy 52.653197 -151.485921) (xy 52.623731 -151.440071)
			(xy 52.601089 -151.390494) (xy 52.585734 -151.338199) (xy 52.577978 -151.284251) (xy 52.577978 -151.229749)
			(xy 52.585734 -151.175801) (xy 52.601089 -151.123506) (xy 52.623731 -151.073929) (xy 52.653197 -151.028079)
			(xy 52.688888 -150.986888) (xy 52.730079 -150.951197) (xy 52.775929 -150.921731) (xy 52.825506 -150.899089)
			(xy 52.877801 -150.883734) (xy 52.931749 -150.875978) (xy 52.959 -150.875492) (xy 52.989368 -150.876082)
			(xy 53.049336 -150.885712) (xy 53.107019 -150.90473) (xy 53.13426 -150.918164) (xy 53.134514 -150.918164)
			(xy 53.142333 -150.921792) (xy 53.159403 -150.924102) (xy 53.176267 -150.92059) (xy 53.18379 -150.916386)
			(xy 53.258212 -150.871174) (xy 53.265471 -150.866355) (xy 53.276463 -150.852853) (xy 53.282286 -150.836446)
			(xy 53.282596 -150.82774) (xy 53.282596 -143.674338) (xy 53.282161 -143.664273) (xy 53.274431 -143.645685)
			(xy 53.26761 -143.63827) (xy 52.76977 -143.14043) (xy 52.74666 -143.116652) (xy 52.705328 -143.064799)
			(xy 52.670061 -143.008644) (xy 52.641302 -142.948894) (xy 52.619414 -142.886301) (xy 52.604671 -142.82165)
			(xy 52.597258 -142.755755) (xy 52.596796 -142.7226) (xy 52.596796 -139.838938) (xy 52.596361 -139.828873)
			(xy 52.588631 -139.810285) (xy 52.58181 -139.80287) (xy 51.993546 -139.214606) (xy 51.98583 -139.207538)
			(xy 51.966418 -139.199786) (xy 51.945524 -139.200423) (xy 51.92662 -139.209342) (xy 51.919378 -139.216892)
			(xy 51.901205 -139.236867) (xy 51.860193 -139.271997) (xy 51.814631 -139.300984) (xy 51.765432 -139.323245)
			(xy 51.713582 -139.338334) (xy 51.660121 -139.34595) (xy 51.63312 -139.346432) (xy 51.606751 -139.345987)
			(xy 51.554517 -139.338723) (xy 51.503782 -139.32433) (xy 51.455514 -139.303083) (xy 51.410635 -139.275388)
			(xy 51.37 -139.241772) (xy 51.334385 -139.202878) (xy 51.304469 -139.159447) (xy 51.280823 -139.112308)
			(xy 51.263899 -139.062361) (xy 51.25847 -139.036552) (xy 51.255646 -139.025147) (xy 51.241428 -139.006476)
			(xy 51.220418 -138.996019) (xy 51.208686 -138.995404) (xy 50.3936 -138.995404) (xy 50.360445 -138.99494)
			(xy 50.294551 -138.98752) (xy 50.229902 -138.972774) (xy 50.167308 -138.950886) (xy 50.107557 -138.922131)
			(xy 50.051399 -138.886872) (xy 49.999539 -138.845549) (xy 49.97577 -138.82243) (xy 49.52873 -138.37539)
			(xy 49.521332 -138.368545) (xy 49.502733 -138.360822) (xy 49.492662 -138.360404) (xy 47.545752 -138.360404)
			(xy 47.534331 -138.360857) (xy 47.513693 -138.370632) (xy 47.506128 -138.3792) (xy 47.456344 -138.440922)
			(xy 47.449682 -138.450107) (xy 47.444385 -138.472139) (xy 47.446184 -138.48334) (xy 47.446184 -138.483594)
			(xy 47.450226 -138.503478) (xy 47.454553 -138.543823) (xy 47.45482 -138.564112) (xy 47.454334 -138.591363)
			(xy 47.446578 -138.645311) (xy 47.431223 -138.697606) (xy 47.408581 -138.747183) (xy 47.379115 -138.793033)
			(xy 47.343424 -138.834224) (xy 47.302233 -138.869915) (xy 47.256383 -138.899381) (xy 47.206806 -138.922023)
			(xy 47.154511 -138.937378) (xy 47.100563 -138.945134) (xy 47.046061 -138.945134) (xy 46.992113 -138.937378)
			(xy 46.939818 -138.922023) (xy 46.890241 -138.899381) (xy 46.844391 -138.869915) (xy 46.8032 -138.834224)
			(xy 46.767509 -138.793033) (xy 46.738043 -138.747183) (xy 46.715401 -138.697606) (xy 46.700046 -138.645311)
			(xy 46.69229 -138.591363) (xy 46.691804 -138.564112) (xy 46.692086 -138.543824) (xy 46.696409 -138.503479)
			(xy 46.70044 -138.483594) (xy 46.70044 -138.48334) (xy 46.702168 -138.472138) (xy 46.696904 -138.450119)
			(xy 46.69028 -138.440922) (xy 46.640496 -138.3792) (xy 46.632827 -138.370765) (xy 46.612256 -138.361005)
			(xy 46.600872 -138.360404) (xy 46.163738 -138.360404) (xy 46.153673 -138.360839) (xy 46.135085 -138.368569)
			(xy 46.12767 -138.37539) (xy 45.879258 -138.623802) (xy 45.855479 -138.646911) (xy 45.803624 -138.68824)
			(xy 45.74747 -138.723506) (xy 45.68772 -138.752263) (xy 45.625127 -138.774152) (xy 45.560477 -138.788896)
			(xy 45.494583 -138.796311) (xy 45.461428 -138.796776) (xy 44.98721 -138.796776) (xy 44.977138 -138.797197)
			(xy 44.958529 -138.804906) (xy 44.951142 -138.811762) (xy 44.848272 -138.914632) (xy 44.824512 -138.937772)
			(xy 44.772668 -138.97914) (xy 44.716518 -139.014442) (xy 44.656769 -139.043236) (xy 44.594171 -139.065158)
			(xy 44.529512 -139.079934) (xy 44.463605 -139.087376) (xy 44.430442 -139.08786) (xy 44.397272 -139.087415)
			(xy 44.33135 -139.079991) (xy 44.266673 -139.065234) (xy 44.204056 -139.043327) (xy 44.144285 -139.014546)
			(xy 44.088113 -138.979255) (xy 44.036245 -138.937895) (xy 43.989334 -138.890988) (xy 43.947971 -138.839123)
			(xy 43.912675 -138.782954) (xy 43.88389 -138.723185) (xy 43.861979 -138.660569) (xy 43.847216 -138.595893)
			(xy 43.839788 -138.529972) (xy 43.839384 -138.496802) (xy 43.839818 -138.464489) (xy 43.846871 -138.40025)
			(xy 43.860892 -138.337163) (xy 43.881715 -138.275984) (xy 43.909091 -138.217443) (xy 43.942692 -138.16224)
			(xy 43.962066 -138.136376) (xy 43.967146 -138.130026) (xy 43.97248 -138.114024) (xy 43.97248 -138.01598)
			(xy 43.967146 -137.999978) (xy 43.962066 -137.993628) (xy 43.942698 -137.96776) (xy 43.909097 -137.912557)
			(xy 43.881721 -137.854017) (xy 43.860898 -137.792839) (xy 43.846876 -137.729753) (xy 43.839823 -137.665514)
			(xy 43.839384 -137.633202) (xy 43.839832 -137.600035) (xy 43.847259 -137.534118) (xy 43.86202 -137.469447)
			(xy 43.88393 -137.406835) (xy 43.912713 -137.34707) (xy 43.948006 -137.290904) (xy 43.989366 -137.239043)
			(xy 44.036273 -137.192139) (xy 44.088137 -137.150783) (xy 44.144305 -137.115493) (xy 44.204072 -137.086715)
			(xy 44.266685 -137.064809) (xy 44.331357 -137.050053) (xy 44.397275 -137.04263) (xy 44.430442 -137.042144)
			(xy 44.463605 -137.042622) (xy 44.529511 -137.050071) (xy 44.59417 -137.06485) (xy 44.656768 -137.086772)
			(xy 44.71652 -137.115563) (xy 44.772675 -137.150859) (xy 44.824526 -137.192218) (xy 44.848272 -137.215372)
			(xy 44.951142 -137.318242) (xy 44.95854 -137.325088) (xy 44.977139 -137.332816) (xy 44.98721 -137.333228)
			(xy 45.07865 -137.333228) (xy 45.088717 -137.332797) (xy 45.107311 -137.325073) (xy 45.114718 -137.318242)
			(xy 45.36313 -137.06983) (xy 45.386909 -137.04672) (xy 45.438762 -137.005387) (xy 45.494916 -136.970118)
			(xy 45.554665 -136.941358) (xy 45.617259 -136.919467) (xy 45.681909 -136.90472) (xy 45.747804 -136.897304)
			(xy 45.78096 -136.896856) (xy 49.87544 -136.896856) (xy 49.908594 -136.897322) (xy 49.974486 -136.904745)
			(xy 50.039134 -136.919495) (xy 50.101725 -136.941385) (xy 50.161475 -136.97014) (xy 50.217631 -137.005401)
			(xy 50.26949 -137.046723) (xy 50.29327 -137.06983) (xy 50.51044 -137.287) (xy 56.767982 -137.287)
			(xy 56.772053 -137.231378) (xy 56.784179 -137.176941) (xy 56.804102 -137.12485) (xy 56.831398 -137.076215)
			(xy 56.865484 -137.032072) (xy 56.905633 -136.993363) (xy 56.950991 -136.960912) (xy 57.000591 -136.935411)
			(xy 57.053375 -136.917404) (xy 57.108218 -136.907274) (xy 57.163952 -136.905237) (xy 57.219389 -136.911337)
			(xy 57.273346 -136.925443) (xy 57.324675 -136.947255) (xy 57.372281 -136.976309) (xy 57.383938 -136.98601)
			(xy 80.557622 -136.98601) (xy 80.561693 -136.930388) (xy 80.573819 -136.875951) (xy 80.593742 -136.82386)
			(xy 80.621038 -136.775225) (xy 80.655124 -136.731082) (xy 80.695273 -136.692373) (xy 80.740631 -136.659922)
			(xy 80.790231 -136.634421) (xy 80.843015 -136.616414) (xy 80.897858 -136.606284) (xy 80.953592 -136.604247)
			(xy 81.009029 -136.610347) (xy 81.062986 -136.624453) (xy 81.114315 -136.646265) (xy 81.161921 -136.675319)
			(xy 81.204789 -136.710994) (xy 81.242006 -136.752531) (xy 81.272779 -136.799044) (xy 81.296451 -136.849541)
			(xy 81.312519 -136.902948) (xy 81.320639 -136.958124) (xy 81.321148 -136.98601) (xy 81.320639 -137.013896)
			(xy 81.312519 -137.069072) (xy 81.296451 -137.122479) (xy 81.272779 -137.172976) (xy 81.242006 -137.219489)
			(xy 81.204789 -137.261026) (xy 81.161921 -137.296701) (xy 81.114315 -137.325755) (xy 81.062986 -137.347567)
			(xy 81.009029 -137.361673) (xy 80.953592 -137.367773) (xy 80.897858 -137.365736) (xy 80.843015 -137.355606)
			(xy 80.790231 -137.337599) (xy 80.740631 -137.312098) (xy 80.695273 -137.279647) (xy 80.655124 -137.240938)
			(xy 80.621038 -137.196795) (xy 80.593742 -137.14816) (xy 80.573819 -137.096069) (xy 80.561693 -137.041632)
			(xy 80.557622 -136.98601) (xy 57.383938 -136.98601) (xy 57.415149 -137.011984) (xy 57.452366 -137.053521)
			(xy 57.483139 -137.100034) (xy 57.506811 -137.150531) (xy 57.522879 -137.203938) (xy 57.530999 -137.259114)
			(xy 57.531508 -137.287) (xy 57.530999 -137.314886) (xy 57.522879 -137.370062) (xy 57.506811 -137.423469)
			(xy 57.483139 -137.473966) (xy 57.452366 -137.520479) (xy 57.415149 -137.562016) (xy 57.372281 -137.597691)
			(xy 57.324675 -137.626745) (xy 57.273346 -137.648557) (xy 57.219389 -137.662663) (xy 57.163952 -137.668763)
			(xy 57.108218 -137.666726) (xy 57.053375 -137.656596) (xy 57.000591 -137.638589) (xy 56.950991 -137.613088)
			(xy 56.905633 -137.580637) (xy 56.865484 -137.541928) (xy 56.831398 -137.497785) (xy 56.804102 -137.44915)
			(xy 56.784179 -137.397059) (xy 56.772053 -137.342622) (xy 56.767982 -137.287) (xy 50.51044 -137.287)
			(xy 50.74031 -137.51687) (xy 50.747708 -137.523718) (xy 50.766306 -137.531454) (xy 50.776378 -137.531856)
			(xy 52.13604 -137.531856) (xy 52.169194 -137.532322) (xy 52.235086 -137.539745) (xy 52.299734 -137.554495)
			(xy 52.362325 -137.576385) (xy 52.422075 -137.60514) (xy 52.478231 -137.640401) (xy 52.53009 -137.681723)
			(xy 52.55387 -137.70483) (xy 52.697888 -137.848848) (xy 61.93993 -137.848848) (xy 61.944001 -137.793226)
			(xy 61.956127 -137.738789) (xy 61.97605 -137.686698) (xy 62.003346 -137.638063) (xy 62.037432 -137.59392)
			(xy 62.077581 -137.555211) (xy 62.122939 -137.52276) (xy 62.172539 -137.497259) (xy 62.225323 -137.479252)
			(xy 62.280166 -137.469122) (xy 62.3359 -137.467085) (xy 62.391337 -137.473185) (xy 62.445294 -137.487291)
			(xy 62.496623 -137.509103) (xy 62.544229 -137.538157) (xy 62.587097 -137.573832) (xy 62.624314 -137.615369)
			(xy 62.655087 -137.661882) (xy 62.678759 -137.712379) (xy 62.694827 -137.765786) (xy 62.702947 -137.820962)
			(xy 62.703456 -137.848848) (xy 62.702947 -137.876734) (xy 62.694827 -137.93191) (xy 62.678759 -137.985317)
			(xy 62.655087 -138.035814) (xy 62.624314 -138.082327) (xy 62.587097 -138.123864) (xy 62.544229 -138.159539)
			(xy 62.496623 -138.188593) (xy 62.445294 -138.210405) (xy 62.391337 -138.224511) (xy 62.3359 -138.230611)
			(xy 62.280166 -138.228574) (xy 62.225323 -138.218444) (xy 62.172539 -138.200437) (xy 62.122939 -138.174936)
			(xy 62.077581 -138.142485) (xy 62.037432 -138.103776) (xy 62.003346 -138.059633) (xy 61.97605 -138.010998)
			(xy 61.956127 -137.958907) (xy 61.944001 -137.90447) (xy 61.93993 -137.848848) (xy 52.697888 -137.848848)
			(xy 53.207412 -138.358372) (xy 84.809328 -138.358372) (xy 84.813399 -138.30275) (xy 84.825525 -138.248313)
			(xy 84.845448 -138.196222) (xy 84.872744 -138.147587) (xy 84.90683 -138.103444) (xy 84.946979 -138.064735)
			(xy 84.992337 -138.032284) (xy 85.041937 -138.006783) (xy 85.094721 -137.988776) (xy 85.149564 -137.978646)
			(xy 85.205298 -137.976609) (xy 85.260735 -137.982709) (xy 85.314692 -137.996815) (xy 85.366021 -138.018627)
			(xy 85.413627 -138.047681) (xy 85.456495 -138.083356) (xy 85.493712 -138.124893) (xy 85.524485 -138.171406)
			(xy 85.548157 -138.221903) (xy 85.564225 -138.27531) (xy 85.572345 -138.330486) (xy 85.572854 -138.358372)
			(xy 85.572345 -138.386258) (xy 85.564225 -138.441434) (xy 85.548157 -138.494841) (xy 85.524485 -138.545338)
			(xy 85.493712 -138.591851) (xy 85.456495 -138.633388) (xy 85.413627 -138.669063) (xy 85.366021 -138.698117)
			(xy 85.314692 -138.719929) (xy 85.260735 -138.734035) (xy 85.205298 -138.740135) (xy 85.149564 -138.738098)
			(xy 85.094721 -138.727968) (xy 85.041937 -138.709961) (xy 84.992337 -138.68446) (xy 84.946979 -138.652009)
			(xy 84.90683 -138.6133) (xy 84.872744 -138.569157) (xy 84.845448 -138.520522) (xy 84.825525 -138.468431)
			(xy 84.813399 -138.413994) (xy 84.809328 -138.358372) (xy 53.207412 -138.358372) (xy 53.80609 -138.95705)
			(xy 56.514492 -138.95705) (xy 56.514978 -138.929799) (xy 56.522734 -138.875851) (xy 56.538089 -138.823556)
			(xy 56.560731 -138.773979) (xy 56.590197 -138.728129) (xy 56.625888 -138.686938) (xy 56.667079 -138.651247)
			(xy 56.712929 -138.621781) (xy 56.762506 -138.599139) (xy 56.814801 -138.583784) (xy 56.868749 -138.576028)
			(xy 56.923251 -138.576028) (xy 56.977199 -138.583784) (xy 57.029494 -138.599139) (xy 57.079071 -138.621781)
			(xy 57.124921 -138.651247) (xy 57.166112 -138.686938) (xy 57.201803 -138.728129) (xy 57.231269 -138.773979)
			(xy 57.253911 -138.823556) (xy 57.266035 -138.864848) (xy 61.93993 -138.864848) (xy 61.944001 -138.809226)
			(xy 61.956127 -138.754789) (xy 61.97605 -138.702698) (xy 62.003346 -138.654063) (xy 62.037432 -138.60992)
			(xy 62.077581 -138.571211) (xy 62.122939 -138.53876) (xy 62.172539 -138.513259) (xy 62.225323 -138.495252)
			(xy 62.280166 -138.485122) (xy 62.3359 -138.483085) (xy 62.391337 -138.489185) (xy 62.445294 -138.503291)
			(xy 62.496623 -138.525103) (xy 62.544229 -138.554157) (xy 62.587097 -138.589832) (xy 62.624314 -138.631369)
			(xy 62.655087 -138.677882) (xy 62.678759 -138.728379) (xy 62.694827 -138.781786) (xy 62.702947 -138.836962)
			(xy 62.703456 -138.864848) (xy 62.702947 -138.892734) (xy 62.694827 -138.94791) (xy 62.678759 -139.001317)
			(xy 62.655087 -139.051814) (xy 62.624314 -139.098327) (xy 62.587097 -139.139864) (xy 62.544229 -139.175539)
			(xy 62.496623 -139.204593) (xy 62.445294 -139.226405) (xy 62.391337 -139.240511) (xy 62.3359 -139.246611)
			(xy 62.280166 -139.244574) (xy 62.225323 -139.234444) (xy 62.172539 -139.216437) (xy 62.122939 -139.190936)
			(xy 62.077581 -139.158485) (xy 62.037432 -139.119776) (xy 62.003346 -139.075633) (xy 61.97605 -139.026998)
			(xy 61.956127 -138.974907) (xy 61.944001 -138.92047) (xy 61.93993 -138.864848) (xy 57.266035 -138.864848)
			(xy 57.269266 -138.875851) (xy 57.277022 -138.929799) (xy 57.277508 -138.95705) (xy 57.277021 -138.984831)
			(xy 57.268946 -139.039802) (xy 57.252975 -139.093019) (xy 57.229446 -139.143352) (xy 57.198858 -139.189736)
			(xy 57.180734 -139.210796) (xy 57.18048 -139.21105) (xy 57.174172 -139.218927) (xy 57.167759 -139.238046)
			(xy 57.168034 -139.248134) (xy 57.173368 -139.321286) (xy 57.17455 -139.33136) (xy 57.183715 -139.349437)
			(xy 57.191148 -139.356338) (xy 57.191402 -139.356592) (xy 57.212402 -139.374834) (xy 57.249478 -139.416297)
			(xy 57.280132 -139.46271) (xy 57.303711 -139.513087) (xy 57.319715 -139.566358) (xy 57.327802 -139.621389)
			(xy 57.328308 -139.6492) (xy 57.327822 -139.676451) (xy 57.322063 -139.71651) (xy 82.791806 -139.71651)
			(xy 82.795877 -139.660888) (xy 82.808003 -139.606451) (xy 82.827926 -139.55436) (xy 82.855222 -139.505725)
			(xy 82.889308 -139.461582) (xy 82.929457 -139.422873) (xy 82.974815 -139.390422) (xy 83.024415 -139.364921)
			(xy 83.077199 -139.346914) (xy 83.132042 -139.336784) (xy 83.187776 -139.334747) (xy 83.243213 -139.340847)
			(xy 83.29717 -139.354953) (xy 83.348499 -139.376765) (xy 83.396105 -139.405819) (xy 83.438973 -139.441494)
			(xy 83.47619 -139.483031) (xy 83.506963 -139.529544) (xy 83.530635 -139.580041) (xy 83.546703 -139.633448)
			(xy 83.554823 -139.688624) (xy 83.555332 -139.71651) (xy 83.554823 -139.744396) (xy 83.546703 -139.799572)
			(xy 83.530635 -139.852979) (xy 83.506963 -139.903476) (xy 83.47619 -139.949989) (xy 83.438973 -139.991526)
			(xy 83.396105 -140.027201) (xy 83.35748 -140.050774) (xy 85.235794 -140.050774) (xy 85.239865 -139.995152)
			(xy 85.251991 -139.940715) (xy 85.271914 -139.888624) (xy 85.29921 -139.839989) (xy 85.333296 -139.795846)
			(xy 85.373445 -139.757137) (xy 85.418803 -139.724686) (xy 85.468403 -139.699185) (xy 85.521187 -139.681178)
			(xy 85.57603 -139.671048) (xy 85.631764 -139.669011) (xy 85.687201 -139.675111) (xy 85.741158 -139.689217)
			(xy 85.792487 -139.711029) (xy 85.840093 -139.740083) (xy 85.882961 -139.775758) (xy 85.920178 -139.817295)
			(xy 85.950951 -139.863808) (xy 85.974623 -139.914305) (xy 85.990691 -139.967712) (xy 85.998811 -140.022888)
			(xy 85.99932 -140.050774) (xy 85.998811 -140.07866) (xy 85.990691 -140.133836) (xy 85.974623 -140.187243)
			(xy 85.950951 -140.23774) (xy 85.920178 -140.284253) (xy 85.882961 -140.32579) (xy 85.840093 -140.361465)
			(xy 85.792487 -140.390519) (xy 85.741158 -140.412331) (xy 85.687201 -140.426437) (xy 85.631764 -140.432537)
			(xy 85.57603 -140.4305) (xy 85.521187 -140.42037) (xy 85.468403 -140.402363) (xy 85.418803 -140.376862)
			(xy 85.373445 -140.344411) (xy 85.333296 -140.305702) (xy 85.29921 -140.261559) (xy 85.271914 -140.212924)
			(xy 85.251991 -140.160833) (xy 85.239865 -140.106396) (xy 85.235794 -140.050774) (xy 83.35748 -140.050774)
			(xy 83.348499 -140.056255) (xy 83.29717 -140.078067) (xy 83.243213 -140.092173) (xy 83.187776 -140.098273)
			(xy 83.132042 -140.096236) (xy 83.077199 -140.086106) (xy 83.024415 -140.068099) (xy 82.974815 -140.042598)
			(xy 82.929457 -140.010147) (xy 82.889308 -139.971438) (xy 82.855222 -139.927295) (xy 82.827926 -139.87866)
			(xy 82.808003 -139.826569) (xy 82.795877 -139.772132) (xy 82.791806 -139.71651) (xy 57.322063 -139.71651)
			(xy 57.320066 -139.730399) (xy 57.304711 -139.782694) (xy 57.282069 -139.832271) (xy 57.252603 -139.878121)
			(xy 57.216912 -139.919312) (xy 57.175721 -139.955003) (xy 57.129871 -139.984469) (xy 57.080294 -140.007111)
			(xy 57.027999 -140.022466) (xy 56.974051 -140.030222) (xy 56.919549 -140.030222) (xy 56.865601 -140.022466)
			(xy 56.813306 -140.007111) (xy 56.763729 -139.984469) (xy 56.717879 -139.955003) (xy 56.676688 -139.919312)
			(xy 56.640997 -139.878121) (xy 56.611531 -139.832271) (xy 56.588889 -139.782694) (xy 56.573534 -139.730399)
			(xy 56.565778 -139.676451) (xy 56.565292 -139.6492) (xy 56.565809 -139.62142) (xy 56.573876 -139.56645)
			(xy 56.58984 -139.513234) (xy 56.613363 -139.4629) (xy 56.643945 -139.416515) (xy 56.662066 -139.395454)
			(xy 56.66232 -139.3952) (xy 56.668651 -139.387339) (xy 56.675051 -139.368207) (xy 56.674766 -139.358116)
			(xy 56.669432 -139.284964) (xy 56.668275 -139.274885) (xy 56.659093 -139.25681) (xy 56.651652 -139.249912)
			(xy 56.651398 -139.249658) (xy 56.630374 -139.231443) (xy 56.593299 -139.189974) (xy 56.562649 -139.143555)
			(xy 56.539074 -139.093173) (xy 56.523075 -139.039898) (xy 56.514994 -138.984863) (xy 56.514492 -138.95705)
			(xy 53.80609 -138.95705) (xy 53.88737 -139.03833) (xy 53.91048 -139.062109) (xy 53.951813 -139.113962)
			(xy 53.987082 -139.170116) (xy 54.015842 -139.229865) (xy 54.037733 -139.292459) (xy 54.05248 -139.357109)
			(xy 54.059896 -139.423004) (xy 54.060344 -139.45616) (xy 54.060344 -140.534898) (xy 81.097372 -140.534898)
			(xy 81.101443 -140.479276) (xy 81.113569 -140.424839) (xy 81.133492 -140.372748) (xy 81.160788 -140.324113)
			(xy 81.194874 -140.27997) (xy 81.235023 -140.241261) (xy 81.280381 -140.20881) (xy 81.329981 -140.183309)
			(xy 81.382765 -140.165302) (xy 81.437608 -140.155172) (xy 81.493342 -140.153135) (xy 81.548779 -140.159235)
			(xy 81.602736 -140.173341) (xy 81.654065 -140.195153) (xy 81.701671 -140.224207) (xy 81.744539 -140.259882)
			(xy 81.781756 -140.301419) (xy 81.812529 -140.347932) (xy 81.836201 -140.398429) (xy 81.852269 -140.451836)
			(xy 81.860389 -140.507012) (xy 81.860898 -140.534898) (xy 81.860389 -140.562784) (xy 81.852269 -140.61796)
			(xy 81.836201 -140.671367) (xy 81.812529 -140.721864) (xy 81.781756 -140.768377) (xy 81.744539 -140.809914)
			(xy 81.701671 -140.845589) (xy 81.654065 -140.874643) (xy 81.602736 -140.896455) (xy 81.548779 -140.910561)
			(xy 81.493342 -140.916661) (xy 81.437608 -140.914624) (xy 81.382765 -140.904494) (xy 81.329981 -140.886487)
			(xy 81.280381 -140.860986) (xy 81.235023 -140.828535) (xy 81.194874 -140.789826) (xy 81.160788 -140.745683)
			(xy 81.133492 -140.697048) (xy 81.113569 -140.644957) (xy 81.101443 -140.59052) (xy 81.097372 -140.534898)
			(xy 54.060344 -140.534898) (xy 54.060344 -141.9352) (xy 56.524142 -141.9352) (xy 56.528213 -141.879578)
			(xy 56.540339 -141.825141) (xy 56.560262 -141.77305) (xy 56.587558 -141.724415) (xy 56.621644 -141.680272)
			(xy 56.661793 -141.641563) (xy 56.707151 -141.609112) (xy 56.756751 -141.583611) (xy 56.809535 -141.565604)
			(xy 56.864378 -141.555474) (xy 56.920112 -141.553437) (xy 56.975549 -141.559537) (xy 57.029506 -141.573643)
			(xy 57.080835 -141.595455) (xy 57.128441 -141.624509) (xy 57.171309 -141.660184) (xy 57.208526 -141.701721)
			(xy 57.239299 -141.748234) (xy 57.262971 -141.798731) (xy 57.279039 -141.852138) (xy 57.287159 -141.907314)
			(xy 57.287668 -141.9352) (xy 57.287159 -141.963086) (xy 57.279039 -142.018262) (xy 57.262971 -142.071669)
			(xy 57.239299 -142.122166) (xy 57.208526 -142.168679) (xy 57.171309 -142.210216) (xy 57.128441 -142.245891)
			(xy 57.080835 -142.274945) (xy 57.029506 -142.296757) (xy 56.975549 -142.310863) (xy 56.920112 -142.316963)
			(xy 56.864378 -142.314926) (xy 56.809535 -142.304796) (xy 56.756751 -142.286789) (xy 56.707151 -142.261288)
			(xy 56.661793 -142.228837) (xy 56.621644 -142.190128) (xy 56.587558 -142.145985) (xy 56.560262 -142.09735)
			(xy 56.540339 -142.045259) (xy 56.528213 -141.990822) (xy 56.524142 -141.9352) (xy 54.060344 -141.9352)
			(xy 54.060344 -141.960346) (xy 54.060832 -141.970754) (xy 54.069079 -141.989867) (xy 54.084238 -142.004132)
			(xy 54.093872 -142.008098) (xy 54.121218 -142.01847) (xy 54.172606 -142.046388) (xy 54.219128 -142.081829)
			(xy 54.259691 -142.123959) (xy 54.293342 -142.17179) (xy 54.319293 -142.2242) (xy 54.336934 -142.279959)
			(xy 54.345852 -142.337758) (xy 54.346348 -142.367) (xy 54.345719 -142.39866) (xy 54.335266 -142.461112)
			(xy 54.314661 -142.520987) (xy 54.30012 -142.549118) (xy 54.295312 -142.558951) (xy 54.293718 -142.580758)
			(xy 54.301368 -142.601241) (xy 54.308756 -142.609316) (xy 54.57317 -142.87373) (xy 54.59628 -142.897509)
			(xy 54.637613 -142.949362) (xy 54.638767 -142.9512) (xy 56.540398 -142.9512) (xy 56.544469 -142.895578)
			(xy 56.556595 -142.841141) (xy 56.576518 -142.78905) (xy 56.603814 -142.740415) (xy 56.6379 -142.696272)
			(xy 56.678049 -142.657563) (xy 56.723407 -142.625112) (xy 56.773007 -142.599611) (xy 56.825791 -142.581604)
			(xy 56.880634 -142.571474) (xy 56.936368 -142.569437) (xy 56.991805 -142.575537) (xy 57.045762 -142.589643)
			(xy 57.097091 -142.611455) (xy 57.144697 -142.640509) (xy 57.187565 -142.676184) (xy 57.224782 -142.717721)
			(xy 57.255555 -142.764234) (xy 57.279227 -142.814731) (xy 57.295295 -142.868138) (xy 57.303415 -142.923314)
			(xy 57.303924 -142.9512) (xy 57.303415 -142.979086) (xy 57.295295 -143.034262) (xy 57.279227 -143.087669)
			(xy 57.255555 -143.138166) (xy 57.224782 -143.184679) (xy 57.187565 -143.226216) (xy 57.144697 -143.261891)
			(xy 57.097091 -143.290945) (xy 57.045762 -143.312757) (xy 56.991805 -143.326863) (xy 56.936368 -143.332963)
			(xy 56.880634 -143.330926) (xy 56.825791 -143.320796) (xy 56.773007 -143.302789) (xy 56.723407 -143.277288)
			(xy 56.678049 -143.244837) (xy 56.6379 -143.206128) (xy 56.603814 -143.161985) (xy 56.576518 -143.11335)
			(xy 56.556595 -143.061259) (xy 56.544469 -143.006822) (xy 56.540398 -142.9512) (xy 54.638767 -142.9512)
			(xy 54.672882 -143.005516) (xy 54.701642 -143.065265) (xy 54.723533 -143.127859) (xy 54.73828 -143.192509)
			(xy 54.745696 -143.258404) (xy 54.746144 -143.29156) (xy 54.746144 -143.48714) (xy 66.599308 -143.48714)
			(xy 66.599308 -142.62354) (xy 66.599798 -142.593556) (xy 66.607626 -142.5341) (xy 66.623147 -142.476175)
			(xy 66.646096 -142.420771) (xy 66.67608 -142.368837) (xy 66.712586 -142.321261) (xy 66.754991 -142.278856)
			(xy 66.802567 -142.24235) (xy 66.854501 -142.212366) (xy 66.909905 -142.189417) (xy 66.96783 -142.173896)
			(xy 67.027286 -142.166068) (xy 67.087254 -142.166068) (xy 67.14671 -142.173896) (xy 67.204635 -142.189417)
			(xy 67.260039 -142.212366) (xy 67.311973 -142.24235) (xy 67.359549 -142.278856) (xy 67.401954 -142.321261)
			(xy 67.43846 -142.368837) (xy 67.468444 -142.420771) (xy 67.491393 -142.476175) (xy 67.506914 -142.5341)
			(xy 67.514742 -142.593556) (xy 67.515232 -142.62354) (xy 67.515232 -143.479266) (xy 81.07426 -143.479266)
			(xy 81.07426 -142.615666) (xy 81.07475 -142.585682) (xy 81.082578 -142.526226) (xy 81.098099 -142.468301)
			(xy 81.121048 -142.412897) (xy 81.151032 -142.360963) (xy 81.187538 -142.313387) (xy 81.229943 -142.270982)
			(xy 81.277519 -142.234476) (xy 81.329453 -142.204492) (xy 81.384857 -142.181543) (xy 81.442782 -142.166022)
			(xy 81.502238 -142.158194) (xy 81.562206 -142.158194) (xy 81.621662 -142.166022) (xy 81.679587 -142.181543)
			(xy 81.734991 -142.204492) (xy 81.786925 -142.234476) (xy 81.834501 -142.270982) (xy 81.876906 -142.313387)
			(xy 81.913412 -142.360963) (xy 81.943396 -142.412897) (xy 81.966345 -142.468301) (xy 81.981866 -142.526226)
			(xy 81.989694 -142.585682) (xy 81.990184 -142.615666) (xy 81.990184 -143.479266) (xy 81.989694 -143.50925)
			(xy 81.981866 -143.568706) (xy 81.966345 -143.626631) (xy 81.943396 -143.682035) (xy 81.913412 -143.733969)
			(xy 81.876906 -143.781545) (xy 81.834501 -143.82395) (xy 81.786925 -143.860456) (xy 81.734991 -143.89044)
			(xy 81.679587 -143.913389) (xy 81.621662 -143.92891) (xy 81.562206 -143.936738) (xy 81.502238 -143.936738)
			(xy 81.442782 -143.92891) (xy 81.384857 -143.913389) (xy 81.329453 -143.89044) (xy 81.277519 -143.860456)
			(xy 81.229943 -143.82395) (xy 81.187538 -143.781545) (xy 81.151032 -143.733969) (xy 81.121048 -143.682035)
			(xy 81.098099 -143.626631) (xy 81.082578 -143.568706) (xy 81.07475 -143.50925) (xy 81.07426 -143.479266)
			(xy 67.515232 -143.479266) (xy 67.515232 -143.48714) (xy 67.514742 -143.517124) (xy 67.506914 -143.57658)
			(xy 67.491393 -143.634505) (xy 67.468444 -143.689909) (xy 67.43846 -143.741843) (xy 67.401954 -143.789419)
			(xy 67.359549 -143.831824) (xy 67.311973 -143.86833) (xy 67.260039 -143.898314) (xy 67.204635 -143.921263)
			(xy 67.14671 -143.936784) (xy 67.087254 -143.944612) (xy 67.027286 -143.944612) (xy 66.96783 -143.936784)
			(xy 66.909905 -143.921263) (xy 66.854501 -143.898314) (xy 66.802567 -143.86833) (xy 66.754991 -143.831824)
			(xy 66.712586 -143.789419) (xy 66.67608 -143.741843) (xy 66.646096 -143.689909) (xy 66.623147 -143.634505)
			(xy 66.607626 -143.57658) (xy 66.599798 -143.517124) (xy 66.599308 -143.48714) (xy 54.746144 -143.48714)
			(xy 54.746144 -144.272) (xy 56.386982 -144.272) (xy 56.391053 -144.216378) (xy 56.403179 -144.161941)
			(xy 56.423102 -144.10985) (xy 56.450398 -144.061215) (xy 56.484484 -144.017072) (xy 56.524633 -143.978363)
			(xy 56.569991 -143.945912) (xy 56.619591 -143.920411) (xy 56.672375 -143.902404) (xy 56.727218 -143.892274)
			(xy 56.782952 -143.890237) (xy 56.838389 -143.896337) (xy 56.892346 -143.910443) (xy 56.943675 -143.932255)
			(xy 56.991281 -143.961309) (xy 57.034149 -143.996984) (xy 57.071366 -144.038521) (xy 57.102139 -144.085034)
			(xy 57.125811 -144.135531) (xy 57.141879 -144.188938) (xy 57.149999 -144.244114) (xy 57.150508 -144.272)
			(xy 57.149999 -144.299886) (xy 57.141879 -144.355062) (xy 57.125811 -144.408469) (xy 57.102139 -144.458966)
			(xy 57.071366 -144.505479) (xy 57.034149 -144.547016) (xy 56.991281 -144.582691) (xy 56.943675 -144.611745)
			(xy 56.892346 -144.633557) (xy 56.838389 -144.647663) (xy 56.782952 -144.653763) (xy 56.727218 -144.651726)
			(xy 56.672375 -144.641596) (xy 56.619591 -144.623589) (xy 56.569991 -144.598088) (xy 56.524633 -144.565637)
			(xy 56.484484 -144.526928) (xy 56.450398 -144.482785) (xy 56.423102 -144.43415) (xy 56.403179 -144.382059)
			(xy 56.391053 -144.327622) (xy 56.386982 -144.272) (xy 54.746144 -144.272) (xy 54.746144 -145.287238)
			(xy 64.745108 -145.287238) (xy 64.745108 -144.423638) (xy 64.745598 -144.393654) (xy 64.753426 -144.334198)
			(xy 64.768947 -144.276273) (xy 64.791896 -144.220869) (xy 64.82188 -144.168935) (xy 64.858386 -144.121359)
			(xy 64.900791 -144.078954) (xy 64.948367 -144.042448) (xy 65.000301 -144.012464) (xy 65.055705 -143.989515)
			(xy 65.11363 -143.973994) (xy 65.173086 -143.966166) (xy 65.233054 -143.966166) (xy 65.29251 -143.973994)
			(xy 65.350435 -143.989515) (xy 65.405839 -144.012464) (xy 65.457773 -144.042448) (xy 65.505349 -144.078954)
			(xy 65.547754 -144.121359) (xy 65.58426 -144.168935) (xy 65.614244 -144.220869) (xy 65.637193 -144.276273)
			(xy 65.652714 -144.334198) (xy 65.660542 -144.393654) (xy 65.661032 -144.423638) (xy 65.661032 -145.285714)
			(xy 83.716368 -145.285714) (xy 83.716368 -144.422114) (xy 83.716858 -144.39213) (xy 83.724686 -144.332674)
			(xy 83.740207 -144.274749) (xy 83.763156 -144.219345) (xy 83.79314 -144.167411) (xy 83.829646 -144.119835)
			(xy 83.872051 -144.07743) (xy 83.919627 -144.040924) (xy 83.971561 -144.01094) (xy 84.026965 -143.987991)
			(xy 84.08489 -143.97247) (xy 84.144346 -143.964642) (xy 84.204314 -143.964642) (xy 84.26377 -143.97247)
			(xy 84.321695 -143.987991) (xy 84.377099 -144.01094) (xy 84.429033 -144.040924) (xy 84.476609 -144.07743)
			(xy 84.519014 -144.119835) (xy 84.55552 -144.167411) (xy 84.585504 -144.219345) (xy 84.608453 -144.274749)
			(xy 84.623974 -144.332674) (xy 84.631802 -144.39213) (xy 84.632292 -144.422114) (xy 84.632292 -145.285714)
			(xy 84.631802 -145.315698) (xy 84.623974 -145.375154) (xy 84.608453 -145.433079) (xy 84.585504 -145.488483)
			(xy 84.55552 -145.540417) (xy 84.519014 -145.587993) (xy 84.476609 -145.630398) (xy 84.429033 -145.666904)
			(xy 84.377099 -145.696888) (xy 84.321695 -145.719837) (xy 84.26377 -145.735358) (xy 84.204314 -145.743186)
			(xy 84.144346 -145.743186) (xy 84.08489 -145.735358) (xy 84.026965 -145.719837) (xy 83.971561 -145.696888)
			(xy 83.919627 -145.666904) (xy 83.872051 -145.630398) (xy 83.829646 -145.587993) (xy 83.79314 -145.540417)
			(xy 83.763156 -145.488483) (xy 83.740207 -145.433079) (xy 83.724686 -145.375154) (xy 83.716858 -145.315698)
			(xy 83.716368 -145.285714) (xy 65.661032 -145.285714) (xy 65.661032 -145.287238) (xy 65.660542 -145.317222)
			(xy 65.652714 -145.376678) (xy 65.637193 -145.434603) (xy 65.614244 -145.490007) (xy 65.58426 -145.541941)
			(xy 65.547754 -145.589517) (xy 65.505349 -145.631922) (xy 65.457773 -145.668428) (xy 65.405839 -145.698412)
			(xy 65.350435 -145.721361) (xy 65.29251 -145.736882) (xy 65.233054 -145.74471) (xy 65.173086 -145.74471)
			(xy 65.11363 -145.736882) (xy 65.055705 -145.721361) (xy 65.000301 -145.698412) (xy 64.948367 -145.668428)
			(xy 64.900791 -145.631922) (xy 64.858386 -145.589517) (xy 64.82188 -145.541941) (xy 64.791896 -145.490007)
			(xy 64.768947 -145.434603) (xy 64.753426 -145.376678) (xy 64.745598 -145.317222) (xy 64.745108 -145.287238)
			(xy 54.746144 -145.287238) (xy 54.746144 -147.087336) (xy 66.599308 -147.087336) (xy 66.599308 -146.223736)
			(xy 66.599798 -146.193752) (xy 66.607626 -146.134296) (xy 66.623147 -146.076371) (xy 66.646096 -146.020967)
			(xy 66.67608 -145.969033) (xy 66.712586 -145.921457) (xy 66.754991 -145.879052) (xy 66.802567 -145.842546)
			(xy 66.854501 -145.812562) (xy 66.909905 -145.789613) (xy 66.96783 -145.774092) (xy 67.027286 -145.766264)
			(xy 67.087254 -145.766264) (xy 67.14671 -145.774092) (xy 67.204635 -145.789613) (xy 67.260039 -145.812562)
			(xy 67.311973 -145.842546) (xy 67.359549 -145.879052) (xy 67.401954 -145.921457) (xy 67.43846 -145.969033)
			(xy 67.468444 -146.020967) (xy 67.491393 -146.076371) (xy 67.506914 -146.134296) (xy 67.514742 -146.193752)
			(xy 67.515232 -146.223736) (xy 67.515232 -147.079208) (xy 81.07426 -147.079208) (xy 81.07426 -146.215608)
			(xy 81.07475 -146.185624) (xy 81.082578 -146.126168) (xy 81.098099 -146.068243) (xy 81.121048 -146.012839)
			(xy 81.151032 -145.960905) (xy 81.187538 -145.913329) (xy 81.229943 -145.870924) (xy 81.277519 -145.834418)
			(xy 81.329453 -145.804434) (xy 81.384857 -145.781485) (xy 81.442782 -145.765964) (xy 81.502238 -145.758136)
			(xy 81.562206 -145.758136) (xy 81.621662 -145.765964) (xy 81.679587 -145.781485) (xy 81.734991 -145.804434)
			(xy 81.786925 -145.834418) (xy 81.834501 -145.870924) (xy 81.876906 -145.913329) (xy 81.913412 -145.960905)
			(xy 81.943396 -146.012839) (xy 81.966345 -146.068243) (xy 81.981866 -146.126168) (xy 81.989694 -146.185624)
			(xy 81.990184 -146.215608) (xy 81.990184 -147.079208) (xy 81.989694 -147.109192) (xy 81.981866 -147.168648)
			(xy 81.966345 -147.226573) (xy 81.943396 -147.281977) (xy 81.913412 -147.333911) (xy 81.876906 -147.381487)
			(xy 81.834501 -147.423892) (xy 81.786925 -147.460398) (xy 81.734991 -147.490382) (xy 81.679587 -147.513331)
			(xy 81.621662 -147.528852) (xy 81.562206 -147.53668) (xy 81.502238 -147.53668) (xy 81.442782 -147.528852)
			(xy 81.384857 -147.513331) (xy 81.329453 -147.490382) (xy 81.277519 -147.460398) (xy 81.229943 -147.423892)
			(xy 81.187538 -147.381487) (xy 81.151032 -147.333911) (xy 81.121048 -147.281977) (xy 81.098099 -147.226573)
			(xy 81.082578 -147.168648) (xy 81.07475 -147.109192) (xy 81.07426 -147.079208) (xy 67.515232 -147.079208)
			(xy 67.515232 -147.087336) (xy 67.514742 -147.11732) (xy 67.506914 -147.176776) (xy 67.491393 -147.234701)
			(xy 67.468444 -147.290105) (xy 67.43846 -147.342039) (xy 67.401954 -147.389615) (xy 67.359549 -147.43202)
			(xy 67.311973 -147.468526) (xy 67.260039 -147.49851) (xy 67.204635 -147.521459) (xy 67.14671 -147.53698)
			(xy 67.087254 -147.544808) (xy 67.027286 -147.544808) (xy 66.96783 -147.53698) (xy 66.909905 -147.521459)
			(xy 66.854501 -147.49851) (xy 66.802567 -147.468526) (xy 66.754991 -147.43202) (xy 66.712586 -147.389615)
			(xy 66.67608 -147.342039) (xy 66.646096 -147.290105) (xy 66.623147 -147.234701) (xy 66.607626 -147.176776)
			(xy 66.599798 -147.11732) (xy 66.599308 -147.087336) (xy 54.746144 -147.087336) (xy 54.746144 -148.887434)
			(xy 64.745108 -148.887434) (xy 64.745108 -148.023834) (xy 64.745598 -147.99385) (xy 64.753426 -147.934394)
			(xy 64.768947 -147.876469) (xy 64.791896 -147.821065) (xy 64.82188 -147.769131) (xy 64.858386 -147.721555)
			(xy 64.900791 -147.67915) (xy 64.948367 -147.642644) (xy 65.000301 -147.61266) (xy 65.055705 -147.589711)
			(xy 65.11363 -147.57419) (xy 65.173086 -147.566362) (xy 65.233054 -147.566362) (xy 65.29251 -147.57419)
			(xy 65.350435 -147.589711) (xy 65.405839 -147.61266) (xy 65.457773 -147.642644) (xy 65.505349 -147.67915)
			(xy 65.547754 -147.721555) (xy 65.58426 -147.769131) (xy 65.614244 -147.821065) (xy 65.637193 -147.876469)
			(xy 65.652714 -147.934394) (xy 65.660542 -147.99385) (xy 65.661032 -148.023834) (xy 65.661032 -148.88591)
			(xy 83.716368 -148.88591) (xy 83.716368 -148.02231) (xy 83.716858 -147.992326) (xy 83.724686 -147.93287)
			(xy 83.740207 -147.874945) (xy 83.763156 -147.819541) (xy 83.79314 -147.767607) (xy 83.829646 -147.720031)
			(xy 83.872051 -147.677626) (xy 83.919627 -147.64112) (xy 83.971561 -147.611136) (xy 84.026965 -147.588187)
			(xy 84.08489 -147.572666) (xy 84.144346 -147.564838) (xy 84.204314 -147.564838) (xy 84.26377 -147.572666)
			(xy 84.321695 -147.588187) (xy 84.377099 -147.611136) (xy 84.429033 -147.64112) (xy 84.476609 -147.677626)
			(xy 84.519014 -147.720031) (xy 84.55552 -147.767607) (xy 84.585504 -147.819541) (xy 84.608453 -147.874945)
			(xy 84.623974 -147.93287) (xy 84.631802 -147.992326) (xy 84.632292 -148.02231) (xy 84.632292 -148.88591)
			(xy 84.631802 -148.915894) (xy 84.623974 -148.97535) (xy 84.608453 -149.033275) (xy 84.585504 -149.088679)
			(xy 84.55552 -149.140613) (xy 84.519014 -149.188189) (xy 84.476609 -149.230594) (xy 84.429033 -149.2671)
			(xy 84.377099 -149.297084) (xy 84.321695 -149.320033) (xy 84.26377 -149.335554) (xy 84.204314 -149.343382)
			(xy 84.144346 -149.343382) (xy 84.08489 -149.335554) (xy 84.026965 -149.320033) (xy 83.971561 -149.297084)
			(xy 83.919627 -149.2671) (xy 83.872051 -149.230594) (xy 83.829646 -149.188189) (xy 83.79314 -149.140613)
			(xy 83.763156 -149.088679) (xy 83.740207 -149.033275) (xy 83.724686 -148.97535) (xy 83.716858 -148.915894)
			(xy 83.716368 -148.88591) (xy 65.661032 -148.88591) (xy 65.661032 -148.887434) (xy 65.660542 -148.917418)
			(xy 65.652714 -148.976874) (xy 65.637193 -149.034799) (xy 65.614244 -149.090203) (xy 65.58426 -149.142137)
			(xy 65.547754 -149.189713) (xy 65.505349 -149.232118) (xy 65.457773 -149.268624) (xy 65.405839 -149.298608)
			(xy 65.350435 -149.321557) (xy 65.29251 -149.337078) (xy 65.233054 -149.344906) (xy 65.173086 -149.344906)
			(xy 65.11363 -149.337078) (xy 65.055705 -149.321557) (xy 65.000301 -149.298608) (xy 64.948367 -149.268624)
			(xy 64.900791 -149.232118) (xy 64.858386 -149.189713) (xy 64.82188 -149.142137) (xy 64.791896 -149.090203)
			(xy 64.768947 -149.034799) (xy 64.753426 -148.976874) (xy 64.745598 -148.917418) (xy 64.745108 -148.887434)
			(xy 54.746144 -148.887434) (xy 54.746144 -150.08733) (xy 56.079388 -150.08733) (xy 56.083459 -150.031708)
			(xy 56.095585 -149.977271) (xy 56.115508 -149.92518) (xy 56.142804 -149.876545) (xy 56.17689 -149.832402)
			(xy 56.217039 -149.793693) (xy 56.262397 -149.761242) (xy 56.311997 -149.735741) (xy 56.364781 -149.717734)
			(xy 56.419624 -149.707604) (xy 56.475358 -149.705567) (xy 56.530795 -149.711667) (xy 56.584752 -149.725773)
			(xy 56.636081 -149.747585) (xy 56.683687 -149.776639) (xy 56.726555 -149.812314) (xy 56.763772 -149.853851)
			(xy 56.794545 -149.900364) (xy 56.818217 -149.950861) (xy 56.834285 -150.004268) (xy 56.842405 -150.059444)
			(xy 56.842914 -150.08733) (xy 56.842405 -150.115216) (xy 56.834285 -150.170392) (xy 56.818217 -150.223799)
			(xy 56.794545 -150.274296) (xy 56.763772 -150.320809) (xy 56.726555 -150.362346) (xy 56.683687 -150.398021)
			(xy 56.636081 -150.427075) (xy 56.584752 -150.448887) (xy 56.530795 -150.462993) (xy 56.475358 -150.469093)
			(xy 56.419624 -150.467056) (xy 56.364781 -150.456926) (xy 56.311997 -150.438919) (xy 56.262397 -150.413418)
			(xy 56.217039 -150.380967) (xy 56.17689 -150.342258) (xy 56.142804 -150.298115) (xy 56.115508 -150.24948)
			(xy 56.095585 -150.197389) (xy 56.083459 -150.142952) (xy 56.079388 -150.08733) (xy 54.746144 -150.08733)
			(xy 54.746144 -150.687278) (xy 66.599308 -150.687278) (xy 66.599308 -149.823678) (xy 66.599798 -149.793694)
			(xy 66.607626 -149.734238) (xy 66.623147 -149.676313) (xy 66.646096 -149.620909) (xy 66.67608 -149.568975)
			(xy 66.712586 -149.521399) (xy 66.754991 -149.478994) (xy 66.802567 -149.442488) (xy 66.854501 -149.412504)
			(xy 66.909905 -149.389555) (xy 66.96783 -149.374034) (xy 67.027286 -149.366206) (xy 67.087254 -149.366206)
			(xy 67.14671 -149.374034) (xy 67.204635 -149.389555) (xy 67.260039 -149.412504) (xy 67.311973 -149.442488)
			(xy 67.359549 -149.478994) (xy 67.401954 -149.521399) (xy 67.43846 -149.568975) (xy 67.468444 -149.620909)
			(xy 67.491393 -149.676313) (xy 67.506914 -149.734238) (xy 67.514742 -149.793694) (xy 67.515232 -149.823678)
			(xy 67.515232 -150.67915) (xy 81.07426 -150.67915) (xy 81.07426 -149.81555) (xy 81.07475 -149.785566)
			(xy 81.082578 -149.72611) (xy 81.098099 -149.668185) (xy 81.121048 -149.612781) (xy 81.151032 -149.560847)
			(xy 81.187538 -149.513271) (xy 81.229943 -149.470866) (xy 81.277519 -149.43436) (xy 81.329453 -149.404376)
			(xy 81.384857 -149.381427) (xy 81.442782 -149.365906) (xy 81.502238 -149.358078) (xy 81.562206 -149.358078)
			(xy 81.621662 -149.365906) (xy 81.679587 -149.381427) (xy 81.734991 -149.404376) (xy 81.786925 -149.43436)
			(xy 81.834501 -149.470866) (xy 81.876906 -149.513271) (xy 81.913412 -149.560847) (xy 81.943396 -149.612781)
			(xy 81.966345 -149.668185) (xy 81.981866 -149.72611) (xy 81.989694 -149.785566) (xy 81.990184 -149.81555)
			(xy 81.990184 -150.67915) (xy 81.989694 -150.709134) (xy 81.981866 -150.76859) (xy 81.966345 -150.826515)
			(xy 81.943396 -150.881919) (xy 81.913412 -150.933853) (xy 81.876906 -150.981429) (xy 81.834501 -151.023834)
			(xy 81.786925 -151.06034) (xy 81.734991 -151.090324) (xy 81.679587 -151.113273) (xy 81.621662 -151.128794)
			(xy 81.562206 -151.136622) (xy 81.502238 -151.136622) (xy 81.442782 -151.128794) (xy 81.384857 -151.113273)
			(xy 81.329453 -151.090324) (xy 81.277519 -151.06034) (xy 81.229943 -151.023834) (xy 81.187538 -150.981429)
			(xy 81.151032 -150.933853) (xy 81.121048 -150.881919) (xy 81.098099 -150.826515) (xy 81.082578 -150.76859)
			(xy 81.07475 -150.709134) (xy 81.07426 -150.67915) (xy 67.515232 -150.67915) (xy 67.515232 -150.687278)
			(xy 67.514742 -150.717262) (xy 67.506914 -150.776718) (xy 67.491393 -150.834643) (xy 67.468444 -150.890047)
			(xy 67.43846 -150.941981) (xy 67.401954 -150.989557) (xy 67.359549 -151.031962) (xy 67.311973 -151.068468)
			(xy 67.260039 -151.098452) (xy 67.204635 -151.121401) (xy 67.14671 -151.136922) (xy 67.087254 -151.14475)
			(xy 67.027286 -151.14475) (xy 66.96783 -151.136922) (xy 66.909905 -151.121401) (xy 66.854501 -151.098452)
			(xy 66.802567 -151.068468) (xy 66.754991 -151.031962) (xy 66.712586 -150.989557) (xy 66.67608 -150.941981)
			(xy 66.646096 -150.890047) (xy 66.623147 -150.834643) (xy 66.607626 -150.776718) (xy 66.599798 -150.717262)
			(xy 66.599308 -150.687278) (xy 54.746144 -150.687278) (xy 54.746144 -151.125428) (xy 55.928004 -151.125428)
			(xy 55.932075 -151.069806) (xy 55.944201 -151.015369) (xy 55.964124 -150.963278) (xy 55.99142 -150.914643)
			(xy 56.025506 -150.8705) (xy 56.065655 -150.831791) (xy 56.111013 -150.79934) (xy 56.160613 -150.773839)
			(xy 56.213397 -150.755832) (xy 56.26824 -150.745702) (xy 56.323974 -150.743665) (xy 56.379411 -150.749765)
			(xy 56.433368 -150.763871) (xy 56.484697 -150.785683) (xy 56.532303 -150.814737) (xy 56.575171 -150.850412)
			(xy 56.612388 -150.891949) (xy 56.643161 -150.938462) (xy 56.666833 -150.988959) (xy 56.682901 -151.042366)
			(xy 56.691021 -151.097542) (xy 56.69153 -151.125428) (xy 56.691021 -151.153314) (xy 56.682901 -151.20849)
			(xy 56.666833 -151.261897) (xy 56.643161 -151.312394) (xy 56.612388 -151.358907) (xy 56.575171 -151.400444)
			(xy 56.532303 -151.436119) (xy 56.484697 -151.465173) (xy 56.433368 -151.486985) (xy 56.379411 -151.501091)
			(xy 56.323974 -151.507191) (xy 56.26824 -151.505154) (xy 56.213397 -151.495024) (xy 56.160613 -151.477017)
			(xy 56.111013 -151.451516) (xy 56.065655 -151.419065) (xy 56.025506 -151.380356) (xy 55.99142 -151.336213)
			(xy 55.964124 -151.287578) (xy 55.944201 -151.235487) (xy 55.932075 -151.18105) (xy 55.928004 -151.125428)
			(xy 54.746144 -151.125428) (xy 54.746144 -152.487376) (xy 64.745108 -152.487376) (xy 64.745108 -151.623776)
			(xy 64.745598 -151.593792) (xy 64.753426 -151.534336) (xy 64.768947 -151.476411) (xy 64.791896 -151.421007)
			(xy 64.82188 -151.369073) (xy 64.858386 -151.321497) (xy 64.900791 -151.279092) (xy 64.948367 -151.242586)
			(xy 65.000301 -151.212602) (xy 65.055705 -151.189653) (xy 65.11363 -151.174132) (xy 65.173086 -151.166304)
			(xy 65.233054 -151.166304) (xy 65.29251 -151.174132) (xy 65.350435 -151.189653) (xy 65.405839 -151.212602)
			(xy 65.457773 -151.242586) (xy 65.505349 -151.279092) (xy 65.547754 -151.321497) (xy 65.58426 -151.369073)
			(xy 65.614244 -151.421007) (xy 65.637193 -151.476411) (xy 65.652714 -151.534336) (xy 65.660542 -151.593792)
			(xy 65.661032 -151.623776) (xy 65.661032 -152.485852) (xy 83.716368 -152.485852) (xy 83.716368 -151.622252)
			(xy 83.716858 -151.592268) (xy 83.724686 -151.532812) (xy 83.740207 -151.474887) (xy 83.763156 -151.419483)
			(xy 83.79314 -151.367549) (xy 83.829646 -151.319973) (xy 83.872051 -151.277568) (xy 83.919627 -151.241062)
			(xy 83.971561 -151.211078) (xy 84.026965 -151.188129) (xy 84.08489 -151.172608) (xy 84.144346 -151.16478)
			(xy 84.204314 -151.16478) (xy 84.26377 -151.172608) (xy 84.321695 -151.188129) (xy 84.377099 -151.211078)
			(xy 84.429033 -151.241062) (xy 84.476609 -151.277568) (xy 84.519014 -151.319973) (xy 84.55552 -151.367549)
			(xy 84.585504 -151.419483) (xy 84.608453 -151.474887) (xy 84.623974 -151.532812) (xy 84.631802 -151.592268)
			(xy 84.632292 -151.622252) (xy 84.632292 -152.485852) (xy 84.631802 -152.515836) (xy 84.623974 -152.575292)
			(xy 84.608453 -152.633217) (xy 84.585504 -152.688621) (xy 84.55552 -152.740555) (xy 84.519014 -152.788131)
			(xy 84.476609 -152.830536) (xy 84.429033 -152.867042) (xy 84.377099 -152.897026) (xy 84.321695 -152.919975)
			(xy 84.26377 -152.935496) (xy 84.204314 -152.943324) (xy 84.144346 -152.943324) (xy 84.08489 -152.935496)
			(xy 84.026965 -152.919975) (xy 83.971561 -152.897026) (xy 83.919627 -152.867042) (xy 83.872051 -152.830536)
			(xy 83.829646 -152.788131) (xy 83.79314 -152.740555) (xy 83.763156 -152.688621) (xy 83.740207 -152.633217)
			(xy 83.724686 -152.575292) (xy 83.716858 -152.515836) (xy 83.716368 -152.485852) (xy 65.661032 -152.485852)
			(xy 65.661032 -152.487376) (xy 65.660542 -152.51736) (xy 65.652714 -152.576816) (xy 65.637193 -152.634741)
			(xy 65.614244 -152.690145) (xy 65.58426 -152.742079) (xy 65.547754 -152.789655) (xy 65.505349 -152.83206)
			(xy 65.457773 -152.868566) (xy 65.405839 -152.89855) (xy 65.350435 -152.921499) (xy 65.29251 -152.93702)
			(xy 65.233054 -152.944848) (xy 65.173086 -152.944848) (xy 65.11363 -152.93702) (xy 65.055705 -152.921499)
			(xy 65.000301 -152.89855) (xy 64.948367 -152.868566) (xy 64.900791 -152.83206) (xy 64.858386 -152.789655)
			(xy 64.82188 -152.742079) (xy 64.791896 -152.690145) (xy 64.768947 -152.634741) (xy 64.753426 -152.576816)
			(xy 64.745598 -152.51736) (xy 64.745108 -152.487376) (xy 54.746144 -152.487376) (xy 54.746144 -153.083006)
			(xy 62.492126 -153.083006) (xy 62.496197 -153.027384) (xy 62.508323 -152.972947) (xy 62.528246 -152.920856)
			(xy 62.555542 -152.872221) (xy 62.589628 -152.828078) (xy 62.629777 -152.789369) (xy 62.675135 -152.756918)
			(xy 62.724735 -152.731417) (xy 62.777519 -152.71341) (xy 62.832362 -152.70328) (xy 62.888096 -152.701243)
			(xy 62.943533 -152.707343) (xy 62.99749 -152.721449) (xy 63.048819 -152.743261) (xy 63.096425 -152.772315)
			(xy 63.139293 -152.80799) (xy 63.17651 -152.849527) (xy 63.207283 -152.89604) (xy 63.230955 -152.946537)
			(xy 63.247023 -152.999944) (xy 63.255143 -153.05512) (xy 63.255652 -153.083006) (xy 63.255143 -153.110892)
			(xy 63.247023 -153.166068) (xy 63.230955 -153.219475) (xy 63.207283 -153.269972) (xy 63.17651 -153.316485)
			(xy 63.139293 -153.358022) (xy 63.096425 -153.393697) (xy 63.048819 -153.422751) (xy 62.99749 -153.444563)
			(xy 62.943533 -153.458669) (xy 62.888096 -153.464769) (xy 62.832362 -153.462732) (xy 62.777519 -153.452602)
			(xy 62.724735 -153.434595) (xy 62.675135 -153.409094) (xy 62.629777 -153.376643) (xy 62.589628 -153.337934)
			(xy 62.555542 -153.293791) (xy 62.528246 -153.245156) (xy 62.508323 -153.193065) (xy 62.496197 -153.138628)
			(xy 62.492126 -153.083006) (xy 54.746144 -153.083006) (xy 54.746144 -154.28722) (xy 66.599308 -154.28722)
			(xy 66.599308 -153.42362) (xy 66.599798 -153.393636) (xy 66.607626 -153.33418) (xy 66.623147 -153.276255)
			(xy 66.646096 -153.220851) (xy 66.67608 -153.168917) (xy 66.712586 -153.121341) (xy 66.754991 -153.078936)
			(xy 66.802567 -153.04243) (xy 66.854501 -153.012446) (xy 66.909905 -152.989497) (xy 66.96783 -152.973976)
			(xy 67.027286 -152.966148) (xy 67.087254 -152.966148) (xy 67.14671 -152.973976) (xy 67.204635 -152.989497)
			(xy 67.260039 -153.012446) (xy 67.311973 -153.04243) (xy 67.359549 -153.078936) (xy 67.401954 -153.121341)
			(xy 67.43846 -153.168917) (xy 67.468444 -153.220851) (xy 67.491393 -153.276255) (xy 67.506914 -153.33418)
			(xy 67.514742 -153.393636) (xy 67.515232 -153.42362) (xy 67.515232 -154.279346) (xy 81.07426 -154.279346)
			(xy 81.07426 -153.415746) (xy 81.07475 -153.385762) (xy 81.082578 -153.326306) (xy 81.098099 -153.268381)
			(xy 81.121048 -153.212977) (xy 81.151032 -153.161043) (xy 81.187538 -153.113467) (xy 81.229943 -153.071062)
			(xy 81.277519 -153.034556) (xy 81.329453 -153.004572) (xy 81.384857 -152.981623) (xy 81.442782 -152.966102)
			(xy 81.502238 -152.958274) (xy 81.562206 -152.958274) (xy 81.621662 -152.966102) (xy 81.679587 -152.981623)
			(xy 81.734991 -153.004572) (xy 81.786925 -153.034556) (xy 81.834501 -153.071062) (xy 81.876906 -153.113467)
			(xy 81.913412 -153.161043) (xy 81.943396 -153.212977) (xy 81.966345 -153.268381) (xy 81.981866 -153.326306)
			(xy 81.989694 -153.385762) (xy 81.990184 -153.415746) (xy 81.990184 -154.279346) (xy 81.989694 -154.30933)
			(xy 81.981866 -154.368786) (xy 81.966345 -154.426711) (xy 81.943396 -154.482115) (xy 81.913412 -154.534049)
			(xy 81.876906 -154.581625) (xy 81.834501 -154.62403) (xy 81.786925 -154.660536) (xy 81.734991 -154.69052)
			(xy 81.679587 -154.713469) (xy 81.621662 -154.72899) (xy 81.562206 -154.736818) (xy 81.502238 -154.736818)
			(xy 81.442782 -154.72899) (xy 81.384857 -154.713469) (xy 81.329453 -154.69052) (xy 81.277519 -154.660536)
			(xy 81.229943 -154.62403) (xy 81.187538 -154.581625) (xy 81.151032 -154.534049) (xy 81.121048 -154.482115)
			(xy 81.098099 -154.426711) (xy 81.082578 -154.368786) (xy 81.07475 -154.30933) (xy 81.07426 -154.279346)
			(xy 67.515232 -154.279346) (xy 67.515232 -154.28722) (xy 67.514742 -154.317204) (xy 67.506914 -154.37666)
			(xy 67.491393 -154.434585) (xy 67.468444 -154.489989) (xy 67.43846 -154.541923) (xy 67.401954 -154.589499)
			(xy 67.359549 -154.631904) (xy 67.311973 -154.66841) (xy 67.260039 -154.698394) (xy 67.204635 -154.721343)
			(xy 67.14671 -154.736864) (xy 67.087254 -154.744692) (xy 67.027286 -154.744692) (xy 66.96783 -154.736864)
			(xy 66.909905 -154.721343) (xy 66.854501 -154.698394) (xy 66.802567 -154.66841) (xy 66.754991 -154.631904)
			(xy 66.712586 -154.589499) (xy 66.67608 -154.541923) (xy 66.646096 -154.489989) (xy 66.623147 -154.434585)
			(xy 66.607626 -154.37666) (xy 66.599798 -154.317204) (xy 66.599308 -154.28722) (xy 54.746144 -154.28722)
			(xy 54.746144 -156.087318) (xy 64.745108 -156.087318) (xy 64.745108 -155.223718) (xy 64.745598 -155.193734)
			(xy 64.753426 -155.134278) (xy 64.768947 -155.076353) (xy 64.791896 -155.020949) (xy 64.82188 -154.969015)
			(xy 64.858386 -154.921439) (xy 64.900791 -154.879034) (xy 64.948367 -154.842528) (xy 65.000301 -154.812544)
			(xy 65.055705 -154.789595) (xy 65.11363 -154.774074) (xy 65.173086 -154.766246) (xy 65.233054 -154.766246)
			(xy 65.29251 -154.774074) (xy 65.350435 -154.789595) (xy 65.405839 -154.812544) (xy 65.457773 -154.842528)
			(xy 65.505349 -154.879034) (xy 65.547754 -154.921439) (xy 65.58426 -154.969015) (xy 65.614244 -155.020949)
			(xy 65.637193 -155.076353) (xy 65.652714 -155.134278) (xy 65.660542 -155.193734) (xy 65.661032 -155.223718)
			(xy 65.661032 -156.085794) (xy 83.716368 -156.085794) (xy 83.716368 -155.222194) (xy 83.716858 -155.19221)
			(xy 83.724686 -155.132754) (xy 83.740207 -155.074829) (xy 83.763156 -155.019425) (xy 83.79314 -154.967491)
			(xy 83.829646 -154.919915) (xy 83.872051 -154.87751) (xy 83.919627 -154.841004) (xy 83.971561 -154.81102)
			(xy 84.026965 -154.788071) (xy 84.08489 -154.77255) (xy 84.144346 -154.764722) (xy 84.204314 -154.764722)
			(xy 84.26377 -154.77255) (xy 84.321695 -154.788071) (xy 84.377099 -154.81102) (xy 84.429033 -154.841004)
			(xy 84.476609 -154.87751) (xy 84.519014 -154.919915) (xy 84.55552 -154.967491) (xy 84.585504 -155.019425)
			(xy 84.608453 -155.074829) (xy 84.623974 -155.132754) (xy 84.631802 -155.19221) (xy 84.632292 -155.222194)
			(xy 84.632292 -156.085794) (xy 84.631802 -156.115778) (xy 84.623974 -156.175234) (xy 84.608453 -156.233159)
			(xy 84.585504 -156.288563) (xy 84.55552 -156.340497) (xy 84.519014 -156.388073) (xy 84.476609 -156.430478)
			(xy 84.429033 -156.466984) (xy 84.377099 -156.496968) (xy 84.321695 -156.519917) (xy 84.26377 -156.535438)
			(xy 84.204314 -156.543266) (xy 84.144346 -156.543266) (xy 84.08489 -156.535438) (xy 84.026965 -156.519917)
			(xy 83.971561 -156.496968) (xy 83.919627 -156.466984) (xy 83.872051 -156.430478) (xy 83.829646 -156.388073)
			(xy 83.79314 -156.340497) (xy 83.763156 -156.288563) (xy 83.740207 -156.233159) (xy 83.724686 -156.175234)
			(xy 83.716858 -156.115778) (xy 83.716368 -156.085794) (xy 65.661032 -156.085794) (xy 65.661032 -156.087318)
			(xy 65.660542 -156.117302) (xy 65.652714 -156.176758) (xy 65.637193 -156.234683) (xy 65.614244 -156.290087)
			(xy 65.58426 -156.342021) (xy 65.547754 -156.389597) (xy 65.505349 -156.432002) (xy 65.457773 -156.468508)
			(xy 65.405839 -156.498492) (xy 65.350435 -156.521441) (xy 65.29251 -156.536962) (xy 65.233054 -156.54479)
			(xy 65.173086 -156.54479) (xy 65.11363 -156.536962) (xy 65.055705 -156.521441) (xy 65.000301 -156.498492)
			(xy 64.948367 -156.468508) (xy 64.900791 -156.432002) (xy 64.858386 -156.389597) (xy 64.82188 -156.342021)
			(xy 64.791896 -156.290087) (xy 64.768947 -156.234683) (xy 64.753426 -156.176758) (xy 64.745598 -156.117302)
			(xy 64.745108 -156.087318) (xy 54.746144 -156.087318) (xy 54.746144 -156.95422) (xy 55.582564 -156.95422)
			(xy 55.586635 -156.898598) (xy 55.598761 -156.844161) (xy 55.618684 -156.79207) (xy 55.64598 -156.743435)
			(xy 55.680066 -156.699292) (xy 55.720215 -156.660583) (xy 55.765573 -156.628132) (xy 55.815173 -156.602631)
			(xy 55.867957 -156.584624) (xy 55.9228 -156.574494) (xy 55.978534 -156.572457) (xy 56.033971 -156.578557)
			(xy 56.087928 -156.592663) (xy 56.139257 -156.614475) (xy 56.186863 -156.643529) (xy 56.229731 -156.679204)
			(xy 56.266948 -156.720741) (xy 56.297721 -156.767254) (xy 56.321393 -156.817751) (xy 56.337461 -156.871158)
			(xy 56.345581 -156.926334) (xy 56.34609 -156.95422) (xy 56.345581 -156.982106) (xy 56.337461 -157.037282)
			(xy 56.335093 -157.045152) (xy 61.410594 -157.045152) (xy 61.414665 -156.98953) (xy 61.426791 -156.935093)
			(xy 61.446714 -156.883002) (xy 61.47401 -156.834367) (xy 61.508096 -156.790224) (xy 61.548245 -156.751515)
			(xy 61.593603 -156.719064) (xy 61.643203 -156.693563) (xy 61.695987 -156.675556) (xy 61.75083 -156.665426)
			(xy 61.806564 -156.663389) (xy 61.862001 -156.669489) (xy 61.915958 -156.683595) (xy 61.967287 -156.705407)
			(xy 62.014893 -156.734461) (xy 62.057761 -156.770136) (xy 62.094978 -156.811673) (xy 62.125751 -156.858186)
			(xy 62.149423 -156.908683) (xy 62.165491 -156.96209) (xy 62.173611 -157.017266) (xy 62.17412 -157.045152)
			(xy 62.426594 -157.045152) (xy 62.430665 -156.98953) (xy 62.442791 -156.935093) (xy 62.462714 -156.883002)
			(xy 62.49001 -156.834367) (xy 62.524096 -156.790224) (xy 62.564245 -156.751515) (xy 62.609603 -156.719064)
			(xy 62.659203 -156.693563) (xy 62.711987 -156.675556) (xy 62.76683 -156.665426) (xy 62.822564 -156.663389)
			(xy 62.878001 -156.669489) (xy 62.931958 -156.683595) (xy 62.983287 -156.705407) (xy 63.030893 -156.734461)
			(xy 63.073761 -156.770136) (xy 63.110978 -156.811673) (xy 63.141751 -156.858186) (xy 63.165423 -156.908683)
			(xy 63.181491 -156.96209) (xy 63.189611 -157.017266) (xy 63.19012 -157.045152) (xy 63.189611 -157.073038)
			(xy 63.181491 -157.128214) (xy 63.165423 -157.181621) (xy 63.141751 -157.232118) (xy 63.110978 -157.278631)
			(xy 63.073761 -157.320168) (xy 63.030893 -157.355843) (xy 62.983287 -157.384897) (xy 62.931958 -157.406709)
			(xy 62.878001 -157.420815) (xy 62.822564 -157.426915) (xy 62.76683 -157.424878) (xy 62.711987 -157.414748)
			(xy 62.659203 -157.396741) (xy 62.609603 -157.37124) (xy 62.564245 -157.338789) (xy 62.524096 -157.30008)
			(xy 62.49001 -157.255937) (xy 62.462714 -157.207302) (xy 62.442791 -157.155211) (xy 62.430665 -157.100774)
			(xy 62.426594 -157.045152) (xy 62.17412 -157.045152) (xy 62.173611 -157.073038) (xy 62.165491 -157.128214)
			(xy 62.149423 -157.181621) (xy 62.125751 -157.232118) (xy 62.094978 -157.278631) (xy 62.057761 -157.320168)
			(xy 62.014893 -157.355843) (xy 61.967287 -157.384897) (xy 61.915958 -157.406709) (xy 61.862001 -157.420815)
			(xy 61.806564 -157.426915) (xy 61.75083 -157.424878) (xy 61.695987 -157.414748) (xy 61.643203 -157.396741)
			(xy 61.593603 -157.37124) (xy 61.548245 -157.338789) (xy 61.508096 -157.30008) (xy 61.47401 -157.255937)
			(xy 61.446714 -157.207302) (xy 61.426791 -157.155211) (xy 61.414665 -157.100774) (xy 61.410594 -157.045152)
			(xy 56.335093 -157.045152) (xy 56.321393 -157.090689) (xy 56.297721 -157.141186) (xy 56.266948 -157.187699)
			(xy 56.229731 -157.229236) (xy 56.186863 -157.264911) (xy 56.139257 -157.293965) (xy 56.087928 -157.315777)
			(xy 56.033971 -157.329883) (xy 55.978534 -157.335983) (xy 55.9228 -157.333946) (xy 55.867957 -157.323816)
			(xy 55.815173 -157.305809) (xy 55.765573 -157.280308) (xy 55.720215 -157.247857) (xy 55.680066 -157.209148)
			(xy 55.64598 -157.165005) (xy 55.618684 -157.11637) (xy 55.598761 -157.064279) (xy 55.586635 -157.009842)
			(xy 55.582564 -156.95422) (xy 54.746144 -156.95422) (xy 54.746144 -158.219648) (xy 81.182208 -158.219648)
			(xy 81.186279 -158.164026) (xy 81.198405 -158.109589) (xy 81.218328 -158.057498) (xy 81.245624 -158.008863)
			(xy 81.27971 -157.96472) (xy 81.319859 -157.926011) (xy 81.365217 -157.89356) (xy 81.414817 -157.868059)
			(xy 81.467601 -157.850052) (xy 81.522444 -157.839922) (xy 81.578178 -157.837885) (xy 81.633615 -157.843985)
			(xy 81.687572 -157.858091) (xy 81.738901 -157.879903) (xy 81.786507 -157.908957) (xy 81.829375 -157.944632)
			(xy 81.866592 -157.986169) (xy 81.897365 -158.032682) (xy 81.921037 -158.083179) (xy 81.937105 -158.136586)
			(xy 81.945225 -158.191762) (xy 81.945734 -158.219648) (xy 81.945225 -158.247534) (xy 81.937105 -158.30271)
			(xy 81.921037 -158.356117) (xy 81.897365 -158.406614) (xy 81.866592 -158.453127) (xy 81.829375 -158.494664)
			(xy 81.786507 -158.530339) (xy 81.738901 -158.559393) (xy 81.687572 -158.581205) (xy 81.633615 -158.595311)
			(xy 81.578178 -158.601411) (xy 81.522444 -158.599374) (xy 81.467601 -158.589244) (xy 81.414817 -158.571237)
			(xy 81.365217 -158.545736) (xy 81.319859 -158.513285) (xy 81.27971 -158.474576) (xy 81.245624 -158.430433)
			(xy 81.218328 -158.381798) (xy 81.198405 -158.329707) (xy 81.186279 -158.27527) (xy 81.182208 -158.219648)
			(xy 54.746144 -158.219648) (xy 54.746144 -159.956246) (xy 55.562752 -159.956246) (xy 55.566823 -159.900624)
			(xy 55.578949 -159.846187) (xy 55.598872 -159.794096) (xy 55.626168 -159.745461) (xy 55.660254 -159.701318)
			(xy 55.700403 -159.662609) (xy 55.745761 -159.630158) (xy 55.795361 -159.604657) (xy 55.848145 -159.58665)
			(xy 55.902988 -159.57652) (xy 55.958722 -159.574483) (xy 56.014159 -159.580583) (xy 56.068116 -159.594689)
			(xy 56.119445 -159.616501) (xy 56.167051 -159.645555) (xy 56.209919 -159.68123) (xy 56.247136 -159.722767)
			(xy 56.277909 -159.76928) (xy 56.301581 -159.819777) (xy 56.317649 -159.873184) (xy 56.325769 -159.92836)
			(xy 56.326278 -159.956246) (xy 56.325769 -159.984132) (xy 56.317649 -160.039308) (xy 56.301581 -160.092715)
			(xy 56.277909 -160.143212) (xy 56.250196 -160.1851) (xy 69.888875 -160.1851) (xy 69.892831 -160.093241)
			(xy 69.904668 -160.002062) (xy 69.9243 -159.912238) (xy 69.951581 -159.824435) (xy 69.986309 -159.739302)
			(xy 70.028227 -159.657469) (xy 70.077025 -159.579542) (xy 70.13234 -159.506099) (xy 70.193765 -159.437683)
			(xy 70.260844 -159.374801) (xy 70.333079 -159.317918) (xy 70.409938 -159.267455) (xy 70.49085 -159.223786)
			(xy 70.575216 -159.187234) (xy 70.662412 -159.15807) (xy 70.751793 -159.13651) (xy 70.842696 -159.122714)
			(xy 70.934449 -159.116782) (xy 71.026371 -159.118761) (xy 71.117784 -159.128634) (xy 71.208009 -159.146329)
			(xy 71.29638 -159.171714) (xy 71.38224 -159.204602) (xy 71.464956 -159.24475) (xy 71.543914 -159.291859)
			(xy 71.618531 -159.345582) (xy 71.688252 -159.40552) (xy 71.752563 -159.47123) (xy 71.810988 -159.542226)
			(xy 71.863093 -159.61798) (xy 71.908492 -159.697934) (xy 71.946851 -159.781494) (xy 71.977884 -159.868043)
			(xy 72.001362 -159.956939) (xy 72.017112 -160.047524) (xy 72.025016 -160.139128) (xy 72.02551 -160.1851)
			(xy 72.025016 -160.231072) (xy 72.017112 -160.322676) (xy 72.001362 -160.413261) (xy 71.977884 -160.502157)
			(xy 71.946851 -160.588706) (xy 71.908492 -160.672266) (xy 71.863093 -160.75222) (xy 71.810988 -160.827974)
			(xy 71.752563 -160.89897) (xy 71.688252 -160.96468) (xy 71.618531 -161.024618) (xy 71.543914 -161.078341)
			(xy 71.464956 -161.12545) (xy 71.38224 -161.165598) (xy 71.29638 -161.198486) (xy 71.208009 -161.223871)
			(xy 71.117784 -161.241566) (xy 71.026371 -161.251439) (xy 70.934449 -161.253418) (xy 70.842696 -161.247486)
			(xy 70.751793 -161.23369) (xy 70.662412 -161.21213) (xy 70.575216 -161.182966) (xy 70.49085 -161.146414)
			(xy 70.409938 -161.102745) (xy 70.333079 -161.052282) (xy 70.260844 -160.995399) (xy 70.193765 -160.932517)
			(xy 70.13234 -160.864101) (xy 70.077025 -160.790658) (xy 70.028227 -160.712731) (xy 69.986309 -160.630898)
			(xy 69.951581 -160.545765) (xy 69.9243 -160.457962) (xy 69.904668 -160.368138) (xy 69.892831 -160.276959)
			(xy 69.888875 -160.1851) (xy 56.250196 -160.1851) (xy 56.247136 -160.189725) (xy 56.209919 -160.231262)
			(xy 56.167051 -160.266937) (xy 56.119445 -160.295991) (xy 56.068116 -160.317803) (xy 56.014159 -160.331909)
			(xy 55.958722 -160.338009) (xy 55.902988 -160.335972) (xy 55.848145 -160.325842) (xy 55.795361 -160.307835)
			(xy 55.745761 -160.282334) (xy 55.700403 -160.249883) (xy 55.660254 -160.211174) (xy 55.626168 -160.167031)
			(xy 55.598872 -160.118396) (xy 55.578949 -160.066305) (xy 55.566823 -160.011868) (xy 55.562752 -159.956246)
			(xy 54.746144 -159.956246) (xy 54.746144 -161.636456) (xy 63.800734 -161.636456) (xy 63.804805 -161.580834)
			(xy 63.816931 -161.526397) (xy 63.836854 -161.474306) (xy 63.86415 -161.425671) (xy 63.898236 -161.381528)
			(xy 63.938385 -161.342819) (xy 63.983743 -161.310368) (xy 64.033343 -161.284867) (xy 64.086127 -161.26686)
			(xy 64.14097 -161.25673) (xy 64.196704 -161.254693) (xy 64.252141 -161.260793) (xy 64.306098 -161.274899)
			(xy 64.357427 -161.296711) (xy 64.405033 -161.325765) (xy 64.447901 -161.36144) (xy 64.485118 -161.402977)
			(xy 64.515891 -161.44949) (xy 64.539563 -161.499987) (xy 64.555631 -161.553394) (xy 64.563751 -161.60857)
			(xy 64.56426 -161.636456) (xy 64.563751 -161.664342) (xy 64.555631 -161.719518) (xy 64.539563 -161.772925)
			(xy 64.515891 -161.823422) (xy 64.485118 -161.869935) (xy 64.447901 -161.911472) (xy 64.405033 -161.947147)
			(xy 64.357427 -161.976201) (xy 64.306098 -161.998013) (xy 64.252141 -162.012119) (xy 64.196704 -162.018219)
			(xy 64.14097 -162.016182) (xy 64.086127 -162.006052) (xy 64.033343 -161.988045) (xy 63.983743 -161.962544)
			(xy 63.938385 -161.930093) (xy 63.898236 -161.891384) (xy 63.86415 -161.847241) (xy 63.836854 -161.798606)
			(xy 63.816931 -161.746515) (xy 63.804805 -161.692078) (xy 63.800734 -161.636456) (xy 54.746144 -161.636456)
			(xy 54.746144 -161.694622) (xy 54.746572 -161.704689) (xy 54.754297 -161.723284) (xy 54.76113 -161.73069)
			(xy 56.381142 -163.350702) (xy 60.627258 -163.350702) (xy 60.631329 -163.29508) (xy 60.643455 -163.240643)
			(xy 60.663378 -163.188552) (xy 60.690674 -163.139917) (xy 60.72476 -163.095774) (xy 60.764909 -163.057065)
			(xy 60.810267 -163.024614) (xy 60.859867 -162.999113) (xy 60.912651 -162.981106) (xy 60.967494 -162.970976)
			(xy 61.023228 -162.968939) (xy 61.078665 -162.975039) (xy 61.132622 -162.989145) (xy 61.183951 -163.010957)
			(xy 61.231557 -163.040011) (xy 61.274425 -163.075686) (xy 61.311642 -163.117223) (xy 61.342415 -163.163736)
			(xy 61.366087 -163.214233) (xy 61.382155 -163.26764) (xy 61.390275 -163.322816) (xy 61.390784 -163.350702)
			(xy 61.390275 -163.378588) (xy 61.382155 -163.433764) (xy 61.366087 -163.487171) (xy 61.342415 -163.537668)
			(xy 61.311642 -163.584181) (xy 61.274425 -163.625718) (xy 61.231557 -163.661393) (xy 61.183951 -163.690447)
			(xy 61.132622 -163.712259) (xy 61.078665 -163.726365) (xy 61.023228 -163.732465) (xy 60.967494 -163.730428)
			(xy 60.912651 -163.720298) (xy 60.859867 -163.702291) (xy 60.810267 -163.67679) (xy 60.764909 -163.644339)
			(xy 60.72476 -163.60563) (xy 60.690674 -163.561487) (xy 60.663378 -163.512852) (xy 60.643455 -163.460761)
			(xy 60.631329 -163.406324) (xy 60.627258 -163.350702) (xy 56.381142 -163.350702) (xy 57.24271 -164.21227)
			(xy 57.250108 -164.219118) (xy 57.268706 -164.226854) (xy 57.278778 -164.227256) (xy 83.93684 -164.227256)
			(xy 83.969994 -164.227722) (xy 84.035886 -164.235145) (xy 84.100534 -164.249895) (xy 84.163125 -164.271785)
			(xy 84.222875 -164.30054) (xy 84.279031 -164.335801) (xy 84.33089 -164.377123) (xy 84.35467 -164.40023)
			(xy 95.018352 -175.063912) (xy 95.025749 -175.07076) (xy 95.044348 -175.078489) (xy 95.05442 -175.078898)
			(xy 98.67138 -175.078898) (xy 98.681444 -175.07846) (xy 98.700027 -175.070725) (xy 98.707448 -175.063912)
			(xy 100.010722 -173.760638) (xy 100.017567 -173.75324) (xy 100.025291 -173.734641) (xy 100.025708 -173.72457)
			(xy 100.025708 -134.663688) (xy 100.025283 -134.653619) (xy 100.017567 -134.635016) (xy 100.010722 -134.62762)
			(xy 98.683826 -133.300724) (xy 98.676425 -133.293887) (xy 98.657826 -133.286175) (xy 98.647758 -133.285738)
			(xy 82.079084 -133.285738) (xy 82.067671 -133.286206) (xy 82.047059 -133.296003) (xy 82.03946 -133.304534)
			(xy 81.98231 -133.375146) (xy 81.97723 -133.397498) (xy 81.97977 -133.408928) (xy 81.984619 -133.432828)
			(xy 81.989839 -133.481318) (xy 81.990184 -133.505702) (xy 81.990184 -134.369302) (xy 81.989694 -134.399286)
			(xy 81.981866 -134.458742) (xy 81.966345 -134.516667) (xy 81.943396 -134.572071) (xy 81.913412 -134.624005)
			(xy 81.876906 -134.671581) (xy 81.834501 -134.713986) (xy 81.786925 -134.750492) (xy 81.734991 -134.780476)
			(xy 81.679587 -134.803425) (xy 81.621662 -134.818946) (xy 81.562206 -134.826774) (xy 81.502238 -134.826774)
			(xy 81.442782 -134.818946) (xy 81.384857 -134.803425) (xy 81.329453 -134.780476) (xy 81.277519 -134.750492)
			(xy 81.229943 -134.713986) (xy 81.187538 -134.671581) (xy 81.151032 -134.624005) (xy 81.121048 -134.572071)
			(xy 81.098099 -134.516667) (xy 81.082578 -134.458742) (xy 81.07475 -134.399286) (xy 81.07426 -134.369302)
			(xy 81.07426 -133.505702) (xy 81.074587 -133.481316) (xy 81.079808 -133.432825) (xy 81.084674 -133.408928)
			(xy 81.087214 -133.397498) (xy 81.082134 -133.375146) (xy 81.024984 -133.304534) (xy 81.017316 -133.296096)
			(xy 80.996745 -133.286335) (xy 80.98536 -133.285738) (xy 74.567542 -133.285738) (xy 74.556937 -133.286274)
			(xy 74.53751 -133.294793) (xy 74.52995 -133.302248) (xy 74.510122 -133.323174) (xy 74.465283 -133.359402)
			(xy 74.415504 -133.388473) (xy 74.361918 -133.409724) (xy 74.305745 -133.422671) (xy 74.248264 -133.427019)
			(xy 74.190783 -133.422671) (xy 74.13461 -133.409724) (xy 74.081024 -133.388473) (xy 74.031245 -133.359402)
			(xy 73.986406 -133.323174) (xy 73.966578 -133.302248) (xy 73.959083 -133.294697) (xy 73.939618 -133.286152)
			(xy 73.928986 -133.285738) (xy 67.986148 -133.285738) (xy 67.975542 -133.286273) (xy 67.956114 -133.29479)
			(xy 67.948556 -133.302248) (xy 67.930408 -133.321452) (xy 67.889732 -133.355174) (xy 67.844791 -133.38296)
			(xy 67.796445 -133.404277) (xy 67.74562 -133.418718) (xy 67.693288 -133.426006) (xy 67.66687 -133.426454)
			(xy 67.649821 -133.42627) (xy 67.615861 -133.423214) (xy 67.599052 -133.420358) (xy 67.587713 -133.418744)
			(xy 67.565619 -133.424688) (xy 67.556634 -133.431788) (xy 67.53225 -133.45287) (xy 67.523872 -133.460883)
			(xy 67.514746 -133.482171) (xy 67.514724 -133.493764) (xy 67.515232 -133.513576) (xy 67.515232 -134.377176)
			(xy 67.514742 -134.40716) (xy 67.506914 -134.466616) (xy 67.491393 -134.524541) (xy 67.468444 -134.579945)
			(xy 67.43846 -134.631879) (xy 67.401954 -134.679455) (xy 67.359549 -134.72186) (xy 67.311973 -134.758366)
			(xy 67.260039 -134.78835) (xy 67.204635 -134.811299) (xy 67.14671 -134.82682) (xy 67.087254 -134.834648)
			(xy 67.027286 -134.834648) (xy 66.96783 -134.82682) (xy 66.909905 -134.811299) (xy 66.854501 -134.78835)
			(xy 66.802567 -134.758366) (xy 66.754991 -134.72186) (xy 66.712586 -134.679455) (xy 66.67608 -134.631879)
			(xy 66.646096 -134.579945) (xy 66.623147 -134.524541) (xy 66.607626 -134.466616) (xy 66.599798 -134.40716)
			(xy 66.599308 -134.377176) (xy 66.599308 -133.513576) (xy 66.599816 -133.494018) (xy 66.599845 -133.482412)
			(xy 66.59072 -133.4611) (xy 66.58229 -133.453124) (xy 66.557906 -133.432042) (xy 66.548831 -133.425114)
			(xy 66.526815 -133.41918) (xy 66.515488 -133.420612) (xy 66.498678 -133.423457) (xy 66.464718 -133.426513)
			(xy 66.44767 -133.426708) (xy 66.420301 -133.426234) (xy 66.366124 -133.418407) (xy 66.313623 -133.402917)
			(xy 66.263875 -133.380082) (xy 66.2179 -133.350372) (xy 66.196972 -133.332728) (xy 66.196718 -133.332728)
			(xy 66.196718 -133.332474) (xy 66.189631 -133.326889) (xy 66.172714 -133.320644) (xy 66.163698 -133.320282)
			(xy 66.096642 -133.320282) (xy 66.087623 -133.320634) (xy 66.070696 -133.326869) (xy 66.063622 -133.332474)
			(xy 66.063368 -133.332728) (xy 66.042435 -133.350367) (xy 65.996468 -133.380087) (xy 65.946721 -133.402924)
			(xy 65.894218 -133.418409) (xy 65.84004 -133.426222) (xy 65.81267 -133.426708) (xy 65.786222 -133.426255)
			(xy 65.733834 -133.418946) (xy 65.682957 -133.404471) (xy 65.634567 -133.383108) (xy 65.589591 -133.355266)
			(xy 65.548892 -133.32148) (xy 65.53073 -133.302248) (xy 65.523238 -133.294688) (xy 65.503773 -133.286124)
			(xy 65.493138 -133.285738) (xy 64.913002 -133.285738) (xy 64.9024 -133.286282) (xy 64.882985 -133.294811)
			(xy 64.87541 -133.302248) (xy 64.855577 -133.323215) (xy 64.810713 -133.359521) (xy 64.760894 -133.388656)
			(xy 64.707254 -133.409954) (xy 64.651019 -133.422931) (xy 64.59347 -133.427289) (xy 64.535921 -133.422931)
			(xy 64.479686 -133.409954) (xy 64.426046 -133.388656) (xy 64.376227 -133.359521) (xy 64.331363 -133.323215)
			(xy 64.31153 -133.302248) (xy 64.304038 -133.294688) (xy 64.284573 -133.286124) (xy 64.273938 -133.285738)
			(xy 52.69103 -133.285738) (xy 52.681857 -133.286113) (xy 52.664693 -133.292584) (xy 52.650946 -133.304729)
			(xy 52.646326 -133.312662) (xy 52.631295 -133.339655) (xy 52.595067 -133.389702) (xy 52.552437 -133.434422)
			(xy 52.504181 -133.473003) (xy 52.451175 -133.504744) (xy 52.394382 -133.529069) (xy 52.334834 -133.545535)
			(xy 52.273612 -133.553844) (xy 52.211828 -133.553844) (xy 52.150606 -133.545535) (xy 52.091058 -133.529069)
			(xy 52.034265 -133.504744) (xy 51.981259 -133.473003) (xy 51.933003 -133.434422) (xy 51.890373 -133.389702)
			(xy 51.854145 -133.339655) (xy 51.839114 -133.312662) (xy 51.834452 -133.304768) (xy 51.820691 -133.292673)
			(xy 51.803568 -133.286158) (xy 51.79441 -133.285738) (xy 38.220396 -133.285738) (xy 38.211071 -133.286155)
			(xy 38.19366 -133.292836) (xy 38.179796 -133.305309) (xy 38.175184 -133.313424) (xy 38.161291 -133.339518)
			(xy 38.127781 -133.388221) (xy 38.088281 -133.432205) (xy 38.043447 -133.470738) (xy 37.994026 -133.503179)
			(xy 37.940841 -133.528989) (xy 37.884775 -133.547738) (xy 37.826762 -133.559113) (xy 37.767768 -133.562926)
			(xy 37.708774 -133.559113) (xy 37.650761 -133.547738) (xy 37.594695 -133.528989) (xy 37.54151 -133.503179)
			(xy 37.492089 -133.470738) (xy 37.447255 -133.432205) (xy 37.407755 -133.388221) (xy 37.374245 -133.339518)
			(xy 37.360352 -133.313424) (xy 37.355735 -133.305316) (xy 37.341866 -133.292857) (xy 37.324461 -133.286179)
			(xy 37.31514 -133.285738) (xy 33.081976 -133.285738) (xy 33.071909 -133.286166) (xy 33.053314 -133.293891)
			(xy 33.045908 -133.300724) (xy 31.448756 -134.897876) (xy 34.667952 -134.897876) (xy 34.667952 -134.034276)
			(xy 34.668442 -134.004308) (xy 34.676265 -133.944886) (xy 34.691778 -133.886993) (xy 34.714714 -133.83162)
			(xy 34.744681 -133.779714) (xy 34.781168 -133.732164) (xy 34.823548 -133.689784) (xy 34.871098 -133.653297)
			(xy 34.923004 -133.62333) (xy 34.978377 -133.600394) (xy 35.03627 -133.584881) (xy 35.095692 -133.577058)
			(xy 35.155628 -133.577058) (xy 35.21505 -133.584881) (xy 35.272943 -133.600394) (xy 35.328316 -133.62333)
			(xy 35.380222 -133.653297) (xy 35.427772 -133.689784) (xy 35.470152 -133.732164) (xy 35.506639 -133.779714)
			(xy 35.536606 -133.83162) (xy 35.559542 -133.886993) (xy 35.575055 -133.944886) (xy 35.582878 -134.004308)
			(xy 35.583368 -134.034276) (xy 35.583368 -134.896352) (xy 53.639212 -134.896352) (xy 53.639212 -134.032752)
			(xy 53.639702 -134.002784) (xy 53.647525 -133.943362) (xy 53.663038 -133.885469) (xy 53.685974 -133.830096)
			(xy 53.715941 -133.77819) (xy 53.752428 -133.73064) (xy 53.794808 -133.68826) (xy 53.842358 -133.651773)
			(xy 53.894264 -133.621806) (xy 53.949637 -133.59887) (xy 54.00753 -133.583357) (xy 54.066952 -133.575534)
			(xy 54.126888 -133.575534) (xy 54.18631 -133.583357) (xy 54.244203 -133.59887) (xy 54.299576 -133.621806)
			(xy 54.351482 -133.651773) (xy 54.399032 -133.68826) (xy 54.441412 -133.73064) (xy 54.477899 -133.77819)
			(xy 54.507866 -133.830096) (xy 54.530802 -133.885469) (xy 54.546315 -133.943362) (xy 54.554138 -134.002784)
			(xy 54.554628 -134.032752) (xy 54.554628 -134.62) (xy 56.894982 -134.62) (xy 56.899053 -134.564378)
			(xy 56.911179 -134.509941) (xy 56.931102 -134.45785) (xy 56.958398 -134.409215) (xy 56.992484 -134.365072)
			(xy 57.032633 -134.326363) (xy 57.077991 -134.293912) (xy 57.127591 -134.268411) (xy 57.180375 -134.250404)
			(xy 57.235218 -134.240274) (xy 57.290952 -134.238237) (xy 57.346389 -134.244337) (xy 57.400346 -134.258443)
			(xy 57.451675 -134.280255) (xy 57.499281 -134.309309) (xy 57.542149 -134.344984) (xy 57.579366 -134.386521)
			(xy 57.610139 -134.433034) (xy 57.633811 -134.483531) (xy 57.649879 -134.536938) (xy 57.657999 -134.592114)
			(xy 57.658508 -134.62) (xy 57.657999 -134.647886) (xy 57.649879 -134.703062) (xy 57.633811 -134.756469)
			(xy 57.610139 -134.806966) (xy 57.579366 -134.853479) (xy 57.542149 -134.895016) (xy 57.499281 -134.930691)
			(xy 57.451675 -134.959745) (xy 57.400346 -134.981557) (xy 57.346389 -134.995663) (xy 57.290952 -135.001763)
			(xy 57.235218 -134.999726) (xy 57.180375 -134.989596) (xy 57.127591 -134.971589) (xy 57.077991 -134.946088)
			(xy 57.032633 -134.913637) (xy 56.992484 -134.874928) (xy 56.958398 -134.830785) (xy 56.931102 -134.78215)
			(xy 56.911179 -134.730059) (xy 56.899053 -134.675622) (xy 56.894982 -134.62) (xy 54.554628 -134.62)
			(xy 54.554628 -134.896352) (xy 54.554138 -134.92632) (xy 54.546315 -134.985742) (xy 54.530802 -135.043635)
			(xy 54.507866 -135.099008) (xy 54.477899 -135.150914) (xy 54.441412 -135.198464) (xy 54.399032 -135.240844)
			(xy 54.351482 -135.277331) (xy 54.299576 -135.307298) (xy 54.244203 -135.330234) (xy 54.18631 -135.345747)
			(xy 54.126888 -135.35357) (xy 54.066952 -135.35357) (xy 54.00753 -135.345747) (xy 53.949637 -135.330234)
			(xy 53.894264 -135.307298) (xy 53.842358 -135.277331) (xy 53.794808 -135.240844) (xy 53.752428 -135.198464)
			(xy 53.715941 -135.150914) (xy 53.685974 -135.099008) (xy 53.663038 -135.043635) (xy 53.647525 -134.985742)
			(xy 53.639702 -134.92632) (xy 53.639212 -134.896352) (xy 35.583368 -134.896352) (xy 35.583368 -134.897876)
			(xy 35.582878 -134.927844) (xy 35.575055 -134.987266) (xy 35.559542 -135.045159) (xy 35.536606 -135.100532)
			(xy 35.506639 -135.152438) (xy 35.470152 -135.199988) (xy 35.427772 -135.242368) (xy 35.380222 -135.278855)
			(xy 35.328316 -135.308822) (xy 35.272943 -135.331758) (xy 35.21505 -135.347271) (xy 35.155628 -135.355094)
			(xy 35.095692 -135.355094) (xy 35.03627 -135.347271) (xy 34.978377 -135.331758) (xy 34.923004 -135.308822)
			(xy 34.871098 -135.278855) (xy 34.823548 -135.242368) (xy 34.781168 -135.199988) (xy 34.744681 -135.152438)
			(xy 34.714714 -135.100532) (xy 34.691778 -135.045159) (xy 34.676265 -134.987266) (xy 34.668442 -134.927844)
			(xy 34.667952 -134.897876) (xy 31.448756 -134.897876) (xy 29.642308 -136.704324) (xy 37.31006 -136.704324)
			(xy 37.31006 -135.840724) (xy 37.31055 -135.810756) (xy 37.318373 -135.751334) (xy 37.333886 -135.693441)
			(xy 37.356822 -135.638068) (xy 37.386789 -135.586162) (xy 37.423276 -135.538612) (xy 37.465656 -135.496232)
			(xy 37.513206 -135.459745) (xy 37.565112 -135.429778) (xy 37.620485 -135.406842) (xy 37.678378 -135.391329)
			(xy 37.7378 -135.383506) (xy 37.797736 -135.383506) (xy 37.857158 -135.391329) (xy 37.915051 -135.406842)
			(xy 37.970424 -135.429778) (xy 38.02233 -135.459745) (xy 38.06988 -135.496232) (xy 38.11226 -135.538612)
			(xy 38.148747 -135.586162) (xy 38.178714 -135.638068) (xy 38.20165 -135.693441) (xy 38.217163 -135.751334)
			(xy 38.224986 -135.810756) (xy 38.225476 -135.840724) (xy 38.225476 -136.69645) (xy 51.785012 -136.69645)
			(xy 51.785012 -135.83285) (xy 51.785502 -135.802882) (xy 51.793325 -135.74346) (xy 51.808838 -135.685567)
			(xy 51.831774 -135.630194) (xy 51.861741 -135.578288) (xy 51.898228 -135.530738) (xy 51.940608 -135.488358)
			(xy 51.988158 -135.451871) (xy 52.040064 -135.421904) (xy 52.095437 -135.398968) (xy 52.15333 -135.383455)
			(xy 52.212752 -135.375632) (xy 52.272688 -135.375632) (xy 52.33211 -135.383455) (xy 52.390003 -135.398968)
			(xy 52.445376 -135.421904) (xy 52.497282 -135.451871) (xy 52.544832 -135.488358) (xy 52.587212 -135.530738)
			(xy 52.623699 -135.578288) (xy 52.653666 -135.630194) (xy 52.676602 -135.685567) (xy 52.692115 -135.74346)
			(xy 52.699938 -135.802882) (xy 52.700428 -135.83285) (xy 52.700428 -136.177274) (xy 64.745108 -136.177274)
			(xy 64.745108 -135.313674) (xy 64.745598 -135.28369) (xy 64.753426 -135.224234) (xy 64.768947 -135.166309)
			(xy 64.791896 -135.110905) (xy 64.82188 -135.058971) (xy 64.858386 -135.011395) (xy 64.900791 -134.96899)
			(xy 64.948367 -134.932484) (xy 65.000301 -134.9025) (xy 65.055705 -134.879551) (xy 65.11363 -134.86403)
			(xy 65.173086 -134.856202) (xy 65.233054 -134.856202) (xy 65.29251 -134.86403) (xy 65.350435 -134.879551)
			(xy 65.405839 -134.9025) (xy 65.457773 -134.932484) (xy 65.505349 -134.96899) (xy 65.547754 -135.011395)
			(xy 65.58426 -135.058971) (xy 65.614244 -135.110905) (xy 65.637193 -135.166309) (xy 65.652714 -135.224234)
			(xy 65.660542 -135.28369) (xy 65.661032 -135.313674) (xy 65.661032 -136.17575) (xy 83.716368 -136.17575)
			(xy 83.716368 -135.31215) (xy 83.716858 -135.282166) (xy 83.724686 -135.22271) (xy 83.740207 -135.164785)
			(xy 83.763156 -135.109381) (xy 83.79314 -135.057447) (xy 83.829646 -135.009871) (xy 83.872051 -134.967466)
			(xy 83.919627 -134.93096) (xy 83.971561 -134.900976) (xy 84.026965 -134.878027) (xy 84.08489 -134.862506)
			(xy 84.144346 -134.854678) (xy 84.204314 -134.854678) (xy 84.26377 -134.862506) (xy 84.321695 -134.878027)
			(xy 84.377099 -134.900976) (xy 84.429033 -134.93096) (xy 84.476609 -134.967466) (xy 84.519014 -135.009871)
			(xy 84.55552 -135.057447) (xy 84.585504 -135.109381) (xy 84.608453 -135.164785) (xy 84.623974 -135.22271)
			(xy 84.631802 -135.282166) (xy 84.632292 -135.31215) (xy 84.632292 -136.17575) (xy 84.631802 -136.205734)
			(xy 84.623974 -136.26519) (xy 84.608453 -136.323115) (xy 84.585504 -136.378519) (xy 84.55552 -136.430453)
			(xy 84.519014 -136.478029) (xy 84.476609 -136.520434) (xy 84.429033 -136.55694) (xy 84.377099 -136.586924)
			(xy 84.321695 -136.609873) (xy 84.26377 -136.625394) (xy 84.204314 -136.633222) (xy 84.144346 -136.633222)
			(xy 84.08489 -136.625394) (xy 84.026965 -136.609873) (xy 83.971561 -136.586924) (xy 83.919627 -136.55694)
			(xy 83.872051 -136.520434) (xy 83.829646 -136.478029) (xy 83.79314 -136.430453) (xy 83.763156 -136.378519)
			(xy 83.740207 -136.323115) (xy 83.724686 -136.26519) (xy 83.716858 -136.205734) (xy 83.716368 -136.17575)
			(xy 65.661032 -136.17575) (xy 65.661032 -136.177274) (xy 65.660542 -136.207258) (xy 65.652714 -136.266714)
			(xy 65.637193 -136.324639) (xy 65.614244 -136.380043) (xy 65.58426 -136.431977) (xy 65.547754 -136.479553)
			(xy 65.505349 -136.521958) (xy 65.457773 -136.558464) (xy 65.405839 -136.588448) (xy 65.350435 -136.611397)
			(xy 65.29251 -136.626918) (xy 65.233054 -136.634746) (xy 65.173086 -136.634746) (xy 65.11363 -136.626918)
			(xy 65.055705 -136.611397) (xy 65.000301 -136.588448) (xy 64.948367 -136.558464) (xy 64.900791 -136.521958)
			(xy 64.858386 -136.479553) (xy 64.82188 -136.431977) (xy 64.791896 -136.380043) (xy 64.768947 -136.324639)
			(xy 64.753426 -136.266714) (xy 64.745598 -136.207258) (xy 64.745108 -136.177274) (xy 52.700428 -136.177274)
			(xy 52.700428 -136.69645) (xy 52.699938 -136.726418) (xy 52.692115 -136.78584) (xy 52.676602 -136.843733)
			(xy 52.653666 -136.899106) (xy 52.623699 -136.951012) (xy 52.587212 -136.998562) (xy 52.544832 -137.040942)
			(xy 52.497282 -137.077429) (xy 52.445376 -137.107396) (xy 52.390003 -137.130332) (xy 52.33211 -137.145845)
			(xy 52.272688 -137.153668) (xy 52.212752 -137.153668) (xy 52.15333 -137.145845) (xy 52.095437 -137.130332)
			(xy 52.040064 -137.107396) (xy 51.988158 -137.077429) (xy 51.940608 -137.040942) (xy 51.898228 -136.998562)
			(xy 51.861741 -136.951012) (xy 51.831774 -136.899106) (xy 51.808838 -136.843733) (xy 51.793325 -136.78584)
			(xy 51.785502 -136.726418) (xy 51.785012 -136.69645) (xy 38.225476 -136.69645) (xy 38.225476 -136.704324)
			(xy 38.224986 -136.734292) (xy 38.217163 -136.793714) (xy 38.20165 -136.851607) (xy 38.178714 -136.90698)
			(xy 38.148747 -136.958886) (xy 38.11226 -137.006436) (xy 38.06988 -137.048816) (xy 38.02233 -137.085303)
			(xy 37.970424 -137.11527) (xy 37.915051 -137.138206) (xy 37.857158 -137.153719) (xy 37.797736 -137.161542)
			(xy 37.7378 -137.161542) (xy 37.678378 -137.153719) (xy 37.620485 -137.138206) (xy 37.565112 -137.11527)
			(xy 37.513206 -137.085303) (xy 37.465656 -137.048816) (xy 37.423276 -137.006436) (xy 37.386789 -136.958886)
			(xy 37.356822 -136.90698) (xy 37.333886 -136.851607) (xy 37.318373 -136.793714) (xy 37.31055 -136.734292)
			(xy 37.31006 -136.704324) (xy 29.642308 -136.704324) (xy 28.19146 -138.155172) (xy 28.184618 -138.162571)
			(xy 28.1769 -138.18117) (xy 28.176474 -138.19124) (xy 28.176474 -140.326364) (xy 35.692078 -140.326364)
			(xy 35.696149 -140.270742) (xy 35.708275 -140.216305) (xy 35.728198 -140.164214) (xy 35.755494 -140.115579)
			(xy 35.78958 -140.071436) (xy 35.829729 -140.032727) (xy 35.875087 -140.000276) (xy 35.924687 -139.974775)
			(xy 35.977471 -139.956768) (xy 36.032314 -139.946638) (xy 36.088048 -139.944601) (xy 36.143485 -139.950701)
			(xy 36.197442 -139.964807) (xy 36.248771 -139.986619) (xy 36.296377 -140.015673) (xy 36.339245 -140.051348)
			(xy 36.376462 -140.092885) (xy 36.407235 -140.139398) (xy 36.430907 -140.189895) (xy 36.446975 -140.243302)
			(xy 36.455095 -140.298478) (xy 36.455604 -140.326364) (xy 36.455095 -140.35425) (xy 36.446975 -140.409426)
			(xy 36.430907 -140.462833) (xy 36.407235 -140.51333) (xy 36.376462 -140.559843) (xy 36.371503 -140.565378)
			(xy 43.589702 -140.565378) (xy 43.590155 -140.538007) (xy 43.597976 -140.483828) (xy 43.613468 -140.431324)
			(xy 43.636313 -140.381578) (xy 43.66604 -140.335611) (xy 43.683682 -140.31468) (xy 43.683936 -140.314426)
			(xy 43.689522 -140.307339) (xy 43.695768 -140.290422) (xy 43.696128 -140.281406) (xy 43.696128 -140.21435)
			(xy 43.695741 -140.205336) (xy 43.689514 -140.188419) (xy 43.683936 -140.18133) (xy 43.683682 -140.18133)
			(xy 43.683682 -140.181076) (xy 43.666062 -140.160128) (xy 43.636348 -140.11416) (xy 43.613509 -140.064416)
			(xy 43.598013 -140.011919) (xy 43.590179 -139.957746) (xy 43.589702 -139.930378) (xy 43.590157 -139.903126)
			(xy 43.597917 -139.849176) (xy 43.613276 -139.79688) (xy 43.63592 -139.747303) (xy 43.665389 -139.701452)
			(xy 43.701084 -139.660262) (xy 43.742277 -139.62457) (xy 43.788131 -139.595105) (xy 43.837711 -139.572464)
			(xy 43.890008 -139.55711) (xy 43.943958 -139.549355) (xy 43.97121 -139.54887) (xy 43.998581 -139.549313)
			(xy 44.052762 -139.557134) (xy 44.105266 -139.572627) (xy 44.155013 -139.595475) (xy 44.200978 -139.625205)
			(xy 44.221908 -139.64285) (xy 44.222162 -139.643104) (xy 44.229255 -139.648681) (xy 44.246167 -139.654933)
			(xy 44.255182 -139.655296) (xy 44.322238 -139.655296) (xy 44.331257 -139.654958) (xy 44.348174 -139.648697)
			(xy 44.355258 -139.643104) (xy 44.355258 -139.64285) (xy 44.355512 -139.64285) (xy 44.376473 -139.625246)
			(xy 44.422437 -139.595528) (xy 44.472177 -139.572684) (xy 44.524672 -139.557185) (xy 44.578843 -139.549348)
			(xy 44.60621 -139.54887) (xy 44.63346 -139.549368) (xy 44.687407 -139.557126) (xy 44.7397 -139.572481)
			(xy 44.789276 -139.595122) (xy 44.835125 -139.624587) (xy 44.876314 -139.660277) (xy 44.912006 -139.701465)
			(xy 44.941473 -139.747314) (xy 44.964115 -139.796889) (xy 44.979472 -139.849182) (xy 44.987231 -139.903128)
			(xy 44.987718 -139.930378) (xy 44.987259 -139.957749) (xy 44.979443 -140.011929) (xy 44.963953 -140.064433)
			(xy 44.941109 -140.11418) (xy 44.932506 -140.127482) (xy 51.605178 -140.127482) (xy 51.609249 -140.07186)
			(xy 51.621375 -140.017423) (xy 51.641298 -139.965332) (xy 51.668594 -139.916697) (xy 51.70268 -139.872554)
			(xy 51.742829 -139.833845) (xy 51.788187 -139.801394) (xy 51.837787 -139.775893) (xy 51.890571 -139.757886)
			(xy 51.945414 -139.747756) (xy 52.001148 -139.745719) (xy 52.056585 -139.751819) (xy 52.110542 -139.765925)
			(xy 52.161871 -139.787737) (xy 52.209477 -139.816791) (xy 52.252345 -139.852466) (xy 52.289562 -139.894003)
			(xy 52.320335 -139.940516) (xy 52.344007 -139.991013) (xy 52.360075 -140.04442) (xy 52.368195 -140.099596)
			(xy 52.368704 -140.127482) (xy 52.368195 -140.155368) (xy 52.360075 -140.210544) (xy 52.344007 -140.263951)
			(xy 52.320335 -140.314448) (xy 52.289562 -140.360961) (xy 52.252345 -140.402498) (xy 52.209477 -140.438173)
			(xy 52.161871 -140.467227) (xy 52.110542 -140.489039) (xy 52.056585 -140.503145) (xy 52.001148 -140.509245)
			(xy 51.945414 -140.507208) (xy 51.890571 -140.497078) (xy 51.837787 -140.479071) (xy 51.788187 -140.45357)
			(xy 51.742829 -140.421119) (xy 51.70268 -140.38241) (xy 51.668594 -140.338267) (xy 51.641298 -140.289632)
			(xy 51.621375 -140.237541) (xy 51.609249 -140.183104) (xy 51.605178 -140.127482) (xy 44.932506 -140.127482)
			(xy 44.911381 -140.160145) (xy 44.893738 -140.181076) (xy 44.893484 -140.18133) (xy 44.887919 -140.188431)
			(xy 44.88166 -140.205337) (xy 44.881292 -140.21435) (xy 44.881292 -140.281406) (xy 44.881648 -140.290423)
			(xy 44.887896 -140.30734) (xy 44.893484 -140.314426) (xy 44.893738 -140.314426) (xy 44.893738 -140.31468)
			(xy 44.911387 -140.335604) (xy 44.941097 -140.381579) (xy 44.96393 -140.431329) (xy 44.979419 -140.483831)
			(xy 44.987245 -140.538008) (xy 44.987718 -140.565378) (xy 44.987224 -140.59263) (xy 44.979471 -140.646579)
			(xy 44.964118 -140.698876) (xy 44.941479 -140.748455) (xy 44.912014 -140.794308) (xy 44.876323 -140.835501)
			(xy 44.835134 -140.871195) (xy 44.789283 -140.900663) (xy 44.739706 -140.923307) (xy 44.68741 -140.938664)
			(xy 44.633462 -140.946422) (xy 44.60621 -140.946886) (xy 44.57884 -140.946417) (xy 44.524661 -140.938601)
			(xy 44.472157 -140.923112) (xy 44.422411 -140.900271) (xy 44.376444 -140.870547) (xy 44.355512 -140.852906)
			(xy 44.355258 -140.852652) (xy 44.348163 -140.847078) (xy 44.331253 -140.840825) (xy 44.322238 -140.84046)
			(xy 44.255182 -140.84046) (xy 44.246163 -140.840796) (xy 44.229245 -140.847057) (xy 44.222162 -140.852652)
			(xy 44.222162 -140.852906) (xy 44.221908 -140.852906) (xy 44.200985 -140.870556) (xy 44.155009 -140.900266)
			(xy 44.10526 -140.9231) (xy 44.052757 -140.938588) (xy 43.99858 -140.946414) (xy 43.97121 -140.946886)
			(xy 43.943956 -140.946435) (xy 43.890004 -140.938679) (xy 43.837704 -140.923323) (xy 43.788123 -140.90068)
			(xy 43.742269 -140.871211) (xy 43.701075 -140.835516) (xy 43.665381 -140.794322) (xy 43.635914 -140.748467)
			(xy 43.613273 -140.698884) (xy 43.597918 -140.646584) (xy 43.590164 -140.592632) (xy 43.589702 -140.565378)
			(xy 36.371503 -140.565378) (xy 36.339245 -140.60138) (xy 36.296377 -140.637055) (xy 36.248771 -140.666109)
			(xy 36.197442 -140.687921) (xy 36.143485 -140.702027) (xy 36.088048 -140.708127) (xy 36.032314 -140.70609)
			(xy 35.977471 -140.69596) (xy 35.924687 -140.677953) (xy 35.875087 -140.652452) (xy 35.829729 -140.620001)
			(xy 35.78958 -140.581292) (xy 35.755494 -140.537149) (xy 35.728198 -140.488514) (xy 35.708275 -140.436423)
			(xy 35.696149 -140.381986) (xy 35.692078 -140.326364) (xy 28.176474 -140.326364) (xy 28.176474 -142.60068)
			(xy 51.605688 -142.60068) (xy 51.606137 -142.573274) (xy 51.61399 -142.519029) (xy 51.629529 -142.466466)
			(xy 51.652436 -142.416671) (xy 51.682238 -142.37067) (xy 51.699922 -142.349728) (xy 51.700176 -142.349474)
			(xy 51.705747 -142.342377) (xy 51.712001 -142.325468) (xy 51.712368 -142.316454) (xy 51.712368 -142.249144)
			(xy 51.711997 -142.240128) (xy 51.70576 -142.223211) (xy 51.700176 -142.216124) (xy 51.699668 -142.215616)
			(xy 51.682018 -142.194693) (xy 51.652309 -142.148717) (xy 51.629476 -142.098967) (xy 51.613987 -142.046465)
			(xy 51.606161 -141.992288) (xy 51.605688 -141.964918) (xy 51.606174 -141.937667) (xy 51.61393 -141.883719)
			(xy 51.629285 -141.831424) (xy 51.651927 -141.781847) (xy 51.681393 -141.735997) (xy 51.717084 -141.694806)
			(xy 51.758275 -141.659115) (xy 51.804125 -141.629649) (xy 51.853702 -141.607007) (xy 51.905997 -141.591652)
			(xy 51.959945 -141.583896) (xy 52.014447 -141.583896) (xy 52.068395 -141.591652) (xy 52.12069 -141.607007)
			(xy 52.170267 -141.629649) (xy 52.216117 -141.659115) (xy 52.257308 -141.694806) (xy 52.292999 -141.735997)
			(xy 52.322465 -141.781847) (xy 52.345107 -141.831424) (xy 52.360462 -141.883719) (xy 52.368218 -141.937667)
			(xy 52.368704 -141.964918) (xy 52.368256 -141.992324) (xy 52.360403 -142.04657) (xy 52.344863 -142.099132)
			(xy 52.321956 -142.148927) (xy 52.292154 -142.194928) (xy 52.27447 -142.21587) (xy 52.274216 -142.216124)
			(xy 52.268615 -142.223201) (xy 52.262376 -142.240125) (xy 52.262024 -142.249144) (xy 52.262024 -142.316454)
			(xy 52.262398 -142.325469) (xy 52.268633 -142.342387) (xy 52.274216 -142.349474) (xy 52.274724 -142.349982)
			(xy 52.292372 -142.370907) (xy 52.322082 -142.416882) (xy 52.344915 -142.466631) (xy 52.360405 -142.519134)
			(xy 52.368231 -142.57331) (xy 52.368704 -142.60068) (xy 52.368218 -142.627931) (xy 52.360462 -142.681879)
			(xy 52.345107 -142.734174) (xy 52.322465 -142.783751) (xy 52.292999 -142.829601) (xy 52.257308 -142.870792)
			(xy 52.216117 -142.906483) (xy 52.170267 -142.935949) (xy 52.12069 -142.958591) (xy 52.068395 -142.973946)
			(xy 52.014447 -142.981702) (xy 51.959945 -142.981702) (xy 51.905997 -142.973946) (xy 51.853702 -142.958591)
			(xy 51.804125 -142.935949) (xy 51.758275 -142.906483) (xy 51.717084 -142.870792) (xy 51.681393 -142.829601)
			(xy 51.651927 -142.783751) (xy 51.629285 -142.734174) (xy 51.61393 -142.681879) (xy 51.606174 -142.627931)
			(xy 51.605688 -142.60068) (xy 28.176474 -142.60068) (xy 28.176474 -145.30578) (xy 43.138598 -145.30578)
			(xy 43.139069 -145.278446) (xy 43.146849 -145.224334) (xy 43.162276 -145.171887) (xy 43.185033 -145.12218)
			(xy 43.214654 -145.076232) (xy 43.250532 -145.034984) (xy 43.291932 -144.999282) (xy 43.338006 -144.969856)
			(xy 43.387809 -144.947311) (xy 43.413934 -144.939258) (xy 43.422799 -144.936263) (xy 43.437779 -144.925079)
			(xy 43.443144 -144.917414) (xy 43.484038 -144.852136) (xy 43.487594 -144.834356) (xy 43.48607 -144.825212)
			(xy 43.48607 -144.824704) (xy 43.483585 -144.809074) (xy 43.480916 -144.777537) (xy 43.480736 -144.761712)
			(xy 43.481167 -144.734457) (xy 43.488923 -144.680503) (xy 43.50428 -144.628202) (xy 43.526924 -144.578619)
			(xy 43.556395 -144.532764) (xy 43.592092 -144.49157) (xy 43.633289 -144.455876) (xy 43.679147 -144.426409)
			(xy 43.728732 -144.403769) (xy 43.781034 -144.388416) (xy 43.834989 -144.380664) (xy 43.862244 -144.380204)
			(xy 43.874215 -144.380314) (xy 43.898108 -144.381841) (xy 43.909996 -144.383252) (xy 43.91025 -144.383252)
			(xy 43.919424 -144.383939) (xy 43.937265 -144.37952) (xy 43.945048 -144.374616) (xy 44.001182 -144.3355)
			(xy 44.008599 -144.32993) (xy 44.019139 -144.314682) (xy 44.021756 -144.305782) (xy 44.021756 -144.305528)
			(xy 44.028689 -144.277959) (xy 44.049728 -144.225149) (xy 44.078374 -144.176046) (xy 44.113991 -144.13174)
			(xy 44.15579 -144.093212) (xy 44.202845 -144.061316) (xy 44.254114 -144.036758) (xy 44.308461 -144.020082)
			(xy 44.36468 -144.011659) (xy 44.393104 -144.011142) (xy 44.417775 -144.011568) (xy 44.466701 -144.017963)
			(xy 44.514395 -144.030607) (xy 44.537376 -144.03959) (xy 44.548486 -144.043465) (xy 44.571921 -144.041763)
			(xy 44.582334 -144.036288) (xy 44.652184 -143.994632) (xy 44.661971 -143.988174) (xy 44.674817 -143.968592)
			(xy 44.676822 -143.95704) (xy 44.676822 -143.956532) (xy 44.680475 -143.928969) (xy 44.694738 -143.875231)
			(xy 44.716654 -143.824133) (xy 44.745758 -143.77676) (xy 44.781433 -143.734115) (xy 44.822922 -143.697103)
			(xy 44.869346 -143.666509) (xy 44.919721 -143.64298) (xy 44.972979 -143.627016) (xy 45.02799 -143.618955)
			(xy 45.05579 -143.618458) (xy 45.083039 -143.618987) (xy 45.136984 -143.626742) (xy 45.189276 -143.642094)
			(xy 45.23885 -143.664731) (xy 45.284699 -143.694193) (xy 45.325889 -143.72988) (xy 45.36158 -143.771066)
			(xy 45.391048 -143.816911) (xy 45.413691 -143.866483) (xy 45.429049 -143.918773) (xy 45.436809 -143.972717)
			(xy 45.437298 -143.999966) (xy 45.436835 -144.026547) (xy 45.429452 -144.079195) (xy 45.414826 -144.130306)
			(xy 45.393239 -144.178888) (xy 45.365111 -144.224) (xy 45.330987 -144.264765) (xy 45.311568 -144.282922)
			(xy 45.304979 -144.289398) (xy 45.296513 -144.305803) (xy 45.295058 -144.314926) (xy 45.287692 -144.381474)
			(xy 45.286951 -144.39065) (xy 45.291393 -144.4085) (xy 45.296328 -144.416272) (xy 45.312439 -144.4404)
			(xy 45.337976 -144.492493) (xy 45.355334 -144.54785) (xy 45.364113 -144.605197) (xy 45.364654 -144.634204)
			(xy 45.364126 -144.661453) (xy 45.35637 -144.715397) (xy 45.341017 -144.767688) (xy 45.318379 -144.817262)
			(xy 45.288916 -144.863111) (xy 45.253229 -144.9043) (xy 45.212044 -144.939991) (xy 45.166199 -144.969458)
			(xy 45.116628 -144.992102) (xy 45.064338 -145.007461) (xy 45.010395 -145.015223) (xy 44.983146 -145.015712)
			(xy 44.982638 -145.015712) (xy 44.972841 -145.015644) (xy 44.953273 -145.014629) (xy 44.943522 -145.01368)
			(xy 44.943268 -145.01368) (xy 44.933878 -145.013094) (xy 44.915742 -145.018044) (xy 44.907962 -145.023332)
			(xy 44.84497 -145.070068) (xy 44.835064 -145.08607) (xy 44.833286 -145.095722) (xy 44.827837 -145.121546)
			(xy 44.81091 -145.171534) (xy 44.787254 -145.218711) (xy 44.757323 -145.262178) (xy 44.721687 -145.301105)
			(xy 44.681025 -145.334749) (xy 44.636115 -145.362469) (xy 44.587814 -145.383734) (xy 44.537042 -145.39814)
			(xy 44.48477 -145.405411) (xy 44.458382 -145.405856) (xy 44.430833 -145.40536) (xy 44.376305 -145.397444)
			(xy 44.323485 -145.381765) (xy 44.273469 -145.35865) (xy 44.227301 -145.328578) (xy 44.185939 -145.292177)
			(xy 44.150245 -145.250203) (xy 44.120961 -145.20353) (xy 44.109386 -145.178526) (xy 44.105576 -145.16989)
			(xy 44.092114 -145.156428) (xy 44.01185 -145.121122) (xy 43.993308 -145.120106) (xy 43.984418 -145.1229)
			(xy 43.983402 -145.123408) (xy 43.968416 -145.128234) (xy 43.959545 -145.131213) (xy 43.944569 -145.142409)
			(xy 43.939206 -145.150078) (xy 43.898312 -145.215356) (xy 43.894756 -145.233136) (xy 43.89628 -145.24228)
			(xy 43.89628 -145.242788) (xy 43.898764 -145.258418) (xy 43.901433 -145.289955) (xy 43.901614 -145.30578)
			(xy 43.901128 -145.333031) (xy 43.893372 -145.386979) (xy 43.878017 -145.439274) (xy 43.855375 -145.488851)
			(xy 43.825909 -145.534701) (xy 43.790218 -145.575892) (xy 43.749027 -145.611583) (xy 43.703177 -145.641049)
			(xy 43.6536 -145.663691) (xy 43.601305 -145.679046) (xy 43.547357 -145.686802) (xy 43.492855 -145.686802)
			(xy 43.438907 -145.679046) (xy 43.386612 -145.663691) (xy 43.337035 -145.641049) (xy 43.291185 -145.611583)
			(xy 43.249994 -145.575892) (xy 43.214303 -145.534701) (xy 43.184837 -145.488851) (xy 43.162195 -145.439274)
			(xy 43.14684 -145.386979) (xy 43.139084 -145.333031) (xy 43.138598 -145.30578) (xy 28.176474 -145.30578)
			(xy 28.176474 -146.739864) (xy 48.909984 -146.739864) (xy 48.914055 -146.684242) (xy 48.926181 -146.629805)
			(xy 48.946104 -146.577714) (xy 48.9734 -146.529079) (xy 49.007486 -146.484936) (xy 49.047635 -146.446227)
			(xy 49.092993 -146.413776) (xy 49.142593 -146.388275) (xy 49.195377 -146.370268) (xy 49.25022 -146.360138)
			(xy 49.305954 -146.358101) (xy 49.361391 -146.364201) (xy 49.415348 -146.378307) (xy 49.466677 -146.400119)
			(xy 49.514283 -146.429173) (xy 49.557151 -146.464848) (xy 49.594368 -146.506385) (xy 49.625141 -146.552898)
			(xy 49.648813 -146.603395) (xy 49.664881 -146.656802) (xy 49.673001 -146.711978) (xy 49.67351 -146.739864)
			(xy 49.673001 -146.76775) (xy 49.668844 -146.795998) (xy 50.543712 -146.795998) (xy 50.547783 -146.740376)
			(xy 50.559909 -146.685939) (xy 50.579832 -146.633848) (xy 50.607128 -146.585213) (xy 50.641214 -146.54107)
			(xy 50.681363 -146.502361) (xy 50.726721 -146.46991) (xy 50.776321 -146.444409) (xy 50.829105 -146.426402)
			(xy 50.883948 -146.416272) (xy 50.939682 -146.414235) (xy 50.995119 -146.420335) (xy 51.049076 -146.434441)
			(xy 51.100405 -146.456253) (xy 51.148011 -146.485307) (xy 51.190879 -146.520982) (xy 51.228096 -146.562519)
			(xy 51.258869 -146.609032) (xy 51.282541 -146.659529) (xy 51.298609 -146.712936) (xy 51.306729 -146.768112)
			(xy 51.307238 -146.795998) (xy 51.306729 -146.823884) (xy 51.298609 -146.87906) (xy 51.282541 -146.932467)
			(xy 51.258869 -146.982964) (xy 51.228096 -147.029477) (xy 51.190879 -147.071014) (xy 51.148011 -147.106689)
			(xy 51.100405 -147.135743) (xy 51.049076 -147.157555) (xy 50.995119 -147.171661) (xy 50.939682 -147.177761)
			(xy 50.883948 -147.175724) (xy 50.829105 -147.165594) (xy 50.776321 -147.147587) (xy 50.726721 -147.122086)
			(xy 50.681363 -147.089635) (xy 50.641214 -147.050926) (xy 50.607128 -147.006783) (xy 50.579832 -146.958148)
			(xy 50.559909 -146.906057) (xy 50.547783 -146.85162) (xy 50.543712 -146.795998) (xy 49.668844 -146.795998)
			(xy 49.664881 -146.822926) (xy 49.648813 -146.876333) (xy 49.625141 -146.92683) (xy 49.594368 -146.973343)
			(xy 49.557151 -147.01488) (xy 49.514283 -147.050555) (xy 49.466677 -147.079609) (xy 49.415348 -147.101421)
			(xy 49.361391 -147.115527) (xy 49.305954 -147.121627) (xy 49.25022 -147.11959) (xy 49.195377 -147.10946)
			(xy 49.142593 -147.091453) (xy 49.092993 -147.065952) (xy 49.047635 -147.033501) (xy 49.007486 -146.994792)
			(xy 48.9734 -146.950649) (xy 48.946104 -146.902014) (xy 48.926181 -146.849923) (xy 48.914055 -146.795486)
			(xy 48.909984 -146.739864) (xy 28.176474 -146.739864) (xy 28.176474 -153.3144) (xy 37.190932 -153.3144)
			(xy 37.195003 -153.258778) (xy 37.207129 -153.204341) (xy 37.227052 -153.15225) (xy 37.254348 -153.103615)
			(xy 37.288434 -153.059472) (xy 37.328583 -153.020763) (xy 37.373941 -152.988312) (xy 37.423541 -152.962811)
			(xy 37.476325 -152.944804) (xy 37.531168 -152.934674) (xy 37.586902 -152.932637) (xy 37.642339 -152.938737)
			(xy 37.696296 -152.952843) (xy 37.747625 -152.974655) (xy 37.795231 -153.003709) (xy 37.838099 -153.039384)
			(xy 37.875316 -153.080921) (xy 37.906089 -153.127434) (xy 37.929761 -153.177931) (xy 37.945829 -153.231338)
			(xy 37.953949 -153.286514) (xy 37.954458 -153.3144) (xy 37.953949 -153.342286) (xy 37.945829 -153.397462)
			(xy 37.929761 -153.450869) (xy 37.906089 -153.501366) (xy 37.875316 -153.547879) (xy 37.838099 -153.589416)
			(xy 37.795231 -153.625091) (xy 37.747625 -153.654145) (xy 37.696296 -153.675957) (xy 37.642339 -153.690063)
			(xy 37.586902 -153.696163) (xy 37.531168 -153.694126) (xy 37.476325 -153.683996) (xy 37.423541 -153.665989)
			(xy 37.373941 -153.640488) (xy 37.328583 -153.608037) (xy 37.288434 -153.569328) (xy 37.254348 -153.525185)
			(xy 37.227052 -153.47655) (xy 37.207129 -153.424459) (xy 37.195003 -153.370022) (xy 37.190932 -153.3144)
			(xy 28.176474 -153.3144) (xy 28.176474 -154.159966) (xy 51.306982 -154.159966) (xy 51.311053 -154.104344)
			(xy 51.323179 -154.049907) (xy 51.343102 -153.997816) (xy 51.370398 -153.949181) (xy 51.404484 -153.905038)
			(xy 51.444633 -153.866329) (xy 51.489991 -153.833878) (xy 51.539591 -153.808377) (xy 51.592375 -153.79037)
			(xy 51.647218 -153.78024) (xy 51.702952 -153.778203) (xy 51.758389 -153.784303) (xy 51.812346 -153.798409)
			(xy 51.863675 -153.820221) (xy 51.911281 -153.849275) (xy 51.954149 -153.88495) (xy 51.991366 -153.926487)
			(xy 52.022139 -153.973) (xy 52.045811 -154.023497) (xy 52.061879 -154.076904) (xy 52.069999 -154.13208)
			(xy 52.070508 -154.159966) (xy 52.069999 -154.187852) (xy 52.061879 -154.243028) (xy 52.045811 -154.296435)
			(xy 52.022139 -154.346932) (xy 51.991366 -154.393445) (xy 51.954149 -154.434982) (xy 51.911281 -154.470657)
			(xy 51.863675 -154.499711) (xy 51.812346 -154.521523) (xy 51.758389 -154.535629) (xy 51.702952 -154.541729)
			(xy 51.647218 -154.539692) (xy 51.592375 -154.529562) (xy 51.539591 -154.511555) (xy 51.489991 -154.486054)
			(xy 51.444633 -154.453603) (xy 51.404484 -154.414894) (xy 51.370398 -154.370751) (xy 51.343102 -154.322116)
			(xy 51.323179 -154.270025) (xy 51.311053 -154.215588) (xy 51.306982 -154.159966) (xy 28.176474 -154.159966)
			(xy 28.176474 -155.0416) (xy 48.163732 -155.0416) (xy 48.167803 -154.985978) (xy 48.179929 -154.931541)
			(xy 48.199852 -154.87945) (xy 48.227148 -154.830815) (xy 48.261234 -154.786672) (xy 48.301383 -154.747963)
			(xy 48.346741 -154.715512) (xy 48.396341 -154.690011) (xy 48.449125 -154.672004) (xy 48.503968 -154.661874)
			(xy 48.559702 -154.659837) (xy 48.615139 -154.665937) (xy 48.669096 -154.680043) (xy 48.720425 -154.701855)
			(xy 48.768031 -154.730909) (xy 48.810899 -154.766584) (xy 48.848116 -154.808121) (xy 48.878889 -154.854634)
			(xy 48.902561 -154.905131) (xy 48.918629 -154.958538) (xy 48.926749 -155.013714) (xy 48.927258 -155.0416)
			(xy 48.926749 -155.069486) (xy 48.918629 -155.124662) (xy 48.902561 -155.178069) (xy 48.878889 -155.228566)
			(xy 48.848116 -155.275079) (xy 48.810899 -155.316616) (xy 48.768031 -155.352291) (xy 48.720425 -155.381345)
			(xy 48.669096 -155.403157) (xy 48.615139 -155.417263) (xy 48.559702 -155.423363) (xy 48.503968 -155.421326)
			(xy 48.449125 -155.411196) (xy 48.396341 -155.393189) (xy 48.346741 -155.367688) (xy 48.301383 -155.335237)
			(xy 48.261234 -155.296528) (xy 48.227148 -155.252385) (xy 48.199852 -155.20375) (xy 48.179929 -155.151659)
			(xy 48.167803 -155.097222) (xy 48.163732 -155.0416) (xy 28.176474 -155.0416) (xy 28.176474 -155.598368)
			(xy 51.368196 -155.598368) (xy 51.372267 -155.542746) (xy 51.384393 -155.488309) (xy 51.404316 -155.436218)
			(xy 51.431612 -155.387583) (xy 51.465698 -155.34344) (xy 51.505847 -155.304731) (xy 51.551205 -155.27228)
			(xy 51.600805 -155.246779) (xy 51.653589 -155.228772) (xy 51.708432 -155.218642) (xy 51.764166 -155.216605)
			(xy 51.819603 -155.222705) (xy 51.87356 -155.236811) (xy 51.924889 -155.258623) (xy 51.972495 -155.287677)
			(xy 52.015363 -155.323352) (xy 52.05258 -155.364889) (xy 52.083353 -155.411402) (xy 52.107025 -155.461899)
			(xy 52.123093 -155.515306) (xy 52.131213 -155.570482) (xy 52.131722 -155.598368) (xy 52.131213 -155.626254)
			(xy 52.123093 -155.68143) (xy 52.107025 -155.734837) (xy 52.083353 -155.785334) (xy 52.05258 -155.831847)
			(xy 52.015363 -155.873384) (xy 51.972495 -155.909059) (xy 51.924889 -155.938113) (xy 51.87356 -155.959925)
			(xy 51.819603 -155.974031) (xy 51.764166 -155.980131) (xy 51.708432 -155.978094) (xy 51.653589 -155.967964)
			(xy 51.600805 -155.949957) (xy 51.551205 -155.924456) (xy 51.505847 -155.892005) (xy 51.465698 -155.853296)
			(xy 51.431612 -155.809153) (xy 51.404316 -155.760518) (xy 51.384393 -155.708427) (xy 51.372267 -155.65399)
			(xy 51.368196 -155.598368) (xy 28.176474 -155.598368) (xy 28.176474 -157.3784) (xy 37.190932 -157.3784)
			(xy 37.195003 -157.322778) (xy 37.207129 -157.268341) (xy 37.227052 -157.21625) (xy 37.254348 -157.167615)
			(xy 37.288434 -157.123472) (xy 37.328583 -157.084763) (xy 37.373941 -157.052312) (xy 37.423541 -157.026811)
			(xy 37.476325 -157.008804) (xy 37.531168 -156.998674) (xy 37.586902 -156.996637) (xy 37.642339 -157.002737)
			(xy 37.696296 -157.016843) (xy 37.747625 -157.038655) (xy 37.795231 -157.067709) (xy 37.80231 -157.0736)
			(xy 51.296822 -157.0736) (xy 51.300893 -157.017978) (xy 51.313019 -156.963541) (xy 51.332942 -156.91145)
			(xy 51.360238 -156.862815) (xy 51.394324 -156.818672) (xy 51.434473 -156.779963) (xy 51.479831 -156.747512)
			(xy 51.529431 -156.722011) (xy 51.582215 -156.704004) (xy 51.637058 -156.693874) (xy 51.692792 -156.691837)
			(xy 51.748229 -156.697937) (xy 51.802186 -156.712043) (xy 51.853515 -156.733855) (xy 51.901121 -156.762909)
			(xy 51.943989 -156.798584) (xy 51.981206 -156.840121) (xy 52.011979 -156.886634) (xy 52.035651 -156.937131)
			(xy 52.051719 -156.990538) (xy 52.059839 -157.045714) (xy 52.060348 -157.0736) (xy 52.059839 -157.101486)
			(xy 52.051719 -157.156662) (xy 52.035651 -157.210069) (xy 52.011979 -157.260566) (xy 51.981206 -157.307079)
			(xy 51.943989 -157.348616) (xy 51.901121 -157.384291) (xy 51.853515 -157.413345) (xy 51.802186 -157.435157)
			(xy 51.748229 -157.449263) (xy 51.692792 -157.455363) (xy 51.637058 -157.453326) (xy 51.582215 -157.443196)
			(xy 51.529431 -157.425189) (xy 51.479831 -157.399688) (xy 51.434473 -157.367237) (xy 51.394324 -157.328528)
			(xy 51.360238 -157.284385) (xy 51.332942 -157.23575) (xy 51.313019 -157.183659) (xy 51.300893 -157.129222)
			(xy 51.296822 -157.0736) (xy 37.80231 -157.0736) (xy 37.838099 -157.103384) (xy 37.875316 -157.144921)
			(xy 37.906089 -157.191434) (xy 37.929761 -157.241931) (xy 37.945829 -157.295338) (xy 37.953949 -157.350514)
			(xy 37.954458 -157.3784) (xy 37.953949 -157.406286) (xy 37.945829 -157.461462) (xy 37.929761 -157.514869)
			(xy 37.906089 -157.565366) (xy 37.875316 -157.611879) (xy 37.838099 -157.653416) (xy 37.795231 -157.689091)
			(xy 37.747625 -157.718145) (xy 37.696296 -157.739957) (xy 37.642339 -157.754063) (xy 37.586902 -157.760163)
			(xy 37.531168 -157.758126) (xy 37.476325 -157.747996) (xy 37.423541 -157.729989) (xy 37.373941 -157.704488)
			(xy 37.328583 -157.672037) (xy 37.288434 -157.633328) (xy 37.254348 -157.589185) (xy 37.227052 -157.54055)
			(xy 37.207129 -157.488459) (xy 37.195003 -157.434022) (xy 37.190932 -157.3784) (xy 28.176474 -157.3784)
			(xy 28.176474 -158.3944) (xy 37.190932 -158.3944) (xy 37.195003 -158.338778) (xy 37.207129 -158.284341)
			(xy 37.227052 -158.23225) (xy 37.254348 -158.183615) (xy 37.288434 -158.139472) (xy 37.328583 -158.100763)
			(xy 37.373941 -158.068312) (xy 37.423541 -158.042811) (xy 37.476325 -158.024804) (xy 37.531168 -158.014674)
			(xy 37.586902 -158.012637) (xy 37.642339 -158.018737) (xy 37.696296 -158.032843) (xy 37.747625 -158.054655)
			(xy 37.795231 -158.083709) (xy 37.838099 -158.119384) (xy 37.875316 -158.160921) (xy 37.906089 -158.207434)
			(xy 37.929761 -158.257931) (xy 37.945829 -158.311338) (xy 37.953949 -158.366514) (xy 37.954458 -158.3944)
			(xy 37.953949 -158.422286) (xy 37.945829 -158.477462) (xy 37.929761 -158.530869) (xy 37.906089 -158.581366)
			(xy 37.875316 -158.627879) (xy 37.838099 -158.669416) (xy 37.795231 -158.705091) (xy 37.747625 -158.734145)
			(xy 37.696296 -158.755957) (xy 37.642339 -158.770063) (xy 37.586902 -158.776163) (xy 37.531168 -158.774126)
			(xy 37.476325 -158.763996) (xy 37.423541 -158.745989) (xy 37.373941 -158.720488) (xy 37.328583 -158.688037)
			(xy 37.288434 -158.649328) (xy 37.254348 -158.605185) (xy 37.227052 -158.55655) (xy 37.207129 -158.504459)
			(xy 37.195003 -158.450022) (xy 37.190932 -158.3944) (xy 28.176474 -158.3944) (xy 28.176474 -160.1851)
			(xy 45.524179 -160.1851) (xy 45.528134 -160.093263) (xy 45.539969 -160.002106) (xy 45.559596 -159.912303)
			(xy 45.58687 -159.824521) (xy 45.62159 -159.739407) (xy 45.663498 -159.657594) (xy 45.712284 -159.579686)
			(xy 45.767587 -159.506261) (xy 45.828997 -159.437861) (xy 45.896059 -159.374994) (xy 45.968278 -159.318124)
			(xy 46.045118 -159.267673) (xy 46.126011 -159.224014) (xy 46.210357 -159.187471) (xy 46.297533 -159.158314)
			(xy 46.386892 -159.13676) (xy 46.477773 -159.122966) (xy 46.569504 -159.117036) (xy 46.661405 -159.119014)
			(xy 46.752796 -159.128885) (xy 46.843 -159.146575) (xy 46.931349 -159.171955) (xy 47.017189 -159.204835)
			(xy 47.099885 -159.244973) (xy 47.178825 -159.292072) (xy 47.253423 -159.345782) (xy 47.323129 -159.405706)
			(xy 47.387424 -159.4714) (xy 47.445835 -159.542378) (xy 47.497927 -159.618115) (xy 47.543316 -159.69805)
			(xy 47.581666 -159.78159) (xy 47.612691 -159.868118) (xy 47.636164 -159.956993) (xy 47.65191 -160.047557)
			(xy 47.659812 -160.139139) (xy 47.660306 -160.1851) (xy 47.659812 -160.231061) (xy 47.65191 -160.322643)
			(xy 47.636164 -160.413207) (xy 47.612691 -160.502082) (xy 47.581666 -160.58861) (xy 47.543316 -160.67215)
			(xy 47.497927 -160.752085) (xy 47.445835 -160.827822) (xy 47.387424 -160.8988) (xy 47.323129 -160.964494)
			(xy 47.253423 -161.024418) (xy 47.178825 -161.078128) (xy 47.099885 -161.125227) (xy 47.017189 -161.165365)
			(xy 46.931349 -161.198245) (xy 46.843 -161.223625) (xy 46.752796 -161.241315) (xy 46.661405 -161.251186)
			(xy 46.569504 -161.253164) (xy 46.477773 -161.247234) (xy 46.386892 -161.23344) (xy 46.297533 -161.211886)
			(xy 46.210357 -161.182729) (xy 46.126011 -161.146186) (xy 46.045118 -161.102527) (xy 45.968278 -161.052076)
			(xy 45.896059 -160.995206) (xy 45.828997 -160.932339) (xy 45.767587 -160.863939) (xy 45.712284 -160.790514)
			(xy 45.663498 -160.712606) (xy 45.62159 -160.630793) (xy 45.58687 -160.545679) (xy 45.559596 -160.457897)
			(xy 45.539969 -160.368094) (xy 45.528134 -160.276937) (xy 45.524179 -160.1851) (xy 28.176474 -160.1851)
			(xy 28.176474 -161.08426) (xy 37.583108 -161.08426) (xy 37.587179 -161.028638) (xy 37.599305 -160.974201)
			(xy 37.619228 -160.92211) (xy 37.646524 -160.873475) (xy 37.68061 -160.829332) (xy 37.720759 -160.790623)
			(xy 37.766117 -160.758172) (xy 37.815717 -160.732671) (xy 37.868501 -160.714664) (xy 37.923344 -160.704534)
			(xy 37.979078 -160.702497) (xy 38.034515 -160.708597) (xy 38.088472 -160.722703) (xy 38.139801 -160.744515)
			(xy 38.187407 -160.773569) (xy 38.230275 -160.809244) (xy 38.267492 -160.850781) (xy 38.298265 -160.897294)
			(xy 38.321937 -160.947791) (xy 38.338005 -161.001198) (xy 38.346125 -161.056374) (xy 38.346634 -161.08426)
			(xy 38.346125 -161.112146) (xy 38.338005 -161.167322) (xy 38.321937 -161.220729) (xy 38.298265 -161.271226)
			(xy 38.267492 -161.317739) (xy 38.230275 -161.359276) (xy 38.187407 -161.394951) (xy 38.139801 -161.424005)
			(xy 38.088472 -161.445817) (xy 38.034515 -161.459923) (xy 37.979078 -161.466023) (xy 37.923344 -161.463986)
			(xy 37.868501 -161.453856) (xy 37.815717 -161.435849) (xy 37.766117 -161.410348) (xy 37.720759 -161.377897)
			(xy 37.68061 -161.339188) (xy 37.646524 -161.295045) (xy 37.619228 -161.24641) (xy 37.599305 -161.194319)
			(xy 37.587179 -161.139882) (xy 37.583108 -161.08426) (xy 28.176474 -161.08426) (xy 28.176474 -163.928806)
			(xy 38.393114 -163.928806) (xy 38.397185 -163.873184) (xy 38.409311 -163.818747) (xy 38.429234 -163.766656)
			(xy 38.45653 -163.718021) (xy 38.490616 -163.673878) (xy 38.530765 -163.635169) (xy 38.576123 -163.602718)
			(xy 38.625723 -163.577217) (xy 38.678507 -163.55921) (xy 38.73335 -163.54908) (xy 38.789084 -163.547043)
			(xy 38.844521 -163.553143) (xy 38.898478 -163.567249) (xy 38.949807 -163.589061) (xy 38.997413 -163.618115)
			(xy 39.040281 -163.65379) (xy 39.077498 -163.695327) (xy 39.108271 -163.74184) (xy 39.131943 -163.792337)
			(xy 39.148011 -163.845744) (xy 39.156131 -163.90092) (xy 39.15664 -163.928806) (xy 39.156131 -163.956692)
			(xy 39.148011 -164.011868) (xy 39.131943 -164.065275) (xy 39.108271 -164.115772) (xy 39.077498 -164.162285)
			(xy 39.040281 -164.203822) (xy 38.997413 -164.239497) (xy 38.949807 -164.268551) (xy 38.898478 -164.290363)
			(xy 38.844521 -164.304469) (xy 38.789084 -164.310569) (xy 38.73335 -164.308532) (xy 38.678507 -164.298402)
			(xy 38.625723 -164.280395) (xy 38.576123 -164.254894) (xy 38.530765 -164.222443) (xy 38.490616 -164.183734)
			(xy 38.45653 -164.139591) (xy 38.429234 -164.090956) (xy 38.409311 -164.038865) (xy 38.397185 -163.984428)
			(xy 38.393114 -163.928806) (xy 28.176474 -163.928806) (xy 28.176474 -166.705534) (xy 61.11189 -166.705534)
			(xy 61.115961 -166.649912) (xy 61.128087 -166.595475) (xy 61.14801 -166.543384) (xy 61.175306 -166.494749)
			(xy 61.209392 -166.450606) (xy 61.249541 -166.411897) (xy 61.294899 -166.379446) (xy 61.344499 -166.353945)
			(xy 61.397283 -166.335938) (xy 61.452126 -166.325808) (xy 61.50786 -166.323771) (xy 61.563297 -166.329871)
			(xy 61.617254 -166.343977) (xy 61.668583 -166.365789) (xy 61.716189 -166.394843) (xy 61.759057 -166.430518)
			(xy 61.796274 -166.472055) (xy 61.827047 -166.518568) (xy 61.850719 -166.569065) (xy 61.866787 -166.622472)
			(xy 61.874907 -166.677648) (xy 61.875416 -166.705534) (xy 62.12789 -166.705534) (xy 62.131961 -166.649912)
			(xy 62.144087 -166.595475) (xy 62.16401 -166.543384) (xy 62.191306 -166.494749) (xy 62.225392 -166.450606)
			(xy 62.265541 -166.411897) (xy 62.310899 -166.379446) (xy 62.360499 -166.353945) (xy 62.413283 -166.335938)
			(xy 62.468126 -166.325808) (xy 62.52386 -166.323771) (xy 62.579297 -166.329871) (xy 62.633254 -166.343977)
			(xy 62.684583 -166.365789) (xy 62.732189 -166.394843) (xy 62.775057 -166.430518) (xy 62.812274 -166.472055)
			(xy 62.843047 -166.518568) (xy 62.866719 -166.569065) (xy 62.882787 -166.622472) (xy 62.890907 -166.677648)
			(xy 62.891416 -166.705534) (xy 62.890907 -166.73342) (xy 62.882787 -166.788596) (xy 62.866719 -166.842003)
			(xy 62.843047 -166.8925) (xy 62.812274 -166.939013) (xy 62.775057 -166.98055) (xy 62.732189 -167.016225)
			(xy 62.684583 -167.045279) (xy 62.633254 -167.067091) (xy 62.579297 -167.081197) (xy 62.52386 -167.087297)
			(xy 62.468126 -167.08526) (xy 62.413283 -167.07513) (xy 62.360499 -167.057123) (xy 62.310899 -167.031622)
			(xy 62.265541 -166.999171) (xy 62.225392 -166.960462) (xy 62.191306 -166.916319) (xy 62.16401 -166.867684)
			(xy 62.144087 -166.815593) (xy 62.131961 -166.761156) (xy 62.12789 -166.705534) (xy 61.875416 -166.705534)
			(xy 61.874907 -166.73342) (xy 61.866787 -166.788596) (xy 61.850719 -166.842003) (xy 61.827047 -166.8925)
			(xy 61.796274 -166.939013) (xy 61.759057 -166.98055) (xy 61.716189 -167.016225) (xy 61.668583 -167.045279)
			(xy 61.617254 -167.067091) (xy 61.563297 -167.081197) (xy 61.50786 -167.087297) (xy 61.452126 -167.08526)
			(xy 61.397283 -167.07513) (xy 61.344499 -167.057123) (xy 61.294899 -167.031622) (xy 61.249541 -166.999171)
			(xy 61.209392 -166.960462) (xy 61.175306 -166.916319) (xy 61.14801 -166.867684) (xy 61.128087 -166.815593)
			(xy 61.115961 -166.761156) (xy 61.11189 -166.705534) (xy 28.176474 -166.705534) (xy 28.176474 -172.329348)
			(xy 61.847982 -172.329348) (xy 61.852053 -172.273726) (xy 61.864179 -172.219289) (xy 61.884102 -172.167198)
			(xy 61.911398 -172.118563) (xy 61.945484 -172.07442) (xy 61.985633 -172.035711) (xy 62.030991 -172.00326)
			(xy 62.080591 -171.977759) (xy 62.133375 -171.959752) (xy 62.188218 -171.949622) (xy 62.243952 -171.947585)
			(xy 62.299389 -171.953685) (xy 62.353346 -171.967791) (xy 62.404675 -171.989603) (xy 62.452281 -172.018657)
			(xy 62.495149 -172.054332) (xy 62.532366 -172.095869) (xy 62.563139 -172.142382) (xy 62.586811 -172.192879)
			(xy 62.602879 -172.246286) (xy 62.610999 -172.301462) (xy 62.611508 -172.329348) (xy 62.611244 -172.343826)
			(xy 62.785242 -172.343826) (xy 62.789313 -172.288204) (xy 62.801439 -172.233767) (xy 62.821362 -172.181676)
			(xy 62.848658 -172.133041) (xy 62.882744 -172.088898) (xy 62.922893 -172.050189) (xy 62.968251 -172.017738)
			(xy 63.017851 -171.992237) (xy 63.070635 -171.97423) (xy 63.125478 -171.9641) (xy 63.181212 -171.962063)
			(xy 63.236649 -171.968163) (xy 63.290606 -171.982269) (xy 63.341935 -172.004081) (xy 63.389541 -172.033135)
			(xy 63.432409 -172.06881) (xy 63.469626 -172.110347) (xy 63.500399 -172.15686) (xy 63.524071 -172.207357)
			(xy 63.540139 -172.260764) (xy 63.548259 -172.31594) (xy 63.548768 -172.343826) (xy 63.548259 -172.371712)
			(xy 63.540139 -172.426888) (xy 63.524071 -172.480295) (xy 63.500399 -172.530792) (xy 63.469626 -172.577305)
			(xy 63.432409 -172.618842) (xy 63.389541 -172.654517) (xy 63.341935 -172.683571) (xy 63.290606 -172.705383)
			(xy 63.236649 -172.719489) (xy 63.181212 -172.725589) (xy 63.125478 -172.723552) (xy 63.070635 -172.713422)
			(xy 63.017851 -172.695415) (xy 62.968251 -172.669914) (xy 62.922893 -172.637463) (xy 62.882744 -172.598754)
			(xy 62.848658 -172.554611) (xy 62.821362 -172.505976) (xy 62.801439 -172.453885) (xy 62.789313 -172.399448)
			(xy 62.785242 -172.343826) (xy 62.611244 -172.343826) (xy 62.610999 -172.357234) (xy 62.602879 -172.41241)
			(xy 62.586811 -172.465817) (xy 62.563139 -172.516314) (xy 62.532366 -172.562827) (xy 62.495149 -172.604364)
			(xy 62.452281 -172.640039) (xy 62.404675 -172.669093) (xy 62.353346 -172.690905) (xy 62.299389 -172.705011)
			(xy 62.243952 -172.711111) (xy 62.188218 -172.709074) (xy 62.133375 -172.698944) (xy 62.080591 -172.680937)
			(xy 62.030991 -172.655436) (xy 61.985633 -172.622985) (xy 61.945484 -172.584276) (xy 61.911398 -172.540133)
			(xy 61.884102 -172.491498) (xy 61.864179 -172.439407) (xy 61.852053 -172.38497) (xy 61.847982 -172.329348)
			(xy 28.176474 -172.329348) (xy 28.176474 -173.886876) (xy 28.176979 -173.896927) (xy 28.184699 -173.915489)
			(xy 28.19146 -173.922944) (xy 29.332428 -175.063912) (xy 29.339824 -175.070764) (xy 29.358423 -175.078502)
			(xy 29.368496 -175.078898)
		)
		(stroke
			(width 0)
			(type solid)
		)
		(fill yes)
		(layer "In15.Cu")
		(net "GND")
	)
	(gr_poly
		(pts
			(xy 136.570466 -165.460172) (xy 136.580339 -165.459703) (xy 136.598623 -165.452244) (xy 136.606026 -165.445694)
			(xy 136.60628 -165.44544) (xy 138.596624 -163.455096) (xy 138.597132 -163.454588) (xy 138.603723 -163.44721)
			(xy 138.611191 -163.428911) (xy 138.61161 -163.419028) (xy 138.61161 -154.245564) (xy 138.611038 -154.233651)
			(xy 138.600444 -154.212316) (xy 138.59129 -154.20467) (xy 138.516106 -154.14879) (xy 138.492484 -154.144472)
			(xy 138.4808 -154.148028) (xy 138.454112 -154.155487) (xy 138.399286 -154.163526) (xy 138.37158 -154.16403)
			(xy 138.344329 -154.163543) (xy 138.290382 -154.155784) (xy 138.238089 -154.140428) (xy 138.188513 -154.117786)
			(xy 138.142663 -154.088319) (xy 138.101474 -154.052628) (xy 138.065782 -154.011438) (xy 138.036315 -153.965589)
			(xy 138.013673 -153.916013) (xy 137.998316 -153.86372) (xy 137.990557 -153.809773) (xy 137.990072 -153.782522)
			(xy 137.990684 -153.752081) (xy 138.000376 -153.691975) (xy 138.009376 -153.662888) (xy 138.013186 -153.651204)
			(xy 138.009376 -153.627074) (xy 137.96137 -153.560526) (xy 137.953758 -153.551144) (xy 137.932284 -153.540146)
			(xy 137.920222 -153.539444) (xy 136.790938 -153.539444) (xy 136.778867 -153.540114) (xy 136.757379 -153.551116)
			(xy 136.74979 -153.560526) (xy 136.701784 -153.627074) (xy 136.697974 -153.651204) (xy 136.701784 -153.662888)
			(xy 136.710789 -153.691974) (xy 136.720492 -153.75208) (xy 136.721088 -153.782522) (xy 136.720602 -153.809773)
			(xy 136.712846 -153.863721) (xy 136.697491 -153.916016) (xy 136.674849 -153.965593) (xy 136.645383 -154.011443)
			(xy 136.609692 -154.052634) (xy 136.568501 -154.088325) (xy 136.522651 -154.117791) (xy 136.473074 -154.140433)
			(xy 136.420779 -154.155788) (xy 136.366831 -154.163544) (xy 136.312329 -154.163544) (xy 136.258381 -154.155788)
			(xy 136.206086 -154.140433) (xy 136.156509 -154.117791) (xy 136.110659 -154.088325) (xy 136.069468 -154.052634)
			(xy 136.033777 -154.011443) (xy 136.004311 -153.965593) (xy 135.981669 -153.916016) (xy 135.966314 -153.863721)
			(xy 135.958558 -153.809773) (xy 135.958072 -153.782522) (xy 135.958684 -153.752081) (xy 135.968376 -153.691975)
			(xy 135.977376 -153.662888) (xy 135.981186 -153.651204) (xy 135.977376 -153.627074) (xy 135.92937 -153.560526)
			(xy 135.921758 -153.551144) (xy 135.900284 -153.540146) (xy 135.888222 -153.539444) (xy 133.76783 -153.539444)
			(xy 133.757841 -153.539977) (xy 133.739405 -153.547688) (xy 133.732016 -153.55443) (xy 133.644386 -153.64206)
			(xy 133.63829 -153.672032) (xy 133.644386 -153.686256) (xy 133.653493 -153.709426) (xy 133.666293 -153.757536)
			(xy 133.672709 -153.806905) (xy 133.673088 -153.831798) (xy 133.672625 -153.85905) (xy 133.664868 -153.913)
			(xy 133.649512 -153.965297) (xy 133.626869 -154.014877) (xy 133.597401 -154.060728) (xy 133.561707 -154.10192)
			(xy 133.520514 -154.137612) (xy 133.474661 -154.167078) (xy 133.425081 -154.189718) (xy 133.372783 -154.205072)
			(xy 133.318832 -154.212826) (xy 133.29158 -154.213306) (xy 133.262239 -154.212773) (xy 133.204247 -154.203795)
			(xy 133.148316 -154.186038) (xy 133.095766 -154.159921) (xy 133.047837 -154.126062) (xy 133.005661 -154.08526)
			(xy 132.987542 -154.062176) (xy 132.980938 -154.053286) (xy 132.961634 -154.043126) (xy 132.874258 -154.03703)
			(xy 132.863351 -154.036766) (xy 132.842934 -154.044395) (xy 132.834888 -154.051762) (xy 132.689854 -154.196796)
			(xy 132.666299 -154.219742) (xy 132.6149 -154.260762) (xy 132.559229 -154.295766) (xy 132.499987 -154.324313)
			(xy 132.437919 -154.346042) (xy 132.373808 -154.360682) (xy 132.308461 -154.368047) (xy 132.27558 -154.3685)
			(xy 132.24081 -154.368003) (xy 132.171758 -154.359769) (xy 132.104167 -154.343418) (xy 132.038986 -154.319182)
			(xy 131.977133 -154.287401) (xy 131.919476 -154.248521) (xy 131.866828 -154.20309) (xy 131.843018 -154.177746)
			(xy 131.835906 -154.169872) (xy 131.817364 -154.16149) (xy 131.73329 -154.159458) (xy 131.722962 -154.159733)
			(xy 131.703823 -154.167464) (xy 131.696206 -154.174444) (xy 131.673854 -154.196796) (xy 131.650299 -154.219742)
			(xy 131.5989 -154.260762) (xy 131.543229 -154.295766) (xy 131.483987 -154.324313) (xy 131.421919 -154.346042)
			(xy 131.357808 -154.360682) (xy 131.292461 -154.368047) (xy 131.25958 -154.3685) (xy 131.224173 -154.367985)
			(xy 131.153875 -154.359445) (xy 131.08512 -154.342491) (xy 131.018911 -154.31737) (xy 130.956214 -154.284451)
			(xy 130.897943 -154.244212) (xy 130.844949 -154.19724) (xy 130.798004 -154.144222) (xy 130.757795 -154.085931)
			(xy 130.724907 -154.023217) (xy 130.699821 -153.956995) (xy 130.682902 -153.888231) (xy 130.674397 -153.817929)
			(xy 130.673856 -153.782522) (xy 130.674282 -153.749647) (xy 130.681611 -153.684308) (xy 130.696214 -153.620202)
			(xy 130.717905 -153.558134) (xy 130.746412 -153.498887) (xy 130.781377 -153.443206) (xy 130.822359 -153.391793)
			(xy 130.845306 -153.368248) (xy 131.485894 -152.72766) (xy 131.509449 -152.704714) (xy 131.560847 -152.663695)
			(xy 131.616519 -152.628692) (xy 131.675761 -152.600148) (xy 131.737829 -152.578421) (xy 131.80194 -152.563785)
			(xy 131.867288 -152.556424) (xy 131.900168 -152.555956) (xy 131.988814 -152.555956) (xy 131.998779 -152.555478)
			(xy 132.017213 -152.547899) (xy 132.024628 -152.541224) (xy 132.340096 -152.22601) (xy 132.346782 -152.21861)
			(xy 132.354388 -152.200195) (xy 132.354402 -152.180272) (xy 132.351018 -152.170892) (xy 132.310124 -152.070054)
			(xy 132.284978 -152.052782) (xy 132.269738 -152.052528) (xy 132.242757 -152.051653) (xy 132.189436 -152.043236)
			(xy 132.137834 -152.027387) (xy 132.088982 -152.004422) (xy 132.043855 -151.974798) (xy 132.003354 -151.939109)
			(xy 131.96829 -151.898067) (xy 131.939361 -151.852492) (xy 131.917147 -151.803293) (xy 131.902089 -151.751455)
			(xy 131.894491 -151.698011) (xy 131.894072 -151.67102) (xy 131.894558 -151.643769) (xy 131.902314 -151.589821)
			(xy 131.917669 -151.537526) (xy 131.940311 -151.487949) (xy 131.969777 -151.442099) (xy 132.005468 -151.400908)
			(xy 132.046659 -151.365217) (xy 132.092509 -151.335751) (xy 132.142086 -151.313109) (xy 132.194381 -151.297754)
			(xy 132.248329 -151.289998) (xy 132.302831 -151.289998) (xy 132.356779 -151.297754) (xy 132.409074 -151.313109)
			(xy 132.458651 -151.335751) (xy 132.504501 -151.365217) (xy 132.545692 -151.400908) (xy 132.581383 -151.442099)
			(xy 132.610849 -151.487949) (xy 132.633491 -151.537526) (xy 132.648846 -151.589821) (xy 132.656602 -151.643769)
			(xy 132.657088 -151.67102) (xy 132.656485 -151.701927) (xy 132.646523 -151.762934) (xy 132.637276 -151.792432)
			(xy 132.63245 -151.806402) (xy 132.639054 -151.834088) (xy 132.649468 -151.844502) (xy 132.656834 -151.851342)
			(xy 132.675367 -151.859084) (xy 132.695451 -151.859084) (xy 132.713984 -151.851342) (xy 132.72135 -151.844502)
			(xy 132.732526 -151.833326) (xy 132.754756 -151.811676) (xy 132.803025 -151.772676) (xy 132.855136 -151.738982)
			(xy 132.88264 -151.724614) (xy 132.890486 -151.720206) (xy 132.902699 -151.707003) (xy 132.909622 -151.690404)
			(xy 132.910326 -151.681434) (xy 132.91186 -151.654925) (xy 132.92135 -151.602681) (xy 132.937993 -151.552257)
			(xy 132.961469 -151.504629) (xy 132.991323 -151.460717) (xy 133.026978 -151.42137) (xy 133.067746 -151.387348)
			(xy 133.112838 -151.359308) (xy 133.161383 -151.337793) (xy 133.212443 -151.323218) (xy 133.26503 -151.315865)
			(xy 133.29158 -151.31542) (xy 133.320643 -151.315964) (xy 133.378096 -151.324776) (xy 133.433548 -151.3422)
			(xy 133.485716 -151.367833) (xy 133.533393 -151.40108) (xy 133.575476 -151.441175) (xy 133.610991 -151.487187)
			(xy 133.639117 -151.538054) (xy 133.659204 -151.592599) (xy 133.665468 -151.620982) (xy 133.669024 -151.638762)
			(xy 133.697218 -151.661876) (xy 134.060692 -151.661876) (xy 134.072784 -151.661131) (xy 134.094258 -151.64999)
			(xy 134.10184 -151.64054) (xy 134.157212 -151.563578) (xy 134.160768 -151.539448) (xy 134.156958 -151.527764)
			(xy 134.147708 -151.498333) (xy 134.137761 -151.437451) (xy 134.137146 -151.406606) (xy 134.137632 -151.379355)
			(xy 134.145388 -151.325407) (xy 134.160743 -151.273112) (xy 134.183385 -151.223535) (xy 134.212851 -151.177685)
			(xy 134.248542 -151.136494) (xy 134.289733 -151.100803) (xy 134.335583 -151.071337) (xy 134.38516 -151.048695)
			(xy 134.437455 -151.03334) (xy 134.491403 -151.025584) (xy 134.545905 -151.025584) (xy 134.599853 -151.03334)
			(xy 134.652148 -151.048695) (xy 134.701725 -151.071337) (xy 134.747575 -151.100803) (xy 134.788766 -151.136494)
			(xy 134.824457 -151.177685) (xy 134.853923 -151.223535) (xy 134.876565 -151.273112) (xy 134.89192 -151.325407)
			(xy 134.899676 -151.379355) (xy 134.900162 -151.406606) (xy 134.899548 -151.43745) (xy 134.889596 -151.498332)
			(xy 134.88035 -151.527764) (xy 134.87654 -151.539448) (xy 134.880096 -151.563578) (xy 134.935468 -151.64054)
			(xy 134.94304 -151.649997) (xy 134.964523 -151.66112) (xy 134.976616 -151.661876) (xy 135.36168 -151.661876)
			(xy 135.371404 -151.661398) (xy 135.389433 -151.654094) (xy 135.396732 -151.647652) (xy 135.454644 -151.59228)
			(xy 135.462772 -151.574754) (xy 135.46328 -151.564848) (xy 135.465066 -151.537206) (xy 135.475624 -151.48283)
			(xy 135.493937 -151.430554) (xy 135.519619 -151.381477) (xy 135.55213 -151.33663) (xy 135.590786 -151.296958)
			(xy 135.634774 -151.263295) (xy 135.683168 -151.236349) (xy 135.734952 -151.216686) (xy 135.789035 -151.20472)
			(xy 135.84428 -151.200703) (xy 135.899525 -151.20472) (xy 135.953608 -151.216686) (xy 136.005392 -151.236349)
			(xy 136.053786 -151.263295) (xy 136.097774 -151.296958) (xy 136.13643 -151.33663) (xy 136.168941 -151.381477)
			(xy 136.194623 -151.430554) (xy 136.212936 -151.48283) (xy 136.223494 -151.537206) (xy 136.22528 -151.564848)
			(xy 136.225788 -151.574754) (xy 136.233916 -151.59228) (xy 136.291828 -151.647652) (xy 136.299125 -151.654101)
			(xy 136.317153 -151.661419) (xy 136.32688 -151.661876) (xy 136.925304 -151.661876) (xy 136.935323 -151.661455)
			(xy 136.953834 -151.653784) (xy 136.967999 -151.639611) (xy 136.975661 -151.621095) (xy 136.976104 -151.611076)
			(xy 136.976104 -151.608536) (xy 136.97585 -151.605996) (xy 136.974072 -151.569166) (xy 136.974558 -151.541915)
			(xy 136.982314 -151.487967) (xy 136.997669 -151.435672) (xy 137.020311 -151.386095) (xy 137.049777 -151.340245)
			(xy 137.085468 -151.299054) (xy 137.126659 -151.263363) (xy 137.172509 -151.233897) (xy 137.222086 -151.211255)
			(xy 137.274381 -151.1959) (xy 137.328329 -151.188144) (xy 137.382831 -151.188144) (xy 137.436779 -151.1959)
			(xy 137.489074 -151.211255) (xy 137.538651 -151.233897) (xy 137.584501 -151.263363) (xy 137.625692 -151.299054)
			(xy 137.661383 -151.340245) (xy 137.690849 -151.386095) (xy 137.713491 -151.435672) (xy 137.728846 -151.487967)
			(xy 137.736602 -151.541915) (xy 137.737088 -151.569166) (xy 137.73531 -151.605996) (xy 137.735056 -151.608536)
			(xy 137.735056 -151.611076) (xy 137.735539 -151.62109) (xy 137.743193 -151.639598) (xy 137.757345 -151.653769)
			(xy 137.775843 -151.661447) (xy 137.785856 -151.661876) (xy 138.15314 -151.661876) (xy 138.163206 -151.661445)
			(xy 138.181798 -151.653718) (xy 138.189208 -151.64689) (xy 138.596624 -151.23922) (xy 138.60343 -151.231874)
			(xy 138.611146 -151.21341) (xy 138.61161 -151.203406) (xy 138.61161 -148.201634) (xy 138.61097 -148.189652)
			(xy 138.600098 -148.168301) (xy 138.590782 -148.16074) (xy 138.514582 -148.105114) (xy 138.490706 -148.101304)
			(xy 138.479022 -148.10486) (xy 138.450871 -148.113264) (xy 138.392825 -148.122328) (xy 138.363452 -148.122894)
			(xy 138.336204 -148.122404) (xy 138.282264 -148.114643) (xy 138.229977 -148.099284) (xy 138.180407 -148.076641)
			(xy 138.134565 -148.047175) (xy 138.093382 -148.011484) (xy 138.057697 -147.970297) (xy 138.028236 -147.924451)
			(xy 138.005599 -147.874878) (xy 137.990247 -147.822589) (xy 137.982492 -147.768648) (xy 137.982492 -147.714152)
			(xy 137.990247 -147.66021) (xy 138.005599 -147.607922) (xy 138.028236 -147.558349) (xy 138.057697 -147.512503)
			(xy 138.093382 -147.471316) (xy 138.134565 -147.435625) (xy 138.180407 -147.406159) (xy 138.229977 -147.383516)
			(xy 138.282264 -147.368157) (xy 138.336204 -147.360396) (xy 138.363452 -147.359878) (xy 138.392827 -147.360436)
			(xy 138.450875 -147.369491) (xy 138.479022 -147.377912) (xy 138.490706 -147.381468) (xy 138.514582 -147.377658)
			(xy 138.590782 -147.322032) (xy 138.600042 -147.314426) (xy 138.610907 -147.2931) (xy 138.61161 -147.281138)
			(xy 138.61161 -122.518932) (xy 138.611175 -122.508867) (xy 138.603444 -122.490279) (xy 138.596624 -122.482864)
			(xy 136.162542 -120.048782) (xy 136.155694 -120.041385) (xy 136.147959 -120.022786) (xy 136.147556 -120.012714)
			(xy 136.147556 -119.426482) (xy 136.147128 -119.416414) (xy 136.139404 -119.397819) (xy 136.13257 -119.390414)
			(xy 135.692388 -118.950232) (xy 135.663178 -118.943882) (xy 135.648954 -118.94947) (xy 135.620316 -118.95975)
			(xy 135.560501 -118.970873) (xy 135.530082 -118.971568) (xy 132.307076 -118.971568) (xy 132.29711 -118.972046)
			(xy 132.278671 -118.979619) (xy 132.271262 -118.9863) (xy 131.769358 -119.488204) (xy 131.763008 -119.498872)
			(xy 131.760976 -119.504714) (xy 131.752538 -119.53027) (xy 131.729483 -119.578901) (xy 131.699823 -119.623809)
			(xy 131.664149 -119.664105) (xy 131.623166 -119.698989) (xy 131.577689 -119.727769) (xy 131.52862 -119.749875)
			(xy 131.476931 -119.764866) (xy 131.423649 -119.772447) (xy 131.39674 -119.772938) (xy 131.369484 -119.772478)
			(xy 131.315528 -119.764726) (xy 131.263223 -119.749373) (xy 131.213636 -119.726734) (xy 131.167776 -119.697267)
			(xy 131.126576 -119.661574) (xy 131.090875 -119.62038) (xy 131.0614 -119.574526) (xy 131.038751 -119.524943)
			(xy 131.023389 -119.472641) (xy 131.015627 -119.418685) (xy 131.015232 -119.39143) (xy 131.015692 -119.364517)
			(xy 131.023256 -119.311226) (xy 131.038238 -119.259528) (xy 131.060341 -119.21045) (xy 131.089124 -119.164967)
			(xy 131.124016 -119.123984) (xy 131.164325 -119.088313) (xy 131.209249 -119.058665) (xy 131.257895 -119.035628)
			(xy 131.283456 -119.027194) (xy 131.289298 -119.025162) (xy 131.299966 -119.018812) (xy 131.490974 -118.827804)
			(xy 131.497752 -118.820414) (xy 131.505387 -118.801889) (xy 131.505335 -118.781853) (xy 131.501896 -118.772432)
			(xy 131.496054 -118.758208) (xy 131.470654 -118.74119) (xy 127.545084 -118.74119) (xy 127.535015 -118.741616)
			(xy 127.516414 -118.749333) (xy 127.509016 -118.756176) (xy 127.38227 -118.882922) (xy 127.374787 -118.891271)
			(xy 127.367267 -118.912363) (xy 127.367792 -118.923562) (xy 127.376428 -119.013224) (xy 127.388112 -119.032528)
			(xy 127.397764 -119.039132) (xy 127.419687 -119.05439) (xy 127.459445 -119.090056) (xy 127.493843 -119.130918)
			(xy 127.522208 -119.176175) (xy 127.543986 -119.224946) (xy 127.558752 -119.276276) (xy 127.566217 -119.329164)
			(xy 127.566674 -119.35587) (xy 127.819148 -119.35587) (xy 127.823219 -119.300248) (xy 127.835345 -119.245811)
			(xy 127.855268 -119.19372) (xy 127.882564 -119.145085) (xy 127.91665 -119.100942) (xy 127.956799 -119.062233)
			(xy 128.002157 -119.029782) (xy 128.051757 -119.004281) (xy 128.104541 -118.986274) (xy 128.159384 -118.976144)
			(xy 128.215118 -118.974107) (xy 128.270555 -118.980207) (xy 128.324512 -118.994313) (xy 128.375841 -119.016125)
			(xy 128.423447 -119.045179) (xy 128.466315 -119.080854) (xy 128.503532 -119.122391) (xy 128.534305 -119.168904)
			(xy 128.557977 -119.219401) (xy 128.574045 -119.272808) (xy 128.582165 -119.327984) (xy 128.582674 -119.35587)
			(xy 128.582165 -119.383756) (xy 128.574045 -119.438932) (xy 128.557977 -119.492339) (xy 128.534305 -119.542836)
			(xy 128.503532 -119.589349) (xy 128.466315 -119.630886) (xy 128.423447 -119.666561) (xy 128.375841 -119.695615)
			(xy 128.324512 -119.717427) (xy 128.270555 -119.731533) (xy 128.215118 -119.737633) (xy 128.159384 -119.735596)
			(xy 128.104541 -119.725466) (xy 128.051757 -119.707459) (xy 128.002157 -119.681958) (xy 127.956799 -119.649507)
			(xy 127.91665 -119.610798) (xy 127.882564 -119.566655) (xy 127.855268 -119.51802) (xy 127.835345 -119.465929)
			(xy 127.823219 -119.411492) (xy 127.819148 -119.35587) (xy 127.566674 -119.35587) (xy 127.566213 -119.383123)
			(xy 127.558459 -119.437076) (xy 127.543105 -119.489375) (xy 127.520464 -119.538957) (xy 127.490996 -119.584811)
			(xy 127.455302 -119.626005) (xy 127.414108 -119.661699) (xy 127.368253 -119.691166) (xy 127.318671 -119.713807)
			(xy 127.266372 -119.72916) (xy 127.212419 -119.736913) (xy 127.185166 -119.737378) (xy 127.165139 -119.737121)
			(xy 127.125305 -119.732917) (xy 127.105664 -119.728996) (xy 127.094488 -119.72671) (xy 127.072136 -119.732044)
			(xy 127.001778 -119.78894) (xy 126.993378 -119.796555) (xy 126.98362 -119.81699) (xy 126.982982 -119.82831)
			(xy 126.982982 -121.57075) (xy 129.719832 -121.57075) (xy 129.720262 -121.544433) (xy 129.727485 -121.492298)
			(xy 129.741802 -121.441649) (xy 129.762941 -121.393446) (xy 129.790501 -121.348605) (xy 129.823959 -121.307975)
			(xy 129.843022 -121.289826) (xy 129.850417 -121.2823) (xy 129.858945 -121.263023) (xy 129.859532 -121.252488)
			(xy 129.859532 -121.177812) (xy 129.859001 -121.167263) (xy 129.850466 -121.147968) (xy 129.843022 -121.140474)
			(xy 129.823934 -121.122348) (xy 129.790456 -121.081726) (xy 129.762886 -121.036884) (xy 129.741749 -120.988675)
			(xy 129.727446 -120.938015) (xy 129.720251 -120.88587) (xy 129.719832 -120.85955) (xy 129.720318 -120.832299)
			(xy 129.728074 -120.778351) (xy 129.743429 -120.726056) (xy 129.766071 -120.676479) (xy 129.795537 -120.630629)
			(xy 129.831228 -120.589438) (xy 129.872419 -120.553747) (xy 129.918269 -120.524281) (xy 129.967846 -120.501639)
			(xy 130.020141 -120.486284) (xy 130.074089 -120.478528) (xy 130.128591 -120.478528) (xy 130.182539 -120.486284)
			(xy 130.234834 -120.501639) (xy 130.284411 -120.524281) (xy 130.330261 -120.553747) (xy 130.371452 -120.589438)
			(xy 130.407143 -120.630629) (xy 130.436609 -120.676479) (xy 130.459251 -120.726056) (xy 130.474606 -120.778351)
			(xy 130.482362 -120.832299) (xy 130.482848 -120.85955) (xy 130.482393 -120.885866) (xy 130.475171 -120.937999)
			(xy 130.460857 -120.988647) (xy 130.439723 -121.036848) (xy 130.412169 -121.08169) (xy 130.378717 -121.122323)
			(xy 130.359658 -121.140474) (xy 130.352274 -121.148011) (xy 130.343738 -121.167279) (xy 130.343148 -121.177812)
			(xy 130.343148 -121.252488) (xy 130.343656 -121.263041) (xy 130.352204 -121.282337) (xy 130.359658 -121.289826)
			(xy 130.378742 -121.307956) (xy 130.412221 -121.348577) (xy 130.439792 -121.393418) (xy 130.46093 -121.441626)
			(xy 130.475233 -121.492285) (xy 130.482429 -121.54443) (xy 130.482848 -121.57075) (xy 130.482362 -121.598001)
			(xy 130.474606 -121.651949) (xy 130.459251 -121.704244) (xy 130.436609 -121.753821) (xy 130.407143 -121.799671)
			(xy 130.371452 -121.840862) (xy 130.330261 -121.876553) (xy 130.284411 -121.906019) (xy 130.234834 -121.928661)
			(xy 130.182539 -121.944016) (xy 130.128591 -121.951772) (xy 130.074089 -121.951772) (xy 130.020141 -121.944016)
			(xy 129.967846 -121.928661) (xy 129.918269 -121.906019) (xy 129.872419 -121.876553) (xy 129.831228 -121.840862)
			(xy 129.795537 -121.799671) (xy 129.766071 -121.753821) (xy 129.743429 -121.704244) (xy 129.728074 -121.651949)
			(xy 129.720318 -121.598001) (xy 129.719832 -121.57075) (xy 126.982982 -121.57075) (xy 126.982982 -122.121168)
			(xy 126.983452 -122.131106) (xy 126.991008 -122.149491) (xy 127.004994 -122.163614) (xy 127.01397 -122.167904)
			(xy 127.113792 -122.210576) (xy 127.143764 -122.204988) (xy 127.15494 -122.194574) (xy 127.176367 -122.174778)
			(xy 127.224114 -122.14127) (xy 127.276409 -122.115427) (xy 127.33203 -122.097853) (xy 127.38968 -122.088958)
			(xy 127.418846 -122.088402) (xy 127.446094 -122.088891) (xy 127.500036 -122.096653) (xy 127.552323 -122.112012)
			(xy 127.601893 -122.134655) (xy 127.647737 -122.164122) (xy 127.68892 -122.199812) (xy 127.724606 -122.241)
			(xy 127.754067 -122.286847) (xy 127.776704 -122.33642) (xy 127.792057 -122.388709) (xy 127.799812 -122.442652)
			(xy 127.799812 -122.497148) (xy 127.792057 -122.551091) (xy 127.776704 -122.60338) (xy 127.754067 -122.652953)
			(xy 127.724606 -122.6988) (xy 127.68892 -122.739988) (xy 127.647737 -122.775678) (xy 127.601893 -122.805145)
			(xy 127.552323 -122.827788) (xy 127.500036 -122.843147) (xy 127.446094 -122.850909) (xy 127.418846 -122.851418)
			(xy 127.389684 -122.85084) (xy 127.332045 -122.841918) (xy 127.276432 -122.824336) (xy 127.22414 -122.798503)
			(xy 127.176384 -122.765019) (xy 127.15494 -122.745246) (xy 127.143764 -122.734832) (xy 127.113792 -122.729244)
			(xy 126.999746 -122.778012) (xy 126.982982 -122.803412) (xy 126.982982 -122.809) (xy 126.54223 -123.249752)
			(xy 128.009867 -123.249752) (xy 128.009867 -123.195248) (xy 128.017624 -123.141298) (xy 128.03298 -123.089002)
			(xy 128.055622 -123.039423) (xy 128.085089 -122.993571) (xy 128.120782 -122.95238) (xy 128.161974 -122.916687)
			(xy 128.207826 -122.88722) (xy 128.257405 -122.864579) (xy 128.309702 -122.849223) (xy 128.363652 -122.841467)
			(xy 128.390904 -122.841004) (xy 128.417934 -122.841497) (xy 128.471452 -122.849135) (xy 128.523353 -122.864259)
			(xy 128.572597 -122.886563) (xy 128.618196 -122.915602) (xy 128.659234 -122.950791) (xy 128.677416 -122.970798)
			(xy 128.684782 -122.978926) (xy 128.704594 -122.98807) (xy 128.802638 -122.988324) (xy 128.82245 -122.979434)
			(xy 128.829816 -122.971306) (xy 128.847975 -122.951581) (xy 128.888876 -122.916917) (xy 128.934232 -122.888329)
			(xy 128.983148 -122.86638) (xy 129.034657 -122.851505) (xy 129.087743 -122.843997) (xy 129.11455 -122.843544)
			(xy 129.14192 -122.844029) (xy 129.196098 -122.85184) (xy 129.248602 -122.867324) (xy 129.298349 -122.890162)
			(xy 129.344316 -122.919884) (xy 129.365248 -122.937524) (xy 129.37236 -122.94362) (xy 129.389378 -122.94997)
			(xy 129.474722 -122.94997) (xy 129.49174 -122.94362) (xy 129.498852 -122.937524) (xy 129.519785 -122.919883)
			(xy 129.565753 -122.890159) (xy 129.615499 -122.867313) (xy 129.668001 -122.851817) (xy 129.722179 -122.843988)
			(xy 129.776921 -122.843988) (xy 129.831099 -122.851817) (xy 129.883601 -122.867313) (xy 129.933347 -122.890159)
			(xy 129.979315 -122.919883) (xy 130.000248 -122.937524) (xy 130.00736 -122.94362) (xy 130.024378 -122.94997)
			(xy 130.109722 -122.94997) (xy 130.12674 -122.94362) (xy 130.133852 -122.937524) (xy 130.146653 -122.926579)
			(xy 130.173869 -122.906735) (xy 130.188208 -122.8979) (xy 130.197352 -122.892566) (xy 130.209544 -122.875548)
			(xy 130.22961 -122.78233) (xy 130.225546 -122.761756) (xy 130.21945 -122.75312) (xy 130.203451 -122.729056)
			(xy 130.178109 -122.677124) (xy 130.160884 -122.621966) (xy 130.152168 -122.564842) (xy 130.151632 -122.53595)
			(xy 130.152118 -122.508699) (xy 130.159874 -122.454751) (xy 130.175229 -122.402456) (xy 130.197871 -122.352879)
			(xy 130.227337 -122.307029) (xy 130.263028 -122.265838) (xy 130.304219 -122.230147) (xy 130.350069 -122.200681)
			(xy 130.399646 -122.178039) (xy 130.451941 -122.162684) (xy 130.505889 -122.154928) (xy 130.560391 -122.154928)
			(xy 130.614339 -122.162684) (xy 130.666634 -122.178039) (xy 130.716211 -122.200681) (xy 130.762061 -122.230147)
			(xy 130.803252 -122.265838) (xy 130.838943 -122.307029) (xy 130.868409 -122.352879) (xy 130.891051 -122.402456)
			(xy 130.906406 -122.454751) (xy 130.914162 -122.508699) (xy 130.914648 -122.53595) (xy 130.914099 -122.564039)
			(xy 130.90588 -122.619613) (xy 130.889597 -122.673381) (xy 130.865603 -122.724177) (xy 130.834417 -122.770905)
			(xy 130.796714 -122.812552) (xy 130.753308 -122.848217) (xy 130.729482 -122.863102) (xy 130.720338 -122.868436)
			(xy 130.708146 -122.885454) (xy 130.68808 -122.978672) (xy 130.692144 -122.999246) (xy 130.69824 -123.007882)
			(xy 130.714239 -123.031946) (xy 130.739581 -123.083878) (xy 130.756807 -123.139036) (xy 130.765523 -123.19616)
			(xy 130.766058 -123.225052) (xy 130.7656 -123.252306) (xy 130.757848 -123.30626) (xy 130.742496 -123.358561)
			(xy 130.719855 -123.408144) (xy 130.690387 -123.454) (xy 130.654693 -123.495194) (xy 130.613498 -123.530889)
			(xy 130.567642 -123.560356) (xy 130.518059 -123.582996) (xy 130.465758 -123.598349) (xy 130.411804 -123.6061)
			(xy 130.38455 -123.60656) (xy 130.35718 -123.606074) (xy 130.303002 -123.598263) (xy 130.250498 -123.582779)
			(xy 130.200751 -123.559941) (xy 130.154784 -123.53022) (xy 130.133852 -123.51258) (xy 130.12674 -123.506484)
			(xy 130.109722 -123.500134) (xy 130.024378 -123.500134) (xy 130.00736 -123.506484) (xy 130.000248 -123.51258)
			(xy 129.979315 -123.530221) (xy 129.933347 -123.559945) (xy 129.883601 -123.582791) (xy 129.831099 -123.598287)
			(xy 129.776921 -123.606116) (xy 129.722179 -123.606116) (xy 129.668001 -123.598287) (xy 129.615499 -123.582791)
			(xy 129.565753 -123.559945) (xy 129.519785 -123.530221) (xy 129.498852 -123.51258) (xy 129.49174 -123.506484)
			(xy 129.474722 -123.500134) (xy 129.389378 -123.500134) (xy 129.37236 -123.506484) (xy 129.365248 -123.51258)
			(xy 129.344306 -123.530207) (xy 129.298336 -123.559921) (xy 129.248591 -123.58276) (xy 129.196093 -123.598254)
			(xy 129.141919 -123.606085) (xy 129.11455 -123.60656) (xy 129.08752 -123.606077) (xy 129.034003 -123.598433)
			(xy 128.982102 -123.583307) (xy 128.932859 -123.561) (xy 128.88726 -123.531961) (xy 128.846221 -123.496772)
			(xy 128.828038 -123.476766) (xy 128.820672 -123.468638) (xy 128.80086 -123.459494) (xy 128.702816 -123.45924)
			(xy 128.683004 -123.46813) (xy 128.675638 -123.476258) (xy 128.657465 -123.495969) (xy 128.616566 -123.530632)
			(xy 128.571212 -123.559221) (xy 128.522299 -123.581171) (xy 128.470793 -123.59605) (xy 128.41771 -123.603564)
			(xy 128.390904 -123.60402) (xy 128.363652 -123.603533) (xy 128.309702 -123.595777) (xy 128.257405 -123.580421)
			(xy 128.207826 -123.55778) (xy 128.161974 -123.528313) (xy 128.120782 -123.49262) (xy 128.085089 -123.451429)
			(xy 128.055622 -123.405577) (xy 128.03298 -123.355998) (xy 128.017624 -123.303702) (xy 128.009867 -123.249752)
			(xy 126.54223 -123.249752) (xy 125.320806 -124.471176) (xy 125.312964 -124.47991) (xy 125.305555 -124.502154)
			(xy 125.306582 -124.513848) (xy 125.319028 -124.605796) (xy 125.332236 -124.625354) (xy 125.34265 -124.63145)
			(xy 125.367467 -124.646064) (xy 125.412789 -124.681595) (xy 125.452254 -124.723537) (xy 125.484961 -124.770938)
			(xy 125.510169 -124.822718) (xy 125.527304 -124.8777) (xy 125.535975 -124.934633) (xy 125.536452 -124.963428)
			(xy 125.536143 -124.9807) (xy 126.928878 -124.9807) (xy 126.932949 -124.925078) (xy 126.945075 -124.870641)
			(xy 126.964998 -124.81855) (xy 126.992294 -124.769915) (xy 127.02638 -124.725772) (xy 127.066529 -124.687063)
			(xy 127.111887 -124.654612) (xy 127.161487 -124.629111) (xy 127.214271 -124.611104) (xy 127.269114 -124.600974)
			(xy 127.324848 -124.598937) (xy 127.380285 -124.605037) (xy 127.434242 -124.619143) (xy 127.485571 -124.640955)
			(xy 127.533177 -124.670009) (xy 127.576045 -124.705684) (xy 127.613262 -124.747221) (xy 127.644035 -124.793734)
			(xy 127.667707 -124.844231) (xy 127.683775 -124.897638) (xy 127.691895 -124.952814) (xy 127.692404 -124.9807)
			(xy 127.691895 -125.008586) (xy 127.683775 -125.063762) (xy 127.667707 -125.117169) (xy 127.644035 -125.167666)
			(xy 127.613262 -125.214179) (xy 127.576045 -125.255716) (xy 127.533177 -125.291391) (xy 127.485571 -125.320445)
			(xy 127.434242 -125.342257) (xy 127.380285 -125.356363) (xy 127.324848 -125.362463) (xy 127.269114 -125.360426)
			(xy 127.214271 -125.350296) (xy 127.161487 -125.332289) (xy 127.111887 -125.306788) (xy 127.066529 -125.274337)
			(xy 127.02638 -125.235628) (xy 126.992294 -125.191485) (xy 126.964998 -125.14285) (xy 126.945075 -125.090759)
			(xy 126.932949 -125.036322) (xy 126.928878 -124.9807) (xy 125.536143 -124.9807) (xy 125.535964 -124.990679)
			(xy 125.528205 -125.044626) (xy 125.512848 -125.09692) (xy 125.490206 -125.146497) (xy 125.460739 -125.192347)
			(xy 125.425048 -125.233537) (xy 125.383859 -125.26923) (xy 125.338011 -125.298698) (xy 125.288435 -125.321342)
			(xy 125.236142 -125.336701) (xy 125.182195 -125.344463) (xy 125.154944 -125.344936) (xy 125.126149 -125.344413)
			(xy 125.069214 -125.335757) (xy 125.014228 -125.318637) (xy 124.962442 -125.293441) (xy 124.915036 -125.260742)
			(xy 124.873087 -125.221285) (xy 124.837549 -125.175968) (xy 124.822966 -125.151134) (xy 124.81687 -125.14072)
			(xy 124.797312 -125.127512) (xy 124.705364 -125.115066) (xy 124.693673 -125.114064) (xy 124.671432 -125.121463)
			(xy 124.662692 -125.12929) (xy 124.388626 -125.403356) (xy 131.644136 -125.403356) (xy 131.644626 -125.375987)
			(xy 131.652437 -125.321808) (xy 131.66792 -125.269305) (xy 131.690756 -125.219558) (xy 131.720477 -125.17359)
			(xy 131.738116 -125.152658) (xy 131.744212 -125.145546) (xy 131.750562 -125.128528) (xy 131.750562 -125.043184)
			(xy 131.744212 -125.026166) (xy 131.738116 -125.019054) (xy 131.720491 -124.99811) (xy 131.690777 -124.952141)
			(xy 131.667938 -124.902396) (xy 131.652443 -124.849898) (xy 131.644612 -124.795724) (xy 131.644136 -124.768356)
			(xy 131.644622 -124.741105) (xy 131.652378 -124.687157) (xy 131.667733 -124.634862) (xy 131.690375 -124.585285)
			(xy 131.719841 -124.539435) (xy 131.755532 -124.498244) (xy 131.796723 -124.462553) (xy 131.842573 -124.433087)
			(xy 131.89215 -124.410445) (xy 131.944445 -124.39509) (xy 131.998393 -124.387334) (xy 132.052895 -124.387334)
			(xy 132.106843 -124.39509) (xy 132.159138 -124.410445) (xy 132.208715 -124.433087) (xy 132.254565 -124.462553)
			(xy 132.295756 -124.498244) (xy 132.331447 -124.539435) (xy 132.360913 -124.585285) (xy 132.383555 -124.634862)
			(xy 132.39891 -124.687157) (xy 132.406666 -124.741105) (xy 132.407152 -124.768356) (xy 132.406672 -124.795726)
			(xy 132.398859 -124.849905) (xy 132.383374 -124.902408) (xy 132.360535 -124.952155) (xy 132.330813 -124.998122)
			(xy 132.313172 -125.019054) (xy 132.307076 -125.026166) (xy 132.300726 -125.043184) (xy 132.300726 -125.128528)
			(xy 132.307076 -125.145546) (xy 132.313172 -125.152658) (xy 132.330801 -125.173599) (xy 132.360515 -125.219569)
			(xy 132.383353 -125.269314) (xy 132.398847 -125.321813) (xy 132.406677 -125.375987) (xy 132.407152 -125.403356)
			(xy 132.406666 -125.430607) (xy 132.39891 -125.484555) (xy 132.383555 -125.53685) (xy 132.360913 -125.586427)
			(xy 132.331447 -125.632277) (xy 132.295756 -125.673468) (xy 132.254565 -125.709159) (xy 132.208715 -125.738625)
			(xy 132.159138 -125.761267) (xy 132.106843 -125.776622) (xy 132.052895 -125.784378) (xy 131.998393 -125.784378)
			(xy 131.944445 -125.776622) (xy 131.89215 -125.761267) (xy 131.842573 -125.738625) (xy 131.796723 -125.709159)
			(xy 131.755532 -125.673468) (xy 131.719841 -125.632277) (xy 131.690375 -125.586427) (xy 131.667733 -125.53685)
			(xy 131.652378 -125.484555) (xy 131.644622 -125.430607) (xy 131.644136 -125.403356) (xy 124.388626 -125.403356)
			(xy 123.851924 -125.940058) (xy 123.845084 -125.947459) (xy 123.837367 -125.966057) (xy 123.836938 -125.976126)
			(xy 123.836938 -125.979428) (xy 124.772926 -125.979428) (xy 124.776997 -125.923806) (xy 124.789123 -125.869369)
			(xy 124.809046 -125.817278) (xy 124.836342 -125.768643) (xy 124.870428 -125.7245) (xy 124.910577 -125.685791)
			(xy 124.955935 -125.65334) (xy 125.005535 -125.627839) (xy 125.058319 -125.609832) (xy 125.113162 -125.599702)
			(xy 125.168896 -125.597665) (xy 125.224333 -125.603765) (xy 125.27829 -125.617871) (xy 125.329619 -125.639683)
			(xy 125.377225 -125.668737) (xy 125.420093 -125.704412) (xy 125.45731 -125.745949) (xy 125.488083 -125.792462)
			(xy 125.511755 -125.842959) (xy 125.527823 -125.896366) (xy 125.535943 -125.951542) (xy 125.536151 -125.962918)
			(xy 127.251204 -125.962918) (xy 127.255275 -125.907296) (xy 127.267401 -125.852859) (xy 127.287324 -125.800768)
			(xy 127.31462 -125.752133) (xy 127.348706 -125.70799) (xy 127.388855 -125.669281) (xy 127.434213 -125.63683)
			(xy 127.483813 -125.611329) (xy 127.536597 -125.593322) (xy 127.59144 -125.583192) (xy 127.647174 -125.581155)
			(xy 127.702611 -125.587255) (xy 127.756568 -125.601361) (xy 127.807897 -125.623173) (xy 127.855503 -125.652227)
			(xy 127.898371 -125.687902) (xy 127.935588 -125.729439) (xy 127.966361 -125.775952) (xy 127.990033 -125.826449)
			(xy 127.998231 -125.853698) (xy 132.584698 -125.853698) (xy 132.585163 -125.826328) (xy 132.592981 -125.772149)
			(xy 132.608471 -125.719646) (xy 132.631313 -125.669899) (xy 132.661037 -125.623932) (xy 132.678678 -125.603)
			(xy 132.684774 -125.595888) (xy 132.691124 -125.57887) (xy 132.691124 -125.493526) (xy 132.684774 -125.476508)
			(xy 132.678678 -125.469396) (xy 132.66102 -125.448479) (xy 132.631312 -125.402502) (xy 132.60848 -125.35275)
			(xy 132.592993 -125.300246) (xy 132.58517 -125.246068) (xy 132.584698 -125.218698) (xy 132.585184 -125.191447)
			(xy 132.59294 -125.137499) (xy 132.608295 -125.085204) (xy 132.630937 -125.035627) (xy 132.660403 -124.989777)
			(xy 132.696094 -124.948586) (xy 132.737285 -124.912895) (xy 132.783135 -124.883429) (xy 132.832712 -124.860787)
			(xy 132.885007 -124.845432) (xy 132.938955 -124.837676) (xy 132.993457 -124.837676) (xy 133.047405 -124.845432)
			(xy 133.0997 -124.860787) (xy 133.149277 -124.883429) (xy 133.195127 -124.912895) (xy 133.236318 -124.948586)
			(xy 133.272009 -124.989777) (xy 133.301475 -125.035627) (xy 133.324117 -125.085204) (xy 133.339472 -125.137499)
			(xy 133.347228 -125.191447) (xy 133.347714 -125.218698) (xy 133.347243 -125.246068) (xy 133.339426 -125.300247)
			(xy 133.323938 -125.35275) (xy 133.301097 -125.402497) (xy 133.271374 -125.448464) (xy 133.253734 -125.469396)
			(xy 133.247638 -125.476508) (xy 133.241288 -125.493526) (xy 133.241288 -125.57887) (xy 133.247638 -125.595888)
			(xy 133.253734 -125.603) (xy 133.271392 -125.623917) (xy 133.3011 -125.669894) (xy 133.323931 -125.719646)
			(xy 133.339418 -125.77215) (xy 133.347242 -125.826328) (xy 133.347714 -125.853698) (xy 133.347228 -125.880949)
			(xy 133.339472 -125.934897) (xy 133.324117 -125.987192) (xy 133.301475 -126.036769) (xy 133.272009 -126.082619)
			(xy 133.236318 -126.12381) (xy 133.195127 -126.159501) (xy 133.149277 -126.188967) (xy 133.0997 -126.211609)
			(xy 133.047405 -126.226964) (xy 132.993457 -126.23472) (xy 132.938955 -126.23472) (xy 132.885007 -126.226964)
			(xy 132.832712 -126.211609) (xy 132.783135 -126.188967) (xy 132.737285 -126.159501) (xy 132.696094 -126.12381)
			(xy 132.660403 -126.082619) (xy 132.630937 -126.036769) (xy 132.608295 -125.987192) (xy 132.59294 -125.934897)
			(xy 132.585184 -125.880949) (xy 132.584698 -125.853698) (xy 127.998231 -125.853698) (xy 128.006101 -125.879856)
			(xy 128.014221 -125.935032) (xy 128.01473 -125.962918) (xy 128.014221 -125.990804) (xy 128.006101 -126.04598)
			(xy 127.990033 -126.099387) (xy 127.966361 -126.149884) (xy 127.935588 -126.196397) (xy 127.898371 -126.237934)
			(xy 127.855503 -126.273609) (xy 127.807897 -126.302663) (xy 127.756568 -126.324475) (xy 127.702611 -126.338581)
			(xy 127.647174 -126.344681) (xy 127.59144 -126.342644) (xy 127.536597 -126.332514) (xy 127.483813 -126.314507)
			(xy 127.434213 -126.289006) (xy 127.388855 -126.256555) (xy 127.348706 -126.217846) (xy 127.31462 -126.173703)
			(xy 127.287324 -126.125068) (xy 127.267401 -126.072977) (xy 127.255275 -126.01854) (xy 127.251204 -125.962918)
			(xy 125.536151 -125.962918) (xy 125.536452 -125.979428) (xy 125.535943 -126.007314) (xy 125.527823 -126.06249)
			(xy 125.511755 -126.115897) (xy 125.488083 -126.166394) (xy 125.45731 -126.212907) (xy 125.420093 -126.254444)
			(xy 125.377225 -126.290119) (xy 125.329619 -126.319173) (xy 125.27829 -126.340985) (xy 125.224333 -126.355091)
			(xy 125.168896 -126.361191) (xy 125.113162 -126.359154) (xy 125.058319 -126.349024) (xy 125.005535 -126.331017)
			(xy 124.955935 -126.305516) (xy 124.910577 -126.273065) (xy 124.870428 -126.234356) (xy 124.836342 -126.190213)
			(xy 124.809046 -126.141578) (xy 124.789123 -126.089487) (xy 124.776997 -126.03505) (xy 124.772926 -125.979428)
			(xy 123.836938 -125.979428) (xy 123.836938 -126.261876) (xy 123.836499 -126.271939) (xy 123.828759 -126.290517)
			(xy 123.821952 -126.297944) (xy 123.821952 -126.530354) (xy 133.79323 -126.530354) (xy 133.79377 -126.50269)
			(xy 133.801763 -126.447941) (xy 133.817574 -126.39492) (xy 133.840871 -126.344735) (xy 133.871169 -126.298439)
			(xy 133.907831 -126.257) (xy 133.95009 -126.221287) (xy 133.973316 -126.20625) (xy 133.983476 -126.1999)
			(xy 133.995922 -126.180342) (xy 134.006336 -126.076202) (xy 133.998208 -126.054358) (xy 133.989318 -126.045976)
			(xy 133.970746 -126.027885) (xy 133.938166 -125.987556) (xy 133.911352 -125.943184) (xy 133.890797 -125.895587)
			(xy 133.876882 -125.845644) (xy 133.869863 -125.794277) (xy 133.86943 -125.768354) (xy 133.869835 -125.7411)
			(xy 133.877599 -125.687147) (xy 133.892962 -125.634849) (xy 133.915611 -125.585269) (xy 133.945086 -125.539417)
			(xy 133.980786 -125.498226) (xy 134.021984 -125.462535) (xy 134.067843 -125.433071) (xy 134.117428 -125.410432)
			(xy 134.169729 -125.395081) (xy 134.223684 -125.387329) (xy 134.250938 -125.386846) (xy 134.278307 -125.387337)
			(xy 134.332486 -125.395147) (xy 134.384989 -125.41063) (xy 134.434737 -125.433466) (xy 134.480704 -125.463187)
			(xy 134.501636 -125.480826) (xy 134.508748 -125.486922) (xy 134.525766 -125.493272) (xy 134.61111 -125.493272)
			(xy 134.628128 -125.486922) (xy 134.63524 -125.480826) (xy 134.656187 -125.463206) (xy 134.702155 -125.43349)
			(xy 134.751899 -125.41065) (xy 134.804397 -125.395155) (xy 134.85857 -125.387322) (xy 134.885938 -125.386846)
			(xy 134.913188 -125.387342) (xy 134.967133 -125.395103) (xy 135.019425 -125.41046) (xy 135.068999 -125.433103)
			(xy 135.114847 -125.462569) (xy 135.156036 -125.498259) (xy 135.191727 -125.539447) (xy 135.221194 -125.585294)
			(xy 135.243837 -125.634868) (xy 135.259195 -125.687159) (xy 135.266957 -125.741104) (xy 135.267446 -125.768354)
			(xy 135.266915 -125.797271) (xy 135.258192 -125.854442) (xy 135.240938 -125.909642) (xy 135.215548 -125.961604)
			(xy 135.182606 -126.009138) (xy 135.142865 -126.051154) (xy 135.12038 -126.069344) (xy 135.111599 -126.076888)
			(xy 135.101427 -126.09766) (xy 135.100822 -126.109222) (xy 135.100822 -126.189486) (xy 135.101393 -126.201054)
			(xy 135.111586 -126.221825) (xy 135.12038 -126.229364) (xy 135.142842 -126.24758) (xy 135.18258 -126.289594)
			(xy 135.215522 -126.337124) (xy 135.240914 -126.38908) (xy 135.258175 -126.444273) (xy 135.266908 -126.501439)
			(xy 135.267446 -126.530354) (xy 135.266902 -126.557604) (xy 135.259152 -126.61155) (xy 135.247051 -126.652782)
			(xy 135.538718 -126.652782) (xy 135.539169 -126.625411) (xy 135.54699 -126.571231) (xy 135.562482 -126.518728)
			(xy 135.585327 -126.468981) (xy 135.615055 -126.423015) (xy 135.632698 -126.402084) (xy 135.638794 -126.394972)
			(xy 135.645144 -126.377954) (xy 135.645144 -126.29261) (xy 135.638794 -126.275592) (xy 135.632698 -126.26848)
			(xy 135.615041 -126.247561) (xy 135.585319 -126.20159) (xy 135.562476 -126.151841) (xy 135.546983 -126.099337)
			(xy 135.539157 -126.045158) (xy 135.539159 -125.990415) (xy 135.546989 -125.936236) (xy 135.562486 -125.883733)
			(xy 135.585332 -125.833986) (xy 135.615057 -125.788017) (xy 135.632698 -125.767084) (xy 135.638794 -125.759972)
			(xy 135.645144 -125.742954) (xy 135.645144 -125.65761) (xy 135.638794 -125.640592) (xy 135.632698 -125.63348)
			(xy 135.615041 -125.612561) (xy 135.585319 -125.56659) (xy 135.562476 -125.516841) (xy 135.546983 -125.464337)
			(xy 135.539157 -125.410158) (xy 135.539159 -125.355415) (xy 135.546989 -125.301236) (xy 135.562486 -125.248733)
			(xy 135.585332 -125.198986) (xy 135.615057 -125.153017) (xy 135.632698 -125.132084) (xy 135.638794 -125.124972)
			(xy 135.645144 -125.107954) (xy 135.645144 -125.02261) (xy 135.638794 -125.005592) (xy 135.632698 -124.99848)
			(xy 135.615083 -124.977529) (xy 135.585367 -124.931561) (xy 135.562527 -124.881819) (xy 135.54703 -124.829322)
			(xy 135.539196 -124.77515) (xy 135.538718 -124.747782) (xy 135.539204 -124.720531) (xy 135.54696 -124.666583)
			(xy 135.562315 -124.614288) (xy 135.584957 -124.564711) (xy 135.614423 -124.518861) (xy 135.650114 -124.47767)
			(xy 135.691305 -124.441979) (xy 135.737155 -124.412513) (xy 135.786732 -124.389871) (xy 135.839027 -124.374516)
			(xy 135.892975 -124.36676) (xy 135.947477 -124.36676) (xy 136.001425 -124.374516) (xy 136.05372 -124.389871)
			(xy 136.103297 -124.412513) (xy 136.149147 -124.441979) (xy 136.190338 -124.47767) (xy 136.226029 -124.518861)
			(xy 136.255495 -124.564711) (xy 136.278137 -124.614288) (xy 136.293492 -124.666583) (xy 136.301248 -124.720531)
			(xy 136.301734 -124.747782) (xy 136.301273 -124.775153) (xy 136.293457 -124.829333) (xy 136.277967 -124.881836)
			(xy 136.255124 -124.931583) (xy 136.225397 -124.977549) (xy 136.207754 -124.99848) (xy 136.201658 -125.005592)
			(xy 136.195308 -125.02261) (xy 136.195308 -125.107954) (xy 136.201658 -125.124972) (xy 136.207754 -125.132084)
			(xy 136.225378 -125.153031) (xy 136.255105 -125.198996) (xy 136.277952 -125.248739) (xy 136.293451 -125.30124)
			(xy 136.301282 -125.355416) (xy 136.301284 -125.410156) (xy 136.293457 -125.464334) (xy 136.277962 -125.516835)
			(xy 136.255118 -125.566581) (xy 136.225394 -125.612548) (xy 136.207754 -125.63348) (xy 136.201658 -125.640592)
			(xy 136.195308 -125.65761) (xy 136.195308 -125.742954) (xy 136.201658 -125.759972) (xy 136.207754 -125.767084)
			(xy 136.225378 -125.788031) (xy 136.255105 -125.833996) (xy 136.277952 -125.883739) (xy 136.293451 -125.93624)
			(xy 136.301282 -125.990416) (xy 136.301284 -126.045156) (xy 136.293457 -126.099334) (xy 136.277962 -126.151835)
			(xy 136.255118 -126.201581) (xy 136.225394 -126.247548) (xy 136.207754 -126.26848) (xy 136.201658 -126.275592)
			(xy 136.195308 -126.29261) (xy 136.195308 -126.377954) (xy 136.201658 -126.394972) (xy 136.207754 -126.402084)
			(xy 136.225392 -126.423017) (xy 136.255105 -126.468989) (xy 136.277942 -126.518736) (xy 136.293434 -126.571237)
			(xy 136.301261 -126.625413) (xy 136.301734 -126.652782) (xy 136.301248 -126.680033) (xy 136.293492 -126.733981)
			(xy 136.278137 -126.786276) (xy 136.255495 -126.835853) (xy 136.226029 -126.881703) (xy 136.190338 -126.922894)
			(xy 136.149147 -126.958585) (xy 136.103297 -126.988051) (xy 136.05372 -127.010693) (xy 136.001425 -127.026048)
			(xy 135.947477 -127.033804) (xy 135.892975 -127.033804) (xy 135.839027 -127.026048) (xy 135.786732 -127.010693)
			(xy 135.737155 -126.988051) (xy 135.691305 -126.958585) (xy 135.650114 -126.922894) (xy 135.614423 -126.881703)
			(xy 135.584957 -126.835853) (xy 135.562315 -126.786276) (xy 135.54696 -126.733981) (xy 135.539204 -126.680033)
			(xy 135.538718 -126.652782) (xy 135.247051 -126.652782) (xy 135.243804 -126.663844) (xy 135.22117 -126.713422)
			(xy 135.19171 -126.759273) (xy 135.156025 -126.800465) (xy 135.11484 -126.83616) (xy 135.068995 -126.865629)
			(xy 135.019423 -126.888275) (xy 134.967132 -126.903634) (xy 134.913188 -126.911396) (xy 134.885938 -126.911862)
			(xy 134.859621 -126.911442) (xy 134.807485 -126.904217) (xy 134.756835 -126.889898) (xy 134.708633 -126.868758)
			(xy 134.663792 -126.841196) (xy 134.623163 -126.807736) (xy 134.605014 -126.788672) (xy 134.59748 -126.781285)
			(xy 134.57821 -126.77275) (xy 134.567676 -126.772162) (xy 134.493 -126.772162) (xy 134.48245 -126.772689)
			(xy 134.463156 -126.781227) (xy 134.455662 -126.788672) (xy 134.43754 -126.807764) (xy 134.396918 -126.841242)
			(xy 134.352075 -126.868812) (xy 134.303865 -126.889948) (xy 134.253205 -126.90425) (xy 134.201058 -126.911444)
			(xy 134.174738 -126.911862) (xy 134.147484 -126.911409) (xy 134.09353 -126.903656) (xy 134.041229 -126.888303)
			(xy 133.991646 -126.865661) (xy 133.945791 -126.836193) (xy 133.904597 -126.800498) (xy 133.868902 -126.759303)
			(xy 133.839435 -126.713447) (xy 133.816795 -126.663863) (xy 133.801442 -126.611562) (xy 133.79369 -126.557608)
			(xy 133.79323 -126.530354) (xy 123.821952 -126.530354) (xy 123.821952 -127.051308) (xy 126.844042 -127.051308)
			(xy 126.848113 -126.995686) (xy 126.860239 -126.941249) (xy 126.880162 -126.889158) (xy 126.907458 -126.840523)
			(xy 126.941544 -126.79638) (xy 126.981693 -126.757671) (xy 127.027051 -126.72522) (xy 127.076651 -126.699719)
			(xy 127.129435 -126.681712) (xy 127.184278 -126.671582) (xy 127.240012 -126.669545) (xy 127.295449 -126.675645)
			(xy 127.349406 -126.689751) (xy 127.400735 -126.711563) (xy 127.448341 -126.740617) (xy 127.491209 -126.776292)
			(xy 127.528426 -126.817829) (xy 127.559199 -126.864342) (xy 127.582871 -126.914839) (xy 127.598939 -126.968246)
			(xy 127.607059 -127.023422) (xy 127.607568 -127.051308) (xy 127.607059 -127.079194) (xy 127.598939 -127.13437)
			(xy 127.582871 -127.187777) (xy 127.559199 -127.238274) (xy 127.528426 -127.284787) (xy 127.491209 -127.326324)
			(xy 127.448341 -127.361999) (xy 127.400735 -127.391053) (xy 127.349406 -127.412865) (xy 127.295449 -127.426971)
			(xy 127.240012 -127.433071) (xy 127.184278 -127.431034) (xy 127.129435 -127.420904) (xy 127.076651 -127.402897)
			(xy 127.027051 -127.377396) (xy 126.981693 -127.344945) (xy 126.941544 -127.306236) (xy 126.907458 -127.262093)
			(xy 126.880162 -127.213458) (xy 126.860239 -127.161367) (xy 126.848113 -127.10693) (xy 126.844042 -127.051308)
			(xy 123.821952 -127.051308) (xy 123.821952 -128.252748) (xy 125.828328 -128.252748) (xy 125.828328 -128.198252)
			(xy 125.836084 -128.144312) (xy 125.851437 -128.092024) (xy 125.874075 -128.042454) (xy 125.903537 -127.99661)
			(xy 125.939223 -127.955425) (xy 125.980408 -127.919738) (xy 126.026252 -127.890276) (xy 126.075822 -127.867637)
			(xy 126.12811 -127.852284) (xy 126.18205 -127.844528) (xy 126.209298 -127.844042) (xy 126.236669 -127.844499)
			(xy 126.290849 -127.852317) (xy 126.343352 -127.867808) (xy 126.393099 -127.890652) (xy 126.439065 -127.920379)
			(xy 126.459996 -127.938022) (xy 126.467108 -127.944118) (xy 126.484126 -127.950468) (xy 126.56947 -127.950468)
			(xy 126.586488 -127.944118) (xy 126.5936 -127.938022) (xy 126.614533 -127.920381) (xy 126.660501 -127.890657)
			(xy 126.710247 -127.867811) (xy 126.762749 -127.852315) (xy 126.816927 -127.844486) (xy 126.871669 -127.844486)
			(xy 126.925847 -127.852315) (xy 126.978349 -127.867811) (xy 127.028095 -127.890657) (xy 127.074063 -127.920381)
			(xy 127.094996 -127.938022) (xy 127.102108 -127.944118) (xy 127.119126 -127.950468) (xy 127.20447 -127.950468)
			(xy 127.221488 -127.944118) (xy 127.2286 -127.938022) (xy 127.249524 -127.920373) (xy 127.295499 -127.890662)
			(xy 127.345248 -127.867827) (xy 127.397751 -127.852339) (xy 127.451928 -127.844514) (xy 127.479298 -127.844042)
			(xy 127.506555 -127.844405) (xy 127.560513 -127.852163) (xy 127.612818 -127.86752) (xy 127.662405 -127.890166)
			(xy 127.708264 -127.919638) (xy 127.749463 -127.955336) (xy 127.785161 -127.996534) (xy 127.814633 -128.042393)
			(xy 127.837279 -128.09198) (xy 127.852637 -128.144285) (xy 127.860395 -128.198243) (xy 127.860395 -128.252757)
			(xy 127.852637 -128.306715) (xy 127.837279 -128.35902) (xy 127.814633 -128.408607) (xy 127.785161 -128.454466)
			(xy 127.749463 -128.495664) (xy 127.708264 -128.531362) (xy 127.662405 -128.560834) (xy 127.612818 -128.58348)
			(xy 127.560513 -128.598837) (xy 127.506555 -128.606595) (xy 127.479298 -128.607058) (xy 127.451927 -128.606603)
			(xy 127.397747 -128.598784) (xy 127.345244 -128.583293) (xy 127.295497 -128.560449) (xy 127.249531 -128.530721)
			(xy 127.2286 -128.513078) (xy 127.221488 -128.506982) (xy 127.20447 -128.500632) (xy 127.119126 -128.500632)
			(xy 127.102108 -128.506982) (xy 127.094996 -128.513078) (xy 127.074063 -128.530719) (xy 127.028095 -128.560443)
			(xy 126.978349 -128.583289) (xy 126.925847 -128.598785) (xy 126.871669 -128.606614) (xy 126.816927 -128.606614)
			(xy 126.762749 -128.598785) (xy 126.710247 -128.583289) (xy 126.660501 -128.560443) (xy 126.614533 -128.530719)
			(xy 126.5936 -128.513078) (xy 126.586488 -128.506982) (xy 126.56947 -128.500632) (xy 126.484126 -128.500632)
			(xy 126.467108 -128.506982) (xy 126.459996 -128.513078) (xy 126.439073 -128.530729) (xy 126.393098 -128.56044)
			(xy 126.343348 -128.583274) (xy 126.290846 -128.598762) (xy 126.236668 -128.606586) (xy 126.209298 -128.607058)
			(xy 126.18205 -128.606472) (xy 126.12811 -128.598716) (xy 126.075822 -128.583363) (xy 126.026252 -128.560724)
			(xy 125.980408 -128.531262) (xy 125.939223 -128.495575) (xy 125.903537 -128.45439) (xy 125.874075 -128.408546)
			(xy 125.851437 -128.358976) (xy 125.836084 -128.306688) (xy 125.828328 -128.252748) (xy 123.821952 -128.252748)
			(xy 123.821952 -131.447157) (xy 125.813209 -131.447157) (xy 125.813209 -131.392643) (xy 125.820967 -131.338685)
			(xy 125.836326 -131.28638) (xy 125.858972 -131.236793) (xy 125.888445 -131.190933) (xy 125.924144 -131.149735)
			(xy 125.965343 -131.114037) (xy 126.011203 -131.084566) (xy 126.060791 -131.061922) (xy 126.113096 -131.046565)
			(xy 126.167055 -131.038808) (xy 126.194312 -131.038346) (xy 126.221683 -131.038794) (xy 126.275863 -131.046614)
			(xy 126.328367 -131.062107) (xy 126.378114 -131.084953) (xy 126.424079 -131.114682) (xy 126.44501 -131.132326)
			(xy 126.452122 -131.138422) (xy 126.46914 -131.144772) (xy 126.554484 -131.144772) (xy 126.571502 -131.138422)
			(xy 126.578614 -131.132326) (xy 126.599547 -131.114685) (xy 126.645515 -131.084961) (xy 126.695261 -131.062115)
			(xy 126.747763 -131.046619) (xy 126.801941 -131.03879) (xy 126.856683 -131.03879) (xy 126.910861 -131.046619)
			(xy 126.963363 -131.062115) (xy 127.013109 -131.084961) (xy 127.059077 -131.114685) (xy 127.08001 -131.132326)
			(xy 127.087122 -131.138422) (xy 127.10414 -131.144772) (xy 127.189484 -131.144772) (xy 127.206502 -131.138422)
			(xy 127.213614 -131.132326) (xy 127.234571 -131.114718) (xy 127.280537 -131.085) (xy 127.330278 -131.062158)
			(xy 127.382773 -131.04666) (xy 127.436944 -131.038824) (xy 127.464312 -131.038346) (xy 127.491559 -131.038925)
			(xy 127.545499 -131.046682) (xy 127.597786 -131.062036) (xy 127.647356 -131.084675) (xy 127.693199 -131.114138)
			(xy 127.734383 -131.149826) (xy 127.770069 -131.19101) (xy 127.79953 -131.236855) (xy 127.822168 -131.286425)
			(xy 127.837521 -131.338712) (xy 127.845276 -131.392653) (xy 127.845276 -131.447147) (xy 127.837521 -131.501087)
			(xy 127.822168 -131.553375) (xy 127.79953 -131.602945) (xy 127.770069 -131.64879) (xy 127.734383 -131.689974)
			(xy 127.693199 -131.725662) (xy 127.647356 -131.755125) (xy 127.597786 -131.777764) (xy 127.545499 -131.793118)
			(xy 127.491559 -131.800875) (xy 127.464312 -131.801362) (xy 127.436942 -131.800898) (xy 127.382762 -131.793081)
			(xy 127.330259 -131.777592) (xy 127.280512 -131.75475) (xy 127.234545 -131.725024) (xy 127.213614 -131.707382)
			(xy 127.206502 -131.701286) (xy 127.189484 -131.694936) (xy 127.10414 -131.694936) (xy 127.087122 -131.701286)
			(xy 127.08001 -131.707382) (xy 127.059077 -131.725023) (xy 127.013109 -131.754747) (xy 126.963363 -131.777593)
			(xy 126.910861 -131.793089) (xy 126.856683 -131.800918) (xy 126.801941 -131.800918) (xy 126.747763 -131.793089)
			(xy 126.695261 -131.777593) (xy 126.645515 -131.754747) (xy 126.599547 -131.725023) (xy 126.578614 -131.707382)
			(xy 126.571502 -131.701286) (xy 126.554484 -131.694936) (xy 126.46914 -131.694936) (xy 126.452122 -131.701286)
			(xy 126.44501 -131.707382) (xy 126.424083 -131.725027) (xy 126.378109 -131.754739) (xy 126.32836 -131.777574)
			(xy 126.275858 -131.793063) (xy 126.221682 -131.800889) (xy 126.194312 -131.801362) (xy 126.167055 -131.800992)
			(xy 126.113096 -131.793235) (xy 126.060791 -131.777878) (xy 126.011203 -131.755234) (xy 125.965343 -131.725763)
			(xy 125.924144 -131.690065) (xy 125.888445 -131.648867) (xy 125.858972 -131.603007) (xy 125.836326 -131.55342)
			(xy 125.820967 -131.501115) (xy 125.813209 -131.447157) (xy 123.821952 -131.447157) (xy 123.821952 -133.443726)
			(xy 127.222758 -133.443726) (xy 127.223195 -133.41741) (xy 127.230421 -133.365275) (xy 127.244738 -133.314628)
			(xy 127.265875 -133.266426) (xy 127.293432 -133.221584) (xy 127.326887 -133.180952) (xy 127.345948 -133.162802)
			(xy 127.353343 -133.155275) (xy 127.361873 -133.135999) (xy 127.362458 -133.125464) (xy 127.362458 -133.050788)
			(xy 127.361961 -133.040234) (xy 127.353405 -133.020938) (xy 127.345948 -133.01345) (xy 127.326854 -132.99533)
			(xy 127.293375 -132.954708) (xy 127.265805 -132.909864) (xy 127.244669 -132.861654) (xy 127.230368 -132.810993)
			(xy 127.223175 -132.758847) (xy 127.222758 -132.732526) (xy 127.223244 -132.705275) (xy 127.231 -132.651327)
			(xy 127.246355 -132.599032) (xy 127.268997 -132.549455) (xy 127.298463 -132.503605) (xy 127.334154 -132.462414)
			(xy 127.375345 -132.426723) (xy 127.421195 -132.397257) (xy 127.470772 -132.374615) (xy 127.523067 -132.35926)
			(xy 127.577015 -132.351504) (xy 127.631517 -132.351504) (xy 127.685465 -132.35926) (xy 127.73776 -132.374615)
			(xy 127.787337 -132.397257) (xy 127.833187 -132.426723) (xy 127.874378 -132.462414) (xy 127.910069 -132.503605)
			(xy 127.939535 -132.549455) (xy 127.962177 -132.599032) (xy 127.977532 -132.651327) (xy 127.985288 -132.705275)
			(xy 127.985774 -132.732526) (xy 127.985326 -132.758842) (xy 127.978106 -132.810977) (xy 127.963793 -132.861625)
			(xy 127.942657 -132.909828) (xy 127.915101 -132.954669) (xy 127.881645 -132.995301) (xy 127.862584 -133.01345)
			(xy 127.855156 -133.020949) (xy 127.846647 -133.040246) (xy 127.846074 -133.050788) (xy 127.846074 -133.125464)
			(xy 127.846617 -133.136012) (xy 127.855143 -133.155307) (xy 127.862584 -133.162802) (xy 127.881661 -133.180939)
			(xy 127.91514 -133.221558) (xy 127.942711 -133.266398) (xy 127.96385 -133.314606) (xy 127.978155 -133.365263)
			(xy 127.985353 -133.417407) (xy 127.985774 -133.443726) (xy 127.985288 -133.470977) (xy 127.977532 -133.524925)
			(xy 127.962177 -133.57722) (xy 127.939535 -133.626797) (xy 127.910069 -133.672647) (xy 127.874378 -133.713838)
			(xy 127.833187 -133.749529) (xy 127.787337 -133.778995) (xy 127.73776 -133.801637) (xy 127.685465 -133.816992)
			(xy 127.631517 -133.824748) (xy 127.577015 -133.824748) (xy 127.523067 -133.816992) (xy 127.470772 -133.801637)
			(xy 127.421195 -133.778995) (xy 127.375345 -133.749529) (xy 127.334154 -133.713838) (xy 127.298463 -133.672647)
			(xy 127.268997 -133.626797) (xy 127.246355 -133.57722) (xy 127.231 -133.524925) (xy 127.223244 -133.470977)
			(xy 127.222758 -133.443726) (xy 123.821952 -133.443726) (xy 123.821952 -135.142051) (xy 125.46177 -135.142051)
			(xy 125.46177 -135.087549) (xy 125.469526 -135.033603) (xy 125.48488 -134.981309) (xy 125.50752 -134.931732)
			(xy 125.536985 -134.885882) (xy 125.572674 -134.844691) (xy 125.613862 -134.808999) (xy 125.659711 -134.779531)
			(xy 125.709286 -134.756888) (xy 125.761579 -134.741531) (xy 125.815525 -134.733771) (xy 125.842776 -134.733284)
			(xy 125.871694 -134.733788) (xy 125.928867 -134.742515) (xy 125.984068 -134.759774) (xy 126.03603 -134.785168)
			(xy 126.083563 -134.818116) (xy 126.125578 -134.857862) (xy 126.143766 -134.88035) (xy 126.151132 -134.889748)
			(xy 126.172976 -134.900162) (xy 126.278386 -134.897876) (xy 126.299722 -134.8867) (xy 126.30658 -134.876794)
			(xy 126.321977 -134.855883) (xy 126.357555 -134.818056) (xy 126.397935 -134.785404) (xy 126.442369 -134.75853)
			(xy 126.490038 -134.737929) (xy 126.54006 -134.723985) (xy 126.591511 -134.716952) (xy 126.617476 -134.71652)
			(xy 126.644846 -134.716995) (xy 126.699025 -134.72481) (xy 126.751528 -134.740297) (xy 126.801275 -134.763137)
			(xy 126.847242 -134.792859) (xy 126.868174 -134.8105) (xy 126.875286 -134.816596) (xy 126.892304 -134.822946)
			(xy 126.977648 -134.822946) (xy 126.994666 -134.816596) (xy 127.001778 -134.8105) (xy 127.022711 -134.792859)
			(xy 127.068679 -134.763135) (xy 127.118425 -134.740289) (xy 127.170927 -134.724793) (xy 127.225105 -134.716964)
			(xy 127.279847 -134.716964) (xy 127.334025 -134.724793) (xy 127.386527 -134.740289) (xy 127.436273 -134.763135)
			(xy 127.482241 -134.792859) (xy 127.503174 -134.8105) (xy 127.510286 -134.816596) (xy 127.527304 -134.822946)
			(xy 127.612648 -134.822946) (xy 127.629666 -134.816596) (xy 127.636778 -134.8105) (xy 127.649576 -134.799552)
			(xy 127.676794 -134.779709) (xy 127.691134 -134.770876) (xy 127.700278 -134.765542) (xy 127.71247 -134.748524)
			(xy 127.732536 -134.655306) (xy 127.728472 -134.634732) (xy 127.722376 -134.626096) (xy 127.706369 -134.602036)
			(xy 127.681029 -134.550103) (xy 127.663805 -134.494944) (xy 127.655092 -134.437819) (xy 127.654558 -134.408926)
			(xy 127.655044 -134.381675) (xy 127.6628 -134.327727) (xy 127.678155 -134.275432) (xy 127.700797 -134.225855)
			(xy 127.730263 -134.180005) (xy 127.765954 -134.138814) (xy 127.807145 -134.103123) (xy 127.852995 -134.073657)
			(xy 127.902572 -134.051015) (xy 127.954867 -134.03566) (xy 128.008815 -134.027904) (xy 128.063317 -134.027904)
			(xy 128.117265 -134.03566) (xy 128.16956 -134.051015) (xy 128.219137 -134.073657) (xy 128.264987 -134.103123)
			(xy 128.306178 -134.138814) (xy 128.341869 -134.180005) (xy 128.371335 -134.225855) (xy 128.393977 -134.275432)
			(xy 128.409332 -134.327727) (xy 128.417088 -134.381675) (xy 128.417574 -134.408926) (xy 128.417121 -134.437019)
			(xy 128.408889 -134.492599) (xy 128.392592 -134.54637) (xy 128.368583 -134.597169) (xy 128.337381 -134.643895)
			(xy 128.299662 -134.685539) (xy 128.256242 -134.721198) (xy 128.232408 -134.736078) (xy 128.223264 -134.741412)
			(xy 128.211072 -134.75843) (xy 128.191006 -134.851648) (xy 128.19507 -134.872222) (xy 128.201166 -134.880858)
			(xy 128.217146 -134.904934) (xy 128.242495 -134.956861) (xy 128.259726 -135.012015) (xy 128.268447 -135.069136)
			(xy 128.268984 -135.098028) (xy 128.268548 -135.125281) (xy 128.260787 -135.179232) (xy 128.245427 -135.231529)
			(xy 128.222781 -135.281108) (xy 128.19331 -135.326959) (xy 128.157613 -135.36815) (xy 128.116418 -135.403841)
			(xy 128.070562 -135.433306) (xy 128.02098 -135.455946) (xy 127.968681 -135.471298) (xy 127.914729 -135.479052)
			(xy 127.887476 -135.479536) (xy 127.860105 -135.4791) (xy 127.805924 -135.471277) (xy 127.753419 -135.455782)
			(xy 127.703673 -135.432933) (xy 127.657708 -135.403201) (xy 127.636778 -135.385556) (xy 127.629666 -135.37946)
			(xy 127.612648 -135.37311) (xy 127.527304 -135.37311) (xy 127.510286 -135.37946) (xy 127.503174 -135.385556)
			(xy 127.482241 -135.403197) (xy 127.436273 -135.432921) (xy 127.386527 -135.455767) (xy 127.334025 -135.471263)
			(xy 127.279847 -135.479092) (xy 127.225105 -135.479092) (xy 127.170927 -135.471263) (xy 127.118425 -135.455767)
			(xy 127.068679 -135.432921) (xy 127.022711 -135.403197) (xy 127.001778 -135.385556) (xy 126.994666 -135.37946)
			(xy 126.977648 -135.37311) (xy 126.892304 -135.37311) (xy 126.875286 -135.37946) (xy 126.868174 -135.385556)
			(xy 126.847219 -135.403167) (xy 126.801253 -135.432885) (xy 126.751512 -135.455727) (xy 126.699016 -135.471224)
			(xy 126.644844 -135.479059) (xy 126.617476 -135.479536) (xy 126.58856 -135.478987) (xy 126.531389 -135.470268)
			(xy 126.47619 -135.453018) (xy 126.424227 -135.427632) (xy 126.376693 -135.394692) (xy 126.334676 -135.354954)
			(xy 126.316486 -135.33247) (xy 126.30912 -135.323072) (xy 126.287276 -135.312658) (xy 126.181866 -135.314944)
			(xy 126.16053 -135.32612) (xy 126.153672 -135.336026) (xy 126.138249 -135.356917) (xy 126.102675 -135.394743)
			(xy 126.062299 -135.427397) (xy 126.017869 -135.454273) (xy 125.970205 -135.474877) (xy 125.920187 -135.488826)
			(xy 125.868739 -135.495864) (xy 125.842776 -135.4963) (xy 125.815525 -135.495829) (xy 125.761579 -135.488069)
			(xy 125.709286 -135.472712) (xy 125.659711 -135.450069) (xy 125.613862 -135.420601) (xy 125.572674 -135.384909)
			(xy 125.536985 -135.343718) (xy 125.50752 -135.297868) (xy 125.48488 -135.248291) (xy 125.469526 -135.195997)
			(xy 125.46177 -135.142051) (xy 123.821952 -135.142051) (xy 123.821952 -135.831072) (xy 123.821514 -135.841135)
			(xy 123.813776 -135.859716) (xy 123.807199 -135.866886) (xy 124.539754 -135.866886) (xy 124.543825 -135.811264)
			(xy 124.555951 -135.756827) (xy 124.575874 -135.704736) (xy 124.60317 -135.656101) (xy 124.637256 -135.611958)
			(xy 124.677405 -135.573249) (xy 124.722763 -135.540798) (xy 124.772363 -135.515297) (xy 124.825147 -135.49729)
			(xy 124.87999 -135.48716) (xy 124.935724 -135.485123) (xy 124.991161 -135.491223) (xy 125.045118 -135.505329)
			(xy 125.096447 -135.527141) (xy 125.144053 -135.556195) (xy 125.186921 -135.59187) (xy 125.224138 -135.633407)
			(xy 125.254911 -135.67992) (xy 125.278583 -135.730417) (xy 125.294651 -135.783824) (xy 125.302771 -135.839)
			(xy 125.30328 -135.866886) (xy 125.302771 -135.894772) (xy 125.294651 -135.949948) (xy 125.278583 -136.003355)
			(xy 125.254911 -136.053852) (xy 125.224138 -136.100365) (xy 125.186921 -136.141902) (xy 125.144053 -136.177577)
			(xy 125.096447 -136.206631) (xy 125.045118 -136.228443) (xy 124.991161 -136.242549) (xy 124.935724 -136.248649)
			(xy 124.87999 -136.246612) (xy 124.825147 -136.236482) (xy 124.772363 -136.218475) (xy 124.722763 -136.192974)
			(xy 124.677405 -136.160523) (xy 124.637256 -136.121814) (xy 124.60317 -136.077671) (xy 124.575874 -136.029036)
			(xy 124.555951 -135.976945) (xy 124.543825 -135.922508) (xy 124.539754 -135.866886) (xy 123.807199 -135.866886)
			(xy 123.806966 -135.86714) (xy 123.506484 -136.167622) (xy 123.499088 -136.174474) (xy 123.480489 -136.182215)
			(xy 123.470416 -136.182608) (xy 122.438668 -136.182608) (xy 122.428601 -136.183037) (xy 122.410005 -136.190761)
			(xy 122.4026 -136.197594) (xy 122.013472 -136.586722) (xy 122.006106 -136.593834) (xy 121.998486 -136.61263)
			(xy 121.998486 -137.44829) (xy 124.445012 -137.44829) (xy 124.449083 -137.392668) (xy 124.461209 -137.338231)
			(xy 124.481132 -137.28614) (xy 124.508428 -137.237505) (xy 124.542514 -137.193362) (xy 124.582663 -137.154653)
			(xy 124.628021 -137.122202) (xy 124.677621 -137.096701) (xy 124.730405 -137.078694) (xy 124.785248 -137.068564)
			(xy 124.840982 -137.066527) (xy 124.896419 -137.072627) (xy 124.950376 -137.086733) (xy 125.001705 -137.108545)
			(xy 125.049311 -137.137599) (xy 125.092179 -137.173274) (xy 125.129396 -137.214811) (xy 125.160169 -137.261324)
			(xy 125.167204 -137.276332) (xy 129.147062 -137.276332) (xy 129.147532 -137.248962) (xy 129.155346 -137.194782)
			(xy 129.170834 -137.142279) (xy 129.193675 -137.092532) (xy 129.2234 -137.046565) (xy 129.241042 -137.025634)
			(xy 129.247138 -137.018522) (xy 129.253488 -137.001504) (xy 129.253488 -136.91616) (xy 129.247138 -136.899142)
			(xy 129.241042 -136.89203) (xy 129.22341 -136.871092) (xy 129.193696 -136.825122) (xy 129.170858 -136.775376)
			(xy 129.155365 -136.722876) (xy 129.147536 -136.668701) (xy 129.147062 -136.641332) (xy 129.147548 -136.614081)
			(xy 129.155304 -136.560133) (xy 129.170659 -136.507838) (xy 129.193301 -136.458261) (xy 129.222767 -136.412411)
			(xy 129.258458 -136.37122) (xy 129.299649 -136.335529) (xy 129.345499 -136.306063) (xy 129.395076 -136.283421)
			(xy 129.447371 -136.268066) (xy 129.501319 -136.26031) (xy 129.555821 -136.26031) (xy 129.609769 -136.268066)
			(xy 129.662064 -136.283421) (xy 129.711641 -136.306063) (xy 129.757491 -136.335529) (xy 129.798682 -136.37122)
			(xy 129.834373 -136.412411) (xy 129.863839 -136.458261) (xy 129.886481 -136.507838) (xy 129.901836 -136.560133)
			(xy 129.909592 -136.614081) (xy 129.910078 -136.641332) (xy 129.909636 -136.668703) (xy 129.901813 -136.722883)
			(xy 129.886319 -136.775387) (xy 129.863472 -136.825134) (xy 129.833742 -136.871099) (xy 129.816098 -136.89203)
			(xy 129.810002 -136.899142) (xy 129.803652 -136.91616) (xy 129.803652 -137.001504) (xy 129.810002 -137.018522)
			(xy 129.816098 -137.025634) (xy 129.833719 -137.04658) (xy 129.863434 -137.092549) (xy 129.886273 -137.142293)
			(xy 129.901769 -137.194791) (xy 129.909601 -137.248964) (xy 129.910078 -137.276332) (xy 129.909592 -137.303583)
			(xy 129.901836 -137.357531) (xy 129.886481 -137.409826) (xy 129.863839 -137.459403) (xy 129.834373 -137.505253)
			(xy 129.798682 -137.546444) (xy 129.757491 -137.582135) (xy 129.711641 -137.611601) (xy 129.662064 -137.634243)
			(xy 129.609769 -137.649598) (xy 129.555821 -137.657354) (xy 129.501319 -137.657354) (xy 129.447371 -137.649598)
			(xy 129.395076 -137.634243) (xy 129.345499 -137.611601) (xy 129.299649 -137.582135) (xy 129.258458 -137.546444)
			(xy 129.222767 -137.505253) (xy 129.193301 -137.459403) (xy 129.170659 -137.409826) (xy 129.155304 -137.357531)
			(xy 129.147548 -137.303583) (xy 129.147062 -137.276332) (xy 125.167204 -137.276332) (xy 125.183841 -137.311821)
			(xy 125.199909 -137.365228) (xy 125.208029 -137.420404) (xy 125.208538 -137.44829) (xy 125.208029 -137.476176)
			(xy 125.199909 -137.531352) (xy 125.183841 -137.584759) (xy 125.160169 -137.635256) (xy 125.129396 -137.681769)
			(xy 125.092179 -137.723306) (xy 125.088132 -137.726674) (xy 130.087624 -137.726674) (xy 130.088069 -137.699303)
			(xy 130.095891 -137.645123) (xy 130.111385 -137.592619) (xy 130.134231 -137.542873) (xy 130.16396 -137.496907)
			(xy 130.181604 -137.475976) (xy 130.1877 -137.468864) (xy 130.19405 -137.451846) (xy 130.19405 -137.366502)
			(xy 130.1877 -137.349484) (xy 130.181604 -137.342372) (xy 130.163986 -137.321423) (xy 130.134271 -137.275455)
			(xy 130.111431 -137.225712) (xy 130.095935 -137.173215) (xy 130.088101 -137.119042) (xy 130.087624 -137.091674)
			(xy 130.08811 -137.064423) (xy 130.095866 -137.010475) (xy 130.111221 -136.95818) (xy 130.133863 -136.908603)
			(xy 130.163329 -136.862753) (xy 130.19902 -136.821562) (xy 130.240211 -136.785871) (xy 130.286061 -136.756405)
			(xy 130.335638 -136.733763) (xy 130.387933 -136.718408) (xy 130.441881 -136.710652) (xy 130.496383 -136.710652)
			(xy 130.550331 -136.718408) (xy 130.602626 -136.733763) (xy 130.652203 -136.756405) (xy 130.698053 -136.785871)
			(xy 130.739244 -136.821562) (xy 130.774935 -136.862753) (xy 130.804401 -136.908603) (xy 130.827043 -136.95818)
			(xy 130.842398 -137.010475) (xy 130.850154 -137.064423) (xy 130.85064 -137.091674) (xy 130.850173 -137.119044)
			(xy 130.842358 -137.173224) (xy 130.82687 -137.225728) (xy 130.804028 -137.275475) (xy 130.774302 -137.321441)
			(xy 130.75666 -137.342372) (xy 130.750564 -137.349484) (xy 130.744214 -137.366502) (xy 130.744214 -137.451846)
			(xy 130.750564 -137.468864) (xy 130.75666 -137.475976) (xy 130.774295 -137.496911) (xy 130.804009 -137.542883)
			(xy 130.826846 -137.592629) (xy 130.842338 -137.645129) (xy 130.850166 -137.699305) (xy 130.85064 -137.726674)
			(xy 130.850154 -137.753925) (xy 130.842398 -137.807873) (xy 130.827043 -137.860168) (xy 130.804401 -137.909745)
			(xy 130.774935 -137.955595) (xy 130.739244 -137.996786) (xy 130.698053 -138.032477) (xy 130.652203 -138.061943)
			(xy 130.602626 -138.084585) (xy 130.550331 -138.09994) (xy 130.496383 -138.107696) (xy 130.441881 -138.107696)
			(xy 130.387933 -138.09994) (xy 130.335638 -138.084585) (xy 130.286061 -138.061943) (xy 130.240211 -138.032477)
			(xy 130.19902 -137.996786) (xy 130.163329 -137.955595) (xy 130.133863 -137.909745) (xy 130.111221 -137.860168)
			(xy 130.095866 -137.807873) (xy 130.08811 -137.753925) (xy 130.087624 -137.726674) (xy 125.088132 -137.726674)
			(xy 125.049311 -137.758981) (xy 125.001705 -137.788035) (xy 124.950376 -137.809847) (xy 124.896419 -137.823953)
			(xy 124.840982 -137.830053) (xy 124.785248 -137.828016) (xy 124.730405 -137.817886) (xy 124.677621 -137.799879)
			(xy 124.628021 -137.774378) (xy 124.582663 -137.741927) (xy 124.542514 -137.703218) (xy 124.508428 -137.659075)
			(xy 124.481132 -137.61044) (xy 124.461209 -137.558349) (xy 124.449083 -137.503912) (xy 124.445012 -137.44829)
			(xy 121.998486 -137.44829) (xy 121.998486 -138.360404) (xy 122.275852 -138.360404) (xy 122.279923 -138.304782)
			(xy 122.292049 -138.250345) (xy 122.311972 -138.198254) (xy 122.339268 -138.149619) (xy 122.373354 -138.105476)
			(xy 122.413503 -138.066767) (xy 122.458861 -138.034316) (xy 122.508461 -138.008815) (xy 122.561245 -137.990808)
			(xy 122.616088 -137.980678) (xy 122.671822 -137.978641) (xy 122.727259 -137.984741) (xy 122.781216 -137.998847)
			(xy 122.832545 -138.020659) (xy 122.880151 -138.049713) (xy 122.923019 -138.085388) (xy 122.960236 -138.126925)
			(xy 122.991009 -138.173438) (xy 123.014681 -138.223935) (xy 123.030749 -138.277342) (xy 123.038869 -138.332518)
			(xy 123.039378 -138.360404) (xy 123.038869 -138.38829) (xy 123.036656 -138.40333) (xy 131.296156 -138.40333)
			(xy 131.296666 -138.375664) (xy 131.304662 -138.320914) (xy 131.320477 -138.267891) (xy 131.34378 -138.217706)
			(xy 131.374082 -138.17141) (xy 131.41075 -138.129973) (xy 131.453014 -138.094262) (xy 131.476242 -138.079226)
			(xy 131.486402 -138.072876) (xy 131.498848 -138.053318) (xy 131.509262 -137.949178) (xy 131.501134 -137.927334)
			(xy 131.492244 -137.918952) (xy 131.473666 -137.900868) (xy 131.441085 -137.860538) (xy 131.414271 -137.816164)
			(xy 131.393717 -137.768566) (xy 131.379804 -137.718622) (xy 131.372787 -137.667253) (xy 131.372356 -137.64133)
			(xy 131.372906 -137.614081) (xy 131.380658 -137.560138) (xy 131.396007 -137.507846) (xy 131.418642 -137.458272)
			(xy 131.448102 -137.412423) (xy 131.483787 -137.371233) (xy 131.52497 -137.335541) (xy 131.570814 -137.306074)
			(xy 131.620384 -137.28343) (xy 131.672673 -137.268072) (xy 131.726615 -137.260311) (xy 131.753864 -137.259822)
			(xy 131.781234 -137.260304) (xy 131.835412 -137.268117) (xy 131.887915 -137.283602) (xy 131.937663 -137.30644)
			(xy 131.98363 -137.336162) (xy 132.004562 -137.353802) (xy 132.011674 -137.359898) (xy 132.028692 -137.366248)
			(xy 132.114036 -137.366248) (xy 132.131054 -137.359898) (xy 132.138166 -137.353802) (xy 132.1591 -137.336166)
			(xy 132.205072 -137.306453) (xy 132.254819 -137.283617) (xy 132.30732 -137.268125) (xy 132.361495 -137.260296)
			(xy 132.388864 -137.259822) (xy 132.416117 -137.260289) (xy 132.47007 -137.268042) (xy 132.522369 -137.283395)
			(xy 132.571951 -137.306035) (xy 132.617806 -137.335502) (xy 132.659 -137.371196) (xy 132.694694 -137.412389)
			(xy 132.724162 -137.458243) (xy 132.746803 -137.507825) (xy 132.762157 -137.560124) (xy 132.769911 -137.614077)
			(xy 132.770372 -137.64133) (xy 132.769814 -137.670246) (xy 132.761095 -137.727415) (xy 132.743846 -137.782614)
			(xy 132.718461 -137.834576) (xy 132.685524 -137.882111) (xy 132.645789 -137.924129) (xy 132.623306 -137.94232)
			(xy 132.61454 -137.949879) (xy 132.604359 -137.97064) (xy 132.603748 -137.982198) (xy 132.603748 -138.062462)
			(xy 132.604324 -138.07403) (xy 132.614513 -138.094802) (xy 132.623306 -138.10234) (xy 132.64581 -138.120507)
			(xy 132.685544 -138.162532) (xy 132.71848 -138.210072) (xy 132.743865 -138.262038) (xy 132.761117 -138.31724)
			(xy 132.76984 -138.374413) (xy 132.770372 -138.40333) (xy 132.769973 -138.430585) (xy 132.762211 -138.48454)
			(xy 132.750105 -138.525758) (xy 133.041644 -138.525758) (xy 133.042133 -138.498388) (xy 133.049944 -138.44421)
			(xy 133.065427 -138.391707) (xy 133.088264 -138.341959) (xy 133.117984 -138.295992) (xy 133.135624 -138.27506)
			(xy 133.14172 -138.267948) (xy 133.14807 -138.25093) (xy 133.14807 -138.165586) (xy 133.14172 -138.148568)
			(xy 133.135624 -138.141456) (xy 133.117942 -138.120557) (xy 133.088219 -138.074583) (xy 133.065377 -138.024831)
			(xy 133.049884 -137.972324) (xy 133.042059 -137.918141) (xy 133.042064 -137.863396) (xy 133.049897 -137.809214)
			(xy 133.065399 -137.75671) (xy 133.08825 -137.706962) (xy 133.11798 -137.660993) (xy 133.135624 -137.64006)
			(xy 133.14172 -137.632948) (xy 133.14807 -137.61593) (xy 133.14807 -137.530586) (xy 133.14172 -137.513568)
			(xy 133.135624 -137.506456) (xy 133.117942 -137.485557) (xy 133.088219 -137.439583) (xy 133.065377 -137.389831)
			(xy 133.049884 -137.337324) (xy 133.042059 -137.283141) (xy 133.042064 -137.228396) (xy 133.049897 -137.174214)
			(xy 133.065399 -137.12171) (xy 133.08825 -137.071962) (xy 133.11798 -137.025993) (xy 133.135624 -137.00506)
			(xy 133.14172 -136.997948) (xy 133.14807 -136.98093) (xy 133.14807 -136.895586) (xy 133.14172 -136.878568)
			(xy 133.135624 -136.871456) (xy 133.118001 -136.850511) (xy 133.088286 -136.804542) (xy 133.065447 -136.754798)
			(xy 133.049952 -136.7023) (xy 133.04212 -136.648126) (xy 133.041644 -136.620758) (xy 133.04213 -136.593507)
			(xy 133.049886 -136.539559) (xy 133.065241 -136.487264) (xy 133.087883 -136.437687) (xy 133.117349 -136.391837)
			(xy 133.15304 -136.350646) (xy 133.194231 -136.314955) (xy 133.240081 -136.285489) (xy 133.289658 -136.262847)
			(xy 133.341953 -136.247492) (xy 133.395901 -136.239736) (xy 133.450403 -136.239736) (xy 133.504351 -136.247492)
			(xy 133.556646 -136.262847) (xy 133.606223 -136.285489) (xy 133.652073 -136.314955) (xy 133.693264 -136.350646)
			(xy 133.728955 -136.391837) (xy 133.758421 -136.437687) (xy 133.781063 -136.487264) (xy 133.796418 -136.539559)
			(xy 133.804174 -136.593507) (xy 133.80466 -136.620758) (xy 133.804179 -136.648128) (xy 133.796366 -136.702307)
			(xy 133.780881 -136.75481) (xy 133.758043 -136.804557) (xy 133.72832 -136.850524) (xy 133.71068 -136.871456)
			(xy 133.704584 -136.878568) (xy 133.698234 -136.895586) (xy 133.698234 -136.98093) (xy 133.704584 -136.997948)
			(xy 133.71068 -137.00506) (xy 133.728279 -137.026026) (xy 133.758005 -137.071988) (xy 133.780853 -137.121729)
			(xy 133.796352 -137.174226) (xy 133.804184 -137.2284) (xy 133.804189 -137.283137) (xy 133.796365 -137.337312)
			(xy 133.780875 -137.389812) (xy 133.758036 -137.439556) (xy 133.728317 -137.485523) (xy 133.71068 -137.506456)
			(xy 133.704584 -137.513568) (xy 133.698234 -137.530586) (xy 133.698234 -137.61593) (xy 133.704584 -137.632948)
			(xy 133.71068 -137.64006) (xy 133.728279 -137.661026) (xy 133.758005 -137.706988) (xy 133.780853 -137.756729)
			(xy 133.796352 -137.809226) (xy 133.804184 -137.8634) (xy 133.804189 -137.918137) (xy 133.796365 -137.972312)
			(xy 133.780875 -138.024812) (xy 133.758036 -138.074556) (xy 133.728317 -138.120523) (xy 133.71068 -138.141456)
			(xy 133.704584 -138.148568) (xy 133.698234 -138.165586) (xy 133.698234 -138.25093) (xy 133.704584 -138.267948)
			(xy 133.71068 -138.27506) (xy 133.728311 -138.295999) (xy 133.758024 -138.34197) (xy 133.780862 -138.391715)
			(xy 133.796355 -138.444215) (xy 133.804185 -138.498389) (xy 133.80466 -138.525758) (xy 133.804185 -138.552387)
			(xy 133.796782 -138.605129) (xy 133.782114 -138.656328) (xy 133.760466 -138.704988) (xy 133.732259 -138.750164)
			(xy 133.715506 -138.770868) (xy 133.707632 -138.780266) (xy 133.702044 -138.80338) (xy 133.726428 -138.906504)
			(xy 133.741668 -138.924538) (xy 133.752844 -138.929364) (xy 133.779561 -138.941549) (xy 133.829186 -138.972936)
			(xy 133.85165 -138.991848) (xy 133.858762 -138.997944) (xy 133.87578 -139.004294) (xy 133.961124 -139.004294)
			(xy 133.978142 -138.997944) (xy 133.985254 -138.991848) (xy 134.006187 -138.974207) (xy 134.052155 -138.944483)
			(xy 134.101901 -138.921637) (xy 134.154403 -138.906141) (xy 134.208581 -138.898312) (xy 134.263323 -138.898312)
			(xy 134.317501 -138.906141) (xy 134.370003 -138.921637) (xy 134.419749 -138.944483) (xy 134.465717 -138.974207)
			(xy 134.48665 -138.991848) (xy 134.493762 -138.997944) (xy 134.51078 -139.004294) (xy 134.596124 -139.004294)
			(xy 134.613142 -138.997944) (xy 134.620254 -138.991848) (xy 134.641187 -138.974207) (xy 134.687155 -138.944483)
			(xy 134.736901 -138.921637) (xy 134.789403 -138.906141) (xy 134.843581 -138.898312) (xy 134.898323 -138.898312)
			(xy 134.952501 -138.906141) (xy 135.005003 -138.921637) (xy 135.054749 -138.944483) (xy 135.100717 -138.974207)
			(xy 135.12165 -138.991848) (xy 135.128762 -138.997944) (xy 135.14578 -139.004294) (xy 135.231124 -139.004294)
			(xy 135.248142 -138.997944) (xy 135.255254 -138.991848) (xy 135.276199 -138.974224) (xy 135.322167 -138.944509)
			(xy 135.371912 -138.921669) (xy 135.42441 -138.906174) (xy 135.478584 -138.898343) (xy 135.505952 -138.897868)
			(xy 135.533205 -138.898376) (xy 135.587158 -138.906127) (xy 135.639458 -138.921478) (xy 135.689041 -138.944116)
			(xy 135.734898 -138.973581) (xy 135.776094 -139.009272) (xy 135.81179 -139.050464) (xy 135.841261 -139.096316)
			(xy 135.863905 -139.145897) (xy 135.879263 -139.198195) (xy 135.887021 -139.252147) (xy 135.887021 -139.306653)
			(xy 135.879263 -139.360605) (xy 135.863905 -139.412903) (xy 135.841261 -139.462484) (xy 135.81179 -139.508336)
			(xy 135.776094 -139.549528) (xy 135.734898 -139.585219) (xy 135.689041 -139.614684) (xy 135.639458 -139.637322)
			(xy 135.587158 -139.652673) (xy 135.533205 -139.660424) (xy 135.505952 -139.660884) (xy 135.478583 -139.660391)
			(xy 135.424405 -139.652581) (xy 135.371902 -139.637098) (xy 135.322154 -139.614262) (xy 135.276186 -139.584543)
			(xy 135.255254 -139.566904) (xy 135.248142 -139.560808) (xy 135.231124 -139.554458) (xy 135.14578 -139.554458)
			(xy 135.128762 -139.560808) (xy 135.12165 -139.566904) (xy 135.100717 -139.584545) (xy 135.054749 -139.614269)
			(xy 135.005003 -139.637115) (xy 134.952501 -139.652611) (xy 134.898323 -139.66044) (xy 134.843581 -139.66044)
			(xy 134.789403 -139.652611) (xy 134.736901 -139.637115) (xy 134.687155 -139.614269) (xy 134.641187 -139.584545)
			(xy 134.620254 -139.566904) (xy 134.613142 -139.560808) (xy 134.596124 -139.554458) (xy 134.51078 -139.554458)
			(xy 134.493762 -139.560808) (xy 134.48665 -139.566904) (xy 134.465717 -139.584545) (xy 134.419749 -139.614269)
			(xy 134.370003 -139.637115) (xy 134.317501 -139.652611) (xy 134.263323 -139.66044) (xy 134.208581 -139.66044)
			(xy 134.154403 -139.652611) (xy 134.101901 -139.637115) (xy 134.052155 -139.614269) (xy 134.006187 -139.584545)
			(xy 133.985254 -139.566904) (xy 133.978142 -139.560808) (xy 133.961124 -139.554458) (xy 133.87578 -139.554458)
			(xy 133.858762 -139.560808) (xy 133.85165 -139.566904) (xy 133.83071 -139.584534) (xy 133.78474 -139.614247)
			(xy 133.734994 -139.637085) (xy 133.682495 -139.652578) (xy 133.628321 -139.660409) (xy 133.600952 -139.660884)
			(xy 133.573698 -139.660467) (xy 133.519747 -139.652703) (xy 133.46745 -139.637341) (xy 133.417871 -139.614692)
			(xy 133.372019 -139.585219) (xy 133.330829 -139.54952) (xy 133.295138 -139.508323) (xy 133.265673 -139.462466)
			(xy 133.243034 -139.412883) (xy 133.227682 -139.360583) (xy 133.219928 -139.30663) (xy 133.219444 -139.279376)
			(xy 133.21988 -139.252745) (xy 133.227292 -139.200002) (xy 133.241969 -139.148803) (xy 133.263626 -139.100143)
			(xy 133.291841 -139.054969) (xy 133.308598 -139.034266) (xy 133.316472 -139.024868) (xy 133.32206 -139.001754)
			(xy 133.297676 -138.89863) (xy 133.282436 -138.880596) (xy 133.27126 -138.87577) (xy 133.246048 -138.864275)
			(xy 133.198951 -138.835085) (xy 133.156571 -138.799391) (xy 133.119797 -138.757944) (xy 133.089403 -138.711615)
			(xy 133.066029 -138.661377) (xy 133.050164 -138.608288) (xy 133.042143 -138.553462) (xy 133.041644 -138.525758)
			(xy 132.750105 -138.525758) (xy 132.746849 -138.536842) (xy 132.724201 -138.586424) (xy 132.694726 -138.632279)
			(xy 132.659026 -138.673472) (xy 132.617826 -138.709166) (xy 132.571966 -138.738632) (xy 132.52238 -138.761272)
			(xy 132.470076 -138.776625) (xy 132.416119 -138.784378) (xy 132.388864 -138.784838) (xy 132.362548 -138.784377)
			(xy 132.310415 -138.777156) (xy 132.259768 -138.762844) (xy 132.211566 -138.741711) (xy 132.166724 -138.714158)
			(xy 132.126091 -138.680707) (xy 132.10794 -138.661648) (xy 132.100399 -138.654269) (xy 132.081134 -138.64573)
			(xy 132.070602 -138.645138) (xy 131.995926 -138.645138) (xy 131.985375 -138.645657) (xy 131.966079 -138.654198)
			(xy 131.958588 -138.661648) (xy 131.940449 -138.680723) (xy 131.899831 -138.714204) (xy 131.854991 -138.741776)
			(xy 131.806785 -138.762916) (xy 131.756127 -138.77722) (xy 131.703983 -138.784418) (xy 131.677664 -138.784838)
			(xy 131.650413 -138.784356) (xy 131.596467 -138.776595) (xy 131.544174 -138.761237) (xy 131.494599 -138.738594)
			(xy 131.44875 -138.709127) (xy 131.407561 -138.673435) (xy 131.37187 -138.632245) (xy 131.342403 -138.586396)
			(xy 131.319761 -138.53682) (xy 131.304404 -138.484527) (xy 131.296644 -138.430581) (xy 131.296156 -138.40333)
			(xy 123.036656 -138.40333) (xy 123.030749 -138.443466) (xy 123.014681 -138.496873) (xy 122.991009 -138.54737)
			(xy 122.960236 -138.593883) (xy 122.923019 -138.63542) (xy 122.880151 -138.671095) (xy 122.832545 -138.700149)
			(xy 122.781216 -138.721961) (xy 122.727259 -138.736067) (xy 122.671822 -138.742167) (xy 122.616088 -138.74013)
			(xy 122.561245 -138.73) (xy 122.508461 -138.711993) (xy 122.458861 -138.686492) (xy 122.413503 -138.654041)
			(xy 122.373354 -138.615332) (xy 122.339268 -138.571189) (xy 122.311972 -138.522554) (xy 122.292049 -138.470463)
			(xy 122.279923 -138.416026) (xy 122.275852 -138.360404) (xy 121.998486 -138.360404) (xy 121.998486 -138.824462)
			(xy 124.461776 -138.824462) (xy 124.465847 -138.76884) (xy 124.477973 -138.714403) (xy 124.497896 -138.662312)
			(xy 124.525192 -138.613677) (xy 124.559278 -138.569534) (xy 124.599427 -138.530825) (xy 124.644785 -138.498374)
			(xy 124.694385 -138.472873) (xy 124.747169 -138.454866) (xy 124.802012 -138.444736) (xy 124.857746 -138.442699)
			(xy 124.913183 -138.448799) (xy 124.96714 -138.462905) (xy 125.018469 -138.484717) (xy 125.066075 -138.513771)
			(xy 125.108943 -138.549446) (xy 125.14616 -138.590983) (xy 125.176933 -138.637496) (xy 125.200605 -138.687993)
			(xy 125.216673 -138.7414) (xy 125.224793 -138.796576) (xy 125.225302 -138.824462) (xy 125.224793 -138.852348)
			(xy 125.216673 -138.907524) (xy 125.200605 -138.960931) (xy 125.176933 -139.011428) (xy 125.14616 -139.057941)
			(xy 125.108943 -139.099478) (xy 125.066075 -139.135153) (xy 125.018469 -139.164207) (xy 124.96714 -139.186019)
			(xy 124.913183 -139.200125) (xy 124.857746 -139.206225) (xy 124.802012 -139.204188) (xy 124.747169 -139.194058)
			(xy 124.694385 -139.176051) (xy 124.644785 -139.15055) (xy 124.599427 -139.118099) (xy 124.559278 -139.07939)
			(xy 124.525192 -139.035247) (xy 124.497896 -138.986612) (xy 124.477973 -138.934521) (xy 124.465847 -138.880084)
			(xy 124.461776 -138.824462) (xy 121.998486 -138.824462) (xy 121.998486 -139.376404) (xy 122.275852 -139.376404)
			(xy 122.279923 -139.320782) (xy 122.292049 -139.266345) (xy 122.311972 -139.214254) (xy 122.339268 -139.165619)
			(xy 122.373354 -139.121476) (xy 122.413503 -139.082767) (xy 122.458861 -139.050316) (xy 122.508461 -139.024815)
			(xy 122.561245 -139.006808) (xy 122.616088 -138.996678) (xy 122.671822 -138.994641) (xy 122.727259 -139.000741)
			(xy 122.781216 -139.014847) (xy 122.832545 -139.036659) (xy 122.880151 -139.065713) (xy 122.923019 -139.101388)
			(xy 122.960236 -139.142925) (xy 122.991009 -139.189438) (xy 123.014681 -139.239935) (xy 123.030749 -139.293342)
			(xy 123.038869 -139.348518) (xy 123.039378 -139.376404) (xy 123.038869 -139.40429) (xy 123.030749 -139.459466)
			(xy 123.014681 -139.512873) (xy 122.991009 -139.56337) (xy 122.960236 -139.609883) (xy 122.923019 -139.65142)
			(xy 122.880151 -139.687095) (xy 122.832545 -139.716149) (xy 122.781216 -139.737961) (xy 122.727259 -139.752067)
			(xy 122.671822 -139.758167) (xy 122.616088 -139.75613) (xy 122.561245 -139.746) (xy 122.508461 -139.727993)
			(xy 122.458861 -139.702492) (xy 122.413503 -139.670041) (xy 122.373354 -139.631332) (xy 122.339268 -139.587189)
			(xy 122.311972 -139.538554) (xy 122.292049 -139.486463) (xy 122.279923 -139.432026) (xy 122.275852 -139.376404)
			(xy 121.998486 -139.376404) (xy 121.998486 -140.392404) (xy 124.467618 -140.392404) (xy 124.471689 -140.336782)
			(xy 124.483815 -140.282345) (xy 124.503738 -140.230254) (xy 124.531034 -140.181619) (xy 124.56512 -140.137476)
			(xy 124.605269 -140.098767) (xy 124.650627 -140.066316) (xy 124.700227 -140.040815) (xy 124.753011 -140.022808)
			(xy 124.807854 -140.012678) (xy 124.863588 -140.010641) (xy 124.919025 -140.016741) (xy 124.972982 -140.030847)
			(xy 125.024311 -140.052659) (xy 125.071917 -140.081713) (xy 125.114785 -140.117388) (xy 125.152002 -140.158925)
			(xy 125.182775 -140.205438) (xy 125.206447 -140.255935) (xy 125.222515 -140.309342) (xy 125.230635 -140.364518)
			(xy 125.231144 -140.392404) (xy 125.230635 -140.42029) (xy 125.222515 -140.475466) (xy 125.206447 -140.528873)
			(xy 125.182775 -140.57937) (xy 125.152002 -140.625883) (xy 125.114785 -140.66742) (xy 125.071917 -140.703095)
			(xy 125.024311 -140.732149) (xy 124.972982 -140.753961) (xy 124.919025 -140.768067) (xy 124.863588 -140.774167)
			(xy 124.807854 -140.77213) (xy 124.753011 -140.762) (xy 124.700227 -140.743993) (xy 124.650627 -140.718492)
			(xy 124.605269 -140.686041) (xy 124.56512 -140.647332) (xy 124.531034 -140.603189) (xy 124.503738 -140.554554)
			(xy 124.483815 -140.502463) (xy 124.471689 -140.448026) (xy 124.467618 -140.392404) (xy 121.998486 -140.392404)
			(xy 121.998486 -141.046551) (xy 126.854954 -141.046551) (xy 126.854954 -140.992049) (xy 126.86271 -140.9381)
			(xy 126.878064 -140.885805) (xy 126.900704 -140.836227) (xy 126.930169 -140.790375) (xy 126.965859 -140.749183)
			(xy 127.007048 -140.71349) (xy 127.052897 -140.684021) (xy 127.102473 -140.661376) (xy 127.154767 -140.646017)
			(xy 127.208715 -140.638256) (xy 127.235966 -140.637768) (xy 127.262282 -140.638208) (xy 127.314417 -140.645432)
			(xy 127.365065 -140.659748) (xy 127.413266 -140.680885) (xy 127.458108 -140.708442) (xy 127.49874 -140.741897)
			(xy 127.51689 -140.760958) (xy 127.524419 -140.768351) (xy 127.543693 -140.776882) (xy 127.554228 -140.777468)
			(xy 127.628904 -140.777468) (xy 127.639457 -140.776964) (xy 127.658752 -140.768412) (xy 127.666242 -140.760958)
			(xy 127.684368 -140.741869) (xy 127.724989 -140.70839) (xy 127.769831 -140.680819) (xy 127.81804 -140.659682)
			(xy 127.8687 -140.64538) (xy 127.920846 -140.638186) (xy 127.947166 -140.637768) (xy 127.974419 -140.638277)
			(xy 128.02837 -140.64603) (xy 128.080669 -140.661382) (xy 128.13025 -140.684021) (xy 128.176104 -140.713486)
			(xy 128.217299 -140.749177) (xy 128.252994 -140.790368) (xy 128.282463 -140.83622) (xy 128.305106 -140.8858)
			(xy 128.320463 -140.938097) (xy 128.328221 -140.992047) (xy 128.328221 -141.046553) (xy 128.320463 -141.100503)
			(xy 128.305106 -141.1528) (xy 128.282463 -141.20238) (xy 128.252994 -141.248232) (xy 128.217299 -141.289423)
			(xy 128.176104 -141.325114) (xy 128.13025 -141.354579) (xy 128.080669 -141.377218) (xy 128.02837 -141.39257)
			(xy 127.974419 -141.400323) (xy 127.947166 -141.400784) (xy 127.92085 -141.400338) (xy 127.868715 -141.393118)
			(xy 127.818067 -141.378803) (xy 127.769865 -141.357668) (xy 127.725023 -141.330111) (xy 127.684392 -141.296655)
			(xy 127.666242 -141.277594) (xy 127.658707 -141.270208) (xy 127.639437 -141.261675) (xy 127.628904 -141.261084)
			(xy 127.554228 -141.261084) (xy 127.543679 -141.26162) (xy 127.524384 -141.270151) (xy 127.51689 -141.277594)
			(xy 127.498759 -141.296677) (xy 127.458138 -141.330155) (xy 127.413297 -141.357725) (xy 127.365088 -141.378863)
			(xy 127.31443 -141.393167) (xy 127.262286 -141.400364) (xy 127.235966 -141.400784) (xy 127.208715 -141.400344)
			(xy 127.154767 -141.392583) (xy 127.102473 -141.377224) (xy 127.052897 -141.354579) (xy 127.007048 -141.32511)
			(xy 126.965859 -141.289417) (xy 126.930169 -141.248225) (xy 126.900704 -141.202373) (xy 126.878064 -141.152795)
			(xy 126.86271 -141.1005) (xy 126.854954 -141.046551) (xy 121.998486 -141.046551) (xy 121.998486 -143.078551)
			(xy 126.854954 -143.078551) (xy 126.854954 -143.024049) (xy 126.86271 -142.9701) (xy 126.878064 -142.917805)
			(xy 126.900704 -142.868227) (xy 126.930169 -142.822375) (xy 126.965859 -142.781183) (xy 127.007048 -142.74549)
			(xy 127.052897 -142.716021) (xy 127.102473 -142.693376) (xy 127.154767 -142.678017) (xy 127.208715 -142.670256)
			(xy 127.235966 -142.669768) (xy 127.262282 -142.670208) (xy 127.314417 -142.677432) (xy 127.365065 -142.691748)
			(xy 127.413266 -142.712885) (xy 127.458108 -142.740442) (xy 127.49874 -142.773897) (xy 127.51689 -142.792958)
			(xy 127.524419 -142.800351) (xy 127.543693 -142.808882) (xy 127.554228 -142.809468) (xy 127.628904 -142.809468)
			(xy 127.639457 -142.808964) (xy 127.658752 -142.800412) (xy 127.666242 -142.792958) (xy 127.684368 -142.773869)
			(xy 127.724989 -142.74039) (xy 127.769831 -142.712819) (xy 127.81804 -142.691682) (xy 127.8687 -142.67738)
			(xy 127.920846 -142.670186) (xy 127.947166 -142.669768) (xy 127.974419 -142.670277) (xy 128.02837 -142.67803)
			(xy 128.080669 -142.693382) (xy 128.13025 -142.716021) (xy 128.176104 -142.745486) (xy 128.217299 -142.781177)
			(xy 128.252994 -142.822368) (xy 128.282463 -142.86822) (xy 128.305106 -142.9178) (xy 128.320463 -142.970097)
			(xy 128.328221 -143.024047) (xy 128.328221 -143.078553) (xy 128.320463 -143.132503) (xy 128.305106 -143.1848)
			(xy 128.282463 -143.23438) (xy 128.252994 -143.280232) (xy 128.217299 -143.321423) (xy 128.176104 -143.357114)
			(xy 128.13025 -143.386579) (xy 128.080669 -143.409218) (xy 128.02837 -143.42457) (xy 127.974419 -143.432323)
			(xy 127.947166 -143.432784) (xy 127.92085 -143.432338) (xy 127.868715 -143.425118) (xy 127.818067 -143.410803)
			(xy 127.769865 -143.389668) (xy 127.725023 -143.362111) (xy 127.684392 -143.328655) (xy 127.666242 -143.309594)
			(xy 127.658707 -143.302208) (xy 127.639437 -143.293675) (xy 127.628904 -143.293084) (xy 127.554228 -143.293084)
			(xy 127.543679 -143.29362) (xy 127.524384 -143.302151) (xy 127.51689 -143.309594) (xy 127.498759 -143.328677)
			(xy 127.458138 -143.362155) (xy 127.413297 -143.389725) (xy 127.365088 -143.410863) (xy 127.31443 -143.425167)
			(xy 127.262286 -143.432364) (xy 127.235966 -143.432784) (xy 127.208715 -143.432344) (xy 127.154767 -143.424583)
			(xy 127.102473 -143.409224) (xy 127.052897 -143.386579) (xy 127.007048 -143.35711) (xy 126.965859 -143.321417)
			(xy 126.930169 -143.280225) (xy 126.900704 -143.234373) (xy 126.878064 -143.184795) (xy 126.86271 -143.1325)
			(xy 126.854954 -143.078551) (xy 121.998486 -143.078551) (xy 121.998486 -143.966438) (xy 135.564118 -143.966438)
			(xy 135.564527 -143.940462) (xy 135.571578 -143.88899) (xy 135.585553 -143.838952) (xy 135.606195 -143.791276)
			(xy 135.63312 -143.746845) (xy 135.66583 -143.706483) (xy 135.703718 -143.670936) (xy 135.724646 -143.655542)
			(xy 135.734137 -143.64791) (xy 135.745282 -143.626298) (xy 135.745982 -143.61414) (xy 135.745982 -143.531336)
			(xy 135.745289 -143.519174) (xy 135.73415 -143.497553) (xy 135.724646 -143.489934) (xy 135.703727 -143.474531)
			(xy 135.665851 -143.438978) (xy 135.633151 -143.398613) (xy 135.606232 -143.354184) (xy 135.585593 -143.306511)
			(xy 135.571616 -143.256479) (xy 135.56456 -143.205012) (xy 135.564118 -143.179038) (xy 135.564626 -143.150299)
			(xy 135.573256 -143.093472) (xy 135.590311 -143.038582) (xy 135.615405 -142.98687) (xy 135.647971 -142.939507)
			(xy 135.667242 -142.91818) (xy 135.673846 -142.911068) (xy 135.680958 -142.893542) (xy 135.680958 -142.804134)
			(xy 135.673846 -142.786608) (xy 135.667242 -142.779496) (xy 135.648008 -142.758137) (xy 135.61544 -142.710781)
			(xy 135.590345 -142.659074) (xy 135.573292 -142.604188) (xy 135.564665 -142.547365) (xy 135.564661 -142.489891)
			(xy 135.573279 -142.433066) (xy 135.590325 -142.378177) (xy 135.615412 -142.326467) (xy 135.647973 -142.279106)
			(xy 135.667242 -142.25778) (xy 135.673846 -142.250668) (xy 135.680958 -142.233142) (xy 135.680958 -142.143734)
			(xy 135.673846 -142.126208) (xy 135.667242 -142.119096) (xy 135.648008 -142.097737) (xy 135.61544 -142.050381)
			(xy 135.590345 -141.998674) (xy 135.573292 -141.943788) (xy 135.564665 -141.886965) (xy 135.564661 -141.829491)
			(xy 135.573279 -141.772666) (xy 135.590325 -141.717777) (xy 135.615412 -141.666067) (xy 135.647973 -141.618706)
			(xy 135.667242 -141.59738) (xy 135.673846 -141.590268) (xy 135.680958 -141.572742) (xy 135.680958 -141.483334)
			(xy 135.673846 -141.465808) (xy 135.667242 -141.458696) (xy 135.648008 -141.437337) (xy 135.61544 -141.389981)
			(xy 135.590345 -141.338274) (xy 135.573292 -141.283388) (xy 135.564665 -141.226565) (xy 135.564661 -141.169091)
			(xy 135.573279 -141.112266) (xy 135.590325 -141.057377) (xy 135.615412 -141.005667) (xy 135.647973 -140.958306)
			(xy 135.667242 -140.93698) (xy 135.673846 -140.929868) (xy 135.680958 -140.912342) (xy 135.680958 -140.822934)
			(xy 135.673846 -140.805408) (xy 135.667242 -140.798296) (xy 135.64799 -140.776953) (xy 135.615421 -140.729595)
			(xy 135.590325 -140.677888) (xy 135.57327 -140.623001) (xy 135.564642 -140.566176) (xy 135.564118 -140.537438)
			(xy 135.564604 -140.510187) (xy 135.57236 -140.456239) (xy 135.587715 -140.403944) (xy 135.610357 -140.354367)
			(xy 135.639823 -140.308517) (xy 135.675514 -140.267326) (xy 135.716705 -140.231635) (xy 135.762555 -140.202169)
			(xy 135.812132 -140.179527) (xy 135.864427 -140.164172) (xy 135.918375 -140.156416) (xy 135.972877 -140.156416)
			(xy 136.026825 -140.164172) (xy 136.07912 -140.179527) (xy 136.128697 -140.202169) (xy 136.174547 -140.231635)
			(xy 136.215738 -140.267326) (xy 136.251429 -140.308517) (xy 136.280895 -140.354367) (xy 136.303537 -140.403944)
			(xy 136.318892 -140.456239) (xy 136.326648 -140.510187) (xy 136.327134 -140.537438) (xy 136.326624 -140.566177)
			(xy 136.317997 -140.623005) (xy 136.300943 -140.677895) (xy 136.275849 -140.729607) (xy 136.243281 -140.776969)
			(xy 136.22401 -140.798296) (xy 136.217406 -140.805408) (xy 136.210294 -140.822934) (xy 136.210294 -140.912342)
			(xy 136.217406 -140.929868) (xy 136.22401 -140.93698) (xy 136.243317 -140.958275) (xy 136.275878 -141.005644)
			(xy 136.300965 -141.057361) (xy 136.318011 -141.112256) (xy 136.326629 -141.169087) (xy 136.326625 -141.226568)
			(xy 136.317999 -141.283398) (xy 136.300945 -141.338291) (xy 136.27585 -141.390004) (xy 136.243282 -141.437368)
			(xy 136.22401 -141.458696) (xy 136.217406 -141.465808) (xy 136.210294 -141.483334) (xy 136.210294 -141.572742)
			(xy 136.217406 -141.590268) (xy 136.22401 -141.59738) (xy 136.243317 -141.618675) (xy 136.275878 -141.666044)
			(xy 136.300965 -141.717761) (xy 136.318011 -141.772656) (xy 136.326629 -141.829487) (xy 136.326625 -141.886968)
			(xy 136.317999 -141.943798) (xy 136.300945 -141.998691) (xy 136.27585 -142.050404) (xy 136.243282 -142.097768)
			(xy 136.22401 -142.119096) (xy 136.217406 -142.126208) (xy 136.210294 -142.143734) (xy 136.210294 -142.233142)
			(xy 136.217406 -142.250668) (xy 136.22401 -142.25778) (xy 136.243317 -142.279075) (xy 136.275878 -142.326444)
			(xy 136.300965 -142.378161) (xy 136.318011 -142.433056) (xy 136.326629 -142.489887) (xy 136.326625 -142.547368)
			(xy 136.317999 -142.604198) (xy 136.300945 -142.659091) (xy 136.27585 -142.710804) (xy 136.243282 -142.758168)
			(xy 136.22401 -142.779496) (xy 136.217406 -142.786608) (xy 136.210294 -142.804134) (xy 136.210294 -142.893542)
			(xy 136.217406 -142.911068) (xy 136.22401 -142.91818) (xy 136.24329 -142.939499) (xy 136.275857 -142.986863)
			(xy 136.300948 -143.038576) (xy 136.317996 -143.093469) (xy 136.326615 -143.150298) (xy 136.327134 -143.179038)
			(xy 136.326727 -143.205015) (xy 136.319679 -143.256488) (xy 136.305704 -143.306526) (xy 136.285063 -143.354203)
			(xy 136.258137 -143.398634) (xy 136.225426 -143.438996) (xy 136.187535 -143.474541) (xy 136.166606 -143.489934)
			(xy 136.157135 -143.497587) (xy 136.145977 -143.519183) (xy 136.14527 -143.531336) (xy 136.14527 -143.61414)
			(xy 136.145957 -143.626303) (xy 136.157098 -143.647926) (xy 136.166606 -143.655542) (xy 136.187525 -143.670945)
			(xy 136.225399 -143.706499) (xy 136.258098 -143.746865) (xy 136.285015 -143.791294) (xy 136.305654 -143.838966)
			(xy 136.319632 -143.888998) (xy 136.326691 -143.940464) (xy 136.327134 -143.966438) (xy 136.326648 -143.993689)
			(xy 136.318892 -144.047637) (xy 136.303537 -144.099932) (xy 136.280895 -144.149509) (xy 136.251429 -144.195359)
			(xy 136.215738 -144.23655) (xy 136.174547 -144.272241) (xy 136.128697 -144.301707) (xy 136.07912 -144.324349)
			(xy 136.026825 -144.339704) (xy 135.972877 -144.34746) (xy 135.918375 -144.34746) (xy 135.864427 -144.339704)
			(xy 135.812132 -144.324349) (xy 135.762555 -144.301707) (xy 135.716705 -144.272241) (xy 135.675514 -144.23655)
			(xy 135.639823 -144.195359) (xy 135.610357 -144.149509) (xy 135.587715 -144.099932) (xy 135.57236 -144.047637)
			(xy 135.564604 -143.993689) (xy 135.564118 -143.966438) (xy 121.998486 -143.966438) (xy 121.998486 -145.110551)
			(xy 126.854954 -145.110551) (xy 126.854954 -145.056049) (xy 126.86271 -145.0021) (xy 126.878064 -144.949805)
			(xy 126.900704 -144.900227) (xy 126.930169 -144.854375) (xy 126.965859 -144.813183) (xy 127.007048 -144.77749)
			(xy 127.052897 -144.748021) (xy 127.102473 -144.725376) (xy 127.154767 -144.710017) (xy 127.208715 -144.702256)
			(xy 127.235966 -144.701768) (xy 127.262282 -144.702208) (xy 127.314417 -144.709432) (xy 127.365065 -144.723748)
			(xy 127.413266 -144.744885) (xy 127.458108 -144.772442) (xy 127.49874 -144.805897) (xy 127.51689 -144.824958)
			(xy 127.524419 -144.832351) (xy 127.543693 -144.840882) (xy 127.554228 -144.841468) (xy 127.628904 -144.841468)
			(xy 127.639457 -144.840964) (xy 127.658752 -144.832412) (xy 127.666242 -144.824958) (xy 127.684368 -144.805869)
			(xy 127.724989 -144.77239) (xy 127.769831 -144.744819) (xy 127.81804 -144.723682) (xy 127.8687 -144.70938)
			(xy 127.920846 -144.702186) (xy 127.947166 -144.701768) (xy 127.974419 -144.702277) (xy 128.02837 -144.71003)
			(xy 128.080669 -144.725382) (xy 128.13025 -144.748021) (xy 128.176104 -144.777486) (xy 128.217299 -144.813177)
			(xy 128.252994 -144.854368) (xy 128.282463 -144.90022) (xy 128.305106 -144.9498) (xy 128.306411 -144.954244)
			(xy 134.038848 -144.954244) (xy 134.039419 -144.926996) (xy 134.047168 -144.873054) (xy 134.062516 -144.820763)
			(xy 134.085149 -144.771189) (xy 134.114606 -144.725341) (xy 134.150289 -144.684151) (xy 134.19147 -144.648459)
			(xy 134.237312 -144.618991) (xy 134.286881 -144.596347) (xy 134.339167 -144.580987) (xy 134.393108 -144.573225)
			(xy 134.420356 -144.572736) (xy 134.44913 -144.573257) (xy 134.506025 -144.581907) (xy 134.560976 -144.599004)
			(xy 134.612736 -144.624159) (xy 134.660132 -144.656801) (xy 134.681468 -144.676114) (xy 134.689596 -144.683734)
			(xy 134.709154 -144.690592) (xy 134.805674 -144.68348) (xy 134.823962 -144.673574) (xy 134.83082 -144.664938)
			(xy 134.849055 -144.642762) (xy 134.890987 -144.603551) (xy 134.938321 -144.571063) (xy 134.989987 -144.546033)
			(xy 135.04482 -144.529025) (xy 135.101581 -144.520423) (xy 135.130286 -144.519904) (xy 135.157539 -144.520368)
			(xy 135.211491 -144.528124) (xy 135.263789 -144.543479) (xy 135.31337 -144.56612) (xy 135.359224 -144.595588)
			(xy 135.400417 -144.631282) (xy 135.436111 -144.672475) (xy 135.465579 -144.718328) (xy 135.488221 -144.767909)
			(xy 135.503576 -144.820207) (xy 135.511331 -144.874159) (xy 135.511794 -144.901412) (xy 135.511345 -144.928315)
			(xy 135.503772 -144.981586) (xy 135.48879 -145.033265) (xy 135.466698 -145.082327) (xy 135.437933 -145.127799)
			(xy 135.403067 -145.16878) (xy 135.362789 -145.204457) (xy 135.340598 -145.219674) (xy 135.329676 -145.226786)
			(xy 135.317738 -145.249646) (xy 135.31977 -145.361914) (xy 135.332724 -145.384266) (xy 135.3439 -145.391124)
			(xy 135.367501 -145.406046) (xy 135.410453 -145.441725) (xy 135.447747 -145.483283) (xy 135.478584 -145.529833)
			(xy 135.502308 -145.58038) (xy 135.51841 -145.633846) (xy 135.526548 -145.689087) (xy 135.527034 -145.717006)
			(xy 135.526579 -145.744) (xy 135.518972 -145.797448) (xy 135.50391 -145.849292) (xy 135.481695 -145.898496)
			(xy 135.452769 -145.94408) (xy 135.435594 -145.96491) (xy 135.428482 -145.973038) (xy 135.422386 -145.993612)
			(xy 135.434578 -146.089624) (xy 135.445754 -146.107912) (xy 135.454644 -146.114262) (xy 135.47585 -146.129648)
			(xy 135.514304 -146.16523) (xy 135.547524 -146.205741) (xy 135.574886 -146.250418) (xy 135.595874 -146.298421)
			(xy 135.610092 -146.348845) (xy 135.617273 -146.400741) (xy 135.617712 -146.426936) (xy 135.617226 -146.454187)
			(xy 135.60947 -146.508135) (xy 135.594115 -146.56043) (xy 135.571473 -146.610007) (xy 135.542007 -146.655857)
			(xy 135.506316 -146.697048) (xy 135.465125 -146.732739) (xy 135.419275 -146.762205) (xy 135.369698 -146.784847)
			(xy 135.317403 -146.800202) (xy 135.263455 -146.807958) (xy 135.208953 -146.807958) (xy 135.155005 -146.800202)
			(xy 135.10271 -146.784847) (xy 135.053133 -146.762205) (xy 135.007283 -146.732739) (xy 134.966092 -146.697048)
			(xy 134.930401 -146.655857) (xy 134.900935 -146.610007) (xy 134.878293 -146.56043) (xy 134.862938 -146.508135)
			(xy 134.855182 -146.454187) (xy 134.854696 -146.426936) (xy 134.855192 -146.399944) (xy 134.862792 -146.346498)
			(xy 134.877845 -146.294656) (xy 134.90005 -146.24545) (xy 134.928966 -146.199864) (xy 134.946136 -146.179032)
			(xy 134.953248 -146.170904) (xy 134.959344 -146.15033) (xy 134.947152 -146.054318) (xy 134.935976 -146.03603)
			(xy 134.927086 -146.02968) (xy 134.902785 -146.012068) (xy 134.859526 -145.970472) (xy 134.84098 -145.946876)
			(xy 134.834884 -145.938748) (xy 134.817866 -145.928588) (xy 134.726934 -145.91538) (xy 134.707884 -145.920206)
			(xy 134.699756 -145.926048) (xy 134.675012 -145.943552) (xy 134.62116 -145.971355) (xy 134.563588 -145.990291)
			(xy 134.503745 -145.999883) (xy 134.473442 -146.00047) (xy 134.446188 -146.000006) (xy 134.392236 -145.992253)
			(xy 134.339935 -145.976901) (xy 134.290353 -145.95426) (xy 134.244498 -145.924793) (xy 134.203304 -145.889099)
			(xy 134.167609 -145.847905) (xy 134.138142 -145.802051) (xy 134.115501 -145.752468) (xy 134.100148 -145.700168)
			(xy 134.092395 -145.646216) (xy 134.091934 -145.618962) (xy 134.092369 -145.592928) (xy 134.09946 -145.541345)
			(xy 134.113493 -145.491203) (xy 134.134206 -145.443432) (xy 134.161217 -145.398918) (xy 134.177278 -145.378424)
			(xy 134.183628 -145.370804) (xy 134.189216 -145.352262) (xy 134.182104 -145.2626) (xy 134.173468 -145.245328)
			(xy 134.166102 -145.238724) (xy 134.146463 -145.220535) (xy 134.111937 -145.179632) (xy 134.083465 -145.134305)
			(xy 134.061605 -145.085444) (xy 134.046787 -145.034009) (xy 134.039302 -144.981008) (xy 134.038848 -144.954244)
			(xy 128.306411 -144.954244) (xy 128.320463 -145.002097) (xy 128.328221 -145.056047) (xy 128.328221 -145.110553)
			(xy 128.320463 -145.164503) (xy 128.305106 -145.2168) (xy 128.282463 -145.26638) (xy 128.252994 -145.312232)
			(xy 128.217299 -145.353423) (xy 128.176104 -145.389114) (xy 128.13025 -145.418579) (xy 128.080669 -145.441218)
			(xy 128.02837 -145.45657) (xy 127.974419 -145.464323) (xy 127.947166 -145.464784) (xy 127.92085 -145.464338)
			(xy 127.868715 -145.457118) (xy 127.818067 -145.442803) (xy 127.769865 -145.421668) (xy 127.725023 -145.394111)
			(xy 127.684392 -145.360655) (xy 127.666242 -145.341594) (xy 127.658707 -145.334208) (xy 127.639437 -145.325675)
			(xy 127.628904 -145.325084) (xy 127.554228 -145.325084) (xy 127.543679 -145.32562) (xy 127.524384 -145.334151)
			(xy 127.51689 -145.341594) (xy 127.498759 -145.360677) (xy 127.458138 -145.394155) (xy 127.413297 -145.421725)
			(xy 127.365088 -145.442863) (xy 127.31443 -145.457167) (xy 127.262286 -145.464364) (xy 127.235966 -145.464784)
			(xy 127.208715 -145.464344) (xy 127.154767 -145.456583) (xy 127.102473 -145.441224) (xy 127.052897 -145.418579)
			(xy 127.007048 -145.38911) (xy 126.965859 -145.353417) (xy 126.930169 -145.312225) (xy 126.900704 -145.266373)
			(xy 126.878064 -145.216795) (xy 126.86271 -145.1645) (xy 126.854954 -145.110551) (xy 121.998486 -145.110551)
			(xy 121.998486 -146.91487) (xy 135.716008 -146.91487) (xy 135.720079 -146.859248) (xy 135.732205 -146.804811)
			(xy 135.752128 -146.75272) (xy 135.779424 -146.704085) (xy 135.81351 -146.659942) (xy 135.853659 -146.621233)
			(xy 135.899017 -146.588782) (xy 135.948617 -146.563281) (xy 136.001401 -146.545274) (xy 136.056244 -146.535144)
			(xy 136.111978 -146.533107) (xy 136.167415 -146.539207) (xy 136.221372 -146.553313) (xy 136.272701 -146.575125)
			(xy 136.320307 -146.604179) (xy 136.363175 -146.639854) (xy 136.400392 -146.681391) (xy 136.431165 -146.727904)
			(xy 136.454837 -146.778401) (xy 136.470905 -146.831808) (xy 136.479025 -146.886984) (xy 136.479534 -146.91487)
			(xy 136.479025 -146.942756) (xy 136.470905 -146.997932) (xy 136.454837 -147.051339) (xy 136.449631 -147.062444)
			(xy 137.094212 -147.062444) (xy 137.098283 -147.006822) (xy 137.110409 -146.952385) (xy 137.130332 -146.900294)
			(xy 137.157628 -146.851659) (xy 137.191714 -146.807516) (xy 137.231863 -146.768807) (xy 137.277221 -146.736356)
			(xy 137.326821 -146.710855) (xy 137.379605 -146.692848) (xy 137.434448 -146.682718) (xy 137.490182 -146.680681)
			(xy 137.545619 -146.686781) (xy 137.599576 -146.700887) (xy 137.650905 -146.722699) (xy 137.698511 -146.751753)
			(xy 137.741379 -146.787428) (xy 137.778596 -146.828965) (xy 137.809369 -146.875478) (xy 137.833041 -146.925975)
			(xy 137.849109 -146.979382) (xy 137.857229 -147.034558) (xy 137.857738 -147.062444) (xy 137.857229 -147.09033)
			(xy 137.849109 -147.145506) (xy 137.833041 -147.198913) (xy 137.809369 -147.24941) (xy 137.778596 -147.295923)
			(xy 137.741379 -147.33746) (xy 137.698511 -147.373135) (xy 137.650905 -147.402189) (xy 137.599576 -147.424001)
			(xy 137.545619 -147.438107) (xy 137.490182 -147.444207) (xy 137.434448 -147.44217) (xy 137.379605 -147.43204)
			(xy 137.326821 -147.414033) (xy 137.277221 -147.388532) (xy 137.231863 -147.356081) (xy 137.191714 -147.317372)
			(xy 137.157628 -147.273229) (xy 137.130332 -147.224594) (xy 137.110409 -147.172503) (xy 137.098283 -147.118066)
			(xy 137.094212 -147.062444) (xy 136.449631 -147.062444) (xy 136.431165 -147.101836) (xy 136.400392 -147.148349)
			(xy 136.363175 -147.189886) (xy 136.320307 -147.225561) (xy 136.272701 -147.254615) (xy 136.221372 -147.276427)
			(xy 136.167415 -147.290533) (xy 136.111978 -147.296633) (xy 136.056244 -147.294596) (xy 136.001401 -147.284466)
			(xy 135.948617 -147.266459) (xy 135.899017 -147.240958) (xy 135.853659 -147.208507) (xy 135.81351 -147.169798)
			(xy 135.779424 -147.125655) (xy 135.752128 -147.07702) (xy 135.732205 -147.024929) (xy 135.720079 -146.970492)
			(xy 135.716008 -146.91487) (xy 121.998486 -146.91487) (xy 121.998486 -147.657656) (xy 127.250343 -147.657656)
			(xy 127.250343 -147.603144) (xy 127.258101 -147.549188) (xy 127.27346 -147.496885) (xy 127.296107 -147.4473)
			(xy 127.32558 -147.401443) (xy 127.361279 -147.360248) (xy 127.402478 -147.324553) (xy 127.448339 -147.295085)
			(xy 127.497926 -147.272445) (xy 127.550231 -147.257092) (xy 127.604188 -147.24934) (xy 127.631444 -147.24888)
			(xy 127.65776 -147.24933) (xy 127.709894 -147.256552) (xy 127.760542 -147.270866) (xy 127.808744 -147.292001)
			(xy 127.853586 -147.319556) (xy 127.894218 -147.35301) (xy 127.912368 -147.37207) (xy 127.919904 -147.379455)
			(xy 127.939173 -147.38799) (xy 127.949706 -147.38858) (xy 128.024382 -147.38858) (xy 128.034933 -147.388061)
			(xy 128.054229 -147.379519) (xy 128.06172 -147.37207) (xy 128.079859 -147.352994) (xy 128.120477 -147.319513)
			(xy 128.165316 -147.291941) (xy 128.213523 -147.270801) (xy 128.26418 -147.256496) (xy 128.316324 -147.249299)
			(xy 128.342644 -147.24888) (xy 128.36896 -147.24933) (xy 128.421094 -147.256552) (xy 128.471742 -147.270866)
			(xy 128.519944 -147.292001) (xy 128.564786 -147.319556) (xy 128.605418 -147.35301) (xy 128.623568 -147.37207)
			(xy 128.631104 -147.379455) (xy 128.650373 -147.38799) (xy 128.660906 -147.38858) (xy 128.735582 -147.38858)
			(xy 128.746133 -147.388061) (xy 128.765429 -147.379519) (xy 128.77292 -147.37207) (xy 128.791059 -147.352994)
			(xy 128.831677 -147.319513) (xy 128.876516 -147.291941) (xy 128.924723 -147.270801) (xy 128.97538 -147.256496)
			(xy 129.027524 -147.249299) (xy 129.053844 -147.24888) (xy 129.081092 -147.249393) (xy 129.135034 -147.257155)
			(xy 129.187321 -147.272513) (xy 129.236891 -147.295156) (xy 129.282735 -147.324622) (xy 129.323918 -147.360313)
			(xy 129.359604 -147.401501) (xy 129.389065 -147.447347) (xy 129.411702 -147.49692) (xy 129.427055 -147.54921)
			(xy 129.43481 -147.603152) (xy 129.43481 -147.657648) (xy 129.427055 -147.71159) (xy 129.411702 -147.76388)
			(xy 129.389065 -147.813453) (xy 129.359604 -147.859299) (xy 129.323918 -147.900487) (xy 129.282735 -147.936178)
			(xy 129.236891 -147.965644) (xy 129.187321 -147.988287) (xy 129.135034 -148.003645) (xy 129.081092 -148.011407)
			(xy 129.053844 -148.011896) (xy 129.027527 -148.011461) (xy 128.975392 -148.004238) (xy 128.924744 -147.989921)
			(xy 128.876542 -147.968783) (xy 128.8317 -147.941225) (xy 128.791069 -147.907768) (xy 128.77292 -147.888706)
			(xy 128.765392 -147.881312) (xy 128.746117 -147.872783) (xy 128.735582 -147.872196) (xy 128.660906 -147.872196)
			(xy 128.650355 -147.872716) (xy 128.63106 -147.881258) (xy 128.623568 -147.888706) (xy 128.60545 -147.907802)
			(xy 128.564826 -147.941278) (xy 128.519982 -147.968846) (xy 128.471771 -147.989982) (xy 128.421111 -148.004283)
			(xy 128.368965 -148.011477) (xy 128.342644 -148.011896) (xy 128.316327 -148.011461) (xy 128.264192 -148.004238)
			(xy 128.213544 -147.989921) (xy 128.165342 -147.968783) (xy 128.1205 -147.941225) (xy 128.079869 -147.907768)
			(xy 128.06172 -147.888706) (xy 128.054192 -147.881312) (xy 128.034917 -147.872783) (xy 128.024382 -147.872196)
			(xy 127.949706 -147.872196) (xy 127.939155 -147.872716) (xy 127.91986 -147.881258) (xy 127.912368 -147.888706)
			(xy 127.89425 -147.907802) (xy 127.853626 -147.941278) (xy 127.808782 -147.968846) (xy 127.760571 -147.989982)
			(xy 127.709911 -148.004283) (xy 127.657765 -148.011477) (xy 127.631444 -148.011896) (xy 127.604188 -148.01146)
			(xy 127.550231 -148.003708) (xy 127.497926 -147.988355) (xy 127.448339 -147.965715) (xy 127.402478 -147.936247)
			(xy 127.361279 -147.900552) (xy 127.32558 -147.859357) (xy 127.296107 -147.8135) (xy 127.27346 -147.763915)
			(xy 127.258101 -147.711612) (xy 127.250343 -147.657656) (xy 121.998486 -147.657656) (xy 121.998486 -148.017738)
			(xy 132.077458 -148.017738) (xy 132.081529 -147.962116) (xy 132.093655 -147.907679) (xy 132.113578 -147.855588)
			(xy 132.140874 -147.806953) (xy 132.17496 -147.76281) (xy 132.215109 -147.724101) (xy 132.260467 -147.69165)
			(xy 132.310067 -147.666149) (xy 132.362851 -147.648142) (xy 132.417694 -147.638012) (xy 132.473428 -147.635975)
			(xy 132.528865 -147.642075) (xy 132.582822 -147.656181) (xy 132.634151 -147.677993) (xy 132.681757 -147.707047)
			(xy 132.724625 -147.742722) (xy 132.761842 -147.784259) (xy 132.792615 -147.830772) (xy 132.816287 -147.881269)
			(xy 132.832355 -147.934676) (xy 132.840475 -147.989852) (xy 132.840984 -148.017738) (xy 132.840475 -148.045624)
			(xy 132.832355 -148.1008) (xy 132.816287 -148.154207) (xy 132.792615 -148.204704) (xy 132.761842 -148.251217)
			(xy 132.724625 -148.292754) (xy 132.681757 -148.328429) (xy 132.634151 -148.357483) (xy 132.582822 -148.379295)
			(xy 132.528865 -148.393401) (xy 132.473428 -148.399501) (xy 132.417694 -148.397464) (xy 132.362851 -148.387334)
			(xy 132.310067 -148.369327) (xy 132.260467 -148.343826) (xy 132.215109 -148.311375) (xy 132.17496 -148.272666)
			(xy 132.140874 -148.228523) (xy 132.113578 -148.179888) (xy 132.093655 -148.127797) (xy 132.081529 -148.07336)
			(xy 132.077458 -148.017738) (xy 121.998486 -148.017738) (xy 121.998486 -150.195854) (xy 127.250365 -150.195854)
			(xy 127.250365 -150.141346) (xy 127.258123 -150.087392) (xy 127.273481 -150.035093) (xy 127.296126 -149.985511)
			(xy 127.325598 -149.939657) (xy 127.361295 -149.898464) (xy 127.402492 -149.862771) (xy 127.448349 -149.833305)
			(xy 127.497934 -149.810666) (xy 127.550236 -149.795314) (xy 127.60419 -149.787562) (xy 127.631444 -149.787102)
			(xy 127.65776 -149.787545) (xy 127.709895 -149.794767) (xy 127.760543 -149.809082) (xy 127.808745 -149.830219)
			(xy 127.853587 -149.857776) (xy 127.894218 -149.891231) (xy 127.912368 -149.910292) (xy 127.919901 -149.91768)
			(xy 127.939172 -149.926212) (xy 127.949706 -149.926802) (xy 128.024382 -149.926802) (xy 128.034932 -149.926276)
			(xy 128.054227 -149.917738) (xy 128.06172 -149.910292) (xy 128.079843 -149.891201) (xy 128.120466 -149.857725)
			(xy 128.165309 -149.830156) (xy 128.213519 -149.809019) (xy 128.264178 -149.794717) (xy 128.316324 -149.787521)
			(xy 128.342644 -149.787102) (xy 128.36896 -149.787545) (xy 128.421095 -149.794767) (xy 128.471743 -149.809082)
			(xy 128.519945 -149.830219) (xy 128.564787 -149.857776) (xy 128.605418 -149.891231) (xy 128.623568 -149.910292)
			(xy 128.631101 -149.91768) (xy 128.650372 -149.926212) (xy 128.660906 -149.926802) (xy 128.735582 -149.926802)
			(xy 128.746132 -149.926276) (xy 128.765427 -149.917738) (xy 128.77292 -149.910292) (xy 128.791043 -149.891201)
			(xy 128.831666 -149.857725) (xy 128.876509 -149.830156) (xy 128.924719 -149.809019) (xy 128.975378 -149.794717)
			(xy 129.027524 -149.787521) (xy 129.053844 -149.787102) (xy 129.081094 -149.787571) (xy 129.135038 -149.795333)
			(xy 129.187329 -149.810692) (xy 129.236902 -149.833336) (xy 129.282748 -149.862804) (xy 129.323934 -149.898497)
			(xy 129.359622 -149.939687) (xy 129.389085 -149.985537) (xy 129.411723 -150.035112) (xy 129.420045 -150.063454)
			(xy 131.938012 -150.063454) (xy 131.942083 -150.007832) (xy 131.954209 -149.953395) (xy 131.974132 -149.901304)
			(xy 132.001428 -149.852669) (xy 132.035514 -149.808526) (xy 132.075663 -149.769817) (xy 132.121021 -149.737366)
			(xy 132.170621 -149.711865) (xy 132.223405 -149.693858) (xy 132.278248 -149.683728) (xy 132.333982 -149.681691)
			(xy 132.389419 -149.687791) (xy 132.443376 -149.701897) (xy 132.494705 -149.723709) (xy 132.542311 -149.752763)
			(xy 132.585179 -149.788438) (xy 132.622396 -149.829975) (xy 132.653169 -149.876488) (xy 132.676841 -149.926985)
			(xy 132.692909 -149.980392) (xy 132.701029 -150.035568) (xy 132.701538 -150.063454) (xy 132.701029 -150.09134)
			(xy 132.692909 -150.146516) (xy 132.676841 -150.199923) (xy 132.653169 -150.25042) (xy 132.622396 -150.296933)
			(xy 132.585179 -150.33847) (xy 132.542311 -150.374145) (xy 132.494705 -150.403199) (xy 132.443376 -150.425011)
			(xy 132.389419 -150.439117) (xy 132.333982 -150.445217) (xy 132.278248 -150.44318) (xy 132.223405 -150.43305)
			(xy 132.170621 -150.415043) (xy 132.121021 -150.389542) (xy 132.075663 -150.357091) (xy 132.035514 -150.318382)
			(xy 132.001428 -150.274239) (xy 131.974132 -150.225604) (xy 131.954209 -150.173513) (xy 131.942083 -150.119076)
			(xy 131.938012 -150.063454) (xy 129.420045 -150.063454) (xy 129.427077 -150.087405) (xy 129.434832 -150.14135)
			(xy 129.434832 -150.19585) (xy 129.427077 -150.249795) (xy 129.411723 -150.302088) (xy 129.389085 -150.351663)
			(xy 129.359622 -150.397513) (xy 129.323934 -150.438703) (xy 129.282748 -150.474396) (xy 129.236902 -150.503864)
			(xy 129.187329 -150.526508) (xy 129.135038 -150.541867) (xy 129.081094 -150.549629) (xy 129.053844 -150.550118)
			(xy 129.027528 -150.549676) (xy 128.975393 -150.542453) (xy 128.924745 -150.528137) (xy 128.876543 -150.507001)
			(xy 128.831702 -150.479444) (xy 128.79107 -150.445989) (xy 128.77292 -150.426928) (xy 128.765389 -150.419537)
			(xy 128.746116 -150.411006) (xy 128.735582 -150.410418) (xy 128.660906 -150.410418) (xy 128.650354 -150.410932)
			(xy 128.631059 -150.419477) (xy 128.623568 -150.426928) (xy 128.605435 -150.446009) (xy 128.564816 -150.47949)
			(xy 128.519975 -150.507062) (xy 128.471767 -150.528201) (xy 128.421109 -150.542504) (xy 128.368964 -150.549699)
			(xy 128.342644 -150.550118) (xy 128.316328 -150.549676) (xy 128.264193 -150.542453) (xy 128.213545 -150.528137)
			(xy 128.165343 -150.507001) (xy 128.120502 -150.479444) (xy 128.07987 -150.445989) (xy 128.06172 -150.426928)
			(xy 128.054189 -150.419537) (xy 128.034916 -150.411006) (xy 128.024382 -150.410418) (xy 127.949706 -150.410418)
			(xy 127.939154 -150.410932) (xy 127.919859 -150.419477) (xy 127.912368 -150.426928) (xy 127.894235 -150.446009)
			(xy 127.853616 -150.47949) (xy 127.808775 -150.507062) (xy 127.760567 -150.528201) (xy 127.709909 -150.542504)
			(xy 127.657764 -150.549699) (xy 127.631444 -150.550118) (xy 127.60419 -150.549638) (xy 127.550236 -150.541886)
			(xy 127.497934 -150.526534) (xy 127.448349 -150.503895) (xy 127.402492 -150.474429) (xy 127.361295 -150.438736)
			(xy 127.325598 -150.397543) (xy 127.296126 -150.351689) (xy 127.273481 -150.302107) (xy 127.258123 -150.249808)
			(xy 127.250365 -150.195854) (xy 121.998486 -150.195854) (xy 121.998486 -155.212034) (xy 123.369068 -155.212034)
			(xy 123.373139 -155.156412) (xy 123.385265 -155.101975) (xy 123.405188 -155.049884) (xy 123.432484 -155.001249)
			(xy 123.46657 -154.957106) (xy 123.506719 -154.918397) (xy 123.552077 -154.885946) (xy 123.601677 -154.860445)
			(xy 123.654461 -154.842438) (xy 123.709304 -154.832308) (xy 123.765038 -154.830271) (xy 123.820475 -154.836371)
			(xy 123.874432 -154.850477) (xy 123.925761 -154.872289) (xy 123.973367 -154.901343) (xy 124.016235 -154.937018)
			(xy 124.053452 -154.978555) (xy 124.084225 -155.025068) (xy 124.107897 -155.075565) (xy 124.108988 -155.079192)
			(xy 125.969774 -155.079192) (xy 125.973845 -155.02357) (xy 125.985971 -154.969133) (xy 126.005894 -154.917042)
			(xy 126.03319 -154.868407) (xy 126.067276 -154.824264) (xy 126.107425 -154.785555) (xy 126.152783 -154.753104)
			(xy 126.202383 -154.727603) (xy 126.255167 -154.709596) (xy 126.31001 -154.699466) (xy 126.365744 -154.697429)
			(xy 126.421181 -154.703529) (xy 126.475138 -154.717635) (xy 126.526467 -154.739447) (xy 126.574073 -154.768501)
			(xy 126.616941 -154.804176) (xy 126.654158 -154.845713) (xy 126.684931 -154.892226) (xy 126.708603 -154.942723)
			(xy 126.724671 -154.99613) (xy 126.732791 -155.051306) (xy 126.7333 -155.079192) (xy 126.733235 -155.082748)
			(xy 127.293624 -155.082748) (xy 127.294055 -155.056431) (xy 127.301279 -155.004296) (xy 127.315595 -154.953647)
			(xy 127.336734 -154.905445) (xy 127.364294 -154.860604) (xy 127.397752 -154.819973) (xy 127.416814 -154.801824)
			(xy 127.424209 -154.794297) (xy 127.432737 -154.775021) (xy 127.433324 -154.764486) (xy 127.433324 -154.68981)
			(xy 127.432796 -154.67926) (xy 127.424259 -154.659965) (xy 127.416814 -154.652472) (xy 127.397724 -154.634348)
			(xy 127.364246 -154.593726) (xy 127.336677 -154.548883) (xy 127.31554 -154.500673) (xy 127.301238 -154.450014)
			(xy 127.294043 -154.397868) (xy 127.293624 -154.371548) (xy 127.2941 -154.344295) (xy 127.301851 -154.290343)
			(xy 127.317203 -154.238043) (xy 127.339842 -154.188461) (xy 127.369308 -154.142606) (xy 127.405001 -154.101412)
			(xy 127.446193 -154.065718) (xy 127.492047 -154.03625) (xy 127.541628 -154.013608) (xy 127.593927 -153.998255)
			(xy 127.647879 -153.990501) (xy 127.675132 -153.99004) (xy 127.701449 -153.990479) (xy 127.753584 -153.9977)
			(xy 127.804233 -154.012015) (xy 127.852435 -154.033152) (xy 127.897276 -154.060711) (xy 127.937907 -154.094168)
			(xy 127.956056 -154.11323) (xy 127.963601 -154.120604) (xy 127.982863 -154.129147) (xy 127.993394 -154.12974)
			(xy 128.06807 -154.12974) (xy 128.078618 -154.129197) (xy 128.097913 -154.12067) (xy 128.105408 -154.11323)
			(xy 128.123545 -154.094152) (xy 128.164164 -154.060673) (xy 128.209004 -154.033102) (xy 128.257211 -154.011963)
			(xy 128.307869 -153.997658) (xy 128.360012 -153.99046) (xy 128.386332 -153.99004) (xy 128.412649 -153.990479)
			(xy 128.464784 -153.9977) (xy 128.515433 -154.012015) (xy 128.563635 -154.033152) (xy 128.608476 -154.060711)
			(xy 128.649107 -154.094168) (xy 128.667256 -154.11323) (xy 128.674801 -154.120604) (xy 128.694063 -154.129147)
			(xy 128.704594 -154.12974) (xy 128.77927 -154.12974) (xy 128.789818 -154.129197) (xy 128.809113 -154.12067)
			(xy 128.816608 -154.11323) (xy 128.834745 -154.094152) (xy 128.875364 -154.060673) (xy 128.920204 -154.033102)
			(xy 128.968411 -154.011963) (xy 129.019069 -153.997658) (xy 129.071212 -153.99046) (xy 129.097532 -153.99004)
			(xy 129.123849 -153.990479) (xy 129.175984 -153.9977) (xy 129.226633 -154.012015) (xy 129.274835 -154.033152)
			(xy 129.319676 -154.060711) (xy 129.360307 -154.094168) (xy 129.378456 -154.11323) (xy 129.386001 -154.120604)
			(xy 129.405263 -154.129147) (xy 129.415794 -154.12974) (xy 129.49047 -154.12974) (xy 129.501018 -154.129197)
			(xy 129.520313 -154.12067) (xy 129.527808 -154.11323) (xy 129.545945 -154.094152) (xy 129.586564 -154.060673)
			(xy 129.631404 -154.033102) (xy 129.679611 -154.011963) (xy 129.730269 -153.997658) (xy 129.782412 -153.99046)
			(xy 129.808732 -153.99004) (xy 129.835988 -153.990425) (xy 129.889944 -153.998188) (xy 129.942246 -154.01355)
			(xy 129.99183 -154.0362) (xy 130.037685 -154.065676) (xy 130.078879 -154.101378) (xy 130.114572 -154.142579)
			(xy 130.144038 -154.18844) (xy 130.166678 -154.238029) (xy 130.182029 -154.290334) (xy 130.18978 -154.344292)
			(xy 130.19024 -154.371548) (xy 130.189786 -154.397864) (xy 130.182564 -154.449997) (xy 130.168251 -154.500645)
			(xy 130.147116 -154.548847) (xy 130.119562 -154.593689) (xy 130.086109 -154.634321) (xy 130.06705 -154.652472)
			(xy 130.059666 -154.660009) (xy 130.05113 -154.679277) (xy 130.05054 -154.68981) (xy 130.05054 -154.764486)
			(xy 130.051051 -154.775038) (xy 130.059598 -154.794334) (xy 130.06705 -154.801824) (xy 130.086132 -154.819957)
			(xy 130.119611 -154.860577) (xy 130.147183 -154.905417) (xy 130.168321 -154.953625) (xy 130.182625 -155.004283)
			(xy 130.189821 -155.056428) (xy 130.19024 -155.082748) (xy 130.189767 -155.109999) (xy 130.182005 -155.163945)
			(xy 130.166645 -155.216238) (xy 130.144001 -155.265814) (xy 130.114532 -155.311662) (xy 130.07884 -155.352851)
			(xy 130.03765 -155.388542) (xy 129.9918 -155.418008) (xy 129.942223 -155.440651) (xy 129.88993 -155.456008)
			(xy 129.835983 -155.463768) (xy 129.808732 -155.464256) (xy 129.782415 -155.463842) (xy 129.730278 -155.456616)
			(xy 129.679629 -155.442296) (xy 129.631427 -155.421154) (xy 129.586586 -155.393592) (xy 129.545956 -155.36013)
			(xy 129.527808 -155.341066) (xy 129.520277 -155.333676) (xy 129.501004 -155.325143) (xy 129.49047 -155.324556)
			(xy 129.415794 -155.324556) (xy 129.405244 -155.325082) (xy 129.38595 -155.333621) (xy 129.378456 -155.341066)
			(xy 129.360336 -155.36016) (xy 129.319713 -155.393638) (xy 129.27487 -155.421208) (xy 129.226659 -155.442344)
			(xy 129.175999 -155.456645) (xy 129.123853 -155.463838) (xy 129.097532 -155.464256) (xy 129.071215 -155.463842)
			(xy 129.019078 -155.456616) (xy 128.968429 -155.442296) (xy 128.920227 -155.421154) (xy 128.875386 -155.393592)
			(xy 128.834756 -155.36013) (xy 128.816608 -155.341066) (xy 128.809077 -155.333676) (xy 128.789804 -155.325143)
			(xy 128.77927 -155.324556) (xy 128.704594 -155.324556) (xy 128.694044 -155.325082) (xy 128.67475 -155.333621)
			(xy 128.667256 -155.341066) (xy 128.649136 -155.36016) (xy 128.608513 -155.393638) (xy 128.56367 -155.421208)
			(xy 128.515459 -155.442344) (xy 128.464799 -155.456645) (xy 128.412653 -155.463838) (xy 128.386332 -155.464256)
			(xy 128.360015 -155.463842) (xy 128.307878 -155.456616) (xy 128.257229 -155.442296) (xy 128.209027 -155.421154)
			(xy 128.164186 -155.393592) (xy 128.123556 -155.36013) (xy 128.105408 -155.341066) (xy 128.097877 -155.333676)
			(xy 128.078604 -155.325143) (xy 128.06807 -155.324556) (xy 127.993394 -155.324556) (xy 127.982844 -155.325082)
			(xy 127.96355 -155.333621) (xy 127.956056 -155.341066) (xy 127.937936 -155.36016) (xy 127.897313 -155.393638)
			(xy 127.85247 -155.421208) (xy 127.804259 -155.442344) (xy 127.753599 -155.456645) (xy 127.701453 -155.463838)
			(xy 127.675132 -155.464256) (xy 127.647884 -155.463692) (xy 127.593941 -155.455941) (xy 127.541651 -155.440593)
			(xy 127.492077 -155.417959) (xy 127.446229 -155.3885) (xy 127.40504 -155.352817) (xy 127.369348 -155.311635)
			(xy 127.33988 -155.265793) (xy 127.317235 -155.216224) (xy 127.301876 -155.163937) (xy 127.294114 -155.109996)
			(xy 127.293624 -155.082748) (xy 126.733235 -155.082748) (xy 126.732791 -155.107078) (xy 126.724671 -155.162254)
			(xy 126.708603 -155.215661) (xy 126.684931 -155.266158) (xy 126.654158 -155.312671) (xy 126.616941 -155.354208)
			(xy 126.574073 -155.389883) (xy 126.526467 -155.418937) (xy 126.475138 -155.440749) (xy 126.421181 -155.454855)
			(xy 126.365744 -155.460955) (xy 126.31001 -155.458918) (xy 126.255167 -155.448788) (xy 126.202383 -155.430781)
			(xy 126.152783 -155.40528) (xy 126.107425 -155.372829) (xy 126.067276 -155.33412) (xy 126.03319 -155.289977)
			(xy 126.005894 -155.241342) (xy 125.985971 -155.189251) (xy 125.973845 -155.134814) (xy 125.969774 -155.079192)
			(xy 124.108988 -155.079192) (xy 124.123965 -155.128972) (xy 124.132085 -155.184148) (xy 124.132594 -155.212034)
			(xy 124.132085 -155.23992) (xy 124.123965 -155.295096) (xy 124.107897 -155.348503) (xy 124.084225 -155.399)
			(xy 124.053452 -155.445513) (xy 124.016235 -155.48705) (xy 123.973367 -155.522725) (xy 123.925761 -155.551779)
			(xy 123.874432 -155.573591) (xy 123.820475 -155.587697) (xy 123.765038 -155.593797) (xy 123.709304 -155.59176)
			(xy 123.654461 -155.58163) (xy 123.601677 -155.563623) (xy 123.552077 -155.538122) (xy 123.506719 -155.505671)
			(xy 123.46657 -155.466962) (xy 123.432484 -155.422819) (xy 123.405188 -155.374184) (xy 123.385265 -155.322093)
			(xy 123.373139 -155.267656) (xy 123.369068 -155.212034) (xy 121.998486 -155.212034) (xy 121.998486 -156.69387)
			(xy 124.987302 -156.69387) (xy 124.991373 -156.638248) (xy 125.003499 -156.583811) (xy 125.023422 -156.53172)
			(xy 125.050718 -156.483085) (xy 125.084804 -156.438942) (xy 125.124953 -156.400233) (xy 125.170311 -156.367782)
			(xy 125.219911 -156.342281) (xy 125.272695 -156.324274) (xy 125.327538 -156.314144) (xy 125.383272 -156.312107)
			(xy 125.438709 -156.318207) (xy 125.492666 -156.332313) (xy 125.543995 -156.354125) (xy 125.591601 -156.383179)
			(xy 125.634469 -156.418854) (xy 125.671686 -156.460391) (xy 125.702459 -156.506904) (xy 125.726131 -156.557401)
			(xy 125.742199 -156.610808) (xy 125.750319 -156.665984) (xy 125.750828 -156.69387) (xy 125.750319 -156.721756)
			(xy 125.742199 -156.776932) (xy 125.726131 -156.830339) (xy 125.702459 -156.880836) (xy 125.671686 -156.927349)
			(xy 125.634469 -156.968886) (xy 125.591601 -157.004561) (xy 125.543995 -157.033615) (xy 125.492666 -157.055427)
			(xy 125.438709 -157.069533) (xy 125.383272 -157.075633) (xy 125.327538 -157.073596) (xy 125.272695 -157.063466)
			(xy 125.219911 -157.045459) (xy 125.170311 -157.019958) (xy 125.124953 -156.987507) (xy 125.084804 -156.948798)
			(xy 125.050718 -156.904655) (xy 125.023422 -156.85602) (xy 125.003499 -156.803929) (xy 124.991373 -156.749492)
			(xy 124.987302 -156.69387) (xy 121.998486 -156.69387) (xy 121.998486 -157.812994) (xy 122.75007 -157.812994)
			(xy 122.754141 -157.757372) (xy 122.766267 -157.702935) (xy 122.78619 -157.650844) (xy 122.813486 -157.602209)
			(xy 122.847572 -157.558066) (xy 122.887721 -157.519357) (xy 122.933079 -157.486906) (xy 122.982679 -157.461405)
			(xy 123.035463 -157.443398) (xy 123.090306 -157.433268) (xy 123.14604 -157.431231) (xy 123.201477 -157.437331)
			(xy 123.255434 -157.451437) (xy 123.306763 -157.473249) (xy 123.354369 -157.502303) (xy 123.397237 -157.537978)
			(xy 123.434454 -157.579515) (xy 123.465227 -157.626028) (xy 123.475477 -157.647894) (xy 127.113792 -157.647894)
			(xy 127.114327 -157.621251) (xy 127.12285 -157.568653) (xy 127.139707 -157.518105) (xy 127.164461 -157.470918)
			(xy 127.196468 -157.428318) (xy 127.2349 -157.391409) (xy 127.25654 -157.37586) (xy 127.267829 -157.367502)
			(xy 127.28568 -157.345826) (xy 127.296959 -157.320111) (xy 127.300815 -157.292297) (xy 127.296957 -157.264483)
			(xy 127.285677 -157.238768) (xy 127.267824 -157.217094) (xy 127.25654 -157.208728) (xy 127.234939 -157.193131)
			(xy 127.196524 -157.156217) (xy 127.164523 -157.113623) (xy 127.139765 -157.066449) (xy 127.12289 -157.015916)
			(xy 127.114334 -156.963332) (xy 127.113792 -156.936694) (xy 127.114302 -156.910707) (xy 127.122432 -156.859372)
			(xy 127.138493 -156.809942) (xy 127.162089 -156.763632) (xy 127.192639 -156.721584) (xy 127.22939 -156.684833)
			(xy 127.271438 -156.654283) (xy 127.317748 -156.630687) (xy 127.367178 -156.614626) (xy 127.418513 -156.606496)
			(xy 127.470487 -156.606496) (xy 127.521822 -156.614626) (xy 127.571252 -156.630687) (xy 127.617562 -156.654283)
			(xy 127.65961 -156.684833) (xy 127.696361 -156.721584) (xy 127.726911 -156.763632) (xy 127.750507 -156.809942)
			(xy 127.766568 -156.859372) (xy 127.774698 -156.910707) (xy 127.775208 -156.936694) (xy 127.774664 -156.963336)
			(xy 127.766143 -157.015935) (xy 127.749288 -157.066482) (xy 127.724536 -157.113669) (xy 127.69253 -157.156269)
			(xy 127.6541 -157.193179) (xy 127.63246 -157.208728) (xy 127.621182 -157.217101) (xy 127.603332 -157.238773)
			(xy 127.592052 -157.264485) (xy 127.588195 -157.292297) (xy 127.59205 -157.320108) (xy 127.603328 -157.345821)
			(xy 127.621177 -157.367494) (xy 127.63246 -157.37586) (xy 127.654056 -157.391465) (xy 127.692471 -157.428377)
			(xy 127.724472 -157.47097) (xy 127.749231 -157.518142) (xy 127.766107 -157.568673) (xy 127.774665 -157.621257)
			(xy 127.775208 -157.647894) (xy 128.013714 -157.647894) (xy 128.014239 -157.621251) (xy 128.022763 -157.568651)
			(xy 128.039622 -157.518103) (xy 128.064377 -157.470916) (xy 128.096387 -157.428316) (xy 128.13482 -157.391408)
			(xy 128.156462 -157.37586) (xy 128.167749 -157.3675) (xy 128.185596 -157.345824) (xy 128.196873 -157.320109)
			(xy 128.200728 -157.292297) (xy 128.196871 -157.264484) (xy 128.185593 -157.238771) (xy 128.167744 -157.217095)
			(xy 128.156462 -157.208728) (xy 128.134866 -157.193124) (xy 128.096449 -157.156213) (xy 128.064448 -157.11362)
			(xy 128.039689 -157.066447) (xy 128.022813 -157.015915) (xy 128.014256 -156.963332) (xy 128.013714 -156.936694)
			(xy 128.014224 -156.910707) (xy 128.022354 -156.859372) (xy 128.038415 -156.809942) (xy 128.062011 -156.763632)
			(xy 128.092561 -156.721584) (xy 128.129312 -156.684833) (xy 128.17136 -156.654283) (xy 128.21767 -156.630687)
			(xy 128.2671 -156.614626) (xy 128.318435 -156.606496) (xy 128.370409 -156.606496) (xy 128.421744 -156.614626)
			(xy 128.471174 -156.630687) (xy 128.517484 -156.654283) (xy 128.559532 -156.684833) (xy 128.596283 -156.721584)
			(xy 128.626833 -156.763632) (xy 128.650429 -156.809942) (xy 128.66649 -156.859372) (xy 128.67462 -156.910707)
			(xy 128.67513 -156.936694) (xy 128.67462 -156.963338) (xy 128.666096 -157.01594) (xy 128.649236 -157.06649)
			(xy 128.624478 -157.113677) (xy 128.592465 -157.156276) (xy 128.554026 -157.193182) (xy 128.532382 -157.208728)
			(xy 128.521103 -157.2171) (xy 128.503248 -157.238771) (xy 128.491966 -157.264484) (xy 128.488108 -157.292297)
			(xy 128.491964 -157.320109) (xy 128.503245 -157.345823) (xy 128.521098 -157.367495) (xy 128.532382 -157.37586)
			(xy 128.553982 -157.391458) (xy 128.592396 -157.428372) (xy 128.624396 -157.470967) (xy 128.649154 -157.51814)
			(xy 128.66603 -157.568673) (xy 128.674587 -157.621256) (xy 128.67513 -157.647894) (xy 128.913636 -157.647894)
			(xy 128.914152 -157.62125) (xy 128.922677 -157.56865) (xy 128.939536 -157.5181) (xy 128.964293 -157.470914)
			(xy 128.996305 -157.428314) (xy 129.034741 -157.391407) (xy 129.056384 -157.37586) (xy 129.067678 -157.367505)
			(xy 129.085539 -157.345831) (xy 129.096824 -157.320115) (xy 129.100683 -157.292297) (xy 129.096823 -157.264479)
			(xy 129.085535 -157.238763) (xy 129.067673 -157.217091) (xy 129.056384 -157.208728) (xy 129.034792 -157.193118)
			(xy 128.996375 -157.156208) (xy 128.964372 -157.113617) (xy 128.939612 -157.066446) (xy 128.922735 -157.015914)
			(xy 128.914178 -156.963331) (xy 128.913636 -156.936694) (xy 128.914146 -156.910707) (xy 128.922276 -156.859372)
			(xy 128.938337 -156.809942) (xy 128.961933 -156.763632) (xy 128.992483 -156.721584) (xy 129.029234 -156.684833)
			(xy 129.071282 -156.654283) (xy 129.117592 -156.630687) (xy 129.167022 -156.614626) (xy 129.218357 -156.606496)
			(xy 129.270331 -156.606496) (xy 129.321666 -156.614626) (xy 129.371096 -156.630687) (xy 129.417406 -156.654283)
			(xy 129.459454 -156.684833) (xy 129.496205 -156.721584) (xy 129.526755 -156.763632) (xy 129.550351 -156.809942)
			(xy 129.566412 -156.859372) (xy 129.574542 -156.910707) (xy 129.575052 -156.936694) (xy 129.574532 -156.963338)
			(xy 129.566009 -157.015938) (xy 129.549151 -157.066488) (xy 129.524395 -157.113674) (xy 129.492383 -157.156274)
			(xy 129.453947 -157.193181) (xy 129.432304 -157.208728) (xy 129.421023 -157.217099) (xy 129.403164 -157.238769)
			(xy 129.39188 -157.264482) (xy 129.38802 -157.292297) (xy 129.391878 -157.320111) (xy 129.403161 -157.345825)
			(xy 129.421018 -157.367497) (xy 129.432304 -157.37586) (xy 129.453887 -157.391481) (xy 129.492306 -157.428388)
			(xy 129.52431 -157.470977) (xy 129.549072 -157.518146) (xy 129.56595 -157.568676) (xy 129.574509 -157.621257)
			(xy 129.575052 -157.647894) (xy 129.813812 -157.647894) (xy 129.814338 -157.621251) (xy 129.822862 -157.568651)
			(xy 129.83972 -157.518103) (xy 129.864475 -157.470916) (xy 129.896485 -157.428316) (xy 129.934919 -157.391408)
			(xy 129.95656 -157.37586) (xy 129.967847 -157.3675) (xy 129.985695 -157.345824) (xy 129.996971 -157.320109)
			(xy 130.000827 -157.292297) (xy 129.99697 -157.264484) (xy 129.985691 -157.23877) (xy 129.967842 -157.217095)
			(xy 129.95656 -157.208728) (xy 129.934963 -157.193125) (xy 129.896547 -157.156213) (xy 129.864545 -157.11362)
			(xy 129.839786 -157.066447) (xy 129.822911 -157.015915) (xy 129.814354 -156.963332) (xy 129.813812 -156.936694)
			(xy 129.814322 -156.910707) (xy 129.822452 -156.859372) (xy 129.838513 -156.809942) (xy 129.862109 -156.763632)
			(xy 129.892659 -156.721584) (xy 129.92941 -156.684833) (xy 129.971458 -156.654283) (xy 130.017768 -156.630687)
			(xy 130.067198 -156.614626) (xy 130.118533 -156.606496) (xy 130.170507 -156.606496) (xy 130.221842 -156.614626)
			(xy 130.271272 -156.630687) (xy 130.317582 -156.654283) (xy 130.35963 -156.684833) (xy 130.396381 -156.721584)
			(xy 130.426931 -156.763632) (xy 130.450527 -156.809942) (xy 130.466588 -156.859372) (xy 130.474718 -156.910707)
			(xy 130.475228 -156.936694) (xy 130.474719 -156.963338) (xy 130.466195 -157.01594) (xy 130.449335 -157.06649)
			(xy 130.424577 -157.113677) (xy 130.392563 -157.156276) (xy 130.354124 -157.193182) (xy 130.33248 -157.208728)
			(xy 130.321201 -157.2171) (xy 130.303346 -157.238771) (xy 130.292064 -157.264484) (xy 130.288206 -157.292297)
			(xy 130.292063 -157.320109) (xy 130.303343 -157.345823) (xy 130.321196 -157.367495) (xy 130.33248 -157.37586)
			(xy 130.35408 -157.391459) (xy 130.392494 -157.428373) (xy 130.424494 -157.470967) (xy 130.449252 -157.518141)
			(xy 130.466128 -157.568673) (xy 130.474685 -157.621256) (xy 130.475187 -157.645862) (xy 131.429252 -157.645862)
			(xy 131.429715 -157.619547) (xy 131.436936 -157.567414) (xy 131.451248 -157.516766) (xy 131.47238 -157.468565)
			(xy 131.499933 -157.423722) (xy 131.533383 -157.383089) (xy 131.552442 -157.364938) (xy 131.55982 -157.357396)
			(xy 131.56836 -157.338132) (xy 131.568952 -157.3276) (xy 131.568952 -157.252924) (xy 131.568437 -157.242372)
			(xy 131.559893 -157.223076) (xy 131.552442 -157.215586) (xy 131.533364 -157.19745) (xy 131.499884 -157.156831)
			(xy 131.472312 -157.111991) (xy 131.451173 -157.063783) (xy 131.436869 -157.013126) (xy 131.429672 -156.960982)
			(xy 131.429252 -156.934662) (xy 131.429738 -156.907411) (xy 131.437494 -156.853463) (xy 131.452849 -156.801168)
			(xy 131.475491 -156.751591) (xy 131.504957 -156.705741) (xy 131.540648 -156.66455) (xy 131.581839 -156.628859)
			(xy 131.627689 -156.599393) (xy 131.677266 -156.576751) (xy 131.729561 -156.561396) (xy 131.783509 -156.55364)
			(xy 131.838011 -156.55364) (xy 131.891959 -156.561396) (xy 131.944254 -156.576751) (xy 131.993831 -156.599393)
			(xy 132.039681 -156.628859) (xy 132.080872 -156.66455) (xy 132.116563 -156.705741) (xy 132.146029 -156.751591)
			(xy 132.168671 -156.801168) (xy 132.184026 -156.853463) (xy 132.191782 -156.907411) (xy 132.192268 -156.934662)
			(xy 132.191846 -156.960979) (xy 132.184621 -157.013115) (xy 132.170303 -157.063764) (xy 132.149162 -157.111966)
			(xy 132.121601 -157.156807) (xy 132.088141 -157.197437) (xy 132.069078 -157.215586) (xy 132.061677 -157.223108)
			(xy 132.053153 -157.242388) (xy 132.052568 -157.252924) (xy 132.052568 -157.3276) (xy 132.053093 -157.33815)
			(xy 132.061126 -157.356302) (xy 133.414516 -157.356302) (xy 133.414919 -157.329984) (xy 133.422148 -157.277848)
			(xy 133.436471 -157.227198) (xy 133.457615 -157.178997) (xy 133.485179 -157.134156) (xy 133.518642 -157.093526)
			(xy 133.537706 -157.075378) (xy 133.54512 -157.067867) (xy 133.553637 -157.048579) (xy 133.554216 -157.03804)
			(xy 133.554216 -156.963364) (xy 133.553661 -156.952817) (xy 133.545144 -156.933522) (xy 133.537706 -156.926026)
			(xy 133.51864 -156.907877) (xy 133.485161 -156.86726) (xy 133.457588 -156.822423) (xy 133.436447 -156.774218)
			(xy 133.42214 -156.723563) (xy 133.414938 -156.671421) (xy 133.414516 -156.645102) (xy 133.414919 -156.618784)
			(xy 133.422148 -156.566648) (xy 133.436471 -156.515998) (xy 133.457615 -156.467797) (xy 133.485179 -156.422956)
			(xy 133.518642 -156.382326) (xy 133.537706 -156.364178) (xy 133.54512 -156.356667) (xy 133.553637 -156.337379)
			(xy 133.554216 -156.32684) (xy 133.554216 -156.252164) (xy 133.553661 -156.241617) (xy 133.545144 -156.222322)
			(xy 133.537706 -156.214826) (xy 133.51864 -156.196677) (xy 133.485161 -156.15606) (xy 133.457588 -156.111223)
			(xy 133.436447 -156.063018) (xy 133.42214 -156.012363) (xy 133.414938 -155.960221) (xy 133.414516 -155.933902)
			(xy 133.415002 -155.906651) (xy 133.422758 -155.852703) (xy 133.438113 -155.800408) (xy 133.460755 -155.750831)
			(xy 133.490221 -155.704981) (xy 133.525912 -155.66379) (xy 133.567103 -155.628099) (xy 133.612953 -155.598633)
			(xy 133.66253 -155.575991) (xy 133.714825 -155.560636) (xy 133.768773 -155.55288) (xy 133.823275 -155.55288)
			(xy 133.877223 -155.560636) (xy 133.929518 -155.575991) (xy 133.979095 -155.598633) (xy 134.024945 -155.628099)
			(xy 134.066136 -155.66379) (xy 134.101827 -155.704981) (xy 134.131293 -155.750831) (xy 134.153935 -155.800408)
			(xy 134.16929 -155.852703) (xy 134.177046 -155.906651) (xy 134.177532 -155.933902) (xy 134.177116 -155.960219)
			(xy 134.169887 -156.012354) (xy 134.155566 -156.063003) (xy 134.134425 -156.111204) (xy 134.106863 -156.156046)
			(xy 134.073404 -156.196676) (xy 134.054342 -156.214826) (xy 134.046933 -156.222342) (xy 134.038412 -156.241626)
			(xy 134.037832 -156.252164) (xy 134.037832 -156.32684) (xy 134.038371 -156.337389) (xy 134.046898 -156.356685)
			(xy 134.054342 -156.364178) (xy 134.0734 -156.382335) (xy 134.106882 -156.422949) (xy 134.134457 -156.467785)
			(xy 134.155599 -156.515988) (xy 134.169908 -156.566642) (xy 134.17711 -156.618784) (xy 134.177532 -156.645102)
			(xy 134.177116 -156.671419) (xy 134.169887 -156.723554) (xy 134.155566 -156.774203) (xy 134.134425 -156.822404)
			(xy 134.106863 -156.867246) (xy 134.073404 -156.907876) (xy 134.054342 -156.926026) (xy 134.046933 -156.933542)
			(xy 134.038412 -156.952826) (xy 134.037832 -156.963364) (xy 134.037832 -157.03804) (xy 134.038371 -157.048589)
			(xy 134.046898 -157.067885) (xy 134.054342 -157.075378) (xy 134.0734 -157.093535) (xy 134.106882 -157.134149)
			(xy 134.134457 -157.178985) (xy 134.155599 -157.227188) (xy 134.169908 -157.277842) (xy 134.17711 -157.329984)
			(xy 134.177532 -157.356302) (xy 134.177046 -157.383553) (xy 134.172017 -157.418532) (xy 136.480296 -157.418532)
			(xy 136.480725 -157.392215) (xy 136.48795 -157.34008) (xy 136.502268 -157.289432) (xy 136.523407 -157.24123)
			(xy 136.550967 -157.196388) (xy 136.584424 -157.155757) (xy 136.603486 -157.137608) (xy 136.610884 -157.130083)
			(xy 136.619411 -157.110806) (xy 136.619996 -157.10027) (xy 136.619996 -157.025594) (xy 136.619485 -157.015042)
			(xy 136.610937 -156.995747) (xy 136.603486 -156.988256) (xy 136.584383 -156.970146) (xy 136.550907 -156.92952)
			(xy 136.52334 -156.884674) (xy 136.502206 -156.836462) (xy 136.487906 -156.7858) (xy 136.480714 -156.733653)
			(xy 136.480296 -156.707332) (xy 136.480725 -156.681015) (xy 136.48795 -156.62888) (xy 136.502268 -156.578232)
			(xy 136.523407 -156.53003) (xy 136.550967 -156.485188) (xy 136.584424 -156.444557) (xy 136.603486 -156.426408)
			(xy 136.610884 -156.418883) (xy 136.619411 -156.399606) (xy 136.619996 -156.38907) (xy 136.619996 -156.314394)
			(xy 136.619485 -156.303842) (xy 136.610937 -156.284547) (xy 136.603486 -156.277056) (xy 136.584383 -156.258946)
			(xy 136.550907 -156.21832) (xy 136.52334 -156.173474) (xy 136.502206 -156.125262) (xy 136.487906 -156.0746)
			(xy 136.480714 -156.022453) (xy 136.480296 -155.996132) (xy 136.480782 -155.968881) (xy 136.488538 -155.914933)
			(xy 136.503893 -155.862638) (xy 136.526535 -155.813061) (xy 136.556001 -155.767211) (xy 136.591692 -155.72602)
			(xy 136.632883 -155.690329) (xy 136.678733 -155.660863) (xy 136.72831 -155.638221) (xy 136.780605 -155.622866)
			(xy 136.834553 -155.61511) (xy 136.889055 -155.61511) (xy 136.943003 -155.622866) (xy 136.995298 -155.638221)
			(xy 137.044875 -155.660863) (xy 137.090725 -155.690329) (xy 137.131916 -155.72602) (xy 137.167607 -155.767211)
			(xy 137.197073 -155.813061) (xy 137.219715 -155.862638) (xy 137.23507 -155.914933) (xy 137.242826 -155.968881)
			(xy 137.243312 -155.996132) (xy 137.242856 -156.022448) (xy 137.235636 -156.074582) (xy 137.221323 -156.12523)
			(xy 137.200189 -156.173431) (xy 137.172635 -156.218274) (xy 137.139182 -156.258906) (xy 137.120122 -156.277056)
			(xy 137.112741 -156.284595) (xy 137.104204 -156.303862) (xy 137.103612 -156.314394) (xy 137.103612 -156.38907)
			(xy 137.10414 -156.39962) (xy 137.112676 -156.418915) (xy 137.120122 -156.426408) (xy 137.13919 -156.444554)
			(xy 137.172672 -156.48517) (xy 137.200246 -156.530008) (xy 137.221387 -156.578213) (xy 137.235693 -156.62887)
			(xy 137.242892 -156.681013) (xy 137.243312 -156.707332) (xy 137.242856 -156.733648) (xy 137.235636 -156.785782)
			(xy 137.221323 -156.83643) (xy 137.200189 -156.884631) (xy 137.172635 -156.929474) (xy 137.139182 -156.970106)
			(xy 137.120122 -156.988256) (xy 137.112741 -156.995795) (xy 137.104204 -157.015062) (xy 137.103612 -157.025594)
			(xy 137.103612 -157.10027) (xy 137.10414 -157.11082) (xy 137.112676 -157.130115) (xy 137.120122 -157.137608)
			(xy 137.13919 -157.155754) (xy 137.172672 -157.19637) (xy 137.200246 -157.241208) (xy 137.221387 -157.289413)
			(xy 137.235693 -157.34007) (xy 137.242892 -157.392213) (xy 137.243312 -157.418532) (xy 137.242826 -157.445783)
			(xy 137.23507 -157.499731) (xy 137.219715 -157.552026) (xy 137.197073 -157.601603) (xy 137.167607 -157.647453)
			(xy 137.131916 -157.688644) (xy 137.090725 -157.724335) (xy 137.044875 -157.753801) (xy 136.995298 -157.776443)
			(xy 136.943003 -157.791798) (xy 136.889055 -157.799554) (xy 136.834553 -157.799554) (xy 136.780605 -157.791798)
			(xy 136.72831 -157.776443) (xy 136.678733 -157.753801) (xy 136.632883 -157.724335) (xy 136.591692 -157.688644)
			(xy 136.556001 -157.647453) (xy 136.526535 -157.601603) (xy 136.503893 -157.552026) (xy 136.488538 -157.499731)
			(xy 136.480782 -157.445783) (xy 136.480296 -157.418532) (xy 134.172017 -157.418532) (xy 134.16929 -157.437501)
			(xy 134.153935 -157.489796) (xy 134.131293 -157.539373) (xy 134.101827 -157.585223) (xy 134.066136 -157.626414)
			(xy 134.024945 -157.662105) (xy 133.979095 -157.691571) (xy 133.929518 -157.714213) (xy 133.877223 -157.729568)
			(xy 133.823275 -157.737324) (xy 133.768773 -157.737324) (xy 133.714825 -157.729568) (xy 133.66253 -157.714213)
			(xy 133.612953 -157.691571) (xy 133.567103 -157.662105) (xy 133.525912 -157.626414) (xy 133.490221 -157.585223)
			(xy 133.460755 -157.539373) (xy 133.438113 -157.489796) (xy 133.422758 -157.437501) (xy 133.415002 -157.383553)
			(xy 133.414516 -157.356302) (xy 132.061126 -157.356302) (xy 132.061632 -157.357445) (xy 132.069078 -157.364938)
			(xy 132.088172 -157.383058) (xy 132.121649 -157.423681) (xy 132.149218 -157.468525) (xy 132.170355 -157.516735)
			(xy 132.184656 -157.567395) (xy 132.19185 -157.619542) (xy 132.192268 -157.645862) (xy 132.191782 -157.673113)
			(xy 132.184026 -157.727061) (xy 132.168671 -157.779356) (xy 132.146029 -157.828933) (xy 132.116563 -157.874783)
			(xy 132.080872 -157.915974) (xy 132.039681 -157.951665) (xy 131.993831 -157.981131) (xy 131.944254 -158.003773)
			(xy 131.891959 -158.019128) (xy 131.838011 -158.026884) (xy 131.783509 -158.026884) (xy 131.729561 -158.019128)
			(xy 131.677266 -158.003773) (xy 131.627689 -157.981131) (xy 131.581839 -157.951665) (xy 131.540648 -157.915974)
			(xy 131.504957 -157.874783) (xy 131.475491 -157.828933) (xy 131.452849 -157.779356) (xy 131.437494 -157.727061)
			(xy 131.429738 -157.673113) (xy 131.429252 -157.645862) (xy 130.475187 -157.645862) (xy 130.475228 -157.647894)
			(xy 130.474718 -157.673881) (xy 130.466588 -157.725216) (xy 130.450527 -157.774646) (xy 130.426931 -157.820956)
			(xy 130.396381 -157.863004) (xy 130.35963 -157.899755) (xy 130.317582 -157.930305) (xy 130.271272 -157.953901)
			(xy 130.221842 -157.969962) (xy 130.170507 -157.978092) (xy 130.118533 -157.978092) (xy 130.067198 -157.969962)
			(xy 130.017768 -157.953901) (xy 129.971458 -157.930305) (xy 129.92941 -157.899755) (xy 129.892659 -157.863004)
			(xy 129.862109 -157.820956) (xy 129.838513 -157.774646) (xy 129.822452 -157.725216) (xy 129.814322 -157.673881)
			(xy 129.813812 -157.647894) (xy 129.575052 -157.647894) (xy 129.574542 -157.673881) (xy 129.566412 -157.725216)
			(xy 129.550351 -157.774646) (xy 129.526755 -157.820956) (xy 129.496205 -157.863004) (xy 129.459454 -157.899755)
			(xy 129.417406 -157.930305) (xy 129.371096 -157.953901) (xy 129.321666 -157.969962) (xy 129.270331 -157.978092)
			(xy 129.218357 -157.978092) (xy 129.167022 -157.969962) (xy 129.117592 -157.953901) (xy 129.071282 -157.930305)
			(xy 129.029234 -157.899755) (xy 128.992483 -157.863004) (xy 128.961933 -157.820956) (xy 128.938337 -157.774646)
			(xy 128.922276 -157.725216) (xy 128.914146 -157.673881) (xy 128.913636 -157.647894) (xy 128.67513 -157.647894)
			(xy 128.67462 -157.673881) (xy 128.66649 -157.725216) (xy 128.650429 -157.774646) (xy 128.626833 -157.820956)
			(xy 128.596283 -157.863004) (xy 128.559532 -157.899755) (xy 128.517484 -157.930305) (xy 128.471174 -157.953901)
			(xy 128.421744 -157.969962) (xy 128.370409 -157.978092) (xy 128.318435 -157.978092) (xy 128.2671 -157.969962)
			(xy 128.21767 -157.953901) (xy 128.17136 -157.930305) (xy 128.129312 -157.899755) (xy 128.092561 -157.863004)
			(xy 128.062011 -157.820956) (xy 128.038415 -157.774646) (xy 128.022354 -157.725216) (xy 128.014224 -157.673881)
			(xy 128.013714 -157.647894) (xy 127.775208 -157.647894) (xy 127.774698 -157.673881) (xy 127.766568 -157.725216)
			(xy 127.750507 -157.774646) (xy 127.726911 -157.820956) (xy 127.696361 -157.863004) (xy 127.65961 -157.899755)
			(xy 127.617562 -157.930305) (xy 127.571252 -157.953901) (xy 127.521822 -157.969962) (xy 127.470487 -157.978092)
			(xy 127.418513 -157.978092) (xy 127.367178 -157.969962) (xy 127.317748 -157.953901) (xy 127.271438 -157.930305)
			(xy 127.22939 -157.899755) (xy 127.192639 -157.863004) (xy 127.162089 -157.820956) (xy 127.138493 -157.774646)
			(xy 127.122432 -157.725216) (xy 127.114302 -157.673881) (xy 127.113792 -157.647894) (xy 123.475477 -157.647894)
			(xy 123.488899 -157.676525) (xy 123.504967 -157.729932) (xy 123.513087 -157.785108) (xy 123.513596 -157.812994)
			(xy 123.513087 -157.84088) (xy 123.504967 -157.896056) (xy 123.488899 -157.949463) (xy 123.465227 -157.99996)
			(xy 123.434454 -158.046473) (xy 123.421984 -158.06039) (xy 124.93955 -158.06039) (xy 124.943621 -158.004768)
			(xy 124.955747 -157.950331) (xy 124.97567 -157.89824) (xy 125.002966 -157.849605) (xy 125.037052 -157.805462)
			(xy 125.077201 -157.766753) (xy 125.122559 -157.734302) (xy 125.172159 -157.708801) (xy 125.224943 -157.690794)
			(xy 125.279786 -157.680664) (xy 125.33552 -157.678627) (xy 125.390957 -157.684727) (xy 125.444914 -157.698833)
			(xy 125.496243 -157.720645) (xy 125.543849 -157.749699) (xy 125.586717 -157.785374) (xy 125.623934 -157.826911)
			(xy 125.654707 -157.873424) (xy 125.678379 -157.923921) (xy 125.694447 -157.977328) (xy 125.702567 -158.032504)
			(xy 125.703076 -158.06039) (xy 125.702567 -158.088276) (xy 125.694447 -158.143452) (xy 125.678379 -158.196859)
			(xy 125.654707 -158.247356) (xy 125.623934 -158.293869) (xy 125.586717 -158.335406) (xy 125.543849 -158.371081)
			(xy 125.496243 -158.400135) (xy 125.444914 -158.421947) (xy 125.390957 -158.436053) (xy 125.33552 -158.442153)
			(xy 125.279786 -158.440116) (xy 125.224943 -158.429986) (xy 125.172159 -158.411979) (xy 125.122559 -158.386478)
			(xy 125.077201 -158.354027) (xy 125.037052 -158.315318) (xy 125.002966 -158.271175) (xy 124.97567 -158.22254)
			(xy 124.955747 -158.170449) (xy 124.943621 -158.116012) (xy 124.93955 -158.06039) (xy 123.421984 -158.06039)
			(xy 123.397237 -158.08801) (xy 123.354369 -158.123685) (xy 123.306763 -158.152739) (xy 123.255434 -158.174551)
			(xy 123.201477 -158.188657) (xy 123.14604 -158.194757) (xy 123.090306 -158.19272) (xy 123.035463 -158.18259)
			(xy 122.982679 -158.164583) (xy 122.933079 -158.139082) (xy 122.887721 -158.106631) (xy 122.847572 -158.067922)
			(xy 122.813486 -158.023779) (xy 122.78619 -157.975144) (xy 122.766267 -157.923053) (xy 122.754141 -157.868616)
			(xy 122.75007 -157.812994) (xy 121.998486 -157.812994) (xy 121.998486 -158.828994) (xy 122.75007 -158.828994)
			(xy 122.754141 -158.773372) (xy 122.766267 -158.718935) (xy 122.78619 -158.666844) (xy 122.813486 -158.618209)
			(xy 122.847572 -158.574066) (xy 122.887721 -158.535357) (xy 122.933079 -158.502906) (xy 122.982679 -158.477405)
			(xy 123.035463 -158.459398) (xy 123.090306 -158.449268) (xy 123.14604 -158.447231) (xy 123.201477 -158.453331)
			(xy 123.255434 -158.467437) (xy 123.306763 -158.489249) (xy 123.354369 -158.518303) (xy 123.397237 -158.553978)
			(xy 123.434454 -158.595515) (xy 123.465227 -158.642028) (xy 123.488899 -158.692525) (xy 123.504967 -158.745932)
			(xy 123.506052 -158.753302) (xy 132.616446 -158.753302) (xy 132.620517 -158.69768) (xy 132.632643 -158.643243)
			(xy 132.652566 -158.591152) (xy 132.679862 -158.542517) (xy 132.713948 -158.498374) (xy 132.754097 -158.459665)
			(xy 132.799455 -158.427214) (xy 132.849055 -158.401713) (xy 132.901839 -158.383706) (xy 132.956682 -158.373576)
			(xy 133.012416 -158.371539) (xy 133.067853 -158.377639) (xy 133.12181 -158.391745) (xy 133.173139 -158.413557)
			(xy 133.220745 -158.442611) (xy 133.263613 -158.478286) (xy 133.30083 -158.519823) (xy 133.331603 -158.566336)
			(xy 133.355275 -158.616833) (xy 133.371343 -158.67024) (xy 133.379463 -158.725416) (xy 133.379972 -158.753302)
			(xy 133.379463 -158.781188) (xy 133.371343 -158.836364) (xy 133.355275 -158.889771) (xy 133.331603 -158.940268)
			(xy 133.30083 -158.986781) (xy 133.263613 -159.028318) (xy 133.220745 -159.063993) (xy 133.173139 -159.093047)
			(xy 133.12181 -159.114859) (xy 133.067853 -159.128965) (xy 133.012416 -159.135065) (xy 132.956682 -159.133028)
			(xy 132.901839 -159.122898) (xy 132.849055 -159.104891) (xy 132.799455 -159.07939) (xy 132.754097 -159.046939)
			(xy 132.713948 -159.00823) (xy 132.679862 -158.964087) (xy 132.652566 -158.915452) (xy 132.632643 -158.863361)
			(xy 132.620517 -158.808924) (xy 132.616446 -158.753302) (xy 123.506052 -158.753302) (xy 123.513087 -158.801108)
			(xy 123.513596 -158.828994) (xy 123.513087 -158.85688) (xy 123.504967 -158.912056) (xy 123.488899 -158.965463)
			(xy 123.465227 -159.01596) (xy 123.434454 -159.062473) (xy 123.397237 -159.10401) (xy 123.354369 -159.139685)
			(xy 123.306763 -159.168739) (xy 123.255434 -159.190551) (xy 123.201477 -159.204657) (xy 123.14604 -159.210757)
			(xy 123.090306 -159.20872) (xy 123.035463 -159.19859) (xy 122.982679 -159.180583) (xy 122.933079 -159.155082)
			(xy 122.887721 -159.122631) (xy 122.847572 -159.083922) (xy 122.813486 -159.039779) (xy 122.78619 -158.991144)
			(xy 122.766267 -158.939053) (xy 122.754141 -158.884616) (xy 122.75007 -158.828994) (xy 121.998486 -158.828994)
			(xy 121.998486 -159.439102) (xy 125.007876 -159.439102) (xy 125.011947 -159.38348) (xy 125.024073 -159.329043)
			(xy 125.043996 -159.276952) (xy 125.071292 -159.228317) (xy 125.105378 -159.184174) (xy 125.145527 -159.145465)
			(xy 125.190885 -159.113014) (xy 125.240485 -159.087513) (xy 125.293269 -159.069506) (xy 125.348112 -159.059376)
			(xy 125.403846 -159.057339) (xy 125.459283 -159.063439) (xy 125.51324 -159.077545) (xy 125.564569 -159.099357)
			(xy 125.612175 -159.128411) (xy 125.655043 -159.164086) (xy 125.69226 -159.205623) (xy 125.723033 -159.252136)
			(xy 125.746705 -159.302633) (xy 125.762773 -159.35604) (xy 125.770893 -159.411216) (xy 125.771402 -159.439102)
			(xy 125.770893 -159.466988) (xy 125.762773 -159.522164) (xy 125.75987 -159.531812) (xy 128.212594 -159.531812)
			(xy 128.216665 -159.47619) (xy 128.228791 -159.421753) (xy 128.248714 -159.369662) (xy 128.27601 -159.321027)
			(xy 128.310096 -159.276884) (xy 128.350245 -159.238175) (xy 128.395603 -159.205724) (xy 128.445203 -159.180223)
			(xy 128.497987 -159.162216) (xy 128.55283 -159.152086) (xy 128.608564 -159.150049) (xy 128.664001 -159.156149)
			(xy 128.717958 -159.170255) (xy 128.769287 -159.192067) (xy 128.816893 -159.221121) (xy 128.859761 -159.256796)
			(xy 128.896978 -159.298333) (xy 128.927751 -159.344846) (xy 128.951423 -159.395343) (xy 128.967491 -159.44875)
			(xy 128.97336 -159.488632) (xy 130.4958 -159.488632) (xy 130.499871 -159.43301) (xy 130.511997 -159.378573)
			(xy 130.53192 -159.326482) (xy 130.559216 -159.277847) (xy 130.593302 -159.233704) (xy 130.633451 -159.194995)
			(xy 130.678809 -159.162544) (xy 130.728409 -159.137043) (xy 130.781193 -159.119036) (xy 130.836036 -159.108906)
			(xy 130.89177 -159.106869) (xy 130.947207 -159.112969) (xy 131.001164 -159.127075) (xy 131.052493 -159.148887)
			(xy 131.100099 -159.177941) (xy 131.142967 -159.213616) (xy 131.180184 -159.255153) (xy 131.210957 -159.301666)
			(xy 131.234629 -159.352163) (xy 131.250697 -159.40557) (xy 131.258817 -159.460746) (xy 131.259326 -159.488632)
			(xy 131.258817 -159.516518) (xy 131.250697 -159.571694) (xy 131.234629 -159.625101) (xy 131.210957 -159.675598)
			(xy 131.180184 -159.722111) (xy 131.142967 -159.763648) (xy 131.100099 -159.799323) (xy 131.052493 -159.828377)
			(xy 131.001164 -159.850189) (xy 130.947207 -159.864295) (xy 130.89177 -159.870395) (xy 130.836036 -159.868358)
			(xy 130.781193 -159.858228) (xy 130.728409 -159.840221) (xy 130.678809 -159.81472) (xy 130.633451 -159.782269)
			(xy 130.593302 -159.74356) (xy 130.559216 -159.699417) (xy 130.53192 -159.650782) (xy 130.511997 -159.598691)
			(xy 130.499871 -159.544254) (xy 130.4958 -159.488632) (xy 128.97336 -159.488632) (xy 128.975611 -159.503926)
			(xy 128.97612 -159.531812) (xy 128.975611 -159.559698) (xy 128.967491 -159.614874) (xy 128.951423 -159.668281)
			(xy 128.927751 -159.718778) (xy 128.896978 -159.765291) (xy 128.859761 -159.806828) (xy 128.816893 -159.842503)
			(xy 128.769287 -159.871557) (xy 128.717958 -159.893369) (xy 128.664001 -159.907475) (xy 128.608564 -159.913575)
			(xy 128.55283 -159.911538) (xy 128.497987 -159.901408) (xy 128.445203 -159.883401) (xy 128.395603 -159.8579)
			(xy 128.350245 -159.825449) (xy 128.310096 -159.78674) (xy 128.27601 -159.742597) (xy 128.248714 -159.693962)
			(xy 128.228791 -159.641871) (xy 128.216665 -159.587434) (xy 128.212594 -159.531812) (xy 125.75987 -159.531812)
			(xy 125.746705 -159.575571) (xy 125.723033 -159.626068) (xy 125.69226 -159.672581) (xy 125.655043 -159.714118)
			(xy 125.612175 -159.749793) (xy 125.564569 -159.778847) (xy 125.51324 -159.800659) (xy 125.459283 -159.814765)
			(xy 125.403846 -159.820865) (xy 125.348112 -159.818828) (xy 125.293269 -159.808698) (xy 125.240485 -159.790691)
			(xy 125.190885 -159.76519) (xy 125.145527 -159.732739) (xy 125.105378 -159.69403) (xy 125.071292 -159.649887)
			(xy 125.043996 -159.601252) (xy 125.024073 -159.549161) (xy 125.011947 -159.494724) (xy 125.007876 -159.439102)
			(xy 121.998486 -159.439102) (xy 121.998486 -159.844994) (xy 122.75007 -159.844994) (xy 122.754141 -159.789372)
			(xy 122.766267 -159.734935) (xy 122.78619 -159.682844) (xy 122.813486 -159.634209) (xy 122.847572 -159.590066)
			(xy 122.887721 -159.551357) (xy 122.933079 -159.518906) (xy 122.982679 -159.493405) (xy 123.035463 -159.475398)
			(xy 123.090306 -159.465268) (xy 123.14604 -159.463231) (xy 123.201477 -159.469331) (xy 123.255434 -159.483437)
			(xy 123.306763 -159.505249) (xy 123.354369 -159.534303) (xy 123.397237 -159.569978) (xy 123.434454 -159.611515)
			(xy 123.465227 -159.658028) (xy 123.488899 -159.708525) (xy 123.504967 -159.761932) (xy 123.513087 -159.817108)
			(xy 123.513596 -159.844994) (xy 123.513087 -159.87288) (xy 123.504967 -159.928056) (xy 123.488899 -159.981463)
			(xy 123.465227 -160.03196) (xy 123.434454 -160.078473) (xy 123.397237 -160.12001) (xy 123.354369 -160.155685)
			(xy 123.306763 -160.184739) (xy 123.255434 -160.206551) (xy 123.201477 -160.220657) (xy 123.14604 -160.226757)
			(xy 123.090306 -160.22472) (xy 123.035463 -160.21459) (xy 122.982679 -160.196583) (xy 122.933079 -160.171082)
			(xy 122.887721 -160.138631) (xy 122.847572 -160.099922) (xy 122.813486 -160.055779) (xy 122.78619 -160.007144)
			(xy 122.766267 -159.955053) (xy 122.754141 -159.900616) (xy 122.75007 -159.844994) (xy 121.998486 -159.844994)
			(xy 121.998486 -160.965896) (xy 125.037594 -160.965896) (xy 125.041665 -160.910274) (xy 125.053791 -160.855837)
			(xy 125.073714 -160.803746) (xy 125.10101 -160.755111) (xy 125.135096 -160.710968) (xy 125.175245 -160.672259)
			(xy 125.220603 -160.639808) (xy 125.270203 -160.614307) (xy 125.322987 -160.5963) (xy 125.37783 -160.58617)
			(xy 125.433564 -160.584133) (xy 125.489001 -160.590233) (xy 125.542958 -160.604339) (xy 125.594287 -160.626151)
			(xy 125.641893 -160.655205) (xy 125.684761 -160.69088) (xy 125.721978 -160.732417) (xy 125.752751 -160.77893)
			(xy 125.776423 -160.829427) (xy 125.792491 -160.882834) (xy 125.800611 -160.93801) (xy 125.801083 -160.963864)
			(xy 126.429514 -160.963864) (xy 126.433585 -160.908242) (xy 126.445711 -160.853805) (xy 126.465634 -160.801714)
			(xy 126.49293 -160.753079) (xy 126.527016 -160.708936) (xy 126.567165 -160.670227) (xy 126.612523 -160.637776)
			(xy 126.662123 -160.612275) (xy 126.714907 -160.594268) (xy 126.76975 -160.584138) (xy 126.825484 -160.582101)
			(xy 126.880921 -160.588201) (xy 126.934878 -160.602307) (xy 126.986207 -160.624119) (xy 127.033813 -160.653173)
			(xy 127.076681 -160.688848) (xy 127.113898 -160.730385) (xy 127.144671 -160.776898) (xy 127.168343 -160.827395)
			(xy 127.184411 -160.880802) (xy 127.192531 -160.935978) (xy 127.19304 -160.963864) (xy 127.192947 -160.968944)
			(xy 127.701292 -160.968944) (xy 127.705363 -160.913322) (xy 127.717489 -160.858885) (xy 127.737412 -160.806794)
			(xy 127.764708 -160.758159) (xy 127.798794 -160.714016) (xy 127.838943 -160.675307) (xy 127.884301 -160.642856)
			(xy 127.933901 -160.617355) (xy 127.986685 -160.599348) (xy 128.041528 -160.589218) (xy 128.097262 -160.587181)
			(xy 128.152699 -160.593281) (xy 128.206656 -160.607387) (xy 128.257985 -160.629199) (xy 128.305591 -160.658253)
			(xy 128.348459 -160.693928) (xy 128.385676 -160.735465) (xy 128.416449 -160.781978) (xy 128.440121 -160.832475)
			(xy 128.456189 -160.885882) (xy 128.458582 -160.902142) (xy 129.482594 -160.902142) (xy 129.486665 -160.84652)
			(xy 129.498791 -160.792083) (xy 129.518714 -160.739992) (xy 129.54601 -160.691357) (xy 129.580096 -160.647214)
			(xy 129.620245 -160.608505) (xy 129.665603 -160.576054) (xy 129.715203 -160.550553) (xy 129.767987 -160.532546)
			(xy 129.82283 -160.522416) (xy 129.878564 -160.520379) (xy 129.934001 -160.526479) (xy 129.987958 -160.540585)
			(xy 130.039287 -160.562397) (xy 130.086893 -160.591451) (xy 130.129761 -160.627126) (xy 130.166978 -160.668663)
			(xy 130.197751 -160.715176) (xy 130.221423 -160.765673) (xy 130.237491 -160.81908) (xy 130.245611 -160.874256)
			(xy 130.24612 -160.902142) (xy 130.245611 -160.930028) (xy 130.237491 -160.985204) (xy 130.221423 -161.038611)
			(xy 130.197751 -161.089108) (xy 130.166978 -161.135621) (xy 130.129761 -161.177158) (xy 130.086893 -161.212833)
			(xy 130.039287 -161.241887) (xy 129.987958 -161.263699) (xy 129.934001 -161.277805) (xy 129.878564 -161.283905)
			(xy 129.82283 -161.281868) (xy 129.767987 -161.271738) (xy 129.715203 -161.253731) (xy 129.665603 -161.22823)
			(xy 129.620245 -161.195779) (xy 129.580096 -161.15707) (xy 129.54601 -161.112927) (xy 129.518714 -161.064292)
			(xy 129.498791 -161.012201) (xy 129.486665 -160.957764) (xy 129.482594 -160.902142) (xy 128.458582 -160.902142)
			(xy 128.464309 -160.941058) (xy 128.464818 -160.968944) (xy 128.464309 -160.99683) (xy 128.456189 -161.052006)
			(xy 128.440121 -161.105413) (xy 128.416449 -161.15591) (xy 128.385676 -161.202423) (xy 128.348459 -161.24396)
			(xy 128.305591 -161.279635) (xy 128.257985 -161.308689) (xy 128.206656 -161.330501) (xy 128.152699 -161.344607)
			(xy 128.097262 -161.350707) (xy 128.041528 -161.34867) (xy 127.986685 -161.33854) (xy 127.933901 -161.320533)
			(xy 127.884301 -161.295032) (xy 127.838943 -161.262581) (xy 127.798794 -161.223872) (xy 127.764708 -161.179729)
			(xy 127.737412 -161.131094) (xy 127.717489 -161.079003) (xy 127.705363 -161.024566) (xy 127.701292 -160.968944)
			(xy 127.192947 -160.968944) (xy 127.192531 -160.99175) (xy 127.184411 -161.046926) (xy 127.168343 -161.100333)
			(xy 127.144671 -161.15083) (xy 127.113898 -161.197343) (xy 127.076681 -161.23888) (xy 127.033813 -161.274555)
			(xy 126.986207 -161.303609) (xy 126.934878 -161.325421) (xy 126.880921 -161.339527) (xy 126.825484 -161.345627)
			(xy 126.76975 -161.34359) (xy 126.714907 -161.33346) (xy 126.662123 -161.315453) (xy 126.612523 -161.289952)
			(xy 126.567165 -161.257501) (xy 126.527016 -161.218792) (xy 126.49293 -161.174649) (xy 126.465634 -161.126014)
			(xy 126.445711 -161.073923) (xy 126.433585 -161.019486) (xy 126.429514 -160.963864) (xy 125.801083 -160.963864)
			(xy 125.80112 -160.965896) (xy 125.800611 -160.993782) (xy 125.792491 -161.048958) (xy 125.776423 -161.102365)
			(xy 125.752751 -161.152862) (xy 125.721978 -161.199375) (xy 125.684761 -161.240912) (xy 125.641893 -161.276587)
			(xy 125.594287 -161.305641) (xy 125.542958 -161.327453) (xy 125.489001 -161.341559) (xy 125.433564 -161.347659)
			(xy 125.37783 -161.345622) (xy 125.322987 -161.335492) (xy 125.270203 -161.317485) (xy 125.220603 -161.291984)
			(xy 125.175245 -161.259533) (xy 125.135096 -161.220824) (xy 125.10101 -161.176681) (xy 125.073714 -161.128046)
			(xy 125.053791 -161.075955) (xy 125.041665 -161.021518) (xy 125.037594 -160.965896) (xy 121.998486 -160.965896)
			(xy 121.998486 -162.375342) (xy 121.99895 -162.385217) (xy 122.006398 -162.403511) (xy 122.012964 -162.410902)
			(xy 122.013218 -162.411156) (xy 122.716798 -163.114736) (xy 132.149594 -163.114736) (xy 132.153665 -163.059114)
			(xy 132.165791 -163.004677) (xy 132.185714 -162.952586) (xy 132.21301 -162.903951) (xy 132.247096 -162.859808)
			(xy 132.287245 -162.821099) (xy 132.332603 -162.788648) (xy 132.382203 -162.763147) (xy 132.434987 -162.74514)
			(xy 132.48983 -162.73501) (xy 132.545564 -162.732973) (xy 132.601001 -162.739073) (xy 132.654958 -162.753179)
			(xy 132.706287 -162.774991) (xy 132.753893 -162.804045) (xy 132.796761 -162.83972) (xy 132.833978 -162.881257)
			(xy 132.864751 -162.92777) (xy 132.888423 -162.978267) (xy 132.904491 -163.031674) (xy 132.912611 -163.08685)
			(xy 132.91312 -163.114736) (xy 132.912611 -163.142622) (xy 132.904491 -163.197798) (xy 132.888423 -163.251205)
			(xy 132.864751 -163.301702) (xy 132.833978 -163.348215) (xy 132.796761 -163.389752) (xy 132.753893 -163.425427)
			(xy 132.706287 -163.454481) (xy 132.654958 -163.476293) (xy 132.601001 -163.490399) (xy 132.545564 -163.496499)
			(xy 132.48983 -163.494462) (xy 132.434987 -163.484332) (xy 132.382203 -163.466325) (xy 132.332603 -163.440824)
			(xy 132.287245 -163.408373) (xy 132.247096 -163.369664) (xy 132.21301 -163.325521) (xy 132.185714 -163.276886)
			(xy 132.165791 -163.224795) (xy 132.153665 -163.170358) (xy 132.149594 -163.114736) (xy 122.716798 -163.114736)
			(xy 125.047248 -165.445186) (xy 125.047756 -165.445694) (xy 125.055139 -165.452271) (xy 125.073438 -165.459714)
			(xy 125.083316 -165.460172)
		)
		(stroke
			(width 0)
			(type solid)
		)
		(fill yes)
		(layer "In15.Cu")
		(net "GND")
	)
	(gr_poly
		(pts
			(xy 366.432846 -293.716456) (xy 366.442911 -293.716023) (xy 366.4615 -293.708292) (xy 366.468914 -293.70147)
			(xy 367.900966 -292.269418) (xy 367.907803 -292.262017) (xy 367.915513 -292.243418) (xy 367.915952 -292.23335)
			(xy 367.915952 -286.34944) (xy 367.916388 -286.339376) (xy 367.924123 -286.320792) (xy 367.930938 -286.313372)
			(xy 368.493802 -285.750508) (xy 368.5012 -285.743661) (xy 368.519798 -285.735926) (xy 368.52987 -285.735522)
			(xy 382.434338 -285.735522) (xy 382.444406 -285.735093) (xy 382.463002 -285.727371) (xy 382.470406 -285.720536)
			(xy 383.269998 -284.920944) (xy 383.276836 -284.913543) (xy 383.28455 -284.894944) (xy 383.284984 -284.884876)
			(xy 383.284984 -268.79677) (xy 383.277364 -268.777974) (xy 383.269998 -268.770862) (xy 381.996188 -267.497052)
			(xy 381.989076 -267.489686) (xy 381.97028 -267.482066) (xy 381.49149 -267.482066) (xy 381.481643 -267.48251)
			(xy 381.463397 -267.48992) (xy 381.449305 -267.503677) (xy 381.445008 -267.512546) (xy 381.401828 -267.612114)
			(xy 381.406908 -267.641832) (xy 381.417322 -267.653008) (xy 381.484823 -267.725848) (xy 381.614403 -267.87637)
			(xy 381.737578 -268.032176) (xy 381.854133 -268.192994) (xy 381.963865 -268.358543) (xy 382.066582 -268.528534)
			(xy 382.162104 -268.702669) (xy 382.250264 -268.880645) (xy 382.330908 -269.06215) (xy 382.403895 -269.246867)
			(xy 382.469098 -269.434473) (xy 382.526403 -269.624641) (xy 382.57571 -269.817038) (xy 382.616931 -270.011327)
			(xy 382.649997 -270.207169) (xy 382.674847 -270.404223) (xy 382.69144 -270.602143) (xy 382.699746 -270.800583)
			(xy 382.700276 -270.89989) (xy 382.699782 -270.996805) (xy 382.691876 -271.190473) (xy 382.676077 -271.383657)
			(xy 382.652412 -271.576036) (xy 382.620919 -271.76729) (xy 382.581652 -271.9571) (xy 382.534675 -272.14515)
			(xy 382.480067 -272.331128) (xy 382.417918 -272.514723) (xy 382.348333 -272.695631) (xy 382.271427 -272.87355)
			(xy 382.187328 -273.048184) (xy 382.096175 -273.219243) (xy 381.998121 -273.386441) (xy 381.893329 -273.5495)
			(xy 381.781974 -273.70815) (xy 381.66424 -273.862125) (xy 381.540323 -274.01117) (xy 381.41043 -274.155037)
			(xy 381.274777 -274.293486) (xy 381.13359 -274.426286) (xy 380.987104 -274.553217) (xy 380.835562 -274.674068)
			(xy 380.679217 -274.788637) (xy 380.518329 -274.896733) (xy 380.353166 -274.998177) (xy 380.184002 -275.0928)
			(xy 380.01112 -275.180444) (xy 379.834807 -275.260964) (xy 379.655356 -275.334225) (xy 379.473066 -275.400105)
			(xy 379.288241 -275.458495) (xy 379.101188 -275.509298) (xy 378.912219 -275.552429) (xy 378.721647 -275.587817)
			(xy 378.529791 -275.615401) (xy 378.336969 -275.635138) (xy 378.143503 -275.646993) (xy 377.949714 -275.650947)
			(xy 377.755925 -275.646993) (xy 377.562459 -275.635138) (xy 377.369637 -275.615401) (xy 377.177781 -275.587817)
			(xy 376.987209 -275.552429) (xy 376.79824 -275.509298) (xy 376.611187 -275.458495) (xy 376.426362 -275.400105)
			(xy 376.244072 -275.334225) (xy 376.064621 -275.260964) (xy 375.888308 -275.180444) (xy 375.715426 -275.0928)
			(xy 375.546262 -274.998177) (xy 375.381099 -274.896733) (xy 375.220211 -274.788637) (xy 375.063866 -274.674068)
			(xy 374.912324 -274.553217) (xy 374.765838 -274.426286) (xy 374.624651 -274.293486) (xy 374.488998 -274.155037)
			(xy 374.359105 -274.01117) (xy 374.235188 -273.862125) (xy 374.117454 -273.70815) (xy 374.006099 -273.5495)
			(xy 373.901307 -273.386441) (xy 373.803253 -273.219243) (xy 373.7121 -273.048184) (xy 373.628001 -272.87355)
			(xy 373.551095 -272.695631) (xy 373.48151 -272.514723) (xy 373.419361 -272.331128) (xy 373.364753 -272.14515)
			(xy 373.317776 -271.9571) (xy 373.278509 -271.76729) (xy 373.247016 -271.576036) (xy 373.223351 -271.383657)
			(xy 373.207552 -271.190473) (xy 373.199646 -270.996805) (xy 373.199152 -270.89989) (xy 373.199675 -270.800583)
			(xy 373.207989 -270.602144) (xy 373.224588 -270.404225) (xy 373.249445 -270.207174) (xy 373.282514 -270.011333)
			(xy 373.32374 -269.817045) (xy 373.373049 -269.62465) (xy 373.430356 -269.434484) (xy 373.49556 -269.246878)
			(xy 373.568548 -269.062162) (xy 373.649191 -268.880658) (xy 373.73735 -268.702682) (xy 373.832869 -268.528546)
			(xy 373.935583 -268.358554) (xy 374.045311 -268.193004) (xy 374.161862 -268.032184) (xy 374.285032 -267.876375)
			(xy 374.414607 -267.72585) (xy 374.482106 -267.653008) (xy 374.49252 -267.641832) (xy 374.4976 -267.612114)
			(xy 374.45823 -267.521436) (xy 374.456246 -267.517077) (xy 374.45087 -267.509152) (xy 374.447562 -267.505688)
			(xy 373.88419 -266.942316) (xy 373.877078 -266.93495) (xy 373.858282 -266.92733) (xy 336.371184 -266.92733)
			(xy 336.352388 -266.93495) (xy 336.345276 -266.942316) (xy 335.812892 -267.4747) (xy 335.809323 -267.478106)
			(xy 335.80114 -267.483611) (xy 335.796636 -267.485622) (xy 335.787238 -267.489432) (xy 335.071466 -268.205204)
			(xy 335.06176 -268.215562) (xy 335.047978 -268.240366) (xy 335.041551 -268.268003) (xy 335.042974 -268.296342)
			(xy 335.052137 -268.323197) (xy 335.068334 -268.346495) (xy 335.090314 -268.364439) (xy 335.116383 -268.375645)
			(xy 335.130394 -268.377924) (xy 335.158261 -268.382004) (xy 335.212467 -268.397289) (xy 335.263841 -268.420367)
			(xy 335.311271 -268.450735) (xy 335.332832 -268.468856) (xy 335.34416 -268.478092) (xy 335.370717 -268.490268)
			(xy 335.399634 -268.494441) (xy 335.428551 -268.490268) (xy 335.455108 -268.478092) (xy 335.466436 -268.468856)
			(xy 335.487371 -268.45122) (xy 335.533341 -268.421505) (xy 335.583088 -268.398668) (xy 335.635589 -268.38318)
			(xy 335.689765 -268.375358) (xy 335.717134 -268.374876) (xy 335.744501 -268.375368) (xy 335.798668 -268.38322)
			(xy 335.851162 -268.398717) (xy 335.90091 -268.421542) (xy 335.946895 -268.451227) (xy 335.967832 -268.468856)
			(xy 335.97916 -268.478092) (xy 336.005717 -268.490268) (xy 336.034634 -268.494441) (xy 336.063551 -268.490268)
			(xy 336.090108 -268.478092) (xy 336.101436 -268.468856) (xy 336.122371 -268.45122) (xy 336.168341 -268.421505)
			(xy 336.218088 -268.398668) (xy 336.270589 -268.38318) (xy 336.324765 -268.375358) (xy 336.352134 -268.374876)
			(xy 336.379501 -268.375368) (xy 336.433668 -268.38322) (xy 336.486162 -268.398717) (xy 336.53591 -268.421542)
			(xy 336.581895 -268.451227) (xy 336.602832 -268.468856) (xy 336.61416 -268.478092) (xy 336.640717 -268.490268)
			(xy 336.669634 -268.494441) (xy 336.698551 -268.490268) (xy 336.725108 -268.478092) (xy 336.736436 -268.468856)
			(xy 336.757371 -268.45122) (xy 336.803341 -268.421505) (xy 336.853088 -268.398668) (xy 336.905589 -268.38318)
			(xy 336.959765 -268.375358) (xy 336.987134 -268.374876) (xy 337.014501 -268.375368) (xy 337.068668 -268.38322)
			(xy 337.121162 -268.398717) (xy 337.17091 -268.421542) (xy 337.216895 -268.451227) (xy 337.237832 -268.468856)
			(xy 337.24916 -268.478092) (xy 337.275717 -268.490268) (xy 337.304634 -268.494441) (xy 337.333551 -268.490268)
			(xy 337.360108 -268.478092) (xy 337.371436 -268.468856) (xy 337.392371 -268.45122) (xy 337.438341 -268.421505)
			(xy 337.488088 -268.398668) (xy 337.540589 -268.38318) (xy 337.594765 -268.375358) (xy 337.622134 -268.374876)
			(xy 337.649402 -268.375342) (xy 337.703384 -268.383108) (xy 337.75571 -268.398478) (xy 337.805316 -268.421138)
			(xy 337.851193 -268.450627) (xy 337.892406 -268.486345) (xy 337.928116 -268.527565) (xy 337.957597 -268.573447)
			(xy 337.980247 -268.623058) (xy 337.995607 -268.675387) (xy 338.003363 -268.729369) (xy 338.003896 -268.756638)
			(xy 338.003896 -268.756892) (xy 338.003385 -268.785597) (xy 337.994794 -268.84236) (xy 337.977791 -268.897194)
			(xy 337.952759 -268.948858) (xy 337.920265 -268.996187) (xy 337.901026 -269.017496) (xy 337.890961 -269.02903)
			(xy 337.87763 -269.056573) (xy 337.873055 -269.086828) (xy 337.877646 -269.117081) (xy 337.890992 -269.144616)
			(xy 337.901026 -269.15618) (xy 337.920241 -269.177507) (xy 337.952708 -269.224845) (xy 337.977729 -269.276507)
			(xy 337.994741 -269.331331) (xy 338.00336 -269.388083) (xy 338.003896 -269.416784) (xy 338.003896 -269.417038)
			(xy 357.085392 -269.417038) (xy 357.085392 -269.416784) (xy 357.085931 -269.388083) (xy 357.09455 -269.331332)
			(xy 357.111561 -269.276508) (xy 357.136581 -269.224845) (xy 357.169048 -269.177507) (xy 357.188262 -269.15618)
			(xy 357.198297 -269.144616) (xy 357.211644 -269.117081) (xy 357.216236 -269.086828) (xy 357.211661 -269.056572)
			(xy 357.198328 -269.02903) (xy 357.188262 -269.017496) (xy 357.169021 -268.996189) (xy 357.136528 -268.94886)
			(xy 357.111496 -268.897194) (xy 357.094494 -268.84236) (xy 357.085903 -268.785597) (xy 357.085392 -268.756892)
			(xy 357.085392 -268.756638) (xy 357.08596 -268.729372) (xy 357.093715 -268.675393) (xy 357.109073 -268.623068)
			(xy 357.131722 -268.573461) (xy 357.161199 -268.527582) (xy 357.196906 -268.486365) (xy 357.238115 -268.45065)
			(xy 357.283987 -268.421162) (xy 357.333589 -268.398502) (xy 357.385911 -268.383133) (xy 357.439888 -268.375366)
			(xy 357.467154 -268.374876) (xy 357.494523 -268.375365) (xy 357.548699 -268.383185) (xy 357.6012 -268.398672)
			(xy 357.650947 -268.421507) (xy 357.696917 -268.451221) (xy 357.717852 -268.468856) (xy 357.72918 -268.478092)
			(xy 357.755737 -268.490268) (xy 357.784654 -268.494441) (xy 357.813571 -268.490268) (xy 357.840128 -268.478092)
			(xy 357.851456 -268.468856) (xy 357.872398 -268.451233) (xy 357.918381 -268.421546) (xy 357.968128 -268.398721)
			(xy 358.020621 -268.383223) (xy 358.074788 -268.375369) (xy 358.102154 -268.374876) (xy 358.129523 -268.375365)
			(xy 358.183699 -268.383185) (xy 358.2362 -268.398672) (xy 358.285947 -268.421507) (xy 358.331917 -268.451221)
			(xy 358.352852 -268.468856) (xy 358.36418 -268.478092) (xy 358.390737 -268.490268) (xy 358.419654 -268.494441)
			(xy 358.448571 -268.490268) (xy 358.475128 -268.478092) (xy 358.486456 -268.468856) (xy 358.507398 -268.451233)
			(xy 358.553381 -268.421546) (xy 358.603128 -268.398721) (xy 358.655621 -268.383223) (xy 358.709788 -268.375369)
			(xy 358.737154 -268.374876) (xy 358.764523 -268.375365) (xy 358.818699 -268.383185) (xy 358.8712 -268.398672)
			(xy 358.920947 -268.421507) (xy 358.966917 -268.451221) (xy 358.987852 -268.468856) (xy 358.99918 -268.478092)
			(xy 359.025737 -268.490268) (xy 359.054654 -268.494441) (xy 359.083571 -268.490268) (xy 359.110128 -268.478092)
			(xy 359.121456 -268.468856) (xy 359.142398 -268.451233) (xy 359.188381 -268.421546) (xy 359.238128 -268.398721)
			(xy 359.290621 -268.383223) (xy 359.344788 -268.375369) (xy 359.372154 -268.374876) (xy 359.399523 -268.375365)
			(xy 359.453699 -268.383185) (xy 359.5062 -268.398672) (xy 359.555947 -268.421507) (xy 359.601917 -268.451221)
			(xy 359.622852 -268.468856) (xy 359.63418 -268.478092) (xy 359.660737 -268.490268) (xy 359.689654 -268.494441)
			(xy 359.718571 -268.490268) (xy 359.745128 -268.478092) (xy 359.756456 -268.468856) (xy 359.777398 -268.451233)
			(xy 359.823381 -268.421546) (xy 359.873128 -268.398721) (xy 359.925621 -268.383223) (xy 359.979788 -268.375369)
			(xy 360.007154 -268.374876) (xy 360.034426 -268.375344) (xy 360.088414 -268.383101) (xy 360.140749 -268.398464)
			(xy 360.190365 -268.421119) (xy 360.23625 -268.450605) (xy 360.277472 -268.486322) (xy 360.31319 -268.527543)
			(xy 360.342678 -268.573428) (xy 360.365334 -268.623043) (xy 360.380697 -268.675378) (xy 360.388455 -268.729366)
			(xy 360.388916 -268.756638) (xy 360.388916 -268.756892) (xy 360.38836 -268.785592) (xy 360.379745 -268.842343)
			(xy 360.362738 -268.897166) (xy 360.337722 -268.948829) (xy 360.305259 -268.996169) (xy 360.286046 -269.017496)
			(xy 360.275936 -269.029) (xy 360.262595 -269.056556) (xy 360.258017 -269.086828) (xy 360.262612 -269.117097)
			(xy 360.275967 -269.144646) (xy 360.286046 -269.15618) (xy 360.305277 -269.177496) (xy 360.337772 -269.224823)
			(xy 360.362804 -269.276486) (xy 360.37981 -269.331318) (xy 360.388403 -269.38808) (xy 360.388916 -269.416784)
			(xy 360.388916 -269.417038) (xy 360.388534 -269.444312) (xy 360.380765 -269.498304) (xy 360.365392 -269.550641)
			(xy 360.342726 -269.600258) (xy 360.313231 -269.646143) (xy 360.277505 -269.687364) (xy 360.236276 -269.723081)
			(xy 360.190384 -269.752567) (xy 360.140762 -269.775221) (xy 360.088422 -269.790583) (xy 360.034428 -269.79834)
			(xy 360.007154 -269.7988) (xy 359.979785 -269.798313) (xy 359.925609 -269.790493) (xy 359.873108 -269.775006)
			(xy 359.823361 -269.75217) (xy 359.777391 -269.722456) (xy 359.756456 -269.70482) (xy 359.745128 -269.695584)
			(xy 359.718571 -269.683408) (xy 359.689654 -269.679235) (xy 359.660737 -269.683408) (xy 359.63418 -269.695584)
			(xy 359.622852 -269.70482) (xy 359.601904 -269.722436) (xy 359.555923 -269.752124) (xy 359.506178 -269.774951)
			(xy 359.453686 -269.790451) (xy 359.39952 -269.798307) (xy 359.372154 -269.7988) (xy 359.344785 -269.798313)
			(xy 359.290609 -269.790493) (xy 359.238108 -269.775006) (xy 359.188361 -269.75217) (xy 359.142391 -269.722456)
			(xy 359.121456 -269.70482) (xy 359.110128 -269.695584) (xy 359.083571 -269.683408) (xy 359.054654 -269.679235)
			(xy 359.025737 -269.683408) (xy 358.99918 -269.695584) (xy 358.987852 -269.70482) (xy 358.966904 -269.722436)
			(xy 358.920923 -269.752124) (xy 358.871178 -269.774951) (xy 358.818686 -269.790451) (xy 358.76452 -269.798307)
			(xy 358.737154 -269.7988) (xy 358.709785 -269.798313) (xy 358.655609 -269.790493) (xy 358.603108 -269.775006)
			(xy 358.553361 -269.75217) (xy 358.507391 -269.722456) (xy 358.486456 -269.70482) (xy 358.475128 -269.695584)
			(xy 358.448571 -269.683408) (xy 358.419654 -269.679235) (xy 358.390737 -269.683408) (xy 358.36418 -269.695584)
			(xy 358.352852 -269.70482) (xy 358.331904 -269.722436) (xy 358.285923 -269.752124) (xy 358.236178 -269.774951)
			(xy 358.183686 -269.790451) (xy 358.12952 -269.798307) (xy 358.102154 -269.7988) (xy 358.074785 -269.798313)
			(xy 358.020609 -269.790493) (xy 357.968108 -269.775006) (xy 357.918361 -269.75217) (xy 357.872391 -269.722456)
			(xy 357.851456 -269.70482) (xy 357.840128 -269.695584) (xy 357.813571 -269.683408) (xy 357.784654 -269.679235)
			(xy 357.755737 -269.683408) (xy 357.72918 -269.695584) (xy 357.717852 -269.70482) (xy 357.696904 -269.722436)
			(xy 357.650923 -269.752124) (xy 357.601178 -269.774951) (xy 357.548686 -269.790451) (xy 357.49452 -269.798307)
			(xy 357.467154 -269.7988) (xy 357.439885 -269.798318) (xy 357.385903 -269.790551) (xy 357.333576 -269.775182)
			(xy 357.283968 -269.752523) (xy 357.23809 -269.723036) (xy 357.196873 -269.687321) (xy 357.161159 -269.646104)
			(xy 357.131673 -269.600225) (xy 357.109015 -269.550616) (xy 357.093647 -269.498289) (xy 357.085881 -269.444307)
			(xy 357.085392 -269.417038) (xy 338.003896 -269.417038) (xy 338.003407 -269.444306) (xy 337.995641 -269.498288)
			(xy 337.980273 -269.550615) (xy 337.957615 -269.600222) (xy 337.928129 -269.646101) (xy 337.892414 -269.687317)
			(xy 337.851198 -269.723031) (xy 337.805319 -269.752517) (xy 337.755711 -269.775174) (xy 337.703384 -269.790542)
			(xy 337.649402 -269.798307) (xy 337.622134 -269.7988) (xy 337.594768 -269.798306) (xy 337.540603 -269.790449)
			(xy 337.488112 -269.774948) (xy 337.438368 -269.752119) (xy 337.392388 -269.72243) (xy 337.371436 -269.70482)
			(xy 337.360108 -269.695584) (xy 337.333551 -269.683408) (xy 337.304634 -269.679235) (xy 337.275717 -269.683408)
			(xy 337.24916 -269.695584) (xy 337.237832 -269.70482) (xy 337.216897 -269.722455) (xy 337.170927 -269.752168)
			(xy 337.12118 -269.775002) (xy 337.068679 -269.790487) (xy 337.014503 -269.798306) (xy 336.987134 -269.7988)
			(xy 336.959768 -269.798306) (xy 336.905603 -269.790449) (xy 336.853112 -269.774948) (xy 336.803368 -269.752119)
			(xy 336.757388 -269.72243) (xy 336.736436 -269.70482) (xy 336.725108 -269.695584) (xy 336.698551 -269.683408)
			(xy 336.669634 -269.679235) (xy 336.640717 -269.683408) (xy 336.61416 -269.695584) (xy 336.602832 -269.70482)
			(xy 336.581897 -269.722455) (xy 336.535927 -269.752168) (xy 336.48618 -269.775002) (xy 336.433679 -269.790487)
			(xy 336.379503 -269.798306) (xy 336.352134 -269.7988) (xy 336.324768 -269.798306) (xy 336.270603 -269.790449)
			(xy 336.218112 -269.774948) (xy 336.168368 -269.752119) (xy 336.122388 -269.72243) (xy 336.101436 -269.70482)
			(xy 336.090108 -269.695584) (xy 336.063551 -269.683408) (xy 336.034634 -269.679235) (xy 336.005717 -269.683408)
			(xy 335.97916 -269.695584) (xy 335.967832 -269.70482) (xy 335.946897 -269.722455) (xy 335.900927 -269.752168)
			(xy 335.85118 -269.775002) (xy 335.798679 -269.790487) (xy 335.744503 -269.798306) (xy 335.717134 -269.7988)
			(xy 335.689768 -269.798306) (xy 335.635603 -269.790449) (xy 335.583112 -269.774948) (xy 335.533368 -269.752119)
			(xy 335.487388 -269.72243) (xy 335.466436 -269.70482) (xy 335.455108 -269.695584) (xy 335.428551 -269.683408)
			(xy 335.399634 -269.679235) (xy 335.370717 -269.683408) (xy 335.34416 -269.695584) (xy 335.332832 -269.70482)
			(xy 335.311897 -269.722455) (xy 335.265927 -269.752168) (xy 335.21618 -269.775002) (xy 335.163679 -269.790487)
			(xy 335.109503 -269.798306) (xy 335.082134 -269.7988) (xy 335.054862 -269.798316) (xy 335.000873 -269.790558)
			(xy 334.948537 -269.775196) (xy 334.89892 -269.752543) (xy 334.853032 -269.723058) (xy 334.811807 -269.687344)
			(xy 334.776085 -269.646126) (xy 334.746592 -269.600243) (xy 334.723929 -269.550631) (xy 334.708557 -269.498298)
			(xy 334.700789 -269.44431) (xy 334.700372 -269.417038) (xy 334.700372 -269.416784) (xy 334.700885 -269.38808)
			(xy 334.709478 -269.331318) (xy 334.726483 -269.276485) (xy 334.751515 -269.224822) (xy 334.784009 -269.177494)
			(xy 334.803242 -269.15618) (xy 334.813322 -269.144647) (xy 334.826679 -269.117098) (xy 334.831274 -269.086828)
			(xy 334.826695 -269.056556) (xy 334.813353 -269.028999) (xy 334.803242 -269.017496) (xy 334.783279 -268.995285)
			(xy 334.749796 -268.94584) (xy 334.724411 -268.891789) (xy 334.707742 -268.834447) (xy 334.70342 -268.804898)
			(xy 334.701188 -268.790861) (xy 334.690024 -268.764735) (xy 334.672088 -268.742701) (xy 334.648771 -268.726467)
			(xy 334.621882 -268.717292) (xy 334.593506 -268.715888) (xy 334.565842 -268.722363) (xy 334.541037 -268.736215)
			(xy 334.5307 -268.74597) (xy 332.648814 -270.627856) (xy 332.641448 -270.634968) (xy 332.633828 -270.653764)
			(xy 332.633828 -277.864824) (xy 335.665572 -277.864824) (xy 335.666118 -277.835922) (xy 335.674836 -277.778779)
			(xy 335.692061 -277.7236) (xy 335.717401 -277.671646) (xy 335.750277 -277.624101) (xy 335.789939 -277.582051)
			(xy 335.812384 -277.563834) (xy 335.824165 -277.55391) (xy 335.841684 -277.528594) (xy 335.850862 -277.499208)
			(xy 335.850867 -277.468421) (xy 335.841697 -277.439032) (xy 335.824186 -277.413711) (xy 335.812384 -277.403814)
			(xy 335.789902 -277.38564) (xy 335.750231 -277.343587) (xy 335.717352 -277.296035) (xy 335.692016 -277.244071)
			(xy 335.6748 -277.188883) (xy 335.666098 -277.13173) (xy 335.665572 -277.102824) (xy 335.666131 -277.073415)
			(xy 335.675162 -277.015295) (xy 335.693 -276.959248) (xy 335.719221 -276.906599) (xy 335.753207 -276.858593)
			(xy 335.794152 -276.816368) (xy 335.841088 -276.780921) (xy 335.86674 -276.766528) (xy 335.879628 -276.75901)
			(xy 335.900671 -276.737877) (xy 335.914718 -276.711568) (xy 335.920572 -276.682324) (xy 335.917734 -276.652635)
			(xy 335.906447 -276.62503) (xy 335.887671 -276.601858) (xy 335.87563 -276.593046) (xy 335.853891 -276.577725)
			(xy 335.81446 -276.542039) (xy 335.780362 -276.501226) (xy 335.752258 -276.456077) (xy 335.73069 -276.407464)
			(xy 335.716077 -276.356329) (xy 335.708702 -276.303661) (xy 335.708244 -276.27707) (xy 335.70873 -276.249701)
			(xy 335.716549 -276.195524) (xy 335.732035 -276.143023) (xy 335.754871 -276.093276) (xy 335.784587 -276.047306)
			(xy 335.802224 -276.026372) (xy 335.811488 -276.015065) (xy 335.823659 -275.9885) (xy 335.827825 -275.959577)
			(xy 335.823646 -275.930657) (xy 335.811463 -275.904096) (xy 335.802224 -275.892768) (xy 335.784607 -275.871821)
			(xy 335.754921 -275.825839) (xy 335.732095 -275.776093) (xy 335.716595 -275.723601) (xy 335.708738 -275.669436)
			(xy 335.708244 -275.64207) (xy 335.708835 -275.612248) (xy 335.718095 -275.553329) (xy 335.736402 -275.496565)
			(xy 335.76331 -275.443336) (xy 335.798165 -275.394938) (xy 335.818734 -275.373338) (xy 335.827819 -275.363499)
			(xy 335.84104 -275.340224) (xy 335.847767 -275.314315) (xy 335.847538 -275.287548) (xy 335.840368 -275.261758)
			(xy 335.82675 -275.238713) (xy 335.817464 -275.229066) (xy 335.799515 -275.211007) (xy 335.768015 -275.171007)
			(xy 335.742114 -275.127173) (xy 335.722273 -275.080284) (xy 335.708844 -275.031172) (xy 335.702066 -274.980711)
			(xy 335.70164 -274.955254) (xy 335.702082 -274.927983) (xy 335.70985 -274.873998) (xy 335.725221 -274.821668)
			(xy 335.747883 -274.772057) (xy 335.777373 -274.726176) (xy 335.813093 -274.684959) (xy 335.854315 -274.649245)
			(xy 335.900199 -274.61976) (xy 335.949813 -274.597104) (xy 336.002145 -274.581739) (xy 336.056131 -274.573978)
			(xy 336.083402 -274.573492) (xy 336.112305 -274.574012) (xy 336.16945 -274.582734) (xy 336.224629 -274.599964)
			(xy 336.276583 -274.625309) (xy 336.324128 -274.65819) (xy 336.366177 -274.697857) (xy 336.384392 -274.720304)
			(xy 336.394289 -274.732109) (xy 336.419613 -274.749628) (xy 336.449006 -274.758804) (xy 336.479798 -274.758804)
			(xy 336.509191 -274.749628) (xy 336.534515 -274.732109) (xy 336.544412 -274.720304) (xy 336.561204 -274.699571)
			(xy 336.599585 -274.662512) (xy 336.64275 -274.631156) (xy 336.689858 -274.606111) (xy 336.739993 -274.587865)
			(xy 336.79218 -274.576774) (xy 336.845402 -274.573052) (xy 336.898624 -274.576774) (xy 336.950811 -274.587865)
			(xy 337.000946 -274.606111) (xy 337.048054 -274.631156) (xy 337.091219 -274.662512) (xy 337.1296 -274.699571)
			(xy 337.146392 -274.720304) (xy 337.156289 -274.732109) (xy 337.181613 -274.749628) (xy 337.211006 -274.758804)
			(xy 337.241798 -274.758804) (xy 337.271191 -274.749628) (xy 337.296515 -274.732109) (xy 337.306412 -274.720304)
			(xy 337.324633 -274.697861) (xy 337.366676 -274.658188) (xy 337.414217 -274.625303) (xy 337.466172 -274.599959)
			(xy 337.521353 -274.582735) (xy 337.578499 -274.574024) (xy 337.607402 -274.573492) (xy 337.634669 -274.574022)
			(xy 337.688649 -274.581783) (xy 337.740975 -274.597146) (xy 337.790582 -274.6198) (xy 337.836461 -274.649281)
			(xy 337.877677 -274.684992) (xy 337.913392 -274.726204) (xy 337.942879 -274.772079) (xy 337.965538 -274.821684)
			(xy 337.980907 -274.874008) (xy 337.988674 -274.927987) (xy 337.989164 -274.955254) (xy 337.988586 -274.985076)
			(xy 337.979322 -275.043996) (xy 337.961012 -275.10076) (xy 337.934102 -275.153988) (xy 337.899244 -275.202387)
			(xy 337.878674 -275.223986) (xy 337.869564 -275.233804) (xy 337.856344 -275.257084) (xy 337.84962 -275.282999)
			(xy 337.849853 -275.309771) (xy 337.857029 -275.335565) (xy 337.870654 -275.358611) (xy 337.879944 -275.368258)
			(xy 337.897906 -275.386305) (xy 337.929404 -275.426307) (xy 337.955303 -275.470144) (xy 337.975142 -275.517036)
			(xy 337.988568 -275.566149) (xy 337.995344 -275.616612) (xy 337.995768 -275.64207) (xy 337.995202 -275.670971)
			(xy 337.986487 -275.728113) (xy 337.969264 -275.78329) (xy 337.943928 -275.835244) (xy 337.911056 -275.88279)
			(xy 337.871399 -275.924842) (xy 337.848956 -275.94306) (xy 337.837177 -275.952988) (xy 337.819651 -275.978301)
			(xy 337.810468 -276.007688) (xy 337.810462 -276.038476) (xy 337.814453 -276.051264) (xy 341.261446 -276.051264)
			(xy 341.261945 -276.023861) (xy 341.269794 -275.96962) (xy 341.285326 -275.91706) (xy 341.30822 -275.867265)
			(xy 341.338005 -275.821259) (xy 341.35568 -275.800312) (xy 341.361776 -275.7932) (xy 341.368126 -275.776182)
			(xy 341.368126 -275.691346) (xy 341.361776 -275.674328) (xy 341.35568 -275.667216) (xy 341.338032 -275.646249)
			(xy 341.308262 -275.600239) (xy 341.285369 -275.550448) (xy 341.269823 -275.497897) (xy 341.261943 -275.443664)
			(xy 341.261446 -275.416264) (xy 341.261945 -275.388861) (xy 341.269794 -275.33462) (xy 341.285326 -275.28206)
			(xy 341.30822 -275.232265) (xy 341.338005 -275.186259) (xy 341.35568 -275.165312) (xy 341.361776 -275.1582)
			(xy 341.368126 -275.141182) (xy 341.368126 -275.056346) (xy 341.361776 -275.039328) (xy 341.35568 -275.032216)
			(xy 341.338032 -275.011249) (xy 341.308262 -274.965239) (xy 341.285369 -274.915448) (xy 341.269823 -274.862897)
			(xy 341.261943 -274.808664) (xy 341.261446 -274.781264) (xy 341.261891 -274.753993) (xy 341.269658 -274.700008)
			(xy 341.285028 -274.647677) (xy 341.307689 -274.598066) (xy 341.337179 -274.552185) (xy 341.372899 -274.510968)
			(xy 341.41412 -274.475253) (xy 341.460005 -274.445768) (xy 341.509618 -274.423113) (xy 341.561951 -274.407748)
			(xy 341.615937 -274.399988) (xy 341.643208 -274.399502) (xy 341.670613 -274.399945) (xy 341.724858 -274.407806)
			(xy 341.777418 -274.42335) (xy 341.827213 -274.446257) (xy 341.873216 -274.476055) (xy 341.89416 -274.493736)
			(xy 341.901272 -274.499832) (xy 341.91829 -274.506182) (xy 342.003126 -274.506182) (xy 342.020144 -274.499832)
			(xy 342.027256 -274.493736) (xy 342.048203 -274.476063) (xy 342.094218 -274.446294) (xy 342.144014 -274.423406)
			(xy 342.196569 -274.407866) (xy 342.250806 -274.399994) (xy 342.278208 -274.399502) (xy 342.305476 -274.400017)
			(xy 342.359457 -274.407779) (xy 342.411783 -274.423143) (xy 342.461391 -274.445798) (xy 342.50727 -274.475281)
			(xy 342.548487 -274.510993) (xy 342.584202 -274.552207) (xy 342.613689 -274.598084) (xy 342.636347 -274.64769)
			(xy 342.651715 -274.700016) (xy 342.659481 -274.753996) (xy 342.65997 -274.781264) (xy 342.659484 -274.808667)
			(xy 342.651631 -274.862909) (xy 342.636096 -274.915469) (xy 342.613199 -274.965264) (xy 342.583411 -275.011269)
			(xy 342.565736 -275.032216) (xy 342.55964 -275.039328) (xy 342.55329 -275.056346) (xy 342.55329 -275.141182)
			(xy 342.55964 -275.1582) (xy 342.565736 -275.165312) (xy 342.583384 -275.186279) (xy 342.613157 -275.232288)
			(xy 342.636051 -275.282079) (xy 342.651597 -275.33463) (xy 342.659474 -275.388863) (xy 342.65997 -275.416264)
			(xy 342.659484 -275.443667) (xy 342.651631 -275.497909) (xy 342.636096 -275.550469) (xy 342.613199 -275.600264)
			(xy 342.583411 -275.646269) (xy 342.565736 -275.667216) (xy 342.55964 -275.674328) (xy 342.55329 -275.691346)
			(xy 342.55329 -275.776182) (xy 342.55964 -275.7932) (xy 342.565736 -275.800312) (xy 342.583384 -275.821279)
			(xy 342.613157 -275.867288) (xy 342.636051 -275.917079) (xy 342.651597 -275.96963) (xy 342.659474 -276.023863)
			(xy 342.659547 -276.027896) (xy 352.726752 -276.027896) (xy 352.727242 -276.00026) (xy 352.735258 -275.94557)
			(xy 352.751065 -275.892605) (xy 352.774334 -275.842467) (xy 352.804579 -275.796202) (xy 352.82251 -275.775166)
			(xy 352.824542 -275.772626) (xy 352.832427 -275.761765) (xy 352.842744 -275.736996) (xy 352.846263 -275.710397)
			(xy 352.842742 -275.683798) (xy 352.832424 -275.65903) (xy 352.824542 -275.648166) (xy 352.82251 -275.645626)
			(xy 352.804568 -275.624595) (xy 352.774285 -275.578349) (xy 352.751003 -275.528212) (xy 352.73521 -275.475237)
			(xy 352.727237 -275.420536) (xy 352.726752 -275.392896) (xy 352.727242 -275.36526) (xy 352.735258 -275.31057)
			(xy 352.751065 -275.257605) (xy 352.774334 -275.207467) (xy 352.804579 -275.161202) (xy 352.82251 -275.140166)
			(xy 352.824542 -275.137626) (xy 352.832427 -275.126765) (xy 352.842744 -275.101996) (xy 352.846263 -275.075397)
			(xy 352.842742 -275.048798) (xy 352.832424 -275.02403) (xy 352.824542 -275.013166) (xy 352.82251 -275.010626)
			(xy 352.804568 -274.989595) (xy 352.774285 -274.943349) (xy 352.751003 -274.893212) (xy 352.73521 -274.840237)
			(xy 352.727237 -274.785536) (xy 352.726752 -274.757896) (xy 352.727198 -274.730624) (xy 352.734961 -274.676636)
			(xy 352.750328 -274.624302) (xy 352.772987 -274.574688) (xy 352.802477 -274.528804) (xy 352.838196 -274.487583)
			(xy 352.879418 -274.451866) (xy 352.925304 -274.422379) (xy 352.974919 -274.399722) (xy 353.027254 -274.384357)
			(xy 353.081242 -274.376597) (xy 353.108514 -274.376134) (xy 353.13615 -274.376622) (xy 353.19084 -274.38464)
			(xy 353.243805 -274.400447) (xy 353.293943 -274.423716) (xy 353.340207 -274.453962) (xy 353.361244 -274.471892)
			(xy 353.363784 -274.473924) (xy 353.374647 -274.481807) (xy 353.399414 -274.492127) (xy 353.426014 -274.495648)
			(xy 353.452614 -274.492127) (xy 353.477381 -274.481807) (xy 353.488244 -274.473924) (xy 353.490784 -274.471892)
			(xy 353.511808 -274.453942) (xy 353.558057 -274.423662) (xy 353.608196 -274.400381) (xy 353.661172 -274.38459)
			(xy 353.715874 -274.376619) (xy 353.743514 -274.376134) (xy 353.770784 -274.376611) (xy 353.824767 -274.384375)
			(xy 353.877097 -274.399742) (xy 353.926707 -274.422399) (xy 353.972587 -274.451886) (xy 354.013805 -274.487602)
			(xy 354.04952 -274.528821) (xy 354.079005 -274.574702) (xy 354.101662 -274.624313) (xy 354.117027 -274.676643)
			(xy 354.124789 -274.730626) (xy 354.125276 -274.757896) (xy 354.124775 -274.785532) (xy 354.11676 -274.840221)
			(xy 354.100955 -274.893186) (xy 354.077689 -274.943323) (xy 354.047447 -274.989589) (xy 354.029518 -275.010626)
			(xy 354.027486 -275.013166) (xy 354.019606 -275.024031) (xy 354.009286 -275.048798) (xy 354.005764 -275.075397)
			(xy 354.009284 -275.101996) (xy 354.019603 -275.126763) (xy 354.027486 -275.137626) (xy 354.029518 -275.140166)
			(xy 354.047461 -275.161196) (xy 354.077742 -275.207443) (xy 354.101024 -275.25758) (xy 354.116817 -275.310555)
			(xy 354.12479 -275.365256) (xy 354.125276 -275.392896) (xy 354.124775 -275.420532) (xy 354.11676 -275.475221)
			(xy 354.100955 -275.528186) (xy 354.077689 -275.578323) (xy 354.047447 -275.624589) (xy 354.029518 -275.645626)
			(xy 354.027486 -275.648166) (xy 354.019606 -275.659031) (xy 354.009286 -275.683798) (xy 354.005764 -275.710397)
			(xy 354.009284 -275.736996) (xy 354.019603 -275.761763) (xy 354.027486 -275.772626) (xy 354.029518 -275.775166)
			(xy 354.047461 -275.796196) (xy 354.077742 -275.842443) (xy 354.101024 -275.89258) (xy 354.116817 -275.945555)
			(xy 354.12479 -276.000256) (xy 354.125276 -276.027896) (xy 354.124944 -276.046184) (xy 356.660196 -276.046184)
			(xy 356.660695 -276.018781) (xy 356.668542 -275.964539) (xy 356.684073 -275.911979) (xy 356.706968 -275.862184)
			(xy 356.736755 -275.816178) (xy 356.75443 -275.795232) (xy 356.760526 -275.78812) (xy 356.766876 -275.771102)
			(xy 356.766876 -275.686266) (xy 356.760526 -275.669248) (xy 356.75443 -275.662136) (xy 356.736752 -275.641193)
			(xy 356.706985 -275.595177) (xy 356.684097 -275.54538) (xy 356.668558 -275.492823) (xy 356.660688 -275.438586)
			(xy 356.660196 -275.411184) (xy 356.660709 -275.383916) (xy 356.668472 -275.329936) (xy 356.683837 -275.277609)
			(xy 356.706492 -275.228002) (xy 356.735976 -275.182123) (xy 356.771688 -275.140907) (xy 356.812902 -275.105192)
			(xy 356.858779 -275.075705) (xy 356.908385 -275.053047) (xy 356.96071 -275.037678) (xy 357.01469 -275.029911)
			(xy 357.041958 -275.029422) (xy 357.069361 -275.029914) (xy 357.123603 -275.037766) (xy 357.176162 -275.053299)
			(xy 357.225957 -275.076195) (xy 357.271963 -275.105981) (xy 357.29291 -275.123656) (xy 357.300022 -275.129752)
			(xy 357.31704 -275.136102) (xy 357.401876 -275.136102) (xy 357.418894 -275.129752) (xy 357.426006 -275.123656)
			(xy 357.446974 -275.106009) (xy 357.492983 -275.076236) (xy 357.542774 -275.053342) (xy 357.595325 -275.037796)
			(xy 357.649557 -275.029918) (xy 357.676958 -275.029422) (xy 357.704361 -275.029914) (xy 357.758603 -275.037766)
			(xy 357.811162 -275.053299) (xy 357.860957 -275.076195) (xy 357.906963 -275.105981) (xy 357.92791 -275.123656)
			(xy 357.935022 -275.129752) (xy 357.95204 -275.136102) (xy 358.036876 -275.136102) (xy 358.053894 -275.129752)
			(xy 358.061006 -275.123656) (xy 358.081974 -275.106009) (xy 358.127983 -275.076236) (xy 358.177774 -275.053342)
			(xy 358.230325 -275.037796) (xy 358.284557 -275.029918) (xy 358.311958 -275.029422) (xy 358.339361 -275.029914)
			(xy 358.393603 -275.037766) (xy 358.446162 -275.053299) (xy 358.495957 -275.076195) (xy 358.541963 -275.105981)
			(xy 358.56291 -275.123656) (xy 358.570022 -275.129752) (xy 358.58704 -275.136102) (xy 358.671876 -275.136102)
			(xy 358.688894 -275.129752) (xy 358.696006 -275.123656) (xy 358.716974 -275.106009) (xy 358.762983 -275.076236)
			(xy 358.812774 -275.053342) (xy 358.865325 -275.037796) (xy 358.919557 -275.029918) (xy 358.946958 -275.029422)
			(xy 358.974361 -275.029914) (xy 359.028603 -275.037766) (xy 359.081162 -275.053299) (xy 359.130957 -275.076195)
			(xy 359.176963 -275.105981) (xy 359.19791 -275.123656) (xy 359.205022 -275.129752) (xy 359.22204 -275.136102)
			(xy 359.306876 -275.136102) (xy 359.323894 -275.129752) (xy 359.331006 -275.123656) (xy 359.351974 -275.106009)
			(xy 359.397983 -275.076236) (xy 359.447774 -275.053342) (xy 359.500325 -275.037796) (xy 359.554557 -275.029918)
			(xy 359.581958 -275.029422) (xy 359.609227 -275.02994) (xy 359.663211 -275.037696) (xy 359.715542 -275.053057)
			(xy 359.765154 -275.075708) (xy 359.811037 -275.10519) (xy 359.852257 -275.140902) (xy 359.887975 -275.182116)
			(xy 359.917464 -275.227995) (xy 359.940123 -275.277604) (xy 359.955491 -275.329932) (xy 359.963255 -275.383915)
			(xy 359.96372 -275.411184) (xy 359.963257 -275.438589) (xy 359.955401 -275.492832) (xy 359.939861 -275.545392)
			(xy 359.916958 -275.595187) (xy 359.887165 -275.641191) (xy 359.869486 -275.662136) (xy 359.86339 -275.669248)
			(xy 359.85704 -275.686266) (xy 359.85704 -275.771102) (xy 359.86339 -275.78812) (xy 359.869486 -275.795232)
			(xy 359.887151 -275.816185) (xy 359.91692 -275.862199) (xy 359.93981 -275.911993) (xy 359.955352 -275.964547)
			(xy 359.963226 -276.018782) (xy 359.96372 -276.046184) (xy 359.963284 -276.073457) (xy 359.955522 -276.127447)
			(xy 359.940156 -276.179782) (xy 359.917497 -276.229398) (xy 359.888007 -276.275284) (xy 359.852287 -276.316505)
			(xy 359.811063 -276.352223) (xy 359.765175 -276.38171) (xy 359.715558 -276.404365) (xy 359.663221 -276.419728)
			(xy 359.609231 -276.427485) (xy 359.581958 -276.427946) (xy 359.554555 -276.427452) (xy 359.500313 -276.419602)
			(xy 359.447754 -276.404069) (xy 359.397958 -276.381174) (xy 359.351953 -276.351387) (xy 359.331006 -276.333712)
			(xy 359.323894 -276.327616) (xy 359.306876 -276.321266) (xy 359.22204 -276.321266) (xy 359.205022 -276.327616)
			(xy 359.19791 -276.333712) (xy 359.176945 -276.351362) (xy 359.130934 -276.381132) (xy 359.081142 -276.404025)
			(xy 359.028591 -276.41957) (xy 358.974359 -276.427449) (xy 358.946958 -276.427946) (xy 358.919555 -276.427452)
			(xy 358.865313 -276.419602) (xy 358.812754 -276.404069) (xy 358.762958 -276.381174) (xy 358.716953 -276.351387)
			(xy 358.696006 -276.333712) (xy 358.688894 -276.327616) (xy 358.671876 -276.321266) (xy 358.58704 -276.321266)
			(xy 358.570022 -276.327616) (xy 358.56291 -276.333712) (xy 358.541945 -276.351362) (xy 358.495934 -276.381132)
			(xy 358.446142 -276.404025) (xy 358.393591 -276.41957) (xy 358.339359 -276.427449) (xy 358.311958 -276.427946)
			(xy 358.284555 -276.427452) (xy 358.230313 -276.419602) (xy 358.177754 -276.404069) (xy 358.127958 -276.381174)
			(xy 358.081953 -276.351387) (xy 358.061006 -276.333712) (xy 358.053894 -276.327616) (xy 358.036876 -276.321266)
			(xy 357.95204 -276.321266) (xy 357.935022 -276.327616) (xy 357.92791 -276.333712) (xy 357.906945 -276.351362)
			(xy 357.860934 -276.381132) (xy 357.811142 -276.404025) (xy 357.758591 -276.41957) (xy 357.704359 -276.427449)
			(xy 357.676958 -276.427946) (xy 357.649555 -276.427452) (xy 357.595313 -276.419602) (xy 357.542754 -276.404069)
			(xy 357.492958 -276.381174) (xy 357.446953 -276.351387) (xy 357.426006 -276.333712) (xy 357.418894 -276.327616)
			(xy 357.401876 -276.321266) (xy 357.31704 -276.321266) (xy 357.300022 -276.327616) (xy 357.29291 -276.333712)
			(xy 357.271945 -276.351362) (xy 357.225934 -276.381132) (xy 357.176142 -276.404025) (xy 357.123591 -276.41957)
			(xy 357.069359 -276.427449) (xy 357.041958 -276.427946) (xy 357.014687 -276.427515) (xy 356.9607 -276.419747)
			(xy 356.908369 -276.404375) (xy 356.858758 -276.381713) (xy 356.812876 -276.352221) (xy 356.771659 -276.3165)
			(xy 356.735944 -276.275277) (xy 356.706459 -276.229391) (xy 356.683804 -276.179777) (xy 356.668441 -276.127443)
			(xy 356.660681 -276.073455) (xy 356.660196 -276.046184) (xy 354.124944 -276.046184) (xy 354.124775 -276.055532)
			(xy 354.11676 -276.110221) (xy 354.100955 -276.163186) (xy 354.077689 -276.213323) (xy 354.047447 -276.259589)
			(xy 354.029518 -276.280626) (xy 354.027486 -276.283166) (xy 354.019606 -276.294031) (xy 354.009286 -276.318798)
			(xy 354.005764 -276.345397) (xy 354.009284 -276.371996) (xy 354.019603 -276.396763) (xy 354.027486 -276.407626)
			(xy 354.029518 -276.410166) (xy 354.047461 -276.431196) (xy 354.077742 -276.477443) (xy 354.101024 -276.52758)
			(xy 354.116817 -276.580555) (xy 354.12479 -276.635256) (xy 354.125276 -276.662896) (xy 354.12479 -276.690165)
			(xy 354.117028 -276.744149) (xy 354.101663 -276.796479) (xy 354.079006 -276.846089) (xy 354.04952 -276.89197)
			(xy 354.013805 -276.933187) (xy 353.972588 -276.968902) (xy 353.926707 -276.998388) (xy 353.877097 -277.021045)
			(xy 353.824767 -277.03641) (xy 353.770783 -277.044172) (xy 353.716245 -277.044172) (xy 353.662261 -277.03641)
			(xy 353.609931 -277.021045) (xy 353.560321 -276.998388) (xy 353.51444 -276.968902) (xy 353.473223 -276.933187)
			(xy 353.437508 -276.89197) (xy 353.408022 -276.846089) (xy 353.385365 -276.796479) (xy 353.37 -276.744149)
			(xy 353.362238 -276.690165) (xy 353.361752 -276.662896) (xy 353.362176 -276.63667) (xy 353.369358 -276.584713)
			(xy 353.383584 -276.534227) (xy 353.404589 -276.486165) (xy 353.431976 -276.441431) (xy 353.465229 -276.400868)
			(xy 353.48418 -276.382734) (xy 353.491552 -276.375207) (xy 353.499976 -276.35592) (xy 353.499975 -276.334874)
			(xy 353.491548 -276.315589) (xy 353.48418 -276.308058) (xy 353.463352 -276.28723) (xy 353.455823 -276.279858)
			(xy 353.436538 -276.271427) (xy 353.41549 -276.271427) (xy 353.396205 -276.279858) (xy 353.388676 -276.28723)
			(xy 353.370532 -276.30617) (xy 353.32997 -276.339422) (xy 353.285238 -276.366808) (xy 353.237178 -276.387813)
			(xy 353.186694 -276.40204) (xy 353.134739 -276.409222) (xy 353.108514 -276.409658) (xy 353.081243 -276.409185)
			(xy 353.027256 -276.401425) (xy 352.974924 -276.38606) (xy 352.92531 -276.363404) (xy 352.879426 -276.333918)
			(xy 352.838206 -276.298201) (xy 352.802488 -276.256982) (xy 352.773001 -276.211099) (xy 352.750343 -276.161486)
			(xy 352.734977 -276.109153) (xy 352.727215 -276.055167) (xy 352.726752 -276.027896) (xy 342.659547 -276.027896)
			(xy 342.65997 -276.051264) (xy 342.659484 -276.078667) (xy 342.651631 -276.132909) (xy 342.636096 -276.185469)
			(xy 342.613199 -276.235264) (xy 342.583411 -276.281269) (xy 342.565736 -276.302216) (xy 342.55964 -276.309328)
			(xy 342.55329 -276.326346) (xy 342.55329 -276.411182) (xy 342.55964 -276.4282) (xy 342.565736 -276.435312)
			(xy 342.581938 -276.454449) (xy 342.609715 -276.496194) (xy 342.631788 -276.541216) (xy 342.640158 -276.564852)
			(xy 342.643714 -276.575774) (xy 342.659716 -276.592284) (xy 342.676988 -276.598888) (xy 342.678258 -276.599142)
			(xy 342.75903 -276.627082) (xy 342.77173 -276.624796) (xy 342.78316 -276.623018) (xy 342.792812 -276.616668)
			(xy 342.816556 -276.601225) (xy 342.867669 -276.576823) (xy 342.921833 -276.560258) (xy 342.977852 -276.551896)
			(xy 343.006172 -276.55139) (xy 343.033439 -276.55195) (xy 343.087417 -276.559707) (xy 343.139742 -276.575066)
			(xy 343.189349 -276.597716) (xy 343.235228 -276.627194) (xy 343.276445 -276.662902) (xy 343.31216 -276.704111)
			(xy 343.341648 -276.749984) (xy 343.364307 -276.799587) (xy 343.379677 -276.851909) (xy 343.387444 -276.905886)
			(xy 343.387934 -276.933152) (xy 343.387468 -276.959497) (xy 343.380222 -277.011686) (xy 343.365874 -277.062384)
			(xy 343.344696 -277.11063) (xy 343.31709 -277.155509) (xy 343.28358 -277.19617) (xy 343.26449 -277.21433)
			(xy 343.257072 -277.221837) (xy 343.248557 -277.241128) (xy 343.24798 -277.251668) (xy 343.24798 -277.325836)
			(xy 343.248536 -277.336382) (xy 343.257053 -277.355678) (xy 343.26449 -277.363174) (xy 343.283607 -277.381309)
			(xy 343.317126 -277.42197) (xy 343.344736 -277.466852) (xy 343.365915 -277.515104) (xy 343.380258 -277.565809)
			(xy 343.387495 -277.618004) (xy 343.387765 -277.634192) (xy 352.284792 -277.634192) (xy 352.285212 -277.607846)
			(xy 352.292466 -277.555654) (xy 352.306823 -277.504955) (xy 352.328009 -277.456709) (xy 352.355623 -277.411831)
			(xy 352.389142 -277.371173) (xy 352.408236 -277.353014) (xy 352.41566 -277.345428) (xy 352.424197 -277.326021)
			(xy 352.424746 -277.315422) (xy 352.424746 -277.241508) (xy 352.42431 -277.230879) (xy 352.415778 -277.211416)
			(xy 352.408236 -277.203916) (xy 352.389186 -277.185782) (xy 352.355728 -277.145202) (xy 352.328166 -277.100407)
			(xy 352.307026 -277.052248) (xy 352.292708 -277.00164) (xy 352.285484 -276.949543) (xy 352.285046 -276.923246)
			(xy 352.285046 -276.922992) (xy 352.285641 -276.893102) (xy 352.295003 -276.834057) (xy 352.313435 -276.777188)
			(xy 352.326448 -276.750272) (xy 352.32848 -276.745446) (xy 352.33956 -276.718445) (xy 352.368615 -276.667832)
			(xy 352.405028 -276.622225) (xy 352.447952 -276.582686) (xy 352.49639 -276.550134) (xy 352.549214 -276.525326)
			(xy 352.605196 -276.508839) (xy 352.634042 -276.5044) (xy 352.646682 -276.502826) (xy 352.672104 -276.501175)
			(xy 352.684842 -276.501098) (xy 352.712111 -276.501585) (xy 352.766092 -276.509352) (xy 352.818419 -276.52472)
			(xy 352.868027 -276.547378) (xy 352.913906 -276.576865) (xy 352.955122 -276.61258) (xy 352.990836 -276.653796)
			(xy 353.020323 -276.699675) (xy 353.04298 -276.749283) (xy 353.058349 -276.80161) (xy 353.066115 -276.855591)
			(xy 353.066604 -276.88286) (xy 353.06599 -276.913458) (xy 353.05625 -276.973874) (xy 353.037012 -277.031968)
			(xy 353.023424 -277.05939) (xy 353.021138 -277.063962) (xy 353.010116 -277.090321) (xy 352.981365 -277.139691)
			(xy 352.945556 -277.184208) (xy 352.924872 -277.203916) (xy 352.917435 -277.211492) (xy 352.908905 -277.230906)
			(xy 352.908362 -277.241508) (xy 352.908362 -277.315422) (xy 352.908931 -277.325967) (xy 352.917439 -277.345262)
			(xy 352.924872 -277.35276) (xy 352.944135 -277.371033) (xy 352.977874 -277.412031) (xy 353.005609 -277.457307)
			(xy 353.026804 -277.505989) (xy 353.040934 -277.556722) (xy 353.207572 -277.556722) (xy 353.211645 -277.501063)
			(xy 353.22378 -277.44659) (xy 353.243716 -277.394464) (xy 353.27103 -277.345796) (xy 353.305138 -277.301624)
			(xy 353.345315 -277.262889) (xy 353.390703 -277.230417) (xy 353.440335 -277.204899) (xy 353.493155 -277.18688)
			(xy 353.548034 -277.176743) (xy 353.603805 -277.174705) (xy 353.659279 -277.180808) (xy 353.713272 -277.194924)
			(xy 353.764635 -277.216751) (xy 353.812273 -277.245824) (xy 353.855169 -277.281523) (xy 353.892411 -277.323087)
			(xy 353.923205 -277.369631) (xy 353.946893 -277.420162) (xy 353.962971 -277.473604) (xy 353.971097 -277.528818)
			(xy 353.971606 -277.556722) (xy 353.971097 -277.584626) (xy 353.962971 -277.63984) (xy 353.961614 -277.644352)
			(xy 359.283508 -277.644352) (xy 359.283963 -277.618007) (xy 359.29121 -277.565817) (xy 359.305559 -277.515118)
			(xy 359.326739 -277.466871) (xy 359.354347 -277.421993) (xy 359.38786 -277.381333) (xy 359.406952 -277.363174)
			(xy 359.41436 -277.355657) (xy 359.422882 -277.336374) (xy 359.423462 -277.325836) (xy 359.423462 -277.251668)
			(xy 359.422921 -277.241119) (xy 359.414395 -277.221823) (xy 359.406952 -277.21433) (xy 359.387844 -277.196185)
			(xy 359.354324 -277.155527) (xy 359.326711 -277.110648) (xy 359.305531 -277.062398) (xy 359.291185 -277.011694)
			(xy 359.283947 -276.959499) (xy 359.283508 -276.933152) (xy 359.283994 -276.905883) (xy 359.291756 -276.851899)
			(xy 359.307121 -276.799569) (xy 359.329778 -276.749959) (xy 359.359264 -276.704078) (xy 359.394979 -276.662861)
			(xy 359.436196 -276.627146) (xy 359.482077 -276.59766) (xy 359.531687 -276.575003) (xy 359.584017 -276.559638)
			(xy 359.638001 -276.551876) (xy 359.692539 -276.551876) (xy 359.746523 -276.559638) (xy 359.798853 -276.575003)
			(xy 359.848463 -276.59766) (xy 359.894344 -276.627146) (xy 359.935561 -276.662861) (xy 359.971276 -276.704078)
			(xy 360.000762 -276.749959) (xy 360.023419 -276.799569) (xy 360.038784 -276.851899) (xy 360.046546 -276.905883)
			(xy 360.047032 -276.933152) (xy 360.046567 -276.959497) (xy 360.039321 -277.011686) (xy 360.024972 -277.062384)
			(xy 360.003795 -277.11063) (xy 359.976189 -277.155509) (xy 359.942678 -277.19617) (xy 359.923588 -277.21433)
			(xy 359.916169 -277.221837) (xy 359.907655 -277.241128) (xy 359.907078 -277.251668) (xy 359.907078 -277.325836)
			(xy 359.907635 -277.336382) (xy 359.916151 -277.355678) (xy 359.923588 -277.363174) (xy 359.942705 -277.381309)
			(xy 359.976224 -277.42197) (xy 360.003834 -277.466852) (xy 360.025012 -277.515104) (xy 360.039356 -277.565809)
			(xy 360.046593 -277.618004) (xy 360.047032 -277.644352) (xy 360.046546 -277.671621) (xy 360.038784 -277.725605)
			(xy 360.023419 -277.777935) (xy 360.000762 -277.827545) (xy 359.971276 -277.873426) (xy 359.935561 -277.914643)
			(xy 359.894344 -277.950358) (xy 359.848463 -277.979844) (xy 359.798853 -278.002501) (xy 359.746523 -278.017866)
			(xy 359.692539 -278.025628) (xy 359.638001 -278.025628) (xy 359.584017 -278.017866) (xy 359.531687 -278.002501)
			(xy 359.482077 -277.979844) (xy 359.436196 -277.950358) (xy 359.394979 -277.914643) (xy 359.359264 -277.873426)
			(xy 359.329778 -277.827545) (xy 359.307121 -277.777935) (xy 359.291756 -277.725605) (xy 359.283994 -277.671621)
			(xy 359.283508 -277.644352) (xy 353.961614 -277.644352) (xy 353.946893 -277.693282) (xy 353.923205 -277.743813)
			(xy 353.892411 -277.790357) (xy 353.855169 -277.831921) (xy 353.812273 -277.86762) (xy 353.764635 -277.896693)
			(xy 353.713272 -277.91852) (xy 353.659279 -277.932636) (xy 353.603805 -277.938739) (xy 353.548034 -277.936701)
			(xy 353.493155 -277.926564) (xy 353.440335 -277.908545) (xy 353.390703 -277.883027) (xy 353.345315 -277.850555)
			(xy 353.305138 -277.81182) (xy 353.27103 -277.767648) (xy 353.243716 -277.71898) (xy 353.22378 -277.666854)
			(xy 353.211645 -277.612381) (xy 353.207572 -277.556722) (xy 353.040934 -277.556722) (xy 353.04105 -277.557138)
			(xy 353.045014 -277.583392) (xy 353.046583 -277.596033) (xy 353.048237 -277.621454) (xy 353.048316 -277.634192)
			(xy 353.04783 -277.661461) (xy 353.040068 -277.715445) (xy 353.024703 -277.767775) (xy 353.002046 -277.817385)
			(xy 352.97256 -277.863266) (xy 352.936845 -277.904483) (xy 352.895628 -277.940198) (xy 352.849747 -277.969684)
			(xy 352.800137 -277.992341) (xy 352.747807 -278.007706) (xy 352.693823 -278.015468) (xy 352.639285 -278.015468)
			(xy 352.585301 -278.007706) (xy 352.532971 -277.992341) (xy 352.483361 -277.969684) (xy 352.43748 -277.940198)
			(xy 352.396263 -277.904483) (xy 352.360548 -277.863266) (xy 352.331062 -277.817385) (xy 352.308405 -277.767775)
			(xy 352.29304 -277.715445) (xy 352.285278 -277.661461) (xy 352.284792 -277.634192) (xy 343.387765 -277.634192)
			(xy 343.387934 -277.644352) (xy 343.387454 -277.671623) (xy 343.379697 -277.725611) (xy 343.364336 -277.777945)
			(xy 343.341682 -277.82756) (xy 343.312197 -277.873445) (xy 343.276481 -277.914666) (xy 343.235261 -277.950385)
			(xy 343.189377 -277.979872) (xy 343.139764 -278.002529) (xy 343.08743 -278.017893) (xy 343.033443 -278.025652)
			(xy 343.006172 -278.026114) (xy 342.979673 -278.02568) (xy 342.927184 -278.018359) (xy 342.876212 -278.003847)
			(xy 342.827738 -277.982424) (xy 342.782693 -277.954501) (xy 342.741944 -277.920615) (xy 342.706275 -277.881418)
			(xy 342.67637 -277.837664) (xy 342.652805 -277.790194) (xy 342.636034 -277.73992) (xy 342.63076 -277.713948)
			(xy 342.628474 -277.701502) (xy 342.61298 -277.681944) (xy 342.525604 -277.643336) (xy 342.515114 -277.639363)
			(xy 342.492715 -277.639889) (xy 342.482424 -277.644352) (xy 342.478106 -277.646384) (xy 342.476328 -277.647654)
			(xy 342.453832 -277.660788) (xy 342.406031 -277.68149) (xy 342.355862 -277.695509) (xy 342.304254 -277.702585)
			(xy 342.278208 -277.703026) (xy 342.250936 -277.702591) (xy 342.196946 -277.694829) (xy 342.14461 -277.679462)
			(xy 342.094995 -277.656803) (xy 342.049109 -277.627312) (xy 342.007888 -277.591592) (xy 341.972171 -277.550368)
			(xy 341.942684 -277.504481) (xy 341.920028 -277.454863) (xy 341.904665 -277.402527) (xy 341.896907 -277.348536)
			(xy 341.896446 -277.321264) (xy 341.896945 -277.293861) (xy 341.904794 -277.23962) (xy 341.920326 -277.18706)
			(xy 341.94322 -277.137265) (xy 341.973005 -277.091259) (xy 341.99068 -277.070312) (xy 341.996776 -277.0632)
			(xy 342.003126 -277.046182) (xy 342.003126 -276.961346) (xy 341.996776 -276.944328) (xy 341.99068 -276.937216)
			(xy 341.973032 -276.916249) (xy 341.943262 -276.870239) (xy 341.920369 -276.820448) (xy 341.904823 -276.767897)
			(xy 341.896943 -276.713664) (xy 341.896446 -276.686264) (xy 341.896978 -276.656728) (xy 341.906073 -276.598359)
			(xy 341.924041 -276.542085) (xy 341.950454 -276.489246) (xy 341.984683 -276.441101) (xy 342.004904 -276.419564)
			(xy 342.012016 -276.412452) (xy 342.019382 -276.394164) (xy 342.019382 -276.36089) (xy 342.018988 -276.350866)
			(xy 342.011312 -276.332345) (xy 341.997131 -276.318173) (xy 341.978606 -276.310506) (xy 341.968582 -276.31009)
			(xy 341.935308 -276.31009) (xy 341.91702 -276.317456) (xy 341.909908 -276.324568) (xy 341.88841 -276.344835)
			(xy 341.840269 -276.379085) (xy 341.787422 -276.405501) (xy 341.731133 -276.423449) (xy 341.672749 -276.432502)
			(xy 341.643208 -276.433026) (xy 341.615936 -276.432591) (xy 341.561946 -276.424829) (xy 341.50961 -276.409462)
			(xy 341.459995 -276.386803) (xy 341.414109 -276.357312) (xy 341.372888 -276.321592) (xy 341.337171 -276.280368)
			(xy 341.307684 -276.234481) (xy 341.285028 -276.184863) (xy 341.269665 -276.132527) (xy 341.261907 -276.078536)
			(xy 341.261446 -276.051264) (xy 337.814453 -276.051264) (xy 337.819635 -276.067866) (xy 337.837151 -276.093185)
			(xy 337.848956 -276.10308) (xy 337.871423 -276.121273) (xy 337.911097 -276.16332) (xy 337.94398 -276.210867)
			(xy 337.96932 -276.262828) (xy 337.986538 -276.318014) (xy 337.995241 -276.375165) (xy 337.995768 -276.40407)
			(xy 337.995271 -276.43134) (xy 337.987513 -276.485325) (xy 337.972151 -276.537657) (xy 337.949497 -276.58727)
			(xy 337.920013 -276.633153) (xy 337.884299 -276.674374) (xy 337.843082 -276.710091) (xy 337.797201 -276.73958)
			(xy 337.747591 -276.762238) (xy 337.695261 -276.777605) (xy 337.641276 -276.785368) (xy 337.614006 -276.785832)
			(xy 337.585104 -276.785297) (xy 337.52796 -276.776577) (xy 337.472781 -276.759349) (xy 337.420827 -276.734007)
			(xy 337.373283 -276.701129) (xy 337.331232 -276.661466) (xy 337.313016 -276.63902) (xy 337.303119 -276.627215)
			(xy 337.277795 -276.609696) (xy 337.248402 -276.60052) (xy 337.21761 -276.60052) (xy 337.188217 -276.609696)
			(xy 337.162893 -276.627215) (xy 337.152996 -276.63902) (xy 337.143008 -276.651484) (xy 337.121262 -276.674883)
			(xy 337.109562 -276.685756) (xy 337.099908 -276.695088) (xy 337.085537 -276.717762) (xy 337.077574 -276.743399)
			(xy 337.076569 -276.770224) (xy 337.082592 -276.796385) (xy 337.095226 -276.820071) (xy 337.113597 -276.839644)
			(xy 337.124802 -276.847046) (xy 337.14809 -276.862091) (xy 337.190475 -276.897829) (xy 337.227251 -276.939316)
			(xy 337.257644 -276.985684) (xy 337.281018 -277.035957) (xy 337.29688 -277.08908) (xy 337.304898 -277.143938)
			(xy 337.305396 -277.171658) (xy 337.30491 -277.198927) (xy 337.297148 -277.252911) (xy 337.281783 -277.305241)
			(xy 337.259126 -277.354851) (xy 337.22964 -277.400732) (xy 337.193925 -277.441949) (xy 337.152708 -277.477664)
			(xy 337.106827 -277.50715) (xy 337.057217 -277.529807) (xy 337.004887 -277.545172) (xy 336.950903 -277.552934)
			(xy 336.896365 -277.552934) (xy 336.842381 -277.545172) (xy 336.790051 -277.529807) (xy 336.740441 -277.50715)
			(xy 336.69456 -277.477664) (xy 336.653343 -277.441949) (xy 336.617628 -277.400732) (xy 336.588142 -277.354851)
			(xy 336.565485 -277.305241) (xy 336.55012 -277.252911) (xy 336.542358 -277.198927) (xy 336.541872 -277.171658)
			(xy 336.542362 -277.145241) (xy 336.549645 -277.092912) (xy 336.564079 -277.042089) (xy 336.585389 -276.993743)
			(xy 336.613166 -276.948801) (xy 336.646879 -276.908122) (xy 336.666078 -276.889972) (xy 336.675694 -276.880606)
			(xy 336.69006 -276.857939) (xy 336.698022 -276.832312) (xy 336.69903 -276.805495) (xy 336.693015 -276.779342)
			(xy 336.680393 -276.75566) (xy 336.662036 -276.736086) (xy 336.650838 -276.728682) (xy 336.629314 -276.714833)
			(xy 336.589822 -276.682274) (xy 336.555038 -276.644727) (xy 336.525586 -276.602867) (xy 336.513424 -276.580346)
			(xy 336.506879 -276.56856) (xy 336.488622 -276.548733) (xy 336.465814 -276.534374) (xy 336.440042 -276.526484)
			(xy 336.413104 -276.525612) (xy 336.386876 -276.53182) (xy 336.363187 -276.544674) (xy 336.35315 -276.553676)
			(xy 336.334355 -276.570996) (xy 336.292934 -276.60094) (xy 336.2706 -276.613366) (xy 336.257715 -276.620892)
			(xy 336.236665 -276.642021) (xy 336.222613 -276.668328) (xy 336.216756 -276.697573) (xy 336.219594 -276.727263)
			(xy 336.230885 -276.754869) (xy 336.249666 -276.778038) (xy 336.26171 -276.786848) (xy 336.283455 -276.80216)
			(xy 336.322885 -276.837849) (xy 336.356981 -276.878664) (xy 336.385084 -276.923815) (xy 336.40665 -276.972428)
			(xy 336.421262 -277.023564) (xy 336.428638 -277.076233) (xy 336.429096 -277.102824) (xy 336.428596 -277.131728)
			(xy 336.419871 -277.188874) (xy 336.402637 -277.244054) (xy 336.377288 -277.296008) (xy 336.344404 -277.343551)
			(xy 336.304733 -277.385599) (xy 336.282284 -277.403814) (xy 336.270458 -277.413687) (xy 336.252945 -277.439018)
			(xy 336.243775 -277.468417) (xy 336.24378 -277.499212) (xy 336.252958 -277.528608) (xy 336.270478 -277.553935)
			(xy 336.282284 -277.563834) (xy 336.304735 -277.582046) (xy 336.344408 -277.62409) (xy 336.377292 -277.671634)
			(xy 336.402635 -277.72359) (xy 336.419857 -277.778772) (xy 336.428566 -277.83592) (xy 336.429096 -277.864824)
			(xy 336.42861 -277.892093) (xy 336.420848 -277.946077) (xy 336.405483 -277.998407) (xy 336.382826 -278.048017)
			(xy 336.35334 -278.093898) (xy 336.317625 -278.135115) (xy 336.276408 -278.17083) (xy 336.230527 -278.200316)
			(xy 336.180917 -278.222973) (xy 336.128587 -278.238338) (xy 336.074603 -278.2461) (xy 336.020065 -278.2461)
			(xy 335.966081 -278.238338) (xy 335.913751 -278.222973) (xy 335.864141 -278.200316) (xy 335.81826 -278.17083)
			(xy 335.777043 -278.135115) (xy 335.741328 -278.093898) (xy 335.711842 -278.048017) (xy 335.689185 -277.998407)
			(xy 335.67382 -277.946077) (xy 335.666058 -277.892093) (xy 335.665572 -277.864824) (xy 332.633828 -277.864824)
			(xy 332.633828 -280.617168) (xy 337.733386 -280.617168) (xy 337.733872 -280.589899) (xy 337.741634 -280.535915)
			(xy 337.756999 -280.483585) (xy 337.779656 -280.433975) (xy 337.809142 -280.388094) (xy 337.844857 -280.346877)
			(xy 337.886074 -280.311162) (xy 337.931955 -280.281676) (xy 337.981565 -280.259019) (xy 338.033895 -280.243654)
			(xy 338.087879 -280.235892) (xy 338.142417 -280.235892) (xy 338.196401 -280.243654) (xy 338.248731 -280.259019)
			(xy 338.298341 -280.281676) (xy 338.344222 -280.311162) (xy 338.385439 -280.346877) (xy 338.421154 -280.388094)
			(xy 338.45064 -280.433975) (xy 338.473297 -280.483585) (xy 338.488662 -280.535915) (xy 338.496424 -280.589899)
			(xy 338.49691 -280.617168) (xy 338.49683 -280.62754) (xy 338.495685 -280.648252) (xy 338.494624 -280.65857)
			(xy 338.49437 -280.66111) (xy 338.49437 -280.665428) (xy 338.494748 -280.673316) (xy 338.49965 -280.688317)
			(xy 338.504022 -280.694892) (xy 338.549234 -280.757884) (xy 338.564982 -280.768298) (xy 338.574634 -280.77033)
			(xy 338.586064 -280.77287) (xy 338.591906 -280.77414) (xy 338.604606 -280.77414) (xy 338.611193 -280.773971)
			(xy 338.623935 -280.77063) (xy 338.629752 -280.767536) (xy 338.697062 -280.729436) (xy 338.709254 -280.713942)
			(xy 338.712048 -280.70429) (xy 338.720077 -280.678124) (xy 338.742616 -280.628247) (xy 338.772048 -280.582101)
			(xy 338.807768 -280.540631) (xy 338.849044 -280.504687) (xy 338.89503 -280.475006) (xy 338.944784 -280.452197)
			(xy 338.997285 -280.436728) (xy 339.051458 -280.428915) (xy 339.078824 -280.428446) (xy 339.10589 -280.428947)
			(xy 339.159478 -280.43661) (xy 339.211451 -280.451751) (xy 339.236304 -280.462482) (xy 339.246464 -280.462228)
			(xy 339.251851 -280.461999) (xy 339.262354 -280.459568) (xy 339.267292 -280.457402) (xy 339.34527 -280.420064)
			(xy 339.35924 -280.403808) (xy 339.362288 -280.393394) (xy 339.370998 -280.365413) (xy 339.395899 -280.312363)
			(xy 339.428617 -280.263743) (xy 339.468384 -280.220698) (xy 339.514264 -280.184238) (xy 339.56518 -280.155221)
			(xy 339.619932 -280.13433) (xy 339.677236 -280.122055) (xy 339.706458 -280.119836) (xy 339.718142 -280.119328)
			(xy 339.738208 -280.108152) (xy 339.789008 -280.036778) (xy 339.793072 -280.02992) (xy 339.79866 -280.01849)
			(xy 339.800692 -279.999694) (xy 339.797898 -279.99055) (xy 339.791218 -279.965165) (xy 339.784076 -279.913164)
			(xy 339.783674 -279.886918) (xy 339.78416 -279.859649) (xy 339.791922 -279.805665) (xy 339.807287 -279.753335)
			(xy 339.829944 -279.703725) (xy 339.85943 -279.657844) (xy 339.895145 -279.616627) (xy 339.936362 -279.580912)
			(xy 339.982243 -279.551426) (xy 340.031853 -279.528769) (xy 340.084183 -279.513404) (xy 340.138167 -279.505642)
			(xy 340.192705 -279.505642) (xy 340.246689 -279.513404) (xy 340.299019 -279.528769) (xy 340.348629 -279.551426)
			(xy 340.39451 -279.580912) (xy 340.435727 -279.616627) (xy 340.471442 -279.657844) (xy 340.500928 -279.703725)
			(xy 340.523585 -279.753335) (xy 340.53895 -279.805665) (xy 340.546712 -279.859649) (xy 340.547198 -279.886918)
			(xy 340.546685 -279.915812) (xy 340.537951 -279.972937) (xy 340.520715 -280.028095) (xy 340.49537 -280.080029)
			(xy 340.462494 -280.127555) (xy 340.422837 -280.169588) (xy 340.377303 -280.205172) (xy 340.32693 -280.233493)
			(xy 340.272868 -280.253906) (xy 340.216347 -280.265947) (xy 340.187534 -280.268172) (xy 340.17585 -280.26868)
			(xy 340.155784 -280.279856) (xy 340.104984 -280.35123) (xy 340.10092 -280.358088) (xy 340.095332 -280.369518)
			(xy 340.0933 -280.388314) (xy 340.096094 -280.397458) (xy 340.102775 -280.422842) (xy 340.109917 -280.474844)
			(xy 340.110318 -280.50109) (xy 340.10956 -280.535173) (xy 340.097417 -280.60225) (xy 340.092213 -280.617168)
			(xy 345.893898 -280.617168) (xy 345.894384 -280.589899) (xy 345.902146 -280.535915) (xy 345.917511 -280.483585)
			(xy 345.940168 -280.433975) (xy 345.969654 -280.388094) (xy 346.005369 -280.346877) (xy 346.046586 -280.311162)
			(xy 346.092467 -280.281676) (xy 346.142077 -280.259019) (xy 346.194407 -280.243654) (xy 346.248391 -280.235892)
			(xy 346.302929 -280.235892) (xy 346.356913 -280.243654) (xy 346.409243 -280.259019) (xy 346.458853 -280.281676)
			(xy 346.504734 -280.311162) (xy 346.545951 -280.346877) (xy 346.581666 -280.388094) (xy 346.611152 -280.433975)
			(xy 346.633809 -280.483585) (xy 346.649174 -280.535915) (xy 346.656936 -280.589899) (xy 346.657422 -280.617168)
			(xy 346.657342 -280.62754) (xy 346.656197 -280.648252) (xy 346.655136 -280.65857) (xy 346.654882 -280.66111)
			(xy 346.654882 -280.665428) (xy 346.655258 -280.673316) (xy 346.660161 -280.688317) (xy 346.664534 -280.694892)
			(xy 346.709746 -280.757884) (xy 346.725494 -280.768298) (xy 346.735146 -280.77033) (xy 346.746576 -280.77287)
			(xy 346.752418 -280.77414) (xy 346.765118 -280.77414) (xy 346.771705 -280.773975) (xy 346.784447 -280.770631)
			(xy 346.790264 -280.767536) (xy 346.857574 -280.729436) (xy 346.869766 -280.713942) (xy 346.87256 -280.70429)
			(xy 346.880578 -280.67812) (xy 346.903119 -280.628243) (xy 346.932551 -280.582096) (xy 346.968272 -280.540626)
			(xy 347.00955 -280.504682) (xy 347.055538 -280.475002) (xy 347.105293 -280.452194) (xy 347.157796 -280.436726)
			(xy 347.211969 -280.428914) (xy 347.239336 -280.428446) (xy 347.266402 -280.428943) (xy 347.319991 -280.436607)
			(xy 347.371963 -280.45175) (xy 347.396816 -280.462482) (xy 347.406976 -280.462228) (xy 347.412364 -280.462004)
			(xy 347.422867 -280.459569) (xy 347.427804 -280.457402) (xy 347.505782 -280.420064) (xy 347.519752 -280.403808)
			(xy 347.5228 -280.393394) (xy 347.5315 -280.365409) (xy 347.556402 -280.312359) (xy 347.589121 -280.263739)
			(xy 347.62889 -280.220693) (xy 347.674771 -280.184234) (xy 347.725688 -280.155218) (xy 347.780443 -280.134327)
			(xy 347.837747 -280.122054) (xy 347.86697 -280.119836) (xy 347.878654 -280.119328) (xy 347.89872 -280.108152)
			(xy 347.94952 -280.036778) (xy 347.953584 -280.02992) (xy 347.959172 -280.01849) (xy 347.961204 -279.999694)
			(xy 347.95841 -279.99055) (xy 347.95173 -279.965165) (xy 347.944588 -279.913164) (xy 347.944186 -279.886918)
			(xy 347.944672 -279.859649) (xy 347.952434 -279.805665) (xy 347.967799 -279.753335) (xy 347.990456 -279.703725)
			(xy 348.019942 -279.657844) (xy 348.055657 -279.616627) (xy 348.096874 -279.580912) (xy 348.142755 -279.551426)
			(xy 348.192365 -279.528769) (xy 348.244695 -279.513404) (xy 348.298679 -279.505642) (xy 348.353217 -279.505642)
			(xy 348.407201 -279.513404) (xy 348.459531 -279.528769) (xy 348.509141 -279.551426) (xy 348.555022 -279.580912)
			(xy 348.596239 -279.616627) (xy 348.631954 -279.657844) (xy 348.66144 -279.703725) (xy 348.684097 -279.753335)
			(xy 348.699462 -279.805665) (xy 348.707224 -279.859649) (xy 348.70771 -279.886918) (xy 348.707185 -279.915811)
			(xy 348.698452 -279.972935) (xy 348.681217 -280.028092) (xy 348.655873 -280.080026) (xy 348.622998 -280.127551)
			(xy 348.583343 -280.169585) (xy 348.53781 -280.205168) (xy 348.487439 -280.23349) (xy 348.433378 -280.253904)
			(xy 348.376859 -280.265946) (xy 348.348046 -280.268172) (xy 348.336362 -280.26868) (xy 348.316296 -280.279856)
			(xy 348.265496 -280.35123) (xy 348.261432 -280.358088) (xy 348.255844 -280.369518) (xy 348.253812 -280.388314)
			(xy 348.256606 -280.397458) (xy 348.263285 -280.422843) (xy 348.270429 -280.474844) (xy 348.27083 -280.50109)
			(xy 348.270071 -280.535173) (xy 348.257928 -280.60225) (xy 348.252725 -280.617168) (xy 354.392484 -280.617168)
			(xy 354.39297 -280.589899) (xy 354.400732 -280.535915) (xy 354.416097 -280.483585) (xy 354.438754 -280.433975)
			(xy 354.46824 -280.388094) (xy 354.503955 -280.346877) (xy 354.545172 -280.311162) (xy 354.591053 -280.281676)
			(xy 354.640663 -280.259019) (xy 354.692993 -280.243654) (xy 354.746977 -280.235892) (xy 354.801515 -280.235892)
			(xy 354.855499 -280.243654) (xy 354.907829 -280.259019) (xy 354.957439 -280.281676) (xy 355.00332 -280.311162)
			(xy 355.044537 -280.346877) (xy 355.080252 -280.388094) (xy 355.109738 -280.433975) (xy 355.132395 -280.483585)
			(xy 355.14776 -280.535915) (xy 355.155522 -280.589899) (xy 355.156008 -280.617168) (xy 355.155928 -280.62754)
			(xy 355.154783 -280.648252) (xy 355.153722 -280.65857) (xy 355.153468 -280.66111) (xy 355.153468 -280.665428)
			(xy 355.153847 -280.673316) (xy 355.158749 -280.688317) (xy 355.16312 -280.694892) (xy 355.208332 -280.757884)
			(xy 355.22408 -280.768298) (xy 355.233732 -280.77033) (xy 355.245162 -280.77287) (xy 355.251004 -280.77414)
			(xy 355.263704 -280.77414) (xy 355.270291 -280.77397) (xy 355.283033 -280.77063) (xy 355.28885 -280.767536)
			(xy 355.35616 -280.729436) (xy 355.368352 -280.713942) (xy 355.371146 -280.70429) (xy 355.379177 -280.678125)
			(xy 355.401716 -280.628248) (xy 355.431147 -280.582102) (xy 355.466867 -280.540632) (xy 355.508143 -280.504688)
			(xy 355.554129 -280.475007) (xy 355.603882 -280.452198) (xy 355.656383 -280.436728) (xy 355.710556 -280.428915)
			(xy 355.737922 -280.428446) (xy 355.764988 -280.428948) (xy 355.818576 -280.43661) (xy 355.870549 -280.451751)
			(xy 355.895402 -280.462482) (xy 355.905562 -280.462228) (xy 355.910949 -280.461999) (xy 355.921452 -280.459568)
			(xy 355.92639 -280.457402) (xy 356.004368 -280.420064) (xy 356.018338 -280.403808) (xy 356.021386 -280.393394)
			(xy 356.030098 -280.365413) (xy 356.054998 -280.312364) (xy 356.087716 -280.263744) (xy 356.127483 -280.220698)
			(xy 356.173363 -280.184239) (xy 356.224278 -280.155222) (xy 356.279031 -280.13433) (xy 356.336334 -280.122055)
			(xy 356.365556 -280.119836) (xy 356.37724 -280.119328) (xy 356.397306 -280.108152) (xy 356.448106 -280.036778)
			(xy 356.45217 -280.02992) (xy 356.457758 -280.01849) (xy 356.45979 -279.999694) (xy 356.456996 -279.99055)
			(xy 356.450316 -279.965165) (xy 356.443174 -279.913164) (xy 356.442772 -279.886918) (xy 356.443258 -279.859649)
			(xy 356.45102 -279.805665) (xy 356.466385 -279.753335) (xy 356.489042 -279.703725) (xy 356.518528 -279.657844)
			(xy 356.554243 -279.616627) (xy 356.59546 -279.580912) (xy 356.641341 -279.551426) (xy 356.690951 -279.528769)
			(xy 356.743281 -279.513404) (xy 356.797265 -279.505642) (xy 356.851803 -279.505642) (xy 356.905787 -279.513404)
			(xy 356.958117 -279.528769) (xy 357.007727 -279.551426) (xy 357.053608 -279.580912) (xy 357.094825 -279.616627)
			(xy 357.13054 -279.657844) (xy 357.160026 -279.703725) (xy 357.182683 -279.753335) (xy 357.198048 -279.805665)
			(xy 357.20581 -279.859649) (xy 357.206296 -279.886918) (xy 357.205785 -279.915812) (xy 357.19705 -279.972937)
			(xy 357.179814 -280.028095) (xy 357.15447 -280.08003) (xy 357.121594 -280.127555) (xy 357.081936 -280.169589)
			(xy 357.036402 -280.205172) (xy 356.986029 -280.233493) (xy 356.931966 -280.253907) (xy 356.875445 -280.265947)
			(xy 356.846632 -280.268172) (xy 356.834948 -280.26868) (xy 356.814882 -280.279856) (xy 356.764082 -280.35123)
			(xy 356.760018 -280.358088) (xy 356.75443 -280.369518) (xy 356.752398 -280.388314) (xy 356.755192 -280.397458)
			(xy 356.761873 -280.422842) (xy 356.769015 -280.474844) (xy 356.769416 -280.50109) (xy 356.768658 -280.535173)
			(xy 356.756515 -280.60225) (xy 356.751311 -280.617168) (xy 362.552996 -280.617168) (xy 362.553482 -280.589899)
			(xy 362.561244 -280.535915) (xy 362.576609 -280.483585) (xy 362.599266 -280.433975) (xy 362.628752 -280.388094)
			(xy 362.664467 -280.346877) (xy 362.705684 -280.311162) (xy 362.751565 -280.281676) (xy 362.801175 -280.259019)
			(xy 362.853505 -280.243654) (xy 362.907489 -280.235892) (xy 362.962027 -280.235892) (xy 363.016011 -280.243654)
			(xy 363.068341 -280.259019) (xy 363.117951 -280.281676) (xy 363.163832 -280.311162) (xy 363.205049 -280.346877)
			(xy 363.240764 -280.388094) (xy 363.27025 -280.433975) (xy 363.292907 -280.483585) (xy 363.308272 -280.535915)
			(xy 363.316034 -280.589899) (xy 363.31652 -280.617168) (xy 363.31644 -280.62754) (xy 363.315295 -280.648252)
			(xy 363.314234 -280.65857) (xy 363.31398 -280.66111) (xy 363.31398 -280.665428) (xy 363.314357 -280.673316)
			(xy 363.31926 -280.688317) (xy 363.323632 -280.694892) (xy 363.368844 -280.757884) (xy 363.384592 -280.768298)
			(xy 363.394244 -280.77033) (xy 363.405674 -280.77287) (xy 363.411516 -280.77414) (xy 363.424216 -280.77414)
			(xy 363.430803 -280.773974) (xy 363.443545 -280.770631) (xy 363.449362 -280.767536) (xy 363.516672 -280.729436)
			(xy 363.528864 -280.713942) (xy 363.531658 -280.70429) (xy 363.539678 -280.678121) (xy 363.562218 -280.628244)
			(xy 363.591651 -280.582097) (xy 363.627371 -280.540627) (xy 363.668649 -280.504683) (xy 363.714636 -280.475003)
			(xy 363.764391 -280.452195) (xy 363.816894 -280.436726) (xy 363.871067 -280.428914) (xy 363.898434 -280.428446)
			(xy 363.9255 -280.428944) (xy 363.979089 -280.436608) (xy 364.031061 -280.45175) (xy 364.055914 -280.462482)
			(xy 364.066074 -280.462228) (xy 364.071462 -280.462003) (xy 364.081964 -280.459569) (xy 364.086902 -280.457402)
			(xy 364.16488 -280.420064) (xy 364.17885 -280.403808) (xy 364.181898 -280.393394) (xy 364.1906 -280.36541)
			(xy 364.215501 -280.31236) (xy 364.248221 -280.26374) (xy 364.287989 -280.220694) (xy 364.33387 -280.184235)
			(xy 364.384787 -280.155218) (xy 364.439541 -280.134328) (xy 364.496845 -280.122054) (xy 364.526068 -280.119836)
			(xy 364.537752 -280.119328) (xy 364.557818 -280.108152) (xy 364.608618 -280.036778) (xy 364.612682 -280.02992)
			(xy 364.61827 -280.01849) (xy 364.620302 -279.999694) (xy 364.617508 -279.99055) (xy 364.610828 -279.965165)
			(xy 364.603686 -279.913164) (xy 364.603284 -279.886918) (xy 364.60377 -279.859649) (xy 364.611532 -279.805665)
			(xy 364.626897 -279.753335) (xy 364.649554 -279.703725) (xy 364.67904 -279.657844) (xy 364.714755 -279.616627)
			(xy 364.755972 -279.580912) (xy 364.801853 -279.551426) (xy 364.851463 -279.528769) (xy 364.903793 -279.513404)
			(xy 364.957777 -279.505642) (xy 365.012315 -279.505642) (xy 365.066299 -279.513404) (xy 365.118629 -279.528769)
			(xy 365.168239 -279.551426) (xy 365.21412 -279.580912) (xy 365.255337 -279.616627) (xy 365.291052 -279.657844)
			(xy 365.320538 -279.703725) (xy 365.343195 -279.753335) (xy 365.35856 -279.805665) (xy 365.366322 -279.859649)
			(xy 365.366808 -279.886918) (xy 365.366285 -279.915811) (xy 365.357552 -279.972935) (xy 365.340316 -280.028093)
			(xy 365.314972 -280.080026) (xy 365.282098 -280.127552) (xy 365.242442 -280.169585) (xy 365.196909 -280.205168)
			(xy 365.146538 -280.23349) (xy 365.092476 -280.253905) (xy 365.035957 -280.265946) (xy 365.007144 -280.268172)
			(xy 364.99546 -280.26868) (xy 364.975394 -280.279856) (xy 364.924594 -280.35123) (xy 364.92053 -280.358088)
			(xy 364.914942 -280.369518) (xy 364.91291 -280.388314) (xy 364.915704 -280.397458) (xy 364.922385 -280.422842)
			(xy 364.929527 -280.474844) (xy 364.929928 -280.50109) (xy 364.929169 -280.535173) (xy 364.917026 -280.60225)
			(xy 364.905798 -280.63444) (xy 364.90148 -280.646124) (xy 364.90402 -280.669492) (xy 364.960916 -280.757884)
			(xy 364.981744 -280.770076) (xy 364.993682 -280.770838) (xy 365.022326 -280.773261) (xy 365.078464 -280.785619)
			(xy 365.132116 -280.806252) (xy 365.18207 -280.834692) (xy 365.227197 -280.870298) (xy 365.266478 -280.912265)
			(xy 365.299026 -280.959645) (xy 365.324105 -281.011368) (xy 365.325764 -281.01671) (xy 366.056924 -281.01671)
			(xy 366.060997 -280.961051) (xy 366.073132 -280.906578) (xy 366.093068 -280.854452) (xy 366.120382 -280.805784)
			(xy 366.15449 -280.761612) (xy 366.194667 -280.722877) (xy 366.240055 -280.690405) (xy 366.289687 -280.664887)
			(xy 366.342507 -280.646868) (xy 366.397386 -280.636731) (xy 366.453157 -280.634693) (xy 366.508631 -280.640796)
			(xy 366.562624 -280.654912) (xy 366.613987 -280.676739) (xy 366.640819 -280.693114) (xy 379.638052 -280.693114)
			(xy 379.638589 -280.664341) (xy 379.647262 -280.607451) (xy 379.664397 -280.552515) (xy 379.689605 -280.500783)
			(xy 379.722311 -280.453434) (xy 379.76177 -280.411546) (xy 379.784102 -280.393394) (xy 379.784356 -280.39314)
			(xy 379.79096 -280.387806) (xy 379.799303 -280.380307) (xy 379.809064 -280.36014) (xy 379.809756 -280.348944)
			(xy 379.811026 -280.256996) (xy 379.80112 -280.235914) (xy 379.791976 -280.228548) (xy 379.770116 -280.210356)
			(xy 379.731578 -280.168534) (xy 379.699673 -280.121455) (xy 379.675108 -280.070163) (xy 379.658427 -280.015793)
			(xy 379.65 -279.95955) (xy 379.649482 -279.931114) (xy 379.649968 -279.903862) (xy 379.657723 -279.849912)
			(xy 379.673077 -279.797616) (xy 379.695717 -279.748036) (xy 379.725183 -279.702183) (xy 379.760874 -279.660991)
			(xy 379.802064 -279.625297) (xy 379.847915 -279.595829) (xy 379.897493 -279.573185) (xy 379.949789 -279.557828)
			(xy 380.003738 -279.55007) (xy 380.03099 -279.549606) (xy 380.058243 -279.550065) (xy 380.112195 -279.557821)
			(xy 380.164494 -279.573176) (xy 380.214075 -279.595818) (xy 380.259929 -279.625287) (xy 380.301122 -279.660981)
			(xy 380.336816 -279.702174) (xy 380.366283 -279.748029) (xy 380.388925 -279.79761) (xy 380.40428 -279.849909)
			(xy 380.412036 -279.903861) (xy 380.412498 -279.931114) (xy 380.412 -279.959889) (xy 380.403322 -280.016781)
			(xy 380.38618 -280.071719) (xy 380.360965 -280.123451) (xy 380.328251 -280.170799) (xy 380.288784 -280.212685)
			(xy 380.266448 -280.230834) (xy 380.266194 -280.231088) (xy 380.25959 -280.236422) (xy 380.251226 -280.243901)
			(xy 380.241479 -280.264083) (xy 380.240794 -280.275284) (xy 380.239524 -280.367232) (xy 380.24943 -280.388314)
			(xy 380.258574 -280.39568) (xy 380.280389 -280.413924) (xy 380.318933 -280.455734) (xy 380.350844 -280.502801)
			(xy 380.375417 -280.554084) (xy 380.392107 -280.608445) (xy 380.400545 -280.664681) (xy 380.401068 -280.693114)
			(xy 381.034542 -280.693114) (xy 381.038613 -280.637492) (xy 381.050739 -280.583055) (xy 381.070662 -280.530964)
			(xy 381.097958 -280.482329) (xy 381.132044 -280.438186) (xy 381.172193 -280.399477) (xy 381.217551 -280.367026)
			(xy 381.267151 -280.341525) (xy 381.319935 -280.323518) (xy 381.374778 -280.313388) (xy 381.430512 -280.311351)
			(xy 381.485949 -280.317451) (xy 381.539906 -280.331557) (xy 381.591235 -280.353369) (xy 381.638841 -280.382423)
			(xy 381.681709 -280.418098) (xy 381.718926 -280.459635) (xy 381.749699 -280.506148) (xy 381.773371 -280.556645)
			(xy 381.789439 -280.610052) (xy 381.797559 -280.665228) (xy 381.798068 -280.693114) (xy 381.797559 -280.721)
			(xy 381.789439 -280.776176) (xy 381.773371 -280.829583) (xy 381.749699 -280.88008) (xy 381.718926 -280.926593)
			(xy 381.681709 -280.96813) (xy 381.638841 -281.003805) (xy 381.591235 -281.032859) (xy 381.539906 -281.054671)
			(xy 381.485949 -281.068777) (xy 381.430512 -281.074877) (xy 381.374778 -281.07284) (xy 381.319935 -281.06271)
			(xy 381.267151 -281.044703) (xy 381.217551 -281.019202) (xy 381.172193 -280.986751) (xy 381.132044 -280.948042)
			(xy 381.097958 -280.903899) (xy 381.070662 -280.855264) (xy 381.050739 -280.803173) (xy 381.038613 -280.748736)
			(xy 381.034542 -280.693114) (xy 380.401068 -280.693114) (xy 380.400658 -280.720369) (xy 380.392898 -280.774324)
			(xy 380.377538 -280.826625) (xy 380.354891 -280.876208) (xy 380.325418 -280.922063) (xy 380.289719 -280.963257)
			(xy 380.24852 -280.99895) (xy 380.202661 -281.028417) (xy 380.153075 -281.051057) (xy 380.100771 -281.06641)
			(xy 380.046815 -281.074162) (xy 380.01956 -281.074622) (xy 379.992308 -281.074159) (xy 379.938361 -281.066398)
			(xy 379.886066 -281.051038) (xy 379.83649 -281.028394) (xy 379.79064 -280.998924) (xy 379.749451 -280.963231)
			(xy 379.71376 -280.922039) (xy 379.684294 -280.876187) (xy 379.661653 -280.826609) (xy 379.646297 -280.774314)
			(xy 379.638539 -280.720366) (xy 379.638052 -280.693114) (xy 366.640819 -280.693114) (xy 366.661625 -280.705812)
			(xy 366.704521 -280.741511) (xy 366.741763 -280.783075) (xy 366.772557 -280.829619) (xy 366.796245 -280.88015)
			(xy 366.812323 -280.933592) (xy 366.820449 -280.988806) (xy 366.820958 -281.01671) (xy 366.820449 -281.044614)
			(xy 366.812323 -281.099828) (xy 366.796245 -281.15327) (xy 366.772557 -281.203801) (xy 366.741763 -281.250345)
			(xy 366.704521 -281.291909) (xy 366.661625 -281.327608) (xy 366.613987 -281.356681) (xy 366.562624 -281.378508)
			(xy 366.508631 -281.392624) (xy 366.453157 -281.398727) (xy 366.397386 -281.396689) (xy 366.342507 -281.386552)
			(xy 366.289687 -281.368533) (xy 366.240055 -281.343015) (xy 366.194667 -281.310543) (xy 366.15449 -281.271808)
			(xy 366.120382 -281.227636) (xy 366.093068 -281.178968) (xy 366.073132 -281.126842) (xy 366.060997 -281.072369)
			(xy 366.056924 -281.01671) (xy 365.325764 -281.01671) (xy 365.34115 -281.066265) (xy 365.349774 -281.123097)
			(xy 365.350298 -281.151838) (xy 365.349812 -281.179107) (xy 365.34205 -281.233091) (xy 365.326685 -281.285421)
			(xy 365.304028 -281.335031) (xy 365.274542 -281.380912) (xy 365.238827 -281.422129) (xy 365.19761 -281.457844)
			(xy 365.151729 -281.48733) (xy 365.102119 -281.509987) (xy 365.049789 -281.525352) (xy 364.995805 -281.533114)
			(xy 364.941267 -281.533114) (xy 364.887283 -281.525352) (xy 364.834953 -281.509987) (xy 364.785343 -281.48733)
			(xy 364.739462 -281.457844) (xy 364.698245 -281.422129) (xy 364.66253 -281.380912) (xy 364.633044 -281.335031)
			(xy 364.610387 -281.285421) (xy 364.595022 -281.233091) (xy 364.58726 -281.179107) (xy 364.586774 -281.151838)
			(xy 364.58754 -281.117755) (xy 364.599678 -281.050678) (xy 364.610904 -281.018488) (xy 364.615222 -281.006804)
			(xy 364.612682 -280.983436) (xy 364.555786 -280.895044) (xy 364.534958 -280.882852) (xy 364.52302 -280.88209)
			(xy 364.488828 -280.879031) (xy 364.42226 -280.862291) (xy 364.390686 -280.848816) (xy 364.380526 -280.84907)
			(xy 364.375138 -280.849295) (xy 364.364636 -280.851729) (xy 364.359698 -280.853896) (xy 364.28172 -280.891234)
			(xy 364.26775 -280.90749) (xy 364.264702 -280.917904) (xy 364.25651 -280.943909) (xy 364.233845 -280.993496)
			(xy 364.204357 -281.039353) (xy 364.168645 -281.080549) (xy 364.127435 -281.116245) (xy 364.081566 -281.145716)
			(xy 364.031971 -281.168361) (xy 363.979659 -281.183721) (xy 363.925694 -281.191482) (xy 363.898434 -281.19197)
			(xy 363.876189 -281.191643) (xy 363.832005 -281.18642) (xy 363.810296 -281.181556) (xy 363.804454 -281.180286)
			(xy 363.791754 -281.180286) (xy 363.785166 -281.180437) (xy 363.772424 -281.18379) (xy 363.766608 -281.18689)
			(xy 363.699298 -281.22499) (xy 363.687106 -281.240484) (xy 363.684312 -281.250136) (xy 363.676246 -281.276289)
			(xy 363.653708 -281.326162) (xy 363.62428 -281.372306) (xy 363.588564 -281.413775) (xy 363.547293 -281.449718)
			(xy 363.501312 -281.4794) (xy 363.451564 -281.502213) (xy 363.399068 -281.517687) (xy 363.3449 -281.525507)
			(xy 363.317536 -281.52598) (xy 363.290267 -281.525465) (xy 363.236283 -281.517708) (xy 363.183952 -281.502348)
			(xy 363.13434 -281.479695) (xy 363.088457 -281.450213) (xy 363.047237 -281.414501) (xy 363.011519 -281.373286)
			(xy 362.98203 -281.327407) (xy 362.959371 -281.277799) (xy 362.944003 -281.22547) (xy 362.936239 -281.171487)
			(xy 362.935774 -281.144218) (xy 362.935853 -281.133846) (xy 362.936998 -281.113134) (xy 362.93806 -281.102816)
			(xy 362.938314 -281.100276) (xy 362.938314 -281.095704) (xy 362.937984 -281.087983) (xy 362.933346 -281.07325)
			(xy 362.92917 -281.066748) (xy 362.928662 -281.065986) (xy 362.88345 -281.003248) (xy 362.867448 -280.993088)
			(xy 362.85805 -280.991056) (xy 362.829715 -280.984691) (xy 362.775245 -280.964556) (xy 362.724455 -280.936401)
			(xy 362.678517 -280.900876) (xy 362.638492 -280.8588) (xy 362.605305 -280.811146) (xy 362.579721 -280.759013)
			(xy 362.562331 -280.703606) (xy 362.553537 -280.646204) (xy 362.552996 -280.617168) (xy 356.751311 -280.617168)
			(xy 356.745286 -280.63444) (xy 356.740968 -280.646124) (xy 356.743508 -280.669492) (xy 356.800404 -280.757884)
			(xy 356.821232 -280.770076) (xy 356.83317 -280.770838) (xy 356.861813 -280.773271) (xy 356.917951 -280.785628)
			(xy 356.971603 -280.806259) (xy 357.021557 -280.834698) (xy 357.066684 -280.870302) (xy 357.105965 -280.912268)
			(xy 357.138514 -280.959647) (xy 357.157931 -280.999692) (xy 357.896412 -280.999692) (xy 357.900485 -280.944033)
			(xy 357.91262 -280.88956) (xy 357.932556 -280.837434) (xy 357.95987 -280.788766) (xy 357.993978 -280.744594)
			(xy 358.034155 -280.705859) (xy 358.079543 -280.673387) (xy 358.129175 -280.647869) (xy 358.181995 -280.62985)
			(xy 358.236874 -280.619713) (xy 358.292645 -280.617675) (xy 358.348119 -280.623778) (xy 358.402112 -280.637894)
			(xy 358.453475 -280.659721) (xy 358.501113 -280.688794) (xy 358.544009 -280.724493) (xy 358.581251 -280.766057)
			(xy 358.612045 -280.812601) (xy 358.635733 -280.863132) (xy 358.651811 -280.916574) (xy 358.659937 -280.971788)
			(xy 358.660446 -280.999692) (xy 358.659937 -281.027596) (xy 358.651811 -281.08281) (xy 358.635733 -281.136252)
			(xy 358.612045 -281.186783) (xy 358.581251 -281.233327) (xy 358.544009 -281.274891) (xy 358.501113 -281.31059)
			(xy 358.453475 -281.339663) (xy 358.402112 -281.36149) (xy 358.348119 -281.375606) (xy 358.292645 -281.381709)
			(xy 358.236874 -281.379671) (xy 358.181995 -281.369534) (xy 358.129175 -281.351515) (xy 358.079543 -281.325997)
			(xy 358.034155 -281.293525) (xy 357.993978 -281.25479) (xy 357.95987 -281.210618) (xy 357.932556 -281.16195)
			(xy 357.91262 -281.109824) (xy 357.900485 -281.055351) (xy 357.896412 -280.999692) (xy 357.157931 -280.999692)
			(xy 357.163593 -281.011369) (xy 357.180638 -281.066266) (xy 357.189262 -281.123097) (xy 357.189786 -281.151838)
			(xy 357.1893 -281.179107) (xy 357.181538 -281.233091) (xy 357.166173 -281.285421) (xy 357.143516 -281.335031)
			(xy 357.11403 -281.380912) (xy 357.078315 -281.422129) (xy 357.037098 -281.457844) (xy 356.991217 -281.48733)
			(xy 356.941607 -281.509987) (xy 356.889277 -281.525352) (xy 356.835293 -281.533114) (xy 356.780755 -281.533114)
			(xy 356.726771 -281.525352) (xy 356.674441 -281.509987) (xy 356.624831 -281.48733) (xy 356.57895 -281.457844)
			(xy 356.537733 -281.422129) (xy 356.502018 -281.380912) (xy 356.472532 -281.335031) (xy 356.449875 -281.285421)
			(xy 356.43451 -281.233091) (xy 356.426748 -281.179107) (xy 356.426262 -281.151838) (xy 356.427029 -281.117755)
			(xy 356.439166 -281.050678) (xy 356.450392 -281.018488) (xy 356.45471 -281.006804) (xy 356.45217 -280.983436)
			(xy 356.395274 -280.895044) (xy 356.374446 -280.882852) (xy 356.362508 -280.88209) (xy 356.328315 -280.879034)
			(xy 356.261747 -280.862292) (xy 356.230174 -280.848816) (xy 356.220014 -280.84907) (xy 356.214626 -280.849292)
			(xy 356.204123 -280.851728) (xy 356.199186 -280.853896) (xy 356.121208 -280.891234) (xy 356.107238 -280.90749)
			(xy 356.10419 -280.917904) (xy 356.096008 -280.943913) (xy 356.073343 -280.9935) (xy 356.043854 -281.039358)
			(xy 356.00814 -281.080554) (xy 355.966929 -281.11625) (xy 355.921059 -281.14572) (xy 355.871462 -281.168365)
			(xy 355.819149 -281.183723) (xy 355.765183 -281.191483) (xy 355.737922 -281.19197) (xy 355.715677 -281.191645)
			(xy 355.671493 -281.186421) (xy 355.649784 -281.181556) (xy 355.643942 -281.180286) (xy 355.631242 -281.180286)
			(xy 355.624653 -281.180433) (xy 355.611912 -281.183789) (xy 355.606096 -281.18689) (xy 355.538786 -281.22499)
			(xy 355.526594 -281.240484) (xy 355.5238 -281.250136) (xy 355.515744 -281.276293) (xy 355.493206 -281.326166)
			(xy 355.463776 -281.372311) (xy 355.428059 -281.413779) (xy 355.386786 -281.449723) (xy 355.340804 -281.479405)
			(xy 355.291055 -281.502216) (xy 355.238558 -281.517689) (xy 355.184389 -281.525508) (xy 355.157024 -281.52598)
			(xy 355.129754 -281.525476) (xy 355.07577 -281.517718) (xy 355.023439 -281.502356) (xy 354.973827 -281.479702)
			(xy 354.927944 -281.450219) (xy 354.886724 -281.414505) (xy 354.851007 -281.373289) (xy 354.821518 -281.32741)
			(xy 354.798859 -281.2778) (xy 354.783491 -281.225471) (xy 354.775727 -281.171488) (xy 354.775262 -281.144218)
			(xy 354.775341 -281.133846) (xy 354.776486 -281.113134) (xy 354.777548 -281.102816) (xy 354.777802 -281.100276)
			(xy 354.777802 -281.095704) (xy 354.777474 -281.087983) (xy 354.772834 -281.07325) (xy 354.768658 -281.066748)
			(xy 354.76815 -281.065986) (xy 354.722938 -281.003248) (xy 354.706936 -280.993088) (xy 354.697538 -280.991056)
			(xy 354.669201 -280.984699) (xy 354.614731 -280.964563) (xy 354.563941 -280.936407) (xy 354.518004 -280.90088)
			(xy 354.477979 -280.858803) (xy 354.444792 -280.811148) (xy 354.419208 -280.759015) (xy 354.401819 -280.703607)
			(xy 354.393025 -280.646204) (xy 354.392484 -280.617168) (xy 348.252725 -280.617168) (xy 348.2467 -280.63444)
			(xy 348.242382 -280.646124) (xy 348.244922 -280.669492) (xy 348.301818 -280.757884) (xy 348.322646 -280.770076)
			(xy 348.334584 -280.770838) (xy 348.363228 -280.773259) (xy 348.419366 -280.785618) (xy 348.473018 -280.806251)
			(xy 348.522972 -280.834691) (xy 348.568099 -280.870297) (xy 348.60738 -280.912264) (xy 348.639928 -280.959644)
			(xy 348.665007 -281.011367) (xy 348.666666 -281.01671) (xy 349.397826 -281.01671) (xy 349.401899 -280.961051)
			(xy 349.414034 -280.906578) (xy 349.43397 -280.854452) (xy 349.461284 -280.805784) (xy 349.495392 -280.761612)
			(xy 349.535569 -280.722877) (xy 349.580957 -280.690405) (xy 349.630589 -280.664887) (xy 349.683409 -280.646868)
			(xy 349.738288 -280.636731) (xy 349.794059 -280.634693) (xy 349.849533 -280.640796) (xy 349.903526 -280.654912)
			(xy 349.954889 -280.676739) (xy 350.002527 -280.705812) (xy 350.045423 -280.741511) (xy 350.082665 -280.783075)
			(xy 350.113459 -280.829619) (xy 350.137147 -280.88015) (xy 350.153225 -280.933592) (xy 350.161351 -280.988806)
			(xy 350.16186 -281.01671) (xy 350.161351 -281.044614) (xy 350.153225 -281.099828) (xy 350.137147 -281.15327)
			(xy 350.113459 -281.203801) (xy 350.082665 -281.250345) (xy 350.045423 -281.291909) (xy 350.002527 -281.327608)
			(xy 349.954889 -281.356681) (xy 349.903526 -281.378508) (xy 349.849533 -281.392624) (xy 349.794059 -281.398727)
			(xy 349.738288 -281.396689) (xy 349.683409 -281.386552) (xy 349.630589 -281.368533) (xy 349.580957 -281.343015)
			(xy 349.535569 -281.310543) (xy 349.495392 -281.271808) (xy 349.461284 -281.227636) (xy 349.43397 -281.178968)
			(xy 349.414034 -281.126842) (xy 349.401899 -281.072369) (xy 349.397826 -281.01671) (xy 348.666666 -281.01671)
			(xy 348.682052 -281.066265) (xy 348.690676 -281.123097) (xy 348.6912 -281.151838) (xy 348.690714 -281.179107)
			(xy 348.682952 -281.233091) (xy 348.667587 -281.285421) (xy 348.64493 -281.335031) (xy 348.615444 -281.380912)
			(xy 348.579729 -281.422129) (xy 348.538512 -281.457844) (xy 348.492631 -281.48733) (xy 348.443021 -281.509987)
			(xy 348.390691 -281.525352) (xy 348.336707 -281.533114) (xy 348.282169 -281.533114) (xy 348.228185 -281.525352)
			(xy 348.175855 -281.509987) (xy 348.126245 -281.48733) (xy 348.080364 -281.457844) (xy 348.039147 -281.422129)
			(xy 348.003432 -281.380912) (xy 347.973946 -281.335031) (xy 347.951289 -281.285421) (xy 347.935924 -281.233091)
			(xy 347.928162 -281.179107) (xy 347.927676 -281.151838) (xy 347.928442 -281.117755) (xy 347.94058 -281.050678)
			(xy 347.951806 -281.018488) (xy 347.956124 -281.006804) (xy 347.953584 -280.983436) (xy 347.896688 -280.895044)
			(xy 347.87586 -280.882852) (xy 347.863922 -280.88209) (xy 347.82973 -280.87903) (xy 347.763162 -280.862291)
			(xy 347.731588 -280.848816) (xy 347.721428 -280.84907) (xy 347.716041 -280.849296) (xy 347.705538 -280.851729)
			(xy 347.7006 -280.853896) (xy 347.622622 -280.891234) (xy 347.608652 -280.90749) (xy 347.605604 -280.917904)
			(xy 347.59741 -280.943909) (xy 347.574746 -280.993495) (xy 347.545258 -281.039352) (xy 347.509546 -281.080548)
			(xy 347.468336 -281.116245) (xy 347.422468 -281.145715) (xy 347.372873 -281.168361) (xy 347.320561 -281.18372)
			(xy 347.266596 -281.191482) (xy 347.239336 -281.19197) (xy 347.217091 -281.191642) (xy 347.172907 -281.18642)
			(xy 347.151198 -281.181556) (xy 347.145356 -281.180286) (xy 347.132656 -281.180286) (xy 347.126068 -281.180438)
			(xy 347.113326 -281.18379) (xy 347.10751 -281.18689) (xy 347.0402 -281.22499) (xy 347.028008 -281.240484)
			(xy 347.025214 -281.250136) (xy 347.017146 -281.276289) (xy 346.994608 -281.326162) (xy 346.96518 -281.372305)
			(xy 346.929465 -281.413774) (xy 346.888194 -281.449718) (xy 346.842213 -281.4794) (xy 346.792465 -281.502212)
			(xy 346.73997 -281.517687) (xy 346.685802 -281.525507) (xy 346.658438 -281.52598) (xy 346.631169 -281.525463)
			(xy 346.577185 -281.517707) (xy 346.524854 -281.502346) (xy 346.475242 -281.479694) (xy 346.429359 -281.450212)
			(xy 346.388139 -281.4145) (xy 346.352421 -281.373286) (xy 346.322933 -281.327407) (xy 346.300273 -281.277798)
			(xy 346.284905 -281.22547) (xy 346.277141 -281.171487) (xy 346.276676 -281.144218) (xy 346.276755 -281.133846)
			(xy 346.2779 -281.113134) (xy 346.278962 -281.102816) (xy 346.279216 -281.100276) (xy 346.279216 -281.095704)
			(xy 346.278885 -281.087983) (xy 346.274247 -281.07325) (xy 346.270072 -281.066748) (xy 346.269564 -281.065986)
			(xy 346.224352 -281.003248) (xy 346.20835 -280.993088) (xy 346.198952 -280.991056) (xy 346.170617 -280.98469)
			(xy 346.116147 -280.964555) (xy 346.065357 -280.936401) (xy 346.019419 -280.900875) (xy 345.979394 -280.8588)
			(xy 345.946207 -280.811146) (xy 345.920623 -280.759013) (xy 345.903233 -280.703606) (xy 345.894439 -280.646204)
			(xy 345.893898 -280.617168) (xy 340.092213 -280.617168) (xy 340.086188 -280.63444) (xy 340.08187 -280.646124)
			(xy 340.08441 -280.669492) (xy 340.141306 -280.757884) (xy 340.162134 -280.770076) (xy 340.174072 -280.770838)
			(xy 340.202715 -280.773269) (xy 340.258853 -280.785626) (xy 340.312505 -280.806258) (xy 340.362459 -280.834697)
			(xy 340.407586 -280.870301) (xy 340.446867 -280.912267) (xy 340.479416 -280.959647) (xy 340.498833 -280.999692)
			(xy 341.054942 -280.999692) (xy 341.059015 -280.944033) (xy 341.07115 -280.88956) (xy 341.091086 -280.837434)
			(xy 341.1184 -280.788766) (xy 341.152508 -280.744594) (xy 341.192685 -280.705859) (xy 341.238073 -280.673387)
			(xy 341.287705 -280.647869) (xy 341.340525 -280.62985) (xy 341.395404 -280.619713) (xy 341.451175 -280.617675)
			(xy 341.506649 -280.623778) (xy 341.560642 -280.637894) (xy 341.612005 -280.659721) (xy 341.659643 -280.688794)
			(xy 341.702539 -280.724493) (xy 341.739781 -280.766057) (xy 341.770575 -280.812601) (xy 341.794263 -280.863132)
			(xy 341.810341 -280.916574) (xy 341.818467 -280.971788) (xy 341.818976 -280.999692) (xy 341.818467 -281.027596)
			(xy 341.810341 -281.08281) (xy 341.794263 -281.136252) (xy 341.770575 -281.186783) (xy 341.739781 -281.233327)
			(xy 341.702539 -281.274891) (xy 341.659643 -281.31059) (xy 341.612005 -281.339663) (xy 341.560642 -281.36149)
			(xy 341.506649 -281.375606) (xy 341.451175 -281.381709) (xy 341.395404 -281.379671) (xy 341.340525 -281.369534)
			(xy 341.287705 -281.351515) (xy 341.238073 -281.325997) (xy 341.192685 -281.293525) (xy 341.152508 -281.25479)
			(xy 341.1184 -281.210618) (xy 341.091086 -281.16195) (xy 341.07115 -281.109824) (xy 341.059015 -281.055351)
			(xy 341.054942 -280.999692) (xy 340.498833 -280.999692) (xy 340.504495 -281.011369) (xy 340.52154 -281.066266)
			(xy 340.530164 -281.123097) (xy 340.530688 -281.151838) (xy 340.530202 -281.179107) (xy 340.52244 -281.233091)
			(xy 340.507075 -281.285421) (xy 340.484418 -281.335031) (xy 340.454932 -281.380912) (xy 340.419217 -281.422129)
			(xy 340.378 -281.457844) (xy 340.332119 -281.48733) (xy 340.282509 -281.509987) (xy 340.230179 -281.525352)
			(xy 340.176195 -281.533114) (xy 340.121657 -281.533114) (xy 340.067673 -281.525352) (xy 340.015343 -281.509987)
			(xy 339.965733 -281.48733) (xy 339.919852 -281.457844) (xy 339.878635 -281.422129) (xy 339.84292 -281.380912)
			(xy 339.813434 -281.335031) (xy 339.790777 -281.285421) (xy 339.775412 -281.233091) (xy 339.76765 -281.179107)
			(xy 339.767164 -281.151838) (xy 339.767931 -281.117755) (xy 339.780068 -281.050678) (xy 339.791294 -281.018488)
			(xy 339.795612 -281.006804) (xy 339.793072 -280.983436) (xy 339.736176 -280.895044) (xy 339.715348 -280.882852)
			(xy 339.70341 -280.88209) (xy 339.669217 -280.879033) (xy 339.602649 -280.862292) (xy 339.571076 -280.848816)
			(xy 339.560916 -280.84907) (xy 339.555528 -280.849292) (xy 339.545025 -280.851728) (xy 339.540088 -280.853896)
			(xy 339.46211 -280.891234) (xy 339.44814 -280.90749) (xy 339.445092 -280.917904) (xy 339.436909 -280.943912)
			(xy 339.414243 -280.993499) (xy 339.384754 -281.039357) (xy 339.349041 -281.080553) (xy 339.30783 -281.116249)
			(xy 339.26196 -281.145719) (xy 339.212364 -281.168364) (xy 339.160051 -281.183723) (xy 339.106085 -281.191483)
			(xy 339.078824 -281.19197) (xy 339.056579 -281.191644) (xy 339.012395 -281.186421) (xy 338.990686 -281.181556)
			(xy 338.984844 -281.180286) (xy 338.96427 -281.180286) (xy 338.950554 -281.18435) (xy 338.944204 -281.188414)
			(xy 338.941664 -281.189938) (xy 338.879688 -281.22499) (xy 338.867496 -281.240484) (xy 338.864702 -281.250136)
			(xy 338.856645 -281.276292) (xy 338.834106 -281.326166) (xy 338.804677 -281.37231) (xy 338.76896 -281.413779)
			(xy 338.727687 -281.449722) (xy 338.681705 -281.479404) (xy 338.631956 -281.502215) (xy 338.579459 -281.517689)
			(xy 338.525291 -281.525508) (xy 338.497926 -281.52598) (xy 338.470656 -281.525474) (xy 338.416672 -281.517716)
			(xy 338.364341 -281.502354) (xy 338.314729 -281.479701) (xy 338.268846 -281.450218) (xy 338.227626 -281.414505)
			(xy 338.191909 -281.373289) (xy 338.16242 -281.327409) (xy 338.139761 -281.2778) (xy 338.124393 -281.225471)
			(xy 338.116629 -281.171487) (xy 338.116164 -281.144218) (xy 338.116243 -281.133846) (xy 338.117388 -281.113134)
			(xy 338.11845 -281.102816) (xy 338.118704 -281.100276) (xy 338.118704 -281.095704) (xy 338.118375 -281.087983)
			(xy 338.113736 -281.07325) (xy 338.10956 -281.066748) (xy 338.109052 -281.065986) (xy 338.06384 -281.003248)
			(xy 338.047838 -280.993088) (xy 338.03844 -280.991056) (xy 338.010103 -280.984698) (xy 337.955634 -280.964562)
			(xy 337.904844 -280.936406) (xy 337.858906 -280.900879) (xy 337.818881 -280.858803) (xy 337.785694 -280.811148)
			(xy 337.76011 -280.759015) (xy 337.742721 -280.703607) (xy 337.733927 -280.646204) (xy 337.733386 -280.617168)
			(xy 332.633828 -280.617168) (xy 332.633828 -282.904438) (xy 334.102964 -282.904438) (xy 334.103492 -282.876815)
			(xy 334.111433 -282.822144) (xy 334.127168 -282.769187) (xy 334.15037 -282.719051) (xy 334.180555 -282.672781)
			(xy 334.217091 -282.631343) (xy 334.237838 -282.6131) (xy 334.245958 -282.605499) (xy 334.25531 -282.585346)
			(xy 334.255872 -282.574238) (xy 334.255872 -282.49753) (xy 334.255312 -282.486419) (xy 334.245969 -282.46626)
			(xy 334.237838 -282.458668) (xy 334.217169 -282.440412) (xy 334.180702 -282.399047) (xy 334.150571 -282.352863)
			(xy 334.127405 -282.302821) (xy 334.111687 -282.249965) (xy 334.103743 -282.195396) (xy 334.103739 -282.140253)
			(xy 334.111676 -282.085683) (xy 334.127388 -282.032825) (xy 334.150548 -281.98278) (xy 334.180672 -281.936592)
			(xy 334.217134 -281.895223) (xy 334.237838 -281.877008) (xy 334.245954 -281.869404) (xy 334.255308 -281.849253)
			(xy 334.255872 -281.838146) (xy 334.255872 -281.76093) (xy 334.255312 -281.749819) (xy 334.245969 -281.72966)
			(xy 334.237838 -281.722068) (xy 334.217116 -281.703869) (xy 334.180645 -281.662498) (xy 334.150513 -281.616306)
			(xy 334.127349 -281.566256) (xy 334.111635 -281.513391) (xy 334.1037 -281.458814) (xy 334.103218 -281.431238)
			(xy 334.103691 -281.403985) (xy 334.111443 -281.350033) (xy 334.126796 -281.297734) (xy 334.149436 -281.248152)
			(xy 334.178902 -281.202297) (xy 334.214595 -281.161104) (xy 334.255788 -281.125409) (xy 334.301641 -281.095941)
			(xy 334.351222 -281.0733) (xy 334.403521 -281.057946) (xy 334.457473 -281.050192) (xy 334.484726 -281.04973)
			(xy 334.512598 -281.050245) (xy 334.567749 -281.058348) (xy 334.621133 -281.074391) (xy 334.671614 -281.098033)
			(xy 334.718116 -281.128771) (xy 334.759649 -281.16595) (xy 334.795329 -281.208778) (xy 334.824395 -281.256343)
			(xy 334.846228 -281.307633) (xy 334.853788 -281.334464) (xy 334.856074 -281.343354) (xy 334.866996 -281.358594)
			(xy 334.933798 -281.403298) (xy 334.939386 -281.40533) (xy 334.943911 -281.406975) (xy 334.953369 -281.408764)
			(xy 334.958182 -281.408886) (xy 334.964786 -281.408886) (xy 334.968088 -281.408378) (xy 334.98048 -281.406905)
			(xy 335.005392 -281.405382) (xy 335.017872 -281.40533) (xy 335.01838 -281.40533) (xy 335.03086 -281.405373)
			(xy 335.055772 -281.406898) (xy 335.068164 -281.408378) (xy 335.071466 -281.408886) (xy 335.07807 -281.408886)
			(xy 335.085546 -281.40865) (xy 335.099876 -281.404394) (xy 335.106264 -281.400504) (xy 335.169256 -281.358594)
			(xy 335.180178 -281.343608) (xy 335.182464 -281.334464) (xy 335.19008 -281.307651) (xy 335.211916 -281.25637)
			(xy 335.240981 -281.208811) (xy 335.276655 -281.165987) (xy 335.31818 -281.128809) (xy 335.364672 -281.098068)
			(xy 335.415142 -281.074418) (xy 335.468516 -281.058362) (xy 335.523658 -281.050243) (xy 335.551526 -281.04973)
			(xy 335.578781 -281.050131) (xy 335.632736 -281.057892) (xy 335.685038 -281.073254) (xy 335.734621 -281.095902)
			(xy 335.780476 -281.125376) (xy 335.821669 -281.161076) (xy 335.857362 -281.202276) (xy 335.886829 -281.248136)
			(xy 335.909469 -281.297722) (xy 335.924821 -281.350026) (xy 335.932574 -281.403983) (xy 335.933034 -281.431238)
			(xy 335.932564 -281.458537) (xy 335.924788 -281.512579) (xy 335.909386 -281.564959) (xy 335.886672 -281.614609)
			(xy 335.857111 -281.660512) (xy 335.839562 -281.681428) (xy 335.833212 -281.688794) (xy 335.826862 -281.706574)
			(xy 335.82991 -281.786076) (xy 335.830684 -281.795517) (xy 335.838247 -281.81287) (xy 335.844642 -281.819858)
			(xy 335.84515 -281.820366) (xy 335.866221 -281.842003) (xy 335.901948 -281.890695) (xy 335.929554 -281.944409)
			(xy 335.935763 -281.963368) (xy 340.481664 -281.963368) (xy 340.485737 -281.907709) (xy 340.497872 -281.853236)
			(xy 340.517808 -281.80111) (xy 340.545122 -281.752442) (xy 340.57923 -281.70827) (xy 340.619407 -281.669535)
			(xy 340.664795 -281.637063) (xy 340.714427 -281.611545) (xy 340.767247 -281.593526) (xy 340.822126 -281.583389)
			(xy 340.877897 -281.581351) (xy 340.933371 -281.587454) (xy 340.987364 -281.60157) (xy 341.038727 -281.623397)
			(xy 341.086365 -281.65247) (xy 341.129261 -281.688169) (xy 341.166503 -281.729733) (xy 341.197297 -281.776277)
			(xy 341.220985 -281.826808) (xy 341.237063 -281.88025) (xy 341.245189 -281.935464) (xy 341.245698 -281.963368)
			(xy 341.245189 -281.991272) (xy 341.237063 -282.046486) (xy 341.220985 -282.099928) (xy 341.197297 -282.150459)
			(xy 341.166503 -282.197003) (xy 341.129261 -282.238567) (xy 341.086365 -282.274266) (xy 341.038727 -282.303339)
			(xy 340.987364 -282.325166) (xy 340.933371 -282.339282) (xy 340.877897 -282.345385) (xy 340.822126 -282.343347)
			(xy 340.767247 -282.33321) (xy 340.714427 -282.315191) (xy 340.664795 -282.289673) (xy 340.619407 -282.257201)
			(xy 340.57923 -282.218466) (xy 340.545122 -282.174294) (xy 340.517808 -282.125626) (xy 340.497872 -282.0735)
			(xy 340.485737 -282.019027) (xy 340.481664 -281.963368) (xy 335.935763 -281.963368) (xy 335.948349 -282.001803)
			(xy 335.957862 -282.061442) (xy 335.958434 -282.091638) (xy 335.957968 -282.11857) (xy 335.950355 -282.171895)
			(xy 335.935327 -282.223622) (xy 335.913183 -282.272726) (xy 335.884361 -282.318232) (xy 335.867248 -282.339034)
			(xy 335.8642 -282.34259) (xy 335.86039 -282.347416) (xy 335.853973 -282.356982) (xy 335.849504 -282.379551)
			(xy 335.851754 -282.39085) (xy 335.876138 -282.484322) (xy 335.892902 -282.503118) (xy 335.90484 -282.507182)
			(xy 335.932234 -282.517556) (xy 335.983708 -282.545511) (xy 336.030309 -282.580999) (xy 336.070943 -282.623188)
			(xy 336.104657 -282.671087) (xy 336.130661 -282.723574) (xy 336.148344 -282.779417) (xy 336.157291 -282.837304)
			(xy 336.157824 -282.866592) (xy 336.157824 -282.8671) (xy 336.157353 -282.893854) (xy 336.487447 -282.893854)
			(xy 336.487447 -282.839346) (xy 336.495205 -282.785392) (xy 336.510562 -282.733092) (xy 336.533206 -282.68351)
			(xy 336.562676 -282.637655) (xy 336.598372 -282.596461) (xy 336.639568 -282.560767) (xy 336.685424 -282.531299)
			(xy 336.735007 -282.508657) (xy 336.787308 -282.493302) (xy 336.841262 -282.485546) (xy 336.868516 -282.485084)
			(xy 336.895888 -282.48552) (xy 336.950069 -282.493342) (xy 337.002573 -282.508837) (xy 337.052319 -282.531686)
			(xy 337.098284 -282.561419) (xy 337.119214 -282.579064) (xy 337.119468 -282.579318) (xy 337.126558 -282.584899)
			(xy 337.143472 -282.591149) (xy 337.152488 -282.59151) (xy 337.219544 -282.59151) (xy 337.228558 -282.591124)
			(xy 337.245475 -282.584896) (xy 337.252564 -282.579318) (xy 337.253072 -282.57881) (xy 337.273999 -282.561219)
			(xy 337.319935 -282.53158) (xy 337.369633 -282.508803) (xy 337.422073 -282.493355) (xy 337.476182 -282.485552)
			(xy 337.503516 -282.485084) (xy 337.530766 -282.485587) (xy 337.584711 -282.493345) (xy 337.637003 -282.508701)
			(xy 337.686577 -282.531343) (xy 337.732424 -282.560809) (xy 337.773612 -282.5965) (xy 337.809301 -282.637689)
			(xy 337.838765 -282.683537) (xy 337.861404 -282.733112) (xy 337.876758 -282.785405) (xy 337.884514 -282.83935)
			(xy 337.884514 -282.89385) (xy 337.882992 -282.904438) (xy 342.263476 -282.904438) (xy 342.264 -282.876815)
			(xy 342.271941 -282.822143) (xy 342.287677 -282.769187) (xy 342.31088 -282.71905) (xy 342.341065 -282.67278)
			(xy 342.377602 -282.631343) (xy 342.39835 -282.6131) (xy 342.406472 -282.605501) (xy 342.415822 -282.585346)
			(xy 342.416384 -282.574238) (xy 342.416384 -282.497784) (xy 342.415774 -282.48674) (xy 342.406439 -282.466718)
			(xy 342.39835 -282.459176) (xy 342.377615 -282.440919) (xy 342.341078 -282.399481) (xy 342.310889 -282.353214)
			(xy 342.287678 -282.303081) (xy 342.271927 -282.250129) (xy 342.263966 -282.195461) (xy 342.263476 -282.167838)
			(xy 342.264 -282.140215) (xy 342.271941 -282.085543) (xy 342.287677 -282.032587) (xy 342.31088 -281.98245)
			(xy 342.341065 -281.93618) (xy 342.377602 -281.894743) (xy 342.39835 -281.8765) (xy 342.406433 -281.868953)
			(xy 342.415781 -281.848935) (xy 342.416384 -281.837892) (xy 342.416384 -281.761184) (xy 342.415774 -281.75014)
			(xy 342.406439 -281.730118) (xy 342.39835 -281.722576) (xy 342.377615 -281.704319) (xy 342.341078 -281.662881)
			(xy 342.310889 -281.616614) (xy 342.287678 -281.566481) (xy 342.271927 -281.513529) (xy 342.263966 -281.458861)
			(xy 342.263476 -281.431238) (xy 342.263937 -281.403966) (xy 342.271695 -281.349977) (xy 342.287058 -281.297642)
			(xy 342.309714 -281.248027) (xy 342.339201 -281.202141) (xy 342.374919 -281.160919) (xy 342.416141 -281.125201)
			(xy 342.462027 -281.095714) (xy 342.511642 -281.073058) (xy 342.563977 -281.057695) (xy 342.617966 -281.049937)
			(xy 342.645238 -281.049476) (xy 342.673131 -281.049989) (xy 342.728325 -281.058101) (xy 342.781751 -281.07416)
			(xy 342.832269 -281.097825) (xy 342.878805 -281.128592) (xy 342.920366 -281.165804) (xy 342.956068 -281.208671)
			(xy 342.985151 -281.256277) (xy 343.006993 -281.30761) (xy 343.014554 -281.334464) (xy 343.01684 -281.343608)
			(xy 343.027762 -281.358594) (xy 343.09431 -281.403298) (xy 343.099898 -281.40533) (xy 343.104422 -281.406978)
			(xy 343.113881 -281.408765) (xy 343.118694 -281.408886) (xy 343.12479 -281.408886) (xy 343.128092 -281.408378)
			(xy 343.14067 -281.406819) (xy 343.165964 -281.405164) (xy 343.178638 -281.405076) (xy 343.191312 -281.405175)
			(xy 343.216606 -281.406824) (xy 343.229184 -281.408378) (xy 343.232486 -281.408886) (xy 343.238582 -281.408886)
			(xy 343.246058 -281.408655) (xy 343.260388 -281.404395) (xy 343.266776 -281.400504) (xy 343.329514 -281.358848)
			(xy 343.340436 -281.343608) (xy 343.342722 -281.334464) (xy 343.350322 -281.307623) (xy 343.372168 -281.256297)
			(xy 343.40125 -281.208697) (xy 343.436949 -281.165835) (xy 343.478505 -281.128623) (xy 343.525034 -281.097855)
			(xy 343.575544 -281.074184) (xy 343.628961 -281.058114) (xy 343.684147 -281.049989) (xy 343.712038 -281.049476)
			(xy 343.73931 -281.049889) (xy 343.793298 -281.057657) (xy 343.845631 -281.073029) (xy 343.895244 -281.095693)
			(xy 343.941127 -281.125186) (xy 343.982345 -281.160909) (xy 344.01806 -281.202134) (xy 344.047544 -281.248022)
			(xy 344.070197 -281.29764) (xy 344.085559 -281.349976) (xy 344.093316 -281.403966) (xy 344.0938 -281.431238)
			(xy 344.093321 -281.458571) (xy 344.085515 -281.512678) (xy 344.070067 -281.565117) (xy 344.047294 -281.614815)
			(xy 344.017663 -281.660754) (xy 344.000074 -281.681682) (xy 343.993724 -281.689048) (xy 343.987374 -281.707336)
			(xy 343.990676 -281.79522) (xy 343.99855 -281.813) (xy 344.005408 -281.819858) (xy 344.026575 -281.841502)
			(xy 344.062456 -281.89026) (xy 344.090185 -281.944073) (xy 344.096518 -281.963368) (xy 348.642176 -281.963368)
			(xy 348.646249 -281.907709) (xy 348.658384 -281.853236) (xy 348.67832 -281.80111) (xy 348.705634 -281.752442)
			(xy 348.739742 -281.70827) (xy 348.779919 -281.669535) (xy 348.825307 -281.637063) (xy 348.874939 -281.611545)
			(xy 348.927759 -281.593526) (xy 348.982638 -281.583389) (xy 349.038409 -281.581351) (xy 349.093883 -281.587454)
			(xy 349.147876 -281.60157) (xy 349.199239 -281.623397) (xy 349.246877 -281.65247) (xy 349.289773 -281.688169)
			(xy 349.327015 -281.729733) (xy 349.357809 -281.776277) (xy 349.381497 -281.826808) (xy 349.397575 -281.88025)
			(xy 349.405701 -281.935464) (xy 349.40621 -281.963368) (xy 349.405701 -281.991272) (xy 349.397575 -282.046486)
			(xy 349.381497 -282.099928) (xy 349.357809 -282.150459) (xy 349.327015 -282.197003) (xy 349.289773 -282.238567)
			(xy 349.246877 -282.274266) (xy 349.199239 -282.303339) (xy 349.147876 -282.325166) (xy 349.093883 -282.339282)
			(xy 349.038409 -282.345385) (xy 348.982638 -282.343347) (xy 348.927759 -282.33321) (xy 348.874939 -282.315191)
			(xy 348.825307 -282.289673) (xy 348.779919 -282.257201) (xy 348.739742 -282.218466) (xy 348.705634 -282.174294)
			(xy 348.67832 -282.125626) (xy 348.658384 -282.0735) (xy 348.646249 -282.019027) (xy 348.642176 -281.963368)
			(xy 344.096518 -281.963368) (xy 344.109065 -282.001591) (xy 344.118622 -282.061369) (xy 344.1192 -282.091638)
			(xy 344.118713 -282.119301) (xy 344.110738 -282.174049) (xy 344.094947 -282.227073) (xy 344.07167 -282.277264)
			(xy 344.041395 -282.32357) (xy 344.023442 -282.344622) (xy 344.014806 -282.35402) (xy 344.008964 -282.378658)
			(xy 344.036396 -282.484322) (xy 344.053414 -282.502864) (xy 344.065352 -282.507182) (xy 344.092779 -282.517509)
			(xy 344.144305 -282.54543) (xy 344.190957 -282.5809) (xy 344.231637 -282.623086) (xy 344.265389 -282.670995)
			(xy 344.29142 -282.723502) (xy 344.309116 -282.779371) (xy 344.318062 -282.837289) (xy 344.31859 -282.866592)
			(xy 344.318104 -282.893873) (xy 344.647694 -282.893873) (xy 344.647694 -282.839327) (xy 344.655457 -282.785337)
			(xy 344.670825 -282.733001) (xy 344.693485 -282.683385) (xy 344.722976 -282.637499) (xy 344.758697 -282.596277)
			(xy 344.799921 -282.560559) (xy 344.845809 -282.531071) (xy 344.895427 -282.508415) (xy 344.947764 -282.493051)
			(xy 345.001755 -282.485292) (xy 345.029028 -282.48483) (xy 345.056431 -282.485338) (xy 345.110671 -282.493185)
			(xy 345.163231 -282.508715) (xy 345.213026 -282.531607) (xy 345.259033 -282.561391) (xy 345.27998 -282.579064)
			(xy 345.287092 -282.58516) (xy 345.30411 -282.59151) (xy 345.388946 -282.59151) (xy 345.405964 -282.58516)
			(xy 345.413076 -282.579064) (xy 345.434019 -282.561386) (xy 345.480035 -282.531617) (xy 345.529832 -282.508729)
			(xy 345.582388 -282.493191) (xy 345.636626 -282.485321) (xy 345.664028 -282.48483) (xy 345.691295 -282.485334)
			(xy 345.745275 -282.493099) (xy 345.7976 -282.508467) (xy 345.847206 -282.531124) (xy 345.893082 -282.56061)
			(xy 345.934295 -282.596324) (xy 345.970007 -282.63754) (xy 345.99949 -282.683419) (xy 346.022143 -282.733026)
			(xy 346.037507 -282.785352) (xy 346.045268 -282.839332) (xy 346.045268 -282.893868) (xy 346.043748 -282.904438)
			(xy 350.762062 -282.904438) (xy 350.762591 -282.876815) (xy 350.770532 -282.822144) (xy 350.786267 -282.769188)
			(xy 350.809469 -282.719051) (xy 350.839653 -282.672781) (xy 350.876189 -282.631343) (xy 350.896936 -282.6131)
			(xy 350.905056 -282.605499) (xy 350.914408 -282.585346) (xy 350.91497 -282.574238) (xy 350.91497 -282.497784)
			(xy 350.914364 -282.486739) (xy 350.905026 -282.466717) (xy 350.896936 -282.459176) (xy 350.876198 -282.440922)
			(xy 350.839662 -282.399483) (xy 350.809474 -282.353215) (xy 350.786263 -282.303082) (xy 350.770513 -282.25013)
			(xy 350.762552 -282.195461) (xy 350.762062 -282.167838) (xy 350.762591 -282.140215) (xy 350.770532 -282.085544)
			(xy 350.786267 -282.032588) (xy 350.809469 -281.982451) (xy 350.839653 -281.936181) (xy 350.876189 -281.894743)
			(xy 350.896936 -281.8765) (xy 350.905017 -281.868951) (xy 350.914367 -281.848935) (xy 350.91497 -281.837892)
			(xy 350.91497 -281.761184) (xy 350.914364 -281.750139) (xy 350.905026 -281.730117) (xy 350.896936 -281.722576)
			(xy 350.876198 -281.704322) (xy 350.839662 -281.662883) (xy 350.809474 -281.616615) (xy 350.786263 -281.566482)
			(xy 350.770513 -281.51353) (xy 350.762552 -281.458861) (xy 350.762062 -281.431238) (xy 350.762537 -281.403967)
			(xy 350.770294 -281.349979) (xy 350.785657 -281.297645) (xy 350.808312 -281.248031) (xy 350.837798 -281.202146)
			(xy 350.873514 -281.160924) (xy 350.914734 -281.125206) (xy 350.960618 -281.095719) (xy 351.010232 -281.073062)
			(xy 351.062565 -281.057697) (xy 351.116553 -281.049938) (xy 351.143824 -281.049476) (xy 351.171717 -281.050002)
			(xy 351.22691 -281.058111) (xy 351.280335 -281.074169) (xy 351.330854 -281.097832) (xy 351.37739 -281.128597)
			(xy 351.418951 -281.165808) (xy 351.454654 -281.208673) (xy 351.483736 -281.256279) (xy 351.505579 -281.307611)
			(xy 351.51314 -281.334464) (xy 351.515426 -281.343608) (xy 351.526348 -281.358594) (xy 351.592896 -281.403298)
			(xy 351.598484 -281.40533) (xy 351.603009 -281.406975) (xy 351.612467 -281.408764) (xy 351.61728 -281.408886)
			(xy 351.623376 -281.408886) (xy 351.626678 -281.408378) (xy 351.639255 -281.40681) (xy 351.66455 -281.405161)
			(xy 351.677224 -281.405076) (xy 351.689898 -281.405166) (xy 351.715192 -281.406821) (xy 351.72777 -281.408378)
			(xy 351.731072 -281.408886) (xy 351.737168 -281.408886) (xy 351.744644 -281.408649) (xy 351.758974 -281.404394)
			(xy 351.765362 -281.400504) (xy 351.8281 -281.358848) (xy 351.839022 -281.343608) (xy 351.841308 -281.334464)
			(xy 351.84883 -281.307599) (xy 351.870683 -281.256268) (xy 351.899773 -281.208665) (xy 351.935482 -281.165801)
			(xy 351.977048 -281.12859) (xy 352.023587 -281.097825) (xy 352.074108 -281.074159) (xy 352.127534 -281.058098)
			(xy 352.18273 -281.049983) (xy 352.210624 -281.049476) (xy 352.237897 -281.049879) (xy 352.291888 -281.057646)
			(xy 352.344224 -281.073017) (xy 352.39384 -281.09568) (xy 352.439726 -281.125174) (xy 352.480946 -281.160898)
			(xy 352.516663 -281.202124) (xy 352.54615 -281.248014) (xy 352.568805 -281.297634) (xy 352.584168 -281.349972)
			(xy 352.591925 -281.403965) (xy 352.592386 -281.431238) (xy 352.591911 -281.458572) (xy 352.584104 -281.512678)
			(xy 352.568656 -281.565118) (xy 352.545882 -281.614815) (xy 352.516249 -281.660754) (xy 352.49866 -281.681682)
			(xy 352.49231 -281.689048) (xy 352.48596 -281.707336) (xy 352.489262 -281.79522) (xy 352.497136 -281.813)
			(xy 352.503994 -281.819858) (xy 352.525158 -281.841505) (xy 352.561041 -281.890261) (xy 352.588771 -281.944074)
			(xy 352.595104 -281.963368) (xy 357.140762 -281.963368) (xy 357.144835 -281.907709) (xy 357.15697 -281.853236)
			(xy 357.176906 -281.80111) (xy 357.20422 -281.752442) (xy 357.238328 -281.70827) (xy 357.278505 -281.669535)
			(xy 357.323893 -281.637063) (xy 357.373525 -281.611545) (xy 357.426345 -281.593526) (xy 357.481224 -281.583389)
			(xy 357.536995 -281.581351) (xy 357.592469 -281.587454) (xy 357.646462 -281.60157) (xy 357.697825 -281.623397)
			(xy 357.745463 -281.65247) (xy 357.788359 -281.688169) (xy 357.825601 -281.729733) (xy 357.856395 -281.776277)
			(xy 357.880083 -281.826808) (xy 357.896161 -281.88025) (xy 357.904287 -281.935464) (xy 357.904796 -281.963368)
			(xy 357.904287 -281.991272) (xy 357.896161 -282.046486) (xy 357.880083 -282.099928) (xy 357.856395 -282.150459)
			(xy 357.825601 -282.197003) (xy 357.788359 -282.238567) (xy 357.745463 -282.274266) (xy 357.697825 -282.303339)
			(xy 357.646462 -282.325166) (xy 357.592469 -282.339282) (xy 357.536995 -282.345385) (xy 357.481224 -282.343347)
			(xy 357.426345 -282.33321) (xy 357.373525 -282.315191) (xy 357.323893 -282.289673) (xy 357.278505 -282.257201)
			(xy 357.238328 -282.218466) (xy 357.20422 -282.174294) (xy 357.176906 -282.125626) (xy 357.15697 -282.0735)
			(xy 357.144835 -282.019027) (xy 357.140762 -281.963368) (xy 352.595104 -281.963368) (xy 352.607651 -282.001591)
			(xy 352.617208 -282.061369) (xy 352.617786 -282.091638) (xy 352.617277 -282.1193) (xy 352.609305 -282.174046)
			(xy 352.593518 -282.227069) (xy 352.570246 -282.27726) (xy 352.539977 -282.323569) (xy 352.522028 -282.344622)
			(xy 352.513392 -282.35402) (xy 352.50755 -282.378658) (xy 352.534982 -282.484322) (xy 352.552 -282.502864)
			(xy 352.563938 -282.507182) (xy 352.591362 -282.517517) (xy 352.642889 -282.545436) (xy 352.689541 -282.580904)
			(xy 352.730222 -282.623089) (xy 352.763974 -282.670998) (xy 352.790005 -282.723504) (xy 352.807702 -282.779372)
			(xy 352.816648 -282.83729) (xy 352.817176 -282.866592) (xy 352.81669 -282.893872) (xy 353.146294 -282.893872)
			(xy 353.146294 -282.839328) (xy 353.154056 -282.785339) (xy 353.169424 -282.733004) (xy 353.192083 -282.683389)
			(xy 353.221572 -282.637503) (xy 353.257292 -282.596282) (xy 353.298514 -282.560564) (xy 353.344401 -282.531076)
			(xy 353.394017 -282.508419) (xy 353.446352 -282.493053) (xy 353.500342 -282.485293) (xy 353.527614 -282.48483)
			(xy 353.555019 -282.485287) (xy 353.609261 -282.493147) (xy 353.661821 -282.508689) (xy 353.711616 -282.531592)
			(xy 353.75762 -282.561386) (xy 353.778566 -282.579064) (xy 353.785678 -282.58516) (xy 353.802696 -282.59151)
			(xy 353.887532 -282.59151) (xy 353.90455 -282.58516) (xy 353.911662 -282.579064) (xy 353.93261 -282.561393)
			(xy 353.978624 -282.531623) (xy 354.02842 -282.508733) (xy 354.080976 -282.493193) (xy 354.135212 -282.485322)
			(xy 354.162614 -282.48483) (xy 354.189882 -282.485333) (xy 354.243863 -282.493096) (xy 354.29619 -282.508463)
			(xy 354.345797 -282.531119) (xy 354.391675 -282.560605) (xy 354.432891 -282.596319) (xy 354.468604 -282.637536)
			(xy 354.498087 -282.683415) (xy 354.520742 -282.733023) (xy 354.536106 -282.785351) (xy 354.543868 -282.839332)
			(xy 354.543868 -282.893868) (xy 354.542348 -282.904438) (xy 358.922574 -282.904438) (xy 358.923099 -282.876815)
			(xy 358.93104 -282.822144) (xy 358.946776 -282.769187) (xy 358.969978 -282.71905) (xy 359.000163 -282.67278)
			(xy 359.036701 -282.631343) (xy 359.057448 -282.6131) (xy 359.065569 -282.605501) (xy 359.07492 -282.585346)
			(xy 359.075482 -282.574238) (xy 359.075482 -282.497784) (xy 359.074873 -282.48674) (xy 359.065537 -282.466718)
			(xy 359.057448 -282.459176) (xy 359.036713 -282.440919) (xy 359.000176 -282.399481) (xy 358.969987 -282.353214)
			(xy 358.946775 -282.303082) (xy 358.931025 -282.250129) (xy 358.923064 -282.195461) (xy 358.922574 -282.167838)
			(xy 358.923099 -282.140215) (xy 358.93104 -282.085544) (xy 358.946776 -282.032587) (xy 358.969978 -281.98245)
			(xy 359.000163 -281.93618) (xy 359.036701 -281.894743) (xy 359.057448 -281.8765) (xy 359.065531 -281.868952)
			(xy 359.074879 -281.848935) (xy 359.075482 -281.837892) (xy 359.075482 -281.761184) (xy 359.074873 -281.75014)
			(xy 359.065537 -281.730118) (xy 359.057448 -281.722576) (xy 359.036713 -281.704319) (xy 359.000176 -281.662881)
			(xy 358.969987 -281.616614) (xy 358.946775 -281.566482) (xy 358.931025 -281.513529) (xy 358.923064 -281.458861)
			(xy 358.922574 -281.431238) (xy 358.923037 -281.403966) (xy 358.930795 -281.349978) (xy 358.946158 -281.297643)
			(xy 358.968814 -281.248027) (xy 358.998301 -281.202142) (xy 359.034019 -281.16092) (xy 359.07524 -281.125202)
			(xy 359.121125 -281.095715) (xy 359.170741 -281.073059) (xy 359.223076 -281.057695) (xy 359.277064 -281.049937)
			(xy 359.304336 -281.049476) (xy 359.332229 -281.049991) (xy 359.387423 -281.058102) (xy 359.440848 -281.074161)
			(xy 359.491367 -281.097826) (xy 359.537903 -281.128592) (xy 359.579464 -281.165805) (xy 359.615166 -281.208671)
			(xy 359.644248 -281.256277) (xy 359.666091 -281.30761) (xy 359.673652 -281.334464) (xy 359.675938 -281.343608)
			(xy 359.68686 -281.358594) (xy 359.753408 -281.403298) (xy 359.758996 -281.40533) (xy 359.76352 -281.406978)
			(xy 359.772979 -281.408765) (xy 359.777792 -281.408886) (xy 359.783888 -281.408886) (xy 359.78719 -281.408378)
			(xy 359.799768 -281.406819) (xy 359.825062 -281.405164) (xy 359.837736 -281.405076) (xy 359.85041 -281.405175)
			(xy 359.875704 -281.406824) (xy 359.888282 -281.408378) (xy 359.891584 -281.408886) (xy 359.89768 -281.408886)
			(xy 359.905156 -281.408654) (xy 359.919486 -281.404395) (xy 359.925874 -281.400504) (xy 359.988612 -281.358848)
			(xy 359.999534 -281.343608) (xy 360.00182 -281.334464) (xy 360.009421 -281.307624) (xy 360.031268 -281.256298)
			(xy 360.06035 -281.208698) (xy 360.096049 -281.165835) (xy 360.137604 -281.128624) (xy 360.184132 -281.097855)
			(xy 360.234642 -281.074184) (xy 360.288059 -281.058115) (xy 360.343245 -281.049989) (xy 360.371136 -281.049476)
			(xy 360.39841 -281.049868) (xy 360.452401 -281.057636) (xy 360.504737 -281.073009) (xy 360.554353 -281.095673)
			(xy 360.600238 -281.125168) (xy 360.641459 -281.160893) (xy 360.677176 -281.202121) (xy 360.706662 -281.248012)
			(xy 360.729317 -281.297632) (xy 360.74468 -281.349971) (xy 360.752437 -281.403964) (xy 360.752898 -281.431238)
			(xy 360.75242 -281.458571) (xy 360.744613 -281.512678) (xy 360.729165 -281.565117) (xy 360.706393 -281.614815)
			(xy 360.676761 -281.660754) (xy 360.659172 -281.681682) (xy 360.652822 -281.689048) (xy 360.646472 -281.707336)
			(xy 360.649774 -281.79522) (xy 360.657648 -281.813) (xy 360.664506 -281.819858) (xy 360.685672 -281.841503)
			(xy 360.721554 -281.89026) (xy 360.749283 -281.944073) (xy 360.755616 -281.963368) (xy 365.301274 -281.963368)
			(xy 365.305347 -281.907709) (xy 365.317482 -281.853236) (xy 365.337418 -281.80111) (xy 365.364732 -281.752442)
			(xy 365.39884 -281.70827) (xy 365.439017 -281.669535) (xy 365.484405 -281.637063) (xy 365.534037 -281.611545)
			(xy 365.586857 -281.593526) (xy 365.641736 -281.583389) (xy 365.697507 -281.581351) (xy 365.752981 -281.587454)
			(xy 365.806974 -281.60157) (xy 365.858337 -281.623397) (xy 365.905975 -281.65247) (xy 365.948871 -281.688169)
			(xy 365.986113 -281.729733) (xy 366.016907 -281.776277) (xy 366.040595 -281.826808) (xy 366.041331 -281.829256)
			(xy 374.111518 -281.829256) (xy 374.115589 -281.773634) (xy 374.127715 -281.719197) (xy 374.147638 -281.667106)
			(xy 374.174934 -281.618471) (xy 374.20902 -281.574328) (xy 374.249169 -281.535619) (xy 374.294527 -281.503168)
			(xy 374.344127 -281.477667) (xy 374.396911 -281.45966) (xy 374.451754 -281.44953) (xy 374.507488 -281.447493)
			(xy 374.562925 -281.453593) (xy 374.616882 -281.467699) (xy 374.668211 -281.489511) (xy 374.715817 -281.518565)
			(xy 374.758685 -281.55424) (xy 374.795902 -281.595777) (xy 374.826675 -281.64229) (xy 374.850347 -281.692787)
			(xy 374.866415 -281.746194) (xy 374.874535 -281.80137) (xy 374.875044 -281.829256) (xy 375.596656 -281.829256)
			(xy 375.600727 -281.773634) (xy 375.612853 -281.719197) (xy 375.632776 -281.667106) (xy 375.660072 -281.618471)
			(xy 375.694158 -281.574328) (xy 375.734307 -281.535619) (xy 375.779665 -281.503168) (xy 375.829265 -281.477667)
			(xy 375.882049 -281.45966) (xy 375.936892 -281.44953) (xy 375.992626 -281.447493) (xy 376.048063 -281.453593)
			(xy 376.10202 -281.467699) (xy 376.153349 -281.489511) (xy 376.200955 -281.518565) (xy 376.243823 -281.55424)
			(xy 376.28104 -281.595777) (xy 376.311813 -281.64229) (xy 376.335485 -281.692787) (xy 376.351553 -281.746194)
			(xy 376.359673 -281.80137) (xy 376.360182 -281.829256) (xy 376.359673 -281.857142) (xy 376.351553 -281.912318)
			(xy 376.335485 -281.965725) (xy 376.311813 -282.016222) (xy 376.28104 -282.062735) (xy 376.243823 -282.104272)
			(xy 376.200955 -282.139947) (xy 376.153349 -282.169001) (xy 376.10202 -282.190813) (xy 376.048063 -282.204919)
			(xy 375.992626 -282.211019) (xy 375.936892 -282.208982) (xy 375.882049 -282.198852) (xy 375.829265 -282.180845)
			(xy 375.779665 -282.155344) (xy 375.734307 -282.122893) (xy 375.694158 -282.084184) (xy 375.660072 -282.040041)
			(xy 375.632776 -281.991406) (xy 375.612853 -281.939315) (xy 375.600727 -281.884878) (xy 375.596656 -281.829256)
			(xy 374.875044 -281.829256) (xy 374.874535 -281.857142) (xy 374.866415 -281.912318) (xy 374.850347 -281.965725)
			(xy 374.826675 -282.016222) (xy 374.795902 -282.062735) (xy 374.758685 -282.104272) (xy 374.715817 -282.139947)
			(xy 374.668211 -282.169001) (xy 374.616882 -282.190813) (xy 374.562925 -282.204919) (xy 374.507488 -282.211019)
			(xy 374.451754 -282.208982) (xy 374.396911 -282.198852) (xy 374.344127 -282.180845) (xy 374.294527 -282.155344)
			(xy 374.249169 -282.122893) (xy 374.20902 -282.084184) (xy 374.174934 -282.040041) (xy 374.147638 -281.991406)
			(xy 374.127715 -281.939315) (xy 374.115589 -281.884878) (xy 374.111518 -281.829256) (xy 366.041331 -281.829256)
			(xy 366.056673 -281.88025) (xy 366.064799 -281.935464) (xy 366.065308 -281.963368) (xy 366.064799 -281.991272)
			(xy 366.056673 -282.046486) (xy 366.040595 -282.099928) (xy 366.016907 -282.150459) (xy 365.986113 -282.197003)
			(xy 365.948871 -282.238567) (xy 365.905975 -282.274266) (xy 365.858337 -282.303339) (xy 365.806974 -282.325166)
			(xy 365.752981 -282.339282) (xy 365.697507 -282.345385) (xy 365.641736 -282.343347) (xy 365.586857 -282.33321)
			(xy 365.534037 -282.315191) (xy 365.484405 -282.289673) (xy 365.439017 -282.257201) (xy 365.39884 -282.218466)
			(xy 365.364732 -282.174294) (xy 365.337418 -282.125626) (xy 365.317482 -282.0735) (xy 365.305347 -282.019027)
			(xy 365.301274 -281.963368) (xy 360.755616 -281.963368) (xy 360.768163 -282.001591) (xy 360.77772 -282.061369)
			(xy 360.778298 -282.091638) (xy 360.777786 -282.1193) (xy 360.769814 -282.174046) (xy 360.754027 -282.227069)
			(xy 360.730757 -282.277259) (xy 360.700488 -282.323568) (xy 360.68254 -282.344622) (xy 360.673904 -282.35402)
			(xy 360.668062 -282.378658) (xy 360.695494 -282.484322) (xy 360.712512 -282.502864) (xy 360.72445 -282.507182)
			(xy 360.751876 -282.51751) (xy 360.803403 -282.545431) (xy 360.850055 -282.580901) (xy 360.890735 -282.623086)
			(xy 360.924487 -282.670996) (xy 360.950517 -282.723502) (xy 360.968214 -282.779372) (xy 360.97716 -282.837289)
			(xy 360.977688 -282.866592) (xy 360.977201 -282.893873) (xy 361.306794 -282.893873) (xy 361.306794 -282.839327)
			(xy 361.314557 -282.785337) (xy 361.329924 -282.733001) (xy 361.352584 -282.683385) (xy 361.382075 -282.637499)
			(xy 361.417796 -282.596278) (xy 361.45902 -282.560559) (xy 361.504908 -282.531072) (xy 361.554526 -282.508415)
			(xy 361.606862 -282.493051) (xy 361.660853 -282.485292) (xy 361.688126 -282.48483) (xy 361.715529 -282.485339)
			(xy 361.769769 -282.493186) (xy 361.822329 -282.508716) (xy 361.872124 -282.531608) (xy 361.918131 -282.561391)
			(xy 361.939078 -282.579064) (xy 361.94619 -282.58516) (xy 361.963208 -282.59151) (xy 362.048044 -282.59151)
			(xy 362.065062 -282.58516) (xy 362.072174 -282.579064) (xy 362.093117 -282.561387) (xy 362.139133 -282.531618)
			(xy 362.18893 -282.508729) (xy 362.241486 -282.493191) (xy 362.295724 -282.485321) (xy 362.323126 -282.48483)
			(xy 362.350394 -282.485334) (xy 362.404373 -282.493099) (xy 362.456699 -282.508466) (xy 362.506304 -282.531123)
			(xy 362.552181 -282.560609) (xy 362.593395 -282.596324) (xy 362.629106 -282.63754) (xy 362.658589 -282.683418)
			(xy 362.681243 -282.733026) (xy 362.696607 -282.785352) (xy 362.704368 -282.839332) (xy 362.704368 -282.893868)
			(xy 362.696607 -282.947848) (xy 362.681243 -283.000174) (xy 362.658589 -283.049782) (xy 362.629106 -283.09566)
			(xy 362.593395 -283.136876) (xy 362.552181 -283.172591) (xy 362.506304 -283.202077) (xy 362.456699 -283.224734)
			(xy 362.404373 -283.240101) (xy 362.350394 -283.247866) (xy 362.323126 -283.248354) (xy 362.295722 -283.247877)
			(xy 362.24148 -283.240023) (xy 362.18892 -283.224486) (xy 362.139125 -283.201587) (xy 362.09312 -283.171797)
			(xy 362.072174 -283.15412) (xy 362.065062 -283.148024) (xy 362.048044 -283.141674) (xy 361.963208 -283.141674)
			(xy 361.94619 -283.148024) (xy 361.939078 -283.15412) (xy 361.918126 -283.171786) (xy 361.872111 -283.201554)
			(xy 361.822316 -283.224443) (xy 361.769762 -283.239984) (xy 361.715527 -283.247859) (xy 361.688126 -283.248354)
			(xy 361.660853 -283.247908) (xy 361.606862 -283.240149) (xy 361.554526 -283.224785) (xy 361.504908 -283.202128)
			(xy 361.45902 -283.172641) (xy 361.417796 -283.136922) (xy 361.382075 -283.095701) (xy 361.352584 -283.049815)
			(xy 361.329924 -283.000199) (xy 361.314557 -282.947863) (xy 361.306794 -282.893873) (xy 360.977201 -282.893873)
			(xy 360.977184 -282.894826) (xy 360.968898 -282.950682) (xy 360.961178 -282.977844) (xy 360.958892 -282.98521)
			(xy 360.958892 -283.003752) (xy 360.959135 -283.010412) (xy 360.962608 -283.023275) (xy 360.96575 -283.029152)
			(xy 360.966004 -283.02966) (xy 361.00766 -283.100018) (xy 361.02544 -283.112718) (xy 361.036362 -283.11475)
			(xy 361.062199 -283.12009) (xy 361.112155 -283.137065) (xy 361.159297 -283.160758) (xy 361.202727 -283.190717)
			(xy 361.241617 -283.226372) (xy 361.275227 -283.267043) (xy 361.302916 -283.311955) (xy 361.324155 -283.360252)
			(xy 361.338542 -283.411014) (xy 361.342232 -283.437584) (xy 366.232948 -283.437584) (xy 366.233434 -283.410315)
			(xy 366.241196 -283.356331) (xy 366.256561 -283.304001) (xy 366.279218 -283.254391) (xy 366.308704 -283.20851)
			(xy 366.344419 -283.167293) (xy 366.385636 -283.131578) (xy 366.431517 -283.102092) (xy 366.481127 -283.079435)
			(xy 366.533457 -283.06407) (xy 366.587441 -283.056308) (xy 366.641979 -283.056308) (xy 366.695963 -283.06407)
			(xy 366.748293 -283.079435) (xy 366.797903 -283.102092) (xy 366.843784 -283.131578) (xy 366.885001 -283.167293)
			(xy 366.920716 -283.20851) (xy 366.950202 -283.254391) (xy 366.972859 -283.304001) (xy 366.988224 -283.356331)
			(xy 366.995986 -283.410315) (xy 366.996472 -283.437584) (xy 366.995997 -283.464988) (xy 366.988141 -283.51923)
			(xy 366.972604 -283.57179) (xy 366.949704 -283.621585) (xy 366.919914 -283.66759) (xy 366.902238 -283.688536)
			(xy 366.896142 -283.695648) (xy 366.889792 -283.712666) (xy 366.889792 -283.788612) (xy 366.890145 -283.797629)
			(xy 366.896396 -283.814546) (xy 366.901984 -283.821632) (xy 366.902238 -283.821886) (xy 366.902492 -283.82214)
			(xy 366.920069 -283.843079) (xy 366.94971 -283.889012) (xy 366.972489 -283.938706) (xy 366.987941 -283.991144)
			(xy 366.995748 -284.045251) (xy 366.996218 -284.072584) (xy 366.995732 -284.099835) (xy 366.990228 -284.138116)
			(xy 373.346978 -284.138116) (xy 373.351049 -284.082494) (xy 373.363175 -284.028057) (xy 373.383098 -283.975966)
			(xy 373.410394 -283.927331) (xy 373.44448 -283.883188) (xy 373.484629 -283.844479) (xy 373.529987 -283.812028)
			(xy 373.579587 -283.786527) (xy 373.632371 -283.76852) (xy 373.687214 -283.75839) (xy 373.742948 -283.756353)
			(xy 373.798385 -283.762453) (xy 373.852342 -283.776559) (xy 373.903671 -283.798371) (xy 373.951277 -283.827425)
			(xy 373.994145 -283.8631) (xy 374.021396 -283.893514) (xy 379.638052 -283.893514) (xy 379.638589 -283.864741)
			(xy 379.647262 -283.807851) (xy 379.664397 -283.752915) (xy 379.689605 -283.701183) (xy 379.722311 -283.653834)
			(xy 379.76177 -283.611946) (xy 379.784102 -283.593794) (xy 379.784356 -283.59354) (xy 379.79096 -283.588206)
			(xy 379.799303 -283.580707) (xy 379.809064 -283.56054) (xy 379.809756 -283.549344) (xy 379.811026 -283.457396)
			(xy 379.80112 -283.436314) (xy 379.791976 -283.428948) (xy 379.770116 -283.410756) (xy 379.731578 -283.368934)
			(xy 379.699673 -283.321855) (xy 379.675108 -283.270563) (xy 379.658427 -283.216193) (xy 379.65 -283.15995)
			(xy 379.649482 -283.131514) (xy 379.649968 -283.104262) (xy 379.657723 -283.050312) (xy 379.673077 -282.998016)
			(xy 379.695717 -282.948436) (xy 379.725183 -282.902583) (xy 379.760874 -282.861391) (xy 379.802064 -282.825697)
			(xy 379.847915 -282.796229) (xy 379.897493 -282.773585) (xy 379.949789 -282.758228) (xy 380.003738 -282.75047)
			(xy 380.03099 -282.750006) (xy 380.058243 -282.750465) (xy 380.112195 -282.758221) (xy 380.164494 -282.773576)
			(xy 380.214075 -282.796218) (xy 380.259929 -282.825687) (xy 380.301122 -282.861381) (xy 380.336816 -282.902574)
			(xy 380.366283 -282.948429) (xy 380.388925 -282.99801) (xy 380.40428 -283.050309) (xy 380.412036 -283.104261)
			(xy 380.412498 -283.131514) (xy 380.412 -283.160289) (xy 380.403322 -283.217181) (xy 380.38618 -283.272119)
			(xy 380.360965 -283.323851) (xy 380.328251 -283.371199) (xy 380.288784 -283.413085) (xy 380.266448 -283.431234)
			(xy 380.266194 -283.431488) (xy 380.25959 -283.436822) (xy 380.251226 -283.444301) (xy 380.241479 -283.464483)
			(xy 380.240794 -283.475684) (xy 380.239524 -283.567632) (xy 380.24943 -283.588714) (xy 380.258574 -283.59608)
			(xy 380.280389 -283.614324) (xy 380.318933 -283.656134) (xy 380.350844 -283.703201) (xy 380.375417 -283.754484)
			(xy 380.392107 -283.808845) (xy 380.400545 -283.865081) (xy 380.401068 -283.893514) (xy 381.034542 -283.893514)
			(xy 381.038613 -283.837892) (xy 381.050739 -283.783455) (xy 381.070662 -283.731364) (xy 381.097958 -283.682729)
			(xy 381.132044 -283.638586) (xy 381.172193 -283.599877) (xy 381.217551 -283.567426) (xy 381.267151 -283.541925)
			(xy 381.319935 -283.523918) (xy 381.374778 -283.513788) (xy 381.430512 -283.511751) (xy 381.485949 -283.517851)
			(xy 381.539906 -283.531957) (xy 381.591235 -283.553769) (xy 381.638841 -283.582823) (xy 381.681709 -283.618498)
			(xy 381.718926 -283.660035) (xy 381.749699 -283.706548) (xy 381.773371 -283.757045) (xy 381.789439 -283.810452)
			(xy 381.797559 -283.865628) (xy 381.798068 -283.893514) (xy 381.797559 -283.9214) (xy 381.789439 -283.976576)
			(xy 381.773371 -284.029983) (xy 381.749699 -284.08048) (xy 381.718926 -284.126993) (xy 381.681709 -284.16853)
			(xy 381.638841 -284.204205) (xy 381.591235 -284.233259) (xy 381.539906 -284.255071) (xy 381.485949 -284.269177)
			(xy 381.430512 -284.275277) (xy 381.374778 -284.27324) (xy 381.319935 -284.26311) (xy 381.267151 -284.245103)
			(xy 381.217551 -284.219602) (xy 381.172193 -284.187151) (xy 381.132044 -284.148442) (xy 381.097958 -284.104299)
			(xy 381.070662 -284.055664) (xy 381.050739 -284.003573) (xy 381.038613 -283.949136) (xy 381.034542 -283.893514)
			(xy 380.401068 -283.893514) (xy 380.400658 -283.920769) (xy 380.392898 -283.974724) (xy 380.377538 -284.027025)
			(xy 380.354891 -284.076608) (xy 380.325418 -284.122463) (xy 380.289719 -284.163657) (xy 380.24852 -284.19935)
			(xy 380.202661 -284.228817) (xy 380.153075 -284.251457) (xy 380.100771 -284.26681) (xy 380.046815 -284.274562)
			(xy 380.01956 -284.275022) (xy 379.992308 -284.274559) (xy 379.938361 -284.266798) (xy 379.886066 -284.251438)
			(xy 379.83649 -284.228794) (xy 379.79064 -284.199324) (xy 379.749451 -284.163631) (xy 379.71376 -284.122439)
			(xy 379.684294 -284.076587) (xy 379.661653 -284.027009) (xy 379.646297 -283.974714) (xy 379.638539 -283.920766)
			(xy 379.638052 -283.893514) (xy 374.021396 -283.893514) (xy 374.031362 -283.904637) (xy 374.062135 -283.95115)
			(xy 374.085807 -284.001647) (xy 374.101875 -284.055054) (xy 374.109995 -284.11023) (xy 374.110504 -284.138116)
			(xy 374.109995 -284.166002) (xy 374.101875 -284.221178) (xy 374.085807 -284.274585) (xy 374.062135 -284.325082)
			(xy 374.031362 -284.371595) (xy 373.994145 -284.413132) (xy 373.951277 -284.448807) (xy 373.903671 -284.477861)
			(xy 373.852342 -284.499673) (xy 373.798385 -284.513779) (xy 373.742948 -284.519879) (xy 373.687214 -284.517842)
			(xy 373.632371 -284.507712) (xy 373.579587 -284.489705) (xy 373.529987 -284.464204) (xy 373.484629 -284.431753)
			(xy 373.44448 -284.393044) (xy 373.410394 -284.348901) (xy 373.383098 -284.300266) (xy 373.363175 -284.248175)
			(xy 373.351049 -284.193738) (xy 373.346978 -284.138116) (xy 366.990228 -284.138116) (xy 366.987976 -284.153783)
			(xy 366.972621 -284.206078) (xy 366.949979 -284.255655) (xy 366.920513 -284.301505) (xy 366.884822 -284.342696)
			(xy 366.843631 -284.378387) (xy 366.797781 -284.407853) (xy 366.748204 -284.430495) (xy 366.695909 -284.44585)
			(xy 366.641961 -284.453606) (xy 366.587459 -284.453606) (xy 366.533511 -284.44585) (xy 366.481216 -284.430495)
			(xy 366.431639 -284.407853) (xy 366.385789 -284.378387) (xy 366.344598 -284.342696) (xy 366.308907 -284.301505)
			(xy 366.279441 -284.255655) (xy 366.256799 -284.206078) (xy 366.241444 -284.153783) (xy 366.233688 -284.099835)
			(xy 366.233202 -284.072584) (xy 366.233693 -284.045251) (xy 366.241497 -283.991145) (xy 366.256941 -283.938706)
			(xy 366.279711 -283.889008) (xy 366.30934 -283.843068) (xy 366.326928 -283.82214) (xy 366.327182 -283.821886)
			(xy 366.327436 -283.821632) (xy 366.333019 -283.814543) (xy 366.339267 -283.797628) (xy 366.339628 -283.788612)
			(xy 366.339628 -283.712666) (xy 366.333278 -283.695648) (xy 366.327182 -283.688536) (xy 366.309497 -283.667599)
			(xy 366.279732 -283.621581) (xy 366.256846 -283.571782) (xy 366.241309 -283.519224) (xy 366.23344 -283.464987)
			(xy 366.232948 -283.437584) (xy 361.342232 -283.437584) (xy 361.3458 -283.463273) (xy 361.346242 -283.489654)
			(xy 361.345645 -283.519764) (xy 361.336204 -283.579239) (xy 361.317549 -283.636496) (xy 361.290141 -283.690117)
			(xy 361.254659 -283.738774) (xy 361.23372 -283.760418) (xy 361.226354 -283.76753) (xy 361.218226 -283.787596)
			(xy 361.218226 -283.797756) (xy 361.218226 -283.878782) (xy 361.2261 -283.897578) (xy 361.233212 -283.90469)
			(xy 361.254215 -283.926294) (xy 361.28978 -283.974929) (xy 361.317255 -284.02855) (xy 361.335958 -284.085825)
			(xy 361.345423 -284.145328) (xy 361.345988 -284.175454) (xy 361.345502 -284.202705) (xy 361.337746 -284.256653)
			(xy 361.322391 -284.308948) (xy 361.299749 -284.358525) (xy 361.270283 -284.404375) (xy 361.234592 -284.445566)
			(xy 361.193401 -284.481257) (xy 361.147551 -284.510723) (xy 361.097974 -284.533365) (xy 361.045679 -284.54872)
			(xy 360.991731 -284.556476) (xy 360.937229 -284.556476) (xy 360.883281 -284.54872) (xy 360.830986 -284.533365)
			(xy 360.781409 -284.510723) (xy 360.735559 -284.481257) (xy 360.694368 -284.445566) (xy 360.658677 -284.404375)
			(xy 360.629211 -284.358525) (xy 360.606569 -284.308948) (xy 360.591214 -284.256653) (xy 360.583458 -284.202705)
			(xy 360.582972 -284.175454) (xy 360.583567 -284.145498) (xy 360.592951 -284.086326) (xy 360.61148 -284.029352)
			(xy 360.638698 -283.97598) (xy 360.673934 -283.927526) (xy 360.694732 -283.90596) (xy 360.698796 -283.901896)
			(xy 360.704384 -283.893006) (xy 360.710734 -283.877512) (xy 360.710734 -283.867352) (xy 360.710734 -283.78658)
			(xy 360.70286 -283.768038) (xy 360.695748 -283.760672) (xy 360.674707 -283.739055) (xy 360.639063 -283.69039)
			(xy 360.611523 -283.636722) (xy 360.592775 -283.579387) (xy 360.583286 -283.519815) (xy 360.582718 -283.489654)
			(xy 360.583209 -283.46142) (xy 360.591503 -283.405564) (xy 360.599228 -283.378402) (xy 360.601514 -283.371036)
			(xy 360.601514 -283.352494) (xy 360.60129 -283.345832) (xy 360.597804 -283.33297) (xy 360.594656 -283.327094)
			(xy 360.594402 -283.326586) (xy 360.552746 -283.256228) (xy 360.534966 -283.243528) (xy 360.524044 -283.241496)
			(xy 360.496157 -283.23562) (xy 360.44239 -283.216735) (xy 360.39203 -283.19006) (xy 360.3462 -283.15619)
			(xy 360.305919 -283.115878) (xy 360.272084 -283.070022) (xy 360.245448 -283.019643) (xy 360.226604 -282.965861)
			(xy 360.220768 -282.937966) (xy 360.218482 -282.925266) (xy 360.202988 -282.905962) (xy 360.103674 -282.862528)
			(xy 360.078782 -282.86456) (xy 360.06786 -282.871418) (xy 360.044788 -282.885483) (xy 359.995537 -282.907706)
			(xy 359.943647 -282.922773) (xy 359.890153 -282.930386) (xy 359.863136 -282.930854) (xy 359.85958 -282.930854)
			(xy 359.846118 -282.930346) (xy 359.829919 -282.929444) (xy 359.797744 -282.925248) (xy 359.781856 -282.921964)
			(xy 359.771696 -282.923996) (xy 359.767122 -282.924981) (xy 359.758428 -282.928434) (xy 359.754424 -282.930854)
			(xy 359.69956 -282.965906) (xy 359.698544 -282.966414) (xy 359.687368 -282.974034) (xy 359.6767 -282.989274)
			(xy 359.674414 -282.998418) (xy 359.666963 -283.02581) (xy 359.645004 -283.078158) (xy 359.615536 -283.126677)
			(xy 359.579208 -283.170298) (xy 359.536822 -283.208059) (xy 359.489312 -283.239128) (xy 359.437725 -283.262819)
			(xy 359.383199 -283.278611) (xy 359.355136 -283.282898) (xy 359.342496 -283.284474) (xy 359.317074 -283.286124)
			(xy 359.304336 -283.2862) (xy 359.277069 -283.285642) (xy 359.22309 -283.277886) (xy 359.170764 -283.262528)
			(xy 359.121157 -283.239878) (xy 359.075277 -283.2104) (xy 359.03406 -283.174692) (xy 358.998345 -283.133482)
			(xy 358.968857 -283.087608) (xy 358.946198 -283.038005) (xy 358.930829 -282.985682) (xy 358.923063 -282.931705)
			(xy 358.922574 -282.904438) (xy 354.542348 -282.904438) (xy 354.536106 -282.947849) (xy 354.520742 -283.000177)
			(xy 354.498087 -283.049785) (xy 354.468604 -283.095664) (xy 354.432891 -283.136881) (xy 354.391675 -283.172595)
			(xy 354.345797 -283.202081) (xy 354.29619 -283.224737) (xy 354.243863 -283.240104) (xy 354.189882 -283.247867)
			(xy 354.162614 -283.248354) (xy 354.13521 -283.247884) (xy 354.080967 -283.240028) (xy 354.028408 -283.22449)
			(xy 353.978613 -283.201589) (xy 353.932608 -283.171797) (xy 353.911662 -283.15412) (xy 353.90455 -283.148024)
			(xy 353.887532 -283.141674) (xy 353.802696 -283.141674) (xy 353.785678 -283.148024) (xy 353.778566 -283.15412)
			(xy 353.757618 -283.171791) (xy 353.711602 -283.201558) (xy 353.661806 -283.224447) (xy 353.609252 -283.239987)
			(xy 353.555016 -283.24786) (xy 353.527614 -283.248354) (xy 353.500342 -283.247907) (xy 353.446352 -283.240147)
			(xy 353.394017 -283.224781) (xy 353.344401 -283.202124) (xy 353.298514 -283.172636) (xy 353.257292 -283.136918)
			(xy 353.221572 -283.095697) (xy 353.192083 -283.049811) (xy 353.169424 -283.000196) (xy 353.154056 -282.947861)
			(xy 353.146294 -282.893872) (xy 352.81669 -282.893872) (xy 352.816673 -282.894826) (xy 352.808386 -282.950682)
			(xy 352.800666 -282.977844) (xy 352.79838 -282.98521) (xy 352.79838 -283.003752) (xy 352.798625 -283.010412)
			(xy 352.802096 -283.023274) (xy 352.805238 -283.029152) (xy 352.805492 -283.02966) (xy 352.847148 -283.100018)
			(xy 352.864928 -283.112718) (xy 352.87585 -283.11475) (xy 352.901685 -283.120099) (xy 352.951641 -283.137072)
			(xy 352.998783 -283.160764) (xy 353.042214 -283.190722) (xy 353.081104 -283.226376) (xy 353.114714 -283.267046)
			(xy 353.142403 -283.311957) (xy 353.163643 -283.360253) (xy 353.17803 -283.411015) (xy 353.18172 -283.437584)
			(xy 358.072436 -283.437584) (xy 358.072922 -283.410315) (xy 358.080684 -283.356331) (xy 358.096049 -283.304001)
			(xy 358.118706 -283.254391) (xy 358.148192 -283.20851) (xy 358.183907 -283.167293) (xy 358.225124 -283.131578)
			(xy 358.271005 -283.102092) (xy 358.320615 -283.079435) (xy 358.372945 -283.06407) (xy 358.426929 -283.056308)
			(xy 358.481467 -283.056308) (xy 358.535451 -283.06407) (xy 358.587781 -283.079435) (xy 358.637391 -283.102092)
			(xy 358.683272 -283.131578) (xy 358.724489 -283.167293) (xy 358.760204 -283.20851) (xy 358.78969 -283.254391)
			(xy 358.812347 -283.304001) (xy 358.827712 -283.356331) (xy 358.835474 -283.410315) (xy 358.83596 -283.437584)
			(xy 358.835488 -283.464988) (xy 358.827632 -283.51923) (xy 358.812094 -283.57179) (xy 358.789194 -283.621585)
			(xy 358.759403 -283.66759) (xy 358.741726 -283.688536) (xy 358.73563 -283.695648) (xy 358.72928 -283.712666)
			(xy 358.72928 -283.788612) (xy 358.729636 -283.797629) (xy 358.735885 -283.814546) (xy 358.741472 -283.821632)
			(xy 358.741726 -283.821886) (xy 358.74198 -283.82214) (xy 358.759555 -283.84308) (xy 358.789196 -283.889013)
			(xy 358.811977 -283.938707) (xy 358.827428 -283.991144) (xy 358.835235 -284.045251) (xy 358.835706 -284.072584)
			(xy 358.83522 -284.099835) (xy 358.827464 -284.153783) (xy 358.812109 -284.206078) (xy 358.789467 -284.255655)
			(xy 358.760001 -284.301505) (xy 358.72431 -284.342696) (xy 358.683119 -284.378387) (xy 358.637269 -284.407853)
			(xy 358.587692 -284.430495) (xy 358.535397 -284.44585) (xy 358.481449 -284.453606) (xy 358.426947 -284.453606)
			(xy 358.372999 -284.44585) (xy 358.320704 -284.430495) (xy 358.271127 -284.407853) (xy 358.225277 -284.378387)
			(xy 358.184086 -284.342696) (xy 358.148395 -284.301505) (xy 358.118929 -284.255655) (xy 358.096287 -284.206078)
			(xy 358.080932 -284.153783) (xy 358.073176 -284.099835) (xy 358.07269 -284.072584) (xy 358.073184 -284.045251)
			(xy 358.080987 -283.991145) (xy 358.096432 -283.938707) (xy 358.119201 -283.889009) (xy 358.148829 -283.843068)
			(xy 358.166416 -283.82214) (xy 358.16667 -283.821886) (xy 358.166924 -283.821632) (xy 358.172506 -283.814542)
			(xy 358.178755 -283.797628) (xy 358.179116 -283.788612) (xy 358.179116 -283.712666) (xy 358.172766 -283.695648)
			(xy 358.16667 -283.688536) (xy 358.148983 -283.667601) (xy 358.119219 -283.621581) (xy 358.096334 -283.571782)
			(xy 358.080797 -283.519225) (xy 358.072928 -283.464987) (xy 358.072436 -283.437584) (xy 353.18172 -283.437584)
			(xy 353.185288 -283.463274) (xy 353.18573 -283.489654) (xy 353.185137 -283.519764) (xy 353.175696 -283.579239)
			(xy 353.157039 -283.636497) (xy 353.129631 -283.690118) (xy 353.094148 -283.738774) (xy 353.073208 -283.760418)
			(xy 353.065842 -283.76753) (xy 353.057714 -283.787596) (xy 353.057714 -283.797756) (xy 353.057714 -283.878782)
			(xy 353.065588 -283.897578) (xy 353.0727 -283.90469) (xy 353.093701 -283.926296) (xy 353.129266 -283.97493)
			(xy 353.156743 -284.028551) (xy 353.175446 -284.085826) (xy 353.184911 -284.145328) (xy 353.185476 -284.175454)
			(xy 353.18499 -284.202705) (xy 353.177234 -284.256653) (xy 353.161879 -284.308948) (xy 353.139237 -284.358525)
			(xy 353.109771 -284.404375) (xy 353.07408 -284.445566) (xy 353.032889 -284.481257) (xy 352.987039 -284.510723)
			(xy 352.937462 -284.533365) (xy 352.885167 -284.54872) (xy 352.831219 -284.556476) (xy 352.776717 -284.556476)
			(xy 352.722769 -284.54872) (xy 352.670474 -284.533365) (xy 352.620897 -284.510723) (xy 352.575047 -284.481257)
			(xy 352.533856 -284.445566) (xy 352.498165 -284.404375) (xy 352.468699 -284.358525) (xy 352.446057 -284.308948)
			(xy 352.430702 -284.256653) (xy 352.422946 -284.202705) (xy 352.42246 -284.175454) (xy 352.423029 -284.145497)
			(xy 352.432416 -284.086323) (xy 352.450949 -284.029347) (xy 352.478174 -283.975976) (xy 352.513418 -283.927524)
			(xy 352.53422 -283.90596) (xy 352.538284 -283.901896) (xy 352.543872 -283.893006) (xy 352.550222 -283.877512)
			(xy 352.550222 -283.867352) (xy 352.550222 -283.78658) (xy 352.542348 -283.768038) (xy 352.535236 -283.760672)
			(xy 352.514193 -283.739057) (xy 352.478549 -283.690392) (xy 352.45101 -283.636722) (xy 352.432263 -283.579387)
			(xy 352.422774 -283.519815) (xy 352.422206 -283.489654) (xy 352.422698 -283.46142) (xy 352.430992 -283.405564)
			(xy 352.438716 -283.378402) (xy 352.441002 -283.371036) (xy 352.441002 -283.352494) (xy 352.440779 -283.345832)
			(xy 352.437293 -283.33297) (xy 352.434144 -283.327094) (xy 352.43389 -283.326586) (xy 352.392234 -283.256228)
			(xy 352.374454 -283.243528) (xy 352.363532 -283.241496) (xy 352.335643 -283.235628) (xy 352.281876 -283.216742)
			(xy 352.231517 -283.190066) (xy 352.185687 -283.156194) (xy 352.145406 -283.115881) (xy 352.111571 -283.070024)
			(xy 352.084936 -283.019644) (xy 352.066092 -282.965861) (xy 352.060256 -282.937966) (xy 352.05797 -282.92552)
			(xy 352.042222 -282.905962) (xy 351.942908 -282.862528) (xy 351.917762 -282.86456) (xy 351.907094 -282.871418)
			(xy 351.884055 -282.885475) (xy 351.834861 -282.907673) (xy 351.783036 -282.922737) (xy 351.729609 -282.930368)
			(xy 351.702624 -282.930854) (xy 351.669096 -282.92933) (xy 351.65792 -282.92806) (xy 351.630742 -282.923742)
			(xy 351.62109 -282.921964) (xy 351.602294 -282.92552) (xy 351.539048 -282.965906) (xy 351.538032 -282.966414)
			(xy 351.526856 -282.974034) (xy 351.516188 -282.989274) (xy 351.513902 -282.998418) (xy 351.506525 -283.025491)
			(xy 351.484887 -283.077264) (xy 351.455906 -283.125313) (xy 351.420205 -283.168605) (xy 351.378555 -283.206206)
			(xy 351.33185 -283.237308) (xy 351.281097 -283.26124) (xy 351.227389 -283.277489) (xy 351.17188 -283.285703)
			(xy 351.143824 -283.2862) (xy 351.116557 -283.285653) (xy 351.062577 -283.277896) (xy 351.010251 -283.262536)
			(xy 350.960644 -283.239885) (xy 350.914765 -283.210405) (xy 350.873548 -283.174696) (xy 350.837832 -283.133485)
			(xy 350.808345 -283.087611) (xy 350.785686 -283.038007) (xy 350.770317 -282.985683) (xy 350.762551 -282.931705)
			(xy 350.762062 -282.904438) (xy 346.043748 -282.904438) (xy 346.037507 -282.947848) (xy 346.022143 -283.000174)
			(xy 345.99949 -283.049781) (xy 345.970007 -283.09566) (xy 345.934295 -283.136876) (xy 345.893082 -283.17259)
			(xy 345.847206 -283.202076) (xy 345.7976 -283.224733) (xy 345.745275 -283.240101) (xy 345.691295 -283.247866)
			(xy 345.664028 -283.248354) (xy 345.636624 -283.247876) (xy 345.582382 -283.240022) (xy 345.529822 -283.224485)
			(xy 345.480027 -283.201586) (xy 345.434022 -283.171797) (xy 345.413076 -283.15412) (xy 345.405964 -283.148024)
			(xy 345.388946 -283.141674) (xy 345.30411 -283.141674) (xy 345.287092 -283.148024) (xy 345.27998 -283.15412)
			(xy 345.259027 -283.171785) (xy 345.213013 -283.201553) (xy 345.163218 -283.224442) (xy 345.110664 -283.239984)
			(xy 345.056429 -283.247859) (xy 345.029028 -283.248354) (xy 345.001755 -283.247908) (xy 344.947764 -283.240149)
			(xy 344.895427 -283.224785) (xy 344.845809 -283.202129) (xy 344.799921 -283.172641) (xy 344.758697 -283.136923)
			(xy 344.722976 -283.095701) (xy 344.693485 -283.049815) (xy 344.670825 -283.000199) (xy 344.655457 -282.947863)
			(xy 344.647694 -282.893873) (xy 344.318104 -282.893873) (xy 344.318087 -282.894826) (xy 344.309801 -282.950682)
			(xy 344.30208 -282.977844) (xy 344.299794 -282.98521) (xy 344.299794 -283.003752) (xy 344.300037 -283.010412)
			(xy 344.303509 -283.023275) (xy 344.306652 -283.029152) (xy 344.306906 -283.02966) (xy 344.348562 -283.100018)
			(xy 344.366342 -283.112718) (xy 344.377264 -283.11475) (xy 344.403102 -283.120088) (xy 344.453057 -283.137064)
			(xy 344.500199 -283.160757) (xy 344.543629 -283.190717) (xy 344.58252 -283.226372) (xy 344.616129 -283.267043)
			(xy 344.643818 -283.311955) (xy 344.665058 -283.360252) (xy 344.679444 -283.411014) (xy 344.683134 -283.437584)
			(xy 349.57385 -283.437584) (xy 349.574336 -283.410315) (xy 349.582098 -283.356331) (xy 349.597463 -283.304001)
			(xy 349.62012 -283.254391) (xy 349.649606 -283.20851) (xy 349.685321 -283.167293) (xy 349.726538 -283.131578)
			(xy 349.772419 -283.102092) (xy 349.822029 -283.079435) (xy 349.874359 -283.06407) (xy 349.928343 -283.056308)
			(xy 349.982881 -283.056308) (xy 350.036865 -283.06407) (xy 350.089195 -283.079435) (xy 350.138805 -283.102092)
			(xy 350.184686 -283.131578) (xy 350.225903 -283.167293) (xy 350.261618 -283.20851) (xy 350.291104 -283.254391)
			(xy 350.313761 -283.304001) (xy 350.329126 -283.356331) (xy 350.336888 -283.410315) (xy 350.337374 -283.437584)
			(xy 350.336898 -283.464988) (xy 350.329043 -283.51923) (xy 350.313505 -283.571789) (xy 350.290606 -283.621584)
			(xy 350.260816 -283.66759) (xy 350.24314 -283.688536) (xy 350.237044 -283.695648) (xy 350.230694 -283.712666)
			(xy 350.230694 -283.788612) (xy 350.231047 -283.797629) (xy 350.237297 -283.814546) (xy 350.242886 -283.821632)
			(xy 350.24314 -283.821886) (xy 350.243394 -283.82214) (xy 350.260971 -283.843078) (xy 350.290612 -283.889012)
			(xy 350.313391 -283.938706) (xy 350.328843 -283.991144) (xy 350.33665 -284.045251) (xy 350.33712 -284.072584)
			(xy 350.336634 -284.099835) (xy 350.328878 -284.153783) (xy 350.313523 -284.206078) (xy 350.290881 -284.255655)
			(xy 350.261415 -284.301505) (xy 350.225724 -284.342696) (xy 350.184533 -284.378387) (xy 350.138683 -284.407853)
			(xy 350.089106 -284.430495) (xy 350.036811 -284.44585) (xy 349.982863 -284.453606) (xy 349.928361 -284.453606)
			(xy 349.874413 -284.44585) (xy 349.822118 -284.430495) (xy 349.772541 -284.407853) (xy 349.726691 -284.378387)
			(xy 349.6855 -284.342696) (xy 349.649809 -284.301505) (xy 349.620343 -284.255655) (xy 349.597701 -284.206078)
			(xy 349.582346 -284.153783) (xy 349.57459 -284.099835) (xy 349.574104 -284.072584) (xy 349.574595 -284.045251)
			(xy 349.582398 -283.991145) (xy 349.597843 -283.938706) (xy 349.620613 -283.889008) (xy 349.650242 -283.843068)
			(xy 349.66783 -283.82214) (xy 349.668084 -283.821886) (xy 349.668338 -283.821632) (xy 349.673922 -283.814544)
			(xy 349.680169 -283.797628) (xy 349.68053 -283.788612) (xy 349.68053 -283.712666) (xy 349.67418 -283.695648)
			(xy 349.668084 -283.688536) (xy 349.650399 -283.667599) (xy 349.620634 -283.62158) (xy 349.597748 -283.571782)
			(xy 349.582211 -283.519224) (xy 349.574342 -283.464987) (xy 349.57385 -283.437584) (xy 344.683134 -283.437584)
			(xy 344.686702 -283.463273) (xy 344.687144 -283.489654) (xy 344.686576 -283.519765) (xy 344.677132 -283.579243)
			(xy 344.658472 -283.636502) (xy 344.631056 -283.690122) (xy 344.595566 -283.738776) (xy 344.574622 -283.760418)
			(xy 344.567256 -283.76753) (xy 344.559128 -283.787596) (xy 344.559128 -283.797756) (xy 344.559128 -283.878782)
			(xy 344.567002 -283.897578) (xy 344.574114 -283.90469) (xy 344.595117 -283.926294) (xy 344.630682 -283.974929)
			(xy 344.658157 -284.02855) (xy 344.67686 -284.085825) (xy 344.686325 -284.145328) (xy 344.68689 -284.175454)
			(xy 344.686404 -284.202705) (xy 344.678648 -284.256653) (xy 344.663293 -284.308948) (xy 344.640651 -284.358525)
			(xy 344.611185 -284.404375) (xy 344.575494 -284.445566) (xy 344.534303 -284.481257) (xy 344.488453 -284.510723)
			(xy 344.438876 -284.533365) (xy 344.386581 -284.54872) (xy 344.332633 -284.556476) (xy 344.278131 -284.556476)
			(xy 344.224183 -284.54872) (xy 344.171888 -284.533365) (xy 344.122311 -284.510723) (xy 344.076461 -284.481257)
			(xy 344.03527 -284.445566) (xy 343.999579 -284.404375) (xy 343.970113 -284.358525) (xy 343.947471 -284.308948)
			(xy 343.932116 -284.256653) (xy 343.92436 -284.202705) (xy 343.923874 -284.175454) (xy 343.924468 -284.145498)
			(xy 343.933852 -284.086326) (xy 343.952382 -284.029352) (xy 343.9796 -283.97598) (xy 344.014836 -283.927526)
			(xy 344.035634 -283.90596) (xy 344.039698 -283.901896) (xy 344.045286 -283.893006) (xy 344.051636 -283.877512)
			(xy 344.051636 -283.867352) (xy 344.051636 -283.78658) (xy 344.043762 -283.768038) (xy 344.03665 -283.760672)
			(xy 344.01561 -283.739055) (xy 343.979965 -283.69039) (xy 343.952425 -283.636721) (xy 343.933677 -283.579387)
			(xy 343.924188 -283.519815) (xy 343.92362 -283.489654) (xy 343.924111 -283.46142) (xy 343.932405 -283.405564)
			(xy 343.94013 -283.378402) (xy 343.942416 -283.371036) (xy 343.942416 -283.352494) (xy 343.942191 -283.345832)
			(xy 343.938706 -283.33297) (xy 343.935558 -283.327094) (xy 343.935304 -283.326586) (xy 343.893648 -283.256228)
			(xy 343.875868 -283.243528) (xy 343.864946 -283.241496) (xy 343.83706 -283.235618) (xy 343.783292 -283.216734)
			(xy 343.732933 -283.190059) (xy 343.687102 -283.15619) (xy 343.646821 -283.115878) (xy 343.612986 -283.070022)
			(xy 343.58635 -283.019642) (xy 343.567506 -282.965861) (xy 343.56167 -282.937966) (xy 343.559384 -282.92552)
			(xy 343.543636 -282.905962) (xy 343.45626 -282.867608) (xy 343.444546 -282.863203) (xy 343.41963 -282.86521)
			(xy 343.408762 -282.871418) (xy 343.408254 -282.871672) (xy 343.385247 -282.885706) (xy 343.336106 -282.907831)
			(xy 343.284342 -282.922826) (xy 343.230984 -282.930395) (xy 343.204038 -282.930854) (xy 343.200482 -282.930854)
			(xy 343.18702 -282.930346) (xy 343.173213 -282.92957) (xy 343.145754 -282.926263) (xy 343.132156 -282.923742)
			(xy 343.122607 -282.922343) (xy 343.103672 -282.926006) (xy 343.095326 -282.930854) (xy 343.040462 -282.965906)
			(xy 343.039446 -282.966414) (xy 343.02827 -282.974034) (xy 343.017602 -282.989274) (xy 343.015316 -282.998418)
			(xy 343.007864 -283.02581) (xy 342.985905 -283.078158) (xy 342.956437 -283.126677) (xy 342.920109 -283.170298)
			(xy 342.877723 -283.208059) (xy 342.830213 -283.239128) (xy 342.778627 -283.262819) (xy 342.724101 -283.278611)
			(xy 342.696038 -283.282898) (xy 342.683398 -283.284474) (xy 342.657976 -283.286124) (xy 342.645238 -283.2862)
			(xy 342.617971 -283.28564) (xy 342.563992 -283.277885) (xy 342.511666 -283.262526) (xy 342.462059 -283.239877)
			(xy 342.41618 -283.210399) (xy 342.374963 -283.174691) (xy 342.339247 -283.133481) (xy 342.309759 -283.087608)
			(xy 342.2871 -283.038005) (xy 342.271731 -282.985682) (xy 342.263965 -282.931705) (xy 342.263476 -282.904438)
			(xy 337.882992 -282.904438) (xy 337.876758 -282.947795) (xy 337.861404 -283.000088) (xy 337.838765 -283.049663)
			(xy 337.809301 -283.095511) (xy 337.773612 -283.1367) (xy 337.732424 -283.172391) (xy 337.686577 -283.201857)
			(xy 337.637003 -283.224499) (xy 337.584711 -283.239855) (xy 337.530766 -283.247613) (xy 337.503516 -283.2481)
			(xy 337.476146 -283.247625) (xy 337.421967 -283.239809) (xy 337.369464 -283.224322) (xy 337.319717 -283.201482)
			(xy 337.27375 -283.17176) (xy 337.252818 -283.15412) (xy 337.252564 -283.153866) (xy 337.245466 -283.148296)
			(xy 337.228558 -283.142041) (xy 337.219544 -283.141674) (xy 337.152488 -283.141674) (xy 337.143471 -283.142031)
			(xy 337.126555 -283.148279) (xy 337.119468 -283.153866) (xy 337.11896 -283.154374) (xy 337.098019 -283.171948)
			(xy 337.052087 -283.20159) (xy 337.002393 -283.22437) (xy 336.949956 -283.239822) (xy 336.895849 -283.247629)
			(xy 336.868516 -283.2481) (xy 336.841262 -283.247654) (xy 336.787308 -283.239898) (xy 336.735007 -283.224543)
			(xy 336.685424 -283.201901) (xy 336.639568 -283.172433) (xy 336.598372 -283.136739) (xy 336.562676 -283.095545)
			(xy 336.533206 -283.04969) (xy 336.510562 -283.000108) (xy 336.495205 -282.947808) (xy 336.487447 -282.893854)
			(xy 336.157353 -282.893854) (xy 336.157333 -282.895008) (xy 336.149169 -282.950224) (xy 336.141568 -282.977082)
			(xy 336.139282 -282.984448) (xy 336.139282 -283.003752) (xy 336.139527 -283.010412) (xy 336.142998 -283.023274)
			(xy 336.14614 -283.029152) (xy 336.146394 -283.02966) (xy 336.188304 -283.100526) (xy 336.206084 -283.112972)
			(xy 336.216752 -283.115004) (xy 336.242567 -283.120354) (xy 336.292483 -283.137321) (xy 336.339587 -283.161)
			(xy 336.382982 -283.190939) (xy 336.421841 -283.226569) (xy 336.455423 -283.267211) (xy 336.483088 -283.31209)
			(xy 336.50431 -283.36035) (xy 336.518685 -283.411074) (xy 336.522367 -283.437584) (xy 341.413338 -283.437584)
			(xy 341.413824 -283.410315) (xy 341.421586 -283.356331) (xy 341.436951 -283.304001) (xy 341.459608 -283.254391)
			(xy 341.489094 -283.20851) (xy 341.524809 -283.167293) (xy 341.566026 -283.131578) (xy 341.611907 -283.102092)
			(xy 341.661517 -283.079435) (xy 341.713847 -283.06407) (xy 341.767831 -283.056308) (xy 341.822369 -283.056308)
			(xy 341.876353 -283.06407) (xy 341.928683 -283.079435) (xy 341.978293 -283.102092) (xy 342.024174 -283.131578)
			(xy 342.065391 -283.167293) (xy 342.101106 -283.20851) (xy 342.130592 -283.254391) (xy 342.153249 -283.304001)
			(xy 342.168614 -283.356331) (xy 342.176376 -283.410315) (xy 342.176862 -283.437584) (xy 342.176389 -283.464988)
			(xy 342.168533 -283.51923) (xy 342.152996 -283.57179) (xy 342.130096 -283.621585) (xy 342.100305 -283.66759)
			(xy 342.082628 -283.688536) (xy 342.076532 -283.695648) (xy 342.070182 -283.712666) (xy 342.070182 -283.788612)
			(xy 342.070537 -283.797629) (xy 342.076787 -283.814546) (xy 342.082374 -283.821632) (xy 342.082628 -283.821886)
			(xy 342.082882 -283.82214) (xy 342.100457 -283.84308) (xy 342.130099 -283.889013) (xy 342.152879 -283.938707)
			(xy 342.16833 -283.991144) (xy 342.176137 -284.045251) (xy 342.176608 -284.072584) (xy 342.176122 -284.099835)
			(xy 342.168366 -284.153783) (xy 342.153011 -284.206078) (xy 342.130369 -284.255655) (xy 342.100903 -284.301505)
			(xy 342.065212 -284.342696) (xy 342.024021 -284.378387) (xy 341.978171 -284.407853) (xy 341.928594 -284.430495)
			(xy 341.876299 -284.44585) (xy 341.822351 -284.453606) (xy 341.767849 -284.453606) (xy 341.713901 -284.44585)
			(xy 341.661606 -284.430495) (xy 341.612029 -284.407853) (xy 341.566179 -284.378387) (xy 341.524988 -284.342696)
			(xy 341.489297 -284.301505) (xy 341.459831 -284.255655) (xy 341.437189 -284.206078) (xy 341.421834 -284.153783)
			(xy 341.414078 -284.099835) (xy 341.413592 -284.072584) (xy 341.414086 -284.045251) (xy 341.421889 -283.991145)
			(xy 341.437333 -283.938707) (xy 341.460103 -283.889009) (xy 341.489731 -283.843068) (xy 341.507318 -283.82214)
			(xy 341.507572 -283.821886) (xy 341.507826 -283.821632) (xy 341.513408 -283.814543) (xy 341.519657 -283.797628)
			(xy 341.520018 -283.788612) (xy 341.520018 -283.712666) (xy 341.513668 -283.695648) (xy 341.507572 -283.688536)
			(xy 341.489885 -283.667601) (xy 341.460121 -283.621581) (xy 341.437236 -283.571782) (xy 341.421699 -283.519225)
			(xy 341.41383 -283.464987) (xy 341.413338 -283.437584) (xy 336.522367 -283.437584) (xy 336.525937 -283.463294)
			(xy 336.526378 -283.489654) (xy 336.525803 -283.519611) (xy 336.516416 -283.578784) (xy 336.497883 -283.635759)
			(xy 336.47066 -283.689131) (xy 336.435419 -283.737583) (xy 336.414618 -283.759148) (xy 336.410554 -283.763212)
			(xy 336.404966 -283.772102) (xy 336.398616 -283.787596) (xy 336.398616 -283.797756) (xy 336.398616 -283.878782)
			(xy 336.40649 -283.897578) (xy 336.413602 -283.90469) (xy 336.434603 -283.926296) (xy 336.470168 -283.97493)
			(xy 336.497645 -284.028551) (xy 336.516348 -284.085826) (xy 336.525813 -284.145328) (xy 336.526378 -284.175454)
			(xy 336.525892 -284.202705) (xy 336.518136 -284.256653) (xy 336.502781 -284.308948) (xy 336.480139 -284.358525)
			(xy 336.450673 -284.404375) (xy 336.414982 -284.445566) (xy 336.373791 -284.481257) (xy 336.327941 -284.510723)
			(xy 336.278364 -284.533365) (xy 336.226069 -284.54872) (xy 336.172121 -284.556476) (xy 336.117619 -284.556476)
			(xy 336.063671 -284.54872) (xy 336.011376 -284.533365) (xy 335.961799 -284.510723) (xy 335.915949 -284.481257)
			(xy 335.874758 -284.445566) (xy 335.839067 -284.404375) (xy 335.809601 -284.358525) (xy 335.786959 -284.308948)
			(xy 335.771604 -284.256653) (xy 335.763848 -284.202705) (xy 335.763362 -284.175454) (xy 335.763931 -284.145497)
			(xy 335.773317 -284.086323) (xy 335.791851 -284.029347) (xy 335.819076 -283.975976) (xy 335.854319 -283.927524)
			(xy 335.875122 -283.90596) (xy 335.879186 -283.901896) (xy 335.884774 -283.893006) (xy 335.891124 -283.877512)
			(xy 335.891124 -283.867352) (xy 335.891124 -283.786326) (xy 335.88325 -283.76753) (xy 335.876138 -283.760418)
			(xy 335.855148 -283.738802) (xy 335.819579 -283.690172) (xy 335.7921 -283.636553) (xy 335.773395 -283.57928)
			(xy 335.763928 -283.519779) (xy 335.763362 -283.489654) (xy 335.763362 -283.489146) (xy 335.763863 -283.461238)
			(xy 335.77202 -283.406022) (xy 335.779618 -283.379164) (xy 335.781904 -283.371798) (xy 335.781904 -283.352494)
			(xy 335.781681 -283.345832) (xy 335.778195 -283.33297) (xy 335.775046 -283.327094) (xy 335.774792 -283.326586)
			(xy 335.732882 -283.25572) (xy 335.715102 -283.243274) (xy 335.704434 -283.241242) (xy 335.676617 -283.235366)
			(xy 335.62299 -283.216487) (xy 335.57276 -283.189859) (xy 335.527037 -283.15607) (xy 335.486836 -283.11587)
			(xy 335.453046 -283.070148) (xy 335.426417 -283.019918) (xy 335.407537 -282.966292) (xy 335.401666 -282.938474)
			(xy 335.39938 -282.926028) (xy 335.391252 -282.915868) (xy 335.387442 -282.911042) (xy 335.377536 -282.903422)
			(xy 335.28381 -282.862528) (xy 335.258918 -282.86456) (xy 335.247996 -282.871418) (xy 335.225003 -282.885414)
			(xy 335.175929 -282.907528) (xy 335.124235 -282.92253) (xy 335.070947 -282.930122) (xy 335.044034 -282.9306)
			(xy 335.043526 -282.9306) (xy 335.025507 -282.930374) (xy 334.989632 -282.926942) (xy 334.971898 -282.923742)
			(xy 334.962246 -282.921964) (xy 334.952848 -282.923742) (xy 334.943196 -282.92552) (xy 334.87995 -282.965906)
			(xy 334.878934 -282.966414) (xy 334.867758 -282.974034) (xy 334.85709 -282.989274) (xy 334.854804 -282.998418)
			(xy 334.847425 -283.025491) (xy 334.825787 -283.077264) (xy 334.796806 -283.125313) (xy 334.761106 -283.168604)
			(xy 334.719456 -283.206205) (xy 334.672751 -283.237307) (xy 334.621999 -283.26124) (xy 334.56829 -283.277488)
			(xy 334.512782 -283.285703) (xy 334.484726 -283.2862) (xy 334.457459 -283.285652) (xy 334.40348 -283.277894)
			(xy 334.351154 -283.262534) (xy 334.301546 -283.239884) (xy 334.255667 -283.210404) (xy 334.21445 -283.174695)
			(xy 334.178734 -283.133485) (xy 334.149247 -283.08761) (xy 334.126588 -283.038007) (xy 334.111219 -282.985683)
			(xy 334.103453 -282.931705) (xy 334.102964 -282.904438) (xy 332.633828 -282.904438) (xy 332.633828 -285.029656)
			(xy 374.111518 -285.029656) (xy 374.115589 -284.974034) (xy 374.127715 -284.919597) (xy 374.147638 -284.867506)
			(xy 374.174934 -284.818871) (xy 374.20902 -284.774728) (xy 374.249169 -284.736019) (xy 374.294527 -284.703568)
			(xy 374.344127 -284.678067) (xy 374.396911 -284.66006) (xy 374.451754 -284.64993) (xy 374.507488 -284.647893)
			(xy 374.562925 -284.653993) (xy 374.616882 -284.668099) (xy 374.668211 -284.689911) (xy 374.715817 -284.718965)
			(xy 374.758685 -284.75464) (xy 374.795902 -284.796177) (xy 374.826675 -284.84269) (xy 374.850347 -284.893187)
			(xy 374.866415 -284.946594) (xy 374.874535 -285.00177) (xy 374.875044 -285.029656) (xy 375.596656 -285.029656)
			(xy 375.600727 -284.974034) (xy 375.612853 -284.919597) (xy 375.632776 -284.867506) (xy 375.660072 -284.818871)
			(xy 375.694158 -284.774728) (xy 375.734307 -284.736019) (xy 375.779665 -284.703568) (xy 375.829265 -284.678067)
			(xy 375.882049 -284.66006) (xy 375.936892 -284.64993) (xy 375.992626 -284.647893) (xy 376.048063 -284.653993)
			(xy 376.10202 -284.668099) (xy 376.153349 -284.689911) (xy 376.200955 -284.718965) (xy 376.243823 -284.75464)
			(xy 376.28104 -284.796177) (xy 376.311813 -284.84269) (xy 376.335485 -284.893187) (xy 376.351553 -284.946594)
			(xy 376.359673 -285.00177) (xy 376.360182 -285.029656) (xy 376.359673 -285.057542) (xy 376.351553 -285.112718)
			(xy 376.335485 -285.166125) (xy 376.311813 -285.216622) (xy 376.28104 -285.263135) (xy 376.243823 -285.304672)
			(xy 376.200955 -285.340347) (xy 376.153349 -285.369401) (xy 376.10202 -285.391213) (xy 376.048063 -285.405319)
			(xy 375.992626 -285.411419) (xy 375.936892 -285.409382) (xy 375.882049 -285.399252) (xy 375.829265 -285.381245)
			(xy 375.779665 -285.355744) (xy 375.734307 -285.323293) (xy 375.694158 -285.284584) (xy 375.660072 -285.240441)
			(xy 375.632776 -285.191806) (xy 375.612853 -285.139715) (xy 375.600727 -285.085278) (xy 375.596656 -285.029656)
			(xy 374.875044 -285.029656) (xy 374.874535 -285.057542) (xy 374.866415 -285.112718) (xy 374.850347 -285.166125)
			(xy 374.826675 -285.216622) (xy 374.795902 -285.263135) (xy 374.758685 -285.304672) (xy 374.715817 -285.340347)
			(xy 374.668211 -285.369401) (xy 374.616882 -285.391213) (xy 374.562925 -285.405319) (xy 374.507488 -285.411419)
			(xy 374.451754 -285.409382) (xy 374.396911 -285.399252) (xy 374.344127 -285.381245) (xy 374.294527 -285.355744)
			(xy 374.249169 -285.323293) (xy 374.20902 -285.284584) (xy 374.174934 -285.240441) (xy 374.147638 -285.191806)
			(xy 374.127715 -285.139715) (xy 374.115589 -285.085278) (xy 374.111518 -285.029656) (xy 332.633828 -285.029656)
			(xy 332.633828 -286.644842) (xy 332.633991 -286.650709) (xy 332.636683 -286.662128) (xy 332.639162 -286.667448)
			(xy 332.641956 -286.673036) (xy 332.656688 -286.695642) (xy 332.661501 -286.699452) (xy 340.923878 -286.699452)
			(xy 340.927951 -286.643793) (xy 340.940086 -286.58932) (xy 340.960022 -286.537194) (xy 340.987336 -286.488526)
			(xy 341.021444 -286.444354) (xy 341.061621 -286.405619) (xy 341.107009 -286.373147) (xy 341.156641 -286.347629)
			(xy 341.209461 -286.32961) (xy 341.26434 -286.319473) (xy 341.320111 -286.317435) (xy 341.375585 -286.323538)
			(xy 341.429578 -286.337654) (xy 341.480941 -286.359481) (xy 341.528579 -286.388554) (xy 341.571475 -286.424253)
			(xy 341.608717 -286.465817) (xy 341.639511 -286.512361) (xy 341.663199 -286.562892) (xy 341.673258 -286.596328)
			(xy 341.831928 -286.596328) (xy 341.836001 -286.540669) (xy 341.848136 -286.486196) (xy 341.868072 -286.43407)
			(xy 341.895386 -286.385402) (xy 341.929494 -286.34123) (xy 341.969671 -286.302495) (xy 342.015059 -286.270023)
			(xy 342.064691 -286.244505) (xy 342.117511 -286.226486) (xy 342.17239 -286.216349) (xy 342.228161 -286.214311)
			(xy 342.283635 -286.220414) (xy 342.337628 -286.23453) (xy 342.388991 -286.256357) (xy 342.436629 -286.28543)
			(xy 342.479525 -286.321129) (xy 342.516767 -286.362693) (xy 342.547561 -286.409237) (xy 342.571249 -286.459768)
			(xy 342.587327 -286.51321) (xy 342.595453 -286.568424) (xy 342.595962 -286.596328) (xy 342.595453 -286.624232)
			(xy 342.587327 -286.679446) (xy 342.571249 -286.732888) (xy 342.547561 -286.783419) (xy 342.51909 -286.826452)
			(xy 357.611678 -286.826452) (xy 357.615751 -286.770793) (xy 357.627886 -286.71632) (xy 357.647822 -286.664194)
			(xy 357.675136 -286.615526) (xy 357.709244 -286.571354) (xy 357.749421 -286.532619) (xy 357.794809 -286.500147)
			(xy 357.844441 -286.474629) (xy 357.897261 -286.45661) (xy 357.95214 -286.446473) (xy 358.007911 -286.444435)
			(xy 358.063385 -286.450538) (xy 358.117378 -286.464654) (xy 358.168741 -286.486481) (xy 358.216379 -286.515554)
			(xy 358.259275 -286.551253) (xy 358.296517 -286.592817) (xy 358.327311 -286.639361) (xy 358.350999 -286.689892)
			(xy 358.365796 -286.739076) (xy 358.564686 -286.739076) (xy 358.568759 -286.683417) (xy 358.580894 -286.628944)
			(xy 358.60083 -286.576818) (xy 358.628144 -286.52815) (xy 358.662252 -286.483978) (xy 358.702429 -286.445243)
			(xy 358.747817 -286.412771) (xy 358.797449 -286.387253) (xy 358.850269 -286.369234) (xy 358.905148 -286.359097)
			(xy 358.960919 -286.357059) (xy 359.016393 -286.363162) (xy 359.070386 -286.377278) (xy 359.121749 -286.399105)
			(xy 359.169387 -286.428178) (xy 359.212283 -286.463877) (xy 359.249525 -286.505441) (xy 359.280319 -286.551985)
			(xy 359.304007 -286.602516) (xy 359.320085 -286.655958) (xy 359.328211 -286.711172) (xy 359.32872 -286.739076)
			(xy 359.328211 -286.76698) (xy 359.320085 -286.822194) (xy 359.304007 -286.875636) (xy 359.280319 -286.926167)
			(xy 359.249525 -286.972711) (xy 359.212283 -287.014275) (xy 359.169387 -287.049974) (xy 359.121749 -287.079047)
			(xy 359.070386 -287.100874) (xy 359.016393 -287.11499) (xy 358.960919 -287.121093) (xy 358.905148 -287.119055)
			(xy 358.850269 -287.108918) (xy 358.797449 -287.090899) (xy 358.747817 -287.065381) (xy 358.702429 -287.032909)
			(xy 358.662252 -286.994174) (xy 358.628144 -286.950002) (xy 358.60083 -286.901334) (xy 358.580894 -286.849208)
			(xy 358.568759 -286.794735) (xy 358.564686 -286.739076) (xy 358.365796 -286.739076) (xy 358.367077 -286.743334)
			(xy 358.375203 -286.798548) (xy 358.375712 -286.826452) (xy 358.375203 -286.854356) (xy 358.367077 -286.90957)
			(xy 358.350999 -286.963012) (xy 358.327311 -287.013543) (xy 358.296517 -287.060087) (xy 358.259275 -287.101651)
			(xy 358.216379 -287.13735) (xy 358.168741 -287.166423) (xy 358.117378 -287.18825) (xy 358.063385 -287.202366)
			(xy 358.007911 -287.208469) (xy 357.95214 -287.206431) (xy 357.897261 -287.196294) (xy 357.844441 -287.178275)
			(xy 357.794809 -287.152757) (xy 357.749421 -287.120285) (xy 357.709244 -287.08155) (xy 357.675136 -287.037378)
			(xy 357.647822 -286.98871) (xy 357.627886 -286.936584) (xy 357.615751 -286.882111) (xy 357.611678 -286.826452)
			(xy 342.51909 -286.826452) (xy 342.516767 -286.829963) (xy 342.479525 -286.871527) (xy 342.436629 -286.907226)
			(xy 342.388991 -286.936299) (xy 342.337628 -286.958126) (xy 342.283635 -286.972242) (xy 342.228161 -286.978345)
			(xy 342.17239 -286.976307) (xy 342.117511 -286.96617) (xy 342.064691 -286.948151) (xy 342.015059 -286.922633)
			(xy 341.969671 -286.890161) (xy 341.929494 -286.851426) (xy 341.895386 -286.807254) (xy 341.868072 -286.758586)
			(xy 341.848136 -286.70646) (xy 341.836001 -286.651987) (xy 341.831928 -286.596328) (xy 341.673258 -286.596328)
			(xy 341.679277 -286.616334) (xy 341.687403 -286.671548) (xy 341.687912 -286.699452) (xy 341.687403 -286.727356)
			(xy 341.679277 -286.78257) (xy 341.663199 -286.836012) (xy 341.639511 -286.886543) (xy 341.608717 -286.933087)
			(xy 341.571475 -286.974651) (xy 341.528579 -287.01035) (xy 341.480941 -287.039423) (xy 341.429578 -287.06125)
			(xy 341.375585 -287.075366) (xy 341.320111 -287.081469) (xy 341.26434 -287.079431) (xy 341.209461 -287.069294)
			(xy 341.156641 -287.051275) (xy 341.107009 -287.025757) (xy 341.061621 -286.993285) (xy 341.021444 -286.95455)
			(xy 340.987336 -286.910378) (xy 340.960022 -286.86171) (xy 340.940086 -286.809584) (xy 340.927951 -286.755111)
			(xy 340.923878 -286.699452) (xy 332.661501 -286.699452) (xy 332.662784 -286.700468) (xy 332.678532 -286.713422)
			(xy 332.685136 -286.716216) (xy 332.760249 -286.749067) (xy 332.907544 -286.82109) (xy 333.051173 -286.900173)
			(xy 333.190797 -286.986129) (xy 333.326087 -287.078756) (xy 333.456726 -287.177836) (xy 333.582406 -287.283135)
			(xy 333.70283 -287.394406) (xy 333.817716 -287.511387) (xy 333.926793 -287.633803) (xy 334.029804 -287.761364)
			(xy 334.126507 -287.893772) (xy 334.216674 -288.030715) (xy 334.300093 -288.171869) (xy 334.376568 -288.316903)
			(xy 334.445918 -288.465476) (xy 334.507981 -288.617237) (xy 334.56261 -288.77183) (xy 334.609676 -288.928891)
			(xy 334.64907 -289.088049) (xy 334.680697 -289.248931) (xy 334.704485 -289.411158) (xy 334.720376 -289.574347)
			(xy 334.728333 -289.738115) (xy 334.72882 -289.820096) (xy 334.728298 -289.904131) (xy 334.719937 -290.071994)
			(xy 334.703241 -290.239233) (xy 334.67825 -290.405436) (xy 334.645028 -290.57019) (xy 334.603655 -290.733089)
			(xy 334.554234 -290.89373) (xy 334.496888 -291.051714) (xy 334.431758 -291.206653) (xy 334.359005 -291.358161)
			(xy 334.27881 -291.505865) (xy 334.19137 -291.649399) (xy 334.096902 -291.788409) (xy 333.99564 -291.922549)
			(xy 333.887833 -292.05149) (xy 333.77375 -292.174911) (xy 333.653671 -292.292507) (xy 333.591154 -292.348666)
			(xy 333.58328 -292.355524) (xy 333.57439 -292.374574) (xy 333.57185 -292.459156) (xy 333.572021 -292.469528)
			(xy 333.579617 -292.488809) (xy 333.586582 -292.496494) (xy 334.791558 -293.70147) (xy 334.798958 -293.70831)
			(xy 334.817557 -293.716028) (xy 334.827626 -293.716456)
		)
		(stroke
			(width 0)
			(type solid)
		)
		(fill yes)
		(layer "In15.Cu")
		(net "GND")
	)
	(gr_poly
		(pts
			(xy 156.059632 -417.912042) (xy 156.069698 -417.911611) (xy 156.088289 -417.903882) (xy 156.0957 -417.897056)
			(xy 156.09824 -417.894516) (xy 156.107384 -417.890706) (xy 156.112012 -417.888932) (xy 156.121733 -417.887011)
			(xy 156.126688 -417.886896) (xy 184.804812 -417.886896) (xy 184.814881 -417.88647) (xy 184.833482 -417.878753)
			(xy 184.84088 -417.87191) (xy 184.937146 -417.775644) (xy 184.943838 -417.768233) (xy 184.95145 -417.749795)
			(xy 184.951458 -417.729847) (xy 184.943862 -417.711403) (xy 184.937146 -417.704016) (xy 184.128664 -416.895534)
			(xy 184.128156 -416.895026) (xy 184.12079 -416.887406) (xy 184.093866 -416.876992) (xy 184.088278 -416.876992)
			(xy 184.078626 -416.872928) (xy 184.071514 -416.865816) (xy 184.064679 -416.858414) (xy 184.056973 -416.839815)
			(xy 184.056528 -416.829748) (xy 184.056528 -367.667794) (xy 184.056105 -367.657724) (xy 184.048392 -367.639118)
			(xy 184.041542 -367.631726) (xy 183.555894 -367.146078) (xy 183.548499 -367.139224) (xy 183.5299 -367.13148)
			(xy 183.519826 -367.131092) (xy 178.802284 -367.131092) (xy 178.79229 -367.131591) (xy 178.773816 -367.13923)
			(xy 178.759632 -367.153316) (xy 178.755294 -367.162334) (xy 178.749198 -367.176812) (xy 178.755294 -367.206784)
			(xy 180.124354 -368.575844) (xy 180.147252 -368.599408) (xy 180.188205 -368.650792) (xy 180.223153 -368.706434)
			(xy 180.251656 -368.765638) (xy 180.273357 -368.827658) (xy 180.287982 -368.891717) (xy 180.295349 -368.95701)
			(xy 180.295804 -368.989864) (xy 180.295804 -368.990118) (xy 180.295269 -369.025521) (xy 180.286735 -369.095811)
			(xy 180.269793 -369.16456) (xy 180.244691 -369.230767) (xy 180.211794 -369.293466) (xy 180.171581 -369.351745)
			(xy 180.124639 -369.404753) (xy 180.071651 -369.451719) (xy 180.013391 -369.491958) (xy 179.950706 -369.524883)
			(xy 179.88451 -369.550015) (xy 179.815769 -369.566988) (xy 179.745483 -369.575553) (xy 179.71008 -369.576096)
			(xy 179.677202 -369.575619) (xy 179.611862 -369.568228) (xy 179.547759 -369.553575) (xy 179.485698 -369.531844)
			(xy 179.426456 -369.503308) (xy 179.370778 -369.468324) (xy 179.319362 -369.427332) (xy 179.295806 -369.404392)
			(xy 177.037492 -367.146078) (xy 177.03038 -367.138712) (xy 177.011584 -367.131092) (xy 174.043086 -367.131092)
			(xy 174.033104 -367.131521) (xy 174.014618 -367.139048) (xy 174.000414 -367.15307) (xy 173.996096 -367.16208)
			(xy 173.996096 -367.162334) (xy 173.992553 -367.171778) (xy 173.992455 -367.191933) (xy 174.000172 -367.210552)
			(xy 174.007018 -367.21796) (xy 175.285908 -368.49685) (xy 175.303942 -368.50447) (xy 175.314102 -368.50447)
			(xy 175.345728 -368.50524) (xy 175.408384 -368.513971) (xy 175.469377 -368.530764) (xy 175.527673 -368.555335)
			(xy 175.582284 -368.587267) (xy 175.632287 -368.62602) (xy 175.676835 -368.670938) (xy 175.715172 -368.72126)
			(xy 175.746652 -368.776134) (xy 175.770739 -368.834631) (xy 175.787026 -368.89576) (xy 175.795239 -368.958487)
			(xy 175.795686 -368.990118) (xy 175.795165 -369.021915) (xy 175.786863 -369.084965) (xy 175.770402 -369.146392)
			(xy 175.746065 -369.205145) (xy 175.714268 -369.26022) (xy 175.675555 -369.310673) (xy 175.630588 -369.355642)
			(xy 175.580136 -369.394357) (xy 175.525063 -369.426156) (xy 175.466311 -369.450496) (xy 175.404885 -369.466959)
			(xy 175.341835 -369.475264) (xy 175.310038 -369.475766) (xy 175.278412 -369.475253) (xy 175.215697 -369.467034)
			(xy 175.15458 -369.450742) (xy 175.096095 -369.426654) (xy 175.041232 -369.395178) (xy 174.99092 -369.356845)
			(xy 174.946009 -369.312305) (xy 174.907262 -369.262311) (xy 174.875332 -369.207711) (xy 174.850761 -369.149427)
			(xy 174.833964 -369.088447) (xy 174.825226 -369.025802) (xy 174.82439 -368.994182) (xy 174.82439 -368.984022)
			(xy 174.81677 -368.965988) (xy 172.996606 -367.146078) (xy 172.989494 -367.138712) (xy 172.970698 -367.131092)
			(xy 169.643044 -367.131092) (xy 169.633066 -367.131529) (xy 169.614593 -367.139064) (xy 169.600402 -367.153088)
			(xy 169.596054 -367.16208) (xy 169.596054 -367.162334) (xy 169.592509 -367.171777) (xy 169.59241 -367.191932)
			(xy 169.600134 -367.210547) (xy 169.606976 -367.21796) (xy 170.885866 -368.49685) (xy 170.9039 -368.50447)
			(xy 170.91406 -368.50447) (xy 170.945683 -368.505243) (xy 171.008334 -368.513981) (xy 171.069321 -368.530778)
			(xy 171.12761 -368.555353) (xy 171.182214 -368.587287) (xy 171.232211 -368.62604) (xy 171.276752 -368.670957)
			(xy 171.315085 -368.721278) (xy 171.346559 -368.776149) (xy 171.370643 -368.834642) (xy 171.386928 -368.895767)
			(xy 171.395139 -368.958489) (xy 171.395644 -368.990118) (xy 171.395123 -369.021914) (xy 171.38682 -369.084962)
			(xy 171.370359 -369.146387) (xy 171.346022 -369.205138) (xy 171.314224 -369.260209) (xy 171.275511 -369.31066)
			(xy 171.230543 -369.355625) (xy 171.180091 -369.394337) (xy 171.125018 -369.426132) (xy 171.066266 -369.450467)
			(xy 171.00484 -369.466925) (xy 170.941792 -369.475224) (xy 170.909996 -369.475766) (xy 170.878368 -369.475257)
			(xy 170.815647 -369.467044) (xy 170.754524 -369.450757) (xy 170.696032 -369.426672) (xy 170.641162 -369.395198)
			(xy 170.590844 -369.356866) (xy 170.545927 -369.312325) (xy 170.507174 -369.26233) (xy 170.47524 -369.207726)
			(xy 170.450665 -369.149439) (xy 170.433865 -369.088454) (xy 170.425126 -369.025805) (xy 170.424348 -368.994182)
			(xy 170.424348 -368.984022) (xy 170.416728 -368.965988) (xy 168.837356 -367.38687) (xy 168.830244 -367.379504)
			(xy 168.811448 -367.371884) (xy 165.483794 -367.371884) (xy 165.473798 -367.372381) (xy 165.455321 -367.380017)
			(xy 165.441131 -367.394102) (xy 165.436804 -367.403126) (xy 165.430708 -367.417604) (xy 165.436804 -367.447576)
			(xy 166.485824 -368.49685) (xy 166.503858 -368.50447) (xy 166.514018 -368.50447) (xy 166.545643 -368.505241)
			(xy 166.608298 -368.513974) (xy 166.669289 -368.530768) (xy 166.727583 -368.55534) (xy 166.782193 -368.587272)
			(xy 166.832194 -368.626026) (xy 166.87674 -368.670943) (xy 166.915076 -368.721265) (xy 166.946554 -368.776138)
			(xy 166.97064 -368.834634) (xy 166.986927 -368.895762) (xy 166.995139 -368.958488) (xy 166.995602 -368.990118)
			(xy 166.995103 -369.021915) (xy 166.9868 -369.084963) (xy 166.970338 -369.146389) (xy 166.945999 -369.20514)
			(xy 166.914199 -369.260212) (xy 166.875483 -369.310661) (xy 166.830513 -369.355625) (xy 166.780058 -369.394335)
			(xy 166.724983 -369.426127) (xy 166.666228 -369.450459) (xy 166.604801 -369.466913) (xy 166.541751 -369.475208)
			(xy 166.509954 -369.475766) (xy 166.478328 -369.475254) (xy 166.415611 -369.467037) (xy 166.354492 -369.450746)
			(xy 166.296005 -369.426659) (xy 166.24114 -369.395183) (xy 166.190826 -369.35685) (xy 166.145914 -369.31231)
			(xy 166.107165 -369.262316) (xy 166.075234 -369.207715) (xy 166.050662 -369.14943) (xy 166.033864 -369.088449)
			(xy 166.025126 -369.025803) (xy 166.024306 -368.994182) (xy 166.024306 -368.984022) (xy 166.016686 -368.965988)
			(xy 164.795454 -367.74501) (xy 164.788342 -367.737644) (xy 164.769546 -367.730024) (xy 161.441892 -367.730024)
			(xy 161.431898 -367.730522) (xy 161.413426 -367.738162) (xy 161.399246 -367.752251) (xy 161.394902 -367.761266)
			(xy 161.388806 -367.775744) (xy 161.394902 -367.805716) (xy 162.085782 -368.49685) (xy 162.103816 -368.50447)
			(xy 162.113976 -368.50447) (xy 162.145599 -368.505244) (xy 162.208248 -368.513983) (xy 162.269233 -368.530783)
			(xy 162.32752 -368.555357) (xy 162.382123 -368.587292) (xy 162.432118 -368.626046) (xy 162.476657 -368.670963)
			(xy 162.514988 -368.721282) (xy 162.546462 -368.776153) (xy 162.570544 -368.834645) (xy 162.586829 -368.895769)
			(xy 162.595039 -368.95849) (xy 162.59556 -368.990118) (xy 162.595039 -369.021914) (xy 162.586736 -369.084963)
			(xy 162.570276 -369.146389) (xy 162.545938 -369.205141) (xy 162.514141 -369.260213) (xy 162.475427 -369.310665)
			(xy 162.43046 -369.355631) (xy 162.380008 -369.394344) (xy 162.324935 -369.426141) (xy 162.266183 -369.450478)
			(xy 162.204757 -369.466938) (xy 162.141708 -369.475239) (xy 162.109912 -369.475766) (xy 162.078283 -369.475258)
			(xy 162.015561 -369.467046) (xy 161.954436 -369.450761) (xy 161.895942 -369.426677) (xy 161.841071 -369.395203)
			(xy 161.79075 -369.356871) (xy 161.745832 -369.31233) (xy 161.707077 -369.262335) (xy 161.675142 -369.20773)
			(xy 161.650566 -369.149442) (xy 161.633766 -369.088456) (xy 161.625026 -369.025805) (xy 161.624264 -368.994182)
			(xy 161.624264 -368.984022) (xy 161.616644 -368.965988) (xy 160.753552 -368.10315) (xy 160.74644 -368.095784)
			(xy 160.727644 -368.088164) (xy 158.603442 -368.088164) (xy 158.593478 -368.088648) (xy 158.575049 -368.096229)
			(xy 158.567628 -368.102896) (xy 156.147813 -370.522711) (xy 159.424901 -370.522711) (xy 159.424903 -370.457268)
			(xy 159.433697 -370.392418) (xy 159.451123 -370.329338) (xy 159.476867 -370.269171) (xy 159.493204 -370.240814)
			(xy 159.496514 -370.234787) (xy 159.500123 -370.221525) (xy 159.500316 -370.214652) (xy 159.500316 -369.928902)
			(xy 159.500835 -369.918747) (xy 159.508604 -369.899982) (xy 159.522962 -369.885618) (xy 159.541723 -369.877839)
			(xy 159.551878 -369.87734) (xy 160.268158 -369.87734) (xy 160.278327 -369.877798) (xy 160.297121 -369.88557)
			(xy 160.311508 -369.899945) (xy 160.319294 -369.918733) (xy 160.31972 -369.928902) (xy 160.31972 -370.214652)
			(xy 160.319928 -370.221524) (xy 160.323525 -370.234787) (xy 160.326832 -370.240814) (xy 160.34316 -370.269175)
			(xy 160.368906 -370.329341) (xy 160.386335 -370.39242) (xy 160.39513 -370.457268) (xy 160.395131 -370.522711)
			(xy 160.395131 -370.522712) (xy 163.824938 -370.522712) (xy 163.824939 -370.457268) (xy 163.833733 -370.392418)
			(xy 163.851162 -370.329337) (xy 163.876908 -370.26917) (xy 163.893246 -370.240814) (xy 163.896605 -370.234796)
			(xy 163.900344 -370.221538) (xy 163.900612 -370.214652) (xy 163.900612 -369.928902) (xy 163.901127 -369.918779)
			(xy 163.908849 -369.900063) (xy 163.923126 -369.885708) (xy 163.9418 -369.877884) (xy 163.95192 -369.87734)
			(xy 164.6682 -369.87734) (xy 164.678359 -369.877722) (xy 164.697119 -369.885526) (xy 164.711444 -369.899935)
			(xy 164.719136 -369.918741) (xy 164.719508 -369.928902) (xy 164.719508 -370.214652) (xy 164.719759 -370.221542)
			(xy 164.723489 -370.234808) (xy 164.726874 -370.240814) (xy 164.743201 -370.269176) (xy 164.768945 -370.329341)
			(xy 164.786372 -370.39242) (xy 164.795166 -370.457269) (xy 164.795167 -370.522711) (xy 164.795167 -370.522712)
			(xy 168.224974 -370.522712) (xy 168.224975 -370.457268) (xy 168.23377 -370.392417) (xy 168.2512 -370.329336)
			(xy 168.276948 -370.26917) (xy 168.293288 -370.240814) (xy 168.296597 -370.234786) (xy 168.300206 -370.221525)
			(xy 168.3004 -370.214652) (xy 168.3004 -369.928902) (xy 168.300934 -369.918749) (xy 168.308701 -369.899987)
			(xy 168.323054 -369.885623) (xy 168.341809 -369.877842) (xy 168.351962 -369.87734) (xy 169.068242 -369.87734)
			(xy 169.078403 -369.877799) (xy 169.097173 -369.885588) (xy 169.111537 -369.899964) (xy 169.11931 -369.918741)
			(xy 169.119804 -369.928902) (xy 169.119804 -370.214652) (xy 169.120014 -370.221524) (xy 169.12361 -370.234787)
			(xy 169.126916 -370.240814) (xy 169.143245 -370.269175) (xy 169.168992 -370.32934) (xy 169.186421 -370.392419)
			(xy 169.195216 -370.457268) (xy 169.195217 -370.522711) (xy 169.195217 -370.522712) (xy 172.624763 -370.522712)
			(xy 172.624765 -370.457268) (xy 172.63356 -370.392417) (xy 172.650989 -370.329336) (xy 172.676737 -370.26917)
			(xy 172.693076 -370.240814) (xy 172.696384 -370.234786) (xy 172.699994 -370.221525) (xy 172.700188 -370.214652)
			(xy 172.700188 -369.928902) (xy 172.700567 -369.918724) (xy 172.70836 -369.89992) (xy 172.72276 -369.885533)
			(xy 172.741572 -369.877757) (xy 172.75175 -369.87734) (xy 173.46803 -369.87734) (xy 173.47819 -369.877809)
			(xy 173.49696 -369.885593) (xy 173.511325 -369.899967) (xy 173.519098 -369.918742) (xy 173.519592 -369.928902)
			(xy 173.519592 -370.214652) (xy 173.519804 -370.221524) (xy 173.523399 -370.234786) (xy 173.526704 -370.240814)
			(xy 173.54303 -370.269176) (xy 173.568772 -370.329342) (xy 173.586198 -370.392421) (xy 173.594992 -370.457269)
			(xy 173.594992 -370.489988) (xy 177.023784 -370.489988) (xy 177.027775 -370.427821) (xy 177.039684 -370.366674)
			(xy 177.059313 -370.307553) (xy 177.086342 -370.251427) (xy 177.120326 -370.199218) (xy 177.160708 -370.151783)
			(xy 177.206824 -370.109902) (xy 177.257916 -370.074262) (xy 177.313147 -370.045448) (xy 177.371609 -370.023934)
			(xy 177.432343 -370.010072) (xy 177.49435 -370.00409) (xy 177.556613 -370.006086) (xy 177.61811 -370.016029)
			(xy 177.677831 -370.033753) (xy 177.734794 -370.05897) (xy 177.788065 -370.091263) (xy 177.83677 -370.130103)
			(xy 177.880107 -370.174853) (xy 177.917367 -370.224777) (xy 177.947936 -370.279056) (xy 177.971314 -370.336799)
			(xy 177.987115 -370.397057) (xy 177.995081 -370.45884) (xy 177.99558 -370.489988) (xy 177.995081 -370.521136)
			(xy 177.987115 -370.582919) (xy 177.971314 -370.643177) (xy 177.947936 -370.70092) (xy 177.917367 -370.755199)
			(xy 177.880107 -370.805123) (xy 177.83677 -370.849873) (xy 177.788065 -370.888713) (xy 177.734794 -370.921006)
			(xy 177.677831 -370.946223) (xy 177.61811 -370.963947) (xy 177.556613 -370.97389) (xy 177.49435 -370.975886)
			(xy 177.432343 -370.969904) (xy 177.371609 -370.956042) (xy 177.313147 -370.934528) (xy 177.257916 -370.905714)
			(xy 177.206824 -370.870074) (xy 177.160708 -370.828193) (xy 177.120326 -370.780758) (xy 177.086342 -370.728549)
			(xy 177.059313 -370.672423) (xy 177.039684 -370.613302) (xy 177.027775 -370.552155) (xy 177.023784 -370.489988)
			(xy 173.594992 -370.489988) (xy 173.594993 -370.522711) (xy 173.586203 -370.587559) (xy 173.568779 -370.650639)
			(xy 173.543039 -370.710805) (xy 173.526704 -370.739162) (xy 173.523403 -370.745193) (xy 173.519789 -370.758452)
			(xy 173.519592 -370.765324) (xy 173.519592 -371.514878) (xy 173.519793 -371.521751) (xy 173.523395 -371.535013)
			(xy 173.526704 -371.54104) (xy 173.543052 -371.56939) (xy 173.565896 -371.62279) (xy 174.824904 -371.62279)
			(xy 174.824908 -371.557345) (xy 174.833706 -371.492493) (xy 174.851136 -371.429412) (xy 174.876885 -371.369244)
			(xy 174.893224 -371.340888) (xy 174.896545 -371.334866) (xy 174.900146 -371.3216) (xy 174.900336 -371.314726)
			(xy 174.900336 -371.028722) (xy 174.900782 -371.018552) (xy 174.908559 -370.999758) (xy 174.922938 -370.985373)
			(xy 174.941728 -370.977587) (xy 174.951898 -370.97716) (xy 175.668178 -370.97716) (xy 175.678351 -370.977583)
			(xy 175.697149 -370.985364) (xy 175.711536 -370.999751) (xy 175.719317 -371.018549) (xy 175.71974 -371.028722)
			(xy 175.71974 -371.314726) (xy 175.719917 -371.3216) (xy 175.723535 -371.334863) (xy 175.726852 -371.340888)
			(xy 175.743157 -371.369262) (xy 175.768905 -371.429424) (xy 175.786335 -371.492501) (xy 175.795132 -371.557347)
			(xy 175.795137 -371.622788) (xy 175.786348 -371.687635) (xy 175.768926 -371.750714) (xy 175.752028 -371.790214)
			(xy 177.023784 -371.790214) (xy 177.027775 -371.728047) (xy 177.039684 -371.6669) (xy 177.059313 -371.607779)
			(xy 177.086342 -371.551653) (xy 177.120326 -371.499444) (xy 177.160708 -371.452009) (xy 177.206824 -371.410128)
			(xy 177.257916 -371.374488) (xy 177.313147 -371.345674) (xy 177.371609 -371.32416) (xy 177.432343 -371.310298)
			(xy 177.49435 -371.304316) (xy 177.556613 -371.306312) (xy 177.61811 -371.316255) (xy 177.677831 -371.333979)
			(xy 177.734794 -371.359196) (xy 177.788065 -371.391489) (xy 177.83677 -371.430329) (xy 177.880107 -371.475079)
			(xy 177.917367 -371.525003) (xy 177.947936 -371.579282) (xy 177.9523 -371.590062) (xy 179.223932 -371.590062)
			(xy 179.227923 -371.527895) (xy 179.239832 -371.466748) (xy 179.259461 -371.407627) (xy 179.28649 -371.351501)
			(xy 179.320474 -371.299292) (xy 179.360856 -371.251857) (xy 179.406972 -371.209976) (xy 179.458064 -371.174336)
			(xy 179.513295 -371.145522) (xy 179.571757 -371.124008) (xy 179.632491 -371.110146) (xy 179.694498 -371.104164)
			(xy 179.756761 -371.10616) (xy 179.818258 -371.116103) (xy 179.877979 -371.133827) (xy 179.934942 -371.159044)
			(xy 179.988213 -371.191337) (xy 180.036918 -371.230177) (xy 180.080255 -371.274927) (xy 180.117515 -371.324851)
			(xy 180.148084 -371.37913) (xy 180.171462 -371.436873) (xy 180.187263 -371.497131) (xy 180.195229 -371.558914)
			(xy 180.195728 -371.590062) (xy 180.195229 -371.62121) (xy 180.187263 -371.682993) (xy 180.171462 -371.743251)
			(xy 180.148084 -371.800994) (xy 180.117515 -371.855273) (xy 180.080255 -371.905197) (xy 180.036918 -371.949947)
			(xy 179.988213 -371.988787) (xy 179.934942 -372.02108) (xy 179.877979 -372.046297) (xy 179.818258 -372.064021)
			(xy 179.756761 -372.073964) (xy 179.694498 -372.07596) (xy 179.632491 -372.069978) (xy 179.571757 -372.056116)
			(xy 179.513295 -372.034602) (xy 179.458064 -372.005788) (xy 179.406972 -371.970148) (xy 179.360856 -371.928267)
			(xy 179.320474 -371.880832) (xy 179.28649 -371.828623) (xy 179.259461 -371.772497) (xy 179.239832 -371.713376)
			(xy 179.227923 -371.652229) (xy 179.223932 -371.590062) (xy 177.9523 -371.590062) (xy 177.971314 -371.637025)
			(xy 177.987115 -371.697283) (xy 177.995081 -371.759066) (xy 177.99558 -371.790214) (xy 177.995081 -371.821362)
			(xy 177.987115 -371.883145) (xy 177.971314 -371.943403) (xy 177.947936 -372.001146) (xy 177.917367 -372.055425)
			(xy 177.880107 -372.105349) (xy 177.83677 -372.150099) (xy 177.788065 -372.188939) (xy 177.734794 -372.221232)
			(xy 177.677831 -372.246449) (xy 177.61811 -372.264173) (xy 177.556613 -372.274116) (xy 177.49435 -372.276112)
			(xy 177.432343 -372.27013) (xy 177.371609 -372.256268) (xy 177.313147 -372.234754) (xy 177.257916 -372.20594)
			(xy 177.206824 -372.1703) (xy 177.160708 -372.128419) (xy 177.120326 -372.080984) (xy 177.086342 -372.028775)
			(xy 177.059313 -371.972649) (xy 177.039684 -371.913528) (xy 177.027775 -371.852381) (xy 177.023784 -371.790214)
			(xy 175.752028 -371.790214) (xy 175.743187 -371.81088) (xy 175.726852 -371.839236) (xy 175.723529 -371.845256)
			(xy 175.719928 -371.858523) (xy 175.71974 -371.865398) (xy 175.71974 -372.614698) (xy 175.719928 -372.621572)
			(xy 175.723538 -372.634835) (xy 175.726852 -372.64086) (xy 175.743218 -372.6692) (xy 175.76896 -372.72937)
			(xy 175.786384 -372.792454) (xy 175.795173 -372.857306) (xy 175.795171 -372.890034) (xy 179.223932 -372.890034)
			(xy 179.227923 -372.827867) (xy 179.239832 -372.76672) (xy 179.259461 -372.707599) (xy 179.28649 -372.651473)
			(xy 179.320474 -372.599264) (xy 179.360856 -372.551829) (xy 179.406972 -372.509948) (xy 179.458064 -372.474308)
			(xy 179.513295 -372.445494) (xy 179.571757 -372.42398) (xy 179.632491 -372.410118) (xy 179.694498 -372.404136)
			(xy 179.756761 -372.406132) (xy 179.818258 -372.416075) (xy 179.877979 -372.433799) (xy 179.934942 -372.459016)
			(xy 179.988213 -372.491309) (xy 180.036918 -372.530149) (xy 180.080255 -372.574899) (xy 180.117515 -372.624823)
			(xy 180.148084 -372.679102) (xy 180.171462 -372.736845) (xy 180.187263 -372.797103) (xy 180.195229 -372.858886)
			(xy 180.195728 -372.890034) (xy 180.195229 -372.921182) (xy 180.187263 -372.982965) (xy 180.171462 -373.043223)
			(xy 180.148084 -373.100966) (xy 180.117515 -373.155245) (xy 180.080255 -373.205169) (xy 180.036918 -373.249919)
			(xy 179.988213 -373.288759) (xy 179.934942 -373.321052) (xy 179.877979 -373.346269) (xy 179.818258 -373.363993)
			(xy 179.756761 -373.373936) (xy 179.694498 -373.375932) (xy 179.632491 -373.36995) (xy 179.571757 -373.356088)
			(xy 179.513295 -373.334574) (xy 179.458064 -373.30576) (xy 179.406972 -373.27012) (xy 179.360856 -373.228239)
			(xy 179.320474 -373.180804) (xy 179.28649 -373.128595) (xy 179.259461 -373.072469) (xy 179.239832 -373.013348)
			(xy 179.227923 -372.952201) (xy 179.223932 -372.890034) (xy 175.795171 -372.890034) (xy 175.795169 -372.922752)
			(xy 175.786372 -372.987603) (xy 175.768941 -373.050685) (xy 175.743192 -373.110852) (xy 175.726852 -373.139208)
			(xy 175.723539 -373.145233) (xy 175.719931 -373.158496) (xy 175.71974 -373.16537) (xy 175.71974 -373.451374)
			(xy 175.719314 -373.461547) (xy 175.711534 -373.480345) (xy 175.697148 -373.494731) (xy 175.678351 -373.502513)
			(xy 175.668178 -373.502936) (xy 174.951898 -373.502936) (xy 174.941723 -373.502537) (xy 174.922923 -373.494747)
			(xy 174.908538 -373.480353) (xy 174.900757 -373.461549) (xy 174.900336 -373.451374) (xy 174.900336 -373.16537)
			(xy 174.900151 -373.158496) (xy 174.896537 -373.145234) (xy 174.893224 -373.139208) (xy 174.876916 -373.110836)
			(xy 174.85117 -373.050673) (xy 174.833741 -372.987596) (xy 174.824945 -372.922749) (xy 174.824941 -372.857309)
			(xy 174.833729 -372.792461) (xy 174.851151 -372.729383) (xy 174.876889 -372.669216) (xy 174.893224 -372.64086)
			(xy 174.896555 -372.634843) (xy 174.90015 -372.621573) (xy 174.900336 -372.614698) (xy 174.900336 -371.865398)
			(xy 174.90014 -371.858525) (xy 174.896534 -371.845262) (xy 174.893224 -371.839236) (xy 174.876855 -371.810897)
			(xy 174.851115 -371.750726) (xy 174.833692 -371.687643) (xy 174.824904 -371.62279) (xy 173.565896 -371.62279)
			(xy 173.568792 -371.629559) (xy 173.586216 -371.69264) (xy 173.595007 -371.75749) (xy 173.595005 -371.822934)
			(xy 173.586211 -371.887784) (xy 173.568784 -371.950864) (xy 173.543041 -372.011031) (xy 173.526704 -372.039388)
			(xy 173.523394 -372.045415) (xy 173.519785 -372.058677) (xy 173.519592 -372.06555) (xy 173.519592 -372.351554)
			(xy 173.519099 -372.361719) (xy 173.511335 -372.380507) (xy 173.496971 -372.394892) (xy 173.478194 -372.402684)
			(xy 173.46803 -372.403116) (xy 172.75175 -372.403116) (xy 172.741576 -372.402694) (xy 172.722773 -372.394917)
			(xy 172.708385 -372.38053) (xy 172.700607 -372.361728) (xy 172.700188 -372.351554) (xy 172.700188 -372.06555)
			(xy 172.699978 -372.058678) (xy 172.696382 -372.045415) (xy 172.693076 -372.039388) (xy 172.676749 -372.011026)
			(xy 172.651002 -371.950861) (xy 172.633573 -371.887782) (xy 172.624778 -371.822933) (xy 172.624777 -371.757491)
			(xy 172.633568 -371.692642) (xy 172.650994 -371.629562) (xy 172.676738 -371.569396) (xy 172.693076 -371.54104)
			(xy 172.696375 -371.535008) (xy 172.699991 -371.52175) (xy 172.700188 -371.514878) (xy 172.700188 -370.765324)
			(xy 172.699988 -370.758451) (xy 172.696385 -370.745189) (xy 172.693076 -370.739162) (xy 172.676727 -370.710812)
			(xy 172.650982 -370.650644) (xy 172.633556 -370.587563) (xy 172.624763 -370.522712) (xy 169.195217 -370.522712)
			(xy 169.186425 -370.58756) (xy 169.168999 -370.65064) (xy 169.143254 -370.710806) (xy 169.126916 -370.739162)
			(xy 169.123616 -370.745194) (xy 169.120001 -370.758452) (xy 169.119804 -370.765324) (xy 169.119804 -371.514878)
			(xy 169.120004 -371.521751) (xy 169.123607 -371.535013) (xy 169.126916 -371.54104) (xy 169.143267 -371.569389)
			(xy 169.166117 -371.62279) (xy 170.424854 -371.62279) (xy 170.424858 -371.557344) (xy 170.433657 -371.492492)
			(xy 170.45109 -371.429411) (xy 170.476841 -371.369244) (xy 170.493182 -371.340888) (xy 170.496545 -371.334872)
			(xy 170.500282 -371.321613) (xy 170.500548 -371.314726) (xy 170.500548 -371.028722) (xy 170.501045 -371.018596)
			(xy 170.508767 -370.999873) (xy 170.52305 -370.985516) (xy 170.541732 -370.977698) (xy 170.551856 -370.97716)
			(xy 171.268136 -370.97716) (xy 171.278287 -370.977591) (xy 171.297033 -370.985391) (xy 171.311354 -370.999784)
			(xy 171.319059 -371.018568) (xy 171.319444 -371.028722) (xy 171.319444 -371.314726) (xy 171.319678 -371.321619)
			(xy 171.323406 -371.334891) (xy 171.32681 -371.340888) (xy 171.343117 -371.369261) (xy 171.368866 -371.429424)
			(xy 171.386298 -371.4925) (xy 171.395096 -371.557347) (xy 171.3951 -371.622788) (xy 171.386311 -371.687636)
			(xy 171.368888 -371.750715) (xy 171.343146 -371.81088) (xy 171.32681 -371.839236) (xy 171.323438 -371.845247)
			(xy 171.319706 -371.85851) (xy 171.319444 -371.865398) (xy 171.319444 -372.614698) (xy 171.31965 -372.621593)
			(xy 171.323397 -372.634865) (xy 171.32681 -372.64086) (xy 171.343178 -372.6692) (xy 171.368922 -372.72937)
			(xy 171.386347 -372.792453) (xy 171.395137 -372.857306) (xy 171.395133 -372.922752) (xy 171.386335 -372.987604)
			(xy 171.368902 -373.050685) (xy 171.343151 -373.110852) (xy 171.32681 -373.139208) (xy 171.323448 -373.145224)
			(xy 171.31971 -373.158484) (xy 171.319444 -373.16537) (xy 171.319444 -373.451374) (xy 171.318952 -373.461501)
			(xy 171.31123 -373.480225) (xy 171.296945 -373.494583) (xy 171.27826 -373.5024) (xy 171.268136 -373.502936)
			(xy 170.551856 -373.502936) (xy 170.541704 -373.502515) (xy 170.522957 -373.494712) (xy 170.508637 -373.480316)
			(xy 170.500932 -373.461529) (xy 170.500548 -373.451374) (xy 170.500548 -373.16537) (xy 170.500317 -373.158477)
			(xy 170.496587 -373.145205) (xy 170.493182 -373.139208) (xy 170.476872 -373.110836) (xy 170.451123 -373.050674)
			(xy 170.433692 -372.987597) (xy 170.424895 -372.92275) (xy 170.424891 -372.857309) (xy 170.43368 -372.79246)
			(xy 170.451104 -372.729381) (xy 170.476846 -372.669216) (xy 170.493182 -372.64086) (xy 170.496555 -372.634849)
			(xy 170.500286 -372.621586) (xy 170.500548 -372.614698) (xy 170.500548 -371.865398) (xy 170.500344 -371.858503)
			(xy 170.496596 -371.845231) (xy 170.493182 -371.839236) (xy 170.476811 -371.810898) (xy 170.451068 -371.750728)
			(xy 170.433643 -371.687644) (xy 170.424854 -371.62279) (xy 169.166117 -371.62279) (xy 169.169012 -371.629557)
			(xy 169.186439 -371.692639) (xy 169.195231 -371.75749) (xy 169.195229 -371.822934) (xy 169.186434 -371.887785)
			(xy 169.169004 -371.950866) (xy 169.143256 -372.011032) (xy 169.126916 -372.039388) (xy 169.123607 -372.045415)
			(xy 169.119997 -372.058677) (xy 169.119804 -372.06555) (xy 169.119804 -372.351554) (xy 169.1193 -372.361717)
			(xy 169.111537 -372.380503) (xy 169.097177 -372.394888) (xy 169.078405 -372.402682) (xy 169.068242 -372.403116)
			(xy 168.351962 -372.403116) (xy 168.341782 -372.402766) (xy 168.322978 -372.39496) (xy 168.308593 -372.380552)
			(xy 168.300817 -372.361734) (xy 168.3004 -372.351554) (xy 168.3004 -372.06555) (xy 168.300189 -372.058678)
			(xy 168.296594 -372.045415) (xy 168.293288 -372.039388) (xy 168.276961 -372.011026) (xy 168.251213 -371.950861)
			(xy 168.233784 -371.887782) (xy 168.224989 -371.822933) (xy 168.224987 -371.757491) (xy 168.233779 -371.692641)
			(xy 168.251205 -371.629562) (xy 168.27695 -371.569396) (xy 168.293288 -371.54104) (xy 168.296588 -371.535008)
			(xy 168.300203 -371.52175) (xy 168.3004 -371.514878) (xy 168.3004 -370.765324) (xy 168.300199 -370.758451)
			(xy 168.296597 -370.745189) (xy 168.293288 -370.739162) (xy 168.276939 -370.710812) (xy 168.251193 -370.650644)
			(xy 168.233766 -370.587563) (xy 168.224974 -370.522712) (xy 164.795167 -370.522712) (xy 164.786376 -370.587559)
			(xy 164.768952 -370.650639) (xy 164.74321 -370.710806) (xy 164.726874 -370.739162) (xy 164.72349 -370.745167)
			(xy 164.719767 -370.758435) (xy 164.719508 -370.765324) (xy 164.719508 -371.514878) (xy 164.719749 -371.521769)
			(xy 164.723486 -371.535035) (xy 164.726874 -371.54104) (xy 164.743223 -371.56939) (xy 164.766069 -371.62279)
			(xy 166.024818 -371.62279) (xy 166.024822 -371.557345) (xy 166.03362 -371.492493) (xy 166.051051 -371.429412)
			(xy 166.0768 -371.369244) (xy 166.09314 -371.340888) (xy 166.096454 -371.334863) (xy 166.100061 -371.3216)
			(xy 166.100252 -371.314726) (xy 166.100252 -371.028722) (xy 166.100682 -371.01855) (xy 166.108463 -370.999753)
			(xy 166.122847 -370.985367) (xy 166.141642 -370.977584) (xy 166.151814 -370.97716) (xy 166.868094 -370.97716)
			(xy 166.878268 -370.977569) (xy 166.897067 -370.985356) (xy 166.911453 -370.999747) (xy 166.919234 -371.018548)
			(xy 166.919656 -371.028722) (xy 166.919656 -371.314726) (xy 166.919831 -371.321601) (xy 166.92345 -371.334864)
			(xy 166.926768 -371.340888) (xy 166.943073 -371.369262) (xy 166.968819 -371.429425) (xy 166.986249 -371.492501)
			(xy 166.995046 -371.557347) (xy 166.99505 -371.622788) (xy 166.986262 -371.687635) (xy 166.968841 -371.750714)
			(xy 166.943103 -371.81088) (xy 166.926768 -371.839236) (xy 166.923438 -371.845253) (xy 166.919843 -371.858523)
			(xy 166.919656 -371.865398) (xy 166.919656 -372.614698) (xy 166.919842 -372.621572) (xy 166.923453 -372.634835)
			(xy 166.926768 -372.64086) (xy 166.943134 -372.6692) (xy 166.968875 -372.729371) (xy 166.986298 -372.792454)
			(xy 166.995087 -372.857307) (xy 166.995083 -372.922752) (xy 166.986286 -372.987603) (xy 166.968855 -373.050684)
			(xy 166.943107 -373.110852) (xy 166.926768 -373.139208) (xy 166.923448 -373.14523) (xy 166.919846 -373.158496)
			(xy 166.919656 -373.16537) (xy 166.919656 -373.451374) (xy 166.919215 -373.461545) (xy 166.911437 -373.48034)
			(xy 166.897057 -373.494726) (xy 166.878264 -373.502511) (xy 166.868094 -373.502936) (xy 166.151814 -373.502936)
			(xy 166.14164 -373.502524) (xy 166.122841 -373.494739) (xy 166.108454 -373.480349) (xy 166.100673 -373.461548)
			(xy 166.100252 -373.451374) (xy 166.100252 -373.16537) (xy 166.100077 -373.158495) (xy 166.096458 -373.145232)
			(xy 166.09314 -373.139208) (xy 166.076831 -373.110836) (xy 166.051085 -373.050673) (xy 166.033655 -372.987596)
			(xy 166.024859 -372.922749) (xy 166.024855 -372.857309) (xy 166.033643 -372.792461) (xy 166.051065 -372.729382)
			(xy 166.076805 -372.669216) (xy 166.09314 -372.64086) (xy 166.096464 -372.63484) (xy 166.100065 -372.621573)
			(xy 166.100252 -372.614698) (xy 166.100252 -371.865398) (xy 166.100067 -371.858524) (xy 166.096455 -371.845261)
			(xy 166.09314 -371.839236) (xy 166.07677 -371.810898) (xy 166.051029 -371.750727) (xy 166.033607 -371.687643)
			(xy 166.024818 -371.62279) (xy 164.766069 -371.62279) (xy 164.768965 -371.629558) (xy 164.78639 -371.69264)
			(xy 164.795181 -371.75749) (xy 164.795179 -371.822934) (xy 164.786385 -371.887784) (xy 164.768957 -371.950865)
			(xy 164.743212 -372.011032) (xy 164.726874 -372.039388) (xy 164.723516 -372.045406) (xy 164.719776 -372.058664)
			(xy 164.719508 -372.06555) (xy 164.719508 -372.351554) (xy 164.718937 -372.361672) (xy 164.711233 -372.380383)
			(xy 164.696973 -372.394739) (xy 164.678314 -372.402568) (xy 164.6682 -372.403116) (xy 163.95192 -372.403116)
			(xy 163.941769 -372.402662) (xy 163.92302 -372.394876) (xy 163.908697 -372.38049) (xy 163.900993 -372.361707)
			(xy 163.900612 -372.351554) (xy 163.900612 -372.06555) (xy 163.900393 -372.058656) (xy 163.896655 -372.045384)
			(xy 163.893246 -372.039388) (xy 163.87692 -372.011025) (xy 163.851175 -371.95086) (xy 163.833747 -371.887781)
			(xy 163.824952 -371.822933) (xy 163.824951 -371.757491) (xy 163.833742 -371.692642) (xy 163.851167 -371.629562)
			(xy 163.876909 -371.569396) (xy 163.893246 -371.54104) (xy 163.896631 -371.535035) (xy 163.900353 -371.521767)
			(xy 163.900612 -371.514878) (xy 163.900612 -370.765324) (xy 163.900403 -370.758429) (xy 163.896659 -370.745157)
			(xy 163.893246 -370.739162) (xy 163.876898 -370.710812) (xy 163.851155 -370.650644) (xy 163.833729 -370.587562)
			(xy 163.824938 -370.522712) (xy 160.395131 -370.522712) (xy 160.386339 -370.58756) (xy 160.368913 -370.65064)
			(xy 160.343169 -370.710806) (xy 160.326832 -370.739162) (xy 160.323533 -370.745195) (xy 160.319917 -370.758452)
			(xy 160.31972 -370.765324) (xy 160.31972 -371.514878) (xy 160.319918 -371.521751) (xy 160.323522 -371.535014)
			(xy 160.326832 -371.54104) (xy 160.343182 -371.569389) (xy 160.366031 -371.62279) (xy 161.624781 -371.62279)
			(xy 161.624786 -371.557345) (xy 161.633583 -371.492494) (xy 161.651013 -371.429412) (xy 161.676759 -371.369245)
			(xy 161.693098 -371.340888) (xy 161.696462 -371.334873) (xy 161.700199 -371.321613) (xy 161.700464 -371.314726)
			(xy 161.700464 -371.028722) (xy 161.700945 -371.018594) (xy 161.70867 -370.999868) (xy 161.722959 -370.985511)
			(xy 161.741646 -370.977695) (xy 161.751772 -370.97716) (xy 162.468052 -370.97716) (xy 162.478198 -370.97766)
			(xy 162.496942 -370.985432) (xy 162.511265 -370.999805) (xy 162.518974 -371.018575) (xy 162.51936 -371.028722)
			(xy 162.51936 -371.314726) (xy 162.519592 -371.321619) (xy 162.523321 -371.334891) (xy 162.526726 -371.340888)
			(xy 162.543032 -371.369262) (xy 162.568781 -371.429424) (xy 162.586212 -371.4925) (xy 162.59501 -371.557347)
			(xy 162.595014 -371.622788) (xy 162.586225 -371.687636) (xy 162.568803 -371.750715) (xy 162.543062 -371.81088)
			(xy 162.526726 -371.839236) (xy 162.523347 -371.845244) (xy 162.519621 -371.85851) (xy 162.51936 -371.865398)
			(xy 162.51936 -372.614698) (xy 162.519564 -372.621593) (xy 162.523312 -372.634865) (xy 162.526726 -372.64086)
			(xy 162.543093 -372.6692) (xy 162.568836 -372.72937) (xy 162.586261 -372.792454) (xy 162.595051 -372.857306)
			(xy 162.595047 -372.922752) (xy 162.586249 -372.987604) (xy 162.568817 -373.050685) (xy 162.543067 -373.110852)
			(xy 162.526726 -373.139208) (xy 162.523357 -373.145221) (xy 162.519625 -373.158483) (xy 162.51936 -373.16537)
			(xy 162.51936 -373.451374) (xy 162.518852 -373.461499) (xy 162.511133 -373.48022) (xy 162.496853 -373.494577)
			(xy 162.478174 -373.502397) (xy 162.468052 -373.502936) (xy 161.751772 -373.502936) (xy 161.741621 -373.502502)
			(xy 161.722874 -373.494704) (xy 161.708553 -373.480312) (xy 161.700848 -373.461527) (xy 161.700464 -373.451374)
			(xy 161.700464 -373.16537) (xy 161.700231 -373.158477) (xy 161.696502 -373.145205) (xy 161.693098 -373.139208)
			(xy 161.676791 -373.110835) (xy 161.651046 -373.050672) (xy 161.633618 -372.987595) (xy 161.624822 -372.922749)
			(xy 161.624819 -372.857309) (xy 161.633606 -372.792462) (xy 161.651027 -372.729383) (xy 161.676764 -372.669217)
			(xy 161.693098 -372.64086) (xy 161.696472 -372.63485) (xy 161.700202 -372.621586) (xy 161.700464 -372.614698)
			(xy 161.700464 -371.865398) (xy 161.700236 -371.858506) (xy 161.696491 -371.84524) (xy 161.693098 -371.839236)
			(xy 161.67673 -371.810897) (xy 161.650991 -371.750726) (xy 161.63357 -371.687642) (xy 161.624781 -371.62279)
			(xy 160.366031 -371.62279) (xy 160.368926 -371.629557) (xy 160.386353 -371.692639) (xy 160.395145 -371.75749)
			(xy 160.395143 -371.822934) (xy 160.386348 -371.887785) (xy 160.368919 -371.950865) (xy 160.343171 -372.011032)
			(xy 160.326832 -372.039388) (xy 160.323524 -372.045416) (xy 160.319914 -372.058677) (xy 160.31972 -372.06555)
			(xy 160.31972 -372.351554) (xy 160.319297 -372.361728) (xy 160.31152 -372.38053) (xy 160.297133 -372.394918)
			(xy 160.278332 -372.402697) (xy 160.268158 -372.403116) (xy 159.551878 -372.403116) (xy 159.541699 -372.402753)
			(xy 159.522895 -372.394952) (xy 159.50851 -372.380547) (xy 159.500734 -372.361733) (xy 159.500316 -372.351554)
			(xy 159.500316 -372.06555) (xy 159.500103 -372.058678) (xy 159.496509 -372.045416) (xy 159.493204 -372.039388)
			(xy 159.47688 -372.011025) (xy 159.451136 -371.950859) (xy 159.43371 -371.887781) (xy 159.424916 -371.822933)
			(xy 159.424915 -371.757491) (xy 159.433705 -371.692643) (xy 159.451128 -371.629563) (xy 159.476869 -371.569397)
			(xy 159.493204 -371.54104) (xy 159.496505 -371.535009) (xy 159.500119 -371.52175) (xy 159.500316 -371.514878)
			(xy 159.500316 -370.765324) (xy 159.500113 -370.758452) (xy 159.496512 -370.745189) (xy 159.493204 -370.739162)
			(xy 159.476858 -370.710811) (xy 159.451116 -370.650643) (xy 159.433692 -370.587562) (xy 159.424901 -370.522711)
			(xy 156.147813 -370.522711) (xy 154.742896 -371.927628) (xy 154.736055 -371.935028) (xy 154.728331 -371.953626)
			(xy 154.72791 -371.963696) (xy 154.72791 -374.422887) (xy 159.424884 -374.422887) (xy 159.424889 -374.357441)
			(xy 159.433687 -374.29259) (xy 159.451117 -374.229508) (xy 159.476865 -374.169341) (xy 159.493204 -374.140984)
			(xy 159.496525 -374.134962) (xy 159.500127 -374.121696) (xy 159.500316 -374.114822) (xy 159.500316 -373.828818)
			(xy 159.500847 -373.818664) (xy 159.508612 -373.799899) (xy 159.522966 -373.785534) (xy 159.541724 -373.777755)
			(xy 159.551878 -373.777256) (xy 160.268158 -373.777256) (xy 160.278329 -373.777699) (xy 160.297126 -373.785473)
			(xy 160.311513 -373.799854) (xy 160.319297 -373.818647) (xy 160.31972 -373.828818) (xy 160.31972 -374.114822)
			(xy 160.319901 -374.121696) (xy 160.323516 -374.134959) (xy 160.326832 -374.140984) (xy 160.343135 -374.16936)
			(xy 160.368883 -374.229521) (xy 160.386315 -374.292597) (xy 160.395113 -374.357444) (xy 160.395118 -374.422884)
			(xy 160.395118 -374.422887) (xy 163.82492 -374.422887) (xy 163.824925 -374.357441) (xy 163.833724 -374.292589)
			(xy 163.851156 -374.229508) (xy 163.876906 -374.16934) (xy 163.893246 -374.140984) (xy 163.896615 -374.134972)
			(xy 163.900347 -374.121709) (xy 163.900612 -374.114822) (xy 163.900612 -373.828818) (xy 163.90114 -373.818696)
			(xy 163.908857 -373.79998) (xy 163.92313 -373.785624) (xy 163.941801 -373.7778) (xy 163.95192 -373.777256)
			(xy 164.6682 -373.777256) (xy 164.678349 -373.777721) (xy 164.697092 -373.785508) (xy 164.711414 -373.799891)
			(xy 164.719122 -373.818668) (xy 164.719508 -373.828818) (xy 164.719508 -374.114822) (xy 164.71977 -374.121711)
			(xy 164.723493 -374.134977) (xy 164.726874 -374.140984) (xy 164.743175 -374.16936) (xy 164.768922 -374.229522)
			(xy 164.786352 -374.292598) (xy 164.795149 -374.357444) (xy 164.795154 -374.422884) (xy 164.795154 -374.422887)
			(xy 168.224957 -374.422887) (xy 168.224961 -374.357441) (xy 168.233761 -374.292588) (xy 168.251194 -374.229507)
			(xy 168.276946 -374.16934) (xy 168.293288 -374.140984) (xy 168.296608 -374.134962) (xy 168.30021 -374.121696)
			(xy 168.3004 -374.114822) (xy 168.3004 -373.828818) (xy 168.300947 -373.818666) (xy 168.308709 -373.799905)
			(xy 168.323058 -373.78554) (xy 168.341811 -373.777758) (xy 168.351962 -373.777256) (xy 169.068242 -373.777256)
			(xy 169.078405 -373.777699) (xy 169.097178 -373.785491) (xy 169.111543 -373.799872) (xy 169.119312 -373.818655)
			(xy 169.119804 -373.828818) (xy 169.119804 -374.114822) (xy 169.119987 -374.121696) (xy 169.123601 -374.134959)
			(xy 169.126916 -374.140984) (xy 169.143219 -374.169359) (xy 169.168969 -374.229521) (xy 169.186401 -374.292597)
			(xy 169.195199 -374.357444) (xy 169.195204 -374.422884) (xy 169.195204 -374.422887) (xy 172.624746 -374.422887)
			(xy 172.624751 -374.357441) (xy 172.63355 -374.292589) (xy 172.650983 -374.229507) (xy 172.676735 -374.16934)
			(xy 172.693076 -374.140984) (xy 172.696395 -374.134961) (xy 172.699998 -374.121696) (xy 172.700188 -374.114822)
			(xy 172.700188 -373.828818) (xy 172.70058 -373.818641) (xy 172.708368 -373.799837) (xy 172.722764 -373.78545)
			(xy 172.741573 -373.777673) (xy 172.75175 -373.777256) (xy 173.46803 -373.777256) (xy 173.478192 -373.777709)
			(xy 173.496965 -373.785497) (xy 173.51133 -373.799875) (xy 173.5191 -373.818656) (xy 173.519592 -373.828818)
			(xy 173.519592 -374.114822) (xy 173.519776 -374.121696) (xy 173.52339 -374.134959) (xy 173.526704 -374.140984)
			(xy 173.543004 -374.16936) (xy 173.568749 -374.229523) (xy 173.586178 -374.292599) (xy 173.594975 -374.357444)
			(xy 173.594977 -374.390158) (xy 177.023784 -374.390158) (xy 177.027775 -374.327991) (xy 177.039684 -374.266844)
			(xy 177.059313 -374.207723) (xy 177.086342 -374.151597) (xy 177.120326 -374.099388) (xy 177.160708 -374.051953)
			(xy 177.206824 -374.010072) (xy 177.257916 -373.974432) (xy 177.313147 -373.945618) (xy 177.371609 -373.924104)
			(xy 177.432343 -373.910242) (xy 177.49435 -373.90426) (xy 177.556613 -373.906256) (xy 177.61811 -373.916199)
			(xy 177.677831 -373.933923) (xy 177.734794 -373.95914) (xy 177.788065 -373.991433) (xy 177.83677 -374.030273)
			(xy 177.880107 -374.075023) (xy 177.917367 -374.124947) (xy 177.947936 -374.179226) (xy 177.971314 -374.236969)
			(xy 177.987115 -374.297227) (xy 177.995081 -374.35901) (xy 177.99558 -374.390158) (xy 177.995081 -374.421306)
			(xy 177.987115 -374.483089) (xy 177.971314 -374.543347) (xy 177.947936 -374.60109) (xy 177.917367 -374.655369)
			(xy 177.880107 -374.705293) (xy 177.83677 -374.750043) (xy 177.788065 -374.788883) (xy 177.734794 -374.821176)
			(xy 177.677831 -374.846393) (xy 177.61811 -374.864117) (xy 177.556613 -374.87406) (xy 177.49435 -374.876056)
			(xy 177.432343 -374.870074) (xy 177.371609 -374.856212) (xy 177.313147 -374.834698) (xy 177.257916 -374.805884)
			(xy 177.206824 -374.770244) (xy 177.160708 -374.728363) (xy 177.120326 -374.680928) (xy 177.086342 -374.628719)
			(xy 177.059313 -374.572593) (xy 177.039684 -374.513472) (xy 177.027775 -374.452325) (xy 177.023784 -374.390158)
			(xy 173.594977 -374.390158) (xy 173.59498 -374.422884) (xy 173.586193 -374.487731) (xy 173.568773 -374.550809)
			(xy 173.543037 -374.610975) (xy 173.526704 -374.639332) (xy 173.523378 -374.645351) (xy 173.519779 -374.658619)
			(xy 173.519592 -374.665494) (xy 173.519592 -375.414794) (xy 173.519787 -375.421667) (xy 173.523393 -375.43493)
			(xy 173.526704 -375.440956) (xy 173.543065 -375.469299) (xy 173.568805 -375.529469) (xy 173.586227 -375.592552)
			(xy 173.595016 -375.657403) (xy 173.595012 -375.722848) (xy 173.586216 -375.787699) (xy 173.568788 -375.85078)
			(xy 173.543042 -375.910947) (xy 173.526704 -375.939304) (xy 173.523388 -375.945328) (xy 173.519783 -375.958592)
			(xy 173.519592 -375.965466) (xy 173.519592 -376.25147) (xy 173.519043 -376.261622) (xy 173.511284 -376.280385)
			(xy 173.496935 -376.29475) (xy 173.478182 -376.302531) (xy 173.46803 -376.303032) (xy 172.75175 -376.303032)
			(xy 172.741578 -376.302595) (xy 172.722779 -376.29482) (xy 172.708391 -376.280438) (xy 172.700609 -376.261642)
			(xy 172.700188 -376.25147) (xy 172.700188 -375.965466) (xy 172.700011 -375.958592) (xy 172.696393 -375.945329)
			(xy 172.693076 -375.939304) (xy 172.676763 -375.910934) (xy 172.651015 -375.850771) (xy 172.633584 -375.787694)
			(xy 172.624787 -375.722846) (xy 172.624784 -375.657405) (xy 172.633574 -375.592557) (xy 172.650998 -375.529478)
			(xy 172.676739 -375.469312) (xy 172.693076 -375.440956) (xy 172.696405 -375.434938) (xy 172.700002 -375.421669)
			(xy 172.700188 -375.414794) (xy 172.700188 -374.665494) (xy 172.7 -374.65862) (xy 172.696389 -374.645358)
			(xy 172.693076 -374.639332) (xy 172.676702 -374.610996) (xy 172.650959 -374.550825) (xy 172.633535 -374.487741)
			(xy 172.624746 -374.422887) (xy 169.195204 -374.422887) (xy 169.186415 -374.487732) (xy 169.168993 -374.550811)
			(xy 169.143252 -374.610976) (xy 169.126916 -374.639332) (xy 169.123591 -374.645352) (xy 169.119992 -374.658619)
			(xy 169.119804 -374.665494) (xy 169.119804 -375.414794) (xy 169.119998 -375.421667) (xy 169.123605 -375.43493)
			(xy 169.126916 -375.440956) (xy 169.14328 -375.469298) (xy 169.169024 -375.529467) (xy 169.186449 -375.59255)
			(xy 169.19524 -375.657403) (xy 169.195237 -375.722849) (xy 169.186439 -375.7877) (xy 169.169007 -375.850781)
			(xy 169.143257 -375.910948) (xy 169.126916 -375.939304) (xy 169.123601 -375.945329) (xy 169.119995 -375.958592)
			(xy 169.119804 -375.965466) (xy 169.119804 -376.25147) (xy 169.119243 -376.261621) (xy 169.111487 -376.280381)
			(xy 169.097142 -376.294746) (xy 169.078392 -376.302529) (xy 169.068242 -376.303032) (xy 168.351962 -376.303032)
			(xy 168.341798 -376.302597) (xy 168.323022 -376.294804) (xy 168.308657 -376.280421) (xy 168.30089 -376.261635)
			(xy 168.3004 -376.25147) (xy 168.3004 -375.965466) (xy 168.300221 -375.958592) (xy 168.296604 -375.945329)
			(xy 168.293288 -375.939304) (xy 168.276975 -375.910934) (xy 168.251226 -375.850771) (xy 168.233795 -375.787694)
			(xy 168.224998 -375.722846) (xy 168.224994 -375.657405) (xy 168.233784 -375.592557) (xy 168.251209 -375.529477)
			(xy 168.276951 -375.469312) (xy 168.293288 -375.440956) (xy 168.296618 -375.434939) (xy 168.300214 -375.421669)
			(xy 168.3004 -375.414794) (xy 168.3004 -374.665494) (xy 168.30021 -374.658621) (xy 168.296601 -374.645358)
			(xy 168.293288 -374.639332) (xy 168.276913 -374.610996) (xy 168.25117 -374.550825) (xy 168.233746 -374.487741)
			(xy 168.224957 -374.422887) (xy 164.795154 -374.422887) (xy 164.786366 -374.487731) (xy 164.768946 -374.55081)
			(xy 164.743208 -374.610976) (xy 164.726874 -374.639332) (xy 164.723501 -374.645342) (xy 164.719771 -374.658606)
			(xy 164.719508 -374.665494) (xy 164.719508 -375.414794) (xy 164.719743 -375.421685) (xy 164.723484 -375.434951)
			(xy 164.726874 -375.440956) (xy 164.743236 -375.469298) (xy 164.768977 -375.529468) (xy 164.7864 -375.592551)
			(xy 164.79519 -375.657403) (xy 164.795186 -375.722848) (xy 164.78639 -375.787699) (xy 164.76896 -375.85078)
			(xy 164.743213 -375.910948) (xy 164.726874 -375.939304) (xy 164.72351 -375.945319) (xy 164.719774 -375.958579)
			(xy 164.719508 -375.965466) (xy 164.719508 -376.25147) (xy 164.71895 -376.261589) (xy 164.711241 -376.2803)
			(xy 164.696977 -376.294656) (xy 164.678316 -376.302485) (xy 164.6682 -376.303032) (xy 163.95192 -376.303032)
			(xy 163.941771 -376.302563) (xy 163.923025 -376.29478) (xy 163.908702 -376.280398) (xy 163.900996 -376.26162)
			(xy 163.900612 -376.25147) (xy 163.900612 -375.965466) (xy 163.900387 -375.958573) (xy 163.896653 -375.9453)
			(xy 163.893246 -375.939304) (xy 163.876934 -375.910934) (xy 163.851187 -375.85077) (xy 163.833758 -375.787693)
			(xy 163.824961 -375.722846) (xy 163.824958 -375.657405) (xy 163.833747 -375.592557) (xy 163.85117 -375.529478)
			(xy 163.87691 -375.469312) (xy 163.893246 -375.440956) (xy 163.896625 -375.434948) (xy 163.900351 -375.421682)
			(xy 163.900612 -375.414794) (xy 163.900612 -374.665494) (xy 163.900415 -374.658598) (xy 163.896663 -374.645326)
			(xy 163.893246 -374.639332) (xy 163.876873 -374.610996) (xy 163.851132 -374.550824) (xy 163.833709 -374.48774)
			(xy 163.82492 -374.422887) (xy 160.395118 -374.422887) (xy 160.386329 -374.487732) (xy 160.368907 -374.550811)
			(xy 160.343167 -374.610976) (xy 160.326832 -374.639332) (xy 160.323509 -374.645352) (xy 160.319908 -374.658619)
			(xy 160.31972 -374.665494) (xy 160.31972 -375.414794) (xy 160.319912 -375.421667) (xy 160.32352 -375.43493)
			(xy 160.326832 -375.440956) (xy 160.343196 -375.469298) (xy 160.368939 -375.529468) (xy 160.386363 -375.592551)
			(xy 160.395154 -375.657403) (xy 160.39515 -375.722848) (xy 160.386353 -375.7877) (xy 160.368922 -375.850781)
			(xy 160.343172 -375.910948) (xy 160.326832 -375.939304) (xy 160.323519 -375.945329) (xy 160.319912 -375.958592)
			(xy 160.31972 -375.965466) (xy 160.31972 -376.25147) (xy 160.31931 -376.261645) (xy 160.311528 -376.280447)
			(xy 160.297137 -376.294834) (xy 160.278333 -376.302613) (xy 160.268158 -376.303032) (xy 159.551878 -376.303032)
			(xy 159.541701 -376.302653) (xy 159.5229 -376.294855) (xy 159.508515 -376.280456) (xy 159.500737 -376.261647)
			(xy 159.500316 -376.25147) (xy 159.500316 -375.965466) (xy 159.500135 -375.958592) (xy 159.496519 -375.945329)
			(xy 159.493204 -375.939304) (xy 159.476893 -375.910933) (xy 159.451149 -375.85077) (xy 159.433721 -375.787693)
			(xy 159.424925 -375.722846) (xy 159.424922 -375.657405) (xy 159.43371 -375.592558) (xy 159.451132 -375.529479)
			(xy 159.47687 -375.469313) (xy 159.493204 -375.440956) (xy 159.496535 -375.434939) (xy 159.50013 -375.421669)
			(xy 159.500316 -375.414794) (xy 159.500316 -374.665494) (xy 159.500124 -374.658621) (xy 159.496516 -374.645358)
			(xy 159.493204 -374.639332) (xy 159.476832 -374.610995) (xy 159.451093 -374.550824) (xy 159.433672 -374.487739)
			(xy 159.424884 -374.422887) (xy 154.72791 -374.422887) (xy 154.72791 -376.822925) (xy 161.624805 -376.822925)
			(xy 161.624805 -376.757482) (xy 161.633597 -376.692633) (xy 161.651021 -376.629554) (xy 161.676762 -376.569387)
			(xy 161.693098 -376.54103) (xy 161.696448 -376.535008) (xy 161.700193 -376.521753) (xy 161.700464 -376.514868)
			(xy 161.700464 -375.765568) (xy 161.700231 -375.758675) (xy 161.696503 -375.745403) (xy 161.693098 -375.739406)
			(xy 161.676789 -375.711034) (xy 161.651045 -375.650871) (xy 161.633617 -375.587794) (xy 161.624821 -375.522948)
			(xy 161.624818 -375.457507) (xy 161.633606 -375.39266) (xy 161.651027 -375.329581) (xy 161.676764 -375.269415)
			(xy 161.693098 -375.241058) (xy 161.696473 -375.235048) (xy 161.700202 -375.221784) (xy 161.700464 -375.214896)
			(xy 161.700464 -374.928638) (xy 161.700959 -374.918511) (xy 161.708678 -374.899786) (xy 161.722963 -374.885428)
			(xy 161.741647 -374.877611) (xy 161.751772 -374.877076) (xy 162.468052 -374.877076) (xy 162.4782 -374.877561)
			(xy 162.496947 -374.885336) (xy 162.511271 -374.899713) (xy 162.518977 -374.918489) (xy 162.51936 -374.928638)
			(xy 162.51936 -375.214896) (xy 162.519565 -375.221791) (xy 162.523312 -375.235063) (xy 162.526726 -375.241058)
			(xy 162.543092 -375.269399) (xy 162.568835 -375.329569) (xy 162.58626 -375.392652) (xy 162.59505 -375.457505)
			(xy 162.595046 -375.52295) (xy 162.586248 -375.587802) (xy 162.568817 -375.650883) (xy 162.543067 -375.71105)
			(xy 162.526726 -375.739406) (xy 162.523358 -375.745419) (xy 162.519625 -375.758681) (xy 162.51936 -375.765568)
			(xy 162.51936 -376.514868) (xy 162.519576 -376.521762) (xy 162.523316 -376.535034) (xy 162.526726 -376.54103)
			(xy 162.543068 -376.569384) (xy 162.568813 -376.629551) (xy 162.586241 -376.692631) (xy 162.595034 -376.757482)
			(xy 162.595033 -376.822925) (xy 166.024841 -376.822925) (xy 166.024841 -376.757482) (xy 166.033634 -376.692633)
			(xy 166.051059 -376.629553) (xy 166.076803 -376.569386) (xy 166.09314 -376.54103) (xy 166.096439 -376.534998)
			(xy 166.100055 -376.52174) (xy 166.100252 -376.514868) (xy 166.100252 -375.765568) (xy 166.100078 -375.758693)
			(xy 166.096458 -375.74543) (xy 166.09314 -375.739406) (xy 166.07683 -375.711035) (xy 166.051083 -375.650872)
			(xy 166.033654 -375.587795) (xy 166.024857 -375.522948) (xy 166.024854 -375.457507) (xy 166.033643 -375.392659)
			(xy 166.051065 -375.32958) (xy 166.076805 -375.269414) (xy 166.09314 -375.241058) (xy 166.096465 -375.235038)
			(xy 166.100065 -375.221771) (xy 166.100252 -375.214896) (xy 166.100252 -374.928638) (xy 166.100695 -374.918467)
			(xy 166.10847 -374.899671) (xy 166.12285 -374.885284) (xy 166.141643 -374.8775) (xy 166.151814 -374.877076)
			(xy 166.868094 -374.877076) (xy 166.87827 -374.87747) (xy 166.897072 -374.88526) (xy 166.911458 -374.899655)
			(xy 166.919237 -374.918462) (xy 166.919656 -374.928638) (xy 166.919656 -375.214896) (xy 166.919842 -375.22177)
			(xy 166.923454 -375.235033) (xy 166.926768 -375.241058) (xy 166.943132 -375.269399) (xy 166.968873 -375.32957)
			(xy 166.986296 -375.392653) (xy 166.995086 -375.457505) (xy 166.995082 -375.52295) (xy 166.986285 -375.587801)
			(xy 166.968855 -375.650882) (xy 166.943107 -375.71105) (xy 166.926768 -375.739406) (xy 166.923449 -375.745428)
			(xy 166.919847 -375.758694) (xy 166.919656 -375.765568) (xy 166.919656 -376.514868) (xy 166.919853 -376.521741)
			(xy 166.923457 -376.535004) (xy 166.926768 -376.54103) (xy 166.943109 -376.569384) (xy 166.968852 -376.629552)
			(xy 166.986278 -376.692632) (xy 166.99507 -376.757482) (xy 170.424877 -376.757482) (xy 170.43367 -376.692632)
			(xy 170.451098 -376.629552) (xy 170.476844 -376.569386) (xy 170.493182 -376.54103) (xy 170.49653 -376.535007)
			(xy 170.500277 -376.521753) (xy 170.500548 -376.514868) (xy 170.500548 -375.765568) (xy 170.500317 -375.758675)
			(xy 170.496587 -375.745403) (xy 170.493182 -375.739406) (xy 170.47687 -375.711035) (xy 170.451122 -375.650872)
			(xy 170.433691 -375.587795) (xy 170.424894 -375.522948) (xy 170.42489 -375.457507) (xy 170.43368 -375.392658)
			(xy 170.451104 -375.329579) (xy 170.476845 -375.269414) (xy 170.493182 -375.241058) (xy 170.496556 -375.235048)
			(xy 170.500286 -375.221784) (xy 170.500548 -375.214896) (xy 170.500548 -374.928638) (xy 170.501058 -374.918513)
			(xy 170.508775 -374.899791) (xy 170.523054 -374.885433) (xy 170.541734 -374.877614) (xy 170.551856 -374.877076)
			(xy 171.268136 -374.877076) (xy 171.278289 -374.877492) (xy 171.297038 -374.885295) (xy 171.311359 -374.899692)
			(xy 171.319062 -374.918482) (xy 171.319444 -374.928638) (xy 171.319444 -375.214896) (xy 171.319651 -375.221791)
			(xy 171.323397 -375.235063) (xy 171.32681 -375.241058) (xy 171.343176 -375.269399) (xy 171.36892 -375.329568)
			(xy 171.386345 -375.392652) (xy 171.395136 -375.457505) (xy 171.395132 -375.52295) (xy 171.386334 -375.587802)
			(xy 171.368902 -375.650883) (xy 171.343151 -375.71105) (xy 171.32681 -375.739406) (xy 171.323448 -375.745422)
			(xy 171.31971 -375.758682) (xy 171.319444 -375.765568) (xy 171.319444 -376.514868) (xy 171.319662 -376.521762)
			(xy 171.323401 -376.535034) (xy 171.32681 -376.54103) (xy 171.343152 -376.569384) (xy 171.368899 -376.62955)
			(xy 171.386327 -376.692631) (xy 171.39512 -376.757481) (xy 171.39512 -376.757482) (xy 174.824927 -376.757482)
			(xy 174.833719 -376.692633) (xy 174.851145 -376.629553) (xy 174.876887 -376.569386) (xy 174.893224 -376.54103)
			(xy 174.89653 -376.535001) (xy 174.900141 -376.521741) (xy 174.900336 -376.514868) (xy 174.900336 -375.765568)
			(xy 174.900152 -375.758694) (xy 174.896538 -375.745432) (xy 174.893224 -375.739406) (xy 174.876914 -375.711035)
			(xy 174.851169 -375.650871) (xy 174.83374 -375.587794) (xy 174.824944 -375.522948) (xy 174.82494 -375.457507)
			(xy 174.833729 -375.392659) (xy 174.85115 -375.329581) (xy 174.876889 -375.269414) (xy 174.893224 -375.241058)
			(xy 174.896555 -375.235042) (xy 174.90015 -375.221771) (xy 174.900336 -375.214896) (xy 174.900336 -374.928638)
			(xy 174.900795 -374.918469) (xy 174.908567 -374.899676) (xy 174.922942 -374.88529) (xy 174.941729 -374.877503)
			(xy 174.951898 -374.877076) (xy 175.668178 -374.877076) (xy 175.678353 -374.877483) (xy 175.697154 -374.885268)
			(xy 175.711541 -374.899659) (xy 175.71932 -374.918463) (xy 175.71974 -374.928638) (xy 175.71974 -375.214896)
			(xy 175.719929 -375.22177) (xy 175.723539 -375.235032) (xy 175.726852 -375.241058) (xy 175.743217 -375.269399)
			(xy 175.768959 -375.329569) (xy 175.786382 -375.392652) (xy 175.795172 -375.457505) (xy 175.795168 -375.52295)
			(xy 175.786371 -375.587801) (xy 175.76894 -375.650883) (xy 175.752145 -375.69013) (xy 177.023784 -375.69013)
			(xy 177.027775 -375.627963) (xy 177.039684 -375.566816) (xy 177.059313 -375.507695) (xy 177.086342 -375.451569)
			(xy 177.120326 -375.39936) (xy 177.160708 -375.351925) (xy 177.206824 -375.310044) (xy 177.257916 -375.274404)
			(xy 177.313147 -375.24559) (xy 177.371609 -375.224076) (xy 177.432343 -375.210214) (xy 177.49435 -375.204232)
			(xy 177.556613 -375.206228) (xy 177.61811 -375.216171) (xy 177.677831 -375.233895) (xy 177.734794 -375.259112)
			(xy 177.788065 -375.291405) (xy 177.83677 -375.330245) (xy 177.880107 -375.374995) (xy 177.917367 -375.424919)
			(xy 177.947936 -375.479198) (xy 177.952403 -375.490232) (xy 179.223932 -375.490232) (xy 179.227923 -375.428065)
			(xy 179.239832 -375.366918) (xy 179.259461 -375.307797) (xy 179.28649 -375.251671) (xy 179.320474 -375.199462)
			(xy 179.360856 -375.152027) (xy 179.406972 -375.110146) (xy 179.458064 -375.074506) (xy 179.513295 -375.045692)
			(xy 179.571757 -375.024178) (xy 179.632491 -375.010316) (xy 179.694498 -375.004334) (xy 179.756761 -375.00633)
			(xy 179.818258 -375.016273) (xy 179.877979 -375.033997) (xy 179.934942 -375.059214) (xy 179.988213 -375.091507)
			(xy 180.036918 -375.130347) (xy 180.080255 -375.175097) (xy 180.117515 -375.225021) (xy 180.148084 -375.2793)
			(xy 180.171462 -375.337043) (xy 180.187263 -375.397301) (xy 180.195229 -375.459084) (xy 180.195728 -375.490232)
			(xy 180.195229 -375.52138) (xy 180.187263 -375.583163) (xy 180.171462 -375.643421) (xy 180.148084 -375.701164)
			(xy 180.117515 -375.755443) (xy 180.080255 -375.805367) (xy 180.036918 -375.850117) (xy 179.988213 -375.888957)
			(xy 179.934942 -375.92125) (xy 179.877979 -375.946467) (xy 179.818258 -375.964191) (xy 179.756761 -375.974134)
			(xy 179.694498 -375.97613) (xy 179.632491 -375.970148) (xy 179.571757 -375.956286) (xy 179.513295 -375.934772)
			(xy 179.458064 -375.905958) (xy 179.406972 -375.870318) (xy 179.360856 -375.828437) (xy 179.320474 -375.781002)
			(xy 179.28649 -375.728793) (xy 179.259461 -375.672667) (xy 179.239832 -375.613546) (xy 179.227923 -375.552399)
			(xy 179.223932 -375.490232) (xy 177.952403 -375.490232) (xy 177.971314 -375.536941) (xy 177.987115 -375.597199)
			(xy 177.995081 -375.658982) (xy 177.99558 -375.69013) (xy 177.995081 -375.721278) (xy 177.987115 -375.783061)
			(xy 177.971314 -375.843319) (xy 177.947936 -375.901062) (xy 177.917367 -375.955341) (xy 177.880107 -376.005265)
			(xy 177.83677 -376.050015) (xy 177.788065 -376.088855) (xy 177.734794 -376.121148) (xy 177.677831 -376.146365)
			(xy 177.61811 -376.164089) (xy 177.556613 -376.174032) (xy 177.49435 -376.176028) (xy 177.432343 -376.170046)
			(xy 177.371609 -376.156184) (xy 177.313147 -376.13467) (xy 177.257916 -376.105856) (xy 177.206824 -376.070216)
			(xy 177.160708 -376.028335) (xy 177.120326 -375.9809) (xy 177.086342 -375.928691) (xy 177.059313 -375.872565)
			(xy 177.039684 -375.813444) (xy 177.027775 -375.752297) (xy 177.023784 -375.69013) (xy 175.752145 -375.69013)
			(xy 175.743192 -375.71105) (xy 175.726852 -375.739406) (xy 175.723539 -375.745432) (xy 175.719932 -375.758695)
			(xy 175.71974 -375.765568) (xy 175.71974 -376.514868) (xy 175.719939 -376.521741) (xy 175.723542 -376.535004)
			(xy 175.726852 -376.54103) (xy 175.743193 -376.569384) (xy 175.768937 -376.629551) (xy 175.786363 -376.692632)
			(xy 175.795156 -376.757482) (xy 175.795156 -376.790204) (xy 179.223932 -376.790204) (xy 179.227923 -376.728037)
			(xy 179.239832 -376.66689) (xy 179.259461 -376.607769) (xy 179.28649 -376.551643) (xy 179.320474 -376.499434)
			(xy 179.360856 -376.451999) (xy 179.406972 -376.410118) (xy 179.458064 -376.374478) (xy 179.513295 -376.345664)
			(xy 179.571757 -376.32415) (xy 179.632491 -376.310288) (xy 179.694498 -376.304306) (xy 179.756761 -376.306302)
			(xy 179.818258 -376.316245) (xy 179.877979 -376.333969) (xy 179.934942 -376.359186) (xy 179.988213 -376.391479)
			(xy 180.036918 -376.430319) (xy 180.080255 -376.475069) (xy 180.117515 -376.524993) (xy 180.148084 -376.579272)
			(xy 180.171462 -376.637015) (xy 180.187263 -376.697273) (xy 180.195229 -376.759056) (xy 180.195728 -376.790204)
			(xy 180.195229 -376.821352) (xy 180.187263 -376.883135) (xy 180.171462 -376.943393) (xy 180.148084 -377.001136)
			(xy 180.117515 -377.055415) (xy 180.080255 -377.105339) (xy 180.036918 -377.150089) (xy 179.988213 -377.188929)
			(xy 179.934942 -377.221222) (xy 179.877979 -377.246439) (xy 179.818258 -377.264163) (xy 179.756761 -377.274106)
			(xy 179.694498 -377.276102) (xy 179.632491 -377.27012) (xy 179.571757 -377.256258) (xy 179.513295 -377.234744)
			(xy 179.458064 -377.20593) (xy 179.406972 -377.17029) (xy 179.360856 -377.128409) (xy 179.320474 -377.080974)
			(xy 179.28649 -377.028765) (xy 179.259461 -376.972639) (xy 179.239832 -376.913518) (xy 179.227923 -376.852371)
			(xy 179.223932 -376.790204) (xy 175.795156 -376.790204) (xy 175.795156 -376.822925) (xy 175.786362 -376.887775)
			(xy 175.768935 -376.950855) (xy 175.74319 -377.011022) (xy 175.726852 -377.039378) (xy 175.723549 -377.045409)
			(xy 175.719935 -377.058668) (xy 175.71974 -377.06554) (xy 175.71974 -377.35129) (xy 175.719328 -377.361464)
			(xy 175.711542 -377.380262) (xy 175.697152 -377.394648) (xy 175.678352 -377.40243) (xy 175.668178 -377.402852)
			(xy 174.951898 -377.402852) (xy 174.941725 -377.402438) (xy 174.922928 -377.39465) (xy 174.908543 -377.380262)
			(xy 174.90076 -377.361463) (xy 174.900336 -377.35129) (xy 174.900336 -377.06554) (xy 174.900124 -377.058668)
			(xy 174.896529 -377.045406) (xy 174.893224 -377.039378) (xy 174.87689 -377.01102) (xy 174.851147 -376.950853)
			(xy 174.833721 -376.887774) (xy 174.824928 -376.822925) (xy 174.824927 -376.757482) (xy 171.39512 -376.757482)
			(xy 171.39512 -376.822925) (xy 171.386325 -376.887776) (xy 171.368896 -376.950856) (xy 171.343149 -377.011022)
			(xy 171.32681 -377.039378) (xy 171.323458 -377.045399) (xy 171.319714 -377.058655) (xy 171.319444 -377.06554)
			(xy 171.319444 -377.35129) (xy 171.318965 -377.361418) (xy 171.311237 -377.380142) (xy 171.296948 -377.394499)
			(xy 171.278262 -377.402316) (xy 171.268136 -377.402852) (xy 170.551856 -377.402852) (xy 170.541706 -377.402415)
			(xy 170.522962 -377.394615) (xy 170.508642 -377.380224) (xy 170.500935 -377.361442) (xy 170.500548 -377.35129)
			(xy 170.500548 -377.06554) (xy 170.500328 -377.058646) (xy 170.496591 -377.045374) (xy 170.493182 -377.039378)
			(xy 170.476847 -377.01102) (xy 170.4511 -376.950855) (xy 170.433672 -376.887775) (xy 170.424878 -376.822925)
			(xy 170.424877 -376.757482) (xy 166.99507 -376.757482) (xy 166.995069 -376.822925) (xy 166.986276 -376.887775)
			(xy 166.968849 -376.950855) (xy 166.943105 -377.011022) (xy 166.926768 -377.039378) (xy 166.923459 -377.045405)
			(xy 166.91985 -377.058667) (xy 166.919656 -377.06554) (xy 166.919656 -377.35129) (xy 166.919228 -377.361462)
			(xy 166.911445 -377.380257) (xy 166.897061 -377.394643) (xy 166.878266 -377.402427) (xy 166.868094 -377.402852)
			(xy 166.151814 -377.402852) (xy 166.141642 -377.402425) (xy 166.122846 -377.394642) (xy 166.10846 -377.380258)
			(xy 166.100676 -377.361462) (xy 166.100252 -377.35129) (xy 166.100252 -377.06554) (xy 166.100051 -377.058667)
			(xy 166.09645 -377.045404) (xy 166.09314 -377.039378) (xy 166.076806 -377.01102) (xy 166.051062 -376.950854)
			(xy 166.033635 -376.887774) (xy 166.024841 -376.822925) (xy 162.595033 -376.822925) (xy 162.586239 -376.887775)
			(xy 162.568811 -376.950856) (xy 162.543065 -377.011022) (xy 162.526726 -377.039378) (xy 162.523368 -377.045396)
			(xy 162.519629 -377.058654) (xy 162.51936 -377.06554) (xy 162.51936 -377.35129) (xy 162.518865 -377.361416)
			(xy 162.511141 -377.380137) (xy 162.496857 -377.394494) (xy 162.478175 -377.402313) (xy 162.468052 -377.402852)
			(xy 161.751772 -377.402852) (xy 161.741623 -377.402402) (xy 161.72288 -377.394607) (xy 161.708559 -377.38022)
			(xy 161.700851 -377.361441) (xy 161.700464 -377.35129) (xy 161.700464 -377.06554) (xy 161.700242 -377.058646)
			(xy 161.696506 -377.045374) (xy 161.693098 -377.039378) (xy 161.676765 -377.01102) (xy 161.651023 -376.950853)
			(xy 161.633598 -376.887773) (xy 161.624805 -376.822925) (xy 154.72791 -376.822925) (xy 154.72791 -378.3228)
			(xy 159.424893 -378.3228) (xy 159.424896 -378.257356) (xy 159.433692 -378.192505) (xy 159.45112 -378.129424)
			(xy 159.476866 -378.069257) (xy 159.493204 -378.0409) (xy 159.496519 -378.034876) (xy 159.500124 -378.021612)
			(xy 159.500316 -378.014738) (xy 159.500316 -377.728734) (xy 159.500791 -377.718567) (xy 159.508561 -377.699778)
			(xy 159.522931 -377.685392) (xy 159.541712 -377.677602) (xy 159.551878 -377.677172) (xy 160.268158 -377.677172)
			(xy 160.278331 -377.677599) (xy 160.297131 -377.685377) (xy 160.311519 -377.699762) (xy 160.319299 -377.718561)
			(xy 160.31972 -377.728734) (xy 160.31972 -378.014738) (xy 160.319933 -378.02161) (xy 160.323527 -378.034873)
			(xy 160.326832 -378.0409) (xy 160.343148 -378.069268) (xy 160.368896 -378.129432) (xy 160.386326 -378.192509)
			(xy 160.395122 -378.257357) (xy 160.395125 -378.322798) (xy 160.395125 -378.3228) (xy 163.82493 -378.3228)
			(xy 163.824933 -378.257355) (xy 163.833729 -378.192504) (xy 163.851159 -378.129423) (xy 163.876907 -378.069256)
			(xy 163.893246 -378.0409) (xy 163.89661 -378.034885) (xy 163.900345 -378.021625) (xy 163.900612 -378.014738)
			(xy 163.900612 -377.728734) (xy 163.901154 -377.718613) (xy 163.908865 -377.699898) (xy 163.923134 -377.685542)
			(xy 163.941802 -377.677716) (xy 163.95192 -377.677172) (xy 164.6682 -377.677172) (xy 164.678351 -377.677621)
			(xy 164.697098 -377.685411) (xy 164.71142 -377.699799) (xy 164.719125 -377.718582) (xy 164.719508 -377.728734)
			(xy 164.719508 -378.014738) (xy 164.719764 -378.021628) (xy 164.723491 -378.034894) (xy 164.726874 -378.0409)
			(xy 164.743189 -378.069268) (xy 164.768934 -378.129432) (xy 164.786363 -378.19251) (xy 164.795158 -378.257357)
			(xy 164.795161 -378.322798) (xy 164.795161 -378.3228) (xy 168.224966 -378.3228) (xy 168.224969 -378.257355)
			(xy 168.233766 -378.192504) (xy 168.251197 -378.129422) (xy 168.276947 -378.069256) (xy 168.293288 -378.0409)
			(xy 168.296602 -378.034875) (xy 168.300208 -378.021612) (xy 168.3004 -378.014738) (xy 168.3004 -377.728734)
			(xy 168.30096 -377.718583) (xy 168.308717 -377.699822) (xy 168.323062 -377.685457) (xy 168.341812 -377.677675)
			(xy 168.351962 -377.677172) (xy 169.068242 -377.677172) (xy 169.078407 -377.6776) (xy 169.097183 -377.685394)
			(xy 169.111548 -377.699781) (xy 169.119315 -377.718569) (xy 169.119804 -377.728734) (xy 169.119804 -378.014738)
			(xy 169.120019 -378.02161) (xy 169.123612 -378.034872) (xy 169.126916 -378.0409) (xy 169.143233 -378.069268)
			(xy 169.168981 -378.129431) (xy 169.186412 -378.192509) (xy 169.195208 -378.257357) (xy 169.195211 -378.322799)
			(xy 169.195211 -378.3228) (xy 172.624755 -378.3228) (xy 172.624758 -378.257355) (xy 172.633555 -378.192504)
			(xy 172.650986 -378.129423) (xy 172.676736 -378.069256) (xy 172.693076 -378.0409) (xy 172.696389 -378.034874)
			(xy 172.699996 -378.021611) (xy 172.700188 -378.014738) (xy 172.700188 -377.728734) (xy 172.700593 -377.718558)
			(xy 172.708376 -377.699755) (xy 172.722768 -377.685367) (xy 172.741574 -377.67759) (xy 172.75175 -377.677172)
			(xy 173.46803 -377.677172) (xy 173.478208 -377.67754) (xy 173.49701 -377.685341) (xy 173.511395 -377.699744)
			(xy 173.519173 -377.718556) (xy 173.519592 -377.728734) (xy 173.519592 -378.014738) (xy 173.519809 -378.021609)
			(xy 173.5234 -378.034872) (xy 173.526704 -378.0409) (xy 173.543018 -378.069269) (xy 173.568762 -378.129433)
			(xy 173.586189 -378.19251) (xy 173.594984 -378.257357) (xy 173.594985 -378.290074) (xy 177.023784 -378.290074)
			(xy 177.027775 -378.227907) (xy 177.039684 -378.16676) (xy 177.059313 -378.107639) (xy 177.086342 -378.051513)
			(xy 177.120326 -377.999304) (xy 177.160708 -377.951869) (xy 177.206824 -377.909988) (xy 177.257916 -377.874348)
			(xy 177.313147 -377.845534) (xy 177.371609 -377.82402) (xy 177.432343 -377.810158) (xy 177.49435 -377.804176)
			(xy 177.556613 -377.806172) (xy 177.61811 -377.816115) (xy 177.677831 -377.833839) (xy 177.734794 -377.859056)
			(xy 177.788065 -377.891349) (xy 177.83677 -377.930189) (xy 177.880107 -377.974939) (xy 177.917367 -378.024863)
			(xy 177.947936 -378.079142) (xy 177.971314 -378.136885) (xy 177.987115 -378.197143) (xy 177.995081 -378.258926)
			(xy 177.99558 -378.290074) (xy 177.995081 -378.321222) (xy 177.987115 -378.383005) (xy 177.971314 -378.443263)
			(xy 177.947936 -378.501006) (xy 177.917367 -378.555285) (xy 177.880107 -378.605209) (xy 177.83677 -378.649959)
			(xy 177.788065 -378.688799) (xy 177.734794 -378.721092) (xy 177.677831 -378.746309) (xy 177.61811 -378.764033)
			(xy 177.556613 -378.773976) (xy 177.49435 -378.775972) (xy 177.432343 -378.76999) (xy 177.371609 -378.756128)
			(xy 177.313147 -378.734614) (xy 177.257916 -378.7058) (xy 177.206824 -378.67016) (xy 177.160708 -378.628279)
			(xy 177.120326 -378.580844) (xy 177.086342 -378.528635) (xy 177.059313 -378.472509) (xy 177.039684 -378.413388)
			(xy 177.027775 -378.352241) (xy 177.023784 -378.290074) (xy 173.594985 -378.290074) (xy 173.594987 -378.322798)
			(xy 173.586198 -378.387646) (xy 173.568776 -378.450725) (xy 173.543038 -378.510891) (xy 173.526704 -378.539248)
			(xy 173.523372 -378.545264) (xy 173.519777 -378.558535) (xy 173.519592 -378.56541) (xy 173.519592 -379.31471)
			(xy 173.519781 -379.321583) (xy 173.523391 -379.334846) (xy 173.526704 -379.340872) (xy 173.543079 -379.369207)
			(xy 173.568817 -379.429379) (xy 173.586238 -379.492464) (xy 173.595025 -379.557317) (xy 173.59502 -379.622762)
			(xy 173.586222 -379.687614) (xy 173.568791 -379.750695) (xy 173.543043 -379.810863) (xy 173.526704 -379.83922)
			(xy 173.523382 -379.845241) (xy 173.519781 -379.858508) (xy 173.519592 -379.865382) (xy 173.519592 -380.151386)
			(xy 173.519056 -380.161539) (xy 173.511292 -380.180302) (xy 173.496939 -380.194667) (xy 173.478183 -380.202447)
			(xy 173.46803 -380.202948) (xy 172.75175 -380.202948) (xy 172.74158 -380.202495) (xy 172.722784 -380.194724)
			(xy 172.708396 -380.180347) (xy 172.700612 -380.161556) (xy 172.700188 -380.151386) (xy 172.700188 -379.865382)
			(xy 172.700005 -379.858508) (xy 172.696391 -379.845245) (xy 172.693076 -379.83922) (xy 172.676776 -379.810843)
			(xy 172.651027 -379.750681) (xy 172.633595 -379.687606) (xy 172.624796 -379.62276) (xy 172.624791 -379.557319)
			(xy 172.633579 -379.492472) (xy 172.651001 -379.429393) (xy 172.676741 -379.369228) (xy 172.693076 -379.340872)
			(xy 172.696399 -379.334851) (xy 172.7 -379.321585) (xy 172.700188 -379.31471) (xy 172.700188 -378.56541)
			(xy 172.699994 -378.558537) (xy 172.696387 -378.545274) (xy 172.693076 -378.539248) (xy 172.676715 -378.510904)
			(xy 172.650972 -378.450735) (xy 172.633546 -378.387652) (xy 172.624755 -378.3228) (xy 169.195211 -378.3228)
			(xy 169.186421 -378.387647) (xy 169.168996 -378.450727) (xy 169.143253 -378.510892) (xy 169.126916 -378.539248)
			(xy 169.123585 -378.545265) (xy 169.119989 -378.558535) (xy 169.119804 -378.56541) (xy 169.119804 -379.31471)
			(xy 169.119991 -379.321584) (xy 169.123603 -379.334846) (xy 169.126916 -379.340872) (xy 169.143294 -379.369206)
			(xy 169.169036 -379.429377) (xy 169.18646 -379.492462) (xy 169.195249 -379.557316) (xy 169.195244 -379.622763)
			(xy 169.186444 -379.687615) (xy 169.16901 -379.750697) (xy 169.143258 -379.810864) (xy 169.126916 -379.83922)
			(xy 169.123595 -379.845242) (xy 169.119993 -379.858508) (xy 169.119804 -379.865382) (xy 169.119804 -380.151386)
			(xy 169.119256 -380.161538) (xy 169.111494 -380.180299) (xy 169.097146 -380.194663) (xy 169.078393 -380.202445)
			(xy 169.068242 -380.202948) (xy 168.351962 -380.202948) (xy 168.3418 -380.202497) (xy 168.323027 -380.194708)
			(xy 168.308663 -380.180329) (xy 168.300892 -380.161548) (xy 168.3004 -380.151386) (xy 168.3004 -379.865382)
			(xy 168.300215 -379.858508) (xy 168.296602 -379.845245) (xy 168.293288 -379.83922) (xy 168.276988 -379.810843)
			(xy 168.251238 -379.750682) (xy 168.233805 -379.687606) (xy 168.225007 -379.62276) (xy 168.225001 -379.557319)
			(xy 168.23379 -379.492472) (xy 168.251212 -379.429393) (xy 168.276952 -379.369228) (xy 168.293288 -379.340872)
			(xy 168.296612 -379.334852) (xy 168.300212 -379.321585) (xy 168.3004 -379.31471) (xy 168.3004 -378.56541)
			(xy 168.300204 -378.558537) (xy 168.296599 -378.545274) (xy 168.293288 -378.539248) (xy 168.276927 -378.510905)
			(xy 168.251183 -378.450735) (xy 168.233757 -378.387653) (xy 168.224966 -378.3228) (xy 164.795161 -378.3228)
			(xy 164.786372 -378.387646) (xy 164.768949 -378.450725) (xy 164.743209 -378.510892) (xy 164.726874 -378.539248)
			(xy 164.723495 -378.545256) (xy 164.719769 -378.558522) (xy 164.719508 -378.56541) (xy 164.719508 -379.31471)
			(xy 164.719736 -379.321602) (xy 164.723482 -379.334868) (xy 164.726874 -379.340872) (xy 164.74325 -379.369207)
			(xy 164.76899 -379.429379) (xy 164.786411 -379.492463) (xy 164.795199 -379.557316) (xy 164.795194 -379.622762)
			(xy 164.786395 -379.687614) (xy 164.768963 -379.750696) (xy 164.743214 -379.810864) (xy 164.726874 -379.83922)
			(xy 164.723505 -379.845233) (xy 164.719772 -379.858495) (xy 164.719508 -379.865382) (xy 164.719508 -380.151386)
			(xy 164.718963 -380.161506) (xy 164.711249 -380.180218) (xy 164.696981 -380.194573) (xy 164.678317 -380.202401)
			(xy 164.6682 -380.202948) (xy 163.95192 -380.202948) (xy 163.941773 -380.202463) (xy 163.92303 -380.194683)
			(xy 163.908708 -380.180306) (xy 163.900999 -380.161534) (xy 163.900612 -380.151386) (xy 163.900612 -379.865382)
			(xy 163.900381 -379.858489) (xy 163.896652 -379.845217) (xy 163.893246 -379.83922) (xy 163.876947 -379.810842)
			(xy 163.851199 -379.750681) (xy 163.833769 -379.687605) (xy 163.824971 -379.622759) (xy 163.824965 -379.55732)
			(xy 163.833753 -379.492472) (xy 163.851173 -379.429394) (xy 163.876911 -379.369228) (xy 163.893246 -379.340872)
			(xy 163.896619 -379.334862) (xy 163.900349 -379.321598) (xy 163.900612 -379.31471) (xy 163.900612 -378.56541)
			(xy 163.900409 -378.558515) (xy 163.896661 -378.545243) (xy 163.893246 -378.539248) (xy 163.876886 -378.510904)
			(xy 163.851144 -378.450735) (xy 163.83372 -378.387652) (xy 163.82493 -378.3228) (xy 160.395125 -378.3228)
			(xy 160.386335 -378.387647) (xy 160.36891 -378.450726) (xy 160.343169 -378.510892) (xy 160.326832 -378.539248)
			(xy 160.323503 -378.545266) (xy 160.319906 -378.558535) (xy 160.31972 -378.56541) (xy 160.31972 -379.31471)
			(xy 160.319906 -379.321584) (xy 160.323518 -379.334847) (xy 160.326832 -379.340872) (xy 160.343209 -379.369206)
			(xy 160.368951 -379.429378) (xy 160.386374 -379.492462) (xy 160.395163 -379.557316) (xy 160.395158 -379.622763)
			(xy 160.386358 -379.687615) (xy 160.368925 -379.750697) (xy 160.343173 -379.810864) (xy 160.326832 -379.83922)
			(xy 160.323513 -379.845243) (xy 160.31991 -379.858508) (xy 160.31972 -379.865382) (xy 160.31972 -380.151386)
			(xy 160.319324 -380.161562) (xy 160.311536 -380.180364) (xy 160.297141 -380.194751) (xy 160.278334 -380.202529)
			(xy 160.268158 -380.202948) (xy 159.551878 -380.202948) (xy 159.541717 -380.202484) (xy 159.522945 -380.1947)
			(xy 159.50858 -380.180325) (xy 159.500808 -380.161547) (xy 159.500316 -380.151386) (xy 159.500316 -379.865382)
			(xy 159.500129 -379.858508) (xy 159.496517 -379.845246) (xy 159.493204 -379.83922) (xy 159.476907 -379.810842)
			(xy 159.451161 -379.75068) (xy 159.433732 -379.687604) (xy 159.424934 -379.622759) (xy 159.424929 -379.55732)
			(xy 159.433716 -379.492473) (xy 159.451135 -379.429395) (xy 159.476871 -379.369228) (xy 159.493204 -379.340872)
			(xy 159.496529 -379.334852) (xy 159.500128 -379.321585) (xy 159.500316 -379.31471) (xy 159.500316 -378.56541)
			(xy 159.500118 -378.558537) (xy 159.496514 -378.545274) (xy 159.493204 -378.539248) (xy 159.476846 -378.510904)
			(xy 159.451106 -378.450734) (xy 159.433683 -378.387651) (xy 159.424893 -378.3228) (xy 154.72791 -378.3228)
			(xy 154.72791 -380.657397) (xy 161.624812 -380.657397) (xy 161.633602 -380.592549) (xy 161.651024 -380.529469)
			(xy 161.676763 -380.469303) (xy 161.693098 -380.440946) (xy 161.696477 -380.434938) (xy 161.700204 -380.421672)
			(xy 161.700464 -380.414784) (xy 161.700464 -379.665484) (xy 161.700225 -379.658592) (xy 161.696501 -379.64532)
			(xy 161.693098 -379.639322) (xy 161.676803 -379.610943) (xy 161.651057 -379.550781) (xy 161.633628 -379.487706)
			(xy 161.62483 -379.422861) (xy 161.624825 -379.357422) (xy 161.633611 -379.292575) (xy 161.65103 -379.229497)
			(xy 161.676765 -379.169331) (xy 161.693098 -379.140974) (xy 161.696467 -379.134961) (xy 161.7002 -379.121699)
			(xy 161.700464 -379.114812) (xy 161.700464 -378.828554) (xy 161.70089 -378.818421) (xy 161.708637 -378.799695)
			(xy 161.722942 -378.785339) (xy 161.741641 -378.777526) (xy 161.751772 -378.776992) (xy 162.468052 -378.776992)
			(xy 162.478202 -378.777461) (xy 162.496952 -378.785239) (xy 162.511277 -378.799622) (xy 162.518979 -378.818402)
			(xy 162.51936 -378.828554) (xy 162.51936 -379.114812) (xy 162.519598 -379.121704) (xy 162.523323 -379.134976)
			(xy 162.526726 -379.140974) (xy 162.543105 -379.169307) (xy 162.568847 -379.229479) (xy 162.58627 -379.292564)
			(xy 162.595059 -379.357418) (xy 162.595053 -379.422865) (xy 162.586254 -379.487717) (xy 162.56882 -379.550799)
			(xy 162.543068 -379.610966) (xy 162.526726 -379.639322) (xy 162.523352 -379.645332) (xy 162.519623 -379.658596)
			(xy 162.51936 -379.665484) (xy 162.51936 -380.414784) (xy 162.51957 -380.421679) (xy 162.523314 -380.434951)
			(xy 162.526726 -380.440946) (xy 162.543081 -380.469292) (xy 162.568826 -380.529461) (xy 162.586251 -380.592543)
			(xy 162.595043 -380.657395) (xy 162.595043 -380.657396) (xy 166.024848 -380.657396) (xy 166.033639 -380.592548)
			(xy 166.051063 -380.529468) (xy 166.076804 -380.469302) (xy 166.09314 -380.440946) (xy 166.096434 -380.434911)
			(xy 166.100053 -380.421655) (xy 166.100252 -380.414784) (xy 166.100252 -379.665484) (xy 166.100072 -379.65861)
			(xy 166.096456 -379.645347) (xy 166.09314 -379.639322) (xy 166.076843 -379.610943) (xy 166.051096 -379.550782)
			(xy 166.033665 -379.487706) (xy 166.024867 -379.422861) (xy 166.024861 -379.357421) (xy 166.033648 -379.292574)
			(xy 166.051068 -379.229496) (xy 166.076806 -379.16933) (xy 166.09314 -379.140974) (xy 166.096459 -379.134952)
			(xy 166.100063 -379.121686) (xy 166.100252 -379.114812) (xy 166.100252 -378.828554) (xy 166.100696 -378.818392)
			(xy 166.108488 -378.799619) (xy 166.122869 -378.785255) (xy 166.141651 -378.777484) (xy 166.151814 -378.776992)
			(xy 166.868094 -378.776992) (xy 166.878246 -378.777537) (xy 166.897006 -378.785301) (xy 166.91137 -378.79965)
			(xy 166.919153 -378.818403) (xy 166.919656 -378.828554) (xy 166.919656 -379.114812) (xy 166.919836 -379.121686)
			(xy 166.923452 -379.134949) (xy 166.926768 -379.140974) (xy 166.943146 -379.169308) (xy 166.968886 -379.22948)
			(xy 166.986307 -379.292565) (xy 166.995095 -379.357418) (xy 166.995089 -379.422864) (xy 166.986291 -379.487716)
			(xy 166.968858 -379.550798) (xy 166.943108 -379.610966) (xy 166.926768 -379.639322) (xy 166.923443 -379.645342)
			(xy 166.919844 -379.658609) (xy 166.919656 -379.665484) (xy 166.919656 -380.414784) (xy 166.919847 -380.421657)
			(xy 166.923455 -380.43492) (xy 166.926768 -380.440946) (xy 166.943122 -380.469293) (xy 166.968864 -380.529462)
			(xy 166.986288 -380.592544) (xy 166.995079 -380.657395) (xy 166.995079 -380.657396) (xy 170.424884 -380.657396)
			(xy 170.433676 -380.592547) (xy 170.451101 -380.529468) (xy 170.476845 -380.469302) (xy 170.493182 -380.440946)
			(xy 170.49656 -380.434938) (xy 170.500288 -380.421672) (xy 170.500548 -380.414784) (xy 170.500548 -379.665484)
			(xy 170.500311 -379.658591) (xy 170.496586 -379.645319) (xy 170.493182 -379.639322) (xy 170.476884 -379.610944)
			(xy 170.451134 -379.550783) (xy 170.433702 -379.487707) (xy 170.424903 -379.422861) (xy 170.424897 -379.357421)
			(xy 170.433685 -379.292574) (xy 170.451107 -379.229495) (xy 170.476846 -379.16933) (xy 170.493182 -379.140974)
			(xy 170.49655 -379.134961) (xy 170.500284 -379.121699) (xy 170.500548 -379.114812) (xy 170.500548 -378.828554)
			(xy 170.500989 -378.818423) (xy 170.508734 -378.7997) (xy 170.523034 -378.785345) (xy 170.541727 -378.777529)
			(xy 170.551856 -378.776992) (xy 171.268136 -378.776992) (xy 171.278291 -378.777392) (xy 171.297043 -378.785198)
			(xy 171.311365 -378.799601) (xy 171.319065 -378.818396) (xy 171.319444 -378.828554) (xy 171.319444 -379.114812)
			(xy 171.319683 -379.121704) (xy 171.323407 -379.134976) (xy 171.32681 -379.140974) (xy 171.34319 -379.169307)
			(xy 171.368932 -379.229479) (xy 171.386356 -379.292564) (xy 171.395145 -379.357418) (xy 171.39514 -379.422865)
			(xy 171.38634 -379.487717) (xy 171.368905 -379.550799) (xy 171.343152 -379.610966) (xy 171.32681 -379.639322)
			(xy 171.323443 -379.645336) (xy 171.319708 -379.658597) (xy 171.319444 -379.665484) (xy 171.319444 -380.414784)
			(xy 171.319656 -380.421678) (xy 171.323399 -380.43495) (xy 171.32681 -380.440946) (xy 171.343166 -380.469292)
			(xy 171.368911 -380.529461) (xy 171.386337 -380.592543) (xy 171.395129 -380.657395) (xy 171.395129 -380.657396)
			(xy 174.824935 -380.657396) (xy 174.833725 -380.592548) (xy 174.851148 -380.529469) (xy 174.876888 -380.469302)
			(xy 174.893224 -380.440946) (xy 174.896524 -380.434914) (xy 174.900139 -380.421656) (xy 174.900336 -380.414784)
			(xy 174.900336 -379.665484) (xy 174.900146 -379.658611) (xy 174.896536 -379.645348) (xy 174.893224 -379.639322)
			(xy 174.876928 -379.610943) (xy 174.851181 -379.550782) (xy 174.833751 -379.487706) (xy 174.824953 -379.422861)
			(xy 174.824947 -379.357421) (xy 174.833734 -379.292575) (xy 174.851154 -379.229496) (xy 174.87689 -379.16933)
			(xy 174.893224 -379.140974) (xy 174.89655 -379.134955) (xy 174.900148 -379.121687) (xy 174.900336 -379.114812)
			(xy 174.900336 -378.828554) (xy 174.900796 -378.818394) (xy 174.908585 -378.799624) (xy 174.922961 -378.78526)
			(xy 174.941737 -378.777487) (xy 174.951898 -378.776992) (xy 175.668178 -378.776992) (xy 175.678329 -378.77755)
			(xy 175.697089 -378.785309) (xy 175.711453 -378.799654) (xy 175.719237 -378.818404) (xy 175.71974 -378.828554)
			(xy 175.71974 -379.114812) (xy 175.719922 -379.121686) (xy 175.723537 -379.134949) (xy 175.726852 -379.140974)
			(xy 175.74323 -379.169308) (xy 175.768971 -379.229479) (xy 175.786393 -379.292564) (xy 175.795181 -379.357418)
			(xy 175.795176 -379.422864) (xy 175.786377 -379.487717) (xy 175.768944 -379.550798) (xy 175.752146 -379.590046)
			(xy 177.023784 -379.590046) (xy 177.027775 -379.527879) (xy 177.039684 -379.466732) (xy 177.059313 -379.407611)
			(xy 177.086342 -379.351485) (xy 177.120326 -379.299276) (xy 177.160708 -379.251841) (xy 177.206824 -379.20996)
			(xy 177.257916 -379.17432) (xy 177.313147 -379.145506) (xy 177.371609 -379.123992) (xy 177.432343 -379.11013)
			(xy 177.49435 -379.104148) (xy 177.556613 -379.106144) (xy 177.61811 -379.116087) (xy 177.677831 -379.133811)
			(xy 177.734794 -379.159028) (xy 177.788065 -379.191321) (xy 177.83677 -379.230161) (xy 177.880107 -379.274911)
			(xy 177.917367 -379.324835) (xy 177.947936 -379.379114) (xy 177.952403 -379.390148) (xy 179.223932 -379.390148)
			(xy 179.227923 -379.327981) (xy 179.239832 -379.266834) (xy 179.259461 -379.207713) (xy 179.28649 -379.151587)
			(xy 179.320474 -379.099378) (xy 179.360856 -379.051943) (xy 179.406972 -379.010062) (xy 179.458064 -378.974422)
			(xy 179.513295 -378.945608) (xy 179.571757 -378.924094) (xy 179.632491 -378.910232) (xy 179.694498 -378.90425)
			(xy 179.756761 -378.906246) (xy 179.818258 -378.916189) (xy 179.877979 -378.933913) (xy 179.934942 -378.95913)
			(xy 179.988213 -378.991423) (xy 180.036918 -379.030263) (xy 180.080255 -379.075013) (xy 180.117515 -379.124937)
			(xy 180.148084 -379.179216) (xy 180.171462 -379.236959) (xy 180.187263 -379.297217) (xy 180.195229 -379.359)
			(xy 180.195728 -379.390148) (xy 180.195229 -379.421296) (xy 180.187263 -379.483079) (xy 180.171462 -379.543337)
			(xy 180.148084 -379.60108) (xy 180.117515 -379.655359) (xy 180.080255 -379.705283) (xy 180.036918 -379.750033)
			(xy 179.988213 -379.788873) (xy 179.934942 -379.821166) (xy 179.877979 -379.846383) (xy 179.818258 -379.864107)
			(xy 179.756761 -379.87405) (xy 179.694498 -379.876046) (xy 179.632491 -379.870064) (xy 179.571757 -379.856202)
			(xy 179.513295 -379.834688) (xy 179.458064 -379.805874) (xy 179.406972 -379.770234) (xy 179.360856 -379.728353)
			(xy 179.320474 -379.680918) (xy 179.28649 -379.628709) (xy 179.259461 -379.572583) (xy 179.239832 -379.513462)
			(xy 179.227923 -379.452315) (xy 179.223932 -379.390148) (xy 177.952403 -379.390148) (xy 177.971314 -379.436857)
			(xy 177.987115 -379.497115) (xy 177.995081 -379.558898) (xy 177.99558 -379.590046) (xy 177.995081 -379.621194)
			(xy 177.987115 -379.682977) (xy 177.971314 -379.743235) (xy 177.947936 -379.800978) (xy 177.917367 -379.855257)
			(xy 177.880107 -379.905181) (xy 177.83677 -379.949931) (xy 177.788065 -379.988771) (xy 177.734794 -380.021064)
			(xy 177.677831 -380.046281) (xy 177.61811 -380.064005) (xy 177.556613 -380.073948) (xy 177.49435 -380.075944)
			(xy 177.432343 -380.069962) (xy 177.371609 -380.0561) (xy 177.313147 -380.034586) (xy 177.257916 -380.005772)
			(xy 177.206824 -379.970132) (xy 177.160708 -379.928251) (xy 177.120326 -379.880816) (xy 177.086342 -379.828607)
			(xy 177.059313 -379.772481) (xy 177.039684 -379.71336) (xy 177.027775 -379.652213) (xy 177.023784 -379.590046)
			(xy 175.752146 -379.590046) (xy 175.743193 -379.610966) (xy 175.726852 -379.639322) (xy 175.723534 -379.645345)
			(xy 175.71993 -379.65861) (xy 175.71974 -379.665484) (xy 175.71974 -380.414784) (xy 175.719933 -380.421657)
			(xy 175.72354 -380.43492) (xy 175.726852 -380.440946) (xy 175.743207 -380.469293) (xy 175.768949 -380.529462)
			(xy 175.786374 -380.592544) (xy 175.795165 -380.657395) (xy 175.795164 -380.69012) (xy 179.223932 -380.69012)
			(xy 179.227923 -380.627953) (xy 179.239832 -380.566806) (xy 179.259461 -380.507685) (xy 179.28649 -380.451559)
			(xy 179.320474 -380.39935) (xy 179.360856 -380.351915) (xy 179.406972 -380.310034) (xy 179.458064 -380.274394)
			(xy 179.513295 -380.24558) (xy 179.571757 -380.224066) (xy 179.632491 -380.210204) (xy 179.694498 -380.204222)
			(xy 179.756761 -380.206218) (xy 179.818258 -380.216161) (xy 179.877979 -380.233885) (xy 179.934942 -380.259102)
			(xy 179.988213 -380.291395) (xy 180.036918 -380.330235) (xy 180.080255 -380.374985) (xy 180.117515 -380.424909)
			(xy 180.148084 -380.479188) (xy 180.171462 -380.536931) (xy 180.187263 -380.597189) (xy 180.195229 -380.658972)
			(xy 180.195728 -380.69012) (xy 180.195229 -380.721268) (xy 180.187263 -380.783051) (xy 180.171462 -380.843309)
			(xy 180.148084 -380.901052) (xy 180.117515 -380.955331) (xy 180.080255 -381.005255) (xy 180.036918 -381.050005)
			(xy 179.988213 -381.088845) (xy 179.934942 -381.121138) (xy 179.877979 -381.146355) (xy 179.818258 -381.164079)
			(xy 179.756761 -381.174022) (xy 179.694498 -381.176018) (xy 179.632491 -381.170036) (xy 179.571757 -381.156174)
			(xy 179.513295 -381.13466) (xy 179.458064 -381.105846) (xy 179.406972 -381.070206) (xy 179.360856 -381.028325)
			(xy 179.320474 -380.98089) (xy 179.28649 -380.928681) (xy 179.259461 -380.872555) (xy 179.239832 -380.813434)
			(xy 179.227923 -380.752287) (xy 179.223932 -380.69012) (xy 175.795164 -380.69012) (xy 175.795163 -380.722839)
			(xy 175.786367 -380.78769) (xy 175.768938 -380.850771) (xy 175.743191 -380.910938) (xy 175.726852 -380.939294)
			(xy 175.723544 -380.945322) (xy 175.719933 -380.958583) (xy 175.71974 -380.965456) (xy 175.71974 -381.251206)
			(xy 175.71934 -381.261381) (xy 175.711549 -381.28018) (xy 175.697156 -381.294565) (xy 175.678353 -381.302346)
			(xy 175.668178 -381.302768) (xy 174.951898 -381.302768) (xy 174.941741 -381.302268) (xy 174.922973 -381.294494)
			(xy 174.908608 -381.280131) (xy 174.900832 -381.261363) (xy 174.900336 -381.251206) (xy 174.900336 -380.965456)
			(xy 174.900118 -380.958585) (xy 174.896527 -380.945322) (xy 174.893224 -380.939294) (xy 174.876904 -380.910928)
			(xy 174.851159 -380.850764) (xy 174.833732 -380.787686) (xy 174.824937 -380.722838) (xy 174.824935 -380.657396)
			(xy 171.395129 -380.657396) (xy 171.395127 -380.72284) (xy 171.38633 -380.787691) (xy 171.3689 -380.850772)
			(xy 171.34315 -380.910938) (xy 171.32681 -380.939294) (xy 171.323453 -380.945313) (xy 171.319712 -380.95857)
			(xy 171.319444 -380.965456) (xy 171.319444 -381.251206) (xy 171.318978 -381.261335) (xy 171.311245 -381.280059)
			(xy 171.296952 -381.294416) (xy 171.278263 -381.302232) (xy 171.268136 -381.302768) (xy 170.551856 -381.302768)
			(xy 170.541695 -381.302414) (xy 170.522936 -381.294598) (xy 170.508613 -381.28018) (xy 170.50092 -381.26137)
			(xy 170.500548 -381.251206) (xy 170.500548 -380.965456) (xy 170.500322 -380.958563) (xy 170.496589 -380.945291)
			(xy 170.493182 -380.939294) (xy 170.47686 -380.910929) (xy 170.451112 -380.850765) (xy 170.433683 -380.787687)
			(xy 170.424887 -380.722838) (xy 170.424884 -380.657396) (xy 166.995079 -380.657396) (xy 166.995077 -380.722839)
			(xy 166.986281 -380.78769) (xy 166.968853 -380.850771) (xy 166.943106 -380.910938) (xy 166.926768 -380.939294)
			(xy 166.923453 -380.945318) (xy 166.919848 -380.958582) (xy 166.919656 -380.965456) (xy 166.919656 -381.251206)
			(xy 166.919171 -381.261365) (xy 166.911394 -381.280135) (xy 166.897025 -381.2945) (xy 166.878253 -381.302274)
			(xy 166.868094 -381.302768) (xy 166.151814 -381.302768) (xy 166.141644 -381.302325) (xy 166.122851 -381.294546)
			(xy 166.108466 -381.280166) (xy 166.100679 -381.261376) (xy 166.100252 -381.251206) (xy 166.100252 -380.965456)
			(xy 166.100045 -380.958584) (xy 166.096448 -380.945321) (xy 166.09314 -380.939294) (xy 166.07682 -380.910928)
			(xy 166.051074 -380.850764) (xy 166.033646 -380.787686) (xy 166.024851 -380.722838) (xy 166.024848 -380.657396)
			(xy 162.595043 -380.657396) (xy 162.595041 -380.72284) (xy 162.586245 -380.78769) (xy 162.568814 -380.850771)
			(xy 162.543066 -380.910938) (xy 162.526726 -380.939294) (xy 162.523362 -380.945309) (xy 162.519627 -380.958569)
			(xy 162.51936 -380.965456) (xy 162.51936 -381.251206) (xy 162.518878 -381.261333) (xy 162.511148 -381.280054)
			(xy 162.496861 -381.29441) (xy 162.478177 -381.302229) (xy 162.468052 -381.302768) (xy 161.751772 -381.302768)
			(xy 161.741612 -381.302401) (xy 161.722853 -381.29459) (xy 161.708529 -381.280176) (xy 161.700836 -381.261368)
			(xy 161.700464 -381.251206) (xy 161.700464 -380.965456) (xy 161.700236 -380.958563) (xy 161.696504 -380.945291)
			(xy 161.693098 -380.939294) (xy 161.676779 -380.910928) (xy 161.651036 -380.850763) (xy 161.633609 -380.787685)
			(xy 161.624814 -380.722838) (xy 161.624812 -380.657397) (xy 154.72791 -380.657397) (xy 154.72791 -382.222713)
			(xy 159.424903 -382.222713) (xy 159.424904 -382.15727) (xy 159.433697 -382.09242) (xy 159.451124 -382.02934)
			(xy 159.476867 -381.969173) (xy 159.493204 -381.940816) (xy 159.496513 -381.934789) (xy 159.500122 -381.921527)
			(xy 159.500316 -381.914654) (xy 159.500316 -381.628904) (xy 159.500725 -381.618748) (xy 159.508522 -381.599993)
			(xy 159.522923 -381.585669) (xy 159.54172 -381.577972) (xy 159.551878 -381.577596) (xy 160.268158 -381.577596)
			(xy 160.278277 -381.57816) (xy 160.296988 -381.585866) (xy 160.311345 -381.600128) (xy 160.319173 -381.618789)
			(xy 160.31972 -381.628904) (xy 160.31972 -381.914654) (xy 160.319927 -381.921526) (xy 160.323525 -381.934789)
			(xy 160.326832 -381.940816) (xy 160.343162 -381.969177) (xy 160.368908 -382.029342) (xy 160.386336 -382.092421)
			(xy 160.395131 -382.15727) (xy 160.395132 -382.222713) (xy 163.824939 -382.222713) (xy 163.82494 -382.15727)
			(xy 163.833734 -382.092419) (xy 163.851162 -382.029339) (xy 163.876908 -381.969172) (xy 163.893246 -381.940816)
			(xy 163.896604 -381.934798) (xy 163.900343 -381.92154) (xy 163.900612 -381.914654) (xy 163.900612 -381.628904)
			(xy 163.90102 -381.61878) (xy 163.908769 -381.600074) (xy 163.923088 -381.58576) (xy 163.941796 -381.578016)
			(xy 163.95192 -381.577596) (xy 164.6682 -381.577596) (xy 164.678322 -381.578016) (xy 164.697025 -381.585763)
			(xy 164.711339 -381.600079) (xy 164.719085 -381.618782) (xy 164.719508 -381.628904) (xy 164.719508 -381.914654)
			(xy 164.719758 -381.921544) (xy 164.723489 -381.93481) (xy 164.726874 -381.940816) (xy 164.743202 -381.969177)
			(xy 164.768946 -382.029343) (xy 164.786373 -382.092422) (xy 164.795167 -382.15727) (xy 164.795168 -382.222712)
			(xy 164.795168 -382.222714) (xy 168.224975 -382.222714) (xy 168.224976 -382.157269) (xy 168.233771 -382.092419)
			(xy 168.251201 -382.029338) (xy 168.276948 -381.969172) (xy 168.293288 -381.940816) (xy 168.296596 -381.934788)
			(xy 168.300206 -381.921527) (xy 168.3004 -381.914654) (xy 168.3004 -381.628904) (xy 168.300825 -381.61875)
			(xy 168.308619 -381.599998) (xy 168.323015 -381.585674) (xy 168.341806 -381.577975) (xy 168.351962 -381.577596)
			(xy 169.068242 -381.577596) (xy 169.078366 -381.578091) (xy 169.09708 -381.585824) (xy 169.111433 -381.600107)
			(xy 169.119258 -381.618783) (xy 169.119804 -381.628904) (xy 169.119804 -381.914654) (xy 169.120013 -381.921526)
			(xy 169.12361 -381.934789) (xy 169.126916 -381.940816) (xy 169.143246 -381.969176) (xy 169.168993 -382.029342)
			(xy 169.186422 -382.092421) (xy 169.195217 -382.15727) (xy 169.195218 -382.222713) (xy 172.624764 -382.222713)
			(xy 172.624766 -382.157269) (xy 172.633561 -382.092419) (xy 172.65099 -382.029338) (xy 172.676737 -381.969172)
			(xy 172.693076 -381.940816) (xy 172.696383 -381.934788) (xy 172.699994 -381.921527) (xy 172.700188 -381.914654)
			(xy 172.700188 -381.628904) (xy 172.700625 -381.618752) (xy 172.708417 -381.600002) (xy 172.722809 -381.585679)
			(xy 172.741596 -381.577977) (xy 172.75175 -381.577596) (xy 173.46803 -381.577596) (xy 173.478153 -381.578101)
			(xy 173.496867 -381.58583) (xy 173.51122 -381.60011) (xy 173.519046 -381.618783) (xy 173.519592 -381.628904)
			(xy 173.519592 -381.914654) (xy 173.519803 -381.921526) (xy 173.523398 -381.934789) (xy 173.526704 -381.940816)
			(xy 173.543032 -381.969177) (xy 173.568774 -382.029343) (xy 173.5862 -382.092422) (xy 173.594993 -382.157271)
			(xy 173.594993 -382.18999) (xy 177.023784 -382.18999) (xy 177.027775 -382.127823) (xy 177.039684 -382.066676)
			(xy 177.059313 -382.007555) (xy 177.086342 -381.951429) (xy 177.120326 -381.89922) (xy 177.160708 -381.851785)
			(xy 177.206824 -381.809904) (xy 177.257916 -381.774264) (xy 177.313147 -381.74545) (xy 177.371609 -381.723936)
			(xy 177.432343 -381.710074) (xy 177.49435 -381.704092) (xy 177.556613 -381.706088) (xy 177.61811 -381.716031)
			(xy 177.677831 -381.733755) (xy 177.734794 -381.758972) (xy 177.788065 -381.791265) (xy 177.83677 -381.830105)
			(xy 177.880107 -381.874855) (xy 177.917367 -381.924779) (xy 177.947936 -381.979058) (xy 177.971314 -382.036801)
			(xy 177.987115 -382.097059) (xy 177.995081 -382.158842) (xy 177.99558 -382.18999) (xy 177.995081 -382.221138)
			(xy 177.987115 -382.282921) (xy 177.971314 -382.343179) (xy 177.947936 -382.400922) (xy 177.917367 -382.455201)
			(xy 177.880107 -382.505125) (xy 177.83677 -382.549875) (xy 177.788065 -382.588715) (xy 177.734794 -382.621008)
			(xy 177.677831 -382.646225) (xy 177.61811 -382.663949) (xy 177.556613 -382.673892) (xy 177.49435 -382.675888)
			(xy 177.432343 -382.669906) (xy 177.371609 -382.656044) (xy 177.313147 -382.63453) (xy 177.257916 -382.605716)
			(xy 177.206824 -382.570076) (xy 177.160708 -382.528195) (xy 177.120326 -382.48076) (xy 177.086342 -382.428551)
			(xy 177.059313 -382.372425) (xy 177.039684 -382.313304) (xy 177.027775 -382.252157) (xy 177.023784 -382.18999)
			(xy 173.594993 -382.18999) (xy 173.594994 -382.222712) (xy 173.586203 -382.287561) (xy 173.56878 -382.35064)
			(xy 173.543039 -382.410807) (xy 173.526704 -382.439164) (xy 173.523402 -382.445195) (xy 173.519788 -382.458454)
			(xy 173.519592 -382.465326) (xy 173.519592 -383.21488) (xy 173.519792 -383.221753) (xy 173.523395 -383.235015)
			(xy 173.526704 -383.241042) (xy 173.543054 -383.269391) (xy 173.565899 -383.322792) (xy 174.824905 -383.322792)
			(xy 174.824909 -383.257347) (xy 174.833706 -383.192495) (xy 174.851137 -383.129414) (xy 174.876885 -383.069246)
			(xy 174.893224 -383.04089) (xy 174.896544 -383.034868) (xy 174.900146 -383.021602) (xy 174.900336 -383.014728)
			(xy 174.900336 -382.728724) (xy 174.900742 -382.718567) (xy 174.908536 -382.699808) (xy 174.922939 -382.685482)
			(xy 174.941739 -382.677788) (xy 174.951898 -382.677416) (xy 175.668178 -382.677416) (xy 175.6783 -382.677944)
			(xy 175.697017 -382.68566) (xy 175.711373 -382.699933) (xy 175.719197 -382.718605) (xy 175.71974 -382.728724)
			(xy 175.71974 -383.014728) (xy 175.719916 -383.021602) (xy 175.723535 -383.034865) (xy 175.726852 -383.04089)
			(xy 175.743159 -383.069263) (xy 175.768906 -383.129426) (xy 175.786336 -383.192502) (xy 175.795133 -383.257349)
			(xy 175.795138 -383.322789) (xy 175.786349 -383.387637) (xy 175.768927 -383.450716) (xy 175.752028 -383.490216)
			(xy 177.023784 -383.490216) (xy 177.027775 -383.428049) (xy 177.039684 -383.366902) (xy 177.059313 -383.307781)
			(xy 177.086342 -383.251655) (xy 177.120326 -383.199446) (xy 177.160708 -383.152011) (xy 177.206824 -383.11013)
			(xy 177.257916 -383.07449) (xy 177.313147 -383.045676) (xy 177.371609 -383.024162) (xy 177.432343 -383.0103)
			(xy 177.49435 -383.004318) (xy 177.556613 -383.006314) (xy 177.61811 -383.016257) (xy 177.677831 -383.033981)
			(xy 177.734794 -383.059198) (xy 177.788065 -383.091491) (xy 177.83677 -383.130331) (xy 177.880107 -383.175081)
			(xy 177.917367 -383.225005) (xy 177.947936 -383.279284) (xy 177.9523 -383.290064) (xy 179.223932 -383.290064)
			(xy 179.227923 -383.227897) (xy 179.239832 -383.16675) (xy 179.259461 -383.107629) (xy 179.28649 -383.051503)
			(xy 179.320474 -382.999294) (xy 179.360856 -382.951859) (xy 179.406972 -382.909978) (xy 179.458064 -382.874338)
			(xy 179.513295 -382.845524) (xy 179.571757 -382.82401) (xy 179.632491 -382.810148) (xy 179.694498 -382.804166)
			(xy 179.756761 -382.806162) (xy 179.818258 -382.816105) (xy 179.877979 -382.833829) (xy 179.934942 -382.859046)
			(xy 179.988213 -382.891339) (xy 180.036918 -382.930179) (xy 180.080255 -382.974929) (xy 180.117515 -383.024853)
			(xy 180.148084 -383.079132) (xy 180.171462 -383.136875) (xy 180.187263 -383.197133) (xy 180.195229 -383.258916)
			(xy 180.195728 -383.290064) (xy 180.195229 -383.321212) (xy 180.187263 -383.382995) (xy 180.171462 -383.443253)
			(xy 180.148084 -383.500996) (xy 180.117515 -383.555275) (xy 180.080255 -383.605199) (xy 180.036918 -383.649949)
			(xy 179.988213 -383.688789) (xy 179.934942 -383.721082) (xy 179.877979 -383.746299) (xy 179.818258 -383.764023)
			(xy 179.756761 -383.773966) (xy 179.694498 -383.775962) (xy 179.632491 -383.76998) (xy 179.571757 -383.756118)
			(xy 179.513295 -383.734604) (xy 179.458064 -383.70579) (xy 179.406972 -383.67015) (xy 179.360856 -383.628269)
			(xy 179.320474 -383.580834) (xy 179.28649 -383.528625) (xy 179.259461 -383.472499) (xy 179.239832 -383.413378)
			(xy 179.227923 -383.352231) (xy 179.223932 -383.290064) (xy 177.9523 -383.290064) (xy 177.971314 -383.337027)
			(xy 177.987115 -383.397285) (xy 177.995081 -383.459068) (xy 177.99558 -383.490216) (xy 177.995081 -383.521364)
			(xy 177.987115 -383.583147) (xy 177.971314 -383.643405) (xy 177.947936 -383.701148) (xy 177.917367 -383.755427)
			(xy 177.880107 -383.805351) (xy 177.83677 -383.850101) (xy 177.788065 -383.888941) (xy 177.734794 -383.921234)
			(xy 177.677831 -383.946451) (xy 177.61811 -383.964175) (xy 177.556613 -383.974118) (xy 177.49435 -383.976114)
			(xy 177.432343 -383.970132) (xy 177.371609 -383.95627) (xy 177.313147 -383.934756) (xy 177.257916 -383.905942)
			(xy 177.206824 -383.870302) (xy 177.160708 -383.828421) (xy 177.120326 -383.780986) (xy 177.086342 -383.728777)
			(xy 177.059313 -383.672651) (xy 177.039684 -383.61353) (xy 177.027775 -383.552383) (xy 177.023784 -383.490216)
			(xy 175.752028 -383.490216) (xy 175.743187 -383.510882) (xy 175.726852 -383.539238) (xy 175.723528 -383.545258)
			(xy 175.719928 -383.558525) (xy 175.71974 -383.5654) (xy 175.71974 -384.3147) (xy 175.719927 -384.321574)
			(xy 175.723538 -384.334837) (xy 175.726852 -384.340862) (xy 175.74322 -384.369201) (xy 175.768962 -384.429372)
			(xy 175.786385 -384.492455) (xy 175.795174 -384.557308) (xy 175.795172 -384.590036) (xy 179.223932 -384.590036)
			(xy 179.227923 -384.527869) (xy 179.239832 -384.466722) (xy 179.259461 -384.407601) (xy 179.28649 -384.351475)
			(xy 179.320474 -384.299266) (xy 179.360856 -384.251831) (xy 179.406972 -384.20995) (xy 179.458064 -384.17431)
			(xy 179.513295 -384.145496) (xy 179.571757 -384.123982) (xy 179.632491 -384.11012) (xy 179.694498 -384.104138)
			(xy 179.756761 -384.106134) (xy 179.818258 -384.116077) (xy 179.877979 -384.133801) (xy 179.934942 -384.159018)
			(xy 179.988213 -384.191311) (xy 180.036918 -384.230151) (xy 180.080255 -384.274901) (xy 180.117515 -384.324825)
			(xy 180.148084 -384.379104) (xy 180.171462 -384.436847) (xy 180.187263 -384.497105) (xy 180.195229 -384.558888)
			(xy 180.195728 -384.590036) (xy 180.195229 -384.621184) (xy 180.187263 -384.682967) (xy 180.171462 -384.743225)
			(xy 180.148084 -384.800968) (xy 180.117515 -384.855247) (xy 180.080255 -384.905171) (xy 180.036918 -384.949921)
			(xy 179.988213 -384.988761) (xy 179.934942 -385.021054) (xy 179.877979 -385.046271) (xy 179.818258 -385.063995)
			(xy 179.756761 -385.073938) (xy 179.694498 -385.075934) (xy 179.632491 -385.069952) (xy 179.571757 -385.05609)
			(xy 179.513295 -385.034576) (xy 179.458064 -385.005762) (xy 179.406972 -384.970122) (xy 179.360856 -384.928241)
			(xy 179.320474 -384.880806) (xy 179.28649 -384.828597) (xy 179.259461 -384.772471) (xy 179.239832 -384.71335)
			(xy 179.227923 -384.652203) (xy 179.223932 -384.590036) (xy 175.795172 -384.590036) (xy 175.79517 -384.622754)
			(xy 175.786373 -384.687605) (xy 175.768941 -384.750687) (xy 175.743192 -384.810854) (xy 175.726852 -384.83921)
			(xy 175.723538 -384.845235) (xy 175.719931 -384.858498) (xy 175.71974 -384.865372) (xy 175.71974 -385.151376)
			(xy 175.71926 -385.161524) (xy 175.71148 -385.180268) (xy 175.697101 -385.194591) (xy 175.678327 -385.202298)
			(xy 175.668178 -385.202684) (xy 174.951898 -385.202684) (xy 174.941774 -385.202176) (xy 174.923058 -385.194452)
			(xy 174.908702 -385.180172) (xy 174.900879 -385.161497) (xy 174.900336 -385.151376) (xy 174.900336 -384.865372)
			(xy 174.90015 -384.858498) (xy 174.896537 -384.845236) (xy 174.893224 -384.83921) (xy 174.876918 -384.810837)
			(xy 174.851172 -384.750674) (xy 174.833742 -384.687597) (xy 174.824946 -384.622751) (xy 174.824942 -384.557311)
			(xy 174.83373 -384.492463) (xy 174.851151 -384.429384) (xy 174.87689 -384.369218) (xy 174.893224 -384.340862)
			(xy 174.896554 -384.334845) (xy 174.90015 -384.321575) (xy 174.900336 -384.3147) (xy 174.900336 -383.5654)
			(xy 174.90014 -383.558527) (xy 174.896534 -383.545265) (xy 174.893224 -383.539238) (xy 174.876857 -383.510899)
			(xy 174.851116 -383.450728) (xy 174.833694 -383.387644) (xy 174.824905 -383.322792) (xy 173.565899 -383.322792)
			(xy 173.568794 -383.32956) (xy 173.586217 -383.392642) (xy 173.595008 -383.457492) (xy 173.595006 -383.522935)
			(xy 173.586212 -383.587785) (xy 173.568785 -383.650866) (xy 173.543041 -383.711033) (xy 173.526704 -383.73939)
			(xy 173.523393 -383.745417) (xy 173.519785 -383.758679) (xy 173.519592 -383.765552) (xy 173.519592 -384.051556)
			(xy 173.519142 -384.061708) (xy 173.51136 -384.080461) (xy 173.496971 -384.094786) (xy 173.478184 -384.102486)
			(xy 173.46803 -384.102864) (xy 172.75175 -384.102864) (xy 172.741627 -384.102333) (xy 172.722908 -384.094622)
			(xy 172.70855 -384.080349) (xy 172.700728 -384.061676) (xy 172.700188 -384.051556) (xy 172.700188 -383.765552)
			(xy 172.699978 -383.75868) (xy 172.696382 -383.745417) (xy 172.693076 -383.73939) (xy 172.676751 -383.711027)
			(xy 172.651004 -383.650862) (xy 172.633575 -383.587783) (xy 172.624779 -383.522935) (xy 172.624777 -383.457493)
			(xy 172.633569 -383.392643) (xy 172.650995 -383.329564) (xy 172.676739 -383.269398) (xy 172.693076 -383.241042)
			(xy 172.696374 -383.235009) (xy 172.699991 -383.221752) (xy 172.700188 -383.21488) (xy 172.700188 -382.465326)
			(xy 172.699987 -382.458453) (xy 172.696385 -382.445191) (xy 172.693076 -382.439164) (xy 172.676729 -382.410813)
			(xy 172.650984 -382.350645) (xy 172.633557 -382.287564) (xy 172.624764 -382.222713) (xy 169.195218 -382.222713)
			(xy 169.186426 -382.287562) (xy 169.168999 -382.350642) (xy 169.143254 -382.410808) (xy 169.126916 -382.439164)
			(xy 169.123615 -382.445195) (xy 169.12 -382.458454) (xy 169.119804 -382.465326) (xy 169.119804 -383.21488)
			(xy 169.120003 -383.221753) (xy 169.123607 -383.235015) (xy 169.126916 -383.241042) (xy 169.143268 -383.26939)
			(xy 169.166118 -383.322792) (xy 170.424855 -383.322792) (xy 170.424859 -383.257346) (xy 170.433657 -383.192494)
			(xy 170.45109 -383.129413) (xy 170.476841 -383.069246) (xy 170.493182 -383.04089) (xy 170.496544 -383.034874)
			(xy 170.500282 -383.021615) (xy 170.500548 -383.014728) (xy 170.500548 -382.728724) (xy 170.501103 -382.718623)
			(xy 170.508823 -382.699955) (xy 170.523098 -382.685662) (xy 170.541756 -382.677917) (xy 170.551856 -382.677416)
			(xy 171.268136 -382.677416) (xy 171.278249 -382.677856) (xy 171.296931 -382.685608) (xy 171.311225 -382.699919)
			(xy 171.318956 -382.71861) (xy 171.319444 -382.728724) (xy 171.319444 -383.014728) (xy 171.319677 -383.021621)
			(xy 171.323405 -383.034893) (xy 171.32681 -383.04089) (xy 171.343118 -383.069262) (xy 171.368868 -383.129425)
			(xy 171.3863 -383.192502) (xy 171.395097 -383.257349) (xy 171.395101 -383.32279) (xy 171.386312 -383.387638)
			(xy 171.368888 -383.450717) (xy 171.343147 -383.510882) (xy 171.32681 -383.539238) (xy 171.323437 -383.545249)
			(xy 171.319706 -383.558512) (xy 171.319444 -383.5654) (xy 171.319444 -384.3147) (xy 171.31965 -384.321595)
			(xy 171.323397 -384.334867) (xy 171.32681 -384.340862) (xy 171.343179 -384.369201) (xy 171.368923 -384.429371)
			(xy 171.386348 -384.492455) (xy 171.395138 -384.557308) (xy 171.395134 -384.622754) (xy 171.386336 -384.687606)
			(xy 171.368903 -384.750687) (xy 171.343151 -384.810854) (xy 171.32681 -384.83921) (xy 171.323447 -384.845226)
			(xy 171.31971 -384.858485) (xy 171.319444 -384.865372) (xy 171.319444 -385.151376) (xy 171.318896 -385.161478)
			(xy 171.311175 -385.180147) (xy 171.296897 -385.194441) (xy 171.278237 -385.202185) (xy 171.268136 -385.202684)
			(xy 170.551856 -385.202684) (xy 170.541742 -385.20225) (xy 170.52306 -385.194495) (xy 170.508766 -385.180183)
			(xy 170.501036 -385.16149) (xy 170.500548 -385.151376) (xy 170.500548 -384.865372) (xy 170.500316 -384.858479)
			(xy 170.496587 -384.845207) (xy 170.493182 -384.83921) (xy 170.476874 -384.810837) (xy 170.451125 -384.750675)
			(xy 170.433693 -384.687598) (xy 170.424896 -384.622751) (xy 170.424892 -384.55731) (xy 170.433681 -384.492462)
			(xy 170.451104 -384.429383) (xy 170.476846 -384.369218) (xy 170.493182 -384.340862) (xy 170.496554 -384.334851)
			(xy 170.500286 -384.321588) (xy 170.500548 -384.3147) (xy 170.500548 -383.5654) (xy 170.500344 -383.558505)
			(xy 170.496596 -383.545233) (xy 170.493182 -383.539238) (xy 170.476813 -383.510899) (xy 170.451069 -383.450729)
			(xy 170.433645 -383.387645) (xy 170.424855 -383.322792) (xy 169.166118 -383.322792) (xy 169.169013 -383.329558)
			(xy 169.18644 -383.39264) (xy 169.195232 -383.457491) (xy 169.19523 -383.522936) (xy 169.186434 -383.587787)
			(xy 169.169004 -383.650868) (xy 169.143256 -383.711034) (xy 169.126916 -383.73939) (xy 169.123606 -383.745417)
			(xy 169.119997 -383.758679) (xy 169.119804 -383.765552) (xy 169.119804 -384.051556) (xy 169.119342 -384.061707)
			(xy 169.111562 -384.080457) (xy 169.097177 -384.094782) (xy 169.078394 -384.102484) (xy 169.068242 -384.102864)
			(xy 168.351962 -384.102864) (xy 168.341833 -384.102405) (xy 168.323112 -384.094665) (xy 168.308757 -384.080371)
			(xy 168.300939 -384.061682) (xy 168.3004 -384.051556) (xy 168.3004 -383.765552) (xy 168.300188 -383.75868)
			(xy 168.296593 -383.745418) (xy 168.293288 -383.73939) (xy 168.276963 -383.711027) (xy 168.251215 -383.650862)
			(xy 168.233785 -383.587784) (xy 168.22499 -383.522935) (xy 168.224988 -383.457492) (xy 168.23378 -383.392643)
			(xy 168.251206 -383.329564) (xy 168.27695 -383.269398) (xy 168.293288 -383.241042) (xy 168.296587 -383.23501)
			(xy 168.300203 -383.221752) (xy 168.3004 -383.21488) (xy 168.3004 -382.465326) (xy 168.300198 -382.458454)
			(xy 168.296596 -382.445191) (xy 168.293288 -382.439164) (xy 168.276941 -382.410813) (xy 168.251195 -382.350646)
			(xy 168.233768 -382.287564) (xy 168.224975 -382.222714) (xy 164.795168 -382.222714) (xy 164.786377 -382.287561)
			(xy 164.768952 -382.350641) (xy 164.74321 -382.410808) (xy 164.726874 -382.439164) (xy 164.723524 -382.445186)
			(xy 164.719779 -382.458441) (xy 164.719508 -382.465326) (xy 164.719508 -383.21488) (xy 164.719748 -383.221771)
			(xy 164.723486 -383.235037) (xy 164.726874 -383.241042) (xy 164.743225 -383.269391) (xy 164.766071 -383.322792)
			(xy 166.024819 -383.322792) (xy 166.024823 -383.257346) (xy 166.03362 -383.192495) (xy 166.051051 -383.129414)
			(xy 166.0768 -383.069246) (xy 166.09314 -383.04089) (xy 166.096454 -383.034865) (xy 166.100061 -383.021602)
			(xy 166.100252 -383.014728) (xy 166.100252 -382.728724) (xy 166.10074 -382.718577) (xy 166.108519 -382.699835)
			(xy 166.122895 -382.685512) (xy 166.141666 -382.677803) (xy 166.151814 -382.677416) (xy 166.868094 -382.677416)
			(xy 166.878217 -382.677931) (xy 166.896934 -382.685652) (xy 166.911289 -382.699929) (xy 166.919113 -382.718603)
			(xy 166.919656 -382.728724) (xy 166.919656 -383.014728) (xy 166.91983 -383.021603) (xy 166.92345 -383.034866)
			(xy 166.926768 -383.04089) (xy 166.943075 -383.069263) (xy 166.968821 -383.129426) (xy 166.986251 -383.192503)
			(xy 166.995047 -383.257349) (xy 166.995051 -383.322789) (xy 166.986263 -383.387637) (xy 166.968841 -383.450716)
			(xy 166.943103 -383.510882) (xy 166.926768 -383.539238) (xy 166.923438 -383.545255) (xy 166.919842 -383.558525)
			(xy 166.919656 -383.5654) (xy 166.919656 -384.3147) (xy 166.919841 -384.321574) (xy 166.923453 -384.334837)
			(xy 166.926768 -384.340862) (xy 166.943136 -384.369201) (xy 166.968876 -384.429372) (xy 166.986299 -384.492456)
			(xy 166.995088 -384.557308) (xy 166.995084 -384.622754) (xy 166.986287 -384.687605) (xy 166.968856 -384.750686)
			(xy 166.943108 -384.810854) (xy 166.926768 -384.83921) (xy 166.923447 -384.845232) (xy 166.919846 -384.858498)
			(xy 166.919656 -384.865372) (xy 166.919656 -385.151376) (xy 166.91916 -385.161522) (xy 166.911383 -385.180263)
			(xy 166.89701 -385.194585) (xy 166.878241 -385.202296) (xy 166.868094 -385.202684) (xy 166.151814 -385.202684)
			(xy 166.141691 -385.202163) (xy 166.122975 -385.194444) (xy 166.108619 -385.180169) (xy 166.100795 -385.161496)
			(xy 166.100252 -385.151376) (xy 166.100252 -384.865372) (xy 166.100077 -384.858497) (xy 166.096458 -384.845234)
			(xy 166.09314 -384.83921) (xy 166.076833 -384.810837) (xy 166.051086 -384.750674) (xy 166.033656 -384.687598)
			(xy 166.02486 -384.622751) (xy 166.024856 -384.557311) (xy 166.033644 -384.492463) (xy 166.051066 -384.429384)
			(xy 166.076805 -384.369218) (xy 166.09314 -384.340862) (xy 166.096464 -384.334842) (xy 166.100064 -384.321575)
			(xy 166.100252 -384.3147) (xy 166.100252 -383.5654) (xy 166.100066 -383.558526) (xy 166.096454 -383.545263)
			(xy 166.09314 -383.539238) (xy 166.076772 -383.510899) (xy 166.051031 -383.450728) (xy 166.033608 -383.387644)
			(xy 166.024819 -383.322792) (xy 164.766071 -383.322792) (xy 164.768966 -383.329559) (xy 164.786391 -383.392641)
			(xy 164.795182 -383.457492) (xy 164.79518 -383.522936) (xy 164.786385 -383.587786) (xy 164.768957 -383.650867)
			(xy 164.743212 -383.711034) (xy 164.726874 -383.73939) (xy 164.723515 -383.745408) (xy 164.719776 -383.758666)
			(xy 164.719508 -383.765552) (xy 164.719508 -384.051556) (xy 164.719048 -384.061675) (xy 164.711316 -384.080376)
			(xy 164.697013 -384.094691) (xy 164.678318 -384.102439) (xy 164.6682 -384.102864) (xy 163.95192 -384.102864)
			(xy 163.941794 -384.102467) (xy 163.923084 -384.094719) (xy 163.908768 -384.080396) (xy 163.901028 -384.061682)
			(xy 163.900612 -384.051556) (xy 163.900612 -383.765552) (xy 163.900392 -383.758658) (xy 163.896655 -383.745386)
			(xy 163.893246 -383.73939) (xy 163.876922 -383.711026) (xy 163.851176 -383.650862) (xy 163.833748 -383.587783)
			(xy 163.824953 -383.522935) (xy 163.824952 -383.457493) (xy 163.833743 -383.392644) (xy 163.851167 -383.329564)
			(xy 163.876909 -383.269398) (xy 163.893246 -383.241042) (xy 163.89663 -383.235037) (xy 163.900353 -383.221769)
			(xy 163.900612 -383.21488) (xy 163.900612 -382.465326) (xy 163.900402 -382.458431) (xy 163.896659 -382.445159)
			(xy 163.893246 -382.439164) (xy 163.8769 -382.410813) (xy 163.851156 -382.350645) (xy 163.833731 -382.287564)
			(xy 163.824939 -382.222713) (xy 160.395132 -382.222713) (xy 160.38634 -382.287562) (xy 160.368914 -382.350642)
			(xy 160.34317 -382.410808) (xy 160.326832 -382.439164) (xy 160.323533 -382.445196) (xy 160.319917 -382.458454)
			(xy 160.31972 -382.465326) (xy 160.31972 -383.21488) (xy 160.319917 -383.221753) (xy 160.323522 -383.235016)
			(xy 160.326832 -383.241042) (xy 160.343184 -383.26939) (xy 160.366033 -383.322792) (xy 161.624783 -383.322792)
			(xy 161.624787 -383.257347) (xy 161.633583 -383.192496) (xy 161.651013 -383.129414) (xy 161.67676 -383.069247)
			(xy 161.693098 -383.04089) (xy 161.696462 -383.034875) (xy 161.700198 -383.021615) (xy 161.700464 -383.014728)
			(xy 161.700464 -382.728724) (xy 161.701004 -382.718621) (xy 161.708727 -382.69995) (xy 161.723007 -382.685656)
			(xy 161.74167 -382.677914) (xy 161.751772 -382.677416) (xy 162.468052 -382.677416) (xy 162.478173 -382.677856)
			(xy 162.496879 -382.685591) (xy 162.511195 -382.699901) (xy 162.51894 -382.718603) (xy 162.51936 -382.728724)
			(xy 162.51936 -383.014728) (xy 162.519591 -383.021621) (xy 162.523321 -383.034893) (xy 162.526726 -383.04089)
			(xy 162.543034 -383.069263) (xy 162.568783 -383.129425) (xy 162.586214 -383.192502) (xy 162.595011 -383.257349)
			(xy 162.595015 -383.32279) (xy 162.586226 -383.387638) (xy 162.568803 -383.450717) (xy 162.543062 -383.510882)
			(xy 162.526726 -383.539238) (xy 162.523347 -383.545245) (xy 162.519621 -383.558512) (xy 162.51936 -383.5654)
			(xy 162.51936 -384.3147) (xy 162.519563 -384.321595) (xy 162.523312 -384.334867) (xy 162.526726 -384.340862)
			(xy 162.543095 -384.369201) (xy 162.568838 -384.429371) (xy 162.586262 -384.492455) (xy 162.595052 -384.557308)
			(xy 162.595048 -384.622754) (xy 162.58625 -384.687606) (xy 162.568817 -384.750687) (xy 162.543067 -384.810854)
			(xy 162.526726 -384.83921) (xy 162.523356 -384.845222) (xy 162.519625 -384.858485) (xy 162.51936 -384.865372)
			(xy 162.51936 -385.151376) (xy 162.518964 -385.161502) (xy 162.511216 -385.180213) (xy 162.496893 -385.194529)
			(xy 162.478178 -385.202268) (xy 162.468052 -385.202684) (xy 161.751772 -385.202684) (xy 161.741659 -385.202238)
			(xy 161.722978 -385.194488) (xy 161.708683 -385.180179) (xy 161.700952 -385.161489) (xy 161.700464 -385.151376)
			(xy 161.700464 -384.865372) (xy 161.70023 -384.858479) (xy 161.696502 -384.845207) (xy 161.693098 -384.83921)
			(xy 161.676792 -384.810837) (xy 161.651048 -384.750673) (xy 161.63362 -384.687597) (xy 161.624824 -384.622751)
			(xy 161.624819 -384.557311) (xy 161.633607 -384.492464) (xy 161.651027 -384.429385) (xy 161.676764 -384.369219)
			(xy 161.693098 -384.340862) (xy 161.696471 -384.334851) (xy 161.700202 -384.321588) (xy 161.700464 -384.3147)
			(xy 161.700464 -383.5654) (xy 161.700236 -383.558508) (xy 161.69649 -383.545242) (xy 161.693098 -383.539238)
			(xy 161.676731 -383.510898) (xy 161.650993 -383.450727) (xy 161.633571 -383.387644) (xy 161.624783 -383.322792)
			(xy 160.366033 -383.322792) (xy 160.368928 -383.329559) (xy 160.386354 -383.39264) (xy 160.395146 -383.457492)
			(xy 160.395144 -383.522936) (xy 160.386348 -383.587787) (xy 160.368919 -383.650867) (xy 160.343171 -383.711034)
			(xy 160.326832 -383.73939) (xy 160.323524 -383.745418) (xy 160.319914 -383.758679) (xy 160.31972 -383.765552)
			(xy 160.31972 -384.051556) (xy 160.319243 -384.061705) (xy 160.311465 -384.080452) (xy 160.297086 -384.094777)
			(xy 160.278308 -384.102481) (xy 160.268158 -384.102864) (xy 159.551878 -384.102864) (xy 159.54175 -384.102392)
			(xy 159.523029 -384.094657) (xy 159.508674 -384.080367) (xy 159.500855 -384.061681) (xy 159.500316 -384.051556)
			(xy 159.500316 -383.765552) (xy 159.500102 -383.75868) (xy 159.496508 -383.745418) (xy 159.493204 -383.73939)
			(xy 159.476881 -383.711026) (xy 159.451138 -383.650861) (xy 159.433711 -383.587782) (xy 159.424917 -383.522934)
			(xy 159.424916 -383.457493) (xy 159.433706 -383.392645) (xy 159.451129 -383.329565) (xy 159.476869 -383.269399)
			(xy 159.493204 -383.241042) (xy 159.496504 -383.23501) (xy 159.500119 -383.221752) (xy 159.500316 -383.21488)
			(xy 159.500316 -382.465326) (xy 159.500112 -382.458454) (xy 159.496512 -382.445191) (xy 159.493204 -382.439164)
			(xy 159.476859 -382.410812) (xy 159.451118 -382.350644) (xy 159.433694 -382.287563) (xy 159.424903 -382.222713)
			(xy 154.72791 -382.222713) (xy 154.72791 -392.812778) (xy 155.507434 -392.812778) (xy 155.511505 -392.757156)
			(xy 155.523631 -392.702719) (xy 155.543554 -392.650628) (xy 155.57085 -392.601993) (xy 155.604936 -392.55785)
			(xy 155.645085 -392.519141) (xy 155.690443 -392.48669) (xy 155.740043 -392.461189) (xy 155.792827 -392.443182)
			(xy 155.84767 -392.433052) (xy 155.903404 -392.431015) (xy 155.958841 -392.437115) (xy 156.012798 -392.451221)
			(xy 156.064127 -392.473033) (xy 156.111733 -392.502087) (xy 156.154601 -392.537762) (xy 156.191818 -392.579299)
			(xy 156.222591 -392.625812) (xy 156.246263 -392.676309) (xy 156.262331 -392.729716) (xy 156.270451 -392.784892)
			(xy 156.27096 -392.812778) (xy 156.270451 -392.840664) (xy 156.262331 -392.89584) (xy 156.246263 -392.949247)
			(xy 156.222591 -392.999744) (xy 156.191818 -393.046257) (xy 156.154601 -393.087794) (xy 156.111733 -393.123469)
			(xy 156.064127 -393.152523) (xy 156.012798 -393.174335) (xy 155.958841 -393.188441) (xy 155.903404 -393.194541)
			(xy 155.84767 -393.192504) (xy 155.792827 -393.182374) (xy 155.740043 -393.164367) (xy 155.690443 -393.138866)
			(xy 155.645085 -393.106415) (xy 155.604936 -393.067706) (xy 155.57085 -393.023563) (xy 155.543554 -392.974928)
			(xy 155.523631 -392.922837) (xy 155.511505 -392.8684) (xy 155.507434 -392.812778) (xy 154.72791 -392.812778)
			(xy 154.72791 -395.4272) (xy 157.53664 -395.4272) (xy 157.540711 -395.371578) (xy 157.552837 -395.317141)
			(xy 157.57276 -395.26505) (xy 157.600056 -395.216415) (xy 157.634142 -395.172272) (xy 157.674291 -395.133563)
			(xy 157.719649 -395.101112) (xy 157.769249 -395.075611) (xy 157.822033 -395.057604) (xy 157.876876 -395.047474)
			(xy 157.93261 -395.045437) (xy 157.988047 -395.051537) (xy 158.042004 -395.065643) (xy 158.093333 -395.087455)
			(xy 158.140939 -395.116509) (xy 158.183807 -395.152184) (xy 158.221024 -395.193721) (xy 158.251797 -395.240234)
			(xy 158.275469 -395.290731) (xy 158.291537 -395.344138) (xy 158.299657 -395.399314) (xy 158.300166 -395.4272)
			(xy 158.299657 -395.455086) (xy 158.291537 -395.510262) (xy 158.275469 -395.563669) (xy 158.251797 -395.614166)
			(xy 158.221024 -395.660679) (xy 158.183807 -395.702216) (xy 158.140939 -395.737891) (xy 158.093333 -395.766945)
			(xy 158.042004 -395.788757) (xy 157.988047 -395.802863) (xy 157.93261 -395.808963) (xy 157.876876 -395.806926)
			(xy 157.822033 -395.796796) (xy 157.769249 -395.778789) (xy 157.719649 -395.753288) (xy 157.674291 -395.720837)
			(xy 157.634142 -395.682128) (xy 157.600056 -395.637985) (xy 157.57276 -395.58935) (xy 157.552837 -395.537259)
			(xy 157.540711 -395.482822) (xy 157.53664 -395.4272) (xy 154.72791 -395.4272) (xy 154.72791 -397.82289)
			(xy 159.424887 -397.82289) (xy 159.424891 -397.757445) (xy 159.433688 -397.692594) (xy 159.451118 -397.629512)
			(xy 159.476865 -397.569345) (xy 159.493204 -397.540988) (xy 159.496523 -397.534966) (xy 159.500126 -397.5217)
			(xy 159.500316 -397.514826) (xy 159.500316 -396.765526) (xy 159.500112 -396.758654) (xy 159.496512 -396.745391)
			(xy 159.493204 -396.739364) (xy 159.476859 -396.711012) (xy 159.451118 -396.650844) (xy 159.433694 -396.587763)
			(xy 159.424903 -396.522913) (xy 159.424904 -396.45747) (xy 159.433697 -396.39262) (xy 159.451124 -396.32954)
			(xy 159.476867 -396.269373) (xy 159.493204 -396.241016) (xy 159.496513 -396.234989) (xy 159.500122 -396.221727)
			(xy 159.500316 -396.214854) (xy 159.500316 -395.92885) (xy 159.500804 -395.918684) (xy 159.508569 -395.899895)
			(xy 159.522934 -395.885509) (xy 159.541713 -395.877718) (xy 159.551878 -395.877288) (xy 160.268158 -395.877288)
			(xy 160.278333 -395.877699) (xy 160.297136 -395.88548) (xy 160.311525 -395.89987) (xy 160.319302 -395.918675)
			(xy 160.31972 -395.92885) (xy 160.31972 -396.214854) (xy 160.319927 -396.221726) (xy 160.323525 -396.234989)
			(xy 160.326832 -396.241016) (xy 160.343162 -396.269377) (xy 160.368908 -396.329542) (xy 160.386336 -396.392621)
			(xy 160.395131 -396.45747) (xy 160.395132 -396.522913) (xy 160.38634 -396.587762) (xy 160.368914 -396.650842)
			(xy 160.34317 -396.711008) (xy 160.326832 -396.739364) (xy 160.323533 -396.745396) (xy 160.319917 -396.758654)
			(xy 160.31972 -396.765526) (xy 160.31972 -397.514826) (xy 160.319899 -397.5217) (xy 160.323516 -397.534963)
			(xy 160.326832 -397.540988) (xy 160.336199 -397.557288) (xy 161.624808 -397.557288) (xy 161.633599 -397.492439)
			(xy 161.651022 -397.429359) (xy 161.676763 -397.369193) (xy 161.693098 -397.340836) (xy 161.696446 -397.334813)
			(xy 161.700192 -397.321559) (xy 161.700464 -397.314674) (xy 161.700464 -397.028924) (xy 161.701004 -397.018821)
			(xy 161.708727 -397.00015) (xy 161.723007 -396.985856) (xy 161.74167 -396.978114) (xy 161.751772 -396.977616)
			(xy 162.468052 -396.977616) (xy 162.478173 -396.978056) (xy 162.496879 -396.985791) (xy 162.511195 -397.000101)
			(xy 162.51894 -397.018803) (xy 162.51936 -397.028924) (xy 162.51936 -397.314674) (xy 162.519573 -397.321568)
			(xy 162.523315 -397.33484) (xy 162.526726 -397.340836) (xy 162.543073 -397.369187) (xy 162.568818 -397.429355)
			(xy 162.586245 -397.492436) (xy 162.595037 -397.557287) (xy 162.595036 -397.622731) (xy 162.586241 -397.687581)
			(xy 162.568812 -397.750662) (xy 162.543065 -397.810828) (xy 162.536115 -397.82289) (xy 163.824923 -397.82289)
			(xy 163.824927 -397.757445) (xy 163.833725 -397.692593) (xy 163.851157 -397.629511) (xy 163.876906 -397.569344)
			(xy 163.893246 -397.540988) (xy 163.896614 -397.534975) (xy 163.900347 -397.521713) (xy 163.900612 -397.514826)
			(xy 163.900612 -396.765526) (xy 163.900402 -396.758631) (xy 163.896659 -396.745359) (xy 163.893246 -396.739364)
			(xy 163.8769 -396.711013) (xy 163.851156 -396.650845) (xy 163.833731 -396.587764) (xy 163.824939 -396.522913)
			(xy 163.82494 -396.45747) (xy 163.833734 -396.392619) (xy 163.851162 -396.329539) (xy 163.876908 -396.269372)
			(xy 163.893246 -396.241016) (xy 163.896604 -396.234998) (xy 163.900343 -396.22174) (xy 163.900612 -396.214854)
			(xy 163.900612 -395.92885) (xy 163.901167 -395.91873) (xy 163.908873 -395.900015) (xy 163.923138 -395.885658)
			(xy 163.941803 -395.877832) (xy 163.95192 -395.877288) (xy 164.6682 -395.877288) (xy 164.678353 -395.877721)
			(xy 164.697103 -395.885515) (xy 164.711426 -395.899908) (xy 164.719127 -395.918695) (xy 164.719508 -395.92885)
			(xy 164.719508 -396.214854) (xy 164.719758 -396.221744) (xy 164.723489 -396.23501) (xy 164.726874 -396.241016)
			(xy 164.743202 -396.269377) (xy 164.768946 -396.329543) (xy 164.786373 -396.392622) (xy 164.795167 -396.45747)
			(xy 164.795168 -396.522912) (xy 164.786377 -396.587761) (xy 164.768952 -396.650841) (xy 164.74321 -396.711008)
			(xy 164.726874 -396.739364) (xy 164.723524 -396.745386) (xy 164.719779 -396.758641) (xy 164.719508 -396.765526)
			(xy 164.719508 -397.514826) (xy 164.719769 -397.521715) (xy 164.723492 -397.534981) (xy 164.726874 -397.540988)
			(xy 164.73624 -397.557287) (xy 166.024844 -397.557287) (xy 166.033635 -397.492438) (xy 166.051061 -397.429359)
			(xy 166.076803 -397.369192) (xy 166.09314 -397.340836) (xy 166.096437 -397.334803) (xy 166.100055 -397.321546)
			(xy 166.100252 -397.314674) (xy 166.100252 -397.028924) (xy 166.10074 -397.018777) (xy 166.108519 -397.000035)
			(xy 166.122895 -396.985712) (xy 166.141666 -396.978003) (xy 166.151814 -396.977616) (xy 166.868094 -396.977616)
			(xy 166.878217 -396.978131) (xy 166.896934 -396.985852) (xy 166.911289 -397.000129) (xy 166.919113 -397.018803)
			(xy 166.919656 -397.028924) (xy 166.919656 -397.314674) (xy 166.919851 -397.321547) (xy 166.923456 -397.33481)
			(xy 166.926768 -397.340836) (xy 166.943114 -397.369188) (xy 166.968856 -397.429355) (xy 166.986282 -397.492436)
			(xy 166.995073 -397.557287) (xy 166.995072 -397.62273) (xy 166.986278 -397.68758) (xy 166.968851 -397.750661)
			(xy 166.943106 -397.810828) (xy 166.936156 -397.822891) (xy 168.224959 -397.822891) (xy 168.224963 -397.757444)
			(xy 168.233762 -397.692592) (xy 168.251195 -397.629511) (xy 168.276947 -397.569344) (xy 168.293288 -397.540988)
			(xy 168.296606 -397.534965) (xy 168.30021 -397.5217) (xy 168.3004 -397.514826) (xy 168.3004 -396.765526)
			(xy 168.300198 -396.758654) (xy 168.296596 -396.745391) (xy 168.293288 -396.739364) (xy 168.276941 -396.711013)
			(xy 168.251195 -396.650846) (xy 168.233768 -396.587764) (xy 168.224975 -396.522914) (xy 168.224976 -396.457469)
			(xy 168.233771 -396.392619) (xy 168.251201 -396.329538) (xy 168.276948 -396.269372) (xy 168.293288 -396.241016)
			(xy 168.296596 -396.234988) (xy 168.300206 -396.221727) (xy 168.3004 -396.214854) (xy 168.3004 -395.92885)
			(xy 168.300904 -395.918686) (xy 168.308665 -395.8999) (xy 168.323026 -395.885515) (xy 168.341799 -395.877721)
			(xy 168.351962 -395.877288) (xy 169.068242 -395.877288) (xy 169.078423 -395.877631) (xy 169.097228 -395.885439)
			(xy 169.111613 -395.89985) (xy 169.119388 -395.918669) (xy 169.119804 -395.92885) (xy 169.119804 -396.214854)
			(xy 169.120013 -396.221726) (xy 169.12361 -396.234989) (xy 169.126916 -396.241016) (xy 169.143246 -396.269376)
			(xy 169.168993 -396.329542) (xy 169.186422 -396.392621) (xy 169.195217 -396.45747) (xy 169.195218 -396.522913)
			(xy 169.186426 -396.587762) (xy 169.168999 -396.650842) (xy 169.143254 -396.711008) (xy 169.126916 -396.739364)
			(xy 169.123615 -396.745395) (xy 169.12 -396.758654) (xy 169.119804 -396.765526) (xy 169.119804 -397.514826)
			(xy 169.119985 -397.5217) (xy 169.123601 -397.534963) (xy 169.126916 -397.540988) (xy 169.136284 -397.557287)
			(xy 170.42488 -397.557287) (xy 170.433672 -397.492438) (xy 170.451099 -397.429358) (xy 170.476844 -397.369192)
			(xy 170.493182 -397.340836) (xy 170.496528 -397.334812) (xy 170.500276 -397.321559) (xy 170.500548 -397.314674)
			(xy 170.500548 -397.028924) (xy 170.501103 -397.018823) (xy 170.508823 -397.000155) (xy 170.523098 -396.985862)
			(xy 170.541756 -396.978117) (xy 170.551856 -396.977616) (xy 171.268136 -396.977616) (xy 171.278249 -396.978056)
			(xy 171.296931 -396.985808) (xy 171.311225 -397.000119) (xy 171.318956 -397.01881) (xy 171.319444 -397.028924)
			(xy 171.319444 -397.314674) (xy 171.31966 -397.321568) (xy 171.3234 -397.33484) (xy 171.32681 -397.340836)
			(xy 171.343157 -397.369187) (xy 171.368903 -397.429354) (xy 171.386331 -397.492436) (xy 171.395123 -397.557286)
			(xy 171.395122 -397.622731) (xy 171.386327 -397.687581) (xy 171.368898 -397.750662) (xy 171.34315 -397.810828)
			(xy 171.336199 -397.82289) (xy 172.624749 -397.82289) (xy 172.624753 -397.757444) (xy 172.633551 -397.692592)
			(xy 172.650984 -397.629511) (xy 172.676735 -397.569344) (xy 172.693076 -397.540988) (xy 172.696393 -397.534965)
			(xy 172.699998 -397.5217) (xy 172.700188 -397.514826) (xy 172.700188 -396.765526) (xy 172.699987 -396.758653)
			(xy 172.696385 -396.745391) (xy 172.693076 -396.739364) (xy 172.676729 -396.711013) (xy 172.650984 -396.650845)
			(xy 172.633557 -396.587764) (xy 172.624764 -396.522913) (xy 172.624766 -396.457469) (xy 172.633561 -396.392619)
			(xy 172.65099 -396.329538) (xy 172.676737 -396.269372) (xy 172.693076 -396.241016) (xy 172.696383 -396.234988)
			(xy 172.699994 -396.221727) (xy 172.700188 -396.214854) (xy 172.700188 -395.92885) (xy 172.700606 -395.918675)
			(xy 172.708384 -395.899872) (xy 172.722772 -395.885484) (xy 172.741575 -395.877706) (xy 172.75175 -395.877288)
			(xy 173.46803 -395.877288) (xy 173.47821 -395.87764) (xy 173.497015 -395.885445) (xy 173.5114 -395.899852)
			(xy 173.519175 -395.91867) (xy 173.519592 -395.92885) (xy 173.519592 -396.214854) (xy 173.519803 -396.221726)
			(xy 173.523398 -396.234989) (xy 173.526704 -396.241016) (xy 173.543032 -396.269377) (xy 173.568774 -396.329543)
			(xy 173.5862 -396.392622) (xy 173.594993 -396.457471) (xy 173.594993 -396.49019) (xy 177.023784 -396.49019)
			(xy 177.027775 -396.428023) (xy 177.039684 -396.366876) (xy 177.059313 -396.307755) (xy 177.086342 -396.251629)
			(xy 177.120326 -396.19942) (xy 177.160708 -396.151985) (xy 177.206824 -396.110104) (xy 177.257916 -396.074464)
			(xy 177.313147 -396.04565) (xy 177.371609 -396.024136) (xy 177.432343 -396.010274) (xy 177.49435 -396.004292)
			(xy 177.556613 -396.006288) (xy 177.61811 -396.016231) (xy 177.677831 -396.033955) (xy 177.734794 -396.059172)
			(xy 177.788065 -396.091465) (xy 177.83677 -396.130305) (xy 177.880107 -396.175055) (xy 177.917367 -396.224979)
			(xy 177.947936 -396.279258) (xy 177.971314 -396.337001) (xy 177.987115 -396.397259) (xy 177.995081 -396.459042)
			(xy 177.99558 -396.49019) (xy 177.995081 -396.521338) (xy 177.987115 -396.583121) (xy 177.971314 -396.643379)
			(xy 177.947936 -396.701122) (xy 177.917367 -396.755401) (xy 177.880107 -396.805325) (xy 177.83677 -396.850075)
			(xy 177.788065 -396.888915) (xy 177.734794 -396.921208) (xy 177.677831 -396.946425) (xy 177.61811 -396.964149)
			(xy 177.556613 -396.974092) (xy 177.49435 -396.976088) (xy 177.432343 -396.970106) (xy 177.371609 -396.956244)
			(xy 177.313147 -396.93473) (xy 177.257916 -396.905916) (xy 177.206824 -396.870276) (xy 177.160708 -396.828395)
			(xy 177.120326 -396.78096) (xy 177.086342 -396.728751) (xy 177.059313 -396.672625) (xy 177.039684 -396.613504)
			(xy 177.027775 -396.552357) (xy 177.023784 -396.49019) (xy 173.594993 -396.49019) (xy 173.594994 -396.522912)
			(xy 173.586203 -396.587761) (xy 173.56878 -396.65084) (xy 173.543039 -396.711007) (xy 173.526704 -396.739364)
			(xy 173.523402 -396.745395) (xy 173.519788 -396.758654) (xy 173.519592 -396.765526) (xy 173.519592 -397.514826)
			(xy 173.519775 -397.5217) (xy 173.523389 -397.534963) (xy 173.526704 -397.540988) (xy 173.53607 -397.557288)
			(xy 174.82493 -397.557288) (xy 174.833721 -397.492439) (xy 174.851146 -397.429359) (xy 174.876888 -397.369192)
			(xy 174.893224 -397.340836) (xy 174.896528 -397.334806) (xy 174.90014 -397.321546) (xy 174.900336 -397.314674)
			(xy 174.900336 -397.028924) (xy 174.900742 -397.018767) (xy 174.908536 -397.000008) (xy 174.922939 -396.985682)
			(xy 174.941739 -396.977988) (xy 174.951898 -396.977616) (xy 175.668178 -396.977616) (xy 175.6783 -396.978144)
			(xy 175.697017 -396.98586) (xy 175.711373 -397.000133) (xy 175.719197 -397.018805) (xy 175.71974 -397.028924)
			(xy 175.71974 -397.314674) (xy 175.719937 -397.321547) (xy 175.723541 -397.33481) (xy 175.726852 -397.340836)
			(xy 175.743198 -397.369187) (xy 175.768942 -397.429355) (xy 175.786368 -397.492436) (xy 175.79516 -397.557287)
			(xy 175.795158 -397.62273) (xy 175.786364 -397.687581) (xy 175.768936 -397.750661) (xy 175.752033 -397.790162)
			(xy 177.023784 -397.790162) (xy 177.027775 -397.727995) (xy 177.039684 -397.666848) (xy 177.059313 -397.607727)
			(xy 177.086342 -397.551601) (xy 177.120326 -397.499392) (xy 177.160708 -397.451957) (xy 177.206824 -397.410076)
			(xy 177.257916 -397.374436) (xy 177.313147 -397.345622) (xy 177.371609 -397.324108) (xy 177.432343 -397.310246)
			(xy 177.49435 -397.304264) (xy 177.556613 -397.30626) (xy 177.61811 -397.316203) (xy 177.677831 -397.333927)
			(xy 177.734794 -397.359144) (xy 177.788065 -397.391437) (xy 177.83677 -397.430277) (xy 177.880107 -397.475027)
			(xy 177.917367 -397.524951) (xy 177.947936 -397.57923) (xy 177.9523 -397.59001) (xy 179.223932 -397.59001)
			(xy 179.227923 -397.527843) (xy 179.239832 -397.466696) (xy 179.259461 -397.407575) (xy 179.28649 -397.351449)
			(xy 179.320474 -397.29924) (xy 179.360856 -397.251805) (xy 179.406972 -397.209924) (xy 179.458064 -397.174284)
			(xy 179.513295 -397.14547) (xy 179.571757 -397.123956) (xy 179.632491 -397.110094) (xy 179.694498 -397.104112)
			(xy 179.756761 -397.106108) (xy 179.818258 -397.116051) (xy 179.877979 -397.133775) (xy 179.934942 -397.158992)
			(xy 179.988213 -397.191285) (xy 180.036918 -397.230125) (xy 180.080255 -397.274875) (xy 180.117515 -397.324799)
			(xy 180.148084 -397.379078) (xy 180.171462 -397.436821) (xy 180.187263 -397.497079) (xy 180.195229 -397.558862)
			(xy 180.195728 -397.59001) (xy 180.195229 -397.621158) (xy 180.187263 -397.682941) (xy 180.171462 -397.743199)
			(xy 180.148084 -397.800942) (xy 180.117515 -397.855221) (xy 180.080255 -397.905145) (xy 180.036918 -397.949895)
			(xy 179.988213 -397.988735) (xy 179.934942 -398.021028) (xy 179.877979 -398.046245) (xy 179.818258 -398.063969)
			(xy 179.756761 -398.073912) (xy 179.694498 -398.075908) (xy 179.632491 -398.069926) (xy 179.571757 -398.056064)
			(xy 179.513295 -398.03455) (xy 179.458064 -398.005736) (xy 179.406972 -397.970096) (xy 179.360856 -397.928215)
			(xy 179.320474 -397.88078) (xy 179.28649 -397.828571) (xy 179.259461 -397.772445) (xy 179.239832 -397.713324)
			(xy 179.227923 -397.652177) (xy 179.223932 -397.59001) (xy 177.9523 -397.59001) (xy 177.971314 -397.636973)
			(xy 177.987115 -397.697231) (xy 177.995081 -397.759014) (xy 177.99558 -397.790162) (xy 177.995081 -397.82131)
			(xy 177.987115 -397.883093) (xy 177.971314 -397.943351) (xy 177.947936 -398.001094) (xy 177.917367 -398.055373)
			(xy 177.880107 -398.105297) (xy 177.83677 -398.150047) (xy 177.788065 -398.188887) (xy 177.734794 -398.22118)
			(xy 177.677831 -398.246397) (xy 177.61811 -398.264121) (xy 177.556613 -398.274064) (xy 177.49435 -398.27606)
			(xy 177.432343 -398.270078) (xy 177.371609 -398.256216) (xy 177.313147 -398.234702) (xy 177.257916 -398.205888)
			(xy 177.206824 -398.170248) (xy 177.160708 -398.128367) (xy 177.120326 -398.080932) (xy 177.086342 -398.028723)
			(xy 177.059313 -397.972597) (xy 177.039684 -397.913476) (xy 177.027775 -397.852329) (xy 177.023784 -397.790162)
			(xy 175.752033 -397.790162) (xy 175.74319 -397.810828) (xy 175.726852 -397.839184) (xy 175.723547 -397.845214)
			(xy 175.719935 -397.858473) (xy 175.71974 -397.865346) (xy 175.71974 -398.6149) (xy 175.719927 -398.621774)
			(xy 175.723538 -398.635037) (xy 175.726852 -398.641062) (xy 175.74322 -398.669401) (xy 175.768962 -398.729572)
			(xy 175.786385 -398.792655) (xy 175.795174 -398.857508) (xy 175.795172 -398.890236) (xy 179.223932 -398.890236)
			(xy 179.227923 -398.828069) (xy 179.239832 -398.766922) (xy 179.259461 -398.707801) (xy 179.28649 -398.651675)
			(xy 179.320474 -398.599466) (xy 179.360856 -398.552031) (xy 179.406972 -398.51015) (xy 179.458064 -398.47451)
			(xy 179.513295 -398.445696) (xy 179.571757 -398.424182) (xy 179.632491 -398.41032) (xy 179.694498 -398.404338)
			(xy 179.756761 -398.406334) (xy 179.818258 -398.416277) (xy 179.877979 -398.434001) (xy 179.934942 -398.459218)
			(xy 179.988213 -398.491511) (xy 180.036918 -398.530351) (xy 180.080255 -398.575101) (xy 180.117515 -398.625025)
			(xy 180.148084 -398.679304) (xy 180.171462 -398.737047) (xy 180.187263 -398.797305) (xy 180.195229 -398.859088)
			(xy 180.195728 -398.890236) (xy 180.195229 -398.921384) (xy 180.187263 -398.983167) (xy 180.171462 -399.043425)
			(xy 180.148084 -399.101168) (xy 180.117515 -399.155447) (xy 180.080255 -399.205371) (xy 180.036918 -399.250121)
			(xy 179.988213 -399.288961) (xy 179.934942 -399.321254) (xy 179.877979 -399.346471) (xy 179.818258 -399.364195)
			(xy 179.756761 -399.374138) (xy 179.694498 -399.376134) (xy 179.632491 -399.370152) (xy 179.571757 -399.35629)
			(xy 179.513295 -399.334776) (xy 179.458064 -399.305962) (xy 179.406972 -399.270322) (xy 179.360856 -399.228441)
			(xy 179.320474 -399.181006) (xy 179.28649 -399.128797) (xy 179.259461 -399.072671) (xy 179.239832 -399.01355)
			(xy 179.227923 -398.952403) (xy 179.223932 -398.890236) (xy 175.795172 -398.890236) (xy 175.79517 -398.922954)
			(xy 175.786373 -398.987805) (xy 175.768941 -399.050887) (xy 175.743192 -399.111054) (xy 175.726852 -399.13941)
			(xy 175.723538 -399.145435) (xy 175.719931 -399.158698) (xy 175.71974 -399.165572) (xy 175.71974 -399.451576)
			(xy 175.71926 -399.461724) (xy 175.71148 -399.480468) (xy 175.697101 -399.494791) (xy 175.678327 -399.502498)
			(xy 175.668178 -399.502884) (xy 174.951898 -399.502884) (xy 174.941774 -399.502376) (xy 174.923058 -399.494652)
			(xy 174.908702 -399.480372) (xy 174.900879 -399.461697) (xy 174.900336 -399.451576) (xy 174.900336 -399.165572)
			(xy 174.90015 -399.158698) (xy 174.896537 -399.145436) (xy 174.893224 -399.13941) (xy 174.876918 -399.111037)
			(xy 174.851172 -399.050874) (xy 174.833742 -398.987797) (xy 174.824946 -398.922951) (xy 174.824942 -398.857511)
			(xy 174.83373 -398.792663) (xy 174.851151 -398.729584) (xy 174.87689 -398.669418) (xy 174.893224 -398.641062)
			(xy 174.896554 -398.635045) (xy 174.90015 -398.621775) (xy 174.900336 -398.6149) (xy 174.900336 -397.865346)
			(xy 174.900122 -397.858474) (xy 174.896528 -397.845212) (xy 174.893224 -397.839184) (xy 174.876896 -397.810823)
			(xy 174.851152 -397.750657) (xy 174.833725 -397.687578) (xy 174.824931 -397.62273) (xy 174.82493 -397.557288)
			(xy 173.53607 -397.557288) (xy 173.543008 -397.569362) (xy 173.568752 -397.629525) (xy 173.586181 -397.692602)
			(xy 173.594977 -397.757448) (xy 173.594981 -397.822887) (xy 173.586194 -397.887734) (xy 173.568774 -397.950813)
			(xy 173.543037 -398.010979) (xy 173.526704 -398.039336) (xy 173.523377 -398.045355) (xy 173.519779 -398.058623)
			(xy 173.519592 -398.065498) (xy 173.519592 -398.351502) (xy 173.519069 -398.361656) (xy 173.511299 -398.38042)
			(xy 173.496943 -398.394784) (xy 173.478184 -398.402563) (xy 173.46803 -398.403064) (xy 172.75175 -398.403064)
			(xy 172.741582 -398.402595) (xy 172.722789 -398.394827) (xy 172.708402 -398.380455) (xy 172.700615 -398.36167)
			(xy 172.700188 -398.351502) (xy 172.700188 -398.065498) (xy 172.699999 -398.058625) (xy 172.696389 -398.045362)
			(xy 172.693076 -398.039336) (xy 172.676705 -398.010998) (xy 172.650962 -397.950827) (xy 172.633538 -397.887744)
			(xy 172.624749 -397.82289) (xy 171.336199 -397.82289) (xy 171.32681 -397.839184) (xy 171.323456 -397.845204)
			(xy 171.319713 -397.85846) (xy 171.319444 -397.865346) (xy 171.319444 -398.6149) (xy 171.31965 -398.621795)
			(xy 171.323397 -398.635067) (xy 171.32681 -398.641062) (xy 171.343179 -398.669401) (xy 171.368923 -398.729571)
			(xy 171.386348 -398.792655) (xy 171.395138 -398.857508) (xy 171.395134 -398.922954) (xy 171.386336 -398.987806)
			(xy 171.368903 -399.050887) (xy 171.343151 -399.111054) (xy 171.32681 -399.13941) (xy 171.323447 -399.145426)
			(xy 171.31971 -399.158685) (xy 171.319444 -399.165572) (xy 171.319444 -399.451576) (xy 171.318896 -399.461678)
			(xy 171.311175 -399.480347) (xy 171.296897 -399.494641) (xy 171.278237 -399.502385) (xy 171.268136 -399.502884)
			(xy 170.551856 -399.502884) (xy 170.541742 -399.50245) (xy 170.52306 -399.494695) (xy 170.508766 -399.480383)
			(xy 170.501036 -399.46169) (xy 170.500548 -399.451576) (xy 170.500548 -399.165572) (xy 170.500316 -399.158679)
			(xy 170.496587 -399.145407) (xy 170.493182 -399.13941) (xy 170.476874 -399.111037) (xy 170.451125 -399.050875)
			(xy 170.433693 -398.987798) (xy 170.424896 -398.922951) (xy 170.424892 -398.85751) (xy 170.433681 -398.792662)
			(xy 170.451104 -398.729583) (xy 170.476846 -398.669418) (xy 170.493182 -398.641062) (xy 170.496554 -398.635051)
			(xy 170.500286 -398.621788) (xy 170.500548 -398.6149) (xy 170.500548 -397.865346) (xy 170.500326 -397.858452)
			(xy 170.49659 -397.84518) (xy 170.493182 -397.839184) (xy 170.476852 -397.810824) (xy 170.451105 -397.750658)
			(xy 170.433676 -397.687579) (xy 170.424881 -397.62273) (xy 170.42488 -397.557287) (xy 169.136284 -397.557287)
			(xy 169.143223 -397.569361) (xy 169.168972 -397.629524) (xy 169.186403 -397.6926) (xy 169.195201 -397.757447)
			(xy 169.195206 -397.822888) (xy 169.186417 -397.887736) (xy 169.168993 -397.950815) (xy 169.143252 -398.01098)
			(xy 169.126916 -398.039336) (xy 169.12359 -398.045355) (xy 169.119991 -398.058623) (xy 169.119804 -398.065498)
			(xy 169.119804 -398.351502) (xy 169.119269 -398.361655) (xy 169.111502 -398.380416) (xy 169.097149 -398.394779)
			(xy 169.078394 -398.402561) (xy 169.068242 -398.403064) (xy 168.351962 -398.403064) (xy 168.341802 -398.402598)
			(xy 168.323032 -398.394811) (xy 168.308669 -398.380437) (xy 168.300895 -398.361662) (xy 168.3004 -398.351502)
			(xy 168.3004 -398.065498) (xy 168.300209 -398.058625) (xy 168.2966 -398.045362) (xy 168.293288 -398.039336)
			(xy 168.276917 -398.010998) (xy 168.251173 -397.950828) (xy 168.233749 -397.887744) (xy 168.224959 -397.822891)
			(xy 166.936156 -397.822891) (xy 166.926768 -397.839184) (xy 166.923457 -397.84521) (xy 166.919849 -397.858473)
			(xy 166.919656 -397.865346) (xy 166.919656 -398.6149) (xy 166.919841 -398.621774) (xy 166.923453 -398.635037)
			(xy 166.926768 -398.641062) (xy 166.943136 -398.669401) (xy 166.968876 -398.729572) (xy 166.986299 -398.792656)
			(xy 166.995088 -398.857508) (xy 166.995084 -398.922954) (xy 166.986287 -398.987805) (xy 166.968856 -399.050886)
			(xy 166.943108 -399.111054) (xy 166.926768 -399.13941) (xy 166.923447 -399.145432) (xy 166.919846 -399.158698)
			(xy 166.919656 -399.165572) (xy 166.919656 -399.451576) (xy 166.91916 -399.461722) (xy 166.911383 -399.480463)
			(xy 166.89701 -399.494785) (xy 166.878241 -399.502496) (xy 166.868094 -399.502884) (xy 166.151814 -399.502884)
			(xy 166.141691 -399.502363) (xy 166.122975 -399.494644) (xy 166.108619 -399.480369) (xy 166.100795 -399.461696)
			(xy 166.100252 -399.451576) (xy 166.100252 -399.165572) (xy 166.100077 -399.158697) (xy 166.096458 -399.145434)
			(xy 166.09314 -399.13941) (xy 166.076833 -399.111037) (xy 166.051086 -399.050874) (xy 166.033656 -398.987798)
			(xy 166.02486 -398.922951) (xy 166.024856 -398.857511) (xy 166.033644 -398.792663) (xy 166.051066 -398.729584)
			(xy 166.076805 -398.669418) (xy 166.09314 -398.641062) (xy 166.096464 -398.635042) (xy 166.100064 -398.621775)
			(xy 166.100252 -398.6149) (xy 166.100252 -397.865346) (xy 166.100049 -397.858474) (xy 166.096449 -397.84521)
			(xy 166.09314 -397.839184) (xy 166.076811 -397.810823) (xy 166.051066 -397.750658) (xy 166.033639 -397.687578)
			(xy 166.024845 -397.62273) (xy 166.024844 -397.557287) (xy 164.73624 -397.557287) (xy 164.743179 -397.569362)
			(xy 164.768925 -397.629525) (xy 164.786354 -397.692601) (xy 164.795151 -397.757447) (xy 164.795156 -397.822888)
			(xy 164.786368 -397.887735) (xy 164.768947 -397.950814) (xy 164.743208 -398.01098) (xy 164.726874 -398.039336)
			(xy 164.723499 -398.045346) (xy 164.71977 -398.05861) (xy 164.719508 -398.065498) (xy 164.719508 -398.351502)
			(xy 164.718976 -398.361623) (xy 164.711257 -398.380335) (xy 164.696985 -398.394689) (xy 164.678318 -398.402517)
			(xy 164.6682 -398.403064) (xy 163.95192 -398.403064) (xy 163.941763 -398.402661) (xy 163.923004 -398.394866)
			(xy 163.908678 -398.380462) (xy 163.900984 -398.361662) (xy 163.900612 -398.351502) (xy 163.900612 -398.065498)
			(xy 163.900413 -398.058602) (xy 163.896662 -398.04533) (xy 163.893246 -398.039336) (xy 163.876876 -398.010998)
			(xy 163.851135 -397.950827) (xy 163.833712 -397.887743) (xy 163.824923 -397.82289) (xy 162.536115 -397.82289)
			(xy 162.526726 -397.839184) (xy 162.523365 -397.845201) (xy 162.519628 -397.85846) (xy 162.51936 -397.865346)
			(xy 162.51936 -398.6149) (xy 162.519563 -398.621795) (xy 162.523312 -398.635067) (xy 162.526726 -398.641062)
			(xy 162.543095 -398.669401) (xy 162.568838 -398.729571) (xy 162.586262 -398.792655) (xy 162.595052 -398.857508)
			(xy 162.595048 -398.922954) (xy 162.58625 -398.987806) (xy 162.568817 -399.050887) (xy 162.543067 -399.111054)
			(xy 162.526726 -399.13941) (xy 162.523356 -399.145422) (xy 162.519625 -399.158685) (xy 162.51936 -399.165572)
			(xy 162.51936 -399.451576) (xy 162.518964 -399.461702) (xy 162.511216 -399.480413) (xy 162.496893 -399.494729)
			(xy 162.478178 -399.502468) (xy 162.468052 -399.502884) (xy 161.751772 -399.502884) (xy 161.741659 -399.502438)
			(xy 161.722978 -399.494688) (xy 161.708683 -399.480379) (xy 161.700952 -399.461689) (xy 161.700464 -399.451576)
			(xy 161.700464 -399.165572) (xy 161.70023 -399.158679) (xy 161.696502 -399.145407) (xy 161.693098 -399.13941)
			(xy 161.676792 -399.111037) (xy 161.651048 -399.050873) (xy 161.63362 -398.987797) (xy 161.624824 -398.922951)
			(xy 161.624819 -398.857511) (xy 161.633607 -398.792664) (xy 161.651027 -398.729585) (xy 161.676764 -398.669419)
			(xy 161.693098 -398.641062) (xy 161.696471 -398.635051) (xy 161.700202 -398.621788) (xy 161.700464 -398.6149)
			(xy 161.700464 -397.865346) (xy 161.70024 -397.858453) (xy 161.696505 -397.845181) (xy 161.693098 -397.839184)
			(xy 161.67677 -397.810823) (xy 161.651028 -397.750657) (xy 161.633602 -397.687578) (xy 161.624809 -397.622729)
			(xy 161.624808 -397.557288) (xy 160.336199 -397.557288) (xy 160.343138 -397.569362) (xy 160.368886 -397.629524)
			(xy 160.386318 -397.6926) (xy 160.395115 -397.757447) (xy 160.395119 -397.822888) (xy 160.386331 -397.887736)
			(xy 160.368908 -397.950814) (xy 160.343168 -398.01098) (xy 160.326832 -398.039336) (xy 160.323507 -398.045356)
			(xy 160.319908 -398.058623) (xy 160.31972 -398.065498) (xy 160.31972 -398.351502) (xy 160.319337 -398.361679)
			(xy 160.311543 -398.380482) (xy 160.297145 -398.394868) (xy 160.278335 -398.402645) (xy 160.268158 -398.403064)
			(xy 159.551878 -398.403064) (xy 159.541719 -398.402585) (xy 159.52295 -398.394804) (xy 159.508585 -398.380433)
			(xy 159.500811 -398.361661) (xy 159.500316 -398.351502) (xy 159.500316 -398.065498) (xy 159.500123 -398.058625)
			(xy 159.496515 -398.045362) (xy 159.493204 -398.039336) (xy 159.476836 -398.010997) (xy 159.451096 -397.950826)
			(xy 159.433675 -397.887742) (xy 159.424887 -397.82289) (xy 154.72791 -397.82289) (xy 154.72791 -401.722803)
			(xy 159.424896 -401.722803) (xy 159.424898 -401.657359) (xy 159.433693 -401.592509) (xy 159.451121 -401.529428)
			(xy 159.476866 -401.469261) (xy 159.493204 -401.440904) (xy 159.496518 -401.434879) (xy 159.500124 -401.421615)
			(xy 159.500316 -401.414742) (xy 159.500316 -400.665442) (xy 159.500106 -400.65857) (xy 159.49651 -400.645307)
			(xy 159.493204 -400.63928) (xy 159.476873 -400.610921) (xy 159.45113 -400.550754) (xy 159.433705 -400.487675)
			(xy 159.424912 -400.422826) (xy 159.424911 -400.357384) (xy 159.433703 -400.292535) (xy 159.451127 -400.229455)
			(xy 159.476868 -400.169289) (xy 159.493204 -400.140932) (xy 159.496508 -400.134902) (xy 159.50012 -400.121642)
			(xy 159.500316 -400.11477) (xy 159.500316 -399.828766) (xy 159.500805 -399.818609) (xy 159.508586 -399.799843)
			(xy 159.522953 -399.78548) (xy 159.541721 -399.777703) (xy 159.551878 -399.777204) (xy 160.268158 -399.777204)
			(xy 160.278323 -399.777697) (xy 160.29711 -399.785462) (xy 160.311495 -399.799826) (xy 160.319288 -399.818602)
			(xy 160.31972 -399.828766) (xy 160.31972 -400.11477) (xy 160.319921 -400.121643) (xy 160.323523 -400.134905)
			(xy 160.326832 -400.140932) (xy 160.343175 -400.169285) (xy 160.36892 -400.229452) (xy 160.386347 -400.292533)
			(xy 160.39514 -400.357383) (xy 160.395139 -400.422827) (xy 160.386345 -400.487677) (xy 160.368917 -400.550758)
			(xy 160.343171 -400.610924) (xy 160.326832 -400.63928) (xy 160.323527 -400.645309) (xy 160.319915 -400.658569)
			(xy 160.31972 -400.665442) (xy 160.31972 -401.414742) (xy 160.319932 -401.421614) (xy 160.323526 -401.434877)
			(xy 160.326832 -401.440904) (xy 160.343152 -401.46927) (xy 160.368899 -401.529434) (xy 160.386328 -401.592512)
			(xy 160.395124 -401.65736) (xy 160.395127 -401.722802) (xy 160.386336 -401.787651) (xy 160.368911 -401.85073)
			(xy 160.343169 -401.910896) (xy 160.326832 -401.939252) (xy 160.323501 -401.945269) (xy 160.319906 -401.958539)
			(xy 160.31972 -401.965414) (xy 160.31972 -402.251418) (xy 160.31935 -402.261596) (xy 160.311551 -402.280399)
			(xy 160.297149 -402.294785) (xy 160.278336 -402.302562) (xy 160.268158 -402.30298) (xy 159.551878 -402.30298)
			(xy 159.541721 -402.302485) (xy 159.522955 -402.294707) (xy 159.508591 -402.280342) (xy 159.500814 -402.261575)
			(xy 159.500316 -402.251418) (xy 159.500316 -401.965414) (xy 159.500117 -401.958541) (xy 159.496513 -401.945279)
			(xy 159.493204 -401.939252) (xy 159.476849 -401.910906) (xy 159.451109 -401.850736) (xy 159.433686 -401.787654)
			(xy 159.424896 -401.722803) (xy 154.72791 -401.722803) (xy 154.72791 -402.822882) (xy 161.624776 -402.822882)
			(xy 161.624781 -402.757436) (xy 161.633579 -402.692584) (xy 161.651011 -402.629503) (xy 161.676759 -402.569335)
			(xy 161.693098 -402.540978) (xy 161.696466 -402.534965) (xy 161.7002 -402.521703) (xy 161.700464 -402.514816)
			(xy 161.700464 -401.765516) (xy 161.700251 -401.758622) (xy 161.696509 -401.74535) (xy 161.693098 -401.739354)
			(xy 161.676745 -401.711007) (xy 161.651005 -401.650838) (xy 161.633582 -401.587756) (xy 161.624792 -401.522905)
			(xy 161.624794 -401.457461) (xy 161.633589 -401.392611) (xy 161.651016 -401.32953) (xy 161.676761 -401.269363)
			(xy 161.693098 -401.241006) (xy 161.696456 -401.234988) (xy 161.700196 -401.22173) (xy 161.700464 -401.214844)
			(xy 161.700464 -400.92884) (xy 161.700948 -400.918725) (xy 161.708676 -400.900029) (xy 161.722972 -400.885714)
			(xy 161.741657 -400.877961) (xy 161.751772 -400.877532) (xy 162.468052 -400.877532) (xy 162.478175 -400.877956)
			(xy 162.496884 -400.885694) (xy 162.511201 -400.900009) (xy 162.518942 -400.918717) (xy 162.51936 -400.92884)
			(xy 162.51936 -401.214844) (xy 162.519585 -401.221737) (xy 162.523319 -401.23501) (xy 162.526726 -401.241006)
			(xy 162.543048 -401.269371) (xy 162.568795 -401.329535) (xy 162.586224 -401.392614) (xy 162.59502 -401.457462)
			(xy 162.595022 -401.522904) (xy 162.586231 -401.587753) (xy 162.568806 -401.650832) (xy 162.543063 -401.710998)
			(xy 162.536262 -401.722803) (xy 163.824932 -401.722803) (xy 163.824934 -401.657359) (xy 163.83373 -401.592508)
			(xy 163.85116 -401.529427) (xy 163.876907 -401.46926) (xy 163.893246 -401.440904) (xy 163.896608 -401.434888)
			(xy 163.900345 -401.421628) (xy 163.900612 -401.414742) (xy 163.900612 -400.665442) (xy 163.900396 -400.658548)
			(xy 163.896656 -400.645276) (xy 163.893246 -400.63928) (xy 163.876913 -400.610921) (xy 163.851169 -400.550755)
			(xy 163.833742 -400.487676) (xy 163.824948 -400.422826) (xy 163.824947 -400.357384) (xy 163.833739 -400.292535)
			(xy 163.851165 -400.229455) (xy 163.876909 -400.169288) (xy 163.893246 -400.140932) (xy 163.896598 -400.134911)
			(xy 163.900341 -400.121655) (xy 163.900612 -400.11477) (xy 163.900612 -399.828766) (xy 163.901098 -399.818641)
			(xy 163.908832 -399.799924) (xy 163.923117 -399.78557) (xy 163.941797 -399.777747) (xy 163.95192 -399.777204)
			(xy 164.6682 -399.777204) (xy 164.678355 -399.777622) (xy 164.697108 -399.785418) (xy 164.711431 -399.799816)
			(xy 164.71913 -399.818609) (xy 164.719508 -399.828766) (xy 164.719508 -400.11477) (xy 164.719752 -400.121661)
			(xy 164.723487 -400.134927) (xy 164.726874 -400.140932) (xy 164.743216 -400.169286) (xy 164.768959 -400.229453)
			(xy 164.786384 -400.292534) (xy 164.795176 -400.357384) (xy 164.795176 -400.422827) (xy 164.786382 -400.487676)
			(xy 164.768955 -400.550757) (xy 164.743211 -400.610924) (xy 164.726874 -400.63928) (xy 164.723519 -400.6453)
			(xy 164.719777 -400.658556) (xy 164.719508 -400.665442) (xy 164.719508 -401.414742) (xy 164.719762 -401.421632)
			(xy 164.72349 -401.434898) (xy 164.726874 -401.440904) (xy 164.743192 -401.469271) (xy 164.768937 -401.529435)
			(xy 164.786365 -401.592513) (xy 164.79516 -401.657361) (xy 164.795163 -401.722802) (xy 164.786373 -401.78765)
			(xy 164.76895 -401.850729) (xy 164.743209 -401.910896) (xy 164.726874 -401.939252) (xy 164.723494 -401.945259)
			(xy 164.719768 -401.958525) (xy 164.719508 -401.965414) (xy 164.719508 -402.251418) (xy 164.71899 -402.26154)
			(xy 164.711265 -402.280253) (xy 164.696989 -402.294607) (xy 164.678319 -402.302434) (xy 164.6682 -402.30298)
			(xy 163.95192 -402.30298) (xy 163.941765 -402.302562) (xy 163.923009 -402.294769) (xy 163.908684 -402.280371)
			(xy 163.900987 -402.261575) (xy 163.900612 -402.251418) (xy 163.900612 -401.965414) (xy 163.900407 -401.958519)
			(xy 163.89666 -401.945247) (xy 163.893246 -401.939252) (xy 163.87689 -401.910906) (xy 163.851147 -401.850737)
			(xy 163.833723 -401.787655) (xy 163.824932 -401.722803) (xy 162.536262 -401.722803) (xy 162.526726 -401.739354)
			(xy 162.523341 -401.745359) (xy 162.519619 -401.758627) (xy 162.51936 -401.765516) (xy 162.51936 -402.514816)
			(xy 162.519596 -402.521709) (xy 162.523322 -402.534981) (xy 162.526726 -402.540978) (xy 162.543024 -402.569356)
			(xy 162.568773 -402.629517) (xy 162.586206 -402.692593) (xy 162.595004 -402.757439) (xy 162.59501 -402.822879)
			(xy 162.59501 -402.822882) (xy 166.024812 -402.822882) (xy 166.024817 -402.757436) (xy 166.033616 -402.692584)
			(xy 166.051049 -402.629502) (xy 166.076799 -402.569334) (xy 166.09314 -402.540978) (xy 166.096458 -402.534955)
			(xy 166.100062 -402.52169) (xy 166.100252 -402.514816) (xy 166.100252 -401.765516) (xy 166.10006 -401.758643)
			(xy 166.096452 -401.74538) (xy 166.09314 -401.739354) (xy 166.076786 -401.711007) (xy 166.051043 -401.650838)
			(xy 166.033619 -401.587756) (xy 166.024828 -401.522905) (xy 166.02483 -401.457461) (xy 166.033626 -401.39261)
			(xy 166.051055 -401.329529) (xy 166.076801 -401.269362) (xy 166.09314 -401.241006) (xy 166.096448 -401.234978)
			(xy 166.100059 -401.221717) (xy 166.100252 -401.214844) (xy 166.100252 -400.92884) (xy 166.100754 -400.918694)
			(xy 166.108527 -400.899952) (xy 166.122899 -400.885629) (xy 166.141667 -400.87792) (xy 166.151814 -400.877532)
			(xy 166.868094 -400.877532) (xy 166.878219 -400.878031) (xy 166.896939 -400.885756) (xy 166.911295 -400.900038)
			(xy 166.919116 -400.918717) (xy 166.919656 -400.92884) (xy 166.919656 -401.214844) (xy 166.919862 -401.221716)
			(xy 166.92346 -401.234979) (xy 166.926768 -401.241006) (xy 166.943088 -401.269372) (xy 166.968833 -401.329536)
			(xy 166.986261 -401.392614) (xy 166.995056 -401.457462) (xy 166.995059 -401.522904) (xy 166.986268 -401.587752)
			(xy 166.968845 -401.650831) (xy 166.943104 -401.710998) (xy 166.936303 -401.722804) (xy 168.224968 -401.722804)
			(xy 168.224971 -401.657359) (xy 168.233767 -401.592507) (xy 168.251198 -401.529426) (xy 168.276948 -401.46926)
			(xy 168.293288 -401.440904) (xy 168.2966 -401.434878) (xy 168.300208 -401.421615) (xy 168.3004 -401.414742)
			(xy 168.3004 -400.665442) (xy 168.300192 -400.65857) (xy 168.296595 -400.645307) (xy 168.293288 -400.63928)
			(xy 168.276954 -400.610922) (xy 168.251207 -400.550756) (xy 168.233778 -400.487676) (xy 168.224984 -400.422827)
			(xy 168.224983 -400.357384) (xy 168.233776 -400.292534) (xy 168.251204 -400.229454) (xy 168.27695 -400.169288)
			(xy 168.293288 -400.140932) (xy 168.296591 -400.134901) (xy 168.300204 -400.121642) (xy 168.3004 -400.11477)
			(xy 168.3004 -399.828766) (xy 168.300905 -399.818611) (xy 168.308683 -399.799848) (xy 168.323045 -399.785485)
			(xy 168.341807 -399.777705) (xy 168.351962 -399.777204) (xy 169.068242 -399.777204) (xy 169.078398 -399.777698)
			(xy 169.097162 -399.78548) (xy 169.111524 -399.799845) (xy 169.119303 -399.81861) (xy 169.119804 -399.828766)
			(xy 169.119804 -400.11477) (xy 169.120007 -400.121642) (xy 169.123608 -400.134905) (xy 169.126916 -400.140932)
			(xy 169.14326 -400.169285) (xy 169.169006 -400.229452) (xy 169.186433 -400.292533) (xy 169.195226 -400.357383)
			(xy 169.195226 -400.422827) (xy 169.186431 -400.487677) (xy 169.169002 -400.550758) (xy 169.143255 -400.610924)
			(xy 169.126916 -400.63928) (xy 169.12361 -400.645309) (xy 169.119998 -400.658569) (xy 169.119804 -400.665442)
			(xy 169.119804 -401.414742) (xy 169.120018 -401.421614) (xy 169.123611 -401.434876) (xy 169.126916 -401.440904)
			(xy 169.143236 -401.46927) (xy 169.168984 -401.529434) (xy 169.186414 -401.592512) (xy 169.19521 -401.65736)
			(xy 169.195213 -401.722802) (xy 169.186422 -401.787651) (xy 169.168997 -401.85073) (xy 169.143253 -401.910896)
			(xy 169.126916 -401.939252) (xy 169.123584 -401.945268) (xy 169.119989 -401.958538) (xy 169.119804 -401.965414)
			(xy 169.119804 -402.251418) (xy 169.119283 -402.261572) (xy 169.11151 -402.280333) (xy 169.097154 -402.294697)
			(xy 169.078396 -402.302478) (xy 169.068242 -402.30298) (xy 168.351962 -402.30298) (xy 168.341804 -402.302498)
			(xy 168.323037 -402.294715) (xy 168.308674 -402.280346) (xy 168.300898 -402.261576) (xy 168.3004 -402.251418)
			(xy 168.3004 -401.965414) (xy 168.300203 -401.958541) (xy 168.296598 -401.945278) (xy 168.293288 -401.939252)
			(xy 168.27693 -401.910907) (xy 168.251186 -401.850738) (xy 168.23376 -401.787656) (xy 168.224968 -401.722804)
			(xy 166.936303 -401.722804) (xy 166.926768 -401.739354) (xy 166.923467 -401.745385) (xy 166.919853 -401.758644)
			(xy 166.919656 -401.765516) (xy 166.919656 -402.514816) (xy 166.919835 -402.52169) (xy 166.923451 -402.534953)
			(xy 166.926768 -402.540978) (xy 166.943064 -402.569357) (xy 166.968812 -402.629518) (xy 166.986242 -402.692594)
			(xy 166.99504 -402.757439) (xy 166.995046 -402.822879) (xy 166.995046 -402.822882) (xy 170.424848 -402.822882)
			(xy 170.424854 -402.757435) (xy 170.433653 -402.692583) (xy 170.451088 -402.629501) (xy 170.47684 -402.569334)
			(xy 170.493182 -402.540978) (xy 170.496549 -402.534964) (xy 170.500284 -402.521703) (xy 170.500548 -402.514816)
			(xy 170.500548 -401.765516) (xy 170.500337 -401.758621) (xy 170.496594 -401.745349) (xy 170.493182 -401.739354)
			(xy 170.476826 -401.711008) (xy 170.451082 -401.650839) (xy 170.433656 -401.587757) (xy 170.424864 -401.522905)
			(xy 170.424866 -401.45746) (xy 170.433663 -401.392609) (xy 170.451093 -401.329528) (xy 170.476842 -401.269362)
			(xy 170.493182 -401.241006) (xy 170.496539 -401.234987) (xy 170.50028 -401.22173) (xy 170.500548 -401.214844)
			(xy 170.500548 -400.92884) (xy 170.501117 -400.91874) (xy 170.508832 -400.900073) (xy 170.523102 -400.885779)
			(xy 170.541757 -400.878033) (xy 170.551856 -400.877532) (xy 171.268136 -400.877532) (xy 171.278265 -400.877887)
			(xy 171.296975 -400.885653) (xy 171.311289 -400.899989) (xy 171.319028 -400.918711) (xy 171.319444 -400.92884)
			(xy 171.319444 -401.214844) (xy 171.319671 -401.221737) (xy 171.323404 -401.235009) (xy 171.32681 -401.241006)
			(xy 171.343132 -401.269371) (xy 171.36888 -401.329535) (xy 171.38631 -401.392613) (xy 171.395106 -401.457462)
			(xy 171.395109 -401.522904) (xy 171.386317 -401.587753) (xy 171.368892 -401.650833) (xy 171.343148 -401.710998)
			(xy 171.336346 -401.722804) (xy 172.624758 -401.722804) (xy 172.62476 -401.657359) (xy 172.633557 -401.592508)
			(xy 172.650987 -401.529427) (xy 172.676736 -401.46926) (xy 172.693076 -401.440904) (xy 172.696388 -401.434878)
			(xy 172.699996 -401.421615) (xy 172.700188 -401.414742) (xy 172.700188 -400.665442) (xy 172.699981 -400.65857)
			(xy 172.696383 -400.645307) (xy 172.693076 -400.63928) (xy 172.676743 -400.610921) (xy 172.650996 -400.550756)
			(xy 172.633568 -400.487676) (xy 172.624774 -400.422827) (xy 172.624773 -400.357384) (xy 172.633566 -400.292534)
			(xy 172.650993 -400.229454) (xy 172.676738 -400.169288) (xy 172.693076 -400.140932) (xy 172.696378 -400.134901)
			(xy 172.699992 -400.121642) (xy 172.700188 -400.11477) (xy 172.700188 -399.828766) (xy 172.700537 -399.818586)
			(xy 172.708343 -399.799781) (xy 172.722752 -399.785395) (xy 172.741569 -399.777621) (xy 172.75175 -399.777204)
			(xy 173.46803 -399.777204) (xy 173.478186 -399.777708) (xy 173.496949 -399.785486) (xy 173.511312 -399.799848)
			(xy 173.519091 -399.818611) (xy 173.519592 -399.828766) (xy 173.519592 -400.11477) (xy 173.519796 -400.121642)
			(xy 173.523396 -400.134905) (xy 173.526704 -400.140932) (xy 173.543045 -400.169286) (xy 173.568786 -400.229454)
			(xy 173.586211 -400.292534) (xy 173.595002 -400.357384) (xy 173.595001 -400.390106) (xy 177.023784 -400.390106)
			(xy 177.027775 -400.327939) (xy 177.039684 -400.266792) (xy 177.059313 -400.207671) (xy 177.086342 -400.151545)
			(xy 177.120326 -400.099336) (xy 177.160708 -400.051901) (xy 177.206824 -400.01002) (xy 177.257916 -399.97438)
			(xy 177.313147 -399.945566) (xy 177.371609 -399.924052) (xy 177.432343 -399.91019) (xy 177.49435 -399.904208)
			(xy 177.556613 -399.906204) (xy 177.61811 -399.916147) (xy 177.677831 -399.933871) (xy 177.734794 -399.959088)
			(xy 177.788065 -399.991381) (xy 177.83677 -400.030221) (xy 177.880107 -400.074971) (xy 177.917367 -400.124895)
			(xy 177.947936 -400.179174) (xy 177.971314 -400.236917) (xy 177.987115 -400.297175) (xy 177.995081 -400.358958)
			(xy 177.99558 -400.390106) (xy 177.995081 -400.421254) (xy 177.987115 -400.483037) (xy 177.971314 -400.543295)
			(xy 177.947936 -400.601038) (xy 177.917367 -400.655317) (xy 177.880107 -400.705241) (xy 177.83677 -400.749991)
			(xy 177.788065 -400.788831) (xy 177.734794 -400.821124) (xy 177.677831 -400.846341) (xy 177.61811 -400.864065)
			(xy 177.556613 -400.874008) (xy 177.49435 -400.876004) (xy 177.432343 -400.870022) (xy 177.371609 -400.85616)
			(xy 177.313147 -400.834646) (xy 177.257916 -400.805832) (xy 177.206824 -400.770192) (xy 177.160708 -400.728311)
			(xy 177.120326 -400.680876) (xy 177.086342 -400.628667) (xy 177.059313 -400.572541) (xy 177.039684 -400.51342)
			(xy 177.027775 -400.452273) (xy 177.023784 -400.390106) (xy 173.595001 -400.390106) (xy 173.595001 -400.422827)
			(xy 173.586208 -400.487676) (xy 173.568783 -400.550756) (xy 173.54304 -400.610923) (xy 173.526704 -400.63928)
			(xy 173.523397 -400.645308) (xy 173.519786 -400.658569) (xy 173.519592 -400.665442) (xy 173.519592 -401.414742)
			(xy 173.519807 -401.421614) (xy 173.5234 -401.434876) (xy 173.526704 -401.440904) (xy 173.543021 -401.469271)
			(xy 173.568765 -401.529436) (xy 173.586192 -401.592513) (xy 173.594986 -401.657361) (xy 173.594989 -401.722802)
			(xy 173.586199 -401.78765) (xy 173.568777 -401.850729) (xy 173.543039 -401.910895) (xy 173.526704 -401.939252)
			(xy 173.523371 -401.945268) (xy 173.519777 -401.958538) (xy 173.519592 -401.965414) (xy 173.519592 -402.251418)
			(xy 173.519082 -402.261573) (xy 173.511308 -402.280337) (xy 173.496947 -402.294701) (xy 173.478185 -402.30248)
			(xy 173.46803 -402.30298) (xy 172.75175 -402.30298) (xy 172.741584 -402.302496) (xy 172.722794 -402.29473)
			(xy 172.708408 -402.280363) (xy 172.700618 -402.261584) (xy 172.700188 -402.251418) (xy 172.700188 -401.965414)
			(xy 172.699992 -401.958541) (xy 172.696387 -401.945278) (xy 172.693076 -401.939252) (xy 172.676719 -401.910907)
			(xy 172.650975 -401.850738) (xy 172.633549 -401.787655) (xy 172.624758 -401.722804) (xy 171.336346 -401.722804)
			(xy 171.32681 -401.739354) (xy 171.323432 -401.745362) (xy 171.319704 -401.758628) (xy 171.319444 -401.765516)
			(xy 171.319444 -402.514816) (xy 171.319682 -402.521708) (xy 171.323407 -402.53498) (xy 171.32681 -402.540978)
			(xy 171.343108 -402.569356) (xy 171.368859 -402.629517) (xy 171.386291 -402.692593) (xy 171.39509 -402.757439)
			(xy 171.395096 -402.822879) (xy 171.395096 -402.822882) (xy 174.824898 -402.822882) (xy 174.824904 -402.757436)
			(xy 174.833702 -402.692584) (xy 174.851134 -402.629502) (xy 174.876884 -402.569334) (xy 174.893224 -402.540978)
			(xy 174.896548 -402.534958) (xy 174.900147 -402.521691) (xy 174.900336 -402.514816) (xy 174.900336 -401.765516)
			(xy 174.900133 -401.758644) (xy 174.896532 -401.745381) (xy 174.893224 -401.739354) (xy 174.87687 -401.711007)
			(xy 174.851129 -401.650838) (xy 174.833705 -401.587756) (xy 174.824914 -401.522905) (xy 174.824916 -401.457461)
			(xy 174.833712 -401.39261) (xy 174.85114 -401.32953) (xy 174.876886 -401.269362) (xy 174.893224 -401.241006)
			(xy 174.896538 -401.234981) (xy 174.900144 -401.221718) (xy 174.900336 -401.214844) (xy 174.900336 -400.92884)
			(xy 174.900755 -400.918684) (xy 174.908544 -400.899926) (xy 174.922943 -400.8856) (xy 174.94174 -400.877905)
			(xy 174.951898 -400.877532) (xy 175.668178 -400.877532) (xy 175.678302 -400.878044) (xy 175.697022 -400.885763)
			(xy 175.711378 -400.900042) (xy 175.7192 -400.918718) (xy 175.71974 -400.92884) (xy 175.71974 -401.214844)
			(xy 175.719948 -401.221716) (xy 175.723545 -401.234979) (xy 175.726852 -401.241006) (xy 175.743173 -401.269371)
			(xy 175.768919 -401.329536) (xy 175.786347 -401.392614) (xy 175.795143 -401.457462) (xy 175.795145 -401.522904)
			(xy 175.786354 -401.587752) (xy 175.76893 -401.650832) (xy 175.752139 -401.690078) (xy 177.023784 -401.690078)
			(xy 177.027775 -401.627911) (xy 177.039684 -401.566764) (xy 177.059313 -401.507643) (xy 177.086342 -401.451517)
			(xy 177.120326 -401.399308) (xy 177.160708 -401.351873) (xy 177.206824 -401.309992) (xy 177.257916 -401.274352)
			(xy 177.313147 -401.245538) (xy 177.371609 -401.224024) (xy 177.432343 -401.210162) (xy 177.49435 -401.20418)
			(xy 177.556613 -401.206176) (xy 177.61811 -401.216119) (xy 177.677831 -401.233843) (xy 177.734794 -401.25906)
			(xy 177.788065 -401.291353) (xy 177.83677 -401.330193) (xy 177.880107 -401.374943) (xy 177.917367 -401.424867)
			(xy 177.947936 -401.479146) (xy 177.952403 -401.49018) (xy 179.223932 -401.49018) (xy 179.227923 -401.428013)
			(xy 179.239832 -401.366866) (xy 179.259461 -401.307745) (xy 179.28649 -401.251619) (xy 179.320474 -401.19941)
			(xy 179.360856 -401.151975) (xy 179.406972 -401.110094) (xy 179.458064 -401.074454) (xy 179.513295 -401.04564)
			(xy 179.571757 -401.024126) (xy 179.632491 -401.010264) (xy 179.694498 -401.004282) (xy 179.756761 -401.006278)
			(xy 179.818258 -401.016221) (xy 179.877979 -401.033945) (xy 179.934942 -401.059162) (xy 179.988213 -401.091455)
			(xy 180.036918 -401.130295) (xy 180.080255 -401.175045) (xy 180.117515 -401.224969) (xy 180.148084 -401.279248)
			(xy 180.171462 -401.336991) (xy 180.187263 -401.397249) (xy 180.195229 -401.459032) (xy 180.195728 -401.49018)
			(xy 180.195229 -401.521328) (xy 180.187263 -401.583111) (xy 180.171462 -401.643369) (xy 180.148084 -401.701112)
			(xy 180.117515 -401.755391) (xy 180.080255 -401.805315) (xy 180.036918 -401.850065) (xy 179.988213 -401.888905)
			(xy 179.934942 -401.921198) (xy 179.877979 -401.946415) (xy 179.818258 -401.964139) (xy 179.756761 -401.974082)
			(xy 179.694498 -401.976078) (xy 179.632491 -401.970096) (xy 179.571757 -401.956234) (xy 179.513295 -401.93472)
			(xy 179.458064 -401.905906) (xy 179.406972 -401.870266) (xy 179.360856 -401.828385) (xy 179.320474 -401.78095)
			(xy 179.28649 -401.728741) (xy 179.259461 -401.672615) (xy 179.239832 -401.613494) (xy 179.227923 -401.552347)
			(xy 179.223932 -401.49018) (xy 177.952403 -401.49018) (xy 177.971314 -401.536889) (xy 177.987115 -401.597147)
			(xy 177.995081 -401.65893) (xy 177.99558 -401.690078) (xy 177.995081 -401.721226) (xy 177.987115 -401.783009)
			(xy 177.971314 -401.843267) (xy 177.947936 -401.90101) (xy 177.917367 -401.955289) (xy 177.880107 -402.005213)
			(xy 177.83677 -402.049963) (xy 177.788065 -402.088803) (xy 177.734794 -402.121096) (xy 177.677831 -402.146313)
			(xy 177.61811 -402.164037) (xy 177.556613 -402.17398) (xy 177.49435 -402.175976) (xy 177.432343 -402.169994)
			(xy 177.371609 -402.156132) (xy 177.313147 -402.134618) (xy 177.257916 -402.105804) (xy 177.206824 -402.070164)
			(xy 177.160708 -402.028283) (xy 177.120326 -401.980848) (xy 177.086342 -401.928639) (xy 177.059313 -401.872513)
			(xy 177.039684 -401.813392) (xy 177.027775 -401.752245) (xy 177.023784 -401.690078) (xy 175.752139 -401.690078)
			(xy 175.743188 -401.710998) (xy 175.726852 -401.739354) (xy 175.723558 -401.745389) (xy 175.719939 -401.758645)
			(xy 175.71974 -401.765516) (xy 175.71974 -402.514816) (xy 175.719921 -402.52169) (xy 175.723536 -402.534953)
			(xy 175.726852 -402.540978) (xy 175.743149 -402.569357) (xy 175.768897 -402.629518) (xy 175.786328 -402.692593)
			(xy 175.795127 -402.757439) (xy 175.795129 -402.790152) (xy 179.223932 -402.790152) (xy 179.227923 -402.727985)
			(xy 179.239832 -402.666838) (xy 179.259461 -402.607717) (xy 179.28649 -402.551591) (xy 179.320474 -402.499382)
			(xy 179.360856 -402.451947) (xy 179.406972 -402.410066) (xy 179.458064 -402.374426) (xy 179.513295 -402.345612)
			(xy 179.571757 -402.324098) (xy 179.632491 -402.310236) (xy 179.694498 -402.304254) (xy 179.756761 -402.30625)
			(xy 179.818258 -402.316193) (xy 179.877979 -402.333917) (xy 179.934942 -402.359134) (xy 179.988213 -402.391427)
			(xy 180.036918 -402.430267) (xy 180.080255 -402.475017) (xy 180.117515 -402.524941) (xy 180.148084 -402.57922)
			(xy 180.171462 -402.636963) (xy 180.187263 -402.697221) (xy 180.195229 -402.759004) (xy 180.195728 -402.790152)
			(xy 180.195229 -402.8213) (xy 180.187263 -402.883083) (xy 180.171462 -402.943341) (xy 180.148084 -403.001084)
			(xy 180.117515 -403.055363) (xy 180.080255 -403.105287) (xy 180.036918 -403.150037) (xy 179.988213 -403.188877)
			(xy 179.934942 -403.22117) (xy 179.877979 -403.246387) (xy 179.818258 -403.264111) (xy 179.756761 -403.274054)
			(xy 179.694498 -403.27605) (xy 179.632491 -403.270068) (xy 179.571757 -403.256206) (xy 179.513295 -403.234692)
			(xy 179.458064 -403.205878) (xy 179.406972 -403.170238) (xy 179.360856 -403.128357) (xy 179.320474 -403.080922)
			(xy 179.28649 -403.028713) (xy 179.259461 -402.972587) (xy 179.239832 -402.913466) (xy 179.227923 -402.852319)
			(xy 179.223932 -402.790152) (xy 175.795129 -402.790152) (xy 175.795132 -402.822879) (xy 175.786345 -402.887726)
			(xy 175.768924 -402.950804) (xy 175.743186 -403.01097) (xy 175.726852 -403.039326) (xy 175.723532 -403.045348)
			(xy 175.719929 -403.058614) (xy 175.71974 -403.065488) (xy 175.71974 -403.351492) (xy 175.719273 -403.361641)
			(xy 175.711487 -403.380385) (xy 175.697105 -403.394707) (xy 175.678328 -403.402415) (xy 175.668178 -403.4028)
			(xy 174.951898 -403.4028) (xy 174.941776 -403.402276) (xy 174.923063 -403.394555) (xy 174.908708 -403.380281)
			(xy 174.900882 -403.361611) (xy 174.900336 -403.351492) (xy 174.900336 -403.065488) (xy 174.900144 -403.058615)
			(xy 174.896535 -403.045352) (xy 174.893224 -403.039326) (xy 174.876846 -403.010992) (xy 174.851107 -402.95082)
			(xy 174.833686 -402.887735) (xy 174.824898 -402.822882) (xy 171.395096 -402.822882) (xy 171.386308 -402.887727)
			(xy 171.368886 -402.950805) (xy 171.343146 -403.01097) (xy 171.32681 -403.039326) (xy 171.323441 -403.045339)
			(xy 171.319708 -403.058601) (xy 171.319444 -403.065488) (xy 171.319444 -403.351492) (xy 171.318909 -403.361595)
			(xy 171.311183 -403.380264) (xy 171.296901 -403.394558) (xy 171.278238 -403.402301) (xy 171.268136 -403.4028)
			(xy 170.551856 -403.4028) (xy 170.541744 -403.402351) (xy 170.523065 -403.394599) (xy 170.508772 -403.380291)
			(xy 170.501039 -403.361604) (xy 170.500548 -403.351492) (xy 170.500548 -403.065488) (xy 170.500309 -403.058596)
			(xy 170.496585 -403.045324) (xy 170.493182 -403.039326) (xy 170.476803 -403.010993) (xy 170.45106 -402.950821)
			(xy 170.433637 -402.887736) (xy 170.424848 -402.822882) (xy 166.995046 -402.822882) (xy 166.986259 -402.887726)
			(xy 166.968839 -402.950804) (xy 166.943102 -403.01097) (xy 166.926768 -403.039326) (xy 166.923442 -403.045345)
			(xy 166.919844 -403.058613) (xy 166.919656 -403.065488) (xy 166.919656 -403.351492) (xy 166.919173 -403.361639)
			(xy 166.911391 -403.38038) (xy 166.897014 -403.394702) (xy 166.878242 -403.402412) (xy 166.868094 -403.4028)
			(xy 166.151814 -403.4028) (xy 166.141693 -403.402263) (xy 166.12298 -403.394547) (xy 166.108624 -403.380277)
			(xy 166.100798 -403.36161) (xy 166.100252 -403.351492) (xy 166.100252 -403.065488) (xy 166.100071 -403.058614)
			(xy 166.096456 -403.045351) (xy 166.09314 -403.039326) (xy 166.076762 -403.010992) (xy 166.051022 -402.95082)
			(xy 166.0336 -402.887736) (xy 166.024812 -402.822882) (xy 162.59501 -402.822882) (xy 162.586222 -402.887726)
			(xy 162.568801 -402.950805) (xy 162.543061 -403.01097) (xy 162.526726 -403.039326) (xy 162.523351 -403.045335)
			(xy 162.519623 -403.0586) (xy 162.51936 -403.065488) (xy 162.51936 -403.351492) (xy 162.518976 -403.361619)
			(xy 162.511224 -403.38033) (xy 162.496896 -403.394646) (xy 162.478179 -403.402384) (xy 162.468052 -403.4028)
			(xy 161.751772 -403.4028) (xy 161.741661 -403.402338) (xy 161.722983 -403.394591) (xy 161.708689 -403.380287)
			(xy 161.700955 -403.361603) (xy 161.700464 -403.351492) (xy 161.700464 -403.065488) (xy 161.700224 -403.058596)
			(xy 161.6965 -403.045324) (xy 161.693098 -403.039326) (xy 161.676721 -403.010992) (xy 161.650983 -402.95082)
			(xy 161.633563 -402.887735) (xy 161.624776 -402.822882) (xy 154.72791 -402.822882) (xy 154.72791 -405.622716)
			(xy 159.424905 -405.622716) (xy 159.424906 -405.557273) (xy 159.433699 -405.492424) (xy 159.451124 -405.429344)
			(xy 159.476867 -405.369177) (xy 159.493204 -405.34082) (xy 159.496512 -405.334792) (xy 159.500122 -405.321531)
			(xy 159.500316 -405.314658) (xy 159.500316 -404.565358) (xy 159.5001 -404.558487) (xy 159.496508 -404.545224)
			(xy 159.493204 -404.539196) (xy 159.476886 -404.510829) (xy 159.451143 -404.450665) (xy 159.433715 -404.387587)
			(xy 159.424921 -404.322739) (xy 159.424918 -404.257298) (xy 159.433708 -404.19245) (xy 159.45113 -404.129371)
			(xy 159.476869 -404.069205) (xy 159.493204 -404.040848) (xy 159.496538 -404.034833) (xy 159.500131 -404.021562)
			(xy 159.500316 -404.014686) (xy 159.500316 -403.728682) (xy 159.500818 -403.718526) (xy 159.508594 -403.69976)
			(xy 159.522957 -403.685396) (xy 159.541722 -403.677619) (xy 159.551878 -403.67712) (xy 160.268158 -403.67712)
			(xy 160.278325 -403.677598) (xy 160.297115 -403.685366) (xy 160.311501 -403.699735) (xy 160.31929 -403.718516)
			(xy 160.31972 -403.728682) (xy 160.31972 -404.014686) (xy 160.319915 -404.021559) (xy 160.323521 -404.034822)
			(xy 160.326832 -404.040848) (xy 160.343189 -404.069194) (xy 160.368933 -404.129362) (xy 160.386358 -404.192445)
			(xy 160.395149 -404.257296) (xy 160.395147 -404.322741) (xy 160.38635 -404.387592) (xy 160.36892 -404.450673)
			(xy 160.343172 -404.51084) (xy 160.326832 -404.539196) (xy 160.323521 -404.545223) (xy 160.319913 -404.558485)
			(xy 160.31972 -404.565358) (xy 160.31972 -405.314658) (xy 160.319926 -405.32153) (xy 160.323524 -405.334793)
			(xy 160.326832 -405.34082) (xy 160.343165 -405.369179) (xy 160.368911 -405.429344) (xy 160.386339 -405.492424)
			(xy 160.395133 -405.557273) (xy 160.395134 -405.622716) (xy 160.386341 -405.687566) (xy 160.368914 -405.750646)
			(xy 160.34317 -405.810812) (xy 160.326832 -405.839168) (xy 160.323531 -405.8452) (xy 160.319917 -405.858458)
			(xy 160.31972 -405.86533) (xy 160.31972 -406.151334) (xy 160.319363 -406.161513) (xy 160.311559 -406.180317)
			(xy 160.297153 -406.194702) (xy 160.278338 -406.202478) (xy 160.268158 -406.202896) (xy 159.551878 -406.202896)
			(xy 159.541723 -406.202386) (xy 159.52296 -406.19461) (xy 159.508596 -406.18025) (xy 159.500817 -406.161489)
			(xy 159.500316 -406.151334) (xy 159.500316 -405.86533) (xy 159.500111 -405.858458) (xy 159.496511 -405.845195)
			(xy 159.493204 -405.839168) (xy 159.476863 -405.810814) (xy 159.451121 -405.750647) (xy 159.433696 -405.687566)
			(xy 159.424905 -405.622716) (xy 154.72791 -405.622716) (xy 154.72791 -406.722795) (xy 161.624785 -406.722795)
			(xy 161.624789 -406.65735) (xy 161.633585 -406.592499) (xy 161.651014 -406.529418) (xy 161.67676 -406.469251)
			(xy 161.693098 -406.440894) (xy 161.69646 -406.434878) (xy 161.700198 -406.421618) (xy 161.700464 -406.414732)
			(xy 161.700464 -405.665432) (xy 161.700245 -405.658538) (xy 161.696507 -405.645266) (xy 161.693098 -405.63927)
			(xy 161.676759 -405.610915) (xy 161.651017 -405.550748) (xy 161.633593 -405.487667) (xy 161.624801 -405.422818)
			(xy 161.624801 -405.357375) (xy 161.633594 -405.292526) (xy 161.651019 -405.229446) (xy 161.676762 -405.169279)
			(xy 161.693098 -405.140922) (xy 161.69645 -405.134901) (xy 161.700194 -405.121645) (xy 161.700464 -405.11476)
			(xy 161.700464 -404.828756) (xy 161.700948 -404.818649) (xy 161.708694 -404.799977) (xy 161.72299 -404.785685)
			(xy 161.741665 -404.777945) (xy 161.751772 -404.777448) (xy 162.468052 -404.777448) (xy 162.478165 -404.777954)
			(xy 162.496858 -404.785677) (xy 162.511172 -404.799965) (xy 162.518928 -404.818644) (xy 162.51936 -404.828756)
			(xy 162.51936 -405.11476) (xy 162.519579 -405.121654) (xy 162.523317 -405.134926) (xy 162.526726 -405.140922)
			(xy 162.543061 -405.16928) (xy 162.568807 -405.229446) (xy 162.586235 -405.292525) (xy 162.595029 -405.357375)
			(xy 162.59503 -405.422818) (xy 162.586237 -405.487668) (xy 162.568809 -405.550748) (xy 162.543064 -405.610914)
			(xy 162.536263 -405.622717) (xy 163.824941 -405.622717) (xy 163.824942 -405.557273) (xy 163.833735 -405.492423)
			(xy 163.851163 -405.429343) (xy 163.876908 -405.369176) (xy 163.893246 -405.34082) (xy 163.896603 -405.334801)
			(xy 163.900343 -405.321544) (xy 163.900612 -405.314658) (xy 163.900612 -404.565358) (xy 163.90039 -404.558464)
			(xy 163.896654 -404.545192) (xy 163.893246 -404.539196) (xy 163.876927 -404.51083) (xy 163.851181 -404.450665)
			(xy 163.833752 -404.387587) (xy 163.824957 -404.32274) (xy 163.824954 -404.257298) (xy 163.833745 -404.19245)
			(xy 163.851169 -404.12937) (xy 163.87691 -404.069204) (xy 163.893246 -404.040848) (xy 163.896628 -404.034842)
			(xy 163.900352 -404.021575) (xy 163.900612 -404.014686) (xy 163.900612 -403.728682) (xy 163.901111 -403.718558)
			(xy 163.908839 -403.699841) (xy 163.923121 -403.685486) (xy 163.941798 -403.677663) (xy 163.95192 -403.67712)
			(xy 164.6682 -403.67712) (xy 164.678357 -403.677522) (xy 164.697113 -403.685321) (xy 164.711437 -403.699724)
			(xy 164.719133 -403.718523) (xy 164.719508 -403.728682) (xy 164.719508 -404.014686) (xy 164.719746 -404.021577)
			(xy 164.723485 -404.034843) (xy 164.726874 -404.040848) (xy 164.74323 -404.069194) (xy 164.768971 -404.129363)
			(xy 164.786395 -404.192445) (xy 164.795185 -404.257297) (xy 164.795183 -404.322741) (xy 164.786387 -404.387592)
			(xy 164.768959 -404.450672) (xy 164.743212 -404.51084) (xy 164.726874 -404.539196) (xy 164.723513 -404.545213)
			(xy 164.719775 -404.558472) (xy 164.719508 -404.565358) (xy 164.719508 -405.314658) (xy 164.719756 -405.321548)
			(xy 164.723488 -405.334814) (xy 164.726874 -405.34082) (xy 164.743206 -405.369179) (xy 164.76895 -405.429345)
			(xy 164.786376 -405.492425) (xy 164.795169 -405.557274) (xy 164.79517 -405.622716) (xy 164.786378 -405.687565)
			(xy 164.768953 -405.750645) (xy 164.743211 -405.810812) (xy 164.726874 -405.839168) (xy 164.723523 -405.84519)
			(xy 164.719779 -405.858445) (xy 164.719508 -405.86533) (xy 164.719508 -406.151334) (xy 164.719003 -406.161457)
			(xy 164.711273 -406.18017) (xy 164.696993 -406.194523) (xy 164.67832 -406.20235) (xy 164.6682 -406.202896)
			(xy 163.95192 -406.202896) (xy 163.941767 -406.202462) (xy 163.923014 -406.194672) (xy 163.90869 -406.180279)
			(xy 163.90099 -406.161489) (xy 163.900612 -406.151334) (xy 163.900612 -405.86533) (xy 163.9004 -405.858435)
			(xy 163.896658 -405.845163) (xy 163.893246 -405.839168) (xy 163.876903 -405.810815) (xy 163.85116 -405.750647)
			(xy 163.833733 -405.687567) (xy 163.824941 -405.622717) (xy 162.536263 -405.622717) (xy 162.526726 -405.63927)
			(xy 162.52337 -405.645289) (xy 162.51963 -405.658546) (xy 162.51936 -405.665432) (xy 162.51936 -406.414732)
			(xy 162.519589 -406.421625) (xy 162.52332 -406.434897) (xy 162.526726 -406.440894) (xy 162.543037 -406.469265)
			(xy 162.568786 -406.529428) (xy 162.586216 -406.592505) (xy 162.595013 -406.657352) (xy 162.595017 -406.722793)
			(xy 162.595017 -406.722795) (xy 166.024821 -406.722795) (xy 166.024825 -406.65735) (xy 166.033622 -406.592499)
			(xy 166.051052 -406.529417) (xy 166.0768 -406.46925) (xy 166.09314 -406.440894) (xy 166.096452 -406.434868)
			(xy 166.10006 -406.421605) (xy 166.100252 -406.414732) (xy 166.100252 -405.665432) (xy 166.100054 -405.658559)
			(xy 166.096451 -405.645296) (xy 166.09314 -405.63927) (xy 166.076799 -405.610916) (xy 166.051056 -405.550749)
			(xy 166.033629 -405.487668) (xy 166.024837 -405.422818) (xy 166.024837 -405.357375) (xy 166.033631 -405.292525)
			(xy 166.051058 -405.229445) (xy 166.076802 -405.169278) (xy 166.09314 -405.140922) (xy 166.096442 -405.134891)
			(xy 166.100057 -405.121632) (xy 166.100252 -405.11476) (xy 166.100252 -404.828756) (xy 166.100685 -404.818605)
			(xy 166.108486 -404.799861) (xy 166.122878 -404.785541) (xy 166.141661 -404.777834) (xy 166.151814 -404.777448)
			(xy 166.868094 -404.777448) (xy 166.878221 -404.777932) (xy 166.896944 -404.785659) (xy 166.911301 -404.799946)
			(xy 166.919119 -404.818631) (xy 166.919656 -404.828756) (xy 166.919656 -405.11476) (xy 166.919856 -405.121633)
			(xy 166.923458 -405.134896) (xy 166.926768 -405.140922) (xy 166.943102 -405.16928) (xy 166.968846 -405.229446)
			(xy 166.986272 -405.292526) (xy 166.995065 -405.357375) (xy 166.995066 -405.422818) (xy 166.986274 -405.487667)
			(xy 166.968848 -405.550747) (xy 166.943105 -405.610914) (xy 166.936305 -405.622717) (xy 168.224977 -405.622717)
			(xy 168.224978 -405.557273) (xy 168.233772 -405.492422) (xy 168.251201 -405.429342) (xy 168.276949 -405.369176)
			(xy 168.293288 -405.34082) (xy 168.296595 -405.334791) (xy 168.300206 -405.321531) (xy 168.3004 -405.314658)
			(xy 168.3004 -404.565358) (xy 168.300186 -404.558486) (xy 168.296593 -404.545224) (xy 168.293288 -404.539196)
			(xy 168.276968 -404.51083) (xy 168.25122 -404.450666) (xy 168.233789 -404.387588) (xy 168.224993 -404.32274)
			(xy 168.224991 -404.257298) (xy 168.233782 -404.192449) (xy 168.251207 -404.129369) (xy 168.276951 -404.069204)
			(xy 168.293288 -404.040848) (xy 168.29662 -404.034832) (xy 168.300215 -404.021562) (xy 168.3004 -404.014686)
			(xy 168.3004 -403.728682) (xy 168.300917 -403.718528) (xy 168.308691 -403.699765) (xy 168.323049 -403.685402)
			(xy 168.341808 -403.677621) (xy 168.351962 -403.67712) (xy 169.068242 -403.67712) (xy 169.0784 -403.677599)
			(xy 169.097167 -403.685383) (xy 169.11153 -403.699753) (xy 169.119306 -403.718524) (xy 169.119804 -403.728682)
			(xy 169.119804 -404.014686) (xy 169.120001 -404.021559) (xy 169.123606 -404.034822) (xy 169.126916 -404.040848)
			(xy 169.143273 -404.069193) (xy 169.169018 -404.129362) (xy 169.186444 -404.192444) (xy 169.195235 -404.257296)
			(xy 169.195233 -404.322741) (xy 169.186436 -404.387593) (xy 169.169005 -404.450674) (xy 169.143256 -404.51084)
			(xy 169.126916 -404.539196) (xy 169.123604 -404.545222) (xy 169.119996 -404.558485) (xy 169.119804 -404.565358)
			(xy 169.119804 -405.314658) (xy 169.120012 -405.32153) (xy 169.123609 -405.334793) (xy 169.126916 -405.34082)
			(xy 169.14325 -405.369179) (xy 169.168996 -405.429344) (xy 169.186425 -405.492424) (xy 169.19522 -405.557273)
			(xy 169.19522 -405.622716) (xy 169.186427 -405.687566) (xy 169.169 -405.750646) (xy 169.143254 -405.810812)
			(xy 169.126916 -405.839168) (xy 169.123614 -405.845199) (xy 169.12 -405.858458) (xy 169.119804 -405.86533)
			(xy 169.119804 -406.151334) (xy 169.119296 -406.161489) (xy 169.111518 -406.180251) (xy 169.097157 -406.194613)
			(xy 169.078397 -406.202394) (xy 169.068242 -406.202896) (xy 168.351962 -406.202896) (xy 168.341806 -406.202399)
			(xy 168.323042 -406.194618) (xy 168.30868 -406.180254) (xy 168.300901 -406.16149) (xy 168.3004 -406.151334)
			(xy 168.3004 -405.86533) (xy 168.300196 -405.858458) (xy 168.296596 -405.845195) (xy 168.293288 -405.839168)
			(xy 168.276944 -405.810815) (xy 168.251198 -405.750648) (xy 168.23377 -405.687567) (xy 168.224977 -405.622717)
			(xy 166.936305 -405.622717) (xy 166.926768 -405.63927) (xy 166.923462 -405.645299) (xy 166.919851 -405.658559)
			(xy 166.919656 -405.665432) (xy 166.919656 -406.414732) (xy 166.919829 -406.421607) (xy 166.923449 -406.43487)
			(xy 166.926768 -406.440894) (xy 166.943078 -406.469265) (xy 166.968824 -406.529428) (xy 166.986253 -406.592505)
			(xy 166.995049 -406.657352) (xy 166.995053 -406.722793) (xy 166.995053 -406.722795) (xy 170.424857 -406.722795)
			(xy 170.424861 -406.65735) (xy 170.433659 -406.592498) (xy 170.451091 -406.529417) (xy 170.476841 -406.46925)
			(xy 170.493182 -406.440894) (xy 170.496543 -406.434877) (xy 170.500282 -406.421618) (xy 170.500548 -406.414732)
			(xy 170.500548 -405.665432) (xy 170.500331 -405.658538) (xy 170.496592 -405.645266) (xy 170.493182 -405.63927)
			(xy 170.47684 -405.610916) (xy 170.451094 -405.550749) (xy 170.433666 -405.487669) (xy 170.424873 -405.422818)
			(xy 170.424874 -405.357375) (xy 170.433668 -405.292524) (xy 170.451096 -405.229444) (xy 170.476843 -405.169278)
			(xy 170.493182 -405.140922) (xy 170.496533 -405.1349) (xy 170.500278 -405.121645) (xy 170.500548 -405.11476)
			(xy 170.500548 -404.828756) (xy 170.501048 -404.818651) (xy 170.50879 -404.799982) (xy 170.523082 -404.78569)
			(xy 170.541751 -404.777948) (xy 170.551856 -404.777448) (xy 171.268136 -404.777448) (xy 171.278241 -404.777954)
			(xy 171.29691 -404.785694) (xy 171.311201 -404.799984) (xy 171.318944 -404.818651) (xy 171.319444 -404.828756)
			(xy 171.319444 -405.11476) (xy 171.319665 -405.121654) (xy 171.323402 -405.134926) (xy 171.32681 -405.140922)
			(xy 171.343146 -405.16928) (xy 171.368892 -405.229445) (xy 171.386321 -405.292525) (xy 171.395115 -405.357375)
			(xy 171.395116 -405.422818) (xy 171.386323 -405.487668) (xy 171.368895 -405.550748) (xy 171.343149 -405.610914)
			(xy 171.336348 -405.622717) (xy 172.624767 -405.622717) (xy 172.624767 -405.557273) (xy 172.633562 -405.492423)
			(xy 172.65099 -405.429342) (xy 172.676737 -405.369176) (xy 172.693076 -405.34082) (xy 172.696382 -405.334791)
			(xy 172.699994 -405.321531) (xy 172.700188 -405.314658) (xy 172.700188 -404.565358) (xy 172.699975 -404.558486)
			(xy 172.696381 -404.545223) (xy 172.693076 -404.539196) (xy 172.676756 -404.51083) (xy 172.651009 -404.450666)
			(xy 172.633579 -404.387588) (xy 172.624783 -404.32274) (xy 172.62478 -404.257298) (xy 172.633571 -404.192449)
			(xy 172.650996 -404.12937) (xy 172.676739 -404.069204) (xy 172.693076 -404.040848) (xy 172.696408 -404.034832)
			(xy 172.700003 -404.021562) (xy 172.700188 -404.014686) (xy 172.700188 -403.728682) (xy 172.70055 -403.718503)
			(xy 172.708351 -403.699698) (xy 172.722756 -403.685313) (xy 172.74157 -403.677537) (xy 172.75175 -403.67712)
			(xy 173.46803 -403.67712) (xy 173.478187 -403.677608) (xy 173.496954 -403.685389) (xy 173.511317 -403.699756)
			(xy 173.519094 -403.718524) (xy 173.519592 -403.728682) (xy 173.519592 -404.014686) (xy 173.51979 -404.021559)
			(xy 173.523394 -404.034822) (xy 173.526704 -404.040848) (xy 173.543059 -404.069194) (xy 173.568799 -404.129364)
			(xy 173.586221 -404.192446) (xy 173.595011 -404.257297) (xy 173.59501 -404.290022) (xy 177.023784 -404.290022)
			(xy 177.027775 -404.227855) (xy 177.039684 -404.166708) (xy 177.059313 -404.107587) (xy 177.086342 -404.051461)
			(xy 177.120326 -403.999252) (xy 177.160708 -403.951817) (xy 177.206824 -403.909936) (xy 177.257916 -403.874296)
			(xy 177.313147 -403.845482) (xy 177.371609 -403.823968) (xy 177.432343 -403.810106) (xy 177.49435 -403.804124)
			(xy 177.556613 -403.80612) (xy 177.61811 -403.816063) (xy 177.677831 -403.833787) (xy 177.734794 -403.859004)
			(xy 177.788065 -403.891297) (xy 177.83677 -403.930137) (xy 177.880107 -403.974887) (xy 177.917367 -404.024811)
			(xy 177.947936 -404.07909) (xy 177.971314 -404.136833) (xy 177.987115 -404.197091) (xy 177.995081 -404.258874)
			(xy 177.99558 -404.290022) (xy 177.995081 -404.32117) (xy 177.987115 -404.382953) (xy 177.971314 -404.443211)
			(xy 177.947936 -404.500954) (xy 177.917367 -404.555233) (xy 177.880107 -404.605157) (xy 177.83677 -404.649907)
			(xy 177.788065 -404.688747) (xy 177.734794 -404.72104) (xy 177.677831 -404.746257) (xy 177.61811 -404.763981)
			(xy 177.556613 -404.773924) (xy 177.49435 -404.77592) (xy 177.432343 -404.769938) (xy 177.371609 -404.756076)
			(xy 177.313147 -404.734562) (xy 177.257916 -404.705748) (xy 177.206824 -404.670108) (xy 177.160708 -404.628227)
			(xy 177.120326 -404.580792) (xy 177.086342 -404.528583) (xy 177.059313 -404.472457) (xy 177.039684 -404.413336)
			(xy 177.027775 -404.352189) (xy 177.023784 -404.290022) (xy 173.59501 -404.290022) (xy 173.595009 -404.322741)
			(xy 173.586214 -404.387591) (xy 173.568786 -404.450672) (xy 173.543041 -404.510839) (xy 173.526704 -404.539196)
			(xy 173.523391 -404.545221) (xy 173.519784 -404.558485) (xy 173.519592 -404.565358) (xy 173.519592 -405.314658)
			(xy 173.519801 -405.32153) (xy 173.523398 -405.334793) (xy 173.526704 -405.34082) (xy 173.543035 -405.369179)
			(xy 173.568777 -405.429346) (xy 173.586202 -405.492425) (xy 173.594995 -405.557274) (xy 173.594996 -405.622716)
			(xy 173.586205 -405.687565) (xy 173.56878 -405.750644) (xy 173.54304 -405.810811) (xy 173.526704 -405.839168)
			(xy 173.523401 -405.845198) (xy 173.519788 -405.858458) (xy 173.519592 -405.86533) (xy 173.519592 -406.151334)
			(xy 173.519095 -406.16149) (xy 173.511315 -406.180254) (xy 173.496951 -406.194617) (xy 173.478186 -406.202396)
			(xy 173.46803 -406.202896) (xy 172.75175 -406.202896) (xy 172.741586 -406.202396) (xy 172.722799 -406.194634)
			(xy 172.708413 -406.180272) (xy 172.70062 -406.161497) (xy 172.700188 -406.151334) (xy 172.700188 -405.86533)
			(xy 172.699986 -405.858458) (xy 172.696385 -405.845195) (xy 172.693076 -405.839168) (xy 172.676732 -405.810815)
			(xy 172.650987 -405.750648) (xy 172.63356 -405.687567) (xy 172.624767 -405.622717) (xy 171.336348 -405.622717)
			(xy 171.32681 -405.63927) (xy 171.323461 -405.645293) (xy 171.319715 -405.658547) (xy 171.319444 -405.665432)
			(xy 171.319444 -406.414732) (xy 171.319676 -406.421625) (xy 171.323405 -406.434897) (xy 171.32681 -406.440894)
			(xy 171.343122 -406.469265) (xy 171.368871 -406.529427) (xy 171.386302 -406.592505) (xy 171.3951 -406.657352)
			(xy 171.395103 -406.722793) (xy 171.395103 -406.722795) (xy 174.824907 -406.722795) (xy 174.824911 -406.65735)
			(xy 174.833708 -406.592499) (xy 174.851138 -406.529418) (xy 174.876885 -406.46925) (xy 174.893224 -406.440894)
			(xy 174.896543 -406.434871) (xy 174.900145 -406.421606) (xy 174.900336 -406.414732) (xy 174.900336 -405.665432)
			(xy 174.900127 -405.65856) (xy 174.89653 -405.645297) (xy 174.893224 -405.63927) (xy 174.876884 -405.610916)
			(xy 174.851141 -405.550748) (xy 174.833715 -405.487668) (xy 174.824923 -405.422818) (xy 174.824924 -405.357375)
			(xy 174.833717 -405.292525) (xy 174.851143 -405.229445) (xy 174.876887 -405.169278) (xy 174.893224 -405.140922)
			(xy 174.896533 -405.134894) (xy 174.900142 -405.121633) (xy 174.900336 -405.11476) (xy 174.900336 -404.828756)
			(xy 174.900686 -404.818594) (xy 174.908503 -404.799834) (xy 174.922922 -404.785511) (xy 174.941734 -404.77782)
			(xy 174.951898 -404.777448) (xy 175.668178 -404.777448) (xy 175.678304 -404.777945) (xy 175.697027 -404.785667)
			(xy 175.711384 -404.79995) (xy 175.719202 -404.818632) (xy 175.71974 -404.828756) (xy 175.71974 -405.11476)
			(xy 175.719942 -405.121633) (xy 175.723543 -405.134896) (xy 175.726852 -405.140922) (xy 175.743186 -405.16928)
			(xy 175.768931 -405.229446) (xy 175.786358 -405.292526) (xy 175.795152 -405.357375) (xy 175.795152 -405.422818)
			(xy 175.786359 -405.487667) (xy 175.768933 -405.550747) (xy 175.75214 -405.589994) (xy 177.023784 -405.589994)
			(xy 177.027775 -405.527827) (xy 177.039684 -405.46668) (xy 177.059313 -405.407559) (xy 177.086342 -405.351433)
			(xy 177.120326 -405.299224) (xy 177.160708 -405.251789) (xy 177.206824 -405.209908) (xy 177.257916 -405.174268)
			(xy 177.313147 -405.145454) (xy 177.371609 -405.12394) (xy 177.432343 -405.110078) (xy 177.49435 -405.104096)
			(xy 177.556613 -405.106092) (xy 177.61811 -405.116035) (xy 177.677831 -405.133759) (xy 177.734794 -405.158976)
			(xy 177.788065 -405.191269) (xy 177.83677 -405.230109) (xy 177.880107 -405.274859) (xy 177.917367 -405.324783)
			(xy 177.947936 -405.379062) (xy 177.952403 -405.390096) (xy 179.223932 -405.390096) (xy 179.227923 -405.327929)
			(xy 179.239832 -405.266782) (xy 179.259461 -405.207661) (xy 179.28649 -405.151535) (xy 179.320474 -405.099326)
			(xy 179.360856 -405.051891) (xy 179.406972 -405.01001) (xy 179.458064 -404.97437) (xy 179.513295 -404.945556)
			(xy 179.571757 -404.924042) (xy 179.632491 -404.91018) (xy 179.694498 -404.904198) (xy 179.756761 -404.906194)
			(xy 179.818258 -404.916137) (xy 179.877979 -404.933861) (xy 179.934942 -404.959078) (xy 179.988213 -404.991371)
			(xy 180.036918 -405.030211) (xy 180.080255 -405.074961) (xy 180.117515 -405.124885) (xy 180.148084 -405.179164)
			(xy 180.171462 -405.236907) (xy 180.187263 -405.297165) (xy 180.195229 -405.358948) (xy 180.195728 -405.390096)
			(xy 180.195229 -405.421244) (xy 180.187263 -405.483027) (xy 180.171462 -405.543285) (xy 180.148084 -405.601028)
			(xy 180.117515 -405.655307) (xy 180.080255 -405.705231) (xy 180.036918 -405.749981) (xy 179.988213 -405.788821)
			(xy 179.934942 -405.821114) (xy 179.877979 -405.846331) (xy 179.818258 -405.864055) (xy 179.756761 -405.873998)
			(xy 179.694498 -405.875994) (xy 179.632491 -405.870012) (xy 179.571757 -405.85615) (xy 179.513295 -405.834636)
			(xy 179.458064 -405.805822) (xy 179.406972 -405.770182) (xy 179.360856 -405.728301) (xy 179.320474 -405.680866)
			(xy 179.28649 -405.628657) (xy 179.259461 -405.572531) (xy 179.239832 -405.51341) (xy 179.227923 -405.452263)
			(xy 179.223932 -405.390096) (xy 177.952403 -405.390096) (xy 177.971314 -405.436805) (xy 177.987115 -405.497063)
			(xy 177.995081 -405.558846) (xy 177.99558 -405.589994) (xy 177.995081 -405.621142) (xy 177.987115 -405.682925)
			(xy 177.971314 -405.743183) (xy 177.947936 -405.800926) (xy 177.917367 -405.855205) (xy 177.880107 -405.905129)
			(xy 177.83677 -405.949879) (xy 177.788065 -405.988719) (xy 177.734794 -406.021012) (xy 177.677831 -406.046229)
			(xy 177.61811 -406.063953) (xy 177.556613 -406.073896) (xy 177.49435 -406.075892) (xy 177.432343 -406.06991)
			(xy 177.371609 -406.056048) (xy 177.313147 -406.034534) (xy 177.257916 -406.00572) (xy 177.206824 -405.97008)
			(xy 177.160708 -405.928199) (xy 177.120326 -405.880764) (xy 177.086342 -405.828555) (xy 177.059313 -405.772429)
			(xy 177.039684 -405.713308) (xy 177.027775 -405.652161) (xy 177.023784 -405.589994) (xy 175.75214 -405.589994)
			(xy 175.743189 -405.610914) (xy 175.726852 -405.63927) (xy 175.723552 -405.645302) (xy 175.719936 -405.65856)
			(xy 175.71974 -405.665432) (xy 175.71974 -406.414732) (xy 175.719915 -406.421607) (xy 175.723534 -406.434869)
			(xy 175.726852 -406.440894) (xy 175.743163 -406.469265) (xy 175.768909 -406.529428) (xy 175.786339 -406.592505)
			(xy 175.795136 -406.657352) (xy 175.795137 -406.690068) (xy 179.223932 -406.690068) (xy 179.227923 -406.627901)
			(xy 179.239832 -406.566754) (xy 179.259461 -406.507633) (xy 179.28649 -406.451507) (xy 179.320474 -406.399298)
			(xy 179.360856 -406.351863) (xy 179.406972 -406.309982) (xy 179.458064 -406.274342) (xy 179.513295 -406.245528)
			(xy 179.571757 -406.224014) (xy 179.632491 -406.210152) (xy 179.694498 -406.20417) (xy 179.756761 -406.206166)
			(xy 179.818258 -406.216109) (xy 179.877979 -406.233833) (xy 179.934942 -406.25905) (xy 179.988213 -406.291343)
			(xy 180.036918 -406.330183) (xy 180.080255 -406.374933) (xy 180.117515 -406.424857) (xy 180.148084 -406.479136)
			(xy 180.171462 -406.536879) (xy 180.187263 -406.597137) (xy 180.195229 -406.65892) (xy 180.195728 -406.690068)
			(xy 180.195229 -406.721216) (xy 180.187263 -406.782999) (xy 180.171462 -406.843257) (xy 180.148084 -406.901)
			(xy 180.117515 -406.955279) (xy 180.080255 -407.005203) (xy 180.036918 -407.049953) (xy 179.988213 -407.088793)
			(xy 179.934942 -407.121086) (xy 179.877979 -407.146303) (xy 179.818258 -407.164027) (xy 179.756761 -407.17397)
			(xy 179.694498 -407.175966) (xy 179.632491 -407.169984) (xy 179.571757 -407.156122) (xy 179.513295 -407.134608)
			(xy 179.458064 -407.105794) (xy 179.406972 -407.070154) (xy 179.360856 -407.028273) (xy 179.320474 -406.980838)
			(xy 179.28649 -406.928629) (xy 179.259461 -406.872503) (xy 179.239832 -406.813382) (xy 179.227923 -406.752235)
			(xy 179.223932 -406.690068) (xy 175.795137 -406.690068) (xy 175.795139 -406.722793) (xy 175.78635 -406.787641)
			(xy 175.768928 -406.85072) (xy 175.743188 -406.910886) (xy 175.726852 -406.939242) (xy 175.723526 -406.945261)
			(xy 175.719927 -406.958529) (xy 175.71974 -406.965404) (xy 175.71974 -407.251408) (xy 175.719286 -407.261558)
			(xy 175.711495 -407.280302) (xy 175.697109 -407.294624) (xy 175.678329 -407.302331) (xy 175.668178 -407.302716)
			(xy 174.951898 -407.302716) (xy 174.941766 -407.302274) (xy 174.923036 -407.294537) (xy 174.908679 -407.280237)
			(xy 174.900867 -407.261538) (xy 174.900336 -407.251408) (xy 174.900336 -406.965404) (xy 174.900138 -406.958531)
			(xy 174.896533 -406.945269) (xy 174.893224 -406.939242) (xy 174.87686 -406.910901) (xy 174.851119 -406.85073)
			(xy 174.833696 -406.787647) (xy 174.824907 -406.722795) (xy 171.395103 -406.722795) (xy 171.386313 -406.787642)
			(xy 171.368889 -406.850721) (xy 171.343147 -406.910886) (xy 171.32681 -406.939242) (xy 171.323436 -406.945252)
			(xy 171.319706 -406.958516) (xy 171.319444 -406.965404) (xy 171.319444 -407.251408) (xy 171.318922 -407.261512)
			(xy 171.31119 -407.280182) (xy 171.296905 -407.294475) (xy 171.278239 -407.302217) (xy 171.268136 -407.302716)
			(xy 170.551856 -407.302716) (xy 170.541746 -407.302251) (xy 170.52307 -407.294502) (xy 170.508778 -407.280199)
			(xy 170.501042 -407.261518) (xy 170.500548 -407.251408) (xy 170.500548 -406.965404) (xy 170.500342 -406.958509)
			(xy 170.496595 -406.945237) (xy 170.493182 -406.939242) (xy 170.476816 -406.910901) (xy 170.451073 -406.850731)
			(xy 170.433648 -406.787648) (xy 170.424857 -406.722795) (xy 166.995053 -406.722795) (xy 166.986264 -406.787641)
			(xy 166.968842 -406.85072) (xy 166.943103 -406.910886) (xy 166.926768 -406.939242) (xy 166.923436 -406.945258)
			(xy 166.919842 -406.958529) (xy 166.919656 -406.965404) (xy 166.919656 -407.251408) (xy 166.919186 -407.261556)
			(xy 166.911398 -407.280297) (xy 166.897017 -407.294618) (xy 166.878243 -407.302328) (xy 166.868094 -407.302716)
			(xy 166.151814 -407.302716) (xy 166.141683 -407.302261) (xy 166.122954 -407.294529) (xy 166.108595 -407.280233)
			(xy 166.100783 -407.261537) (xy 166.100252 -407.251408) (xy 166.100252 -406.965404) (xy 166.100064 -406.95853)
			(xy 166.096454 -406.945267) (xy 166.09314 -406.939242) (xy 166.076775 -406.910901) (xy 166.051034 -406.850731)
			(xy 166.033611 -406.787647) (xy 166.024821 -406.722795) (xy 162.595017 -406.722795) (xy 162.586227 -406.787641)
			(xy 162.568804 -406.85072) (xy 162.543062 -406.910886) (xy 162.526726 -406.939242) (xy 162.523345 -406.945249)
			(xy 162.51962 -406.958516) (xy 162.51936 -406.965404) (xy 162.51936 -407.251408) (xy 162.518989 -407.261536)
			(xy 162.511231 -407.280247) (xy 162.4969 -407.294563) (xy 162.47818 -407.3023) (xy 162.468052 -407.302716)
			(xy 161.751772 -407.302716) (xy 161.741663 -407.302238) (xy 161.722988 -407.294494) (xy 161.708694 -407.280196)
			(xy 161.700958 -407.261517) (xy 161.700464 -407.251408) (xy 161.700464 -406.965404) (xy 161.700234 -406.958512)
			(xy 161.69649 -406.945246) (xy 161.693098 -406.939242) (xy 161.676735 -406.9109) (xy 161.650996 -406.85073)
			(xy 161.633574 -406.787647) (xy 161.624785 -406.722795) (xy 154.72791 -406.722795) (xy 154.72791 -409.522892)
			(xy 159.424888 -409.522892) (xy 159.424892 -409.457447) (xy 159.433689 -409.392596) (xy 159.451118 -409.329514)
			(xy 159.476865 -409.269347) (xy 159.493204 -409.24099) (xy 159.496523 -409.234967) (xy 159.500126 -409.221702)
			(xy 159.500316 -409.214828) (xy 159.500316 -408.465528) (xy 159.500112 -408.458656) (xy 159.496512 -408.445393)
			(xy 159.493204 -408.439366) (xy 159.476861 -408.411013) (xy 159.45112 -408.350845) (xy 159.433695 -408.287765)
			(xy 159.424904 -408.222915) (xy 159.424905 -408.157472) (xy 159.433698 -408.092622) (xy 159.451124 -408.029542)
			(xy 159.476867 -407.969375) (xy 159.493204 -407.941018) (xy 159.496513 -407.93499) (xy 159.500122 -407.921729)
			(xy 159.500316 -407.914856) (xy 159.500316 -407.628852) (xy 159.500683 -407.618693) (xy 159.508497 -407.599936)
			(xy 159.522911 -407.585614) (xy 159.541716 -407.577919) (xy 159.551878 -407.577544) (xy 160.268158 -407.577544)
			(xy 160.278283 -407.578061) (xy 160.297003 -407.585776) (xy 160.311361 -407.600053) (xy 160.319181 -407.61873)
			(xy 160.31972 -407.628852) (xy 160.31972 -407.914856) (xy 160.319926 -407.921728) (xy 160.323525 -407.934991)
			(xy 160.326832 -407.941018) (xy 160.343163 -407.969378) (xy 160.36891 -408.029543) (xy 160.386338 -408.092623)
			(xy 160.395132 -408.157472) (xy 160.395133 -408.222915) (xy 160.386341 -408.287764) (xy 160.368914 -408.350844)
			(xy 160.34317 -408.41101) (xy 160.326832 -408.439366) (xy 160.323532 -408.445398) (xy 160.319917 -408.458656)
			(xy 160.31972 -408.465528) (xy 160.31972 -409.214828) (xy 160.319899 -409.221702) (xy 160.323516 -409.234965)
			(xy 160.326832 -409.24099) (xy 160.34314 -409.269363) (xy 160.368888 -409.329525) (xy 160.386319 -409.392602)
			(xy 160.395116 -409.457449) (xy 160.39512 -409.52289) (xy 160.386331 -409.587737) (xy 160.368908 -409.650816)
			(xy 160.343168 -409.710982) (xy 160.326832 -409.739338) (xy 160.323506 -409.745357) (xy 160.319907 -409.758625)
			(xy 160.31972 -409.7655) (xy 160.31972 -410.051504) (xy 160.319282 -410.061656) (xy 160.311489 -410.080404)
			(xy 160.297098 -410.094727) (xy 160.278312 -410.10243) (xy 160.268158 -410.102812) (xy 159.551878 -410.102812)
			(xy 159.541756 -410.102293) (xy 159.523044 -410.094568) (xy 159.508691 -410.080292) (xy 159.500863 -410.061623)
			(xy 159.500316 -410.051504) (xy 159.500316 -409.7655) (xy 159.500122 -409.758627) (xy 159.496515 -409.745364)
			(xy 159.493204 -409.739338) (xy 159.476837 -409.710998) (xy 159.451098 -409.650827) (xy 159.433676 -409.587744)
			(xy 159.424888 -409.522892) (xy 154.72791 -409.522892) (xy 154.72791 -410.622708) (xy 161.624794 -410.622708)
			(xy 161.624796 -410.557265) (xy 161.63359 -410.492415) (xy 161.651017 -410.429334) (xy 161.676761 -410.369167)
			(xy 161.693098 -410.34081) (xy 161.696455 -410.334791) (xy 161.700196 -410.321534) (xy 161.700464 -410.314648)
			(xy 161.700464 -409.565348) (xy 161.700239 -409.558455) (xy 161.696505 -409.545183) (xy 161.693098 -409.539186)
			(xy 161.676772 -409.510824) (xy 161.651029 -409.450658) (xy 161.633603 -409.387579) (xy 161.62481 -409.322731)
			(xy 161.624809 -409.257289) (xy 161.633599 -409.192441) (xy 161.651023 -409.129361) (xy 161.676763 -409.069195)
			(xy 161.693098 -409.040838) (xy 161.69648 -409.034832) (xy 161.700205 -409.021565) (xy 161.700464 -409.014676)
			(xy 161.700464 -408.728672) (xy 161.700961 -408.718566) (xy 161.708701 -408.699894) (xy 161.722994 -408.685601)
			(xy 161.741666 -408.677861) (xy 161.751772 -408.677364) (xy 162.468052 -408.677364) (xy 162.478167 -408.677854)
			(xy 162.496863 -408.68558) (xy 162.511177 -408.699874) (xy 162.518931 -408.718558) (xy 162.51936 -408.728672)
			(xy 162.51936 -409.014676) (xy 162.519573 -409.02157) (xy 162.523315 -409.034842) (xy 162.526726 -409.040838)
			(xy 162.543075 -409.069188) (xy 162.568819 -409.129356) (xy 162.586246 -409.192437) (xy 162.595038 -409.257288)
			(xy 162.595037 -409.322732) (xy 162.586242 -409.387583) (xy 162.568813 -409.450664) (xy 162.543065 -409.51083)
			(xy 162.536115 -409.522892) (xy 163.824924 -409.522892) (xy 163.824928 -409.457446) (xy 163.833726 -409.392595)
			(xy 163.851157 -409.329513) (xy 163.876906 -409.269346) (xy 163.893246 -409.24099) (xy 163.896613 -409.234976)
			(xy 163.900347 -409.221715) (xy 163.900612 -409.214828) (xy 163.900612 -408.465528) (xy 163.900401 -408.458633)
			(xy 163.896658 -408.445361) (xy 163.893246 -408.439366) (xy 163.876902 -408.411014) (xy 163.851158 -408.350846)
			(xy 163.833732 -408.287765) (xy 163.82494 -408.222915) (xy 163.824941 -408.157471) (xy 163.833735 -408.092621)
			(xy 163.851163 -408.029541) (xy 163.876908 -407.969374) (xy 163.893246 -407.941018) (xy 163.896603 -407.935)
			(xy 163.900343 -407.921742) (xy 163.900612 -407.914856) (xy 163.900612 -407.628852) (xy 163.901046 -407.618739)
			(xy 163.908802 -407.600057) (xy 163.923114 -407.585764) (xy 163.941806 -407.578033) (xy 163.95192 -407.577544)
			(xy 164.6682 -407.577544) (xy 164.678302 -407.578084) (xy 164.696969 -407.585811) (xy 164.711262 -407.60009)
			(xy 164.719007 -407.618751) (xy 164.719508 -407.628852) (xy 164.719508 -407.914856) (xy 164.719757 -407.921746)
			(xy 164.723488 -407.935012) (xy 164.726874 -407.941018) (xy 164.743204 -407.969378) (xy 164.768948 -408.029544)
			(xy 164.786375 -408.092623) (xy 164.795168 -408.157472) (xy 164.795169 -408.222914) (xy 164.786377 -408.287763)
			(xy 164.768953 -408.350843) (xy 164.74321 -408.41101) (xy 164.726874 -408.439366) (xy 164.723524 -408.445388)
			(xy 164.719779 -408.458643) (xy 164.719508 -408.465528) (xy 164.719508 -409.214828) (xy 164.719768 -409.221717)
			(xy 164.723492 -409.234983) (xy 164.726874 -409.24099) (xy 164.74318 -409.269363) (xy 164.768927 -409.329526)
			(xy 164.786356 -409.392603) (xy 164.795152 -409.457449) (xy 164.795156 -409.522889) (xy 164.786368 -409.587737)
			(xy 164.768947 -409.650816) (xy 164.743209 -409.710982) (xy 164.726874 -409.739338) (xy 164.723498 -409.745347)
			(xy 164.71977 -409.758612) (xy 164.719508 -409.7655) (xy 164.719508 -410.051504) (xy 164.719018 -410.061612)
			(xy 164.711281 -410.080289) (xy 164.696985 -410.094583) (xy 164.678308 -410.102319) (xy 164.6682 -410.102812)
			(xy 163.95192 -410.102812) (xy 163.9418 -410.102368) (xy 163.923099 -410.094629) (xy 163.908785 -410.080321)
			(xy 163.901037 -410.061624) (xy 163.900612 -410.051504) (xy 163.900612 -409.7655) (xy 163.900412 -409.758604)
			(xy 163.896662 -409.745332) (xy 163.893246 -409.739338) (xy 163.876878 -409.710999) (xy 163.851136 -409.650828)
			(xy 163.833713 -409.587745) (xy 163.824924 -409.522892) (xy 162.536115 -409.522892) (xy 162.526726 -409.539186)
			(xy 162.523365 -409.545202) (xy 162.519628 -409.558462) (xy 162.51936 -409.565348) (xy 162.51936 -410.314648)
			(xy 162.519583 -410.321542) (xy 162.523318 -410.334814) (xy 162.526726 -410.34081) (xy 162.543051 -410.369173)
			(xy 162.568798 -410.429338) (xy 162.586227 -410.492417) (xy 162.595022 -410.557265) (xy 162.595024 -410.622707)
			(xy 162.595024 -410.622708) (xy 166.02483 -410.622708) (xy 166.024832 -410.557264) (xy 166.033627 -410.492414)
			(xy 166.051055 -410.429333) (xy 166.076802 -410.369166) (xy 166.09314 -410.34081) (xy 166.096446 -410.334781)
			(xy 166.100058 -410.321521) (xy 166.100252 -410.314648) (xy 166.100252 -409.565348) (xy 166.100048 -409.558476)
			(xy 166.096449 -409.545213) (xy 166.09314 -409.539186) (xy 166.076813 -409.510824) (xy 166.051068 -409.450659)
			(xy 166.03364 -409.38758) (xy 166.024846 -409.322731) (xy 166.024845 -409.257289) (xy 166.033636 -409.19244)
			(xy 166.051061 -409.129361) (xy 166.076803 -409.069194) (xy 166.09314 -409.040838) (xy 166.096437 -409.034804)
			(xy 166.100054 -409.021548) (xy 166.100252 -409.014676) (xy 166.100252 -408.728672) (xy 166.100698 -408.718522)
			(xy 166.108493 -408.699778) (xy 166.122882 -408.685458) (xy 166.141662 -408.67775) (xy 166.151814 -408.677364)
			(xy 166.868094 -408.677364) (xy 166.878223 -408.677832) (xy 166.896949 -408.685562) (xy 166.911306 -408.699855)
			(xy 166.919121 -408.718545) (xy 166.919656 -408.728672) (xy 166.919656 -409.014676) (xy 166.91985 -409.021549)
			(xy 166.923456 -409.034812) (xy 166.926768 -409.040838) (xy 166.943115 -409.069189) (xy 166.968858 -409.129357)
			(xy 166.986283 -409.192438) (xy 166.995075 -409.257288) (xy 166.995073 -409.322732) (xy 166.986279 -409.387582)
			(xy 166.968851 -409.450663) (xy 166.943106 -409.51083) (xy 166.936156 -409.522892) (xy 168.22496 -409.522892)
			(xy 168.224964 -409.457446) (xy 168.233762 -409.392594) (xy 168.251195 -409.329513) (xy 168.276947 -409.269346)
			(xy 168.293288 -409.24099) (xy 168.296605 -409.234967) (xy 168.30021 -409.221702) (xy 168.3004 -409.214828)
			(xy 168.3004 -408.465528) (xy 168.300197 -408.458656) (xy 168.296596 -408.445393) (xy 168.293288 -408.439366)
			(xy 168.276942 -408.411014) (xy 168.251196 -408.350847) (xy 168.233769 -408.287766) (xy 168.224976 -408.222915)
			(xy 168.224977 -408.157471) (xy 168.233772 -408.092621) (xy 168.251201 -408.02954) (xy 168.276949 -407.969374)
			(xy 168.293288 -407.941018) (xy 168.296595 -407.93499) (xy 168.300206 -407.921729) (xy 168.3004 -407.914856)
			(xy 168.3004 -407.628852) (xy 168.300782 -407.618695) (xy 168.308594 -407.599941) (xy 168.323002 -407.58562)
			(xy 168.341802 -407.577922) (xy 168.351962 -407.577544) (xy 169.068242 -407.577544) (xy 169.078372 -407.577992)
			(xy 169.097095 -407.585735) (xy 169.11145 -407.600032) (xy 169.119267 -407.618724) (xy 169.119804 -407.628852)
			(xy 169.119804 -407.914856) (xy 169.120012 -407.921728) (xy 169.123609 -407.934991) (xy 169.126916 -407.941018)
			(xy 169.143248 -407.969377) (xy 169.168995 -408.029543) (xy 169.186424 -408.092622) (xy 169.195218 -408.157472)
			(xy 169.195219 -408.222915) (xy 169.186426 -408.287764) (xy 169.168999 -408.350844) (xy 169.143254 -408.41101)
			(xy 169.126916 -408.439366) (xy 169.123614 -408.445397) (xy 169.12 -408.458656) (xy 169.119804 -408.465528)
			(xy 169.119804 -409.214828) (xy 169.119985 -409.221702) (xy 169.1236 -409.234965) (xy 169.126916 -409.24099)
			(xy 169.143224 -409.269363) (xy 169.168973 -409.329525) (xy 169.186405 -409.392602) (xy 169.195202 -409.457449)
			(xy 169.195207 -409.52289) (xy 169.186417 -409.587738) (xy 169.168994 -409.650817) (xy 169.143252 -409.710982)
			(xy 169.126916 -409.739338) (xy 169.123589 -409.745357) (xy 169.119991 -409.758625) (xy 169.119804 -409.7655)
			(xy 169.119804 -410.051504) (xy 169.119382 -410.061658) (xy 169.111586 -410.08041) (xy 169.097189 -410.094733)
			(xy 169.078398 -410.102433) (xy 169.068242 -410.102812) (xy 168.351962 -410.102812) (xy 168.341839 -410.102306)
			(xy 168.323127 -410.094575) (xy 168.308774 -410.080296) (xy 168.300947 -410.061624) (xy 168.3004 -410.051504)
			(xy 168.3004 -409.7655) (xy 168.300208 -409.758627) (xy 168.2966 -409.745364) (xy 168.293288 -409.739338)
			(xy 168.276919 -409.710999) (xy 168.251175 -409.650829) (xy 168.23375 -409.587745) (xy 168.22496 -409.522892)
			(xy 166.936156 -409.522892) (xy 166.926768 -409.539186) (xy 166.923456 -409.545212) (xy 166.919849 -409.558475)
			(xy 166.919656 -409.565348) (xy 166.919656 -410.314648) (xy 166.919861 -410.32152) (xy 166.923459 -410.334783)
			(xy 166.926768 -410.34081) (xy 166.943092 -410.369174) (xy 166.968836 -410.429339) (xy 166.986264 -410.492417)
			(xy 166.995059 -410.557265) (xy 166.99506 -410.622707) (xy 166.99506 -410.622709) (xy 170.424866 -410.622709)
			(xy 170.424868 -410.557264) (xy 170.433664 -410.492413) (xy 170.451094 -410.429332) (xy 170.476842 -410.369166)
			(xy 170.493182 -410.34081) (xy 170.496537 -410.33479) (xy 170.50028 -410.321534) (xy 170.500548 -410.314648)
			(xy 170.500548 -409.565348) (xy 170.500325 -409.558454) (xy 170.49659 -409.545182) (xy 170.493182 -409.539186)
			(xy 170.476853 -409.510825) (xy 170.451106 -409.45066) (xy 170.433677 -409.387581) (xy 170.424882 -409.322732)
			(xy 170.424881 -409.257289) (xy 170.433673 -409.19244) (xy 170.4511 -409.12936) (xy 170.476844 -409.069194)
			(xy 170.493182 -409.040838) (xy 170.496563 -409.034831) (xy 170.500289 -409.021565) (xy 170.500548 -409.014676)
			(xy 170.500548 -408.728672) (xy 170.501061 -408.718568) (xy 170.508798 -408.699899) (xy 170.523086 -408.685607)
			(xy 170.541752 -408.677864) (xy 170.551856 -408.677364) (xy 171.268136 -408.677364) (xy 171.278243 -408.677855)
			(xy 171.296915 -408.685598) (xy 171.311207 -408.699892) (xy 171.318947 -408.718565) (xy 171.319444 -408.728672)
			(xy 171.319444 -409.014676) (xy 171.319659 -409.02157) (xy 171.3234 -409.034842) (xy 171.32681 -409.040838)
			(xy 171.343159 -409.069188) (xy 171.368905 -409.129356) (xy 171.386332 -409.192437) (xy 171.395125 -409.257288)
			(xy 171.395123 -409.322732) (xy 171.386328 -409.387583) (xy 171.368898 -409.450664) (xy 171.34315 -409.51083)
			(xy 171.336199 -409.522892) (xy 172.62475 -409.522892) (xy 172.624754 -409.457446) (xy 172.633552 -409.392594)
			(xy 172.650984 -409.329513) (xy 172.676735 -409.269346) (xy 172.693076 -409.24099) (xy 172.696393 -409.234966)
			(xy 172.699998 -409.221702) (xy 172.700188 -409.214828) (xy 172.700188 -408.465528) (xy 172.699987 -408.458655)
			(xy 172.696385 -408.445393) (xy 172.693076 -408.439366) (xy 172.676731 -408.411014) (xy 172.650985 -408.350847)
			(xy 172.633558 -408.287766) (xy 172.624766 -408.222915) (xy 172.624767 -408.157471) (xy 172.633561 -408.092621)
			(xy 172.65099 -408.02954) (xy 172.676737 -407.969374) (xy 172.693076 -407.941018) (xy 172.696383 -407.934989)
			(xy 172.699994 -407.921729) (xy 172.700188 -407.914856) (xy 172.700188 -407.628852) (xy 172.700582 -407.618696)
			(xy 172.708391 -407.599945) (xy 172.722796 -407.585624) (xy 172.741592 -407.577924) (xy 172.75175 -407.577544)
			(xy 173.46803 -407.577544) (xy 173.478159 -407.578002) (xy 173.496882 -407.58574) (xy 173.511237 -407.600035)
			(xy 173.519055 -407.618725) (xy 173.519592 -407.628852) (xy 173.519592 -407.914856) (xy 173.519802 -407.921728)
			(xy 173.523398 -407.934991) (xy 173.526704 -407.941018) (xy 173.543033 -407.969378) (xy 173.568776 -408.029545)
			(xy 173.586201 -408.092624) (xy 173.594994 -408.157472) (xy 173.594994 -408.190192) (xy 177.023784 -408.190192)
			(xy 177.027775 -408.128025) (xy 177.039684 -408.066878) (xy 177.059313 -408.007757) (xy 177.086342 -407.951631)
			(xy 177.120326 -407.899422) (xy 177.160708 -407.851987) (xy 177.206824 -407.810106) (xy 177.257916 -407.774466)
			(xy 177.313147 -407.745652) (xy 177.371609 -407.724138) (xy 177.432343 -407.710276) (xy 177.49435 -407.704294)
			(xy 177.556613 -407.70629) (xy 177.61811 -407.716233) (xy 177.677831 -407.733957) (xy 177.734794 -407.759174)
			(xy 177.788065 -407.791467) (xy 177.83677 -407.830307) (xy 177.880107 -407.875057) (xy 177.917367 -407.924981)
			(xy 177.947936 -407.97926) (xy 177.971314 -408.037003) (xy 177.987115 -408.097261) (xy 177.995081 -408.159044)
			(xy 177.99558 -408.190192) (xy 177.995081 -408.22134) (xy 177.987115 -408.283123) (xy 177.971314 -408.343381)
			(xy 177.947936 -408.401124) (xy 177.917367 -408.455403) (xy 177.880107 -408.505327) (xy 177.83677 -408.550077)
			(xy 177.788065 -408.588917) (xy 177.734794 -408.62121) (xy 177.677831 -408.646427) (xy 177.61811 -408.664151)
			(xy 177.556613 -408.674094) (xy 177.49435 -408.67609) (xy 177.432343 -408.670108) (xy 177.371609 -408.656246)
			(xy 177.313147 -408.634732) (xy 177.257916 -408.605918) (xy 177.206824 -408.570278) (xy 177.160708 -408.528397)
			(xy 177.120326 -408.480962) (xy 177.086342 -408.428753) (xy 177.059313 -408.372627) (xy 177.039684 -408.313506)
			(xy 177.027775 -408.252359) (xy 177.023784 -408.190192) (xy 173.594994 -408.190192) (xy 173.594995 -408.222914)
			(xy 173.586204 -408.287763) (xy 173.56878 -408.350842) (xy 173.543039 -408.411009) (xy 173.526704 -408.439366)
			(xy 173.523402 -408.445397) (xy 173.519788 -408.458656) (xy 173.519592 -408.465528) (xy 173.519592 -409.214828)
			(xy 173.519774 -409.221702) (xy 173.523389 -409.234965) (xy 173.526704 -409.24099) (xy 173.54301 -409.269363)
			(xy 173.568754 -409.329527) (xy 173.586182 -409.392603) (xy 173.594978 -409.457449) (xy 173.594982 -409.522889)
			(xy 173.586195 -409.587736) (xy 173.568774 -409.650815) (xy 173.543038 -409.710981) (xy 173.526704 -409.739338)
			(xy 173.523376 -409.745356) (xy 173.519779 -409.758625) (xy 173.519592 -409.7655) (xy 173.519592 -410.051504)
			(xy 173.519181 -410.061659) (xy 173.511383 -410.080413) (xy 173.496983 -410.094737) (xy 173.478187 -410.102435)
			(xy 173.46803 -410.102812) (xy 172.75175 -410.102812) (xy 172.741633 -410.102234) (xy 172.722923 -410.094532)
			(xy 172.708567 -410.080274) (xy 172.700736 -410.061618) (xy 172.700188 -410.051504) (xy 172.700188 -409.7655)
			(xy 172.699997 -409.758627) (xy 172.696388 -409.745364) (xy 172.693076 -409.739338) (xy 172.676707 -409.710999)
			(xy 172.650964 -409.650829) (xy 172.63354 -409.587745) (xy 172.62475 -409.522892) (xy 171.336199 -409.522892)
			(xy 171.32681 -409.539186) (xy 171.323455 -409.545206) (xy 171.319713 -409.558462) (xy 171.319444 -409.565348)
			(xy 171.319444 -410.314648) (xy 171.319669 -410.321541) (xy 171.323403 -410.334813) (xy 171.32681 -410.34081)
			(xy 171.343135 -410.369173) (xy 171.368883 -410.429338) (xy 171.386313 -410.492416) (xy 171.395109 -410.557265)
			(xy 171.39511 -410.622708) (xy 174.824916 -410.622708) (xy 174.824918 -410.557264) (xy 174.833713 -410.492414)
			(xy 174.851141 -410.429333) (xy 174.876886 -410.369166) (xy 174.893224 -410.34081) (xy 174.896537 -410.334785)
			(xy 174.900143 -410.321521) (xy 174.900336 -410.314648) (xy 174.900336 -409.565348) (xy 174.900121 -409.558476)
			(xy 174.896528 -409.545214) (xy 174.893224 -409.539186) (xy 174.876897 -409.510824) (xy 174.851153 -409.450659)
			(xy 174.833726 -409.38758) (xy 174.824932 -409.322731) (xy 174.824931 -409.257289) (xy 174.833722 -409.192441)
			(xy 174.851146 -409.129361) (xy 174.876888 -409.069194) (xy 174.893224 -409.040838) (xy 174.896527 -409.034808)
			(xy 174.90014 -409.021548) (xy 174.900336 -409.014676) (xy 174.900336 -408.728672) (xy 174.900699 -408.718512)
			(xy 174.908511 -408.699752) (xy 174.922926 -408.685428) (xy 174.941735 -408.677736) (xy 174.951898 -408.677364)
			(xy 175.668178 -408.677364) (xy 175.678306 -408.677845) (xy 175.697032 -408.68557) (xy 175.711389 -408.699859)
			(xy 175.719205 -408.718546) (xy 175.71974 -408.728672) (xy 175.71974 -409.014676) (xy 175.719936 -409.021549)
			(xy 175.723541 -409.034812) (xy 175.726852 -409.040838) (xy 175.7432 -409.069188) (xy 175.768943 -409.129356)
			(xy 175.786369 -409.192438) (xy 175.795161 -409.257288) (xy 175.795159 -409.322732) (xy 175.786365 -409.387583)
			(xy 175.768936 -409.450663) (xy 175.752033 -409.490164) (xy 177.023784 -409.490164) (xy 177.027775 -409.427997)
			(xy 177.039684 -409.36685) (xy 177.059313 -409.307729) (xy 177.086342 -409.251603) (xy 177.120326 -409.199394)
			(xy 177.160708 -409.151959) (xy 177.206824 -409.110078) (xy 177.257916 -409.074438) (xy 177.313147 -409.045624)
			(xy 177.371609 -409.02411) (xy 177.432343 -409.010248) (xy 177.49435 -409.004266) (xy 177.556613 -409.006262)
			(xy 177.61811 -409.016205) (xy 177.677831 -409.033929) (xy 177.734794 -409.059146) (xy 177.788065 -409.091439)
			(xy 177.83677 -409.130279) (xy 177.880107 -409.175029) (xy 177.917367 -409.224953) (xy 177.947936 -409.279232)
			(xy 177.9523 -409.290012) (xy 179.223932 -409.290012) (xy 179.227923 -409.227845) (xy 179.239832 -409.166698)
			(xy 179.259461 -409.107577) (xy 179.28649 -409.051451) (xy 179.320474 -408.999242) (xy 179.360856 -408.951807)
			(xy 179.406972 -408.909926) (xy 179.458064 -408.874286) (xy 179.513295 -408.845472) (xy 179.571757 -408.823958)
			(xy 179.632491 -408.810096) (xy 179.694498 -408.804114) (xy 179.756761 -408.80611) (xy 179.818258 -408.816053)
			(xy 179.877979 -408.833777) (xy 179.934942 -408.858994) (xy 179.988213 -408.891287) (xy 180.036918 -408.930127)
			(xy 180.080255 -408.974877) (xy 180.117515 -409.024801) (xy 180.148084 -409.07908) (xy 180.171462 -409.136823)
			(xy 180.187263 -409.197081) (xy 180.195229 -409.258864) (xy 180.195728 -409.290012) (xy 180.195229 -409.32116)
			(xy 180.187263 -409.382943) (xy 180.171462 -409.443201) (xy 180.148084 -409.500944) (xy 180.117515 -409.555223)
			(xy 180.080255 -409.605147) (xy 180.036918 -409.649897) (xy 179.988213 -409.688737) (xy 179.934942 -409.72103)
			(xy 179.877979 -409.746247) (xy 179.818258 -409.763971) (xy 179.756761 -409.773914) (xy 179.694498 -409.77591)
			(xy 179.632491 -409.769928) (xy 179.571757 -409.756066) (xy 179.513295 -409.734552) (xy 179.458064 -409.705738)
			(xy 179.406972 -409.670098) (xy 179.360856 -409.628217) (xy 179.320474 -409.580782) (xy 179.28649 -409.528573)
			(xy 179.259461 -409.472447) (xy 179.239832 -409.413326) (xy 179.227923 -409.352179) (xy 179.223932 -409.290012)
			(xy 177.9523 -409.290012) (xy 177.971314 -409.336975) (xy 177.987115 -409.397233) (xy 177.995081 -409.459016)
			(xy 177.99558 -409.490164) (xy 177.995081 -409.521312) (xy 177.987115 -409.583095) (xy 177.971314 -409.643353)
			(xy 177.947936 -409.701096) (xy 177.917367 -409.755375) (xy 177.880107 -409.805299) (xy 177.83677 -409.850049)
			(xy 177.788065 -409.888889) (xy 177.734794 -409.921182) (xy 177.677831 -409.946399) (xy 177.61811 -409.964123)
			(xy 177.556613 -409.974066) (xy 177.49435 -409.976062) (xy 177.432343 -409.97008) (xy 177.371609 -409.956218)
			(xy 177.313147 -409.934704) (xy 177.257916 -409.90589) (xy 177.206824 -409.87025) (xy 177.160708 -409.828369)
			(xy 177.120326 -409.780934) (xy 177.086342 -409.728725) (xy 177.059313 -409.672599) (xy 177.039684 -409.613478)
			(xy 177.027775 -409.552331) (xy 177.023784 -409.490164) (xy 175.752033 -409.490164) (xy 175.74319 -409.51083)
			(xy 175.726852 -409.539186) (xy 175.723546 -409.545215) (xy 175.719934 -409.558475) (xy 175.71974 -409.565348)
			(xy 175.71974 -410.314648) (xy 175.719947 -410.32152) (xy 175.723544 -410.334783) (xy 175.726852 -410.34081)
			(xy 175.743176 -410.369174) (xy 175.768922 -410.429338) (xy 175.78635 -410.492417) (xy 175.795145 -410.557265)
			(xy 175.795146 -410.589984) (xy 179.223932 -410.589984) (xy 179.227923 -410.527817) (xy 179.239832 -410.46667)
			(xy 179.259461 -410.407549) (xy 179.28649 -410.351423) (xy 179.320474 -410.299214) (xy 179.360856 -410.251779)
			(xy 179.406972 -410.209898) (xy 179.458064 -410.174258) (xy 179.513295 -410.145444) (xy 179.571757 -410.12393)
			(xy 179.632491 -410.110068) (xy 179.694498 -410.104086) (xy 179.756761 -410.106082) (xy 179.818258 -410.116025)
			(xy 179.877979 -410.133749) (xy 179.934942 -410.158966) (xy 179.988213 -410.191259) (xy 180.036918 -410.230099)
			(xy 180.080255 -410.274849) (xy 180.117515 -410.324773) (xy 180.148084 -410.379052) (xy 180.171462 -410.436795)
			(xy 180.187263 -410.497053) (xy 180.195229 -410.558836) (xy 180.195728 -410.589984) (xy 180.195229 -410.621132)
			(xy 180.187263 -410.682915) (xy 180.171462 -410.743173) (xy 180.148084 -410.800916) (xy 180.117515 -410.855195)
			(xy 180.080255 -410.905119) (xy 180.036918 -410.949869) (xy 179.988213 -410.988709) (xy 179.934942 -411.021002)
			(xy 179.877979 -411.046219) (xy 179.818258 -411.063943) (xy 179.756761 -411.073886) (xy 179.694498 -411.075882)
			(xy 179.632491 -411.0699) (xy 179.571757 -411.056038) (xy 179.513295 -411.034524) (xy 179.458064 -411.00571)
			(xy 179.406972 -410.97007) (xy 179.360856 -410.928189) (xy 179.320474 -410.880754) (xy 179.28649 -410.828545)
			(xy 179.259461 -410.772419) (xy 179.239832 -410.713298) (xy 179.227923 -410.652151) (xy 179.223932 -410.589984)
			(xy 175.795146 -410.589984) (xy 175.795147 -410.622707) (xy 175.786355 -410.687556) (xy 175.768931 -410.750636)
			(xy 175.743189 -410.810802) (xy 175.726852 -410.839158) (xy 175.723556 -410.845192) (xy 175.719938 -410.858448)
			(xy 175.71974 -410.86532) (xy 175.71974 -411.151324) (xy 175.719299 -411.161475) (xy 175.711503 -411.18022)
			(xy 175.697113 -411.194541) (xy 175.678331 -411.202247) (xy 175.668178 -411.202632) (xy 174.951898 -411.202632)
			(xy 174.941768 -411.202174) (xy 174.923041 -411.194441) (xy 174.908684 -411.180145) (xy 174.90087 -411.161452)
			(xy 174.900336 -411.151324) (xy 174.900336 -410.86532) (xy 174.900132 -410.858448) (xy 174.896531 -410.845185)
			(xy 174.893224 -410.839158) (xy 174.876874 -410.810809) (xy 174.851132 -410.750641) (xy 174.833707 -410.687559)
			(xy 174.824916 -410.622708) (xy 171.39511 -410.622708) (xy 171.386319 -410.687557) (xy 171.368892 -410.750636)
			(xy 171.343148 -410.810802) (xy 171.32681 -410.839158) (xy 171.32343 -410.845165) (xy 171.319704 -410.858431)
			(xy 171.319444 -410.86532) (xy 171.319444 -411.151324) (xy 171.318936 -411.161429) (xy 171.311198 -411.180099)
			(xy 171.296909 -411.194392) (xy 171.278241 -411.202133) (xy 171.268136 -411.202632) (xy 170.551856 -411.202632)
			(xy 170.541748 -411.202152) (xy 170.523075 -411.194405) (xy 170.508783 -411.180108) (xy 170.501044 -411.161432)
			(xy 170.500548 -411.151324) (xy 170.500548 -410.86532) (xy 170.500336 -410.858426) (xy 170.496593 -410.845154)
			(xy 170.493182 -410.839158) (xy 170.47683 -410.81081) (xy 170.451085 -410.750642) (xy 170.433658 -410.68756)
			(xy 170.424866 -410.622709) (xy 166.99506 -410.622709) (xy 166.98627 -410.687556) (xy 166.968845 -410.750635)
			(xy 166.943104 -410.810802) (xy 166.926768 -410.839158) (xy 166.923466 -410.845189) (xy 166.919853 -410.858448)
			(xy 166.919656 -410.86532) (xy 166.919656 -411.151324) (xy 166.919199 -411.161473) (xy 166.911406 -411.180215)
			(xy 166.897021 -411.194535) (xy 166.878245 -411.202244) (xy 166.868094 -411.202632) (xy 166.151814 -411.202632)
			(xy 166.141685 -411.202161) (xy 166.122959 -411.194433) (xy 166.108601 -411.180141) (xy 166.100786 -411.161451)
			(xy 166.100252 -411.151324) (xy 166.100252 -410.86532) (xy 166.100058 -410.858447) (xy 166.096452 -410.845184)
			(xy 166.09314 -410.839158) (xy 166.076789 -410.810809) (xy 166.051046 -410.750641) (xy 166.033621 -410.687559)
			(xy 166.02483 -410.622708) (xy 162.595024 -410.622708) (xy 162.586233 -410.687556) (xy 162.568807 -410.750636)
			(xy 162.543063 -410.810802) (xy 162.526726 -410.839158) (xy 162.52334 -410.845162) (xy 162.519618 -410.858431)
			(xy 162.51936 -410.86532) (xy 162.51936 -411.151324) (xy 162.519003 -411.161453) (xy 162.511239 -411.180165)
			(xy 162.496904 -411.19448) (xy 162.478182 -411.202217) (xy 162.468052 -411.202632) (xy 161.751772 -411.202632)
			(xy 161.741665 -411.202139) (xy 161.722993 -411.194398) (xy 161.7087 -411.180104) (xy 161.700961 -411.161431)
			(xy 161.700464 -411.151324) (xy 161.700464 -410.86532) (xy 161.70025 -410.858426) (xy 161.696508 -410.845154)
			(xy 161.693098 -410.839158) (xy 161.676748 -410.810809) (xy 161.651008 -410.75064) (xy 161.633584 -410.687559)
			(xy 161.624794 -410.622708) (xy 154.72791 -410.622708) (xy 154.72791 -412.090108) (xy 159.42387 -412.090108)
			(xy 159.427861 -412.027941) (xy 159.43977 -411.966794) (xy 159.459399 -411.907673) (xy 159.486428 -411.851547)
			(xy 159.520412 -411.799338) (xy 159.560794 -411.751903) (xy 159.60691 -411.710022) (xy 159.658002 -411.674382)
			(xy 159.713233 -411.645568) (xy 159.771695 -411.624054) (xy 159.832429 -411.610192) (xy 159.894436 -411.60421)
			(xy 159.956699 -411.606206) (xy 160.018196 -411.616149) (xy 160.077917 -411.633873) (xy 160.13488 -411.65909)
			(xy 160.188151 -411.691383) (xy 160.236856 -411.730223) (xy 160.280193 -411.774973) (xy 160.317453 -411.824897)
			(xy 160.348022 -411.879176) (xy 160.3714 -411.936919) (xy 160.387201 -411.997177) (xy 160.395167 -412.05896)
			(xy 160.395666 -412.090108) (xy 163.823912 -412.090108) (xy 163.827903 -412.027941) (xy 163.839812 -411.966794)
			(xy 163.859441 -411.907673) (xy 163.88647 -411.851547) (xy 163.920454 -411.799338) (xy 163.960836 -411.751903)
			(xy 164.006952 -411.710022) (xy 164.058044 -411.674382) (xy 164.113275 -411.645568) (xy 164.171737 -411.624054)
			(xy 164.232471 -411.610192) (xy 164.294478 -411.60421) (xy 164.356741 -411.606206) (xy 164.418238 -411.616149)
			(xy 164.477959 -411.633873) (xy 164.534922 -411.65909) (xy 164.588193 -411.691383) (xy 164.636898 -411.730223)
			(xy 164.680235 -411.774973) (xy 164.717495 -411.824897) (xy 164.748064 -411.879176) (xy 164.771442 -411.936919)
			(xy 164.787243 -411.997177) (xy 164.795209 -412.05896) (xy 164.795708 -412.090108) (xy 168.223954 -412.090108)
			(xy 168.227945 -412.027941) (xy 168.239854 -411.966794) (xy 168.259483 -411.907673) (xy 168.286512 -411.851547)
			(xy 168.320496 -411.799338) (xy 168.360878 -411.751903) (xy 168.406994 -411.710022) (xy 168.458086 -411.674382)
			(xy 168.513317 -411.645568) (xy 168.571779 -411.624054) (xy 168.632513 -411.610192) (xy 168.69452 -411.60421)
			(xy 168.756783 -411.606206) (xy 168.81828 -411.616149) (xy 168.878001 -411.633873) (xy 168.934964 -411.65909)
			(xy 168.988235 -411.691383) (xy 169.03694 -411.730223) (xy 169.080277 -411.774973) (xy 169.117537 -411.824897)
			(xy 169.148106 -411.879176) (xy 169.171484 -411.936919) (xy 169.187285 -411.997177) (xy 169.195251 -412.05896)
			(xy 169.19575 -412.090108) (xy 172.623742 -412.090108) (xy 172.627733 -412.027941) (xy 172.639642 -411.966794)
			(xy 172.659271 -411.907673) (xy 172.6863 -411.851547) (xy 172.720284 -411.799338) (xy 172.760666 -411.751903)
			(xy 172.806782 -411.710022) (xy 172.857874 -411.674382) (xy 172.913105 -411.645568) (xy 172.971567 -411.624054)
			(xy 173.032301 -411.610192) (xy 173.094308 -411.60421) (xy 173.156571 -411.606206) (xy 173.218068 -411.616149)
			(xy 173.277789 -411.633873) (xy 173.334752 -411.65909) (xy 173.388023 -411.691383) (xy 173.436728 -411.730223)
			(xy 173.480065 -411.774973) (xy 173.517325 -411.824897) (xy 173.547894 -411.879176) (xy 173.571272 -411.936919)
			(xy 173.587073 -411.997177) (xy 173.595039 -412.05896) (xy 173.595538 -412.090108) (xy 177.023784 -412.090108)
			(xy 177.027775 -412.027941) (xy 177.039684 -411.966794) (xy 177.059313 -411.907673) (xy 177.086342 -411.851547)
			(xy 177.120326 -411.799338) (xy 177.160708 -411.751903) (xy 177.206824 -411.710022) (xy 177.257916 -411.674382)
			(xy 177.313147 -411.645568) (xy 177.371609 -411.624054) (xy 177.432343 -411.610192) (xy 177.49435 -411.60421)
			(xy 177.556613 -411.606206) (xy 177.61811 -411.616149) (xy 177.677831 -411.633873) (xy 177.734794 -411.65909)
			(xy 177.788065 -411.691383) (xy 177.83677 -411.730223) (xy 177.880107 -411.774973) (xy 177.917367 -411.824897)
			(xy 177.947936 -411.879176) (xy 177.971314 -411.936919) (xy 177.987115 -411.997177) (xy 177.995081 -412.05896)
			(xy 177.99558 -412.090108) (xy 177.995081 -412.121256) (xy 177.987115 -412.183039) (xy 177.971314 -412.243297)
			(xy 177.947936 -412.30104) (xy 177.917367 -412.355319) (xy 177.880107 -412.405243) (xy 177.83677 -412.449993)
			(xy 177.788065 -412.488833) (xy 177.734794 -412.521126) (xy 177.677831 -412.546343) (xy 177.61811 -412.564067)
			(xy 177.556613 -412.57401) (xy 177.49435 -412.576006) (xy 177.432343 -412.570024) (xy 177.371609 -412.556162)
			(xy 177.313147 -412.534648) (xy 177.257916 -412.505834) (xy 177.206824 -412.470194) (xy 177.160708 -412.428313)
			(xy 177.120326 -412.380878) (xy 177.086342 -412.328669) (xy 177.059313 -412.272543) (xy 177.039684 -412.213422)
			(xy 177.027775 -412.152275) (xy 177.023784 -412.090108) (xy 173.595538 -412.090108) (xy 173.595039 -412.121256)
			(xy 173.587073 -412.183039) (xy 173.571272 -412.243297) (xy 173.547894 -412.30104) (xy 173.517325 -412.355319)
			(xy 173.480065 -412.405243) (xy 173.436728 -412.449993) (xy 173.388023 -412.488833) (xy 173.334752 -412.521126)
			(xy 173.277789 -412.546343) (xy 173.218068 -412.564067) (xy 173.156571 -412.57401) (xy 173.094308 -412.576006)
			(xy 173.032301 -412.570024) (xy 172.971567 -412.556162) (xy 172.913105 -412.534648) (xy 172.857874 -412.505834)
			(xy 172.806782 -412.470194) (xy 172.760666 -412.428313) (xy 172.720284 -412.380878) (xy 172.6863 -412.328669)
			(xy 172.659271 -412.272543) (xy 172.639642 -412.213422) (xy 172.627733 -412.152275) (xy 172.623742 -412.090108)
			(xy 169.19575 -412.090108) (xy 169.195251 -412.121256) (xy 169.187285 -412.183039) (xy 169.171484 -412.243297)
			(xy 169.148106 -412.30104) (xy 169.117537 -412.355319) (xy 169.080277 -412.405243) (xy 169.03694 -412.449993)
			(xy 168.988235 -412.488833) (xy 168.934964 -412.521126) (xy 168.878001 -412.546343) (xy 168.81828 -412.564067)
			(xy 168.756783 -412.57401) (xy 168.69452 -412.576006) (xy 168.632513 -412.570024) (xy 168.571779 -412.556162)
			(xy 168.513317 -412.534648) (xy 168.458086 -412.505834) (xy 168.406994 -412.470194) (xy 168.360878 -412.428313)
			(xy 168.320496 -412.380878) (xy 168.286512 -412.328669) (xy 168.259483 -412.272543) (xy 168.239854 -412.213422)
			(xy 168.227945 -412.152275) (xy 168.223954 -412.090108) (xy 164.795708 -412.090108) (xy 164.795209 -412.121256)
			(xy 164.787243 -412.183039) (xy 164.771442 -412.243297) (xy 164.748064 -412.30104) (xy 164.717495 -412.355319)
			(xy 164.680235 -412.405243) (xy 164.636898 -412.449993) (xy 164.588193 -412.488833) (xy 164.534922 -412.521126)
			(xy 164.477959 -412.546343) (xy 164.418238 -412.564067) (xy 164.356741 -412.57401) (xy 164.294478 -412.576006)
			(xy 164.232471 -412.570024) (xy 164.171737 -412.556162) (xy 164.113275 -412.534648) (xy 164.058044 -412.505834)
			(xy 164.006952 -412.470194) (xy 163.960836 -412.428313) (xy 163.920454 -412.380878) (xy 163.88647 -412.328669)
			(xy 163.859441 -412.272543) (xy 163.839812 -412.213422) (xy 163.827903 -412.152275) (xy 163.823912 -412.090108)
			(xy 160.395666 -412.090108) (xy 160.395167 -412.121256) (xy 160.387201 -412.183039) (xy 160.3714 -412.243297)
			(xy 160.348022 -412.30104) (xy 160.317453 -412.355319) (xy 160.280193 -412.405243) (xy 160.236856 -412.449993)
			(xy 160.188151 -412.488833) (xy 160.13488 -412.521126) (xy 160.077917 -412.546343) (xy 160.018196 -412.564067)
			(xy 159.956699 -412.57401) (xy 159.894436 -412.576006) (xy 159.832429 -412.570024) (xy 159.771695 -412.556162)
			(xy 159.713233 -412.534648) (xy 159.658002 -412.505834) (xy 159.60691 -412.470194) (xy 159.560794 -412.428313)
			(xy 159.520412 -412.380878) (xy 159.486428 -412.328669) (xy 159.459399 -412.272543) (xy 159.43977 -412.213422)
			(xy 159.427861 -412.152275) (xy 159.42387 -412.090108) (xy 154.72791 -412.090108) (xy 154.72791 -417.53282)
			(xy 154.727484 -417.542889) (xy 154.719765 -417.561489) (xy 154.712924 -417.568888) (xy 154.528012 -417.7538)
			(xy 154.521164 -417.761198) (xy 154.513428 -417.779796) (xy 154.513026 -417.789868) (xy 154.513026 -417.848034)
			(xy 154.513456 -417.858101) (xy 154.521182 -417.876694) (xy 154.528012 -417.884102) (xy 154.540966 -417.897056)
			(xy 154.548366 -417.903897) (xy 154.566965 -417.911614) (xy 154.577034 -417.912042)
		)
		(stroke
			(width 0)
			(type solid)
		)
		(fill yes)
		(layer "In15.Cu")
		(net "GND")
	)
	(gr_poly
		(pts
			(xy 393.542012 -242.078256) (xy 393.550618 -242.077929) (xy 393.566857 -242.072226) (xy 393.573762 -242.06708)
			(xy 393.59967 -242.040918) (xy 393.602767 -242.037722) (xy 393.607883 -242.030442) (xy 393.60983 -242.02644)
			(xy 393.61237 -242.020852) (xy 393.613132 -242.00993) (xy 393.614656 -241.992658) (xy 393.614656 -241.99215)
			(xy 393.615813 -241.981727) (xy 393.619115 -241.961014) (xy 393.62126 -241.950748) (xy 393.621768 -241.948462)
			(xy 393.623038 -241.938556) (xy 393.623038 -241.900456) (xy 393.62347 -241.89039) (xy 393.6312 -241.871801)
			(xy 393.638024 -241.864388) (xy 393.662408 -241.840004) (xy 393.666218 -241.835686) (xy 393.671552 -241.829082)
			(xy 393.673076 -241.826796) (xy 393.67333 -241.826542) (xy 393.688448 -241.803979) (xy 393.724043 -241.762956)
			(xy 393.765076 -241.727375) (xy 393.78763 -241.712242) (xy 393.787884 -241.711988) (xy 393.79017 -241.710464)
			(xy 393.79652 -241.705384) (xy 393.800838 -241.701574) (xy 393.826238 -241.676174) (xy 393.833635 -241.669325)
			(xy 393.852234 -241.661593) (xy 393.862306 -241.661188) (xy 393.90066 -241.661188) (xy 393.911582 -241.659918)
			(xy 393.914122 -241.65941) (xy 393.934072 -241.65538) (xy 393.974543 -241.651055) (xy 393.994894 -241.650774)
			(xy 393.99591 -241.650774) (xy 394.016262 -241.651032) (xy 394.056736 -241.655358) (xy 394.076682 -241.65941)
			(xy 394.079222 -241.659918) (xy 394.090144 -241.661188) (xy 394.128498 -241.661188) (xy 394.138569 -241.66161)
			(xy 394.157175 -241.669323) (xy 394.164566 -241.676174) (xy 394.189966 -241.701574) (xy 394.194284 -241.705384)
			(xy 394.196824 -241.707416) (xy 394.199872 -241.709702) (xy 394.202412 -241.71148) (xy 394.203174 -241.711988)
			(xy 394.220069 -241.723198) (xy 394.25163 -241.748653) (xy 394.266166 -241.762788) (xy 394.570712 -242.067334)
			(xy 394.577596 -242.072358) (xy 394.593691 -242.077929) (xy 394.602208 -242.078256) (xy 415.530792 -242.078256)
			(xy 415.544287 -242.077788) (xy 415.570313 -242.070622) (xy 415.593556 -242.056895) (xy 415.612396 -242.037563)
			(xy 415.62552 -242.013974) (xy 415.632012 -241.987772) (xy 415.63142 -241.960785) (xy 415.628074 -241.9477)
			(xy 415.620612 -241.921078) (xy 415.612574 -241.866378) (xy 415.612072 -241.838734) (xy 415.612072 -241.83848)
			(xy 415.612558 -241.811211) (xy 415.62032 -241.757227) (xy 415.635685 -241.704897) (xy 415.658342 -241.655287)
			(xy 415.687828 -241.609406) (xy 415.723543 -241.568189) (xy 415.76476 -241.532474) (xy 415.810641 -241.502988)
			(xy 415.860251 -241.480331) (xy 415.912581 -241.464966) (xy 415.966565 -241.457204) (xy 416.021103 -241.457204)
			(xy 416.075087 -241.464966) (xy 416.127417 -241.480331) (xy 416.177027 -241.502988) (xy 416.222908 -241.532474)
			(xy 416.264125 -241.568189) (xy 416.29984 -241.609406) (xy 416.329326 -241.655287) (xy 416.351983 -241.704897)
			(xy 416.367348 -241.757227) (xy 416.37511 -241.811211) (xy 416.375596 -241.83848) (xy 416.375596 -241.838734)
			(xy 416.375066 -241.866375) (xy 416.367028 -241.921072) (xy 416.359594 -241.9477) (xy 416.356138 -241.960772)
			(xy 416.355492 -241.987794) (xy 416.361965 -242.014037) (xy 416.375104 -242.037659) (xy 416.393984 -242.057001)
			(xy 416.417282 -242.070706) (xy 416.443361 -242.077811) (xy 416.456876 -242.078256) (xy 417.994084 -242.078256)
			(xy 418.00963 -242.077662) (xy 418.039267 -242.068254) (xy 418.06472 -242.050392) (xy 418.074602 -242.038378)
			(xy 418.079357 -242.031596) (xy 418.084675 -242.015919) (xy 418.085016 -242.007644) (xy 418.085016 -241.929666)
			(xy 418.083746 -241.924078) (xy 418.079344 -241.903275) (xy 418.074628 -241.861012) (xy 418.074348 -241.83975)
			(xy 418.074639 -241.818488) (xy 418.079354 -241.776227) (xy 418.083746 -241.755422) (xy 418.085016 -241.749834)
			(xy 418.085016 -241.706654) (xy 418.085448 -241.696588) (xy 418.093176 -241.677997) (xy 418.100002 -241.670586)
			(xy 418.124132 -241.646456) (xy 418.126926 -241.643408) (xy 418.127434 -241.642646) (xy 418.127942 -241.642138)
			(xy 418.133022 -241.635788) (xy 418.133784 -241.634772) (xy 418.1348 -241.632994) (xy 418.14186 -241.622194)
			(xy 418.15724 -241.601475) (xy 418.165534 -241.591592) (xy 418.17246 -241.583559) (xy 418.187072 -241.568182)
			(xy 418.194744 -241.560858) (xy 418.208152 -241.548578) (xy 418.236905 -241.52632) (xy 418.252148 -241.516408)
			(xy 418.253672 -241.515392) (xy 418.257228 -241.513106) (xy 418.28085 -241.489738) (xy 418.28085 -241.489484)
			(xy 418.288216 -241.482372) (xy 418.28847 -241.482118) (xy 418.295877 -241.475427) (xy 418.314313 -241.467831)
			(xy 418.324284 -241.467386) (xy 418.367464 -241.467386) (xy 418.373052 -241.466116) (xy 418.393856 -241.461715)
			(xy 418.436118 -241.457004) (xy 418.45738 -241.456718) (xy 437.920384 -241.456718) (xy 437.926629 -241.455621)
			(xy 437.93832 -241.450726) (xy 437.943498 -241.447066) (xy 438.70372 -240.686844) (xy 438.705752 -240.684558)
			(xy 438.710134 -240.679321) (xy 438.716188 -240.667089) (xy 438.71769 -240.660428) (xy 438.718489 -240.654814)
			(xy 438.719001 -240.643485) (xy 438.718706 -240.637822) (xy 438.717924 -240.629041) (xy 438.713708 -240.611926)
			(xy 438.710324 -240.603786) (xy 438.71007 -240.603024) (xy 438.7088 -240.600484) (xy 438.708292 -240.599468)
			(xy 438.70753 -240.598198) (xy 438.706514 -240.596166) (xy 438.700728 -240.586234) (xy 438.685462 -240.569057)
			(xy 438.676288 -240.56213) (xy 438.67197 -240.559336) (xy 438.66646 -240.556556) (xy 438.654515 -240.553469)
			(xy 438.648348 -240.55324) (xy 418.690298 -240.55324) (xy 418.669431 -240.553002) (xy 418.627936 -240.548545)
			(xy 418.607494 -240.54435) (xy 418.601906 -240.54308) (xy 418.557202 -240.54308) (xy 418.547132 -240.542657)
			(xy 418.528529 -240.534941) (xy 418.521134 -240.528094) (xy 418.513768 -240.520728) (xy 418.488622 -240.49609)
			(xy 418.483288 -240.492534) (xy 418.464492 -240.479834) (xy 418.463984 -240.479326) (xy 418.454332 -240.47196)
			(xy 418.437822 -240.458244) (xy 418.437314 -240.457736) (xy 418.422582 -240.44402) (xy 418.401246 -240.421414)
			(xy 418.400738 -240.420906) (xy 418.387276 -240.405158) (xy 418.378132 -240.392458) (xy 418.365686 -240.37417)
			(xy 418.362638 -240.369598) (xy 418.33292 -240.33988) (xy 418.326075 -240.332481) (xy 418.318344 -240.313883)
			(xy 418.317934 -240.303812) (xy 418.317934 -240.259108) (xy 418.316664 -240.25352) (xy 418.312405 -240.233084)
			(xy 418.307818 -240.191589) (xy 418.30752 -240.170716) (xy 418.307813 -240.149842) (xy 418.312399 -240.108348)
			(xy 418.316664 -240.087912) (xy 418.317934 -240.082324) (xy 418.317934 -240.03762) (xy 418.318372 -240.027557)
			(xy 418.326111 -240.008977) (xy 418.33292 -240.001552) (xy 418.35832 -239.976152) (xy 418.36213 -239.971834)
			(xy 418.363654 -239.969802) (xy 418.367972 -239.964214) (xy 418.368734 -239.963452) (xy 418.380549 -239.945664)
			(xy 418.407536 -239.912566) (xy 418.422582 -239.897412) (xy 418.436644 -239.88395) (xy 418.467058 -239.859647)
			(xy 418.483288 -239.848898) (xy 418.488622 -239.845342) (xy 418.513768 -239.820704) (xy 418.513768 -239.82045)
			(xy 418.521134 -239.813338) (xy 418.521388 -239.813084) (xy 418.528798 -239.8064) (xy 418.547234 -239.798816)
			(xy 418.557202 -239.798352) (xy 418.601906 -239.798352) (xy 418.607494 -239.797082) (xy 418.627935 -239.792878)
			(xy 418.66943 -239.788423) (xy 418.690298 -239.788192) (xy 438.91962 -239.788192) (xy 438.927748 -239.78743)
			(xy 438.928256 -239.78743) (xy 438.935774 -239.785827) (xy 438.94946 -239.778849) (xy 438.95518 -239.773714)
			(xy 444.891668 -233.837226) (xy 444.89836 -233.829819) (xy 444.905956 -233.811383) (xy 444.9064 -233.801412)
			(xy 444.9064 -229.56774) (xy 444.906097 -229.559544) (xy 444.900924 -229.543991) (xy 444.89624 -229.53726)
			(xy 444.887507 -229.526347) (xy 444.865304 -229.509382) (xy 444.83933 -229.499084) (xy 444.811535 -229.496225)
			(xy 444.797688 -229.498144) (xy 444.781622 -229.500747) (xy 444.749193 -229.503543) (xy 444.732918 -229.503732)
			(xy 444.73241 -229.503732) (xy 444.705141 -229.503269) (xy 444.651157 -229.495509) (xy 444.598827 -229.480145)
			(xy 444.549217 -229.457489) (xy 444.503335 -229.428004) (xy 444.462117 -229.39229) (xy 444.426402 -229.351073)
			(xy 444.396915 -229.305192) (xy 444.374259 -229.255582) (xy 444.358893 -229.203253) (xy 444.351131 -229.149269)
			(xy 444.351131 -229.094731) (xy 444.358893 -229.040747) (xy 444.374259 -228.988418) (xy 444.396915 -228.938808)
			(xy 444.426402 -228.892927) (xy 444.462117 -228.85171) (xy 444.503335 -228.815996) (xy 444.549217 -228.786511)
			(xy 444.598827 -228.763855) (xy 444.651157 -228.748491) (xy 444.705141 -228.740731) (xy 444.73241 -228.740208)
			(xy 444.732918 -228.740208) (xy 444.749193 -228.740389) (xy 444.781622 -228.743189) (xy 444.797688 -228.745796)
			(xy 444.811526 -228.74773) (xy 444.839308 -228.744828) (xy 444.865265 -228.734512) (xy 444.88746 -228.717552)
			(xy 444.89624 -228.70668) (xy 444.900908 -228.69994) (xy 444.906091 -228.684393) (xy 444.9064 -228.6762)
			(xy 444.9064 -227.54336) (xy 444.906305 -227.538482) (xy 444.904517 -227.528893) (xy 444.902844 -227.52431)
			(xy 444.899034 -227.515166) (xy 442.747654 -225.363786) (xy 442.747146 -225.363278) (xy 442.73978 -225.355912)
			(xy 442.739272 -225.35515) (xy 442.65215 -225.268028) (xy 442.645345 -225.260681) (xy 442.637631 -225.242218)
			(xy 442.637164 -225.232214) (xy 442.637164 -223.871282) (xy 442.637704 -223.861295) (xy 442.645418 -223.842864)
			(xy 442.65215 -223.835468) (xy 442.739526 -223.748092) (xy 442.740034 -223.74733) (xy 442.7474 -223.739964)
			(xy 442.747908 -223.739456) (xy 443.441074 -223.04629) (xy 443.442852 -223.044512) (xy 443.453598 -223.034019)
			(xy 443.476485 -223.014565) (xy 443.488572 -223.00565) (xy 443.501018 -222.997014) (xy 443.507114 -222.99295)
			(xy 443.51194 -222.989902) (xy 443.518036 -222.983806) (xy 443.549786 -222.951802) (xy 443.55004 -222.951548)
			(xy 443.55766 -222.944182) (xy 443.623446 -222.944182) (xy 443.629034 -222.942912) (xy 443.649471 -222.938656)
			(xy 443.690965 -222.934076) (xy 443.711838 -222.933768) (xy 443.732712 -222.934058) (xy 443.774208 -222.938639)
			(xy 443.794642 -222.942912) (xy 443.80023 -222.944182) (xy 443.866016 -222.944182) (xy 443.873636 -222.951548)
			(xy 443.87389 -222.951802) (xy 443.90564 -222.983806) (xy 443.912498 -222.990664) (xy 443.917324 -222.993712)
			(xy 443.940581 -223.009118) (xy 443.982788 -223.045594) (xy 444.019251 -223.087812) (xy 444.034672 -223.11106)
			(xy 444.03772 -223.115886) (xy 444.044578 -223.122744) (xy 444.076582 -223.154494) (xy 444.076836 -223.154748)
			(xy 444.084202 -223.162368) (xy 444.084202 -223.228154) (xy 444.085472 -223.233742) (xy 444.089728 -223.254179)
			(xy 444.094307 -223.295673) (xy 444.094616 -223.316546) (xy 444.094325 -223.33742) (xy 444.089743 -223.378916)
			(xy 444.085472 -223.39935) (xy 444.084202 -223.404938) (xy 444.084202 -223.470724) (xy 444.076836 -223.478344)
			(xy 444.076582 -223.478598) (xy 444.044578 -223.510348) (xy 444.038482 -223.516444) (xy 444.035434 -223.52127)
			(xy 444.03137 -223.527366) (xy 444.022734 -223.539812) (xy 444.013814 -223.551895) (xy 443.994361 -223.574782)
			(xy 443.983872 -223.585532) (xy 443.982094 -223.58731) (xy 443.416944 -224.15246) (xy 443.41026 -224.15987)
			(xy 443.402672 -224.178305) (xy 443.402212 -224.188274) (xy 443.402212 -224.275904) (xy 443.402385 -224.282056)
			(xy 443.405345 -224.293999) (xy 443.408054 -224.299526) (xy 443.411102 -224.304606) (xy 443.419183 -224.315128)
			(xy 443.439674 -224.331965) (xy 443.463806 -224.342965) (xy 443.489955 -224.347391) (xy 443.516362 -224.344943)
			(xy 443.541252 -224.335787) (xy 443.552326 -224.328482) (xy 443.61862 -224.328482) (xy 443.624208 -224.327212)
			(xy 443.645012 -224.322815) (xy 443.687274 -224.318109) (xy 443.708536 -224.317814) (xy 443.729798 -224.318104)
			(xy 443.772059 -224.322817) (xy 443.792864 -224.327212) (xy 443.798452 -224.328482) (xy 443.862714 -224.328482)
			(xy 443.870334 -224.335848) (xy 443.870588 -224.336102) (xy 443.902338 -224.368106) (xy 443.907926 -224.373694)
			(xy 443.912752 -224.376742) (xy 443.930653 -224.38842) (xy 443.964 -224.415158) (xy 443.9793 -224.430082)
			(xy 446.231007 -226.681538) (xy 457.325982 -226.681538) (xy 457.330053 -226.625916) (xy 457.342179 -226.571479)
			(xy 457.362102 -226.519388) (xy 457.389398 -226.470753) (xy 457.423484 -226.42661) (xy 457.463633 -226.387901)
			(xy 457.508991 -226.35545) (xy 457.558591 -226.329949) (xy 457.611375 -226.311942) (xy 457.666218 -226.301812)
			(xy 457.721952 -226.299775) (xy 457.777389 -226.305875) (xy 457.831346 -226.319981) (xy 457.882675 -226.341793)
			(xy 457.930281 -226.370847) (xy 457.973149 -226.406522) (xy 458.010366 -226.448059) (xy 458.041139 -226.494572)
			(xy 458.064811 -226.545069) (xy 458.080879 -226.598476) (xy 458.088999 -226.653652) (xy 458.089508 -226.681538)
			(xy 458.088999 -226.709424) (xy 458.080879 -226.7646) (xy 458.064811 -226.818007) (xy 458.041139 -226.868504)
			(xy 458.010366 -226.915017) (xy 457.973149 -226.956554) (xy 457.930281 -226.992229) (xy 457.882675 -227.021283)
			(xy 457.831346 -227.043095) (xy 457.777389 -227.057201) (xy 457.721952 -227.063301) (xy 457.666218 -227.061264)
			(xy 457.611375 -227.051134) (xy 457.558591 -227.033127) (xy 457.508991 -227.007626) (xy 457.463633 -226.975175)
			(xy 457.423484 -226.936466) (xy 457.389398 -226.892323) (xy 457.362102 -226.843688) (xy 457.342179 -226.791597)
			(xy 457.330053 -226.73716) (xy 457.325982 -226.681538) (xy 446.231007 -226.681538) (xy 446.256664 -226.707192)
			(xy 446.263515 -226.714588) (xy 446.271259 -226.733187) (xy 446.27165 -226.74326) (xy 446.27165 -230.3526)
			(xy 461.872582 -230.3526) (xy 461.876653 -230.296978) (xy 461.888779 -230.242541) (xy 461.908702 -230.19045)
			(xy 461.935998 -230.141815) (xy 461.970084 -230.097672) (xy 462.010233 -230.058963) (xy 462.055591 -230.026512)
			(xy 462.105191 -230.001011) (xy 462.157975 -229.983004) (xy 462.212818 -229.972874) (xy 462.268552 -229.970837)
			(xy 462.323989 -229.976937) (xy 462.377946 -229.991043) (xy 462.429275 -230.012855) (xy 462.476881 -230.041909)
			(xy 462.519749 -230.077584) (xy 462.556966 -230.119121) (xy 462.587739 -230.165634) (xy 462.611411 -230.216131)
			(xy 462.627479 -230.269538) (xy 462.635599 -230.324714) (xy 462.636108 -230.3526) (xy 462.635599 -230.380486)
			(xy 462.627479 -230.435662) (xy 462.611411 -230.489069) (xy 462.587739 -230.539566) (xy 462.556966 -230.586079)
			(xy 462.519749 -230.627616) (xy 462.476881 -230.663291) (xy 462.429275 -230.692345) (xy 462.377946 -230.714157)
			(xy 462.323989 -230.728263) (xy 462.268552 -230.734363) (xy 462.212818 -230.732326) (xy 462.157975 -230.722196)
			(xy 462.105191 -230.704189) (xy 462.055591 -230.678688) (xy 462.010233 -230.646237) (xy 461.970084 -230.607528)
			(xy 461.935998 -230.563385) (xy 461.908702 -230.51475) (xy 461.888779 -230.462659) (xy 461.876653 -230.408222)
			(xy 461.872582 -230.3526) (xy 446.27165 -230.3526) (xy 446.27165 -232.69448) (xy 451.24192 -232.69448)
			(xy 451.245991 -232.638858) (xy 451.258117 -232.584421) (xy 451.27804 -232.53233) (xy 451.305336 -232.483695)
			(xy 451.339422 -232.439552) (xy 451.379571 -232.400843) (xy 451.424929 -232.368392) (xy 451.474529 -232.342891)
			(xy 451.527313 -232.324884) (xy 451.582156 -232.314754) (xy 451.63789 -232.312717) (xy 451.693327 -232.318817)
			(xy 451.747284 -232.332923) (xy 451.798613 -232.354735) (xy 451.846219 -232.383789) (xy 451.889087 -232.419464)
			(xy 451.926304 -232.461001) (xy 451.957077 -232.507514) (xy 451.980749 -232.558011) (xy 451.996817 -232.611418)
			(xy 452.004937 -232.666594) (xy 452.005446 -232.69448) (xy 452.004937 -232.722366) (xy 451.996817 -232.777542)
			(xy 451.980749 -232.830949) (xy 451.957077 -232.881446) (xy 451.926304 -232.927959) (xy 451.889087 -232.969496)
			(xy 451.846219 -233.005171) (xy 451.798613 -233.034225) (xy 451.747284 -233.056037) (xy 451.693327 -233.070143)
			(xy 451.63789 -233.076243) (xy 451.582156 -233.074206) (xy 451.527313 -233.064076) (xy 451.474529 -233.046069)
			(xy 451.424929 -233.020568) (xy 451.379571 -232.988117) (xy 451.339422 -232.949408) (xy 451.305336 -232.905265)
			(xy 451.27804 -232.85663) (xy 451.258117 -232.804539) (xy 451.245991 -232.750102) (xy 451.24192 -232.69448)
			(xy 446.27165 -232.69448) (xy 446.27165 -234.181396) (xy 446.271226 -234.191465) (xy 446.263507 -234.210066)
			(xy 446.256664 -234.217464) (xy 445.962278 -234.51185) (xy 445.96177 -234.51312) (xy 445.819021 -234.655869)
			(xy 448.021157 -234.655869) (xy 448.021157 -234.595931) (xy 448.028981 -234.536505) (xy 448.044494 -234.478608)
			(xy 448.067432 -234.423232) (xy 448.097401 -234.371324) (xy 448.13389 -234.323771) (xy 448.176273 -234.281388)
			(xy 448.223825 -234.2449) (xy 448.275734 -234.214931) (xy 448.33111 -234.191993) (xy 448.389007 -234.17648)
			(xy 448.448433 -234.168657) (xy 448.478402 -234.168188) (xy 449.342002 -234.168188) (xy 449.371969 -234.168686)
			(xy 449.431391 -234.176509) (xy 449.489283 -234.192022) (xy 449.544656 -234.214958) (xy 449.596561 -234.244925)
			(xy 449.64411 -234.281411) (xy 449.68649 -234.323792) (xy 449.722976 -234.371341) (xy 449.752943 -234.423246)
			(xy 449.775879 -234.478618) (xy 449.791391 -234.536511) (xy 449.799214 -234.595933) (xy 449.799214 -234.655867)
			(xy 449.791391 -234.715289) (xy 449.775879 -234.773182) (xy 449.752943 -234.828554) (xy 449.749404 -234.834684)
			(xy 450.697598 -234.834684) (xy 450.701669 -234.779062) (xy 450.713795 -234.724625) (xy 450.733718 -234.672534)
			(xy 450.761014 -234.623899) (xy 450.7951 -234.579756) (xy 450.835249 -234.541047) (xy 450.880607 -234.508596)
			(xy 450.930207 -234.483095) (xy 450.982991 -234.465088) (xy 451.037834 -234.454958) (xy 451.093568 -234.452921)
			(xy 451.149005 -234.459021) (xy 451.202962 -234.473127) (xy 451.254291 -234.494939) (xy 451.301897 -234.523993)
			(xy 451.344765 -234.559668) (xy 451.381982 -234.601205) (xy 451.412755 -234.647718) (xy 451.436427 -234.698215)
			(xy 451.452495 -234.751622) (xy 451.460615 -234.806798) (xy 451.461124 -234.834684) (xy 451.460615 -234.86257)
			(xy 451.452495 -234.917746) (xy 451.436427 -234.971153) (xy 451.412755 -235.02165) (xy 451.381982 -235.068163)
			(xy 451.344765 -235.1097) (xy 451.301897 -235.145375) (xy 451.254291 -235.174429) (xy 451.202962 -235.196241)
			(xy 451.149005 -235.210347) (xy 451.093568 -235.216447) (xy 451.037834 -235.21441) (xy 450.982991 -235.20428)
			(xy 450.930207 -235.186273) (xy 450.880607 -235.160772) (xy 450.835249 -235.128321) (xy 450.7951 -235.089612)
			(xy 450.761014 -235.045469) (xy 450.733718 -234.996834) (xy 450.713795 -234.944743) (xy 450.701669 -234.890306)
			(xy 450.697598 -234.834684) (xy 449.749404 -234.834684) (xy 449.722976 -234.880459) (xy 449.68649 -234.928008)
			(xy 449.64411 -234.970389) (xy 449.596561 -235.006875) (xy 449.544656 -235.036842) (xy 449.489283 -235.059778)
			(xy 449.431391 -235.075291) (xy 449.371969 -235.083114) (xy 449.342002 -235.083604) (xy 448.478402 -235.083604)
			(xy 448.448433 -235.083143) (xy 448.389007 -235.07532) (xy 448.33111 -235.059807) (xy 448.275734 -235.036869)
			(xy 448.223825 -235.0069) (xy 448.176273 -234.970412) (xy 448.13389 -234.928029) (xy 448.097401 -234.880476)
			(xy 448.067432 -234.828568) (xy 448.044494 -234.773192) (xy 448.028981 -234.715295) (xy 448.021157 -234.655869)
			(xy 445.819021 -234.655869) (xy 445.511936 -234.962954) (xy 445.510666 -234.963462) (xy 443.974728 -236.4994)
			(xy 444.422782 -236.4994) (xy 444.426853 -236.443778) (xy 444.438979 -236.389341) (xy 444.458902 -236.33725)
			(xy 444.486198 -236.288615) (xy 444.520284 -236.244472) (xy 444.560433 -236.205763) (xy 444.605791 -236.173312)
			(xy 444.655391 -236.147811) (xy 444.708175 -236.129804) (xy 444.763018 -236.119674) (xy 444.818752 -236.117637)
			(xy 444.874189 -236.123737) (xy 444.928146 -236.137843) (xy 444.979475 -236.159655) (xy 445.027081 -236.188709)
			(xy 445.069949 -236.224384) (xy 445.107166 -236.265921) (xy 445.137939 -236.312434) (xy 445.161611 -236.362931)
			(xy 445.169274 -236.388402) (xy 450.160898 -236.388402) (xy 450.161419 -236.359485) (xy 450.170147 -236.302314)
			(xy 450.187405 -236.247115) (xy 450.212796 -236.195154) (xy 450.245739 -236.14762) (xy 450.285479 -236.105603)
			(xy 450.307964 -236.087412) (xy 450.316727 -236.079852) (xy 450.326907 -236.059091) (xy 450.327522 -236.047534)
			(xy 450.327522 -235.96727) (xy 450.326904 -235.955709) (xy 450.316742 -235.934937) (xy 450.307964 -235.927392)
			(xy 450.285469 -235.909215) (xy 450.245736 -235.867191) (xy 450.2128 -235.819653) (xy 450.187414 -235.767689)
			(xy 450.170159 -235.71249) (xy 450.161432 -235.655319) (xy 450.160898 -235.626402) (xy 450.161384 -235.599151)
			(xy 450.16914 -235.545203) (xy 450.184495 -235.492908) (xy 450.207137 -235.443331) (xy 450.236603 -235.397481)
			(xy 450.272294 -235.35629) (xy 450.313485 -235.320599) (xy 450.359335 -235.291133) (xy 450.408912 -235.268491)
			(xy 450.461207 -235.253136) (xy 450.515155 -235.24538) (xy 450.569657 -235.24538) (xy 450.623605 -235.253136)
			(xy 450.6759 -235.268491) (xy 450.725477 -235.291133) (xy 450.771327 -235.320599) (xy 450.812518 -235.35629)
			(xy 450.848209 -235.397481) (xy 450.877675 -235.443331) (xy 450.900317 -235.492908) (xy 450.915672 -235.545203)
			(xy 450.923428 -235.599151) (xy 450.923914 -235.626402) (xy 450.92343 -235.655321) (xy 450.914698 -235.712495)
			(xy 450.897436 -235.767696) (xy 450.872038 -235.819658) (xy 450.839087 -235.867191) (xy 450.799338 -235.909204)
			(xy 450.776848 -235.927392) (xy 450.768085 -235.934953) (xy 450.757904 -235.955713) (xy 450.75729 -235.96727)
			(xy 450.75729 -236.047534) (xy 450.757902 -236.059096) (xy 450.768068 -236.079868) (xy 450.776848 -236.087412)
			(xy 450.799347 -236.105584) (xy 450.839079 -236.147609) (xy 450.872015 -236.195149) (xy 450.8974 -236.247113)
			(xy 450.914654 -236.302313) (xy 450.921397 -236.346492) (xy 454.16038 -236.346492) (xy 454.164451 -236.29087)
			(xy 454.176577 -236.236433) (xy 454.1965 -236.184342) (xy 454.223796 -236.135707) (xy 454.257882 -236.091564)
			(xy 454.298031 -236.052855) (xy 454.343389 -236.020404) (xy 454.392989 -235.994903) (xy 454.445773 -235.976896)
			(xy 454.500616 -235.966766) (xy 454.55635 -235.964729) (xy 454.611787 -235.970829) (xy 454.665744 -235.984935)
			(xy 454.717073 -236.006747) (xy 454.764679 -236.035801) (xy 454.807547 -236.071476) (xy 454.844764 -236.113013)
			(xy 454.875537 -236.159526) (xy 454.899209 -236.210023) (xy 454.915277 -236.26343) (xy 454.923397 -236.318606)
			(xy 454.923906 -236.346492) (xy 454.923397 -236.374378) (xy 454.915277 -236.429554) (xy 454.899209 -236.482961)
			(xy 454.875537 -236.533458) (xy 454.844764 -236.579971) (xy 454.807547 -236.621508) (xy 454.764679 -236.657183)
			(xy 454.717073 -236.686237) (xy 454.665744 -236.708049) (xy 454.611787 -236.722155) (xy 454.55635 -236.728255)
			(xy 454.500616 -236.726218) (xy 454.445773 -236.716088) (xy 454.392989 -236.698081) (xy 454.343389 -236.67258)
			(xy 454.298031 -236.640129) (xy 454.257882 -236.60142) (xy 454.223796 -236.557277) (xy 454.1965 -236.508642)
			(xy 454.176577 -236.456551) (xy 454.164451 -236.402114) (xy 454.16038 -236.346492) (xy 450.921397 -236.346492)
			(xy 450.92338 -236.359485) (xy 450.923914 -236.388402) (xy 450.923428 -236.415653) (xy 450.915672 -236.469601)
			(xy 450.900317 -236.521896) (xy 450.877675 -236.571473) (xy 450.848209 -236.617323) (xy 450.812518 -236.658514)
			(xy 450.771327 -236.694205) (xy 450.725477 -236.723671) (xy 450.6759 -236.746313) (xy 450.623605 -236.761668)
			(xy 450.569657 -236.769424) (xy 450.515155 -236.769424) (xy 450.461207 -236.761668) (xy 450.408912 -236.746313)
			(xy 450.359335 -236.723671) (xy 450.313485 -236.694205) (xy 450.272294 -236.658514) (xy 450.236603 -236.617323)
			(xy 450.207137 -236.571473) (xy 450.184495 -236.521896) (xy 450.16914 -236.469601) (xy 450.161384 -236.415653)
			(xy 450.160898 -236.388402) (xy 445.169274 -236.388402) (xy 445.177679 -236.416338) (xy 445.185799 -236.471514)
			(xy 445.186308 -236.4994) (xy 445.185799 -236.527286) (xy 445.177679 -236.582462) (xy 445.161611 -236.635869)
			(xy 445.137939 -236.686366) (xy 445.107166 -236.732879) (xy 445.069949 -236.774416) (xy 445.027081 -236.810091)
			(xy 444.979475 -236.839145) (xy 444.928146 -236.860957) (xy 444.874189 -236.875063) (xy 444.818752 -236.881163)
			(xy 444.763018 -236.879126) (xy 444.708175 -236.868996) (xy 444.655391 -236.850989) (xy 444.605791 -236.825488)
			(xy 444.560433 -236.793037) (xy 444.520284 -236.754328) (xy 444.486198 -236.710185) (xy 444.458902 -236.66155)
			(xy 444.438979 -236.609459) (xy 444.426853 -236.555022) (xy 444.422782 -236.4994) (xy 443.974728 -236.4994)
			(xy 443.505336 -236.968792) (xy 443.500764 -236.974126) (xy 443.492299 -236.986251) (xy 443.482078 -237.013984)
			(xy 443.480217 -237.043482) (xy 443.486873 -237.072279) (xy 443.50149 -237.097969) (xy 443.522846 -237.118403)
			(xy 443.549155 -237.131873) (xy 443.578218 -237.137253) (xy 443.592966 -237.136178) (xy 443.59576 -237.135924)
			(xy 443.596268 -237.135924) (xy 443.60627 -237.134894) (xy 443.626346 -237.133751) (xy 443.6364 -237.133638)
			(xy 443.663669 -237.134124) (xy 443.717653 -237.141886) (xy 443.769983 -237.157251) (xy 443.819593 -237.179908)
			(xy 443.865474 -237.209394) (xy 443.906691 -237.245109) (xy 443.942406 -237.286326) (xy 443.971892 -237.332207)
			(xy 443.994549 -237.381817) (xy 444.009914 -237.434147) (xy 444.017676 -237.488131) (xy 444.017676 -237.542669)
			(xy 444.009914 -237.596653) (xy 443.994549 -237.648983) (xy 443.971892 -237.698593) (xy 443.942406 -237.744474)
			(xy 443.906691 -237.785691) (xy 443.865474 -237.821406) (xy 443.819593 -237.850892) (xy 443.769983 -237.873549)
			(xy 443.717653 -237.888914) (xy 443.663669 -237.896676) (xy 443.609131 -237.896676) (xy 443.555147 -237.888914)
			(xy 443.502817 -237.873549) (xy 443.453207 -237.850892) (xy 443.407326 -237.821406) (xy 443.366109 -237.785691)
			(xy 443.330394 -237.744474) (xy 443.300908 -237.698593) (xy 443.278251 -237.648983) (xy 443.262886 -237.596653)
			(xy 443.255124 -237.542669) (xy 443.254638 -237.5154) (xy 443.254737 -237.505282) (xy 443.255883 -237.485079)
			(xy 443.256924 -237.475014) (xy 443.256924 -237.47476) (xy 443.257178 -237.471458) (xy 443.257178 -237.470696)
			(xy 443.258066 -237.45577) (xy 443.252144 -237.426478) (xy 443.237979 -237.400163) (xy 443.21679 -237.379089)
			(xy 443.190398 -237.365068) (xy 443.161073 -237.359306) (xy 443.131338 -237.362299) (xy 443.10375 -237.373788)
			(xy 443.091824 -237.382812) (xy 443.088014 -237.386114) (xy 438.539636 -241.934238) (xy 438.535742 -241.938295)
			(xy 438.529714 -241.947785) (xy 438.527698 -241.953034) (xy 438.525666 -241.9604) (xy 438.523791 -241.974964)
			(xy 438.527514 -242.004078) (xy 438.539365 -242.030931) (xy 438.558363 -242.053304) (xy 438.582941 -242.069349)
			(xy 438.611067 -242.077741) (xy 438.625742 -242.078256) (xy 440.3598 -242.078256) (xy 440.366658 -242.077748)
			(xy 443.911736 -238.532924) (xy 443.919356 -238.525558) (xy 444.009018 -238.435896) (xy 444.016365 -238.429089)
			(xy 444.034827 -238.421364) (xy 444.044832 -238.42091) (xy 444.17742 -238.42091) (xy 444.182246 -238.420656)
			(xy 453.966072 -238.420656) (xy 453.974674 -238.419433) (xy 453.990376 -238.412023) (xy 453.996806 -238.406178)
			(xy 455.566018 -236.836966) (xy 455.572418 -236.82998) (xy 455.57999 -236.812627) (xy 455.58075 -236.803184)
			(xy 455.581004 -236.798358) (xy 455.581158 -236.783651) (xy 455.574018 -236.755133) (xy 455.559039 -236.729836)
			(xy 455.537466 -236.709865) (xy 455.511091 -236.696877) (xy 455.496676 -236.693964) (xy 455.49439 -236.69371)
			(xy 455.467082 -236.689758) (xy 455.413913 -236.67501) (xy 455.363422 -236.652762) (xy 455.316659 -236.623476)
			(xy 455.2746 -236.587763) (xy 455.238121 -236.546366) (xy 455.207981 -236.500149) (xy 455.184809 -236.450075)
			(xy 455.169088 -236.397185) (xy 455.161145 -236.342584) (xy 455.160634 -236.314996) (xy 455.161121 -236.287727)
			(xy 455.168883 -236.233743) (xy 455.184248 -236.181414) (xy 455.206905 -236.131804) (xy 455.236391 -236.085923)
			(xy 455.272106 -236.044706) (xy 455.313323 -236.008991) (xy 455.359204 -235.979505) (xy 455.408814 -235.956848)
			(xy 455.461143 -235.941483) (xy 455.515127 -235.933721) (xy 455.542396 -235.933234) (xy 455.569986 -235.93372)
			(xy 455.624591 -235.941664) (xy 455.677483 -235.957386) (xy 455.727561 -235.980559) (xy 455.773781 -236.010701)
			(xy 455.81518 -236.047183) (xy 455.850896 -236.089244) (xy 455.880184 -236.13601) (xy 455.902434 -236.186505)
			(xy 455.917182 -236.239677) (xy 455.92111 -236.26699) (xy 455.921364 -236.269276) (xy 455.924331 -236.283617)
			(xy 455.937283 -236.309869) (xy 455.957133 -236.331384) (xy 455.982259 -236.346404) (xy 456.010608 -236.353702)
			(xy 456.02525 -236.353604) (xy 456.025758 -236.353604) (xy 456.030584 -236.35335) (xy 456.040031 -236.352596)
			(xy 456.057397 -236.345039) (xy 456.064366 -236.338618) (xy 456.2602 -236.142784) (xy 456.274393 -236.128897)
			(xy 456.305192 -236.10383) (xy 456.321668 -236.092746) (xy 456.322938 -236.091984) (xy 456.32878 -236.087666)
			(xy 456.334114 -236.083348) (xy 456.361546 -236.055916) (xy 456.368946 -236.049075) (xy 456.387545 -236.041355)
			(xy 456.397614 -236.04093) (xy 456.442318 -236.04093) (xy 456.447906 -236.03966) (xy 456.468342 -236.035402)
			(xy 456.509837 -236.030818) (xy 456.53071 -236.030516) (xy 456.551584 -236.030805) (xy 456.593081 -236.035384)
			(xy 456.613514 -236.03966) (xy 456.619102 -236.04093) (xy 456.663806 -236.04093) (xy 456.673875 -236.041355)
			(xy 456.692475 -236.049074) (xy 456.699874 -236.055916) (xy 456.73137 -236.087412) (xy 456.736196 -236.09046)
			(xy 456.759456 -236.105863) (xy 456.801669 -236.142335) (xy 456.83814 -236.184549) (xy 456.853544 -236.207808)
			(xy 456.856592 -236.212634) (xy 456.888088 -236.24413) (xy 456.894931 -236.25153) (xy 456.902656 -236.270128)
			(xy 456.903074 -236.280198) (xy 456.903074 -236.324902) (xy 456.904344 -236.33049) (xy 456.908603 -236.350926)
			(xy 456.913188 -236.392421) (xy 456.913488 -236.413294) (xy 456.913195 -236.434168) (xy 456.908607 -236.475662)
			(xy 456.904344 -236.496098) (xy 456.903074 -236.501686) (xy 456.903074 -236.54639) (xy 456.902652 -236.55646)
			(xy 456.894937 -236.575065) (xy 456.888088 -236.582458) (xy 456.861672 -236.608874) (xy 456.854814 -236.617256)
			(xy 456.842876 -236.634528) (xy 456.842876 -236.635036) (xy 456.833377 -236.647982) (xy 456.81252 -236.672397)
			(xy 456.80122 -236.683804) (xy 454.666604 -238.818674) (xy 454.662695 -238.823606) (xy 454.657176 -238.834912)
			(xy 454.655682 -238.841026) (xy 454.653619 -238.855674) (xy 454.657056 -238.885042) (xy 454.668756 -238.912198)
			(xy 454.687738 -238.934869) (xy 454.712414 -238.951159) (xy 454.740721 -238.959704) (xy 454.755504 -238.960152)
			(xy 460.214218 -238.960152) (xy 460.224286 -238.96058) (xy 460.24288 -238.968305) (xy 460.250286 -238.975138)
			(xy 460.743554 -239.468406) (xy 460.746405 -239.471112) (xy 460.752782 -239.475707) (xy 460.756254 -239.47755)
			(xy 460.76168 -239.480134) (xy 460.77336 -239.482958) (xy 460.779368 -239.483138) (xy 463.018124 -239.483138)
			(xy 463.026252 -239.482376) (xy 463.02676 -239.482376) (xy 463.034276 -239.480771) (xy 463.047957 -239.473787)
			(xy 463.053684 -239.46866) (xy 463.230214 -239.29213) (xy 463.232919 -239.289279) (xy 463.237512 -239.2829)
			(xy 463.239358 -239.27943) (xy 463.24194 -239.274003) (xy 463.24476 -239.262323) (xy 463.244946 -239.256316)
			(xy 463.244946 -136.061958) (xy 463.24478 -136.055948) (xy 463.241961 -136.044264) (xy 463.239358 -136.038844)
			(xy 463.237515 -136.035372) (xy 463.232915 -136.028999) (xy 463.230214 -136.026144) (xy 462.31175 -135.10768)
			(xy 462.308899 -135.104974) (xy 462.302521 -135.10038) (xy 462.29905 -135.098536) (xy 462.293623 -135.095952)
			(xy 462.281944 -135.093128) (xy 462.275936 -135.092948) (xy 440.6392 -135.092948) (xy 440.629131 -135.092523)
			(xy 440.610531 -135.084803) (xy 440.603132 -135.077962) (xy 438.428892 -132.903722) (xy 438.422059 -132.896319)
			(xy 438.414354 -132.877721) (xy 438.413906 -132.867654) (xy 438.413906 -122.64009) (xy 438.413652 -122.634248)
			(xy 438.411811 -122.623431) (xy 438.400342 -122.604754) (xy 438.391554 -122.59818) (xy 438.322974 -122.551952)
			(xy 438.322466 -122.551952) (xy 438.31383 -122.54611) (xy 438.303416 -122.544078) (xy 438.298242 -122.543172)
			(xy 438.287739 -122.5433) (xy 438.282588 -122.544332) (xy 438.274968 -122.54611) (xy 438.271412 -122.54738)
			(xy 438.249282 -122.555658) (xy 438.203489 -122.567301) (xy 438.156607 -122.573185) (xy 438.132982 -122.573542)
			(xy 438.13222 -122.573542) (xy 438.104967 -122.573058) (xy 438.051015 -122.565304) (xy 437.998716 -122.549951)
			(xy 437.949134 -122.527311) (xy 437.903279 -122.497846) (xy 437.862083 -122.462155) (xy 437.826387 -122.420964)
			(xy 437.796915 -122.375113) (xy 437.774268 -122.325535) (xy 437.758908 -122.273238) (xy 437.751146 -122.219287)
			(xy 437.750712 -122.192034) (xy 437.751188 -122.164666) (xy 437.759021 -122.110492) (xy 437.774516 -122.057994)
			(xy 437.797354 -122.00825) (xy 437.827068 -121.96228) (xy 437.844692 -121.941336) (xy 437.850788 -121.934224)
			(xy 437.853836 -121.926096) (xy 437.85538 -121.921748) (xy 437.857043 -121.912675) (xy 437.857138 -121.908062)
			(xy 437.857138 -121.841006) (xy 437.85704 -121.836393) (xy 437.855384 -121.827318) (xy 437.853836 -121.822972)
			(xy 437.850788 -121.814844) (xy 437.844692 -121.807732) (xy 437.82705 -121.786799) (xy 437.797323 -121.740829)
			(xy 437.774475 -121.691082) (xy 437.758976 -121.638578) (xy 437.751144 -121.584397) (xy 437.751141 -121.529654)
			(xy 437.758965 -121.475472) (xy 437.774457 -121.422966) (xy 437.797299 -121.373216) (xy 437.827019 -121.327242)
			(xy 437.844692 -121.306336) (xy 437.850788 -121.299224) (xy 437.853836 -121.291096) (xy 437.85538 -121.286748)
			(xy 437.857043 -121.277675) (xy 437.857138 -121.273062) (xy 437.857138 -121.206006) (xy 437.85704 -121.201393)
			(xy 437.855384 -121.192318) (xy 437.853836 -121.187972) (xy 437.850788 -121.179844) (xy 437.844692 -121.172732)
			(xy 437.82705 -121.151799) (xy 437.797323 -121.105829) (xy 437.774475 -121.056082) (xy 437.758976 -121.003578)
			(xy 437.751144 -120.949397) (xy 437.751141 -120.894654) (xy 437.758965 -120.840472) (xy 437.774457 -120.787966)
			(xy 437.797299 -120.738216) (xy 437.827019 -120.692242) (xy 437.844692 -120.671336) (xy 437.850788 -120.664224)
			(xy 437.853836 -120.656096) (xy 437.85538 -120.651748) (xy 437.857043 -120.642675) (xy 437.857138 -120.638062)
			(xy 437.857138 -120.571006) (xy 437.85704 -120.566393) (xy 437.855384 -120.557318) (xy 437.853836 -120.552972)
			(xy 437.850788 -120.544844) (xy 437.844692 -120.537732) (xy 437.827049 -120.516801) (xy 437.797319 -120.470835)
			(xy 437.774472 -120.421089) (xy 437.758978 -120.368585) (xy 437.751155 -120.314405) (xy 437.750712 -120.287034)
			(xy 437.751173 -120.25978) (xy 437.758926 -120.205827) (xy 437.774279 -120.153526) (xy 437.79692 -120.103943)
			(xy 437.826388 -120.058087) (xy 437.862082 -120.016892) (xy 437.903275 -119.981196) (xy 437.94913 -119.951727)
			(xy 437.998713 -119.929084) (xy 438.051013 -119.913729) (xy 438.104966 -119.905974) (xy 438.13222 -119.905526)
			(xy 438.132474 -119.905526) (xy 438.156005 -119.905892) (xy 438.202705 -119.911716) (xy 438.248334 -119.923242)
			(xy 438.270396 -119.931434) (xy 438.274714 -119.932958) (xy 438.283858 -119.934736) (xy 438.285382 -119.93499)
			(xy 438.296558 -119.937022) (xy 438.316878 -119.93118) (xy 438.323482 -119.926608) (xy 438.391554 -119.880888)
			(xy 438.401531 -119.873408) (xy 438.413254 -119.851431) (xy 438.413906 -119.838978) (xy 438.413906 -117.0813)
			(xy 438.413432 -117.071332) (xy 438.405862 -117.05289) (xy 438.399174 -117.045486) (xy 438.366408 -117.01272)
			(xy 438.340754 -116.986812) (xy 438.334363 -116.980878) (xy 438.318649 -116.973345) (xy 438.31002 -116.97208)
			(xy 438.301638 -116.971318) (xy 438.284874 -116.975382) (xy 438.281064 -116.977668) (xy 438.27573 -116.981478)
			(xy 438.251461 -116.997942) (xy 438.198934 -117.024022) (xy 438.143039 -117.041765) (xy 438.085088 -117.050755)
			(xy 438.055766 -117.051328) (xy 438.055258 -117.051328) (xy 438.028008 -117.050839) (xy 437.974064 -117.043078)
			(xy 437.921773 -117.02772) (xy 437.8722 -117.005076) (xy 437.826353 -116.975609) (xy 437.785166 -116.939918)
			(xy 437.749478 -116.898729) (xy 437.720013 -116.852881) (xy 437.697373 -116.803306) (xy 437.682017 -116.751015)
			(xy 437.674259 -116.69707) (xy 437.67375 -116.66982) (xy 437.674324 -116.640731) (xy 437.683199 -116.583233)
			(xy 437.700688 -116.527745) (xy 437.726385 -116.475549) (xy 437.742584 -116.45138) (xy 437.743854 -116.449602)
			(xy 437.745124 -116.44757) (xy 437.750738 -116.437703) (xy 437.753578 -116.41521) (xy 437.74643 -116.393695)
			(xy 437.739028 -116.385086) (xy 437.256682 -115.902994) (xy 436.300118 -114.94643) (xy 436.29639 -114.942904)
			(xy 436.28782 -114.937265) (xy 436.2831 -114.935254) (xy 436.274464 -114.931698) (xy 436.256176 -114.931698)
			(xy 436.24838 -114.931933) (xy 436.233501 -114.936584) (xy 436.226966 -114.940842) (xy 436.22087 -114.94516)
			(xy 436.211472 -114.957352) (xy 436.208678 -114.964972) (xy 436.178198 -115.047268) (xy 436.177182 -115.049808)
			(xy 436.175092 -115.057149) (xy 436.174962 -115.072405) (xy 436.176928 -115.07978) (xy 436.18023 -115.088416)
			(xy 436.183786 -115.096036) (xy 436.186072 -115.101116) (xy 436.197756 -115.11661) (xy 436.201312 -115.119912)
			(xy 436.220329 -115.138063) (xy 436.253705 -115.17868) (xy 436.281201 -115.223486) (xy 436.302298 -115.271638)
			(xy 436.316598 -115.322226) (xy 436.323831 -115.374297) (xy 436.324248 -115.400582) (xy 436.324248 -115.400836)
			(xy 436.323762 -115.428087) (xy 436.316006 -115.482035) (xy 436.300651 -115.53433) (xy 436.278009 -115.583907)
			(xy 436.248543 -115.629757) (xy 436.212852 -115.670948) (xy 436.171661 -115.706639) (xy 436.125811 -115.736105)
			(xy 436.076234 -115.758747) (xy 436.023939 -115.774102) (xy 435.969991 -115.781858) (xy 435.915489 -115.781858)
			(xy 435.861541 -115.774102) (xy 435.809246 -115.758747) (xy 435.759669 -115.736105) (xy 435.713819 -115.706639)
			(xy 435.672628 -115.670948) (xy 435.636937 -115.629757) (xy 435.607471 -115.583907) (xy 435.584829 -115.53433)
			(xy 435.569474 -115.482035) (xy 435.561718 -115.428087) (xy 435.561232 -115.400836) (xy 435.561674 -115.374143)
			(xy 435.569103 -115.321276) (xy 435.583821 -115.269959) (xy 435.605541 -115.221192) (xy 435.633841 -115.175924)
			(xy 435.668168 -115.135037) (xy 435.687724 -115.116864) (xy 435.695598 -115.109752) (xy 435.708044 -115.082066)
			(xy 435.708806 -115.079272) (xy 435.710584 -115.06835) (xy 435.710806 -115.063045) (xy 435.709271 -115.05254)
			(xy 435.707536 -115.047522) (xy 435.701186 -115.030504) (xy 435.701186 -115.029996) (xy 435.682136 -114.97945)
			(xy 435.676548 -114.964464) (xy 435.673549 -114.957279) (xy 435.663979 -114.945008) (xy 435.657752 -114.940334)
			(xy 435.651656 -114.93627) (xy 435.637432 -114.931698) (xy 423.800524 -114.931698) (xy 423.788078 -114.933222)
			(xy 423.777156 -114.936016) (xy 423.766742 -114.939826) (xy 423.753026 -114.946684) (xy 423.741596 -114.955066)
			(xy 423.7355 -114.961162) (xy 423.733976 -114.96294) (xy 423.732452 -114.964972) (xy 423.729404 -114.968782)
			(xy 423.728388 -114.969798) (xy 423.727118 -114.971322) (xy 423.726102 -114.972592) (xy 423.722292 -114.977418)
			(xy 423.71645 -114.984276) (xy 423.713402 -114.99215) (xy 423.711886 -114.996439) (xy 423.710234 -115.005383)
			(xy 423.7101 -115.00993) (xy 423.7101 -115.076986) (xy 423.710198 -115.081599) (xy 423.711854 -115.090674)
			(xy 423.713402 -115.09502) (xy 423.71645 -115.103148) (xy 423.722546 -115.11026) (xy 423.740187 -115.131191)
			(xy 423.76991 -115.177158) (xy 423.792748 -115.226905) (xy 423.808233 -115.279409) (xy 423.816044 -115.333588)
			(xy 423.816526 -115.360958) (xy 423.816066 -115.388213) (xy 423.808314 -115.44217) (xy 423.792962 -115.494474)
			(xy 423.770322 -115.54406) (xy 423.740855 -115.58992) (xy 423.705162 -115.631119) (xy 423.663968 -115.666819)
			(xy 423.618113 -115.696293) (xy 423.56853 -115.718941) (xy 423.516229 -115.734301) (xy 423.462273 -115.742062)
			(xy 423.435018 -115.742466) (xy 423.40765 -115.741988) (xy 423.353478 -115.734154) (xy 423.300982 -115.718656)
			(xy 423.25124 -115.695815) (xy 423.205273 -115.666099) (xy 423.18432 -115.648486) (xy 423.177208 -115.64239)
			(xy 423.16908 -115.639342) (xy 423.164732 -115.6378) (xy 423.155658 -115.63614) (xy 423.151046 -115.63604)
			(xy 423.08399 -115.63604) (xy 423.079378 -115.636141) (xy 423.070304 -115.637802) (xy 423.065956 -115.639342)
			(xy 423.057828 -115.64239) (xy 423.050716 -115.648486) (xy 423.029785 -115.666129) (xy 422.983819 -115.695859)
			(xy 422.934073 -115.718705) (xy 422.881569 -115.734198) (xy 422.827389 -115.742019) (xy 422.800018 -115.742466)
			(xy 422.772765 -115.742004) (xy 422.718815 -115.734249) (xy 422.666517 -115.718894) (xy 422.616937 -115.696252)
			(xy 422.571085 -115.666784) (xy 422.529894 -115.631089) (xy 422.494202 -115.589896) (xy 422.464737 -115.544041)
			(xy 422.442098 -115.49446) (xy 422.426746 -115.442162) (xy 422.418994 -115.388211) (xy 422.41851 -115.360958)
			(xy 422.418985 -115.333589) (xy 422.426814 -115.279414) (xy 422.442306 -115.226914) (xy 422.465143 -115.177167)
			(xy 422.494855 -115.131195) (xy 422.51249 -115.11026) (xy 422.518586 -115.103148) (xy 422.521634 -115.09502)
			(xy 422.52318 -115.090673) (xy 422.524848 -115.081599) (xy 422.524936 -115.076986) (xy 422.524936 -115.014248)
			(xy 422.524682 -115.009168) (xy 422.522396 -114.99596) (xy 422.521634 -114.99215) (xy 422.518332 -114.983514)
			(xy 422.516046 -114.98072) (xy 422.511474 -114.97564) (xy 422.499028 -114.960908) (xy 422.494964 -114.955828)
			(xy 422.487852 -114.949732) (xy 422.460674 -114.936016) (xy 422.456725 -114.934378) (xy 422.448423 -114.932335)
			(xy 422.444164 -114.931952) (xy 422.4401 -114.931698) (xy 420.929562 -114.931698) (xy 420.922147 -114.931944)
			(xy 420.90794 -114.936194) (xy 420.901622 -114.94008) (xy 420.895526 -114.944144) (xy 420.886128 -114.95532)
			(xy 420.88308 -114.962432) (xy 420.871679 -114.98783) (xy 420.842599 -115.035301) (xy 420.806926 -115.078041)
			(xy 420.76542 -115.115141) (xy 420.718961 -115.145813) (xy 420.668538 -115.169406) (xy 420.61522 -115.185419)
			(xy 420.560141 -115.193512) (xy 420.504471 -115.193512) (xy 420.449392 -115.185419) (xy 420.396074 -115.169406)
			(xy 420.345651 -115.145813) (xy 420.299192 -115.115141) (xy 420.257686 -115.078041) (xy 420.222013 -115.035301)
			(xy 420.192933 -114.98783) (xy 420.181532 -114.962432) (xy 420.181532 -114.962178) (xy 420.178374 -114.955454)
			(xy 420.16882 -114.944089) (xy 420.162736 -114.939826) (xy 420.15664 -114.935762) (xy 420.14267 -114.931698)
			(xy 416.231324 -114.931698) (xy 416.222688 -114.93246) (xy 416.215068 -114.934492) (xy 416.201606 -114.939064)
			(xy 416.19424 -114.941604) (xy 416.188144 -114.945922) (xy 416.166066 -114.961075) (xy 416.118523 -114.98571)
			(xy 416.068001 -115.003455) (xy 416.04184 -115.009168) (xy 416.03168 -115.013486) (xy 416.031172 -115.013994)
			(xy 416.023044 -115.017296) (xy 416.016948 -115.022884) (xy 416.013871 -115.025784) (xy 416.008637 -115.032424)
			(xy 416.006534 -115.036092) (xy 416.000946 -115.046506) (xy 415.995866 -115.056412) (xy 415.99358 -115.06073)
			(xy 415.982658 -115.08105) (xy 415.970466 -115.103656) (xy 415.968 -115.108596) (xy 415.965056 -115.119234)
			(xy 415.964624 -115.124738) (xy 415.964116 -115.135152) (xy 415.96818 -115.145566) (xy 415.976534 -115.167855)
			(xy 415.988284 -115.213983) (xy 415.994223 -115.261212) (xy 415.994596 -115.285012) (xy 415.994596 -115.285774)
			(xy 415.99411 -115.313043) (xy 415.986348 -115.367027) (xy 415.970983 -115.419357) (xy 415.948326 -115.468967)
			(xy 415.91884 -115.514848) (xy 415.883125 -115.556065) (xy 415.841908 -115.59178) (xy 415.796027 -115.621266)
			(xy 415.746417 -115.643923) (xy 415.694087 -115.659288) (xy 415.640103 -115.66705) (xy 415.585565 -115.66705)
			(xy 415.531581 -115.659288) (xy 415.479251 -115.643923) (xy 415.429641 -115.621266) (xy 415.38376 -115.59178)
			(xy 415.342543 -115.556065) (xy 415.306828 -115.514848) (xy 415.277342 -115.468967) (xy 415.254685 -115.419357)
			(xy 415.23932 -115.367027) (xy 415.231558 -115.313043) (xy 415.231072 -115.285774) (xy 415.231513 -115.260317)
			(xy 415.23831 -115.209857) (xy 415.251742 -115.160745) (xy 415.271569 -115.113849) (xy 415.284158 -115.091718)
			(xy 415.288984 -115.080542) (xy 415.29508 -115.060222) (xy 415.295334 -115.047522) (xy 415.256472 -114.977926)
			(xy 415.25444 -114.974116) (xy 415.243264 -114.95405) (xy 415.237676 -114.947446) (xy 415.234244 -114.944001)
			(xy 415.22631 -114.938379) (xy 415.221928 -114.93627) (xy 415.214816 -114.933476) (xy 415.2011 -114.931698)
			(xy 415.057844 -114.931698) (xy 415.049486 -114.93208) (xy 415.033676 -114.93752) (xy 415.026856 -114.942366)
			(xy 415.020506 -114.947446) (xy 415.011108 -114.961416) (xy 415.009076 -114.969798) (xy 415.001659 -114.996799)
			(xy 414.979999 -115.048435) (xy 414.951025 -115.09635) (xy 414.91536 -115.139517) (xy 414.87377 -115.177009)
			(xy 414.827147 -115.20802) (xy 414.776492 -115.231884) (xy 414.722894 -115.248089) (xy 414.667503 -115.256288)
			(xy 414.639506 -115.256818) (xy 414.638998 -115.256818) (xy 414.612789 -115.256344) (xy 414.560874 -115.249093)
			(xy 414.510439 -115.234811) (xy 414.46243 -115.213764) (xy 414.439862 -115.20043) (xy 414.438846 -115.199922)
			(xy 414.433512 -115.19662) (xy 414.399476 -115.201192) (xy 413.751522 -115.849146) (xy 413.744716 -115.856493)
			(xy 413.736997 -115.874955) (xy 413.736536 -115.88496) (xy 413.736536 -116.44757) (xy 414.457132 -116.44757)
			(xy 414.461203 -116.391948) (xy 414.473329 -116.337511) (xy 414.493252 -116.28542) (xy 414.520548 -116.236785)
			(xy 414.554634 -116.192642) (xy 414.594783 -116.153933) (xy 414.640141 -116.121482) (xy 414.689741 -116.095981)
			(xy 414.742525 -116.077974) (xy 414.797368 -116.067844) (xy 414.853102 -116.065807) (xy 414.908539 -116.071907)
			(xy 414.962496 -116.086013) (xy 415.013825 -116.107825) (xy 415.061431 -116.136879) (xy 415.104299 -116.172554)
			(xy 415.141516 -116.214091) (xy 415.172289 -116.260604) (xy 415.195961 -116.311101) (xy 415.212029 -116.364508)
			(xy 415.220149 -116.419684) (xy 415.220658 -116.44757) (xy 415.220149 -116.475456) (xy 415.219879 -116.477288)
			(xy 419.604442 -116.477288) (xy 419.608513 -116.421666) (xy 419.620639 -116.367229) (xy 419.640562 -116.315138)
			(xy 419.667858 -116.266503) (xy 419.701944 -116.22236) (xy 419.742093 -116.183651) (xy 419.787451 -116.1512)
			(xy 419.837051 -116.125699) (xy 419.889835 -116.107692) (xy 419.944678 -116.097562) (xy 420.000412 -116.095525)
			(xy 420.055849 -116.101625) (xy 420.109806 -116.115731) (xy 420.161135 -116.137543) (xy 420.208741 -116.166597)
			(xy 420.251609 -116.202272) (xy 420.288826 -116.243809) (xy 420.319599 -116.290322) (xy 420.343271 -116.340819)
			(xy 420.359339 -116.394226) (xy 420.367459 -116.449402) (xy 420.367968 -116.477288) (xy 420.367459 -116.505174)
			(xy 420.359339 -116.56035) (xy 420.343271 -116.613757) (xy 420.319599 -116.664254) (xy 420.288826 -116.710767)
			(xy 420.251609 -116.752304) (xy 420.208741 -116.787979) (xy 420.161135 -116.817033) (xy 420.109806 -116.838845)
			(xy 420.055849 -116.852951) (xy 420.000412 -116.859051) (xy 419.944678 -116.857014) (xy 419.889835 -116.846884)
			(xy 419.837051 -116.828877) (xy 419.787451 -116.803376) (xy 419.742093 -116.770925) (xy 419.701944 -116.732216)
			(xy 419.667858 -116.688073) (xy 419.640562 -116.639438) (xy 419.620639 -116.587347) (xy 419.608513 -116.53291)
			(xy 419.604442 -116.477288) (xy 415.219879 -116.477288) (xy 415.212029 -116.530632) (xy 415.195961 -116.584039)
			(xy 415.172289 -116.634536) (xy 415.141516 -116.681049) (xy 415.104299 -116.722586) (xy 415.061431 -116.758261)
			(xy 415.013825 -116.787315) (xy 414.962496 -116.809127) (xy 414.908539 -116.823233) (xy 414.853102 -116.829333)
			(xy 414.797368 -116.827296) (xy 414.742525 -116.817166) (xy 414.689741 -116.799159) (xy 414.640141 -116.773658)
			(xy 414.594783 -116.741207) (xy 414.554634 -116.702498) (xy 414.520548 -116.658355) (xy 414.493252 -116.60972)
			(xy 414.473329 -116.557629) (xy 414.461203 -116.503192) (xy 414.457132 -116.44757) (xy 413.736536 -116.44757)
			(xy 413.736536 -117.723666) (xy 417.989764 -117.723666) (xy 417.993835 -117.668044) (xy 418.005961 -117.613607)
			(xy 418.025884 -117.561516) (xy 418.05318 -117.512881) (xy 418.087266 -117.468738) (xy 418.127415 -117.430029)
			(xy 418.172773 -117.397578) (xy 418.222373 -117.372077) (xy 418.275157 -117.35407) (xy 418.33 -117.34394)
			(xy 418.385734 -117.341903) (xy 418.441171 -117.348003) (xy 418.495128 -117.362109) (xy 418.546457 -117.383921)
			(xy 418.594063 -117.412975) (xy 418.636931 -117.44865) (xy 418.674148 -117.490187) (xy 418.704921 -117.5367)
			(xy 418.728593 -117.587197) (xy 418.744661 -117.640604) (xy 418.752781 -117.69578) (xy 418.75329 -117.723666)
			(xy 418.752781 -117.751552) (xy 418.744661 -117.806728) (xy 418.728593 -117.860135) (xy 418.704921 -117.910632)
			(xy 418.674148 -117.957145) (xy 418.636931 -117.998682) (xy 418.594063 -118.034357) (xy 418.546457 -118.063411)
			(xy 418.495128 -118.085223) (xy 418.441171 -118.099329) (xy 418.385734 -118.105429) (xy 418.33 -118.103392)
			(xy 418.275157 -118.093262) (xy 418.222373 -118.075255) (xy 418.172773 -118.049754) (xy 418.127415 -118.017303)
			(xy 418.087266 -117.978594) (xy 418.05318 -117.934451) (xy 418.025884 -117.885816) (xy 418.005961 -117.833725)
			(xy 417.993835 -117.779288) (xy 417.989764 -117.723666) (xy 413.736536 -117.723666) (xy 413.736536 -118.864126)
			(xy 413.736106 -118.874193) (xy 413.728378 -118.892784) (xy 413.72155 -118.900194) (xy 413.574738 -119.047006)
			(xy 413.570674 -119.051324) (xy 413.0548 -119.567198) (xy 414.899348 -119.567198) (xy 414.899348 -118.703598)
			(xy 414.899838 -118.673614) (xy 414.907666 -118.614158) (xy 414.923187 -118.556233) (xy 414.946136 -118.500829)
			(xy 414.97612 -118.448895) (xy 415.012626 -118.401319) (xy 415.055031 -118.358914) (xy 415.102607 -118.322408)
			(xy 415.154541 -118.292424) (xy 415.209945 -118.269475) (xy 415.26787 -118.253954) (xy 415.327326 -118.246126)
			(xy 415.387294 -118.246126) (xy 415.44675 -118.253954) (xy 415.504675 -118.269475) (xy 415.560079 -118.292424)
			(xy 415.612013 -118.322408) (xy 415.659589 -118.358914) (xy 415.701994 -118.401319) (xy 415.7385 -118.448895)
			(xy 415.768484 -118.500829) (xy 415.791433 -118.556233) (xy 415.806954 -118.614158) (xy 415.814782 -118.673614)
			(xy 415.815272 -118.703598) (xy 415.815272 -118.711218) (xy 418.109398 -118.711218) (xy 418.113469 -118.655596)
			(xy 418.125595 -118.601159) (xy 418.145518 -118.549068) (xy 418.172814 -118.500433) (xy 418.2069 -118.45629)
			(xy 418.247049 -118.417581) (xy 418.292407 -118.38513) (xy 418.342007 -118.359629) (xy 418.394791 -118.341622)
			(xy 418.449634 -118.331492) (xy 418.505368 -118.329455) (xy 418.560805 -118.335555) (xy 418.614762 -118.349661)
			(xy 418.666091 -118.371473) (xy 418.713697 -118.400527) (xy 418.756565 -118.436202) (xy 418.793782 -118.477739)
			(xy 418.824555 -118.524252) (xy 418.848227 -118.574749) (xy 418.864295 -118.628156) (xy 418.872415 -118.683332)
			(xy 418.872924 -118.711218) (xy 418.872415 -118.739104) (xy 418.864295 -118.79428) (xy 418.848227 -118.847687)
			(xy 418.824555 -118.898184) (xy 418.793782 -118.944697) (xy 418.756565 -118.986234) (xy 418.713697 -119.021909)
			(xy 418.666091 -119.050963) (xy 418.614762 -119.072775) (xy 418.560805 -119.086881) (xy 418.505368 -119.092981)
			(xy 418.449634 -119.090944) (xy 418.394791 -119.080814) (xy 418.342007 -119.062807) (xy 418.292407 -119.037306)
			(xy 418.247049 -119.004855) (xy 418.2069 -118.966146) (xy 418.172814 -118.922003) (xy 418.145518 -118.873368)
			(xy 418.125595 -118.821277) (xy 418.113469 -118.76684) (xy 418.109398 -118.711218) (xy 415.815272 -118.711218)
			(xy 415.815272 -119.567198) (xy 415.814782 -119.597182) (xy 415.806954 -119.656638) (xy 415.791433 -119.714563)
			(xy 415.768484 -119.769967) (xy 415.7385 -119.821901) (xy 415.701994 -119.869477) (xy 415.659589 -119.911882)
			(xy 415.612013 -119.948388) (xy 415.560079 -119.978372) (xy 415.504675 -120.001321) (xy 415.44675 -120.016842)
			(xy 415.387294 -120.02467) (xy 415.327326 -120.02467) (xy 415.26787 -120.016842) (xy 415.209945 -120.001321)
			(xy 415.154541 -119.978372) (xy 415.102607 -119.948388) (xy 415.055031 -119.911882) (xy 415.012626 -119.869477)
			(xy 414.97612 -119.821901) (xy 414.946136 -119.769967) (xy 414.923187 -119.714563) (xy 414.907666 -119.656638)
			(xy 414.899838 -119.597182) (xy 414.899348 -119.567198) (xy 413.0548 -119.567198) (xy 411.254702 -121.367296)
			(xy 413.045148 -121.367296) (xy 413.045148 -120.503696) (xy 413.045638 -120.473712) (xy 413.053466 -120.414256)
			(xy 413.068987 -120.356331) (xy 413.091936 -120.300927) (xy 413.12192 -120.248993) (xy 413.158426 -120.201417)
			(xy 413.200831 -120.159012) (xy 413.248407 -120.122506) (xy 413.300341 -120.092522) (xy 413.355745 -120.069573)
			(xy 413.41367 -120.054052) (xy 413.473126 -120.046224) (xy 413.533094 -120.046224) (xy 413.59255 -120.054052)
			(xy 413.650475 -120.069573) (xy 413.705879 -120.092522) (xy 413.757813 -120.122506) (xy 413.805389 -120.159012)
			(xy 413.847794 -120.201417) (xy 413.8843 -120.248993) (xy 413.914284 -120.300927) (xy 413.937233 -120.356331)
			(xy 413.952754 -120.414256) (xy 413.960582 -120.473712) (xy 413.961072 -120.503696) (xy 413.961072 -121.367296)
			(xy 413.960582 -121.39728) (xy 413.952754 -121.456736) (xy 413.937233 -121.514661) (xy 413.914284 -121.570065)
			(xy 413.8843 -121.621999) (xy 413.847794 -121.669575) (xy 413.805389 -121.71198) (xy 413.757813 -121.748486)
			(xy 413.705879 -121.77847) (xy 413.650475 -121.801419) (xy 413.59255 -121.81694) (xy 413.533094 -121.824768)
			(xy 413.473126 -121.824768) (xy 413.41367 -121.81694) (xy 413.355745 -121.801419) (xy 413.300341 -121.77847)
			(xy 413.248407 -121.748486) (xy 413.200831 -121.71198) (xy 413.158426 -121.669575) (xy 413.12192 -121.621999)
			(xy 413.091936 -121.570065) (xy 413.068987 -121.514661) (xy 413.053466 -121.456736) (xy 413.045638 -121.39728)
			(xy 413.045148 -121.367296) (xy 411.254702 -121.367296) (xy 409.454858 -123.16714) (xy 414.899348 -123.16714)
			(xy 414.899348 -122.30354) (xy 414.899838 -122.273556) (xy 414.907666 -122.2141) (xy 414.923187 -122.156175)
			(xy 414.946136 -122.100771) (xy 414.97612 -122.048837) (xy 415.012626 -122.001261) (xy 415.055031 -121.958856)
			(xy 415.102607 -121.92235) (xy 415.154541 -121.892366) (xy 415.209945 -121.869417) (xy 415.26787 -121.853896)
			(xy 415.327326 -121.846068) (xy 415.387294 -121.846068) (xy 415.44675 -121.853896) (xy 415.504675 -121.869417)
			(xy 415.560079 -121.892366) (xy 415.612013 -121.92235) (xy 415.659589 -121.958856) (xy 415.701994 -122.001261)
			(xy 415.7385 -122.048837) (xy 415.768484 -122.100771) (xy 415.791433 -122.156175) (xy 415.806954 -122.2141)
			(xy 415.814782 -122.273556) (xy 415.815272 -122.30354) (xy 415.815272 -123.16714) (xy 415.814782 -123.197124)
			(xy 415.806954 -123.25658) (xy 415.791433 -123.314505) (xy 415.768484 -123.369909) (xy 415.7385 -123.421843)
			(xy 415.701994 -123.469419) (xy 415.659589 -123.511824) (xy 415.612013 -123.54833) (xy 415.560079 -123.578314)
			(xy 415.504675 -123.601263) (xy 415.44675 -123.616784) (xy 415.387294 -123.624612) (xy 415.327326 -123.624612)
			(xy 415.26787 -123.616784) (xy 415.209945 -123.601263) (xy 415.154541 -123.578314) (xy 415.102607 -123.54833)
			(xy 415.055031 -123.511824) (xy 415.012626 -123.469419) (xy 414.97612 -123.421843) (xy 414.946136 -123.369909)
			(xy 414.923187 -123.314505) (xy 414.907666 -123.25658) (xy 414.899838 -123.197124) (xy 414.899348 -123.16714)
			(xy 409.454858 -123.16714) (xy 408.032204 -124.589794) (xy 408.026018 -124.596541) (xy 408.018484 -124.613207)
			(xy 408.017472 -124.622306) (xy 408.017472 -124.967238) (xy 413.045148 -124.967238) (xy 413.045148 -124.103638)
			(xy 413.045638 -124.073654) (xy 413.053466 -124.014198) (xy 413.068987 -123.956273) (xy 413.091936 -123.900869)
			(xy 413.12192 -123.848935) (xy 413.158426 -123.801359) (xy 413.200831 -123.758954) (xy 413.248407 -123.722448)
			(xy 413.300341 -123.692464) (xy 413.355745 -123.669515) (xy 413.41367 -123.653994) (xy 413.473126 -123.646166)
			(xy 413.533094 -123.646166) (xy 413.59255 -123.653994) (xy 413.650475 -123.669515) (xy 413.705879 -123.692464)
			(xy 413.757813 -123.722448) (xy 413.805389 -123.758954) (xy 413.847794 -123.801359) (xy 413.8843 -123.848935)
			(xy 413.914284 -123.900869) (xy 413.937233 -123.956273) (xy 413.952754 -124.014198) (xy 413.960582 -124.073654)
			(xy 413.961072 -124.103638) (xy 413.961072 -124.967238) (xy 413.960582 -124.997222) (xy 413.952754 -125.056678)
			(xy 413.937233 -125.114603) (xy 413.914284 -125.170007) (xy 413.8843 -125.221941) (xy 413.847794 -125.269517)
			(xy 413.805389 -125.311922) (xy 413.757813 -125.348428) (xy 413.705879 -125.378412) (xy 413.650475 -125.401361)
			(xy 413.59255 -125.416882) (xy 413.533094 -125.42471) (xy 413.473126 -125.42471) (xy 413.41367 -125.416882)
			(xy 413.355745 -125.401361) (xy 413.300341 -125.378412) (xy 413.248407 -125.348428) (xy 413.200831 -125.311922)
			(xy 413.158426 -125.269517) (xy 413.12192 -125.221941) (xy 413.091936 -125.170007) (xy 413.068987 -125.114603)
			(xy 413.053466 -125.056678) (xy 413.045638 -124.997222) (xy 413.045148 -124.967238) (xy 408.017472 -124.967238)
			(xy 408.017472 -130.777234) (xy 414.899348 -130.777234) (xy 414.899348 -129.913634) (xy 414.899838 -129.88365)
			(xy 414.907666 -129.824194) (xy 414.923187 -129.766269) (xy 414.946136 -129.710865) (xy 414.97612 -129.658931)
			(xy 415.012626 -129.611355) (xy 415.055031 -129.56895) (xy 415.102607 -129.532444) (xy 415.154541 -129.50246)
			(xy 415.209945 -129.479511) (xy 415.26787 -129.46399) (xy 415.327326 -129.456162) (xy 415.387294 -129.456162)
			(xy 415.44675 -129.46399) (xy 415.504675 -129.479511) (xy 415.560079 -129.50246) (xy 415.612013 -129.532444)
			(xy 415.659589 -129.56895) (xy 415.701994 -129.611355) (xy 415.7385 -129.658931) (xy 415.768484 -129.710865)
			(xy 415.791433 -129.766269) (xy 415.806954 -129.824194) (xy 415.814782 -129.88365) (xy 415.815272 -129.913634)
			(xy 415.815272 -130.777234) (xy 415.814782 -130.807218) (xy 415.806954 -130.866674) (xy 415.791433 -130.924599)
			(xy 415.768484 -130.980003) (xy 415.7385 -131.031937) (xy 415.701994 -131.079513) (xy 415.659589 -131.121918)
			(xy 415.612013 -131.158424) (xy 415.560079 -131.188408) (xy 415.504675 -131.211357) (xy 415.44675 -131.226878)
			(xy 415.387294 -131.234706) (xy 415.327326 -131.234706) (xy 415.26787 -131.226878) (xy 415.209945 -131.211357)
			(xy 415.154541 -131.188408) (xy 415.102607 -131.158424) (xy 415.055031 -131.121918) (xy 415.012626 -131.079513)
			(xy 414.97612 -131.031937) (xy 414.946136 -130.980003) (xy 414.923187 -130.924599) (xy 414.907666 -130.866674)
			(xy 414.899838 -130.807218) (xy 414.899348 -130.777234) (xy 408.017472 -130.777234) (xy 408.017472 -132.577332)
			(xy 413.045148 -132.577332) (xy 413.045148 -131.713732) (xy 413.045638 -131.683748) (xy 413.053466 -131.624292)
			(xy 413.068987 -131.566367) (xy 413.091936 -131.510963) (xy 413.12192 -131.459029) (xy 413.158426 -131.411453)
			(xy 413.200831 -131.369048) (xy 413.248407 -131.332542) (xy 413.300341 -131.302558) (xy 413.355745 -131.279609)
			(xy 413.41367 -131.264088) (xy 413.473126 -131.25626) (xy 413.533094 -131.25626) (xy 413.59255 -131.264088)
			(xy 413.650475 -131.279609) (xy 413.705879 -131.302558) (xy 413.757813 -131.332542) (xy 413.805389 -131.369048)
			(xy 413.847794 -131.411453) (xy 413.8843 -131.459029) (xy 413.914284 -131.510963) (xy 413.937233 -131.566367)
			(xy 413.952754 -131.624292) (xy 413.960582 -131.683748) (xy 413.961072 -131.713732) (xy 413.961072 -132.577332)
			(xy 413.960582 -132.607316) (xy 413.952754 -132.666772) (xy 413.937233 -132.724697) (xy 413.914284 -132.780101)
			(xy 413.8843 -132.832035) (xy 413.847794 -132.879611) (xy 413.805389 -132.922016) (xy 413.757813 -132.958522)
			(xy 413.705879 -132.988506) (xy 413.650475 -133.011455) (xy 413.59255 -133.026976) (xy 413.533094 -133.034804)
			(xy 413.473126 -133.034804) (xy 413.41367 -133.026976) (xy 413.355745 -133.011455) (xy 413.300341 -132.988506)
			(xy 413.248407 -132.958522) (xy 413.200831 -132.922016) (xy 413.158426 -132.879611) (xy 413.12192 -132.832035)
			(xy 413.091936 -132.780101) (xy 413.068987 -132.724697) (xy 413.053466 -132.666772) (xy 413.045638 -132.607316)
			(xy 413.045148 -132.577332) (xy 408.017472 -132.577332) (xy 408.017472 -134.377176) (xy 414.899348 -134.377176)
			(xy 414.899348 -133.513576) (xy 414.899838 -133.483592) (xy 414.907666 -133.424136) (xy 414.923187 -133.366211)
			(xy 414.946136 -133.310807) (xy 414.97612 -133.258873) (xy 415.012626 -133.211297) (xy 415.055031 -133.168892)
			(xy 415.102607 -133.132386) (xy 415.154541 -133.102402) (xy 415.209945 -133.079453) (xy 415.26787 -133.063932)
			(xy 415.327326 -133.056104) (xy 415.387294 -133.056104) (xy 415.44675 -133.063932) (xy 415.504675 -133.079453)
			(xy 415.560079 -133.102402) (xy 415.612013 -133.132386) (xy 415.659589 -133.168892) (xy 415.701994 -133.211297)
			(xy 415.7385 -133.258873) (xy 415.768484 -133.310807) (xy 415.791433 -133.366211) (xy 415.806954 -133.424136)
			(xy 415.814782 -133.483592) (xy 415.815272 -133.513576) (xy 415.815272 -134.377176) (xy 415.814782 -134.40716)
			(xy 415.806954 -134.466616) (xy 415.791433 -134.524541) (xy 415.768484 -134.579945) (xy 415.7385 -134.631879)
			(xy 415.701994 -134.679455) (xy 415.659589 -134.72186) (xy 415.612013 -134.758366) (xy 415.560079 -134.78835)
			(xy 415.504675 -134.811299) (xy 415.44675 -134.82682) (xy 415.387294 -134.834648) (xy 415.327326 -134.834648)
			(xy 415.26787 -134.82682) (xy 415.209945 -134.811299) (xy 415.154541 -134.78835) (xy 415.102607 -134.758366)
			(xy 415.055031 -134.72186) (xy 415.012626 -134.679455) (xy 414.97612 -134.631879) (xy 414.946136 -134.579945)
			(xy 414.923187 -134.524541) (xy 414.907666 -134.466616) (xy 414.899838 -134.40716) (xy 414.899348 -134.377176)
			(xy 408.017472 -134.377176) (xy 408.017472 -136.177274) (xy 413.045148 -136.177274) (xy 413.045148 -135.313674)
			(xy 413.045638 -135.28369) (xy 413.053466 -135.224234) (xy 413.068987 -135.166309) (xy 413.091936 -135.110905)
			(xy 413.12192 -135.058971) (xy 413.158426 -135.011395) (xy 413.200831 -134.96899) (xy 413.248407 -134.932484)
			(xy 413.300341 -134.9025) (xy 413.355745 -134.879551) (xy 413.41367 -134.86403) (xy 413.473126 -134.856202)
			(xy 413.533094 -134.856202) (xy 413.59255 -134.86403) (xy 413.650475 -134.879551) (xy 413.705879 -134.9025)
			(xy 413.757813 -134.932484) (xy 413.805389 -134.96899) (xy 413.847794 -135.011395) (xy 413.8843 -135.058971)
			(xy 413.914284 -135.110905) (xy 413.937233 -135.166309) (xy 413.952754 -135.224234) (xy 413.960582 -135.28369)
			(xy 413.961072 -135.313674) (xy 413.961072 -136.177274) (xy 413.960582 -136.207258) (xy 413.952754 -136.266714)
			(xy 413.937233 -136.324639) (xy 413.914284 -136.380043) (xy 413.8843 -136.431977) (xy 413.847794 -136.479553)
			(xy 413.805389 -136.521958) (xy 413.757813 -136.558464) (xy 413.705879 -136.588448) (xy 413.650475 -136.611397)
			(xy 413.59255 -136.626918) (xy 413.533094 -136.634746) (xy 413.473126 -136.634746) (xy 413.41367 -136.626918)
			(xy 413.355745 -136.611397) (xy 413.300341 -136.588448) (xy 413.248407 -136.558464) (xy 413.200831 -136.521958)
			(xy 413.158426 -136.479553) (xy 413.12192 -136.431977) (xy 413.091936 -136.380043) (xy 413.068987 -136.324639)
			(xy 413.053466 -136.266714) (xy 413.045638 -136.207258) (xy 413.045148 -136.177274) (xy 408.017472 -136.177274)
			(xy 408.017472 -137.848848) (xy 410.23997 -137.848848) (xy 410.244041 -137.793226) (xy 410.256167 -137.738789)
			(xy 410.27609 -137.686698) (xy 410.303386 -137.638063) (xy 410.337472 -137.59392) (xy 410.377621 -137.555211)
			(xy 410.422979 -137.52276) (xy 410.472579 -137.497259) (xy 410.525363 -137.479252) (xy 410.580206 -137.469122)
			(xy 410.63594 -137.467085) (xy 410.691377 -137.473185) (xy 410.745334 -137.487291) (xy 410.796663 -137.509103)
			(xy 410.844269 -137.538157) (xy 410.887137 -137.573832) (xy 410.924354 -137.615369) (xy 410.955127 -137.661882)
			(xy 410.978799 -137.712379) (xy 410.994867 -137.765786) (xy 411.002987 -137.820962) (xy 411.003496 -137.848848)
			(xy 411.002987 -137.876734) (xy 410.994867 -137.93191) (xy 410.978799 -137.985317) (xy 410.955127 -138.035814)
			(xy 410.924354 -138.082327) (xy 410.887137 -138.123864) (xy 410.844269 -138.159539) (xy 410.796663 -138.188593)
			(xy 410.745334 -138.210405) (xy 410.691377 -138.224511) (xy 410.63594 -138.230611) (xy 410.580206 -138.228574)
			(xy 410.525363 -138.218444) (xy 410.472579 -138.200437) (xy 410.422979 -138.174936) (xy 410.377621 -138.142485)
			(xy 410.337472 -138.103776) (xy 410.303386 -138.059633) (xy 410.27609 -138.010998) (xy 410.256167 -137.958907)
			(xy 410.244041 -137.90447) (xy 410.23997 -137.848848) (xy 408.017472 -137.848848) (xy 408.017472 -138.864848)
			(xy 410.23997 -138.864848) (xy 410.244041 -138.809226) (xy 410.256167 -138.754789) (xy 410.27609 -138.702698)
			(xy 410.303386 -138.654063) (xy 410.337472 -138.60992) (xy 410.377621 -138.571211) (xy 410.422979 -138.53876)
			(xy 410.472579 -138.513259) (xy 410.525363 -138.495252) (xy 410.580206 -138.485122) (xy 410.63594 -138.483085)
			(xy 410.691377 -138.489185) (xy 410.745334 -138.503291) (xy 410.796663 -138.525103) (xy 410.844269 -138.554157)
			(xy 410.887137 -138.589832) (xy 410.924354 -138.631369) (xy 410.955127 -138.677882) (xy 410.978799 -138.728379)
			(xy 410.994867 -138.781786) (xy 411.002987 -138.836962) (xy 411.003496 -138.864848) (xy 411.002987 -138.892734)
			(xy 410.994867 -138.94791) (xy 410.978799 -139.001317) (xy 410.955127 -139.051814) (xy 410.924354 -139.098327)
			(xy 410.887137 -139.139864) (xy 410.844269 -139.175539) (xy 410.796663 -139.204593) (xy 410.745334 -139.226405)
			(xy 410.691377 -139.240511) (xy 410.63594 -139.246611) (xy 410.580206 -139.244574) (xy 410.525363 -139.234444)
			(xy 410.472579 -139.216437) (xy 410.422979 -139.190936) (xy 410.377621 -139.158485) (xy 410.337472 -139.119776)
			(xy 410.303386 -139.075633) (xy 410.27609 -139.026998) (xy 410.256167 -138.974907) (xy 410.244041 -138.92047)
			(xy 410.23997 -138.864848) (xy 408.017472 -138.864848) (xy 408.017472 -143.48714) (xy 414.899348 -143.48714)
			(xy 414.899348 -142.62354) (xy 414.899838 -142.593556) (xy 414.907666 -142.5341) (xy 414.923187 -142.476175)
			(xy 414.946136 -142.420771) (xy 414.97612 -142.368837) (xy 415.012626 -142.321261) (xy 415.055031 -142.278856)
			(xy 415.102607 -142.24235) (xy 415.154541 -142.212366) (xy 415.209945 -142.189417) (xy 415.26787 -142.173896)
			(xy 415.327326 -142.166068) (xy 415.387294 -142.166068) (xy 415.44675 -142.173896) (xy 415.504675 -142.189417)
			(xy 415.560079 -142.212366) (xy 415.612013 -142.24235) (xy 415.659589 -142.278856) (xy 415.701994 -142.321261)
			(xy 415.7385 -142.368837) (xy 415.768484 -142.420771) (xy 415.791433 -142.476175) (xy 415.806954 -142.5341)
			(xy 415.814782 -142.593556) (xy 415.815272 -142.62354) (xy 415.815272 -143.48714) (xy 415.814782 -143.517124)
			(xy 415.806954 -143.57658) (xy 415.791433 -143.634505) (xy 415.768484 -143.689909) (xy 415.7385 -143.741843)
			(xy 415.701994 -143.789419) (xy 415.659589 -143.831824) (xy 415.612013 -143.86833) (xy 415.560079 -143.898314)
			(xy 415.504675 -143.921263) (xy 415.44675 -143.936784) (xy 415.387294 -143.944612) (xy 415.327326 -143.944612)
			(xy 415.26787 -143.936784) (xy 415.209945 -143.921263) (xy 415.154541 -143.898314) (xy 415.102607 -143.86833)
			(xy 415.055031 -143.831824) (xy 415.012626 -143.789419) (xy 414.97612 -143.741843) (xy 414.946136 -143.689909)
			(xy 414.923187 -143.634505) (xy 414.907666 -143.57658) (xy 414.899838 -143.517124) (xy 414.899348 -143.48714)
			(xy 408.017472 -143.48714) (xy 408.017472 -145.287238) (xy 413.045148 -145.287238) (xy 413.045148 -144.423638)
			(xy 413.045638 -144.393654) (xy 413.053466 -144.334198) (xy 413.068987 -144.276273) (xy 413.091936 -144.220869)
			(xy 413.12192 -144.168935) (xy 413.158426 -144.121359) (xy 413.200831 -144.078954) (xy 413.248407 -144.042448)
			(xy 413.300341 -144.012464) (xy 413.355745 -143.989515) (xy 413.41367 -143.973994) (xy 413.473126 -143.966166)
			(xy 413.533094 -143.966166) (xy 413.59255 -143.973994) (xy 413.650475 -143.989515) (xy 413.705879 -144.012464)
			(xy 413.757813 -144.042448) (xy 413.805389 -144.078954) (xy 413.847794 -144.121359) (xy 413.8843 -144.168935)
			(xy 413.914284 -144.220869) (xy 413.937233 -144.276273) (xy 413.952754 -144.334198) (xy 413.960582 -144.393654)
			(xy 413.961072 -144.423638) (xy 413.961072 -145.287238) (xy 413.960582 -145.317222) (xy 413.952754 -145.376678)
			(xy 413.937233 -145.434603) (xy 413.914284 -145.490007) (xy 413.8843 -145.541941) (xy 413.847794 -145.589517)
			(xy 413.805389 -145.631922) (xy 413.757813 -145.668428) (xy 413.705879 -145.698412) (xy 413.650475 -145.721361)
			(xy 413.59255 -145.736882) (xy 413.533094 -145.74471) (xy 413.473126 -145.74471) (xy 413.41367 -145.736882)
			(xy 413.355745 -145.721361) (xy 413.300341 -145.698412) (xy 413.248407 -145.668428) (xy 413.200831 -145.631922)
			(xy 413.158426 -145.589517) (xy 413.12192 -145.541941) (xy 413.091936 -145.490007) (xy 413.068987 -145.434603)
			(xy 413.053466 -145.376678) (xy 413.045638 -145.317222) (xy 413.045148 -145.287238) (xy 408.017472 -145.287238)
			(xy 408.017472 -147.087336) (xy 414.899348 -147.087336) (xy 414.899348 -146.223736) (xy 414.899838 -146.193752)
			(xy 414.907666 -146.134296) (xy 414.923187 -146.076371) (xy 414.946136 -146.020967) (xy 414.97612 -145.969033)
			(xy 415.012626 -145.921457) (xy 415.055031 -145.879052) (xy 415.102607 -145.842546) (xy 415.154541 -145.812562)
			(xy 415.209945 -145.789613) (xy 415.26787 -145.774092) (xy 415.327326 -145.766264) (xy 415.387294 -145.766264)
			(xy 415.44675 -145.774092) (xy 415.504675 -145.789613) (xy 415.560079 -145.812562) (xy 415.612013 -145.842546)
			(xy 415.659589 -145.879052) (xy 415.701994 -145.921457) (xy 415.7385 -145.969033) (xy 415.768484 -146.020967)
			(xy 415.791433 -146.076371) (xy 415.806954 -146.134296) (xy 415.814782 -146.193752) (xy 415.815272 -146.223736)
			(xy 415.815272 -147.087336) (xy 415.814782 -147.11732) (xy 415.806954 -147.176776) (xy 415.791433 -147.234701)
			(xy 415.768484 -147.290105) (xy 415.7385 -147.342039) (xy 415.701994 -147.389615) (xy 415.659589 -147.43202)
			(xy 415.612013 -147.468526) (xy 415.560079 -147.49851) (xy 415.504675 -147.521459) (xy 415.44675 -147.53698)
			(xy 415.387294 -147.544808) (xy 415.327326 -147.544808) (xy 415.26787 -147.53698) (xy 415.209945 -147.521459)
			(xy 415.154541 -147.49851) (xy 415.102607 -147.468526) (xy 415.055031 -147.43202) (xy 415.012626 -147.389615)
			(xy 414.97612 -147.342039) (xy 414.946136 -147.290105) (xy 414.923187 -147.234701) (xy 414.907666 -147.176776)
			(xy 414.899838 -147.11732) (xy 414.899348 -147.087336) (xy 408.017472 -147.087336) (xy 408.017472 -148.887434)
			(xy 413.045148 -148.887434) (xy 413.045148 -148.023834) (xy 413.045638 -147.99385) (xy 413.053466 -147.934394)
			(xy 413.068987 -147.876469) (xy 413.091936 -147.821065) (xy 413.12192 -147.769131) (xy 413.158426 -147.721555)
			(xy 413.200831 -147.67915) (xy 413.248407 -147.642644) (xy 413.300341 -147.61266) (xy 413.355745 -147.589711)
			(xy 413.41367 -147.57419) (xy 413.473126 -147.566362) (xy 413.533094 -147.566362) (xy 413.59255 -147.57419)
			(xy 413.650475 -147.589711) (xy 413.705879 -147.61266) (xy 413.757813 -147.642644) (xy 413.805389 -147.67915)
			(xy 413.847794 -147.721555) (xy 413.8843 -147.769131) (xy 413.914284 -147.821065) (xy 413.937233 -147.876469)
			(xy 413.952754 -147.934394) (xy 413.960582 -147.99385) (xy 413.961072 -148.023834) (xy 413.961072 -148.887434)
			(xy 413.960582 -148.917418) (xy 413.952754 -148.976874) (xy 413.937233 -149.034799) (xy 413.914284 -149.090203)
			(xy 413.8843 -149.142137) (xy 413.847794 -149.189713) (xy 413.805389 -149.232118) (xy 413.757813 -149.268624)
			(xy 413.705879 -149.298608) (xy 413.650475 -149.321557) (xy 413.59255 -149.337078) (xy 413.533094 -149.344906)
			(xy 413.473126 -149.344906) (xy 413.41367 -149.337078) (xy 413.355745 -149.321557) (xy 413.300341 -149.298608)
			(xy 413.248407 -149.268624) (xy 413.200831 -149.232118) (xy 413.158426 -149.189713) (xy 413.12192 -149.142137)
			(xy 413.091936 -149.090203) (xy 413.068987 -149.034799) (xy 413.053466 -148.976874) (xy 413.045638 -148.917418)
			(xy 413.045148 -148.887434) (xy 408.017472 -148.887434) (xy 408.017472 -150.687278) (xy 414.899348 -150.687278)
			(xy 414.899348 -149.823678) (xy 414.899838 -149.793694) (xy 414.907666 -149.734238) (xy 414.923187 -149.676313)
			(xy 414.946136 -149.620909) (xy 414.97612 -149.568975) (xy 415.012626 -149.521399) (xy 415.055031 -149.478994)
			(xy 415.102607 -149.442488) (xy 415.154541 -149.412504) (xy 415.209945 -149.389555) (xy 415.26787 -149.374034)
			(xy 415.327326 -149.366206) (xy 415.387294 -149.366206) (xy 415.44675 -149.374034) (xy 415.504675 -149.389555)
			(xy 415.560079 -149.412504) (xy 415.612013 -149.442488) (xy 415.659589 -149.478994) (xy 415.701994 -149.521399)
			(xy 415.7385 -149.568975) (xy 415.768484 -149.620909) (xy 415.791433 -149.676313) (xy 415.806954 -149.734238)
			(xy 415.814782 -149.793694) (xy 415.815272 -149.823678) (xy 415.815272 -150.687278) (xy 415.814782 -150.717262)
			(xy 415.806954 -150.776718) (xy 415.791433 -150.834643) (xy 415.768484 -150.890047) (xy 415.7385 -150.941981)
			(xy 415.701994 -150.989557) (xy 415.659589 -151.031962) (xy 415.612013 -151.068468) (xy 415.560079 -151.098452)
			(xy 415.504675 -151.121401) (xy 415.44675 -151.136922) (xy 415.387294 -151.14475) (xy 415.327326 -151.14475)
			(xy 415.26787 -151.136922) (xy 415.209945 -151.121401) (xy 415.154541 -151.098452) (xy 415.102607 -151.068468)
			(xy 415.055031 -151.031962) (xy 415.012626 -150.989557) (xy 414.97612 -150.941981) (xy 414.946136 -150.890047)
			(xy 414.923187 -150.834643) (xy 414.907666 -150.776718) (xy 414.899838 -150.717262) (xy 414.899348 -150.687278)
			(xy 408.017472 -150.687278) (xy 408.017472 -152.487376) (xy 413.045148 -152.487376) (xy 413.045148 -151.623776)
			(xy 413.045638 -151.593792) (xy 413.053466 -151.534336) (xy 413.068987 -151.476411) (xy 413.091936 -151.421007)
			(xy 413.12192 -151.369073) (xy 413.158426 -151.321497) (xy 413.200831 -151.279092) (xy 413.248407 -151.242586)
			(xy 413.300341 -151.212602) (xy 413.355745 -151.189653) (xy 413.41367 -151.174132) (xy 413.473126 -151.166304)
			(xy 413.533094 -151.166304) (xy 413.59255 -151.174132) (xy 413.650475 -151.189653) (xy 413.705879 -151.212602)
			(xy 413.757813 -151.242586) (xy 413.805389 -151.279092) (xy 413.847794 -151.321497) (xy 413.8843 -151.369073)
			(xy 413.914284 -151.421007) (xy 413.937233 -151.476411) (xy 413.952754 -151.534336) (xy 413.960582 -151.593792)
			(xy 413.961072 -151.623776) (xy 413.961072 -152.487376) (xy 413.960582 -152.51736) (xy 413.952754 -152.576816)
			(xy 413.937233 -152.634741) (xy 413.914284 -152.690145) (xy 413.8843 -152.742079) (xy 413.847794 -152.789655)
			(xy 413.805389 -152.83206) (xy 413.757813 -152.868566) (xy 413.705879 -152.89855) (xy 413.650475 -152.921499)
			(xy 413.59255 -152.93702) (xy 413.533094 -152.944848) (xy 413.473126 -152.944848) (xy 413.41367 -152.93702)
			(xy 413.355745 -152.921499) (xy 413.300341 -152.89855) (xy 413.248407 -152.868566) (xy 413.200831 -152.83206)
			(xy 413.158426 -152.789655) (xy 413.12192 -152.742079) (xy 413.091936 -152.690145) (xy 413.068987 -152.634741)
			(xy 413.053466 -152.576816) (xy 413.045638 -152.51736) (xy 413.045148 -152.487376) (xy 408.017472 -152.487376)
			(xy 408.017472 -154.28722) (xy 414.899348 -154.28722) (xy 414.899348 -153.42362) (xy 414.899838 -153.393636)
			(xy 414.907666 -153.33418) (xy 414.923187 -153.276255) (xy 414.946136 -153.220851) (xy 414.97612 -153.168917)
			(xy 415.012626 -153.121341) (xy 415.055031 -153.078936) (xy 415.102607 -153.04243) (xy 415.154541 -153.012446)
			(xy 415.209945 -152.989497) (xy 415.26787 -152.973976) (xy 415.327326 -152.966148) (xy 415.387294 -152.966148)
			(xy 415.44675 -152.973976) (xy 415.504675 -152.989497) (xy 415.560079 -153.012446) (xy 415.612013 -153.04243)
			(xy 415.659589 -153.078936) (xy 415.701994 -153.121341) (xy 415.7385 -153.168917) (xy 415.768484 -153.220851)
			(xy 415.791433 -153.276255) (xy 415.806954 -153.33418) (xy 415.814782 -153.393636) (xy 415.815272 -153.42362)
			(xy 415.815272 -154.28722) (xy 415.814782 -154.317204) (xy 415.806954 -154.37666) (xy 415.791433 -154.434585)
			(xy 415.768484 -154.489989) (xy 415.7385 -154.541923) (xy 415.701994 -154.589499) (xy 415.659589 -154.631904)
			(xy 415.612013 -154.66841) (xy 415.560079 -154.698394) (xy 415.504675 -154.721343) (xy 415.44675 -154.736864)
			(xy 415.387294 -154.744692) (xy 415.327326 -154.744692) (xy 415.26787 -154.736864) (xy 415.209945 -154.721343)
			(xy 415.154541 -154.698394) (xy 415.102607 -154.66841) (xy 415.055031 -154.631904) (xy 415.012626 -154.589499)
			(xy 414.97612 -154.541923) (xy 414.946136 -154.489989) (xy 414.923187 -154.434585) (xy 414.907666 -154.37666)
			(xy 414.899838 -154.317204) (xy 414.899348 -154.28722) (xy 408.017472 -154.28722) (xy 408.017472 -155.549092)
			(xy 408.017218 -155.552394) (xy 408.017218 -155.88107) (xy 408.016783 -155.891135) (xy 408.009052 -155.909723)
			(xy 408.002232 -155.917138) (xy 407.832058 -156.087318) (xy 413.045148 -156.087318) (xy 413.045148 -155.223718)
			(xy 413.045638 -155.193734) (xy 413.053466 -155.134278) (xy 413.068987 -155.076353) (xy 413.091936 -155.020949)
			(xy 413.12192 -154.969015) (xy 413.158426 -154.921439) (xy 413.200831 -154.879034) (xy 413.248407 -154.842528)
			(xy 413.300341 -154.812544) (xy 413.355745 -154.789595) (xy 413.41367 -154.774074) (xy 413.473126 -154.766246)
			(xy 413.533094 -154.766246) (xy 413.59255 -154.774074) (xy 413.650475 -154.789595) (xy 413.705879 -154.812544)
			(xy 413.757813 -154.842528) (xy 413.805389 -154.879034) (xy 413.847794 -154.921439) (xy 413.8843 -154.969015)
			(xy 413.914284 -155.020949) (xy 413.937233 -155.076353) (xy 413.952754 -155.134278) (xy 413.960582 -155.193734)
			(xy 413.961072 -155.223718) (xy 413.961072 -156.087318) (xy 413.960582 -156.117302) (xy 413.952754 -156.176758)
			(xy 413.937233 -156.234683) (xy 413.914284 -156.290087) (xy 413.8843 -156.342021) (xy 413.847794 -156.389597)
			(xy 413.805389 -156.432002) (xy 413.757813 -156.468508) (xy 413.705879 -156.498492) (xy 413.650475 -156.521441)
			(xy 413.59255 -156.536962) (xy 413.533094 -156.54479) (xy 413.473126 -156.54479) (xy 413.41367 -156.536962)
			(xy 413.355745 -156.521441) (xy 413.300341 -156.498492) (xy 413.248407 -156.468508) (xy 413.200831 -156.432002)
			(xy 413.158426 -156.389597) (xy 413.12192 -156.342021) (xy 413.091936 -156.290087) (xy 413.068987 -156.234683)
			(xy 413.053466 -156.176758) (xy 413.045638 -156.117302) (xy 413.045148 -156.087318) (xy 407.832058 -156.087318)
			(xy 406.874255 -157.045152) (xy 409.710634 -157.045152) (xy 409.714705 -156.98953) (xy 409.726831 -156.935093)
			(xy 409.746754 -156.883002) (xy 409.77405 -156.834367) (xy 409.808136 -156.790224) (xy 409.848285 -156.751515)
			(xy 409.893643 -156.719064) (xy 409.943243 -156.693563) (xy 409.996027 -156.675556) (xy 410.05087 -156.665426)
			(xy 410.106604 -156.663389) (xy 410.162041 -156.669489) (xy 410.215998 -156.683595) (xy 410.267327 -156.705407)
			(xy 410.314933 -156.734461) (xy 410.357801 -156.770136) (xy 410.395018 -156.811673) (xy 410.425791 -156.858186)
			(xy 410.449463 -156.908683) (xy 410.465531 -156.96209) (xy 410.473651 -157.017266) (xy 410.47416 -157.045152)
			(xy 410.726634 -157.045152) (xy 410.730705 -156.98953) (xy 410.742831 -156.935093) (xy 410.762754 -156.883002)
			(xy 410.79005 -156.834367) (xy 410.824136 -156.790224) (xy 410.864285 -156.751515) (xy 410.909643 -156.719064)
			(xy 410.959243 -156.693563) (xy 411.012027 -156.675556) (xy 411.06687 -156.665426) (xy 411.122604 -156.663389)
			(xy 411.178041 -156.669489) (xy 411.231998 -156.683595) (xy 411.283327 -156.705407) (xy 411.330933 -156.734461)
			(xy 411.373801 -156.770136) (xy 411.411018 -156.811673) (xy 411.441791 -156.858186) (xy 411.465463 -156.908683)
			(xy 411.481531 -156.96209) (xy 411.489651 -157.017266) (xy 411.49016 -157.045152) (xy 411.489651 -157.073038)
			(xy 411.481531 -157.128214) (xy 411.465463 -157.181621) (xy 411.441791 -157.232118) (xy 411.411018 -157.278631)
			(xy 411.373801 -157.320168) (xy 411.330933 -157.355843) (xy 411.283327 -157.384897) (xy 411.231998 -157.406709)
			(xy 411.178041 -157.420815) (xy 411.122604 -157.426915) (xy 411.06687 -157.424878) (xy 411.012027 -157.414748)
			(xy 410.959243 -157.396741) (xy 410.909643 -157.37124) (xy 410.864285 -157.338789) (xy 410.824136 -157.30008)
			(xy 410.79005 -157.255937) (xy 410.762754 -157.207302) (xy 410.742831 -157.155211) (xy 410.730705 -157.100774)
			(xy 410.726634 -157.045152) (xy 410.47416 -157.045152) (xy 410.473651 -157.073038) (xy 410.465531 -157.128214)
			(xy 410.449463 -157.181621) (xy 410.425791 -157.232118) (xy 410.395018 -157.278631) (xy 410.357801 -157.320168)
			(xy 410.314933 -157.355843) (xy 410.267327 -157.384897) (xy 410.215998 -157.406709) (xy 410.162041 -157.420815)
			(xy 410.106604 -157.426915) (xy 410.05087 -157.424878) (xy 409.996027 -157.414748) (xy 409.943243 -157.396741)
			(xy 409.893643 -157.37124) (xy 409.848285 -157.338789) (xy 409.808136 -157.30008) (xy 409.77405 -157.255937)
			(xy 409.746754 -157.207302) (xy 409.726831 -157.155211) (xy 409.714705 -157.100774) (xy 409.710634 -157.045152)
			(xy 406.874255 -157.045152) (xy 403.73441 -160.1851) (xy 418.189169 -160.1851) (xy 418.193124 -160.093263)
			(xy 418.204959 -160.002106) (xy 418.224586 -159.912303) (xy 418.25186 -159.824521) (xy 418.28658 -159.739407)
			(xy 418.328488 -159.657594) (xy 418.377274 -159.579686) (xy 418.432577 -159.506261) (xy 418.493987 -159.437861)
			(xy 418.561049 -159.374994) (xy 418.633268 -159.318124) (xy 418.710108 -159.267673) (xy 418.791001 -159.224014)
			(xy 418.875347 -159.187471) (xy 418.962523 -159.158314) (xy 419.051882 -159.13676) (xy 419.142763 -159.122966)
			(xy 419.234494 -159.117036) (xy 419.326395 -159.119014) (xy 419.417786 -159.128885) (xy 419.50799 -159.146575)
			(xy 419.596339 -159.171955) (xy 419.682179 -159.204835) (xy 419.764875 -159.244973) (xy 419.843815 -159.292072)
			(xy 419.918413 -159.345782) (xy 419.988119 -159.405706) (xy 420.052414 -159.4714) (xy 420.110825 -159.542378)
			(xy 420.162917 -159.618115) (xy 420.208306 -159.69805) (xy 420.246656 -159.78159) (xy 420.277681 -159.868118)
			(xy 420.301154 -159.956993) (xy 420.3169 -160.047557) (xy 420.324802 -160.139139) (xy 420.325296 -160.1851)
			(xy 420.324802 -160.231061) (xy 420.3169 -160.322643) (xy 420.301154 -160.413207) (xy 420.277681 -160.502082)
			(xy 420.246656 -160.58861) (xy 420.208306 -160.67215) (xy 420.162917 -160.752085) (xy 420.110825 -160.827822)
			(xy 420.052414 -160.8988) (xy 419.988119 -160.964494) (xy 419.918413 -161.024418) (xy 419.843815 -161.078128)
			(xy 419.764875 -161.125227) (xy 419.682179 -161.165365) (xy 419.596339 -161.198245) (xy 419.50799 -161.223625)
			(xy 419.417786 -161.241315) (xy 419.326395 -161.251186) (xy 419.234494 -161.253164) (xy 419.142763 -161.247234)
			(xy 419.051882 -161.23344) (xy 418.962523 -161.211886) (xy 418.875347 -161.182729) (xy 418.791001 -161.146186)
			(xy 418.710108 -161.102527) (xy 418.633268 -161.052076) (xy 418.561049 -160.995206) (xy 418.493987 -160.932339)
			(xy 418.432577 -160.863939) (xy 418.377274 -160.790514) (xy 418.328488 -160.712606) (xy 418.28658 -160.630793)
			(xy 418.25186 -160.545679) (xy 418.224586 -160.457897) (xy 418.204959 -160.368094) (xy 418.193124 -160.276937)
			(xy 418.189169 -160.1851) (xy 403.73441 -160.1851) (xy 400.533608 -163.386008) (xy 412.932878 -163.386008)
			(xy 412.936949 -163.330386) (xy 412.949075 -163.275949) (xy 412.968998 -163.223858) (xy 412.996294 -163.175223)
			(xy 413.03038 -163.13108) (xy 413.070529 -163.092371) (xy 413.115887 -163.05992) (xy 413.165487 -163.034419)
			(xy 413.218271 -163.016412) (xy 413.273114 -163.006282) (xy 413.328848 -163.004245) (xy 413.384285 -163.010345)
			(xy 413.438242 -163.024451) (xy 413.489571 -163.046263) (xy 413.537177 -163.075317) (xy 413.580045 -163.110992)
			(xy 413.617262 -163.152529) (xy 413.648035 -163.199042) (xy 413.671707 -163.249539) (xy 413.687775 -163.302946)
			(xy 413.695895 -163.358122) (xy 413.696404 -163.386008) (xy 413.695895 -163.413894) (xy 413.687775 -163.46907)
			(xy 413.671707 -163.522477) (xy 413.648035 -163.572974) (xy 413.617262 -163.619487) (xy 413.580045 -163.661024)
			(xy 413.537177 -163.696699) (xy 413.489571 -163.725753) (xy 413.438242 -163.747565) (xy 413.384285 -163.761671)
			(xy 413.328848 -163.767771) (xy 413.273114 -163.765734) (xy 413.218271 -163.755604) (xy 413.165487 -163.737597)
			(xy 413.115887 -163.712096) (xy 413.070529 -163.679645) (xy 413.03038 -163.640936) (xy 412.996294 -163.596793)
			(xy 412.968998 -163.548158) (xy 412.949075 -163.496067) (xy 412.936949 -163.44163) (xy 412.932878 -163.386008)
			(xy 400.533608 -163.386008) (xy 400.275552 -163.644072) (xy 400.269964 -163.65093) (xy 400.26717 -163.655502)
			(xy 400.264389 -163.660885) (xy 400.261188 -163.672568) (xy 400.26082 -163.678616) (xy 400.261074 -163.691316)
			(xy 400.261836 -163.724844) (xy 400.261836 -163.728654) (xy 400.261836 -163.731194) (xy 400.262235 -163.735511)
			(xy 400.264281 -163.743936) (xy 400.2659 -163.747958) (xy 400.277838 -163.77539) (xy 400.285204 -163.782502)
			(xy 400.303184 -163.800533) (xy 400.334691 -163.840535) (xy 400.360596 -163.884373) (xy 400.380438 -163.931268)
			(xy 400.393864 -163.980386) (xy 400.400637 -164.030854) (xy 400.401028 -164.056314) (xy 400.400542 -164.083554)
			(xy 400.392791 -164.137479) (xy 400.377447 -164.189752) (xy 400.354824 -164.239312) (xy 400.325381 -164.28515)
			(xy 400.289718 -164.326334) (xy 400.248559 -164.362025) (xy 400.202741 -164.391499) (xy 400.153196 -164.414156)
			(xy 400.100933 -164.429535) (xy 400.047013 -164.437323) (xy 400.019774 -164.437822) (xy 400.019012 -164.437822)
			(xy 399.990918 -164.437281) (xy 399.935347 -164.428962) (xy 399.881595 -164.412591) (xy 399.830821 -164.388521)
			(xy 399.784122 -164.357271) (xy 399.76298 -164.338762) (xy 399.755868 -164.331904) (xy 399.738596 -164.324538)
			(xy 399.728436 -164.324284) (xy 399.723983 -164.324254) (xy 399.715173 -164.325538) (xy 399.71091 -164.326824)
			(xy 399.61947 -164.367464) (xy 399.611358 -164.372078) (xy 399.598893 -164.385945) (xy 399.592213 -164.403353)
			(xy 399.591784 -164.412676) (xy 399.591784 -164.748464) (xy 399.594578 -164.759894) (xy 399.597626 -164.765736)
			(xy 399.60941 -164.789219) (xy 399.627137 -164.838678) (xy 399.637908 -164.890102) (xy 399.641519 -164.942518)
			(xy 399.637903 -164.994933) (xy 399.627127 -165.046356) (xy 399.609396 -165.095814) (xy 399.597626 -165.119304)
			(xy 399.594578 -165.125146) (xy 399.591784 -165.136576) (xy 399.591784 -166.776908) (xy 399.592273 -166.786916)
			(xy 399.599933 -166.805408) (xy 399.614086 -166.819562) (xy 399.632576 -166.827225) (xy 399.642584 -166.827708)
			(xy 401.41398 -166.827708) (xy 401.42388 -166.827192) (xy 401.442181 -166.819618) (xy 401.44954 -166.812976)
			(xy 403.920706 -164.34181) (xy 403.921214 -164.341302) (xy 403.930104 -164.332412) (xy 403.930612 -164.332158)
			(xy 404.092918 -164.169852) (xy 404.100538 -164.169852) (xy 404.113238 -164.161724) (xy 404.119459 -164.157953)
			(xy 404.133399 -164.153813) (xy 404.14067 -164.153596) (xy 419.898068 -164.153596) (xy 419.907969 -164.153082)
			(xy 419.926272 -164.145509) (xy 419.933628 -164.138864) (xy 419.96868 -164.103812) (xy 419.976554 -164.093906)
			(xy 419.980364 -164.087302) (xy 419.984174 -164.079428) (xy 419.989 -164.066982) (xy 419.989762 -164.062664)
			(xy 419.997032 -164.028501) (xy 420.01855 -163.96205) (xy 420.04775 -163.898599) (xy 420.084226 -163.839032)
			(xy 420.127469 -163.784179) (xy 420.151814 -163.759134) (xy 420.502334 -163.408614) (xy 420.527482 -163.384153)
			(xy 420.582599 -163.340744) (xy 420.64247 -163.30417) (xy 420.706252 -163.274946) (xy 420.773047 -163.253483)
			(xy 420.807388 -163.246308) (xy 420.814754 -163.245038) (xy 420.840154 -163.23183) (xy 420.84752 -163.224718)
			(xy 420.85133 -163.204144) (xy 420.858444 -163.169565) (xy 420.879825 -163.10228) (xy 420.909058 -163.038017)
			(xy 420.945728 -162.977688) (xy 420.989315 -162.92215) (xy 421.01389 -162.896804) (xy 421.36441 -162.546284)
			(xy 421.389337 -162.522036) (xy 421.443916 -162.478938) (xy 421.503178 -162.442547) (xy 421.566303 -162.413366)
			(xy 421.632418 -162.391799) (xy 421.666416 -162.384486) (xy 421.669972 -162.383724) (xy 421.680386 -162.380168)
			(xy 421.686736 -162.377374) (xy 421.702992 -162.368992) (xy 421.70985 -162.362388) (xy 421.71366 -162.34156)
			(xy 421.720781 -162.307005) (xy 421.742169 -162.239772) (xy 421.771406 -162.175561) (xy 421.808076 -162.115285)
			(xy 421.851658 -162.0598) (xy 421.87622 -162.034474) (xy 422.22674 -161.683954) (xy 422.251668 -161.659708)
			(xy 422.306249 -161.616615) (xy 422.365512 -161.580228) (xy 422.428638 -161.551052) (xy 422.494753 -161.529489)
			(xy 422.528746 -161.522156) (xy 422.532302 -161.521394) (xy 422.542716 -161.517838) (xy 422.549066 -161.515044)
			(xy 422.565322 -161.506662) (xy 422.57218 -161.500058) (xy 422.57599 -161.47923) (xy 422.583107 -161.444674)
			(xy 422.60449 -161.377436) (xy 422.633723 -161.313221) (xy 422.670389 -161.252941) (xy 422.713968 -161.197453)
			(xy 422.73855 -161.172144) (xy 423.08907 -160.821624) (xy 423.113998 -160.797376) (xy 423.168577 -160.754279)
			(xy 423.227839 -160.717887) (xy 423.290964 -160.688705) (xy 423.357078 -160.667136) (xy 423.391076 -160.659826)
			(xy 423.394632 -160.659064) (xy 423.405046 -160.655508) (xy 423.411396 -160.652714) (xy 423.427652 -160.644332)
			(xy 423.43451 -160.637728) (xy 423.43832 -160.6169) (xy 423.445439 -160.582345) (xy 423.466826 -160.51511)
			(xy 423.496062 -160.450898) (xy 423.532732 -160.390621) (xy 423.576314 -160.335137) (xy 423.60088 -160.309814)
			(xy 423.9514 -159.959294) (xy 423.977118 -159.934316) (xy 424.033576 -159.890129) (xy 424.09497 -159.853105)
			(xy 424.160397 -159.823791) (xy 424.228893 -159.802618) (xy 424.264074 -159.795718) (xy 424.271694 -159.794194)
			(xy 424.278552 -159.790638) (xy 424.281949 -159.788768) (xy 424.288203 -159.784182) (xy 424.290998 -159.781494)
			(xy 424.306746 -159.765746) (xy 424.313096 -159.757872) (xy 424.313096 -128.842008) (xy 424.312334 -128.833372)
			(xy 424.309286 -128.815846) (xy 424.308778 -128.814576) (xy 424.303444 -128.806194) (xy 424.285087 -128.777239)
			(xy 424.254435 -128.715912) (xy 424.231077 -128.651452) (xy 424.215327 -128.584725) (xy 424.207397 -128.516624)
			(xy 424.206924 -128.482344) (xy 424.206924 -128.039622) (xy 424.207341 -128.007821) (xy 424.214169 -127.944587)
			(xy 424.22776 -127.882455) (xy 424.247955 -127.822145) (xy 424.274521 -127.764357) (xy 424.29049 -127.736854)
			(xy 424.294046 -127.731012) (xy 424.297602 -127.718566) (xy 424.299328 -127.711686) (xy 424.299327 -127.697507)
			(xy 424.297602 -127.690626) (xy 424.294046 -127.67818) (xy 424.29049 -127.672338) (xy 424.274549 -127.64482)
			(xy 424.247995 -127.58703) (xy 424.227799 -127.526723) (xy 424.214193 -127.464597) (xy 424.207337 -127.401369)
			(xy 424.206924 -127.36957) (xy 424.206924 -126.927102) (xy 424.207342 -126.895301) (xy 424.214172 -126.832068)
			(xy 424.227765 -126.769937) (xy 424.247962 -126.709628) (xy 424.274529 -126.651842) (xy 424.29049 -126.624334)
			(xy 424.294046 -126.618492) (xy 424.297602 -126.606046) (xy 424.299325 -126.599166) (xy 424.299318 -126.584988)
			(xy 424.297602 -126.578106) (xy 424.294046 -126.56566) (xy 424.29049 -126.559818) (xy 424.27455 -126.532299)
			(xy 424.247998 -126.474509) (xy 424.227804 -126.414203) (xy 424.2142 -126.352076) (xy 424.207346 -126.288849)
			(xy 424.206924 -126.25705) (xy 424.206924 -125.823472) (xy 424.206162 -125.815598) (xy 424.205908 -125.814074)
			(xy 424.202575 -125.791361) (xy 424.199019 -125.745589) (xy 424.198796 -125.722634) (xy 424.198796 -125.226826)
			(xy 424.199012 -125.203871) (xy 424.20257 -125.158098) (xy 424.205908 -125.135386) (xy 424.206162 -125.133862)
			(xy 424.206924 -125.125988) (xy 424.206924 -124.700792) (xy 424.207037 -124.683927) (xy 424.208943 -124.650252)
			(xy 424.210734 -124.633482) (xy 424.211158 -124.629546) (xy 424.210901 -124.621635) (xy 424.210226 -124.617734)
			(xy 424.204918 -124.589392) (xy 424.199196 -124.532012) (xy 424.198796 -124.50318) (xy 424.198796 -124.007626)
			(xy 424.199012 -123.984671) (xy 424.20257 -123.938898) (xy 424.205908 -123.916186) (xy 424.206162 -123.914662)
			(xy 424.206924 -123.906788) (xy 424.206924 -123.589034) (xy 424.206924 -123.588526) (xy 424.207399 -123.556966)
			(xy 424.214267 -123.494218) (xy 424.22064 -123.463304) (xy 424.221656 -123.453144) (xy 424.220132 -123.441206)
			(xy 424.219116 -123.437904) (xy 424.20962 -123.400263) (xy 424.199427 -123.323303) (xy 424.198796 -123.284488)
			(xy 424.198796 -122.788426) (xy 424.199012 -122.765471) (xy 424.20257 -122.719698) (xy 424.205908 -122.696986)
			(xy 424.206162 -122.695462) (xy 424.206924 -122.687588) (xy 424.206924 -122.476768) (xy 424.207292 -122.447061)
			(xy 424.213255 -122.387947) (xy 424.225118 -122.329729) (xy 424.233594 -122.301254) (xy 424.23588 -122.293888)
			(xy 424.23588 -122.270774) (xy 424.232832 -122.262646) (xy 424.222051 -122.230828) (xy 424.206913 -122.165373)
			(xy 424.199276 -122.098625) (xy 424.198796 -122.065034) (xy 424.198796 -121.569226) (xy 424.199012 -121.546271)
			(xy 424.20257 -121.500498) (xy 424.205908 -121.477786) (xy 424.206162 -121.476262) (xy 424.206924 -121.468388)
			(xy 424.206924 -121.364502) (xy 424.207601 -121.325089) (xy 424.218118 -121.246968) (xy 424.238914 -121.170935)
			(xy 424.25366 -121.134378) (xy 424.253914 -121.13387) (xy 424.257978 -121.114058) (xy 424.255692 -121.10339)
			(xy 424.253406 -121.092214) (xy 424.25112 -121.087134) (xy 424.238746 -121.058613) (xy 424.219374 -120.999534)
			(xy 424.206323 -120.938745) (xy 424.199738 -120.876921) (xy 424.199304 -120.845834) (xy 424.199304 -120.35028)
			(xy 424.199576 -120.327707) (xy 424.203133 -120.282699) (xy 424.206416 -120.260364) (xy 424.206924 -120.256554)
			(xy 424.206924 -120.250458) (xy 424.208194 -120.21185) (xy 424.209663 -120.192861) (xy 424.214747 -120.155113)
			(xy 424.218354 -120.136412) (xy 424.225041 -120.105221) (xy 424.244246 -120.044387) (xy 424.269898 -119.985978)
			(xy 424.28541 -119.958104) (xy 424.292522 -119.945658) (xy 424.283009 -119.93057) (xy 424.265599 -119.899433)
			(xy 424.257724 -119.883428) (xy 424.255692 -119.879364) (xy 424.253152 -119.875808) (xy 424.248834 -119.869712)
			(xy 424.242992 -119.8626) (xy 424.236388 -119.855996) (xy 424.23588 -119.855488) (xy 424.221402 -119.840756)
			(xy 424.214848 -119.833431) (xy 424.207388 -119.815267) (xy 424.206924 -119.80545) (xy 424.206924 -119.727472)
			(xy 424.206162 -119.719598) (xy 424.205908 -119.718074) (xy 424.202575 -119.695361) (xy 424.199019 -119.649589)
			(xy 424.198796 -119.626634) (xy 424.198796 -119.130826) (xy 424.199012 -119.107871) (xy 424.20257 -119.062098)
			(xy 424.205908 -119.039386) (xy 424.206162 -119.037862) (xy 424.206924 -119.029988) (xy 424.206924 -118.915942)
			(xy 424.207454 -118.905952) (xy 424.21516 -118.887511) (xy 424.22191 -118.880128) (xy 424.240198 -118.86184)
			(xy 424.240198 -118.861586) (xy 424.261534 -118.84025) (xy 424.268229 -118.83284) (xy 424.275844 -118.8144)
			(xy 424.275854 -118.79445) (xy 424.268257 -118.776003) (xy 424.261534 -118.768622) (xy 423.948606 -118.45544)
			(xy 423.695368 -118.202202) (xy 423.688301 -118.195666) (xy 423.670676 -118.187961) (xy 423.661078 -118.187216)
			(xy 423.651426 -118.186962) (xy 423.633392 -118.193566) (xy 423.625772 -118.200424) (xy 423.598687 -118.223817)
			(xy 423.539857 -118.264574) (xy 423.476534 -118.297924) (xy 423.409644 -118.323378) (xy 423.340169 -118.340564)
			(xy 423.269126 -118.349229) (xy 423.233342 -118.349776) (xy 423.232834 -118.349776) (xy 423.197122 -118.349239)
			(xy 423.126219 -118.340636) (xy 423.056869 -118.323552) (xy 422.990083 -118.298235) (xy 422.926834 -118.265054)
			(xy 422.868045 -118.224493) (xy 422.814573 -118.177144) (xy 422.767195 -118.123696) (xy 422.726604 -118.064928)
			(xy 422.693391 -118.001697) (xy 422.668039 -117.934924) (xy 422.650919 -117.865583) (xy 422.642279 -117.794684)
			(xy 422.641776 -117.758972) (xy 422.642217 -117.726679) (xy 422.649279 -117.662481) (xy 422.663304 -117.599437)
			(xy 422.684124 -117.5383) (xy 422.711492 -117.4798) (xy 422.74508 -117.424636) (xy 422.764458 -117.3988)
			(xy 422.769538 -117.391942) (xy 422.772078 -117.38483) (xy 422.773377 -117.380761) (xy 422.774781 -117.372336)
			(xy 422.774872 -117.368066) (xy 422.774872 -117.290596) (xy 422.774364 -117.283484) (xy 422.77284 -117.272816)
			(xy 422.764204 -117.255544) (xy 422.76141 -117.251734) (xy 422.761156 -117.25148) (xy 422.742294 -117.225802)
			(xy 422.709586 -117.17112) (xy 422.682952 -117.113235) (xy 422.662702 -117.052821) (xy 422.649071 -116.990579)
			(xy 422.642217 -116.927231) (xy 422.641776 -116.895372) (xy 422.642316 -116.859678) (xy 422.650921 -116.78881)
			(xy 422.668003 -116.719496) (xy 422.693313 -116.652745) (xy 422.726482 -116.589531) (xy 422.767026 -116.530773)
			(xy 422.814355 -116.47733) (xy 422.867779 -116.429978) (xy 422.92652 -116.38941) (xy 422.989721 -116.356214)
			(xy 423.056461 -116.330877) (xy 423.125768 -116.313766) (xy 423.196632 -116.305131) (xy 423.232326 -116.304568)
			(xy 423.232834 -116.304568) (xy 423.265988 -116.305034) (xy 423.331881 -116.312457) (xy 423.396528 -116.327206)
			(xy 423.45912 -116.349095) (xy 423.518869 -116.377851) (xy 423.575026 -116.413112) (xy 423.626885 -116.454434)
			(xy 423.650664 -116.477542) (xy 423.757598 -116.584476) (xy 423.760449 -116.587182) (xy 423.766828 -116.591774)
			(xy 423.770298 -116.59362) (xy 423.775724 -116.596207) (xy 423.787404 -116.59904) (xy 423.793412 -116.599208)
			(xy 424.195494 -116.599208) (xy 424.205482 -116.599745) (xy 424.223915 -116.607457) (xy 424.231308 -116.614194)
			(xy 424.378374 -116.76126) (xy 424.379136 -116.761768) (xy 424.388026 -116.770658) (xy 424.388534 -116.771166)
			(xy 425.604178 -117.98681) (xy 425.611544 -117.99443) (xy 425.61256 -117.995446) (xy 425.762166 -118.145052)
			(xy 425.768972 -118.152399) (xy 425.776691 -118.170861) (xy 425.777152 -118.180866) (xy 425.777152 -119.559324)
			(xy 429.3743 -119.559324) (xy 429.3743 -118.695724) (xy 429.37479 -118.66574) (xy 429.382618 -118.606284)
			(xy 429.398139 -118.548359) (xy 429.421088 -118.492955) (xy 429.451072 -118.441021) (xy 429.487578 -118.393445)
			(xy 429.529983 -118.35104) (xy 429.577559 -118.314534) (xy 429.629493 -118.28455) (xy 429.684897 -118.261601)
			(xy 429.742822 -118.24608) (xy 429.802278 -118.238252) (xy 429.862246 -118.238252) (xy 429.921702 -118.24608)
			(xy 429.979627 -118.261601) (xy 430.035031 -118.28455) (xy 430.086965 -118.314534) (xy 430.134541 -118.35104)
			(xy 430.176946 -118.393445) (xy 430.213452 -118.441021) (xy 430.243436 -118.492955) (xy 430.266385 -118.548359)
			(xy 430.281906 -118.606284) (xy 430.289734 -118.66574) (xy 430.290224 -118.695724) (xy 430.290224 -119.559324)
			(xy 430.289734 -119.589308) (xy 430.281906 -119.648764) (xy 430.266385 -119.706689) (xy 430.243436 -119.762093)
			(xy 430.213452 -119.814027) (xy 430.176946 -119.861603) (xy 430.134541 -119.904008) (xy 430.086965 -119.940514)
			(xy 430.035031 -119.970498) (xy 429.979627 -119.993447) (xy 429.921702 -120.008968) (xy 429.862246 -120.016796)
			(xy 429.802278 -120.016796) (xy 429.742822 -120.008968) (xy 429.684897 -119.993447) (xy 429.629493 -119.970498)
			(xy 429.577559 -119.940514) (xy 429.529983 -119.904008) (xy 429.487578 -119.861603) (xy 429.451072 -119.814027)
			(xy 429.421088 -119.762093) (xy 429.398139 -119.706689) (xy 429.382618 -119.648764) (xy 429.37479 -119.589308)
			(xy 429.3743 -119.559324) (xy 425.777152 -119.559324) (xy 425.777152 -121.365772) (xy 432.016408 -121.365772)
			(xy 432.016408 -120.502172) (xy 432.016898 -120.472188) (xy 432.024726 -120.412732) (xy 432.040247 -120.354807)
			(xy 432.063196 -120.299403) (xy 432.09318 -120.247469) (xy 432.129686 -120.199893) (xy 432.172091 -120.157488)
			(xy 432.219667 -120.120982) (xy 432.271601 -120.090998) (xy 432.327005 -120.068049) (xy 432.38493 -120.052528)
			(xy 432.444386 -120.0447) (xy 432.504354 -120.0447) (xy 432.56381 -120.052528) (xy 432.621735 -120.068049)
			(xy 432.677139 -120.090998) (xy 432.729073 -120.120982) (xy 432.776649 -120.157488) (xy 432.819054 -120.199893)
			(xy 432.85556 -120.247469) (xy 432.885544 -120.299403) (xy 432.908493 -120.354807) (xy 432.924014 -120.412732)
			(xy 432.931842 -120.472188) (xy 432.932332 -120.502172) (xy 432.932332 -121.365772) (xy 432.931842 -121.395756)
			(xy 432.924014 -121.455212) (xy 432.908493 -121.513137) (xy 432.885544 -121.568541) (xy 432.85556 -121.620475)
			(xy 432.819054 -121.668051) (xy 432.776649 -121.710456) (xy 432.729073 -121.746962) (xy 432.677139 -121.776946)
			(xy 432.621735 -121.799895) (xy 432.56381 -121.815416) (xy 432.504354 -121.823244) (xy 432.444386 -121.823244)
			(xy 432.38493 -121.815416) (xy 432.327005 -121.799895) (xy 432.271601 -121.776946) (xy 432.219667 -121.746962)
			(xy 432.172091 -121.710456) (xy 432.129686 -121.668051) (xy 432.09318 -121.620475) (xy 432.063196 -121.568541)
			(xy 432.040247 -121.513137) (xy 432.024726 -121.455212) (xy 432.016898 -121.395756) (xy 432.016408 -121.365772)
			(xy 425.777152 -121.365772) (xy 425.777152 -123.159266) (xy 429.3743 -123.159266) (xy 429.3743 -122.295666)
			(xy 429.37479 -122.265682) (xy 429.382618 -122.206226) (xy 429.398139 -122.148301) (xy 429.421088 -122.092897)
			(xy 429.451072 -122.040963) (xy 429.487578 -121.993387) (xy 429.529983 -121.950982) (xy 429.577559 -121.914476)
			(xy 429.629493 -121.884492) (xy 429.684897 -121.861543) (xy 429.742822 -121.846022) (xy 429.802278 -121.838194)
			(xy 429.862246 -121.838194) (xy 429.921702 -121.846022) (xy 429.979627 -121.861543) (xy 430.035031 -121.884492)
			(xy 430.086965 -121.914476) (xy 430.134541 -121.950982) (xy 430.176946 -121.993387) (xy 430.213452 -122.040963)
			(xy 430.243436 -122.092897) (xy 430.266385 -122.148301) (xy 430.281906 -122.206226) (xy 430.289734 -122.265682)
			(xy 430.290224 -122.295666) (xy 430.290224 -123.159266) (xy 430.289734 -123.18925) (xy 430.281906 -123.248706)
			(xy 430.266385 -123.306631) (xy 430.243436 -123.362035) (xy 430.213452 -123.413969) (xy 430.176946 -123.461545)
			(xy 430.134541 -123.50395) (xy 430.086965 -123.540456) (xy 430.035031 -123.57044) (xy 429.979627 -123.593389)
			(xy 429.921702 -123.60891) (xy 429.862246 -123.616738) (xy 429.802278 -123.616738) (xy 429.742822 -123.60891)
			(xy 429.684897 -123.593389) (xy 429.629493 -123.57044) (xy 429.577559 -123.540456) (xy 429.529983 -123.50395)
			(xy 429.487578 -123.461545) (xy 429.451072 -123.413969) (xy 429.421088 -123.362035) (xy 429.398139 -123.306631)
			(xy 429.382618 -123.248706) (xy 429.37479 -123.18925) (xy 429.3743 -123.159266) (xy 425.777152 -123.159266)
			(xy 425.777152 -124.965714) (xy 432.016408 -124.965714) (xy 432.016408 -124.102114) (xy 432.016898 -124.07213)
			(xy 432.024726 -124.012674) (xy 432.040247 -123.954749) (xy 432.063196 -123.899345) (xy 432.09318 -123.847411)
			(xy 432.129686 -123.799835) (xy 432.172091 -123.75743) (xy 432.219667 -123.720924) (xy 432.271601 -123.69094)
			(xy 432.327005 -123.667991) (xy 432.38493 -123.65247) (xy 432.444386 -123.644642) (xy 432.504354 -123.644642)
			(xy 432.56381 -123.65247) (xy 432.621735 -123.667991) (xy 432.677139 -123.69094) (xy 432.729073 -123.720924)
			(xy 432.776649 -123.75743) (xy 432.819054 -123.799835) (xy 432.85556 -123.847411) (xy 432.885544 -123.899345)
			(xy 432.908493 -123.954749) (xy 432.924014 -124.012674) (xy 432.931842 -124.07213) (xy 432.932332 -124.102114)
			(xy 432.932332 -124.965714) (xy 432.931842 -124.995698) (xy 432.924014 -125.055154) (xy 432.908493 -125.113079)
			(xy 432.885544 -125.168483) (xy 432.85556 -125.220417) (xy 432.819054 -125.267993) (xy 432.776649 -125.310398)
			(xy 432.729073 -125.346904) (xy 432.677139 -125.376888) (xy 432.621735 -125.399837) (xy 432.56381 -125.415358)
			(xy 432.504354 -125.423186) (xy 432.444386 -125.423186) (xy 432.38493 -125.415358) (xy 432.327005 -125.399837)
			(xy 432.271601 -125.376888) (xy 432.219667 -125.346904) (xy 432.172091 -125.310398) (xy 432.129686 -125.267993)
			(xy 432.09318 -125.220417) (xy 432.063196 -125.168483) (xy 432.040247 -125.113079) (xy 432.024726 -125.055154)
			(xy 432.016898 -124.995698) (xy 432.016408 -124.965714) (xy 425.777152 -124.965714) (xy 425.777152 -130.769106)
			(xy 429.3743 -130.769106) (xy 429.3743 -129.905506) (xy 429.37479 -129.875522) (xy 429.382618 -129.816066)
			(xy 429.398139 -129.758141) (xy 429.421088 -129.702737) (xy 429.451072 -129.650803) (xy 429.487578 -129.603227)
			(xy 429.529983 -129.560822) (xy 429.577559 -129.524316) (xy 429.629493 -129.494332) (xy 429.684897 -129.471383)
			(xy 429.742822 -129.455862) (xy 429.802278 -129.448034) (xy 429.862246 -129.448034) (xy 429.921702 -129.455862)
			(xy 429.979627 -129.471383) (xy 430.035031 -129.494332) (xy 430.086965 -129.524316) (xy 430.134541 -129.560822)
			(xy 430.176946 -129.603227) (xy 430.213452 -129.650803) (xy 430.243436 -129.702737) (xy 430.266385 -129.758141)
			(xy 430.281906 -129.816066) (xy 430.289734 -129.875522) (xy 430.290224 -129.905506) (xy 430.290224 -130.769106)
			(xy 430.289734 -130.79909) (xy 430.281906 -130.858546) (xy 430.266385 -130.916471) (xy 430.243436 -130.971875)
			(xy 430.213452 -131.023809) (xy 430.176946 -131.071385) (xy 430.134541 -131.11379) (xy 430.086965 -131.150296)
			(xy 430.035031 -131.18028) (xy 429.979627 -131.203229) (xy 429.921702 -131.21875) (xy 429.862246 -131.226578)
			(xy 429.802278 -131.226578) (xy 429.742822 -131.21875) (xy 429.684897 -131.203229) (xy 429.629493 -131.18028)
			(xy 429.577559 -131.150296) (xy 429.529983 -131.11379) (xy 429.487578 -131.071385) (xy 429.451072 -131.023809)
			(xy 429.421088 -130.971875) (xy 429.398139 -130.916471) (xy 429.382618 -130.858546) (xy 429.37479 -130.79909)
			(xy 429.3743 -130.769106) (xy 425.777152 -130.769106) (xy 425.777152 -132.575808) (xy 432.016408 -132.575808)
			(xy 432.016408 -131.712208) (xy 432.016898 -131.682224) (xy 432.024726 -131.622768) (xy 432.040247 -131.564843)
			(xy 432.063196 -131.509439) (xy 432.09318 -131.457505) (xy 432.129686 -131.409929) (xy 432.172091 -131.367524)
			(xy 432.219667 -131.331018) (xy 432.271601 -131.301034) (xy 432.327005 -131.278085) (xy 432.38493 -131.262564)
			(xy 432.444386 -131.254736) (xy 432.504354 -131.254736) (xy 432.56381 -131.262564) (xy 432.621735 -131.278085)
			(xy 432.677139 -131.301034) (xy 432.729073 -131.331018) (xy 432.776649 -131.367524) (xy 432.819054 -131.409929)
			(xy 432.85556 -131.457505) (xy 432.885544 -131.509439) (xy 432.908493 -131.564843) (xy 432.924014 -131.622768)
			(xy 432.931842 -131.682224) (xy 432.932332 -131.712208) (xy 432.932332 -132.575808) (xy 432.931842 -132.605792)
			(xy 432.924014 -132.665248) (xy 432.908493 -132.723173) (xy 432.885544 -132.778577) (xy 432.85556 -132.830511)
			(xy 432.819054 -132.878087) (xy 432.776649 -132.920492) (xy 432.729073 -132.956998) (xy 432.677139 -132.986982)
			(xy 432.621735 -133.009931) (xy 432.56381 -133.025452) (xy 432.504354 -133.03328) (xy 432.444386 -133.03328)
			(xy 432.38493 -133.025452) (xy 432.327005 -133.009931) (xy 432.271601 -132.986982) (xy 432.219667 -132.956998)
			(xy 432.172091 -132.920492) (xy 432.129686 -132.878087) (xy 432.09318 -132.830511) (xy 432.063196 -132.778577)
			(xy 432.040247 -132.723173) (xy 432.024726 -132.665248) (xy 432.016898 -132.605792) (xy 432.016408 -132.575808)
			(xy 425.777152 -132.575808) (xy 425.777152 -134.369302) (xy 429.3743 -134.369302) (xy 429.3743 -133.505702)
			(xy 429.37479 -133.475718) (xy 429.382618 -133.416262) (xy 429.398139 -133.358337) (xy 429.421088 -133.302933)
			(xy 429.451072 -133.250999) (xy 429.487578 -133.203423) (xy 429.529983 -133.161018) (xy 429.577559 -133.124512)
			(xy 429.629493 -133.094528) (xy 429.684897 -133.071579) (xy 429.742822 -133.056058) (xy 429.802278 -133.04823)
			(xy 429.862246 -133.04823) (xy 429.921702 -133.056058) (xy 429.979627 -133.071579) (xy 430.035031 -133.094528)
			(xy 430.086965 -133.124512) (xy 430.134541 -133.161018) (xy 430.176946 -133.203423) (xy 430.213452 -133.250999)
			(xy 430.243436 -133.302933) (xy 430.266385 -133.358337) (xy 430.281906 -133.416262) (xy 430.289734 -133.475718)
			(xy 430.290224 -133.505702) (xy 430.290224 -134.369302) (xy 430.289734 -134.399286) (xy 430.281906 -134.458742)
			(xy 430.266385 -134.516667) (xy 430.243436 -134.572071) (xy 430.213452 -134.624005) (xy 430.176946 -134.671581)
			(xy 430.134541 -134.713986) (xy 430.086965 -134.750492) (xy 430.035031 -134.780476) (xy 429.979627 -134.803425)
			(xy 429.921702 -134.818946) (xy 429.862246 -134.826774) (xy 429.802278 -134.826774) (xy 429.742822 -134.818946)
			(xy 429.684897 -134.803425) (xy 429.629493 -134.780476) (xy 429.577559 -134.750492) (xy 429.529983 -134.713986)
			(xy 429.487578 -134.671581) (xy 429.451072 -134.624005) (xy 429.421088 -134.572071) (xy 429.398139 -134.516667)
			(xy 429.382618 -134.458742) (xy 429.37479 -134.399286) (xy 429.3743 -134.369302) (xy 425.777152 -134.369302)
			(xy 425.777152 -136.17575) (xy 432.016408 -136.17575) (xy 432.016408 -135.31215) (xy 432.016898 -135.282166)
			(xy 432.024726 -135.22271) (xy 432.040247 -135.164785) (xy 432.063196 -135.109381) (xy 432.09318 -135.057447)
			(xy 432.129686 -135.009871) (xy 432.172091 -134.967466) (xy 432.219667 -134.93096) (xy 432.271601 -134.900976)
			(xy 432.327005 -134.878027) (xy 432.38493 -134.862506) (xy 432.444386 -134.854678) (xy 432.504354 -134.854678)
			(xy 432.56381 -134.862506) (xy 432.621735 -134.878027) (xy 432.677139 -134.900976) (xy 432.729073 -134.93096)
			(xy 432.776649 -134.967466) (xy 432.819054 -135.009871) (xy 432.85556 -135.057447) (xy 432.885544 -135.109381)
			(xy 432.908493 -135.164785) (xy 432.924014 -135.22271) (xy 432.931842 -135.282166) (xy 432.932332 -135.31215)
			(xy 432.932332 -136.17575) (xy 432.931842 -136.205734) (xy 432.924014 -136.26519) (xy 432.908493 -136.323115)
			(xy 432.885544 -136.378519) (xy 432.85556 -136.430453) (xy 432.819054 -136.478029) (xy 432.776649 -136.520434)
			(xy 432.729073 -136.55694) (xy 432.677139 -136.586924) (xy 432.621735 -136.609873) (xy 432.56381 -136.625394)
			(xy 432.504354 -136.633222) (xy 432.444386 -136.633222) (xy 432.38493 -136.625394) (xy 432.327005 -136.609873)
			(xy 432.271601 -136.586924) (xy 432.219667 -136.55694) (xy 432.172091 -136.520434) (xy 432.129686 -136.478029)
			(xy 432.09318 -136.430453) (xy 432.063196 -136.378519) (xy 432.040247 -136.323115) (xy 432.024726 -136.26519)
			(xy 432.016898 -136.205734) (xy 432.016408 -136.17575) (xy 425.777152 -136.17575) (xy 425.777152 -136.98601)
			(xy 428.857662 -136.98601) (xy 428.861733 -136.930388) (xy 428.873859 -136.875951) (xy 428.893782 -136.82386)
			(xy 428.921078 -136.775225) (xy 428.955164 -136.731082) (xy 428.995313 -136.692373) (xy 429.040671 -136.659922)
			(xy 429.090271 -136.634421) (xy 429.143055 -136.616414) (xy 429.197898 -136.606284) (xy 429.253632 -136.604247)
			(xy 429.309069 -136.610347) (xy 429.363026 -136.624453) (xy 429.414355 -136.646265) (xy 429.461961 -136.675319)
			(xy 429.504829 -136.710994) (xy 429.542046 -136.752531) (xy 429.572819 -136.799044) (xy 429.596491 -136.849541)
			(xy 429.612559 -136.902948) (xy 429.620679 -136.958124) (xy 429.621188 -136.98601) (xy 429.620679 -137.013896)
			(xy 429.612559 -137.069072) (xy 429.596491 -137.122479) (xy 429.572819 -137.172976) (xy 429.542046 -137.219489)
			(xy 429.504829 -137.261026) (xy 429.461961 -137.296701) (xy 429.414355 -137.325755) (xy 429.363026 -137.347567)
			(xy 429.309069 -137.361673) (xy 429.253632 -137.367773) (xy 429.197898 -137.365736) (xy 429.143055 -137.355606)
			(xy 429.090271 -137.337599) (xy 429.040671 -137.312098) (xy 428.995313 -137.279647) (xy 428.955164 -137.240938)
			(xy 428.921078 -137.196795) (xy 428.893782 -137.14816) (xy 428.873859 -137.096069) (xy 428.861733 -137.041632)
			(xy 428.857662 -136.98601) (xy 425.777152 -136.98601) (xy 425.777152 -137.65276) (xy 444.341248 -137.65276)
			(xy 444.345319 -137.597138) (xy 444.357445 -137.542701) (xy 444.377368 -137.49061) (xy 444.404664 -137.441975)
			(xy 444.43875 -137.397832) (xy 444.478899 -137.359123) (xy 444.524257 -137.326672) (xy 444.573857 -137.301171)
			(xy 444.626641 -137.283164) (xy 444.681484 -137.273034) (xy 444.737218 -137.270997) (xy 444.792655 -137.277097)
			(xy 444.846612 -137.291203) (xy 444.897941 -137.313015) (xy 444.945547 -137.342069) (xy 444.988415 -137.377744)
			(xy 445.025632 -137.419281) (xy 445.056405 -137.465794) (xy 445.080077 -137.516291) (xy 445.096145 -137.569698)
			(xy 445.104265 -137.624874) (xy 445.104774 -137.65276) (xy 445.104265 -137.680646) (xy 445.096145 -137.735822)
			(xy 445.080077 -137.789229) (xy 445.056405 -137.839726) (xy 445.025632 -137.886239) (xy 444.988415 -137.927776)
			(xy 444.977268 -137.937053) (xy 445.665563 -137.937053) (xy 445.665563 -137.882547) (xy 445.67332 -137.828597)
			(xy 445.688676 -137.7763) (xy 445.711319 -137.72672) (xy 445.740787 -137.680868) (xy 445.77648 -137.639676)
			(xy 445.817673 -137.603983) (xy 445.863526 -137.574516) (xy 445.913106 -137.551874) (xy 445.965403 -137.536519)
			(xy 446.019353 -137.528763) (xy 446.046606 -137.5283) (xy 446.074709 -137.528782) (xy 446.130306 -137.537029)
			(xy 446.184092 -137.553344) (xy 446.234901 -137.577374) (xy 446.281636 -137.608598) (xy 446.323284 -137.646341)
			(xy 446.3415 -137.667746) (xy 446.348612 -137.676636) (xy 446.36817 -137.686034) (xy 446.46723 -137.689082)
			(xy 446.487296 -137.680446) (xy 446.494662 -137.672318) (xy 446.512803 -137.653333) (xy 446.553392 -137.620017)
			(xy 446.598162 -137.592577) (xy 446.64627 -137.571529) (xy 446.696808 -137.557272) (xy 446.748823 -137.550074)
			(xy 446.775078 -137.549636) (xy 446.802335 -137.550009) (xy 446.856295 -137.557765) (xy 446.908601 -137.573121)
			(xy 446.95819 -137.595765) (xy 447.004051 -137.625235) (xy 447.045251 -137.660933) (xy 447.080951 -137.702131)
			(xy 447.110425 -137.747991) (xy 447.133072 -137.797578) (xy 447.148431 -137.849884) (xy 447.156189 -137.903843)
			(xy 447.156189 -137.958357) (xy 447.148431 -138.012316) (xy 447.133072 -138.064622) (xy 447.110425 -138.114209)
			(xy 447.080951 -138.160069) (xy 447.045251 -138.201267) (xy 447.004051 -138.236965) (xy 446.95819 -138.266435)
			(xy 446.908601 -138.289079) (xy 446.856295 -138.304435) (xy 446.802335 -138.312191) (xy 446.775078 -138.312652)
			(xy 446.746976 -138.312128) (xy 446.69138 -138.303892) (xy 446.637595 -138.287587) (xy 446.586784 -138.263565)
			(xy 446.540049 -138.232347) (xy 446.4984 -138.194609) (xy 446.480184 -138.173206) (xy 446.473072 -138.164316)
			(xy 446.453514 -138.154918) (xy 446.354454 -138.15187) (xy 446.334388 -138.160506) (xy 446.327022 -138.168634)
			(xy 446.308879 -138.187617) (xy 446.268292 -138.220935) (xy 446.223523 -138.248377) (xy 446.175415 -138.269425)
			(xy 446.124877 -138.283682) (xy 446.072861 -138.290879) (xy 446.046606 -138.291316) (xy 446.019353 -138.290837)
			(xy 445.965403 -138.283081) (xy 445.913106 -138.267726) (xy 445.863526 -138.245084) (xy 445.817673 -138.215617)
			(xy 445.77648 -138.179924) (xy 445.740787 -138.138732) (xy 445.711319 -138.09288) (xy 445.688676 -138.0433)
			(xy 445.67332 -137.991003) (xy 445.665563 -137.937053) (xy 444.977268 -137.937053) (xy 444.945547 -137.963451)
			(xy 444.897941 -137.992505) (xy 444.846612 -138.014317) (xy 444.792655 -138.028423) (xy 444.737218 -138.034523)
			(xy 444.681484 -138.032486) (xy 444.626641 -138.022356) (xy 444.573857 -138.004349) (xy 444.524257 -137.978848)
			(xy 444.478899 -137.946397) (xy 444.43875 -137.907688) (xy 444.404664 -137.863545) (xy 444.377368 -137.81491)
			(xy 444.357445 -137.762819) (xy 444.345319 -137.708382) (xy 444.341248 -137.65276) (xy 425.777152 -137.65276)
			(xy 425.777152 -139.762055) (xy 428.684853 -139.762055) (xy 428.684853 -139.707545) (xy 428.692612 -139.65359)
			(xy 428.70797 -139.601288) (xy 428.730616 -139.551705) (xy 428.760088 -139.50585) (xy 428.795787 -139.464655)
			(xy 428.836985 -139.428962) (xy 428.882844 -139.399495) (xy 428.93243 -139.376855) (xy 428.984733 -139.361502)
			(xy 429.038689 -139.35375) (xy 429.065944 -139.35329) (xy 429.09215 -139.353734) (xy 429.144067 -139.360918)
			(xy 429.194511 -139.375146) (xy 429.24253 -139.396148) (xy 429.287221 -139.423529) (xy 429.32774 -139.456773)
			(xy 429.345852 -139.475718) (xy 429.353411 -139.483041) (xy 429.37268 -139.491444) (xy 429.38319 -139.491974)
			(xy 429.457866 -139.491974) (xy 429.468389 -139.49149) (xy 429.487681 -139.483091) (xy 429.495204 -139.475718)
			(xy 429.513324 -139.45678) (xy 429.553836 -139.423527) (xy 429.598524 -139.396139) (xy 429.646543 -139.375133)
			(xy 429.696987 -139.360905) (xy 429.748906 -139.353725) (xy 429.775112 -139.35329) (xy 429.802363 -139.353781)
			(xy 429.856309 -139.361538) (xy 429.908602 -139.376895) (xy 429.958177 -139.399536) (xy 430.004026 -139.429003)
			(xy 430.045214 -139.464694) (xy 430.080904 -139.505884) (xy 430.11037 -139.551733) (xy 430.13301 -139.60131)
			(xy 430.148364 -139.653603) (xy 430.15612 -139.707549) (xy 430.15612 -139.71651) (xy 431.091846 -139.71651)
			(xy 431.095917 -139.660888) (xy 431.108043 -139.606451) (xy 431.127966 -139.55436) (xy 431.155262 -139.505725)
			(xy 431.189348 -139.461582) (xy 431.229497 -139.422873) (xy 431.274855 -139.390422) (xy 431.324455 -139.364921)
			(xy 431.377239 -139.346914) (xy 431.432082 -139.336784) (xy 431.487816 -139.334747) (xy 431.543253 -139.340847)
			(xy 431.59721 -139.354953) (xy 431.648539 -139.376765) (xy 431.696145 -139.405819) (xy 431.739013 -139.441494)
			(xy 431.77623 -139.483031) (xy 431.807003 -139.529544) (xy 431.830675 -139.580041) (xy 431.846743 -139.633448)
			(xy 431.854863 -139.688624) (xy 431.855372 -139.71651) (xy 431.854863 -139.744396) (xy 431.846743 -139.799572)
			(xy 431.830675 -139.852979) (xy 431.807003 -139.903476) (xy 431.77623 -139.949989) (xy 431.739013 -139.991526)
			(xy 431.696145 -140.027201) (xy 431.648539 -140.056255) (xy 431.59721 -140.078067) (xy 431.543253 -140.092173)
			(xy 431.487816 -140.098273) (xy 431.432082 -140.096236) (xy 431.377239 -140.086106) (xy 431.324455 -140.068099)
			(xy 431.274855 -140.042598) (xy 431.229497 -140.010147) (xy 431.189348 -139.971438) (xy 431.155262 -139.927295)
			(xy 431.127966 -139.87866) (xy 431.108043 -139.826569) (xy 431.095917 -139.772132) (xy 431.091846 -139.71651)
			(xy 430.15612 -139.71651) (xy 430.15612 -139.762051) (xy 430.148364 -139.815997) (xy 430.13301 -139.86829)
			(xy 430.11037 -139.917867) (xy 430.080904 -139.963716) (xy 430.045214 -140.004906) (xy 430.004026 -140.040597)
			(xy 429.958177 -140.070064) (xy 429.908602 -140.092705) (xy 429.856309 -140.108062) (xy 429.802363 -140.115819)
			(xy 429.775112 -140.116306) (xy 429.748905 -140.115893) (xy 429.696987 -140.108702) (xy 429.646542 -140.094469)
			(xy 429.598523 -140.073461) (xy 429.553833 -140.046074) (xy 429.513315 -140.012825) (xy 429.495204 -139.993878)
			(xy 429.487662 -139.986535) (xy 429.46838 -139.978143) (xy 429.457866 -139.977622) (xy 429.38319 -139.977622)
			(xy 429.372665 -139.978084) (xy 429.353373 -139.986499) (xy 429.345852 -139.993878) (xy 429.327753 -140.012837)
			(xy 429.287236 -140.046088) (xy 429.242544 -140.073474) (xy 429.194521 -140.094476) (xy 429.144073 -140.108699)
			(xy 429.092151 -140.115874) (xy 429.065944 -140.116306) (xy 429.038689 -140.11585) (xy 428.984733 -140.108098)
			(xy 428.93243 -140.092745) (xy 428.882844 -140.070105) (xy 428.836985 -140.040638) (xy 428.795787 -140.004945)
			(xy 428.760088 -139.96375) (xy 428.730616 -139.917895) (xy 428.70797 -139.868312) (xy 428.692612 -139.81601)
			(xy 428.684853 -139.762055) (xy 425.777152 -139.762055) (xy 425.777152 -140.487654) (xy 434.002178 -140.487654)
			(xy 434.006249 -140.432032) (xy 434.018375 -140.377595) (xy 434.038298 -140.325504) (xy 434.065594 -140.276869)
			(xy 434.09968 -140.232726) (xy 434.139829 -140.194017) (xy 434.185187 -140.161566) (xy 434.234787 -140.136065)
			(xy 434.287571 -140.118058) (xy 434.342414 -140.107928) (xy 434.398148 -140.105891) (xy 434.453585 -140.111991)
			(xy 434.507542 -140.126097) (xy 434.558871 -140.147909) (xy 434.606477 -140.176963) (xy 434.649345 -140.212638)
			(xy 434.686562 -140.254175) (xy 434.717335 -140.300688) (xy 434.741007 -140.351185) (xy 434.757075 -140.404592)
			(xy 434.765195 -140.459768) (xy 434.765704 -140.487654) (xy 434.765195 -140.51554) (xy 434.757075 -140.570716)
			(xy 434.741007 -140.624123) (xy 434.717335 -140.67462) (xy 434.686562 -140.721133) (xy 434.649345 -140.76267)
			(xy 434.606477 -140.798345) (xy 434.558871 -140.827399) (xy 434.507542 -140.849211) (xy 434.453585 -140.863317)
			(xy 434.398148 -140.869417) (xy 434.342414 -140.86738) (xy 434.287571 -140.85725) (xy 434.234787 -140.839243)
			(xy 434.185187 -140.813742) (xy 434.139829 -140.781291) (xy 434.09968 -140.742582) (xy 434.065594 -140.698439)
			(xy 434.038298 -140.649804) (xy 434.018375 -140.597713) (xy 434.006249 -140.543276) (xy 434.002178 -140.487654)
			(xy 425.777152 -140.487654) (xy 425.777152 -143.479266) (xy 429.3743 -143.479266) (xy 429.3743 -142.615666)
			(xy 429.37479 -142.585682) (xy 429.382618 -142.526226) (xy 429.398139 -142.468301) (xy 429.421088 -142.412897)
			(xy 429.451072 -142.360963) (xy 429.487578 -142.313387) (xy 429.529983 -142.270982) (xy 429.577559 -142.234476)
			(xy 429.629493 -142.204492) (xy 429.684897 -142.181543) (xy 429.742822 -142.166022) (xy 429.802278 -142.158194)
			(xy 429.862246 -142.158194) (xy 429.921702 -142.166022) (xy 429.979627 -142.181543) (xy 430.035031 -142.204492)
			(xy 430.086965 -142.234476) (xy 430.134541 -142.270982) (xy 430.176946 -142.313387) (xy 430.213452 -142.360963)
			(xy 430.243436 -142.412897) (xy 430.266385 -142.468301) (xy 430.281906 -142.526226) (xy 430.289734 -142.585682)
			(xy 430.290224 -142.615666) (xy 430.290224 -143.479266) (xy 430.289734 -143.50925) (xy 430.281906 -143.568706)
			(xy 430.266385 -143.626631) (xy 430.243436 -143.682035) (xy 430.213452 -143.733969) (xy 430.176946 -143.781545)
			(xy 430.134541 -143.82395) (xy 430.086965 -143.860456) (xy 430.035031 -143.89044) (xy 429.979627 -143.913389)
			(xy 429.921702 -143.92891) (xy 429.862246 -143.936738) (xy 429.802278 -143.936738) (xy 429.742822 -143.92891)
			(xy 429.684897 -143.913389) (xy 429.629493 -143.89044) (xy 429.577559 -143.860456) (xy 429.529983 -143.82395)
			(xy 429.487578 -143.781545) (xy 429.451072 -143.733969) (xy 429.421088 -143.682035) (xy 429.398139 -143.626631)
			(xy 429.382618 -143.568706) (xy 429.37479 -143.50925) (xy 429.3743 -143.479266) (xy 425.777152 -143.479266)
			(xy 425.777152 -145.285714) (xy 432.016408 -145.285714) (xy 432.016408 -144.422114) (xy 432.016898 -144.39213)
			(xy 432.024726 -144.332674) (xy 432.040247 -144.274749) (xy 432.063196 -144.219345) (xy 432.09318 -144.167411)
			(xy 432.129686 -144.119835) (xy 432.172091 -144.07743) (xy 432.219667 -144.040924) (xy 432.271601 -144.01094)
			(xy 432.327005 -143.987991) (xy 432.38493 -143.97247) (xy 432.444386 -143.964642) (xy 432.504354 -143.964642)
			(xy 432.56381 -143.97247) (xy 432.621735 -143.987991) (xy 432.677139 -144.01094) (xy 432.729073 -144.040924)
			(xy 432.776649 -144.07743) (xy 432.819054 -144.119835) (xy 432.85556 -144.167411) (xy 432.885544 -144.219345)
			(xy 432.908493 -144.274749) (xy 432.924014 -144.332674) (xy 432.931842 -144.39213) (xy 432.932332 -144.422114)
			(xy 432.932332 -145.285714) (xy 432.931842 -145.315698) (xy 432.924014 -145.375154) (xy 432.908493 -145.433079)
			(xy 432.885544 -145.488483) (xy 432.85556 -145.540417) (xy 432.819054 -145.587993) (xy 432.776649 -145.630398)
			(xy 432.729073 -145.666904) (xy 432.677139 -145.696888) (xy 432.621735 -145.719837) (xy 432.56381 -145.735358)
			(xy 432.504354 -145.743186) (xy 432.444386 -145.743186) (xy 432.38493 -145.735358) (xy 432.327005 -145.719837)
			(xy 432.271601 -145.696888) (xy 432.219667 -145.666904) (xy 432.172091 -145.630398) (xy 432.129686 -145.587993)
			(xy 432.09318 -145.540417) (xy 432.063196 -145.488483) (xy 432.040247 -145.433079) (xy 432.024726 -145.375154)
			(xy 432.016898 -145.315698) (xy 432.016408 -145.285714) (xy 425.777152 -145.285714) (xy 425.777152 -147.079208)
			(xy 429.3743 -147.079208) (xy 429.3743 -146.215608) (xy 429.37479 -146.185624) (xy 429.382618 -146.126168)
			(xy 429.398139 -146.068243) (xy 429.421088 -146.012839) (xy 429.451072 -145.960905) (xy 429.487578 -145.913329)
			(xy 429.529983 -145.870924) (xy 429.577559 -145.834418) (xy 429.629493 -145.804434) (xy 429.684897 -145.781485)
			(xy 429.742822 -145.765964) (xy 429.802278 -145.758136) (xy 429.862246 -145.758136) (xy 429.921702 -145.765964)
			(xy 429.979627 -145.781485) (xy 430.035031 -145.804434) (xy 430.086965 -145.834418) (xy 430.134541 -145.870924)
			(xy 430.176946 -145.913329) (xy 430.213452 -145.960905) (xy 430.243436 -146.012839) (xy 430.266385 -146.068243)
			(xy 430.281906 -146.126168) (xy 430.289734 -146.185624) (xy 430.290224 -146.215608) (xy 430.290224 -147.079208)
			(xy 430.289734 -147.109192) (xy 430.281906 -147.168648) (xy 430.266385 -147.226573) (xy 430.243436 -147.281977)
			(xy 430.213452 -147.333911) (xy 430.176946 -147.381487) (xy 430.134541 -147.423892) (xy 430.086965 -147.460398)
			(xy 430.035031 -147.490382) (xy 429.979627 -147.513331) (xy 429.921702 -147.528852) (xy 429.862246 -147.53668)
			(xy 429.802278 -147.53668) (xy 429.742822 -147.528852) (xy 429.684897 -147.513331) (xy 429.629493 -147.490382)
			(xy 429.577559 -147.460398) (xy 429.529983 -147.423892) (xy 429.487578 -147.381487) (xy 429.451072 -147.333911)
			(xy 429.421088 -147.281977) (xy 429.398139 -147.226573) (xy 429.382618 -147.168648) (xy 429.37479 -147.109192)
			(xy 429.3743 -147.079208) (xy 425.777152 -147.079208) (xy 425.777152 -148.88591) (xy 432.016408 -148.88591)
			(xy 432.016408 -148.02231) (xy 432.016898 -147.992326) (xy 432.024726 -147.93287) (xy 432.040247 -147.874945)
			(xy 432.063196 -147.819541) (xy 432.09318 -147.767607) (xy 432.129686 -147.720031) (xy 432.172091 -147.677626)
			(xy 432.219667 -147.64112) (xy 432.271601 -147.611136) (xy 432.327005 -147.588187) (xy 432.38493 -147.572666)
			(xy 432.444386 -147.564838) (xy 432.504354 -147.564838) (xy 432.56381 -147.572666) (xy 432.621735 -147.588187)
			(xy 432.677139 -147.611136) (xy 432.729073 -147.64112) (xy 432.776649 -147.677626) (xy 432.819054 -147.720031)
			(xy 432.85556 -147.767607) (xy 432.885544 -147.819541) (xy 432.908493 -147.874945) (xy 432.924014 -147.93287)
			(xy 432.931842 -147.992326) (xy 432.932332 -148.02231) (xy 432.932332 -148.88591) (xy 432.931842 -148.915894)
			(xy 432.924014 -148.97535) (xy 432.908493 -149.033275) (xy 432.885544 -149.088679) (xy 432.85556 -149.140613)
			(xy 432.819054 -149.188189) (xy 432.776649 -149.230594) (xy 432.729073 -149.2671) (xy 432.677139 -149.297084)
			(xy 432.621735 -149.320033) (xy 432.56381 -149.335554) (xy 432.504354 -149.343382) (xy 432.444386 -149.343382)
			(xy 432.38493 -149.335554) (xy 432.327005 -149.320033) (xy 432.271601 -149.297084) (xy 432.219667 -149.2671)
			(xy 432.172091 -149.230594) (xy 432.129686 -149.188189) (xy 432.09318 -149.140613) (xy 432.063196 -149.088679)
			(xy 432.040247 -149.033275) (xy 432.024726 -148.97535) (xy 432.016898 -148.915894) (xy 432.016408 -148.88591)
			(xy 425.777152 -148.88591) (xy 425.777152 -150.67915) (xy 429.3743 -150.67915) (xy 429.3743 -149.81555)
			(xy 429.37479 -149.785566) (xy 429.382618 -149.72611) (xy 429.398139 -149.668185) (xy 429.421088 -149.612781)
			(xy 429.451072 -149.560847) (xy 429.487578 -149.513271) (xy 429.529983 -149.470866) (xy 429.577559 -149.43436)
			(xy 429.629493 -149.404376) (xy 429.684897 -149.381427) (xy 429.742822 -149.365906) (xy 429.802278 -149.358078)
			(xy 429.862246 -149.358078) (xy 429.921702 -149.365906) (xy 429.979627 -149.381427) (xy 430.035031 -149.404376)
			(xy 430.086965 -149.43436) (xy 430.134541 -149.470866) (xy 430.176946 -149.513271) (xy 430.213452 -149.560847)
			(xy 430.243436 -149.612781) (xy 430.266385 -149.668185) (xy 430.281906 -149.72611) (xy 430.289734 -149.785566)
			(xy 430.290224 -149.81555) (xy 430.290224 -150.67915) (xy 430.289734 -150.709134) (xy 430.281906 -150.76859)
			(xy 430.266385 -150.826515) (xy 430.243436 -150.881919) (xy 430.213452 -150.933853) (xy 430.176946 -150.981429)
			(xy 430.134541 -151.023834) (xy 430.086965 -151.06034) (xy 430.035031 -151.090324) (xy 429.979627 -151.113273)
			(xy 429.921702 -151.128794) (xy 429.862246 -151.136622) (xy 429.802278 -151.136622) (xy 429.742822 -151.128794)
			(xy 429.684897 -151.113273) (xy 429.629493 -151.090324) (xy 429.577559 -151.06034) (xy 429.529983 -151.023834)
			(xy 429.487578 -150.981429) (xy 429.451072 -150.933853) (xy 429.421088 -150.881919) (xy 429.398139 -150.826515)
			(xy 429.382618 -150.76859) (xy 429.37479 -150.709134) (xy 429.3743 -150.67915) (xy 425.777152 -150.67915)
			(xy 425.777152 -152.485852) (xy 432.016408 -152.485852) (xy 432.016408 -151.622252) (xy 432.016898 -151.592268)
			(xy 432.024726 -151.532812) (xy 432.040247 -151.474887) (xy 432.063196 -151.419483) (xy 432.09318 -151.367549)
			(xy 432.129686 -151.319973) (xy 432.172091 -151.277568) (xy 432.219667 -151.241062) (xy 432.271601 -151.211078)
			(xy 432.327005 -151.188129) (xy 432.38493 -151.172608) (xy 432.444386 -151.16478) (xy 432.504354 -151.16478)
			(xy 432.56381 -151.172608) (xy 432.621735 -151.188129) (xy 432.677139 -151.211078) (xy 432.729073 -151.241062)
			(xy 432.776649 -151.277568) (xy 432.819054 -151.319973) (xy 432.85556 -151.367549) (xy 432.885544 -151.419483)
			(xy 432.908493 -151.474887) (xy 432.924014 -151.532812) (xy 432.931842 -151.592268) (xy 432.932332 -151.622252)
			(xy 432.932332 -152.485852) (xy 432.931842 -152.515836) (xy 432.924014 -152.575292) (xy 432.908493 -152.633217)
			(xy 432.885544 -152.688621) (xy 432.85556 -152.740555) (xy 432.819054 -152.788131) (xy 432.776649 -152.830536)
			(xy 432.729073 -152.867042) (xy 432.677139 -152.897026) (xy 432.621735 -152.919975) (xy 432.56381 -152.935496)
			(xy 432.504354 -152.943324) (xy 432.444386 -152.943324) (xy 432.38493 -152.935496) (xy 432.327005 -152.919975)
			(xy 432.271601 -152.897026) (xy 432.219667 -152.867042) (xy 432.172091 -152.830536) (xy 432.129686 -152.788131)
			(xy 432.09318 -152.740555) (xy 432.063196 -152.688621) (xy 432.040247 -152.633217) (xy 432.024726 -152.575292)
			(xy 432.016898 -152.515836) (xy 432.016408 -152.485852) (xy 425.777152 -152.485852) (xy 425.777152 -154.279346)
			(xy 429.3743 -154.279346) (xy 429.3743 -153.415746) (xy 429.37479 -153.385762) (xy 429.382618 -153.326306)
			(xy 429.398139 -153.268381) (xy 429.421088 -153.212977) (xy 429.451072 -153.161043) (xy 429.487578 -153.113467)
			(xy 429.529983 -153.071062) (xy 429.577559 -153.034556) (xy 429.629493 -153.004572) (xy 429.684897 -152.981623)
			(xy 429.742822 -152.966102) (xy 429.802278 -152.958274) (xy 429.862246 -152.958274) (xy 429.921702 -152.966102)
			(xy 429.979627 -152.981623) (xy 430.035031 -153.004572) (xy 430.086965 -153.034556) (xy 430.134541 -153.071062)
			(xy 430.176946 -153.113467) (xy 430.213452 -153.161043) (xy 430.243436 -153.212977) (xy 430.266385 -153.268381)
			(xy 430.281906 -153.326306) (xy 430.289734 -153.385762) (xy 430.290224 -153.415746) (xy 430.290224 -154.279346)
			(xy 430.289734 -154.30933) (xy 430.281906 -154.368786) (xy 430.266385 -154.426711) (xy 430.243436 -154.482115)
			(xy 430.213452 -154.534049) (xy 430.176946 -154.581625) (xy 430.134541 -154.62403) (xy 430.086965 -154.660536)
			(xy 430.035031 -154.69052) (xy 429.979627 -154.713469) (xy 429.921702 -154.72899) (xy 429.862246 -154.736818)
			(xy 429.802278 -154.736818) (xy 429.742822 -154.72899) (xy 429.684897 -154.713469) (xy 429.629493 -154.69052)
			(xy 429.577559 -154.660536) (xy 429.529983 -154.62403) (xy 429.487578 -154.581625) (xy 429.451072 -154.534049)
			(xy 429.421088 -154.482115) (xy 429.398139 -154.426711) (xy 429.382618 -154.368786) (xy 429.37479 -154.30933)
			(xy 429.3743 -154.279346) (xy 425.777152 -154.279346) (xy 425.777152 -156.085794) (xy 432.016408 -156.085794)
			(xy 432.016408 -155.222194) (xy 432.016898 -155.19221) (xy 432.024726 -155.132754) (xy 432.040247 -155.074829)
			(xy 432.063196 -155.019425) (xy 432.09318 -154.967491) (xy 432.129686 -154.919915) (xy 432.172091 -154.87751)
			(xy 432.219667 -154.841004) (xy 432.271601 -154.81102) (xy 432.327005 -154.788071) (xy 432.38493 -154.77255)
			(xy 432.444386 -154.764722) (xy 432.504354 -154.764722) (xy 432.56381 -154.77255) (xy 432.621735 -154.788071)
			(xy 432.677139 -154.81102) (xy 432.729073 -154.841004) (xy 432.776649 -154.87751) (xy 432.819054 -154.919915)
			(xy 432.85556 -154.967491) (xy 432.885544 -155.019425) (xy 432.908493 -155.074829) (xy 432.924014 -155.132754)
			(xy 432.931842 -155.19221) (xy 432.932332 -155.222194) (xy 432.932332 -156.085794) (xy 432.931842 -156.115778)
			(xy 432.924014 -156.175234) (xy 432.908493 -156.233159) (xy 432.885544 -156.288563) (xy 432.85556 -156.340497)
			(xy 432.819054 -156.388073) (xy 432.776649 -156.430478) (xy 432.729073 -156.466984) (xy 432.677139 -156.496968)
			(xy 432.621735 -156.519917) (xy 432.56381 -156.535438) (xy 432.504354 -156.543266) (xy 432.444386 -156.543266)
			(xy 432.38493 -156.535438) (xy 432.327005 -156.519917) (xy 432.271601 -156.496968) (xy 432.219667 -156.466984)
			(xy 432.172091 -156.430478) (xy 432.129686 -156.388073) (xy 432.09318 -156.340497) (xy 432.063196 -156.288563)
			(xy 432.040247 -156.233159) (xy 432.024726 -156.175234) (xy 432.016898 -156.115778) (xy 432.016408 -156.085794)
			(xy 425.777152 -156.085794) (xy 425.777152 -158.219648) (xy 429.482248 -158.219648) (xy 429.486319 -158.164026)
			(xy 429.498445 -158.109589) (xy 429.518368 -158.057498) (xy 429.545664 -158.008863) (xy 429.57975 -157.96472)
			(xy 429.619899 -157.926011) (xy 429.665257 -157.89356) (xy 429.714857 -157.868059) (xy 429.767641 -157.850052)
			(xy 429.822484 -157.839922) (xy 429.878218 -157.837885) (xy 429.933655 -157.843985) (xy 429.987612 -157.858091)
			(xy 430.038941 -157.879903) (xy 430.086547 -157.908957) (xy 430.129415 -157.944632) (xy 430.166632 -157.986169)
			(xy 430.197405 -158.032682) (xy 430.221077 -158.083179) (xy 430.237145 -158.136586) (xy 430.245265 -158.191762)
			(xy 430.245774 -158.219648) (xy 430.245265 -158.247534) (xy 430.237145 -158.30271) (xy 430.221077 -158.356117)
			(xy 430.197405 -158.406614) (xy 430.166632 -158.453127) (xy 430.129415 -158.494664) (xy 430.086547 -158.530339)
			(xy 430.038941 -158.559393) (xy 429.987612 -158.581205) (xy 429.933655 -158.595311) (xy 429.878218 -158.601411)
			(xy 429.822484 -158.599374) (xy 429.767641 -158.589244) (xy 429.714857 -158.571237) (xy 429.665257 -158.545736)
			(xy 429.619899 -158.513285) (xy 429.57975 -158.474576) (xy 429.545664 -158.430433) (xy 429.518368 -158.381798)
			(xy 429.498445 -158.329707) (xy 429.486319 -158.27527) (xy 429.482248 -158.219648) (xy 425.777152 -158.219648)
			(xy 425.777152 -159.235648) (xy 429.639982 -159.235648) (xy 429.644053 -159.180026) (xy 429.656179 -159.125589)
			(xy 429.676102 -159.073498) (xy 429.703398 -159.024863) (xy 429.737484 -158.98072) (xy 429.777633 -158.942011)
			(xy 429.822991 -158.90956) (xy 429.872591 -158.884059) (xy 429.925375 -158.866052) (xy 429.980218 -158.855922)
			(xy 430.035952 -158.853885) (xy 430.091389 -158.859985) (xy 430.145346 -158.874091) (xy 430.196675 -158.895903)
			(xy 430.244281 -158.924957) (xy 430.287149 -158.960632) (xy 430.324366 -159.002169) (xy 430.355139 -159.048682)
			(xy 430.378811 -159.099179) (xy 430.394879 -159.152586) (xy 430.402999 -159.207762) (xy 430.403508 -159.235648)
			(xy 430.402999 -159.263534) (xy 430.394879 -159.31871) (xy 430.378811 -159.372117) (xy 430.355139 -159.422614)
			(xy 430.324366 -159.469127) (xy 430.287149 -159.510664) (xy 430.244281 -159.546339) (xy 430.196675 -159.575393)
			(xy 430.145346 -159.597205) (xy 430.091389 -159.611311) (xy 430.035952 -159.617411) (xy 429.980218 -159.615374)
			(xy 429.925375 -159.605244) (xy 429.872591 -159.587237) (xy 429.822991 -159.561736) (xy 429.777633 -159.529285)
			(xy 429.737484 -159.490576) (xy 429.703398 -159.446433) (xy 429.676102 -159.397798) (xy 429.656179 -159.345707)
			(xy 429.644053 -159.29127) (xy 429.639982 -159.235648) (xy 425.777152 -159.235648) (xy 425.777152 -160.344358)
			(xy 425.776621 -160.354348) (xy 425.768913 -160.372786) (xy 425.762166 -160.380172) (xy 425.6151 -160.527238)
			(xy 425.614592 -160.528) (xy 425.605702 -160.53689) (xy 425.605194 -160.537398) (xy 420.68115 -165.461442)
			(xy 420.680642 -165.46195) (xy 420.671752 -165.47084) (xy 420.67099 -165.471348) (xy 420.523924 -165.618414)
			(xy 420.516579 -165.625222) (xy 420.498115 -165.63294) (xy 420.48811 -165.6334) (xy 404.720298 -165.6334)
			(xy 404.710331 -165.633875) (xy 404.69189 -165.641446) (xy 404.684484 -165.648132) (xy 403.627082 -166.705534)
			(xy 409.41193 -166.705534) (xy 409.416001 -166.649912) (xy 409.428127 -166.595475) (xy 409.44805 -166.543384)
			(xy 409.475346 -166.494749) (xy 409.509432 -166.450606) (xy 409.549581 -166.411897) (xy 409.594939 -166.379446)
			(xy 409.644539 -166.353945) (xy 409.697323 -166.335938) (xy 409.752166 -166.325808) (xy 409.8079 -166.323771)
			(xy 409.863337 -166.329871) (xy 409.917294 -166.343977) (xy 409.968623 -166.365789) (xy 410.016229 -166.394843)
			(xy 410.059097 -166.430518) (xy 410.096314 -166.472055) (xy 410.127087 -166.518568) (xy 410.150759 -166.569065)
			(xy 410.166827 -166.622472) (xy 410.174947 -166.677648) (xy 410.175456 -166.705534) (xy 410.42793 -166.705534)
			(xy 410.432001 -166.649912) (xy 410.444127 -166.595475) (xy 410.46405 -166.543384) (xy 410.491346 -166.494749)
			(xy 410.525432 -166.450606) (xy 410.565581 -166.411897) (xy 410.610939 -166.379446) (xy 410.660539 -166.353945)
			(xy 410.713323 -166.335938) (xy 410.768166 -166.325808) (xy 410.8239 -166.323771) (xy 410.879337 -166.329871)
			(xy 410.933294 -166.343977) (xy 410.984623 -166.365789) (xy 411.032229 -166.394843) (xy 411.075097 -166.430518)
			(xy 411.112314 -166.472055) (xy 411.143087 -166.518568) (xy 411.166759 -166.569065) (xy 411.182827 -166.622472)
			(xy 411.190947 -166.677648) (xy 411.191456 -166.705534) (xy 411.44393 -166.705534) (xy 411.448001 -166.649912)
			(xy 411.460127 -166.595475) (xy 411.48005 -166.543384) (xy 411.507346 -166.494749) (xy 411.541432 -166.450606)
			(xy 411.581581 -166.411897) (xy 411.626939 -166.379446) (xy 411.676539 -166.353945) (xy 411.729323 -166.335938)
			(xy 411.784166 -166.325808) (xy 411.8399 -166.323771) (xy 411.895337 -166.329871) (xy 411.949294 -166.343977)
			(xy 412.000623 -166.365789) (xy 412.048229 -166.394843) (xy 412.091097 -166.430518) (xy 412.128314 -166.472055)
			(xy 412.159087 -166.518568) (xy 412.182759 -166.569065) (xy 412.198827 -166.622472) (xy 412.206947 -166.677648)
			(xy 412.207456 -166.705534) (xy 412.206947 -166.73342) (xy 412.198827 -166.788596) (xy 412.182759 -166.842003)
			(xy 412.159087 -166.8925) (xy 412.128314 -166.939013) (xy 412.091097 -166.98055) (xy 412.048229 -167.016225)
			(xy 412.000623 -167.045279) (xy 411.949294 -167.067091) (xy 411.895337 -167.081197) (xy 411.8399 -167.087297)
			(xy 411.784166 -167.08526) (xy 411.729323 -167.07513) (xy 411.676539 -167.057123) (xy 411.626939 -167.031622)
			(xy 411.581581 -166.999171) (xy 411.541432 -166.960462) (xy 411.507346 -166.916319) (xy 411.48005 -166.867684)
			(xy 411.460127 -166.815593) (xy 411.448001 -166.761156) (xy 411.44393 -166.705534) (xy 411.191456 -166.705534)
			(xy 411.190947 -166.73342) (xy 411.182827 -166.788596) (xy 411.166759 -166.842003) (xy 411.143087 -166.8925)
			(xy 411.112314 -166.939013) (xy 411.075097 -166.98055) (xy 411.032229 -167.016225) (xy 410.984623 -167.045279)
			(xy 410.933294 -167.067091) (xy 410.879337 -167.081197) (xy 410.8239 -167.087297) (xy 410.768166 -167.08526)
			(xy 410.713323 -167.07513) (xy 410.660539 -167.057123) (xy 410.610939 -167.031622) (xy 410.565581 -166.999171)
			(xy 410.525432 -166.960462) (xy 410.491346 -166.916319) (xy 410.46405 -166.867684) (xy 410.444127 -166.815593)
			(xy 410.432001 -166.761156) (xy 410.42793 -166.705534) (xy 410.175456 -166.705534) (xy 410.174947 -166.73342)
			(xy 410.166827 -166.788596) (xy 410.150759 -166.842003) (xy 410.127087 -166.8925) (xy 410.096314 -166.939013)
			(xy 410.059097 -166.98055) (xy 410.016229 -167.016225) (xy 409.968623 -167.045279) (xy 409.917294 -167.067091)
			(xy 409.863337 -167.081197) (xy 409.8079 -167.087297) (xy 409.752166 -167.08526) (xy 409.697323 -167.07513)
			(xy 409.644539 -167.057123) (xy 409.594939 -167.031622) (xy 409.549581 -166.999171) (xy 409.509432 -166.960462)
			(xy 409.475346 -166.916319) (xy 409.44805 -166.867684) (xy 409.428127 -166.815593) (xy 409.416001 -166.761156)
			(xy 409.41193 -166.705534) (xy 403.627082 -166.705534) (xy 402.213318 -168.119298) (xy 402.21281 -168.119806)
			(xy 402.20392 -168.128696) (xy 402.203412 -168.12895) (xy 402.056092 -168.27627) (xy 402.048748 -168.283083)
			(xy 402.030285 -168.290817) (xy 402.020278 -168.291256) (xy 399.77822 -168.291256) (xy 399.770346 -168.29786)
			(xy 399.717514 -168.352216) (xy 399.71183 -168.359337) (xy 399.705444 -168.376387) (xy 399.705068 -168.38549)
			(xy 399.705068 -168.390824) (xy 399.705322 -168.395142) (xy 399.705322 -168.397428) (xy 399.704855 -168.424798)
			(xy 399.697035 -168.478977) (xy 399.681547 -168.531481) (xy 399.658709 -168.581229) (xy 399.628989 -168.6272)
			(xy 399.611342 -168.648126) (xy 399.605754 -168.654476) (xy 399.59534 -168.68013) (xy 399.593627 -168.684702)
			(xy 399.591833 -168.694298) (xy 399.591784 -168.69918) (xy 399.591784 -172.409104) (xy 400.429982 -172.409104)
			(xy 400.434053 -172.353482) (xy 400.446179 -172.299045) (xy 400.466102 -172.246954) (xy 400.493398 -172.198319)
			(xy 400.527484 -172.154176) (xy 400.567633 -172.115467) (xy 400.612991 -172.083016) (xy 400.662591 -172.057515)
			(xy 400.715375 -172.039508) (xy 400.770218 -172.029378) (xy 400.825952 -172.027341) (xy 400.881389 -172.033441)
			(xy 400.935346 -172.047547) (xy 400.986675 -172.069359) (xy 401.034281 -172.098413) (xy 401.077149 -172.134088)
			(xy 401.114366 -172.175625) (xy 401.145139 -172.222138) (xy 401.168811 -172.272635) (xy 401.184879 -172.326042)
			(xy 401.185366 -172.329348) (xy 410.148022 -172.329348) (xy 410.152093 -172.273726) (xy 410.164219 -172.219289)
			(xy 410.184142 -172.167198) (xy 410.211438 -172.118563) (xy 410.245524 -172.07442) (xy 410.285673 -172.035711)
			(xy 410.331031 -172.00326) (xy 410.380631 -171.977759) (xy 410.433415 -171.959752) (xy 410.488258 -171.949622)
			(xy 410.543992 -171.947585) (xy 410.599429 -171.953685) (xy 410.653386 -171.967791) (xy 410.704715 -171.989603)
			(xy 410.752321 -172.018657) (xy 410.795189 -172.054332) (xy 410.832406 -172.095869) (xy 410.863179 -172.142382)
			(xy 410.886851 -172.192879) (xy 410.902919 -172.246286) (xy 410.911039 -172.301462) (xy 410.911548 -172.329348)
			(xy 410.911284 -172.343826) (xy 411.085282 -172.343826) (xy 411.089353 -172.288204) (xy 411.101479 -172.233767)
			(xy 411.121402 -172.181676) (xy 411.148698 -172.133041) (xy 411.182784 -172.088898) (xy 411.222933 -172.050189)
			(xy 411.268291 -172.017738) (xy 411.317891 -171.992237) (xy 411.370675 -171.97423) (xy 411.425518 -171.9641)
			(xy 411.481252 -171.962063) (xy 411.536689 -171.968163) (xy 411.590646 -171.982269) (xy 411.641975 -172.004081)
			(xy 411.689581 -172.033135) (xy 411.732449 -172.06881) (xy 411.769666 -172.110347) (xy 411.800439 -172.15686)
			(xy 411.824111 -172.207357) (xy 411.840179 -172.260764) (xy 411.848299 -172.31594) (xy 411.848808 -172.343826)
			(xy 411.848299 -172.371712) (xy 411.840179 -172.426888) (xy 411.824111 -172.480295) (xy 411.800439 -172.530792)
			(xy 411.769666 -172.577305) (xy 411.732449 -172.618842) (xy 411.689581 -172.654517) (xy 411.641975 -172.683571)
			(xy 411.590646 -172.705383) (xy 411.536689 -172.719489) (xy 411.481252 -172.725589) (xy 411.425518 -172.723552)
			(xy 411.370675 -172.713422) (xy 411.317891 -172.695415) (xy 411.268291 -172.669914) (xy 411.222933 -172.637463)
			(xy 411.182784 -172.598754) (xy 411.148698 -172.554611) (xy 411.121402 -172.505976) (xy 411.101479 -172.453885)
			(xy 411.089353 -172.399448) (xy 411.085282 -172.343826) (xy 410.911284 -172.343826) (xy 410.911039 -172.357234)
			(xy 410.902919 -172.41241) (xy 410.886851 -172.465817) (xy 410.863179 -172.516314) (xy 410.832406 -172.562827)
			(xy 410.795189 -172.604364) (xy 410.752321 -172.640039) (xy 410.704715 -172.669093) (xy 410.653386 -172.690905)
			(xy 410.599429 -172.705011) (xy 410.543992 -172.711111) (xy 410.488258 -172.709074) (xy 410.433415 -172.698944)
			(xy 410.380631 -172.680937) (xy 410.331031 -172.655436) (xy 410.285673 -172.622985) (xy 410.245524 -172.584276)
			(xy 410.211438 -172.540133) (xy 410.184142 -172.491498) (xy 410.164219 -172.439407) (xy 410.152093 -172.38497)
			(xy 410.148022 -172.329348) (xy 401.185366 -172.329348) (xy 401.192999 -172.381218) (xy 401.193508 -172.409104)
			(xy 401.192999 -172.43699) (xy 401.184879 -172.492166) (xy 401.168811 -172.545573) (xy 401.145139 -172.59607)
			(xy 401.114366 -172.642583) (xy 401.077149 -172.68412) (xy 401.034281 -172.719795) (xy 400.986675 -172.748849)
			(xy 400.935346 -172.770661) (xy 400.881389 -172.784767) (xy 400.825952 -172.790867) (xy 400.770218 -172.78883)
			(xy 400.715375 -172.7787) (xy 400.662591 -172.760693) (xy 400.612991 -172.735192) (xy 400.567633 -172.702741)
			(xy 400.527484 -172.664032) (xy 400.493398 -172.619889) (xy 400.466102 -172.571254) (xy 400.446179 -172.519163)
			(xy 400.434053 -172.464726) (xy 400.429982 -172.409104) (xy 399.591784 -172.409104) (xy 399.591784 -173.103286)
			(xy 399.592205 -173.112655) (xy 399.598935 -173.130143) (xy 399.6115 -173.144043) (xy 399.628222 -173.152498)
			(xy 399.637504 -173.153832) (xy 399.911316 -173.153832) (xy 399.915634 -173.154086) (xy 400.027648 -173.154086)
			(xy 400.037715 -173.154517) (xy 400.056308 -173.162242) (xy 400.063716 -173.169072) (xy 400.14144 -173.246796)
			(xy 400.142202 -173.247304) (xy 400.146012 -173.251114) (xy 400.744436 -173.849538) (xy 400.749949 -173.85386)
			(xy 400.762702 -173.859645) (xy 400.769582 -173.860968) (xy 400.777202 -173.861476) (xy 409.079192 -173.861476)
			(xy 409.090876 -173.858428) (xy 409.095702 -173.856142) (xy 409.09748 -173.855126) (xy 409.097988 -173.854872)
			(xy 409.125367 -173.841291) (xy 409.183376 -173.822059) (xy 409.243707 -173.812315) (xy 409.274264 -173.811692)
			(xy 409.301519 -173.812153) (xy 409.355473 -173.819906) (xy 409.407776 -173.835259) (xy 409.45736 -173.857899)
			(xy 409.503218 -173.887366) (xy 409.544415 -173.92306) (xy 409.580112 -173.964253) (xy 409.609584 -174.010108)
			(xy 409.632229 -174.059691) (xy 409.647587 -174.111991) (xy 409.655345 -174.165946) (xy 409.655345 -174.220454)
			(xy 409.647587 -174.274409) (xy 409.632229 -174.326709) (xy 409.609584 -174.376292) (xy 409.580112 -174.422147)
			(xy 409.544415 -174.46334) (xy 409.503218 -174.499034) (xy 409.45736 -174.528501) (xy 409.407776 -174.551141)
			(xy 409.355473 -174.566494) (xy 409.301519 -174.574247) (xy 409.274264 -174.574708) (xy 409.243705 -174.574109)
			(xy 409.183369 -174.56437) (xy 409.125358 -174.545132) (xy 409.097988 -174.531528) (xy 409.09748 -174.531274)
			(xy 409.095702 -174.530258) (xy 409.090876 -174.527972) (xy 409.079192 -174.524924) (xy 400.502374 -174.524924)
			(xy 400.492305 -174.524497) (xy 400.473705 -174.516778) (xy 400.466306 -174.509938) (xy 400.388582 -174.432214)
			(xy 400.38782 -174.431706) (xy 400.38401 -174.427896) (xy 399.78838 -173.832266) (xy 399.784649 -173.828746)
			(xy 399.776073 -173.823119) (xy 399.771362 -173.82109) (xy 399.763488 -173.817788) (xy 399.612104 -173.817788)
			(xy 399.603006 -173.825394) (xy 399.592425 -173.846585) (xy 399.591784 -173.858428) (xy 399.591784 -175.032416)
			(xy 399.591358 -175.042485) (xy 399.583637 -175.061083) (xy 399.576798 -175.068484) (xy 398.950688 -175.694594)
			(xy 398.943289 -175.701439) (xy 398.924691 -175.70917) (xy 398.91462 -175.70958) (xy 381.067564 -175.70958)
			(xy 381.061554 -175.709746) (xy 381.04987 -175.712565) (xy 381.04445 -175.715168) (xy 381.040976 -175.717008)
			(xy 381.034598 -175.721603) (xy 381.03175 -175.724312) (xy 380.925832 -175.83023) (xy 410.059884 -175.83023)
			(xy 410.063955 -175.774608) (xy 410.076081 -175.720171) (xy 410.096004 -175.66808) (xy 410.1233 -175.619445)
			(xy 410.157386 -175.575302) (xy 410.197535 -175.536593) (xy 410.242893 -175.504142) (xy 410.292493 -175.478641)
			(xy 410.345277 -175.460634) (xy 410.40012 -175.450504) (xy 410.455854 -175.448467) (xy 410.511291 -175.454567)
			(xy 410.565248 -175.468673) (xy 410.616577 -175.490485) (xy 410.664183 -175.519539) (xy 410.707051 -175.555214)
			(xy 410.744268 -175.596751) (xy 410.775041 -175.643264) (xy 410.798713 -175.693761) (xy 410.814781 -175.747168)
			(xy 410.822901 -175.802344) (xy 410.82341 -175.83023) (xy 410.822901 -175.858116) (xy 410.814781 -175.913292)
			(xy 410.798713 -175.966699) (xy 410.775041 -176.017196) (xy 410.744268 -176.063709) (xy 410.707051 -176.105246)
			(xy 410.664183 -176.140921) (xy 410.616577 -176.169975) (xy 410.565248 -176.191787) (xy 410.511291 -176.205893)
			(xy 410.455854 -176.211993) (xy 410.40012 -176.209956) (xy 410.345277 -176.199826) (xy 410.292493 -176.181819)
			(xy 410.242893 -176.156318) (xy 410.197535 -176.123867) (xy 410.157386 -176.085158) (xy 410.1233 -176.041015)
			(xy 410.096004 -175.99238) (xy 410.076081 -175.940289) (xy 410.063955 -175.885852) (xy 410.059884 -175.83023)
			(xy 380.925832 -175.83023) (xy 377.457462 -179.2986) (xy 409.269182 -179.2986) (xy 409.273253 -179.242978)
			(xy 409.285379 -179.188541) (xy 409.305302 -179.13645) (xy 409.332598 -179.087815) (xy 409.366684 -179.043672)
			(xy 409.406833 -179.004963) (xy 409.452191 -178.972512) (xy 409.501791 -178.947011) (xy 409.554575 -178.929004)
			(xy 409.609418 -178.918874) (xy 409.665152 -178.916837) (xy 409.720589 -178.922937) (xy 409.774546 -178.937043)
			(xy 409.825875 -178.958855) (xy 409.873481 -178.987909) (xy 409.916349 -179.023584) (xy 409.953566 -179.065121)
			(xy 409.984339 -179.111634) (xy 410.008011 -179.162131) (xy 410.024079 -179.215538) (xy 410.032199 -179.270714)
			(xy 410.032708 -179.2986) (xy 411.250382 -179.2986) (xy 411.254453 -179.242978) (xy 411.266579 -179.188541)
			(xy 411.286502 -179.13645) (xy 411.313798 -179.087815) (xy 411.347884 -179.043672) (xy 411.388033 -179.004963)
			(xy 411.433391 -178.972512) (xy 411.482991 -178.947011) (xy 411.535775 -178.929004) (xy 411.590618 -178.918874)
			(xy 411.646352 -178.916837) (xy 411.701789 -178.922937) (xy 411.755746 -178.937043) (xy 411.807075 -178.958855)
			(xy 411.854681 -178.987909) (xy 411.897549 -179.023584) (xy 411.934766 -179.065121) (xy 411.965539 -179.111634)
			(xy 411.989211 -179.162131) (xy 412.005279 -179.215538) (xy 412.013399 -179.270714) (xy 412.013908 -179.2986)
			(xy 412.013399 -179.326486) (xy 412.005279 -179.381662) (xy 411.989211 -179.435069) (xy 411.965539 -179.485566)
			(xy 411.934766 -179.532079) (xy 411.897549 -179.573616) (xy 411.854681 -179.609291) (xy 411.807075 -179.638345)
			(xy 411.755746 -179.660157) (xy 411.701789 -179.674263) (xy 411.646352 -179.680363) (xy 411.590618 -179.678326)
			(xy 411.535775 -179.668196) (xy 411.482991 -179.650189) (xy 411.433391 -179.624688) (xy 411.388033 -179.592237)
			(xy 411.347884 -179.553528) (xy 411.313798 -179.509385) (xy 411.286502 -179.46075) (xy 411.266579 -179.408659)
			(xy 411.254453 -179.354222) (xy 411.250382 -179.2986) (xy 410.032708 -179.2986) (xy 410.032199 -179.326486)
			(xy 410.024079 -179.381662) (xy 410.008011 -179.435069) (xy 409.984339 -179.485566) (xy 409.953566 -179.532079)
			(xy 409.916349 -179.573616) (xy 409.873481 -179.609291) (xy 409.825875 -179.638345) (xy 409.774546 -179.660157)
			(xy 409.720589 -179.674263) (xy 409.665152 -179.680363) (xy 409.609418 -179.678326) (xy 409.554575 -179.668196)
			(xy 409.501791 -179.650189) (xy 409.452191 -179.624688) (xy 409.406833 -179.592237) (xy 409.366684 -179.553528)
			(xy 409.332598 -179.509385) (xy 409.305302 -179.46075) (xy 409.285379 -179.408659) (xy 409.273253 -179.354222)
			(xy 409.269182 -179.2986) (xy 377.457462 -179.2986) (xy 377.364244 -179.391818) (xy 377.361539 -179.394669)
			(xy 377.356947 -179.401048) (xy 377.3551 -179.404518) (xy 377.352514 -179.409944) (xy 377.349685 -179.421624)
			(xy 377.349512 -179.427632) (xy 377.349512 -179.728368) (xy 399.71675 -179.728368) (xy 399.720821 -179.672746)
			(xy 399.732947 -179.618309) (xy 399.75287 -179.566218) (xy 399.780166 -179.517583) (xy 399.814252 -179.47344)
			(xy 399.854401 -179.434731) (xy 399.899759 -179.40228) (xy 399.949359 -179.376779) (xy 400.002143 -179.358772)
			(xy 400.056986 -179.348642) (xy 400.11272 -179.346605) (xy 400.168157 -179.352705) (xy 400.222114 -179.366811)
			(xy 400.273443 -179.388623) (xy 400.321049 -179.417677) (xy 400.363917 -179.453352) (xy 400.401134 -179.494889)
			(xy 400.431907 -179.541402) (xy 400.455579 -179.591899) (xy 400.471647 -179.645306) (xy 400.479767 -179.700482)
			(xy 400.480276 -179.728368) (xy 400.479767 -179.756254) (xy 400.471647 -179.81143) (xy 400.455579 -179.864837)
			(xy 400.431907 -179.915334) (xy 400.401134 -179.961847) (xy 400.363917 -180.003384) (xy 400.321049 -180.039059)
			(xy 400.273443 -180.068113) (xy 400.222114 -180.089925) (xy 400.168157 -180.104031) (xy 400.11272 -180.110131)
			(xy 400.056986 -180.108094) (xy 400.002143 -180.097964) (xy 399.949359 -180.079957) (xy 399.899759 -180.054456)
			(xy 399.854401 -180.022005) (xy 399.814252 -179.983296) (xy 399.780166 -179.939153) (xy 399.75287 -179.890518)
			(xy 399.732947 -179.838427) (xy 399.720821 -179.78399) (xy 399.71675 -179.728368) (xy 377.349512 -179.728368)
			(xy 377.349512 -180.699918) (xy 413.180782 -180.699918) (xy 413.184853 -180.644296) (xy 413.196979 -180.589859)
			(xy 413.216902 -180.537768) (xy 413.244198 -180.489133) (xy 413.278284 -180.44499) (xy 413.318433 -180.406281)
			(xy 413.363791 -180.37383) (xy 413.413391 -180.348329) (xy 413.466175 -180.330322) (xy 413.521018 -180.320192)
			(xy 413.576752 -180.318155) (xy 413.632189 -180.324255) (xy 413.686146 -180.338361) (xy 413.737475 -180.360173)
			(xy 413.785081 -180.389227) (xy 413.827949 -180.424902) (xy 413.865166 -180.466439) (xy 413.895939 -180.512952)
			(xy 413.919611 -180.563449) (xy 413.935679 -180.616856) (xy 413.943799 -180.672032) (xy 413.944308 -180.699918)
			(xy 413.943799 -180.727804) (xy 413.935679 -180.78298) (xy 413.919611 -180.836387) (xy 413.895939 -180.886884)
			(xy 413.865166 -180.933397) (xy 413.827949 -180.974934) (xy 413.785081 -181.010609) (xy 413.737475 -181.039663)
			(xy 413.686146 -181.061475) (xy 413.632189 -181.075581) (xy 413.576752 -181.081681) (xy 413.521018 -181.079644)
			(xy 413.466175 -181.069514) (xy 413.413391 -181.051507) (xy 413.363791 -181.026006) (xy 413.318433 -180.993555)
			(xy 413.278284 -180.954846) (xy 413.244198 -180.910703) (xy 413.216902 -180.862068) (xy 413.196979 -180.809977)
			(xy 413.184853 -180.75554) (xy 413.180782 -180.699918) (xy 377.349512 -180.699918) (xy 377.349512 -183.496458)
			(xy 408.81884 -183.496458) (xy 408.822911 -183.440836) (xy 408.835037 -183.386399) (xy 408.85496 -183.334308)
			(xy 408.882256 -183.285673) (xy 408.916342 -183.24153) (xy 408.956491 -183.202821) (xy 409.001849 -183.17037)
			(xy 409.051449 -183.144869) (xy 409.104233 -183.126862) (xy 409.159076 -183.116732) (xy 409.21481 -183.114695)
			(xy 409.270247 -183.120795) (xy 409.324204 -183.134901) (xy 409.375533 -183.156713) (xy 409.423139 -183.185767)
			(xy 409.466007 -183.221442) (xy 409.503224 -183.262979) (xy 409.533997 -183.309492) (xy 409.557669 -183.359989)
			(xy 409.573737 -183.413396) (xy 409.581857 -183.468572) (xy 409.582366 -183.496458) (xy 409.581857 -183.524344)
			(xy 409.573737 -183.57952) (xy 409.557669 -183.632927) (xy 409.533997 -183.683424) (xy 409.527794 -183.6928)
			(xy 411.224982 -183.6928) (xy 411.229053 -183.637178) (xy 411.241179 -183.582741) (xy 411.261102 -183.53065)
			(xy 411.288398 -183.482015) (xy 411.322484 -183.437872) (xy 411.362633 -183.399163) (xy 411.407991 -183.366712)
			(xy 411.457591 -183.341211) (xy 411.510375 -183.323204) (xy 411.565218 -183.313074) (xy 411.620952 -183.311037)
			(xy 411.676389 -183.317137) (xy 411.730346 -183.331243) (xy 411.781675 -183.353055) (xy 411.829281 -183.382109)
			(xy 411.872149 -183.417784) (xy 411.909366 -183.459321) (xy 411.940139 -183.505834) (xy 411.963811 -183.556331)
			(xy 411.979879 -183.609738) (xy 411.987999 -183.664914) (xy 411.988508 -183.6928) (xy 411.987999 -183.720686)
			(xy 411.979879 -183.775862) (xy 411.963811 -183.829269) (xy 411.940139 -183.879766) (xy 411.909366 -183.926279)
			(xy 411.872149 -183.967816) (xy 411.829281 -184.003491) (xy 411.781675 -184.032545) (xy 411.730346 -184.054357)
			(xy 411.676389 -184.068463) (xy 411.620952 -184.074563) (xy 411.565218 -184.072526) (xy 411.510375 -184.062396)
			(xy 411.457591 -184.044389) (xy 411.407991 -184.018888) (xy 411.362633 -183.986437) (xy 411.322484 -183.947728)
			(xy 411.288398 -183.903585) (xy 411.261102 -183.85495) (xy 411.241179 -183.802859) (xy 411.229053 -183.748422)
			(xy 411.224982 -183.6928) (xy 409.527794 -183.6928) (xy 409.503224 -183.729937) (xy 409.466007 -183.771474)
			(xy 409.423139 -183.807149) (xy 409.375533 -183.836203) (xy 409.324204 -183.858015) (xy 409.270247 -183.872121)
			(xy 409.21481 -183.878221) (xy 409.159076 -183.876184) (xy 409.104233 -183.866054) (xy 409.051449 -183.848047)
			(xy 409.001849 -183.822546) (xy 408.956491 -183.790095) (xy 408.916342 -183.751386) (xy 408.882256 -183.707243)
			(xy 408.85496 -183.658608) (xy 408.835037 -183.606517) (xy 408.822911 -183.55208) (xy 408.81884 -183.496458)
			(xy 377.349512 -183.496458) (xy 377.349512 -184.941718) (xy 414.979864 -184.941718) (xy 414.983935 -184.886096)
			(xy 414.996061 -184.831659) (xy 415.015984 -184.779568) (xy 415.04328 -184.730933) (xy 415.077366 -184.68679)
			(xy 415.117515 -184.648081) (xy 415.162873 -184.61563) (xy 415.212473 -184.590129) (xy 415.265257 -184.572122)
			(xy 415.3201 -184.561992) (xy 415.375834 -184.559955) (xy 415.431271 -184.566055) (xy 415.485228 -184.580161)
			(xy 415.536557 -184.601973) (xy 415.584163 -184.631027) (xy 415.627031 -184.666702) (xy 415.664248 -184.708239)
			(xy 415.695021 -184.754752) (xy 415.718693 -184.805249) (xy 415.734761 -184.858656) (xy 415.742881 -184.913832)
			(xy 415.74339 -184.941718) (xy 415.742881 -184.969604) (xy 415.734761 -185.02478) (xy 415.718693 -185.078187)
			(xy 415.695021 -185.128684) (xy 415.664248 -185.175197) (xy 415.627031 -185.216734) (xy 415.584163 -185.252409)
			(xy 415.536557 -185.281463) (xy 415.485228 -185.303275) (xy 415.431271 -185.317381) (xy 415.375834 -185.323481)
			(xy 415.3201 -185.321444) (xy 415.265257 -185.311314) (xy 415.212473 -185.293307) (xy 415.162873 -185.267806)
			(xy 415.117515 -185.235355) (xy 415.077366 -185.196646) (xy 415.04328 -185.152503) (xy 415.015984 -185.103868)
			(xy 414.996061 -185.051777) (xy 414.983935 -184.99734) (xy 414.979864 -184.941718) (xy 377.349512 -184.941718)
			(xy 377.349512 -185.801) (xy 377.569982 -185.801) (xy 377.574053 -185.745378) (xy 377.586179 -185.690941)
			(xy 377.606102 -185.63885) (xy 377.633398 -185.590215) (xy 377.667484 -185.546072) (xy 377.707633 -185.507363)
			(xy 377.752991 -185.474912) (xy 377.802591 -185.449411) (xy 377.855375 -185.431404) (xy 377.910218 -185.421274)
			(xy 377.965952 -185.419237) (xy 378.021389 -185.425337) (xy 378.075346 -185.439443) (xy 378.126675 -185.461255)
			(xy 378.174281 -185.490309) (xy 378.217149 -185.525984) (xy 378.254366 -185.567521) (xy 378.285139 -185.614034)
			(xy 378.308811 -185.664531) (xy 378.324879 -185.717938) (xy 378.332999 -185.773114) (xy 378.333508 -185.801)
			(xy 378.332999 -185.828886) (xy 378.324879 -185.884062) (xy 378.308811 -185.937469) (xy 378.285139 -185.987966)
			(xy 378.254366 -186.034479) (xy 378.217149 -186.076016) (xy 378.174281 -186.111691) (xy 378.126675 -186.140745)
			(xy 378.075346 -186.162557) (xy 378.021389 -186.176663) (xy 377.965952 -186.182763) (xy 377.910218 -186.180726)
			(xy 377.855375 -186.170596) (xy 377.802591 -186.152589) (xy 377.752991 -186.127088) (xy 377.707633 -186.094637)
			(xy 377.667484 -186.055928) (xy 377.633398 -186.011785) (xy 377.606102 -185.96315) (xy 377.586179 -185.911059)
			(xy 377.574053 -185.856622) (xy 377.569982 -185.801) (xy 377.349512 -185.801) (xy 377.349512 -186.937142)
			(xy 408.89504 -186.937142) (xy 408.899111 -186.88152) (xy 408.911237 -186.827083) (xy 408.93116 -186.774992)
			(xy 408.958456 -186.726357) (xy 408.992542 -186.682214) (xy 409.032691 -186.643505) (xy 409.078049 -186.611054)
			(xy 409.127649 -186.585553) (xy 409.180433 -186.567546) (xy 409.235276 -186.557416) (xy 409.29101 -186.555379)
			(xy 409.346447 -186.561479) (xy 409.400404 -186.575585) (xy 409.451733 -186.597397) (xy 409.499339 -186.626451)
			(xy 409.542207 -186.662126) (xy 409.579424 -186.703663) (xy 409.610197 -186.750176) (xy 409.633869 -186.800673)
			(xy 409.649937 -186.85408) (xy 409.658057 -186.909256) (xy 409.658566 -186.937142) (xy 409.658057 -186.965028)
			(xy 409.649937 -187.020204) (xy 409.633869 -187.073611) (xy 409.610197 -187.124108) (xy 409.579424 -187.170621)
			(xy 409.542207 -187.212158) (xy 409.499339 -187.247833) (xy 409.451733 -187.276887) (xy 409.400404 -187.298699)
			(xy 409.346447 -187.312805) (xy 409.29101 -187.318905) (xy 409.235276 -187.316868) (xy 409.180433 -187.306738)
			(xy 409.127649 -187.288731) (xy 409.078049 -187.26323) (xy 409.032691 -187.230779) (xy 408.992542 -187.19207)
			(xy 408.958456 -187.147927) (xy 408.93116 -187.099292) (xy 408.911237 -187.047201) (xy 408.899111 -186.992764)
			(xy 408.89504 -186.937142) (xy 377.349512 -186.937142) (xy 377.349512 -187.833) (xy 377.755656 -187.833)
			(xy 377.759727 -187.777378) (xy 377.771853 -187.722941) (xy 377.791776 -187.67085) (xy 377.819072 -187.622215)
			(xy 377.853158 -187.578072) (xy 377.893307 -187.539363) (xy 377.938665 -187.506912) (xy 377.988265 -187.481411)
			(xy 378.041049 -187.463404) (xy 378.095892 -187.453274) (xy 378.151626 -187.451237) (xy 378.207063 -187.457337)
			(xy 378.26102 -187.471443) (xy 378.312349 -187.493255) (xy 378.359955 -187.522309) (xy 378.367034 -187.5282)
			(xy 411.123382 -187.5282) (xy 411.127453 -187.472578) (xy 411.139579 -187.418141) (xy 411.159502 -187.36605)
			(xy 411.186798 -187.317415) (xy 411.220884 -187.273272) (xy 411.261033 -187.234563) (xy 411.306391 -187.202112)
			(xy 411.355991 -187.176611) (xy 411.408775 -187.158604) (xy 411.463618 -187.148474) (xy 411.519352 -187.146437)
			(xy 411.574789 -187.152537) (xy 411.628746 -187.166643) (xy 411.680075 -187.188455) (xy 411.727681 -187.217509)
			(xy 411.770549 -187.253184) (xy 411.807766 -187.294721) (xy 411.838539 -187.341234) (xy 411.862211 -187.391731)
			(xy 411.878279 -187.445138) (xy 411.886399 -187.500314) (xy 411.886908 -187.5282) (xy 411.886399 -187.556086)
			(xy 411.878279 -187.611262) (xy 411.862211 -187.664669) (xy 411.838539 -187.715166) (xy 411.807766 -187.761679)
			(xy 411.770549 -187.803216) (xy 411.727681 -187.838891) (xy 411.680075 -187.867945) (xy 411.628746 -187.889757)
			(xy 411.574789 -187.903863) (xy 411.519352 -187.909963) (xy 411.463618 -187.907926) (xy 411.408775 -187.897796)
			(xy 411.355991 -187.879789) (xy 411.306391 -187.854288) (xy 411.261033 -187.821837) (xy 411.220884 -187.783128)
			(xy 411.186798 -187.738985) (xy 411.159502 -187.69035) (xy 411.139579 -187.638259) (xy 411.127453 -187.583822)
			(xy 411.123382 -187.5282) (xy 378.367034 -187.5282) (xy 378.402823 -187.557984) (xy 378.44004 -187.599521)
			(xy 378.470813 -187.646034) (xy 378.494485 -187.696531) (xy 378.510553 -187.749938) (xy 378.518673 -187.805114)
			(xy 378.519182 -187.833) (xy 378.518673 -187.860886) (xy 378.510553 -187.916062) (xy 378.494485 -187.969469)
			(xy 378.470813 -188.019966) (xy 378.44004 -188.066479) (xy 378.402823 -188.108016) (xy 378.359955 -188.143691)
			(xy 378.312349 -188.172745) (xy 378.26102 -188.194557) (xy 378.207063 -188.208663) (xy 378.151626 -188.214763)
			(xy 378.095892 -188.212726) (xy 378.041049 -188.202596) (xy 377.988265 -188.184589) (xy 377.938665 -188.159088)
			(xy 377.893307 -188.126637) (xy 377.853158 -188.087928) (xy 377.819072 -188.043785) (xy 377.791776 -187.99515)
			(xy 377.771853 -187.943059) (xy 377.759727 -187.888622) (xy 377.755656 -187.833) (xy 377.349512 -187.833)
			(xy 377.349512 -189.10554) (xy 377.34966 -189.107318) (xy 410.255464 -189.107318) (xy 410.259535 -189.051696)
			(xy 410.271661 -188.997259) (xy 410.291584 -188.945168) (xy 410.31888 -188.896533) (xy 410.352966 -188.85239)
			(xy 410.393115 -188.813681) (xy 410.438473 -188.78123) (xy 410.488073 -188.755729) (xy 410.540857 -188.737722)
			(xy 410.5957 -188.727592) (xy 410.651434 -188.725555) (xy 410.706871 -188.731655) (xy 410.760828 -188.745761)
			(xy 410.812157 -188.767573) (xy 410.859763 -188.796627) (xy 410.902631 -188.832302) (xy 410.939848 -188.873839)
			(xy 410.970621 -188.920352) (xy 410.994293 -188.970849) (xy 411.010361 -189.024256) (xy 411.018481 -189.079432)
			(xy 411.01899 -189.107318) (xy 411.018481 -189.135204) (xy 411.010361 -189.19038) (xy 410.994293 -189.243787)
			(xy 410.970621 -189.294284) (xy 410.939848 -189.340797) (xy 410.902631 -189.382334) (xy 410.859763 -189.418009)
			(xy 410.812157 -189.447063) (xy 410.760828 -189.468875) (xy 410.706871 -189.482981) (xy 410.651434 -189.489081)
			(xy 410.5957 -189.487044) (xy 410.540857 -189.476914) (xy 410.488073 -189.458907) (xy 410.438473 -189.433406)
			(xy 410.393115 -189.400955) (xy 410.352966 -189.362246) (xy 410.31888 -189.318103) (xy 410.291584 -189.269468)
			(xy 410.271661 -189.217377) (xy 410.259535 -189.16294) (xy 410.255464 -189.107318) (xy 377.34966 -189.107318)
			(xy 377.350274 -189.114684) (xy 377.35256 -189.126876) (xy 377.354084 -189.13094) (xy 377.362842 -189.157065)
			(xy 377.372301 -189.211343) (xy 377.37288 -189.23889) (xy 377.37288 -189.811152) (xy 413.217104 -189.811152)
			(xy 413.221175 -189.75553) (xy 413.233301 -189.701093) (xy 413.253224 -189.649002) (xy 413.28052 -189.600367)
			(xy 413.314606 -189.556224) (xy 413.354755 -189.517515) (xy 413.400113 -189.485064) (xy 413.449713 -189.459563)
			(xy 413.502497 -189.441556) (xy 413.55734 -189.431426) (xy 413.613074 -189.429389) (xy 413.668511 -189.435489)
			(xy 413.722468 -189.449595) (xy 413.773797 -189.471407) (xy 413.821403 -189.500461) (xy 413.864271 -189.536136)
			(xy 413.901488 -189.577673) (xy 413.932261 -189.624186) (xy 413.955933 -189.674683) (xy 413.972001 -189.72809)
			(xy 413.980121 -189.783266) (xy 413.98063 -189.811152) (xy 413.980121 -189.839038) (xy 413.972001 -189.894214)
			(xy 413.955933 -189.947621) (xy 413.932261 -189.998118) (xy 413.901488 -190.044631) (xy 413.864271 -190.086168)
			(xy 413.821403 -190.121843) (xy 413.773797 -190.150897) (xy 413.722468 -190.172709) (xy 413.668511 -190.186815)
			(xy 413.613074 -190.192915) (xy 413.55734 -190.190878) (xy 413.502497 -190.180748) (xy 413.449713 -190.162741)
			(xy 413.400113 -190.13724) (xy 413.354755 -190.104789) (xy 413.314606 -190.06608) (xy 413.28052 -190.021937)
			(xy 413.253224 -189.973302) (xy 413.233301 -189.921211) (xy 413.221175 -189.866774) (xy 413.217104 -189.811152)
			(xy 377.37288 -189.811152) (xy 377.37288 -190.627) (xy 379.474982 -190.627) (xy 379.479053 -190.571378)
			(xy 379.491179 -190.516941) (xy 379.511102 -190.46485) (xy 379.538398 -190.416215) (xy 379.572484 -190.372072)
			(xy 379.612633 -190.333363) (xy 379.657991 -190.300912) (xy 379.707591 -190.275411) (xy 379.760375 -190.257404)
			(xy 379.815218 -190.247274) (xy 379.870952 -190.245237) (xy 379.926389 -190.251337) (xy 379.980346 -190.265443)
			(xy 380.031675 -190.287255) (xy 380.079281 -190.316309) (xy 380.122149 -190.351984) (xy 380.159366 -190.393521)
			(xy 380.190139 -190.440034) (xy 380.213811 -190.490531) (xy 380.229879 -190.543938) (xy 380.237999 -190.599114)
			(xy 380.238508 -190.627) (xy 380.237999 -190.654886) (xy 380.229879 -190.710062) (xy 380.213811 -190.763469)
			(xy 380.190139 -190.813966) (xy 380.159366 -190.860479) (xy 380.122149 -190.902016) (xy 380.079281 -190.937691)
			(xy 380.031675 -190.966745) (xy 379.980346 -190.988557) (xy 379.926389 -191.002663) (xy 379.870952 -191.008763)
			(xy 379.815218 -191.006726) (xy 379.760375 -190.996596) (xy 379.707591 -190.978589) (xy 379.657991 -190.953088)
			(xy 379.612633 -190.920637) (xy 379.572484 -190.881928) (xy 379.538398 -190.837785) (xy 379.511102 -190.78915)
			(xy 379.491179 -190.737059) (xy 379.479053 -190.682622) (xy 379.474982 -190.627) (xy 377.37288 -190.627)
			(xy 377.37288 -193.402458) (xy 409.211524 -193.402458) (xy 409.215595 -193.346836) (xy 409.227721 -193.292399)
			(xy 409.247644 -193.240308) (xy 409.27494 -193.191673) (xy 409.309026 -193.14753) (xy 409.349175 -193.108821)
			(xy 409.394533 -193.07637) (xy 409.444133 -193.050869) (xy 409.496917 -193.032862) (xy 409.55176 -193.022732)
			(xy 409.607494 -193.020695) (xy 409.662931 -193.026795) (xy 409.716888 -193.040901) (xy 409.768217 -193.062713)
			(xy 409.815823 -193.091767) (xy 409.858691 -193.127442) (xy 409.895908 -193.168979) (xy 409.926681 -193.215492)
			(xy 409.950353 -193.265989) (xy 409.951139 -193.2686) (xy 412.113982 -193.2686) (xy 412.118053 -193.212978)
			(xy 412.130179 -193.158541) (xy 412.150102 -193.10645) (xy 412.177398 -193.057815) (xy 412.211484 -193.013672)
			(xy 412.251633 -192.974963) (xy 412.296991 -192.942512) (xy 412.346591 -192.917011) (xy 412.399375 -192.899004)
			(xy 412.454218 -192.888874) (xy 412.509952 -192.886837) (xy 412.565389 -192.892937) (xy 412.619346 -192.907043)
			(xy 412.670675 -192.928855) (xy 412.718281 -192.957909) (xy 412.761149 -192.993584) (xy 412.798366 -193.035121)
			(xy 412.829139 -193.081634) (xy 412.852811 -193.132131) (xy 412.868879 -193.185538) (xy 412.876999 -193.240714)
			(xy 412.877508 -193.2686) (xy 412.876999 -193.296486) (xy 412.868879 -193.351662) (xy 412.852811 -193.405069)
			(xy 412.829139 -193.455566) (xy 412.798366 -193.502079) (xy 412.761149 -193.543616) (xy 412.718281 -193.579291)
			(xy 412.670675 -193.608345) (xy 412.619346 -193.630157) (xy 412.565389 -193.644263) (xy 412.509952 -193.650363)
			(xy 412.454218 -193.648326) (xy 412.399375 -193.638196) (xy 412.346591 -193.620189) (xy 412.296991 -193.594688)
			(xy 412.251633 -193.562237) (xy 412.211484 -193.523528) (xy 412.177398 -193.479385) (xy 412.150102 -193.43075)
			(xy 412.130179 -193.378659) (xy 412.118053 -193.324222) (xy 412.113982 -193.2686) (xy 409.951139 -193.2686)
			(xy 409.966421 -193.319396) (xy 409.974541 -193.374572) (xy 409.97505 -193.402458) (xy 409.974541 -193.430344)
			(xy 409.966421 -193.48552) (xy 409.950353 -193.538927) (xy 409.926681 -193.589424) (xy 409.895908 -193.635937)
			(xy 409.858691 -193.677474) (xy 409.815823 -193.713149) (xy 409.768217 -193.742203) (xy 409.716888 -193.764015)
			(xy 409.662931 -193.778121) (xy 409.607494 -193.784221) (xy 409.55176 -193.782184) (xy 409.496917 -193.772054)
			(xy 409.444133 -193.754047) (xy 409.394533 -193.728546) (xy 409.349175 -193.696095) (xy 409.309026 -193.657386)
			(xy 409.27494 -193.613243) (xy 409.247644 -193.564608) (xy 409.227721 -193.512517) (xy 409.215595 -193.45808)
			(xy 409.211524 -193.402458) (xy 377.37288 -193.402458) (xy 377.37288 -194.31) (xy 379.761748 -194.31)
			(xy 379.765819 -194.254378) (xy 379.777945 -194.199941) (xy 379.797868 -194.14785) (xy 379.825164 -194.099215)
			(xy 379.85925 -194.055072) (xy 379.899399 -194.016363) (xy 379.944757 -193.983912) (xy 379.994357 -193.958411)
			(xy 380.047141 -193.940404) (xy 380.101984 -193.930274) (xy 380.157718 -193.928237) (xy 380.213155 -193.934337)
			(xy 380.267112 -193.948443) (xy 380.318441 -193.970255) (xy 380.366047 -193.999309) (xy 380.408915 -194.034984)
			(xy 380.446132 -194.076521) (xy 380.476905 -194.123034) (xy 380.500577 -194.173531) (xy 380.516645 -194.226938)
			(xy 380.524765 -194.282114) (xy 380.525274 -194.31) (xy 380.524765 -194.337886) (xy 380.516645 -194.393062)
			(xy 380.500577 -194.446469) (xy 380.476905 -194.496966) (xy 380.446132 -194.543479) (xy 380.408915 -194.585016)
			(xy 380.366047 -194.620691) (xy 380.318441 -194.649745) (xy 380.267112 -194.671557) (xy 380.213155 -194.685663)
			(xy 380.157718 -194.691763) (xy 380.101984 -194.689726) (xy 380.047141 -194.679596) (xy 379.994357 -194.661589)
			(xy 379.944757 -194.636088) (xy 379.899399 -194.603637) (xy 379.85925 -194.564928) (xy 379.825164 -194.520785)
			(xy 379.797868 -194.47215) (xy 379.777945 -194.420059) (xy 379.765819 -194.365622) (xy 379.761748 -194.31)
			(xy 377.37288 -194.31) (xy 377.37288 -195.241926) (xy 420.27043 -195.241926) (xy 420.274501 -195.186304)
			(xy 420.286627 -195.131867) (xy 420.30655 -195.079776) (xy 420.333846 -195.031141) (xy 420.367932 -194.986998)
			(xy 420.408081 -194.948289) (xy 420.453439 -194.915838) (xy 420.503039 -194.890337) (xy 420.555823 -194.87233)
			(xy 420.610666 -194.8622) (xy 420.6664 -194.860163) (xy 420.721837 -194.866263) (xy 420.775794 -194.880369)
			(xy 420.827123 -194.902181) (xy 420.874729 -194.931235) (xy 420.917597 -194.96691) (xy 420.954814 -195.008447)
			(xy 420.985587 -195.05496) (xy 421.009259 -195.105457) (xy 421.025327 -195.158864) (xy 421.033447 -195.21404)
			(xy 421.033956 -195.241926) (xy 421.033447 -195.269812) (xy 421.025327 -195.324988) (xy 421.009259 -195.378395)
			(xy 420.985587 -195.428892) (xy 420.954814 -195.475405) (xy 420.917597 -195.516942) (xy 420.874729 -195.552617)
			(xy 420.827123 -195.581671) (xy 420.775794 -195.603483) (xy 420.721837 -195.617589) (xy 420.6664 -195.623689)
			(xy 420.610666 -195.621652) (xy 420.555823 -195.611522) (xy 420.503039 -195.593515) (xy 420.453439 -195.568014)
			(xy 420.408081 -195.535563) (xy 420.367932 -195.496854) (xy 420.333846 -195.452711) (xy 420.30655 -195.404076)
			(xy 420.286627 -195.351985) (xy 420.274501 -195.297548) (xy 420.27043 -195.241926) (xy 377.37288 -195.241926)
			(xy 377.37288 -196.342) (xy 379.808738 -196.342) (xy 379.812809 -196.286378) (xy 379.824935 -196.231941)
			(xy 379.844858 -196.17985) (xy 379.872154 -196.131215) (xy 379.90624 -196.087072) (xy 379.946389 -196.048363)
			(xy 379.991747 -196.015912) (xy 380.041347 -195.990411) (xy 380.094131 -195.972404) (xy 380.148974 -195.962274)
			(xy 380.204708 -195.960237) (xy 380.260145 -195.966337) (xy 380.314102 -195.980443) (xy 380.365431 -196.002255)
			(xy 380.413037 -196.031309) (xy 380.455905 -196.066984) (xy 380.493122 -196.108521) (xy 380.523895 -196.155034)
			(xy 380.547567 -196.205531) (xy 380.563635 -196.258938) (xy 380.571755 -196.314114) (xy 380.572264 -196.342)
			(xy 380.571755 -196.369886) (xy 380.563635 -196.425062) (xy 380.547567 -196.478469) (xy 380.523895 -196.528966)
			(xy 380.493122 -196.575479) (xy 380.455905 -196.617016) (xy 380.413037 -196.652691) (xy 380.365431 -196.681745)
			(xy 380.314102 -196.703557) (xy 380.260145 -196.717663) (xy 380.204708 -196.723763) (xy 380.148974 -196.721726)
			(xy 380.094131 -196.711596) (xy 380.041347 -196.693589) (xy 379.991747 -196.668088) (xy 379.946389 -196.635637)
			(xy 379.90624 -196.596928) (xy 379.872154 -196.552785) (xy 379.844858 -196.50415) (xy 379.824935 -196.452059)
			(xy 379.812809 -196.397622) (xy 379.808738 -196.342) (xy 377.37288 -196.342) (xy 377.37288 -197.335394)
			(xy 378.916436 -197.335394) (xy 378.920507 -197.279772) (xy 378.932633 -197.225335) (xy 378.952556 -197.173244)
			(xy 378.979852 -197.124609) (xy 379.013938 -197.080466) (xy 379.054087 -197.041757) (xy 379.099445 -197.009306)
			(xy 379.149045 -196.983805) (xy 379.201829 -196.965798) (xy 379.256672 -196.955668) (xy 379.312406 -196.953631)
			(xy 379.367843 -196.959731) (xy 379.4218 -196.973837) (xy 379.473129 -196.995649) (xy 379.520735 -197.024703)
			(xy 379.563603 -197.060378) (xy 379.60082 -197.101915) (xy 379.631593 -197.148428) (xy 379.655265 -197.198925)
			(xy 379.671333 -197.252332) (xy 379.679453 -197.307508) (xy 379.679962 -197.335394) (xy 379.679549 -197.358)
			(xy 379.795784 -197.358) (xy 379.799855 -197.302378) (xy 379.811981 -197.247941) (xy 379.831904 -197.19585)
			(xy 379.8592 -197.147215) (xy 379.893286 -197.103072) (xy 379.933435 -197.064363) (xy 379.978793 -197.031912)
			(xy 380.028393 -197.006411) (xy 380.081177 -196.988404) (xy 380.13602 -196.978274) (xy 380.191754 -196.976237)
			(xy 380.247191 -196.982337) (xy 380.301148 -196.996443) (xy 380.352477 -197.018255) (xy 380.400083 -197.047309)
			(xy 380.442951 -197.082984) (xy 380.480168 -197.124521) (xy 380.483396 -197.1294) (xy 408.430982 -197.1294)
			(xy 408.435053 -197.073778) (xy 408.447179 -197.019341) (xy 408.467102 -196.96725) (xy 408.494398 -196.918615)
			(xy 408.528484 -196.874472) (xy 408.568633 -196.835763) (xy 408.613991 -196.803312) (xy 408.663591 -196.777811)
			(xy 408.716375 -196.759804) (xy 408.771218 -196.749674) (xy 408.826952 -196.747637) (xy 408.882389 -196.753737)
			(xy 408.888207 -196.755258) (xy 413.72104 -196.755258) (xy 413.725111 -196.699636) (xy 413.737237 -196.645199)
			(xy 413.75716 -196.593108) (xy 413.784456 -196.544473) (xy 413.818542 -196.50033) (xy 413.858691 -196.461621)
			(xy 413.904049 -196.42917) (xy 413.953649 -196.403669) (xy 414.006433 -196.385662) (xy 414.061276 -196.375532)
			(xy 414.11701 -196.373495) (xy 414.172447 -196.379595) (xy 414.226404 -196.393701) (xy 414.277733 -196.415513)
			(xy 414.325339 -196.444567) (xy 414.368207 -196.480242) (xy 414.381803 -196.495416) (xy 420.50665 -196.495416)
			(xy 420.510721 -196.439794) (xy 420.522847 -196.385357) (xy 420.54277 -196.333266) (xy 420.570066 -196.284631)
			(xy 420.604152 -196.240488) (xy 420.644301 -196.201779) (xy 420.689659 -196.169328) (xy 420.739259 -196.143827)
			(xy 420.792043 -196.12582) (xy 420.846886 -196.11569) (xy 420.90262 -196.113653) (xy 420.958057 -196.119753)
			(xy 421.012014 -196.133859) (xy 421.063343 -196.155671) (xy 421.110949 -196.184725) (xy 421.153817 -196.2204)
			(xy 421.191034 -196.261937) (xy 421.221807 -196.30845) (xy 421.245479 -196.358947) (xy 421.261547 -196.412354)
			(xy 421.269667 -196.46753) (xy 421.270176 -196.495416) (xy 421.269667 -196.523302) (xy 421.261547 -196.578478)
			(xy 421.245479 -196.631885) (xy 421.221807 -196.682382) (xy 421.191034 -196.728895) (xy 421.153817 -196.770432)
			(xy 421.110949 -196.806107) (xy 421.063343 -196.835161) (xy 421.012014 -196.856973) (xy 420.958057 -196.871079)
			(xy 420.90262 -196.877179) (xy 420.846886 -196.875142) (xy 420.792043 -196.865012) (xy 420.739259 -196.847005)
			(xy 420.689659 -196.821504) (xy 420.644301 -196.789053) (xy 420.604152 -196.750344) (xy 420.570066 -196.706201)
			(xy 420.54277 -196.657566) (xy 420.522847 -196.605475) (xy 420.510721 -196.551038) (xy 420.50665 -196.495416)
			(xy 414.381803 -196.495416) (xy 414.405424 -196.521779) (xy 414.436197 -196.568292) (xy 414.459869 -196.618789)
			(xy 414.475937 -196.672196) (xy 414.484057 -196.727372) (xy 414.484566 -196.755258) (xy 414.484057 -196.783144)
			(xy 414.475937 -196.83832) (xy 414.459869 -196.891727) (xy 414.436197 -196.942224) (xy 414.405424 -196.988737)
			(xy 414.368207 -197.030274) (xy 414.325339 -197.065949) (xy 414.277733 -197.095003) (xy 414.226404 -197.116815)
			(xy 414.172447 -197.130921) (xy 414.11701 -197.137021) (xy 414.061276 -197.134984) (xy 414.006433 -197.124854)
			(xy 413.953649 -197.106847) (xy 413.904049 -197.081346) (xy 413.858691 -197.048895) (xy 413.818542 -197.010186)
			(xy 413.784456 -196.966043) (xy 413.75716 -196.917408) (xy 413.737237 -196.865317) (xy 413.725111 -196.81088)
			(xy 413.72104 -196.755258) (xy 408.888207 -196.755258) (xy 408.936346 -196.767843) (xy 408.987675 -196.789655)
			(xy 409.035281 -196.818709) (xy 409.078149 -196.854384) (xy 409.115366 -196.895921) (xy 409.146139 -196.942434)
			(xy 409.169811 -196.992931) (xy 409.185879 -197.046338) (xy 409.193999 -197.101514) (xy 409.194508 -197.1294)
			(xy 409.193999 -197.157286) (xy 409.185879 -197.212462) (xy 409.169811 -197.265869) (xy 409.146139 -197.316366)
			(xy 409.115366 -197.362879) (xy 409.078149 -197.404416) (xy 409.035281 -197.440091) (xy 408.987675 -197.469145)
			(xy 408.936346 -197.490957) (xy 408.882389 -197.505063) (xy 408.826952 -197.511163) (xy 408.771218 -197.509126)
			(xy 408.716375 -197.498996) (xy 408.663591 -197.480989) (xy 408.613991 -197.455488) (xy 408.568633 -197.423037)
			(xy 408.528484 -197.384328) (xy 408.494398 -197.340185) (xy 408.467102 -197.29155) (xy 408.447179 -197.239459)
			(xy 408.435053 -197.185022) (xy 408.430982 -197.1294) (xy 380.483396 -197.1294) (xy 380.510941 -197.171034)
			(xy 380.534613 -197.221531) (xy 380.550681 -197.274938) (xy 380.558801 -197.330114) (xy 380.55931 -197.358)
			(xy 380.558801 -197.385886) (xy 380.550681 -197.441062) (xy 380.534613 -197.494469) (xy 380.510941 -197.544966)
			(xy 380.480168 -197.591479) (xy 380.442951 -197.633016) (xy 380.400083 -197.668691) (xy 380.352477 -197.697745)
			(xy 380.301148 -197.719557) (xy 380.247191 -197.733663) (xy 380.191754 -197.739763) (xy 380.13602 -197.737726)
			(xy 380.081177 -197.727596) (xy 380.028393 -197.709589) (xy 379.978793 -197.684088) (xy 379.933435 -197.651637)
			(xy 379.893286 -197.612928) (xy 379.8592 -197.568785) (xy 379.831904 -197.52015) (xy 379.811981 -197.468059)
			(xy 379.799855 -197.413622) (xy 379.795784 -197.358) (xy 379.679549 -197.358) (xy 379.679453 -197.36328)
			(xy 379.671333 -197.418456) (xy 379.655265 -197.471863) (xy 379.631593 -197.52236) (xy 379.60082 -197.568873)
			(xy 379.563603 -197.61041) (xy 379.520735 -197.646085) (xy 379.473129 -197.675139) (xy 379.4218 -197.696951)
			(xy 379.367843 -197.711057) (xy 379.312406 -197.717157) (xy 379.256672 -197.71512) (xy 379.201829 -197.70499)
			(xy 379.149045 -197.686983) (xy 379.099445 -197.661482) (xy 379.054087 -197.629031) (xy 379.013938 -197.590322)
			(xy 378.979852 -197.546179) (xy 378.952556 -197.497544) (xy 378.932633 -197.445453) (xy 378.920507 -197.391016)
			(xy 378.916436 -197.335394) (xy 377.37288 -197.335394) (xy 377.37288 -198.374) (xy 379.855982 -198.374)
			(xy 379.860053 -198.318378) (xy 379.872179 -198.263941) (xy 379.892102 -198.21185) (xy 379.919398 -198.163215)
			(xy 379.953484 -198.119072) (xy 379.993633 -198.080363) (xy 380.038991 -198.047912) (xy 380.088591 -198.022411)
			(xy 380.141375 -198.004404) (xy 380.196218 -197.994274) (xy 380.251952 -197.992237) (xy 380.307389 -197.998337)
			(xy 380.361346 -198.012443) (xy 380.412675 -198.034255) (xy 380.460281 -198.063309) (xy 380.503149 -198.098984)
			(xy 380.540366 -198.140521) (xy 380.571139 -198.187034) (xy 380.578651 -198.203058) (xy 408.97124 -198.203058)
			(xy 408.975311 -198.147436) (xy 408.987437 -198.092999) (xy 409.00736 -198.040908) (xy 409.034656 -197.992273)
			(xy 409.068742 -197.94813) (xy 409.108891 -197.909421) (xy 409.154249 -197.87697) (xy 409.203849 -197.851469)
			(xy 409.256633 -197.833462) (xy 409.311476 -197.823332) (xy 409.36721 -197.821295) (xy 409.422647 -197.827395)
			(xy 409.476604 -197.841501) (xy 409.527933 -197.863313) (xy 409.575539 -197.892367) (xy 409.618407 -197.928042)
			(xy 409.655624 -197.969579) (xy 409.686397 -198.016092) (xy 409.710069 -198.066589) (xy 409.726137 -198.119996)
			(xy 409.734257 -198.175172) (xy 409.734766 -198.203058) (xy 409.734257 -198.230944) (xy 409.726137 -198.28612)
			(xy 409.710069 -198.339527) (xy 409.686397 -198.390024) (xy 409.655624 -198.436537) (xy 409.618407 -198.478074)
			(xy 409.575539 -198.513749) (xy 409.527933 -198.542803) (xy 409.476604 -198.564615) (xy 409.422647 -198.578721)
			(xy 409.36721 -198.584821) (xy 409.311476 -198.582784) (xy 409.256633 -198.572654) (xy 409.203849 -198.554647)
			(xy 409.154249 -198.529146) (xy 409.108891 -198.496695) (xy 409.068742 -198.457986) (xy 409.034656 -198.413843)
			(xy 409.00736 -198.365208) (xy 408.987437 -198.313117) (xy 408.975311 -198.25868) (xy 408.97124 -198.203058)
			(xy 380.578651 -198.203058) (xy 380.594811 -198.237531) (xy 380.610879 -198.290938) (xy 380.618999 -198.346114)
			(xy 380.619508 -198.374) (xy 380.618999 -198.401886) (xy 380.610879 -198.457062) (xy 380.594811 -198.510469)
			(xy 380.571139 -198.560966) (xy 380.540366 -198.607479) (xy 380.503149 -198.649016) (xy 380.460281 -198.684691)
			(xy 380.412675 -198.713745) (xy 380.361346 -198.735557) (xy 380.307389 -198.749663) (xy 380.251952 -198.755763)
			(xy 380.196218 -198.753726) (xy 380.141375 -198.743596) (xy 380.088591 -198.725589) (xy 380.038991 -198.700088)
			(xy 379.993633 -198.667637) (xy 379.953484 -198.628928) (xy 379.919398 -198.584785) (xy 379.892102 -198.53615)
			(xy 379.872179 -198.484059) (xy 379.860053 -198.429622) (xy 379.855982 -198.374) (xy 377.37288 -198.374)
			(xy 377.37288 -199.39) (xy 379.794006 -199.39) (xy 379.798077 -199.334378) (xy 379.810203 -199.279941)
			(xy 379.830126 -199.22785) (xy 379.857422 -199.179215) (xy 379.891508 -199.135072) (xy 379.931657 -199.096363)
			(xy 379.977015 -199.063912) (xy 380.026615 -199.038411) (xy 380.079399 -199.020404) (xy 380.134242 -199.010274)
			(xy 380.189976 -199.008237) (xy 380.245413 -199.014337) (xy 380.29937 -199.028443) (xy 380.350699 -199.050255)
			(xy 380.398305 -199.079309) (xy 380.441173 -199.114984) (xy 380.47839 -199.156521) (xy 380.509163 -199.203034)
			(xy 380.532835 -199.253531) (xy 380.548903 -199.306938) (xy 380.557023 -199.362114) (xy 380.557532 -199.39)
			(xy 380.557023 -199.417886) (xy 380.548903 -199.473062) (xy 380.532835 -199.526469) (xy 380.509163 -199.576966)
			(xy 380.47839 -199.623479) (xy 380.441173 -199.665016) (xy 380.398305 -199.700691) (xy 380.350699 -199.729745)
			(xy 380.29937 -199.751557) (xy 380.245413 -199.765663) (xy 380.189976 -199.771763) (xy 380.134242 -199.769726)
			(xy 380.079399 -199.759596) (xy 380.026615 -199.741589) (xy 379.977015 -199.716088) (xy 379.931657 -199.683637)
			(xy 379.891508 -199.644928) (xy 379.857422 -199.600785) (xy 379.830126 -199.55215) (xy 379.810203 -199.500059)
			(xy 379.798077 -199.445622) (xy 379.794006 -199.39) (xy 377.37288 -199.39) (xy 377.37288 -200.099676)
			(xy 380.524764 -200.099676) (xy 380.528835 -200.044054) (xy 380.540961 -199.989617) (xy 380.560884 -199.937526)
			(xy 380.58818 -199.888891) (xy 380.622266 -199.844748) (xy 380.662415 -199.806039) (xy 380.707773 -199.773588)
			(xy 380.757373 -199.748087) (xy 380.810157 -199.73008) (xy 380.865 -199.71995) (xy 380.920734 -199.717913)
			(xy 380.976171 -199.724013) (xy 381.030128 -199.738119) (xy 381.081457 -199.759931) (xy 381.129063 -199.788985)
			(xy 381.171931 -199.82466) (xy 381.209148 -199.866197) (xy 381.239921 -199.91271) (xy 381.263593 -199.963207)
			(xy 381.268964 -199.981058) (xy 413.61944 -199.981058) (xy 413.623511 -199.925436) (xy 413.635637 -199.870999)
			(xy 413.65556 -199.818908) (xy 413.682856 -199.770273) (xy 413.716942 -199.72613) (xy 413.757091 -199.687421)
			(xy 413.802449 -199.65497) (xy 413.852049 -199.629469) (xy 413.904833 -199.611462) (xy 413.959676 -199.601332)
			(xy 414.01541 -199.599295) (xy 414.070847 -199.605395) (xy 414.124804 -199.619501) (xy 414.176133 -199.641313)
			(xy 414.223739 -199.670367) (xy 414.266607 -199.706042) (xy 414.303824 -199.747579) (xy 414.334597 -199.794092)
			(xy 414.358269 -199.844589) (xy 414.374337 -199.897996) (xy 414.382457 -199.953172) (xy 414.382966 -199.981058)
			(xy 414.382457 -200.008944) (xy 414.374337 -200.06412) (xy 414.358269 -200.117527) (xy 414.334597 -200.168024)
			(xy 414.303824 -200.214537) (xy 414.266607 -200.256074) (xy 414.223739 -200.291749) (xy 414.176133 -200.320803)
			(xy 414.124804 -200.342615) (xy 414.070847 -200.356721) (xy 414.01541 -200.362821) (xy 413.959676 -200.360784)
			(xy 413.904833 -200.350654) (xy 413.852049 -200.332647) (xy 413.802449 -200.307146) (xy 413.757091 -200.274695)
			(xy 413.716942 -200.235986) (xy 413.682856 -200.191843) (xy 413.65556 -200.143208) (xy 413.635637 -200.091117)
			(xy 413.623511 -200.03668) (xy 413.61944 -199.981058) (xy 381.268964 -199.981058) (xy 381.279661 -200.016614)
			(xy 381.287781 -200.07179) (xy 381.28829 -200.099676) (xy 381.287781 -200.127562) (xy 381.279661 -200.182738)
			(xy 381.263593 -200.236145) (xy 381.239921 -200.286642) (xy 381.209148 -200.333155) (xy 381.171931 -200.374692)
			(xy 381.129063 -200.410367) (xy 381.081457 -200.439421) (xy 381.030128 -200.461233) (xy 380.976171 -200.475339)
			(xy 380.920734 -200.481439) (xy 380.865 -200.479402) (xy 380.810157 -200.469272) (xy 380.757373 -200.451265)
			(xy 380.707773 -200.425764) (xy 380.662415 -200.393313) (xy 380.622266 -200.354604) (xy 380.58818 -200.310461)
			(xy 380.560884 -200.261826) (xy 380.540961 -200.209735) (xy 380.528835 -200.155298) (xy 380.524764 -200.099676)
			(xy 377.37288 -200.099676) (xy 377.37288 -200.634092) (xy 379.021846 -200.634092) (xy 379.025917 -200.57847)
			(xy 379.038043 -200.524033) (xy 379.057966 -200.471942) (xy 379.085262 -200.423307) (xy 379.119348 -200.379164)
			(xy 379.159497 -200.340455) (xy 379.204855 -200.308004) (xy 379.254455 -200.282503) (xy 379.307239 -200.264496)
			(xy 379.362082 -200.254366) (xy 379.417816 -200.252329) (xy 379.473253 -200.258429) (xy 379.52721 -200.272535)
			(xy 379.578539 -200.294347) (xy 379.626145 -200.323401) (xy 379.669013 -200.359076) (xy 379.70623 -200.400613)
			(xy 379.737003 -200.447126) (xy 379.760675 -200.497623) (xy 379.776743 -200.55103) (xy 379.784863 -200.606206)
			(xy 379.785372 -200.634092) (xy 379.784863 -200.661978) (xy 379.776743 -200.717154) (xy 379.760675 -200.770561)
			(xy 379.737003 -200.821058) (xy 379.70623 -200.867571) (xy 379.669013 -200.909108) (xy 379.626145 -200.944783)
			(xy 379.578539 -200.973837) (xy 379.52721 -200.995649) (xy 379.473253 -201.009755) (xy 379.417816 -201.015855)
			(xy 379.362082 -201.013818) (xy 379.307239 -201.003688) (xy 379.254455 -200.985681) (xy 379.204855 -200.96018)
			(xy 379.159497 -200.927729) (xy 379.119348 -200.88902) (xy 379.085262 -200.844877) (xy 379.057966 -200.796242)
			(xy 379.038043 -200.744151) (xy 379.025917 -200.689714) (xy 379.021846 -200.634092) (xy 377.37288 -200.634092)
			(xy 377.37288 -200.8505) (xy 377.373253 -200.859066) (xy 377.378969 -200.87522) (xy 377.389666 -200.888606)
			(xy 377.396756 -200.893426) (xy 377.46178 -200.933812) (xy 377.467885 -200.937316) (xy 377.481415 -200.941184)
			(xy 377.48845 -200.941432) (xy 377.518676 -200.941432) (xy 377.528836 -200.93686) (xy 377.553758 -200.926048)
			(xy 377.605892 -200.910784) (xy 377.659663 -200.903054) (xy 377.686824 -200.90257) (xy 377.695206 -200.90257)
			(xy 377.722075 -200.903602) (xy 377.775139 -200.912283) (xy 377.826458 -200.928331) (xy 377.875014 -200.951427)
			(xy 377.919845 -200.981114) (xy 377.960063 -201.016802) (xy 377.99487 -201.057786) (xy 378.023576 -201.103251)
			(xy 378.045612 -201.152298) (xy 378.060541 -201.203953) (xy 378.068068 -201.257193) (xy 378.068586 -201.284078)
			(xy 378.068124 -201.311331) (xy 378.06037 -201.365283) (xy 378.045015 -201.417583) (xy 378.022374 -201.467164)
			(xy 377.992906 -201.513018) (xy 377.957212 -201.554212) (xy 377.916018 -201.589906) (xy 377.870164 -201.619374)
			(xy 377.820583 -201.642015) (xy 377.768283 -201.65737) (xy 377.714331 -201.665124) (xy 377.687078 -201.665586)
			(xy 377.686824 -201.665586) (xy 377.659661 -201.665112) (xy 377.605883 -201.657406) (xy 377.553748 -201.642134)
			(xy 377.528836 -201.631296) (xy 377.523828 -201.629167) (xy 377.513194 -201.626861) (xy 377.507754 -201.626724)
			(xy 377.48845 -201.626724) (xy 377.481412 -201.626952) (xy 377.467882 -201.630828) (xy 377.46178 -201.634344)
			(xy 377.437142 -201.649584) (xy 377.409456 -201.666856) (xy 377.401328 -201.671936) (xy 377.396756 -201.67473)
			(xy 377.389644 -201.679536) (xy 377.378892 -201.692902) (xy 377.373185 -201.709079) (xy 377.37288 -201.717656)
			(xy 377.37288 -201.962258) (xy 409.033724 -201.962258) (xy 409.037795 -201.906636) (xy 409.049921 -201.852199)
			(xy 409.069844 -201.800108) (xy 409.09714 -201.751473) (xy 409.131226 -201.70733) (xy 409.171375 -201.668621)
			(xy 409.216733 -201.63617) (xy 409.266333 -201.610669) (xy 409.319117 -201.592662) (xy 409.37396 -201.582532)
			(xy 409.429694 -201.580495) (xy 409.485131 -201.586595) (xy 409.539088 -201.600701) (xy 409.590417 -201.622513)
			(xy 409.638023 -201.651567) (xy 409.680891 -201.687242) (xy 409.718108 -201.728779) (xy 409.748881 -201.775292)
			(xy 409.772553 -201.825789) (xy 409.788621 -201.879196) (xy 409.796741 -201.934372) (xy 409.79725 -201.962258)
			(xy 409.796741 -201.990144) (xy 409.788621 -202.04532) (xy 409.772553 -202.098727) (xy 409.748881 -202.149224)
			(xy 409.718108 -202.195737) (xy 409.680891 -202.237274) (xy 409.638023 -202.272949) (xy 409.590417 -202.302003)
			(xy 409.539088 -202.323815) (xy 409.485131 -202.337921) (xy 409.429694 -202.344021) (xy 409.37396 -202.341984)
			(xy 409.319117 -202.331854) (xy 409.266333 -202.313847) (xy 409.216733 -202.288346) (xy 409.171375 -202.255895)
			(xy 409.131226 -202.217186) (xy 409.09714 -202.173043) (xy 409.069844 -202.124408) (xy 409.049921 -202.072317)
			(xy 409.037795 -202.01788) (xy 409.033724 -201.962258) (xy 377.37288 -201.962258) (xy 377.37288 -202.35418)
			(xy 379.391162 -202.35418) (xy 379.395233 -202.298558) (xy 379.407359 -202.244121) (xy 379.427282 -202.19203)
			(xy 379.454578 -202.143395) (xy 379.488664 -202.099252) (xy 379.528813 -202.060543) (xy 379.574171 -202.028092)
			(xy 379.623771 -202.002591) (xy 379.676555 -201.984584) (xy 379.731398 -201.974454) (xy 379.787132 -201.972417)
			(xy 379.842569 -201.978517) (xy 379.896526 -201.992623) (xy 379.947855 -202.014435) (xy 379.995461 -202.043489)
			(xy 380.038329 -202.079164) (xy 380.075546 -202.120701) (xy 380.106319 -202.167214) (xy 380.129991 -202.217711)
			(xy 380.146059 -202.271118) (xy 380.154179 -202.326294) (xy 380.154688 -202.35418) (xy 380.154179 -202.382066)
			(xy 380.151779 -202.398376) (xy 381.759712 -202.398376) (xy 381.763783 -202.342754) (xy 381.775909 -202.288317)
			(xy 381.795832 -202.236226) (xy 381.823128 -202.187591) (xy 381.857214 -202.143448) (xy 381.897363 -202.104739)
			(xy 381.942721 -202.072288) (xy 381.992321 -202.046787) (xy 382.045105 -202.02878) (xy 382.099948 -202.01865)
			(xy 382.155682 -202.016613) (xy 382.211119 -202.022713) (xy 382.265076 -202.036819) (xy 382.316405 -202.058631)
			(xy 382.364011 -202.087685) (xy 382.406879 -202.12336) (xy 382.444096 -202.164897) (xy 382.474869 -202.21141)
			(xy 382.498541 -202.261907) (xy 382.514609 -202.315314) (xy 382.522729 -202.37049) (xy 382.523238 -202.398376)
			(xy 382.522729 -202.426262) (xy 382.514609 -202.481438) (xy 382.498541 -202.534845) (xy 382.474869 -202.585342)
			(xy 382.444096 -202.631855) (xy 382.406879 -202.673392) (xy 382.364011 -202.709067) (xy 382.316405 -202.738121)
			(xy 382.265076 -202.759933) (xy 382.211119 -202.774039) (xy 382.155682 -202.780139) (xy 382.099948 -202.778102)
			(xy 382.045105 -202.767972) (xy 381.992321 -202.749965) (xy 381.942721 -202.724464) (xy 381.897363 -202.692013)
			(xy 381.857214 -202.653304) (xy 381.823128 -202.609161) (xy 381.795832 -202.560526) (xy 381.775909 -202.508435)
			(xy 381.763783 -202.453998) (xy 381.759712 -202.398376) (xy 380.151779 -202.398376) (xy 380.146059 -202.437242)
			(xy 380.129991 -202.490649) (xy 380.106319 -202.541146) (xy 380.075546 -202.587659) (xy 380.038329 -202.629196)
			(xy 379.995461 -202.664871) (xy 379.947855 -202.693925) (xy 379.896526 -202.715737) (xy 379.842569 -202.729843)
			(xy 379.787132 -202.735943) (xy 379.731398 -202.733906) (xy 379.676555 -202.723776) (xy 379.623771 -202.705769)
			(xy 379.574171 -202.680268) (xy 379.528813 -202.647817) (xy 379.488664 -202.609108) (xy 379.454578 -202.564965)
			(xy 379.427282 -202.51633) (xy 379.407359 -202.464239) (xy 379.395233 -202.409802) (xy 379.391162 -202.35418)
			(xy 377.37288 -202.35418) (xy 377.37288 -202.79995) (xy 378.439932 -202.79995) (xy 378.444003 -202.744328)
			(xy 378.456129 -202.689891) (xy 378.476052 -202.6378) (xy 378.503348 -202.589165) (xy 378.537434 -202.545022)
			(xy 378.577583 -202.506313) (xy 378.622941 -202.473862) (xy 378.672541 -202.448361) (xy 378.725325 -202.430354)
			(xy 378.780168 -202.420224) (xy 378.835902 -202.418187) (xy 378.891339 -202.424287) (xy 378.945296 -202.438393)
			(xy 378.996625 -202.460205) (xy 379.044231 -202.489259) (xy 379.087099 -202.524934) (xy 379.124316 -202.566471)
			(xy 379.155089 -202.612984) (xy 379.178761 -202.663481) (xy 379.194829 -202.716888) (xy 379.202949 -202.772064)
			(xy 379.203458 -202.79995) (xy 379.202949 -202.827836) (xy 379.194829 -202.883012) (xy 379.178761 -202.936419)
			(xy 379.155089 -202.986916) (xy 379.124316 -203.033429) (xy 379.087099 -203.074966) (xy 379.044231 -203.110641)
			(xy 378.996625 -203.139695) (xy 378.945296 -203.161507) (xy 378.891339 -203.175613) (xy 378.835902 -203.181713)
			(xy 378.780168 -203.179676) (xy 378.725325 -203.169546) (xy 378.672541 -203.151539) (xy 378.622941 -203.126038)
			(xy 378.577583 -203.093587) (xy 378.537434 -203.054878) (xy 378.503348 -203.010735) (xy 378.476052 -202.9621)
			(xy 378.456129 -202.910009) (xy 378.444003 -202.855572) (xy 378.439932 -202.79995) (xy 377.37288 -202.79995)
			(xy 377.37288 -203.562458) (xy 413.13684 -203.562458) (xy 413.140911 -203.506836) (xy 413.153037 -203.452399)
			(xy 413.17296 -203.400308) (xy 413.200256 -203.351673) (xy 413.234342 -203.30753) (xy 413.274491 -203.268821)
			(xy 413.319849 -203.23637) (xy 413.369449 -203.210869) (xy 413.422233 -203.192862) (xy 413.477076 -203.182732)
			(xy 413.53281 -203.180695) (xy 413.588247 -203.186795) (xy 413.642204 -203.200901) (xy 413.693533 -203.222713)
			(xy 413.741139 -203.251767) (xy 413.784007 -203.287442) (xy 413.821224 -203.328979) (xy 413.851997 -203.375492)
			(xy 413.875669 -203.425989) (xy 413.891737 -203.479396) (xy 413.899857 -203.534572) (xy 413.900366 -203.562458)
			(xy 413.899857 -203.590344) (xy 413.891737 -203.64552) (xy 413.875669 -203.698927) (xy 413.851997 -203.749424)
			(xy 413.821224 -203.795937) (xy 413.784007 -203.837474) (xy 413.741139 -203.873149) (xy 413.693533 -203.902203)
			(xy 413.642204 -203.924015) (xy 413.588247 -203.938121) (xy 413.53281 -203.944221) (xy 413.477076 -203.942184)
			(xy 413.422233 -203.932054) (xy 413.369449 -203.914047) (xy 413.319849 -203.888546) (xy 413.274491 -203.856095)
			(xy 413.234342 -203.817386) (xy 413.200256 -203.773243) (xy 413.17296 -203.724608) (xy 413.153037 -203.672517)
			(xy 413.140911 -203.61808) (xy 413.13684 -203.562458) (xy 377.37288 -203.562458) (xy 377.37288 -204.158596)
			(xy 407.590242 -204.158596) (xy 407.594313 -204.102974) (xy 407.606439 -204.048537) (xy 407.626362 -203.996446)
			(xy 407.653658 -203.947811) (xy 407.687744 -203.903668) (xy 407.727893 -203.864959) (xy 407.773251 -203.832508)
			(xy 407.822851 -203.807007) (xy 407.875635 -203.789) (xy 407.930478 -203.77887) (xy 407.986212 -203.776833)
			(xy 408.041649 -203.782933) (xy 408.095606 -203.797039) (xy 408.146935 -203.818851) (xy 408.194541 -203.847905)
			(xy 408.237409 -203.88358) (xy 408.274626 -203.925117) (xy 408.305399 -203.97163) (xy 408.329071 -204.022127)
			(xy 408.345139 -204.075534) (xy 408.353259 -204.13071) (xy 408.353768 -204.158596) (xy 408.353259 -204.186482)
			(xy 408.345139 -204.241658) (xy 408.329071 -204.295065) (xy 408.305399 -204.345562) (xy 408.274626 -204.392075)
			(xy 408.237409 -204.433612) (xy 408.194541 -204.469287) (xy 408.146935 -204.498341) (xy 408.095606 -204.520153)
			(xy 408.041649 -204.534259) (xy 407.986212 -204.540359) (xy 407.930478 -204.538322) (xy 407.875635 -204.528192)
			(xy 407.822851 -204.510185) (xy 407.773251 -204.484684) (xy 407.727893 -204.452233) (xy 407.687744 -204.413524)
			(xy 407.653658 -204.369381) (xy 407.626362 -204.320746) (xy 407.606439 -204.268655) (xy 407.594313 -204.214218)
			(xy 407.590242 -204.158596) (xy 377.37288 -204.158596) (xy 377.37288 -205.169008) (xy 377.373091 -205.175588)
			(xy 377.376439 -205.188317) (xy 377.379484 -205.194154) (xy 377.379738 -205.194408) (xy 377.383159 -205.200056)
			(xy 377.392419 -205.209463) (xy 377.398026 -205.21295) (xy 377.467368 -205.25359) (xy 377.47448 -205.25613)
			(xy 377.481592 -205.257654) (xy 377.4821 -205.257654) (xy 377.488196 -205.258162) (xy 377.513596 -205.258162)
			(xy 377.522486 -205.255876) (xy 377.529344 -205.25232) (xy 377.556738 -205.238793) (xy 377.614754 -205.219653)
			(xy 377.675074 -205.209969) (xy 377.70562 -205.209394) (xy 377.706382 -205.209394) (xy 377.70689 -205.209394)
			(xy 377.7107 -205.209394) (xy 377.737953 -205.209857) (xy 377.791904 -205.217614) (xy 377.844201 -205.23297)
			(xy 377.893781 -205.255613) (xy 377.939634 -205.285081) (xy 377.980827 -205.320775) (xy 378.01652 -205.361967)
			(xy 378.045988 -205.40782) (xy 378.06863 -205.457401) (xy 378.077028 -205.486) (xy 379.816612 -205.486)
			(xy 379.820683 -205.430378) (xy 379.832809 -205.375941) (xy 379.852732 -205.32385) (xy 379.880028 -205.275215)
			(xy 379.914114 -205.231072) (xy 379.954263 -205.192363) (xy 379.999621 -205.159912) (xy 380.049221 -205.134411)
			(xy 380.102005 -205.116404) (xy 380.156848 -205.106274) (xy 380.212582 -205.104237) (xy 380.268019 -205.110337)
			(xy 380.321976 -205.124443) (xy 380.373305 -205.146255) (xy 380.420911 -205.175309) (xy 380.463779 -205.210984)
			(xy 380.500996 -205.252521) (xy 380.531769 -205.299034) (xy 380.555441 -205.349531) (xy 380.571509 -205.402938)
			(xy 380.579629 -205.458114) (xy 380.580138 -205.486) (xy 380.579629 -205.513886) (xy 380.571509 -205.569062)
			(xy 380.555441 -205.622469) (xy 380.531769 -205.672966) (xy 380.500996 -205.719479) (xy 380.463779 -205.761016)
			(xy 380.420911 -205.796691) (xy 380.373305 -205.825745) (xy 380.321976 -205.847557) (xy 380.268019 -205.861663)
			(xy 380.212582 -205.867763) (xy 380.156848 -205.865726) (xy 380.102005 -205.855596) (xy 380.049221 -205.837589)
			(xy 379.999621 -205.812088) (xy 379.954263 -205.779637) (xy 379.914114 -205.740928) (xy 379.880028 -205.696785)
			(xy 379.852732 -205.64815) (xy 379.832809 -205.596059) (xy 379.820683 -205.541622) (xy 379.816612 -205.486)
			(xy 378.077028 -205.486) (xy 378.083986 -205.509698) (xy 378.091743 -205.563649) (xy 378.092208 -205.590902)
			(xy 378.091703 -205.618638) (xy 378.083659 -205.673525) (xy 378.067754 -205.726669) (xy 378.044324 -205.776951)
			(xy 378.013863 -205.823312) (xy 377.977011 -205.864776) (xy 377.934546 -205.900468) (xy 377.887361 -205.929638)
			(xy 377.836451 -205.95167) (xy 377.782888 -205.966101) (xy 377.755404 -205.96987) (xy 377.741688 -205.971394)
			(xy 377.713465 -205.973179) (xy 377.657041 -205.969405) (xy 377.60179 -205.957351) (xy 377.548921 -205.937281)
			(xy 377.52401 -205.923896) (xy 377.523756 -205.923642) (xy 377.517854 -205.920614) (xy 377.504989 -205.917398)
			(xy 377.498356 -205.917292) (xy 377.485656 -205.917292) (xy 377.396248 -205.969362) (xy 377.386801 -205.976118)
			(xy 377.374777 -205.995963) (xy 377.373134 -206.007462) (xy 377.37288 -206.012034) (xy 377.37288 -207.518)
			(xy 379.806706 -207.518) (xy 379.810777 -207.462378) (xy 379.822903 -207.407941) (xy 379.842826 -207.35585)
			(xy 379.870122 -207.307215) (xy 379.904208 -207.263072) (xy 379.944357 -207.224363) (xy 379.989715 -207.191912)
			(xy 380.039315 -207.166411) (xy 380.092099 -207.148404) (xy 380.146942 -207.138274) (xy 380.202676 -207.136237)
			(xy 380.258113 -207.142337) (xy 380.31207 -207.156443) (xy 380.363399 -207.178255) (xy 380.411005 -207.207309)
			(xy 380.453873 -207.242984) (xy 380.49109 -207.284521) (xy 380.521863 -207.331034) (xy 380.545535 -207.381531)
			(xy 380.561603 -207.434938) (xy 380.569723 -207.490114) (xy 380.570232 -207.518) (xy 380.569723 -207.545886)
			(xy 380.561603 -207.601062) (xy 380.545535 -207.654469) (xy 380.521863 -207.704966) (xy 380.49109 -207.751479)
			(xy 380.453873 -207.793016) (xy 380.411005 -207.828691) (xy 380.363399 -207.857745) (xy 380.31207 -207.879557)
			(xy 380.258113 -207.893663) (xy 380.202676 -207.899763) (xy 380.146942 -207.897726) (xy 380.092099 -207.887596)
			(xy 380.039315 -207.869589) (xy 379.989715 -207.844088) (xy 379.944357 -207.811637) (xy 379.904208 -207.772928)
			(xy 379.870122 -207.728785) (xy 379.842826 -207.68015) (xy 379.822903 -207.628059) (xy 379.810777 -207.573622)
			(xy 379.806706 -207.518) (xy 377.37288 -207.518) (xy 377.37288 -208.420052) (xy 378.864354 -208.420052)
			(xy 378.864354 -208.365548) (xy 378.87211 -208.3116) (xy 378.887464 -208.259305) (xy 378.910105 -208.209726)
			(xy 378.93957 -208.163875) (xy 378.97526 -208.122683) (xy 379.016449 -208.086989) (xy 379.062298 -208.05752)
			(xy 379.111875 -208.034876) (xy 379.164169 -208.019517) (xy 379.218117 -208.011756) (xy 379.245368 -208.011268)
			(xy 379.272317 -208.011677) (xy 379.325678 -208.019259) (xy 379.377441 -208.034276) (xy 379.426575 -208.056429)
			(xy 379.444694 -208.06791) (xy 407.722068 -208.06791) (xy 407.726139 -208.012288) (xy 407.738265 -207.957851)
			(xy 407.758188 -207.90576) (xy 407.785484 -207.857125) (xy 407.81957 -207.812982) (xy 407.859719 -207.774273)
			(xy 407.905077 -207.741822) (xy 407.954677 -207.716321) (xy 408.007461 -207.698314) (xy 408.062304 -207.688184)
			(xy 408.118038 -207.686147) (xy 408.173475 -207.692247) (xy 408.227432 -207.706353) (xy 408.278761 -207.728165)
			(xy 408.326367 -207.757219) (xy 408.369235 -207.792894) (xy 408.406452 -207.834431) (xy 408.437225 -207.880944)
			(xy 408.460897 -207.931441) (xy 408.47368 -207.97393) (xy 454.542396 -207.97393) (xy 454.546467 -207.918308)
			(xy 454.558593 -207.863871) (xy 454.578516 -207.81178) (xy 454.605812 -207.763145) (xy 454.639898 -207.719002)
			(xy 454.680047 -207.680293) (xy 454.725405 -207.647842) (xy 454.775005 -207.622341) (xy 454.827789 -207.604334)
			(xy 454.882632 -207.594204) (xy 454.938366 -207.592167) (xy 454.993803 -207.598267) (xy 455.04776 -207.612373)
			(xy 455.099089 -207.634185) (xy 455.146695 -207.663239) (xy 455.189563 -207.698914) (xy 455.22678 -207.740451)
			(xy 455.257553 -207.786964) (xy 455.281225 -207.837461) (xy 455.297293 -207.890868) (xy 455.305413 -207.946044)
			(xy 455.305922 -207.97393) (xy 455.305413 -208.001816) (xy 455.297293 -208.056992) (xy 455.281225 -208.110399)
			(xy 455.257553 -208.160896) (xy 455.22678 -208.207409) (xy 455.189563 -208.248946) (xy 455.146695 -208.284621)
			(xy 455.099089 -208.313675) (xy 455.04776 -208.335487) (xy 454.993803 -208.349593) (xy 454.938366 -208.355693)
			(xy 454.882632 -208.353656) (xy 454.827789 -208.343526) (xy 454.775005 -208.325519) (xy 454.725405 -208.300018)
			(xy 454.680047 -208.267567) (xy 454.639898 -208.228858) (xy 454.605812 -208.184715) (xy 454.578516 -208.13608)
			(xy 454.558593 -208.083989) (xy 454.546467 -208.029552) (xy 454.542396 -207.97393) (xy 408.47368 -207.97393)
			(xy 408.476965 -207.984848) (xy 408.485085 -208.040024) (xy 408.485594 -208.06791) (xy 408.485085 -208.095796)
			(xy 408.476965 -208.150972) (xy 408.460897 -208.204379) (xy 408.437225 -208.254876) (xy 408.406452 -208.301389)
			(xy 408.369235 -208.342926) (xy 408.326367 -208.378601) (xy 408.278761 -208.407655) (xy 408.227432 -208.429467)
			(xy 408.173475 -208.443573) (xy 408.118038 -208.449673) (xy 408.062304 -208.447636) (xy 408.007461 -208.437506)
			(xy 407.954677 -208.419499) (xy 407.905077 -208.393998) (xy 407.859719 -208.361547) (xy 407.81957 -208.322838)
			(xy 407.785484 -208.278695) (xy 407.758188 -208.23006) (xy 407.738265 -208.177969) (xy 407.726139 -208.123532)
			(xy 407.722068 -208.06791) (xy 379.444694 -208.06791) (xy 379.472102 -208.085277) (xy 379.513116 -208.120246)
			(xy 379.548799 -208.16064) (xy 379.578441 -208.205654) (xy 379.601453 -208.254391) (xy 379.609858 -208.28)
			(xy 379.614511 -208.293269) (xy 379.629862 -208.31681) (xy 379.651049 -208.335274) (xy 379.676468 -208.347263)
			(xy 379.704192 -208.351868) (xy 379.732122 -208.34874) (xy 379.75814 -208.338115) (xy 379.780277 -208.3208)
			(xy 379.788928 -208.309718) (xy 379.804341 -208.289161) (xy 379.839856 -208.252028) (xy 379.880034 -208.219999)
			(xy 379.924147 -208.193652) (xy 379.971397 -208.173464) (xy 380.020929 -208.1598) (xy 380.071847 -208.152909)
			(xy 380.097538 -208.152492) (xy 380.124787 -208.15298) (xy 380.178731 -208.160741) (xy 380.231021 -208.1761)
			(xy 380.280594 -208.198743) (xy 380.326439 -208.22821) (xy 380.367625 -208.263902) (xy 380.403312 -208.305091)
			(xy 380.432775 -208.35094) (xy 380.455414 -208.400514) (xy 380.470767 -208.452806) (xy 380.478522 -208.50675)
			(xy 380.478522 -208.56125) (xy 380.470767 -208.615194) (xy 380.455414 -208.667486) (xy 380.432775 -208.71706)
			(xy 380.403312 -208.762909) (xy 380.367625 -208.804098) (xy 380.326439 -208.83979) (xy 380.280594 -208.869257)
			(xy 380.231021 -208.8919) (xy 380.178731 -208.907259) (xy 380.124787 -208.91502) (xy 380.097538 -208.915508)
			(xy 380.070592 -208.91504) (xy 380.017235 -208.907461) (xy 379.965476 -208.892449) (xy 379.916345 -208.870302)
			(xy 379.87082 -208.841461) (xy 379.829807 -208.8065) (xy 379.794121 -208.766115) (xy 379.764475 -208.72111)
			(xy 379.741457 -208.672381) (xy 379.733048 -208.646776) (xy 379.728389 -208.633511) (xy 379.713037 -208.609974)
			(xy 379.69185 -208.591514) (xy 379.666433 -208.579527) (xy 379.638712 -208.574923) (xy 379.610785 -208.578049)
			(xy 379.584768 -208.588669) (xy 379.562631 -208.605979) (xy 379.553978 -208.617058) (xy 379.538554 -208.637607)
			(xy 379.503042 -208.674741) (xy 379.462867 -208.706772) (xy 379.418755 -208.733121) (xy 379.371507 -208.75331)
			(xy 379.321976 -208.766974) (xy 379.271059 -208.773867) (xy 379.245368 -208.774284) (xy 379.218117 -208.773844)
			(xy 379.164169 -208.766083) (xy 379.111875 -208.750724) (xy 379.062298 -208.72808) (xy 379.016449 -208.698611)
			(xy 378.97526 -208.662917) (xy 378.93957 -208.621725) (xy 378.910105 -208.575874) (xy 378.887464 -208.526295)
			(xy 378.87211 -208.474) (xy 378.864354 -208.420052) (xy 377.37288 -208.420052) (xy 377.37288 -209.146902)
			(xy 377.373053 -209.15291) (xy 377.375887 -209.164587) (xy 377.378468 -209.170016) (xy 377.380306 -209.173491)
			(xy 377.384898 -209.179872) (xy 377.387612 -209.182716) (xy 377.390406 -209.18551) (xy 377.448064 -209.235294)
			(xy 377.452308 -209.238707) (xy 377.461915 -209.243832) (xy 377.467114 -209.245454) (xy 377.47575 -209.247994)
			(xy 377.489212 -209.24647) (xy 377.489466 -209.24647) (xy 377.527312 -209.243676) (xy 377.531884 -209.243676)
			(xy 377.539504 -209.243676) (xy 377.542298 -209.243676) (xy 377.569536 -209.244182) (xy 377.623452 -209.251973)
			(xy 377.675712 -209.267354) (xy 377.725253 -209.290012) (xy 377.771067 -209.319486) (xy 377.812223 -209.355177)
			(xy 377.847884 -209.396359) (xy 377.877324 -209.442195) (xy 377.899945 -209.491753) (xy 377.915287 -209.544024)
			(xy 377.916146 -209.55) (xy 379.408942 -209.55) (xy 379.413013 -209.494378) (xy 379.425139 -209.439941)
			(xy 379.445062 -209.38785) (xy 379.472358 -209.339215) (xy 379.506444 -209.295072) (xy 379.546593 -209.256363)
			(xy 379.591951 -209.223912) (xy 379.641551 -209.198411) (xy 379.694335 -209.180404) (xy 379.749178 -209.170274)
			(xy 379.804912 -209.168237) (xy 379.860349 -209.174337) (xy 379.914306 -209.188443) (xy 379.965635 -209.210255)
			(xy 380.013241 -209.239309) (xy 380.056109 -209.274984) (xy 380.093326 -209.316521) (xy 380.124099 -209.363034)
			(xy 380.132444 -209.380836) (xy 445.288416 -209.380836) (xy 445.288416 -208.517236) (xy 445.288906 -208.487268)
			(xy 445.296729 -208.427846) (xy 445.312242 -208.369953) (xy 445.335178 -208.31458) (xy 445.365145 -208.262674)
			(xy 445.401632 -208.215124) (xy 445.444012 -208.172744) (xy 445.491562 -208.136257) (xy 445.543468 -208.10629)
			(xy 445.598841 -208.083354) (xy 445.656734 -208.067841) (xy 445.716156 -208.060018) (xy 445.776092 -208.060018)
			(xy 445.835514 -208.067841) (xy 445.893407 -208.083354) (xy 445.94878 -208.10629) (xy 446.000686 -208.136257)
			(xy 446.048236 -208.172744) (xy 446.090616 -208.215124) (xy 446.127103 -208.262674) (xy 446.15707 -208.31458)
			(xy 446.180006 -208.369953) (xy 446.195519 -208.427846) (xy 446.203342 -208.487268) (xy 446.203832 -208.517236)
			(xy 446.203832 -209.380836) (xy 446.203342 -209.410804) (xy 446.195519 -209.470226) (xy 446.180006 -209.528119)
			(xy 446.15707 -209.583492) (xy 446.127103 -209.635398) (xy 446.090616 -209.682948) (xy 446.048236 -209.725328)
			(xy 446.000686 -209.761815) (xy 445.94878 -209.791782) (xy 445.893407 -209.814718) (xy 445.835514 -209.830231)
			(xy 445.776092 -209.838054) (xy 445.716156 -209.838054) (xy 445.656734 -209.830231) (xy 445.598841 -209.814718)
			(xy 445.543468 -209.791782) (xy 445.491562 -209.761815) (xy 445.444012 -209.725328) (xy 445.401632 -209.682948)
			(xy 445.365145 -209.635398) (xy 445.335178 -209.583492) (xy 445.312242 -209.528119) (xy 445.296729 -209.470226)
			(xy 445.288906 -209.410804) (xy 445.288416 -209.380836) (xy 380.132444 -209.380836) (xy 380.147771 -209.413531)
			(xy 380.163839 -209.466938) (xy 380.171959 -209.522114) (xy 380.172468 -209.55) (xy 380.171959 -209.577886)
			(xy 380.163839 -209.633062) (xy 380.147771 -209.686469) (xy 380.124099 -209.736966) (xy 380.093326 -209.783479)
			(xy 380.056109 -209.825016) (xy 380.013241 -209.860691) (xy 379.965635 -209.889745) (xy 379.914306 -209.911557)
			(xy 379.860349 -209.925663) (xy 379.804912 -209.931763) (xy 379.749178 -209.929726) (xy 379.694335 -209.919596)
			(xy 379.641551 -209.901589) (xy 379.591951 -209.876088) (xy 379.546593 -209.843637) (xy 379.506444 -209.804928)
			(xy 379.472358 -209.760785) (xy 379.445062 -209.71215) (xy 379.425139 -209.660059) (xy 379.413013 -209.605622)
			(xy 379.408942 -209.55) (xy 377.916146 -209.55) (xy 377.923038 -209.597946) (xy 377.923552 -209.625184)
			(xy 377.923067 -209.652437) (xy 377.915313 -209.706389) (xy 377.89996 -209.758688) (xy 377.87732 -209.80827)
			(xy 377.847855 -209.854126) (xy 377.812164 -209.895321) (xy 377.770974 -209.931019) (xy 377.743342 -209.94878)
			(xy 451.586598 -209.94878) (xy 451.590669 -209.893158) (xy 451.602795 -209.838721) (xy 451.622718 -209.78663)
			(xy 451.650014 -209.737995) (xy 451.6841 -209.693852) (xy 451.724249 -209.655143) (xy 451.769607 -209.622692)
			(xy 451.819207 -209.597191) (xy 451.871991 -209.579184) (xy 451.926834 -209.569054) (xy 451.982568 -209.567017)
			(xy 452.038005 -209.573117) (xy 452.091962 -209.587223) (xy 452.143291 -209.609035) (xy 452.190897 -209.638089)
			(xy 452.233765 -209.673764) (xy 452.270982 -209.715301) (xy 452.301755 -209.761814) (xy 452.325427 -209.812311)
			(xy 452.341495 -209.865718) (xy 452.349615 -209.920894) (xy 452.350124 -209.94878) (xy 452.349615 -209.976666)
			(xy 452.341495 -210.031842) (xy 452.325427 -210.085249) (xy 452.301755 -210.135746) (xy 452.270982 -210.182259)
			(xy 452.233765 -210.223796) (xy 452.190897 -210.259471) (xy 452.143291 -210.288525) (xy 452.091962 -210.310337)
			(xy 452.038005 -210.324443) (xy 451.982568 -210.330543) (xy 451.926834 -210.328506) (xy 451.871991 -210.318376)
			(xy 451.819207 -210.300369) (xy 451.769607 -210.274868) (xy 451.724249 -210.242417) (xy 451.6841 -210.203708)
			(xy 451.650014 -210.159565) (xy 451.622718 -210.11093) (xy 451.602795 -210.058839) (xy 451.590669 -210.004402)
			(xy 451.586598 -209.94878) (xy 377.743342 -209.94878) (xy 377.725123 -209.960491) (xy 377.675544 -209.983139)
			(xy 377.623248 -209.9985) (xy 377.569297 -210.006263) (xy 377.542044 -210.006692) (xy 377.54179 -210.006692)
			(xy 377.528604 -210.006594) (xy 377.502292 -210.004813) (xy 377.489212 -210.003136) (xy 377.48464 -210.002374)
			(xy 377.475624 -210.002334) (xy 377.458458 -210.007812) (xy 377.451112 -210.013042) (xy 377.444254 -210.019138)
			(xy 377.387104 -210.068922) (xy 377.380659 -210.076221) (xy 377.373345 -210.094248) (xy 377.37288 -210.103974)
			(xy 377.37288 -210.479894) (xy 377.373052 -210.485902) (xy 377.375884 -210.49758) (xy 377.378468 -210.503008)
			(xy 377.380306 -210.506483) (xy 377.384897 -210.512865) (xy 377.387612 -210.515708) (xy 377.437904 -210.566)
			(xy 379.759716 -210.566) (xy 379.763787 -210.510378) (xy 379.775913 -210.455941) (xy 379.795836 -210.40385)
			(xy 379.823132 -210.355215) (xy 379.857218 -210.311072) (xy 379.897367 -210.272363) (xy 379.942725 -210.239912)
			(xy 379.992325 -210.214411) (xy 380.045109 -210.196404) (xy 380.099952 -210.186274) (xy 380.155686 -210.184237)
			(xy 380.211123 -210.190337) (xy 380.26508 -210.204443) (xy 380.316409 -210.226255) (xy 380.364015 -210.255309)
			(xy 380.406883 -210.290984) (xy 380.4441 -210.332521) (xy 380.450185 -210.341718) (xy 409.3497 -210.341718)
			(xy 409.353771 -210.286096) (xy 409.365897 -210.231659) (xy 409.38582 -210.179568) (xy 409.413116 -210.130933)
			(xy 409.447202 -210.08679) (xy 409.487351 -210.048081) (xy 409.532709 -210.01563) (xy 409.582309 -209.990129)
			(xy 409.635093 -209.972122) (xy 409.689936 -209.961992) (xy 409.74567 -209.959955) (xy 409.801107 -209.966055)
			(xy 409.855064 -209.980161) (xy 409.906393 -210.001973) (xy 409.953999 -210.031027) (xy 409.996867 -210.066702)
			(xy 410.034084 -210.108239) (xy 410.064857 -210.154752) (xy 410.088529 -210.205249) (xy 410.104597 -210.258656)
			(xy 410.112717 -210.313832) (xy 410.113226 -210.341718) (xy 410.112717 -210.369604) (xy 410.104597 -210.42478)
			(xy 410.088529 -210.478187) (xy 410.064857 -210.528684) (xy 410.034084 -210.575197) (xy 409.996867 -210.616734)
			(xy 409.953999 -210.652409) (xy 409.906393 -210.681463) (xy 409.855064 -210.703275) (xy 409.801107 -210.717381)
			(xy 409.74567 -210.723481) (xy 409.689936 -210.721444) (xy 409.635093 -210.711314) (xy 409.582309 -210.693307)
			(xy 409.532709 -210.667806) (xy 409.487351 -210.635355) (xy 409.447202 -210.596646) (xy 409.413116 -210.552503)
			(xy 409.38582 -210.503868) (xy 409.365897 -210.451777) (xy 409.353771 -210.39734) (xy 409.3497 -210.341718)
			(xy 380.450185 -210.341718) (xy 380.474873 -210.379034) (xy 380.498545 -210.429531) (xy 380.514613 -210.482938)
			(xy 380.522733 -210.538114) (xy 380.523242 -210.566) (xy 380.522733 -210.593886) (xy 380.514613 -210.649062)
			(xy 380.498545 -210.702469) (xy 380.474873 -210.752966) (xy 380.4441 -210.799479) (xy 380.406883 -210.841016)
			(xy 380.364015 -210.876691) (xy 380.316409 -210.905745) (xy 380.26508 -210.927557) (xy 380.211123 -210.941663)
			(xy 380.155686 -210.947763) (xy 380.099952 -210.945726) (xy 380.045109 -210.935596) (xy 379.992325 -210.917589)
			(xy 379.942725 -210.892088) (xy 379.897367 -210.859637) (xy 379.857218 -210.820928) (xy 379.823132 -210.776785)
			(xy 379.795836 -210.72815) (xy 379.775913 -210.676059) (xy 379.763787 -210.621622) (xy 379.759716 -210.566)
			(xy 377.437904 -210.566) (xy 377.556014 -210.68411) (xy 377.560301 -210.688129) (xy 377.570308 -210.694283)
			(xy 377.575826 -210.696302) (xy 377.587256 -210.700112) (xy 377.599194 -210.698334) (xy 377.612769 -210.696458)
			(xy 377.640101 -210.694426) (xy 377.653804 -210.69427) (xy 377.681071 -210.694757) (xy 377.73505 -210.702518)
			(xy 377.787374 -210.717883) (xy 377.83698 -210.740537) (xy 377.882856 -210.770021) (xy 377.92407 -210.805733)
			(xy 377.959782 -210.846947) (xy 377.989265 -210.892824) (xy 378.011919 -210.94243) (xy 378.027283 -210.994754)
			(xy 378.035044 -211.048733) (xy 378.035044 -211.103267) (xy 378.027283 -211.157246) (xy 378.011919 -211.20957)
			(xy 377.989265 -211.259176) (xy 377.959782 -211.305053) (xy 377.92407 -211.346267) (xy 377.882856 -211.381979)
			(xy 377.83698 -211.411463) (xy 377.787374 -211.434118) (xy 377.73505 -211.449482) (xy 377.681071 -211.457243)
			(xy 377.653804 -211.457794) (xy 377.64196 -211.457667) (xy 377.618322 -211.456139) (xy 377.60656 -211.454746)
			(xy 377.606052 -211.454746) (xy 377.594526 -211.453918) (xy 377.572713 -211.461471) (xy 377.564142 -211.469224)
			(xy 377.387612 -211.645754) (xy 377.384092 -211.649485) (xy 377.378466 -211.658061) (xy 377.376436 -211.662772)
			(xy 377.37288 -211.671408) (xy 377.37288 -211.810092) (xy 378.849634 -211.810092) (xy 378.853705 -211.75447)
			(xy 378.865831 -211.700033) (xy 378.885754 -211.647942) (xy 378.91305 -211.599307) (xy 378.947136 -211.555164)
			(xy 378.987285 -211.516455) (xy 379.032643 -211.484004) (xy 379.082243 -211.458503) (xy 379.135027 -211.440496)
			(xy 379.18987 -211.430366) (xy 379.245604 -211.428329) (xy 379.301041 -211.434429) (xy 379.354998 -211.448535)
			(xy 379.406327 -211.470347) (xy 379.453933 -211.499401) (xy 379.496801 -211.535076) (xy 379.534018 -211.576613)
			(xy 379.564791 -211.623126) (xy 379.588463 -211.673623) (xy 379.599107 -211.709) (xy 383.29184 -211.709)
			(xy 383.295911 -211.653378) (xy 383.308037 -211.598941) (xy 383.32796 -211.54685) (xy 383.355256 -211.498215)
			(xy 383.389342 -211.454072) (xy 383.429491 -211.415363) (xy 383.474849 -211.382912) (xy 383.524449 -211.357411)
			(xy 383.577233 -211.339404) (xy 383.632076 -211.329274) (xy 383.68781 -211.327237) (xy 383.743247 -211.333337)
			(xy 383.797204 -211.347443) (xy 383.848533 -211.369255) (xy 383.896139 -211.398309) (xy 383.939007 -211.433984)
			(xy 383.976224 -211.475521) (xy 384.006997 -211.522034) (xy 384.030669 -211.572531) (xy 384.046737 -211.625938)
			(xy 384.054857 -211.681114) (xy 384.055366 -211.709) (xy 384.054857 -211.736886) (xy 384.046737 -211.792062)
			(xy 384.030669 -211.845469) (xy 384.006997 -211.895966) (xy 383.976224 -211.942479) (xy 383.939007 -211.984016)
			(xy 383.896139 -212.019691) (xy 383.848533 -212.048745) (xy 383.797204 -212.070557) (xy 383.743247 -212.084663)
			(xy 383.68781 -212.090763) (xy 383.632076 -212.088726) (xy 383.577233 -212.078596) (xy 383.524449 -212.060589)
			(xy 383.474849 -212.035088) (xy 383.429491 -212.002637) (xy 383.389342 -211.963928) (xy 383.355256 -211.919785)
			(xy 383.32796 -211.87115) (xy 383.308037 -211.819059) (xy 383.295911 -211.764622) (xy 383.29184 -211.709)
			(xy 379.599107 -211.709) (xy 379.604531 -211.72703) (xy 379.612651 -211.782206) (xy 379.61316 -211.810092)
			(xy 379.612651 -211.837978) (xy 379.604531 -211.893154) (xy 379.588463 -211.946561) (xy 379.564791 -211.997058)
			(xy 379.534018 -212.043571) (xy 379.496801 -212.085108) (xy 379.453933 -212.120783) (xy 379.406327 -212.149837)
			(xy 379.354998 -212.171649) (xy 379.301041 -212.185755) (xy 379.245604 -212.191855) (xy 379.18987 -212.189818)
			(xy 379.135027 -212.179688) (xy 379.082243 -212.161681) (xy 379.032643 -212.13618) (xy 378.987285 -212.103729)
			(xy 378.947136 -212.06502) (xy 378.91305 -212.020877) (xy 378.885754 -211.972242) (xy 378.865831 -211.920151)
			(xy 378.853705 -211.865714) (xy 378.849634 -211.810092) (xy 377.37288 -211.810092) (xy 377.37288 -212.0265)
			(xy 377.373253 -212.035066) (xy 377.378969 -212.05122) (xy 377.389666 -212.064606) (xy 377.396756 -212.069426)
			(xy 377.46178 -212.109812) (xy 377.467885 -212.113316) (xy 377.481415 -212.117184) (xy 377.48845 -212.117432)
			(xy 377.518676 -212.117432) (xy 377.528836 -212.11286) (xy 377.553758 -212.102048) (xy 377.605892 -212.086784)
			(xy 377.659663 -212.079054) (xy 377.686824 -212.07857) (xy 377.695206 -212.07857) (xy 377.722075 -212.079602)
			(xy 377.775139 -212.088283) (xy 377.826458 -212.104331) (xy 377.875014 -212.127427) (xy 377.919845 -212.157114)
			(xy 377.960063 -212.192802) (xy 377.99487 -212.233786) (xy 378.023576 -212.279251) (xy 378.045612 -212.328298)
			(xy 378.060541 -212.379953) (xy 378.068068 -212.433193) (xy 378.068586 -212.460078) (xy 378.068124 -212.487331)
			(xy 378.06037 -212.541283) (xy 378.045015 -212.593583) (xy 378.022374 -212.643164) (xy 377.998511 -212.680296)
			(xy 378.744732 -212.680296) (xy 378.748803 -212.624674) (xy 378.760929 -212.570237) (xy 378.780852 -212.518146)
			(xy 378.808148 -212.469511) (xy 378.842234 -212.425368) (xy 378.882383 -212.386659) (xy 378.927741 -212.354208)
			(xy 378.977341 -212.328707) (xy 379.030125 -212.3107) (xy 379.084968 -212.30057) (xy 379.140702 -212.298533)
			(xy 379.196139 -212.304633) (xy 379.250096 -212.318739) (xy 379.301425 -212.340551) (xy 379.349031 -212.369605)
			(xy 379.391899 -212.40528) (xy 379.429116 -212.446817) (xy 379.459889 -212.49333) (xy 379.483561 -212.543827)
			(xy 379.499629 -212.597234) (xy 379.507749 -212.65241) (xy 379.508258 -212.680296) (xy 379.507749 -212.708182)
			(xy 379.499629 -212.763358) (xy 379.483561 -212.816765) (xy 379.459889 -212.867262) (xy 379.429116 -212.913775)
			(xy 379.391899 -212.955312) (xy 379.349031 -212.990987) (xy 379.301425 -213.020041) (xy 379.250096 -213.041853)
			(xy 379.196139 -213.055959) (xy 379.140702 -213.062059) (xy 379.084968 -213.060022) (xy 379.030125 -213.049892)
			(xy 378.977341 -213.031885) (xy 378.927741 -213.006384) (xy 378.882383 -212.973933) (xy 378.842234 -212.935224)
			(xy 378.808148 -212.891081) (xy 378.780852 -212.842446) (xy 378.760929 -212.790355) (xy 378.748803 -212.735918)
			(xy 378.744732 -212.680296) (xy 377.998511 -212.680296) (xy 377.992906 -212.689018) (xy 377.957212 -212.730212)
			(xy 377.916018 -212.765906) (xy 377.870164 -212.795374) (xy 377.820583 -212.818015) (xy 377.768283 -212.83337)
			(xy 377.714331 -212.841124) (xy 377.687078 -212.841586) (xy 377.686824 -212.841586) (xy 377.659661 -212.841112)
			(xy 377.605883 -212.833406) (xy 377.553748 -212.818134) (xy 377.528836 -212.807296) (xy 377.523828 -212.805167)
			(xy 377.513194 -212.802861) (xy 377.507754 -212.802724) (xy 377.48845 -212.802724) (xy 377.481412 -212.802952)
			(xy 377.467882 -212.806828) (xy 377.46178 -212.810344) (xy 377.437142 -212.825584) (xy 377.409456 -212.842856)
			(xy 377.401328 -212.847936) (xy 377.396756 -212.85073) (xy 377.389644 -212.855536) (xy 377.378892 -212.868902)
			(xy 377.373185 -212.885079) (xy 377.37288 -212.893656) (xy 377.37288 -213.97595) (xy 378.439932 -213.97595)
			(xy 378.444003 -213.920328) (xy 378.456129 -213.865891) (xy 378.476052 -213.8138) (xy 378.503348 -213.765165)
			(xy 378.537434 -213.721022) (xy 378.577583 -213.682313) (xy 378.622941 -213.649862) (xy 378.672541 -213.624361)
			(xy 378.725325 -213.606354) (xy 378.780168 -213.596224) (xy 378.835902 -213.594187) (xy 378.891339 -213.600287)
			(xy 378.945296 -213.614393) (xy 378.996625 -213.636205) (xy 379.044231 -213.665259) (xy 379.087099 -213.700934)
			(xy 379.124316 -213.742471) (xy 379.155089 -213.788984) (xy 379.178761 -213.839481) (xy 379.194829 -213.892888)
			(xy 379.202949 -213.948064) (xy 379.203458 -213.97595) (xy 379.202949 -214.003836) (xy 379.194829 -214.059012)
			(xy 379.178761 -214.112419) (xy 379.155089 -214.162916) (xy 379.124316 -214.209429) (xy 379.087099 -214.250966)
			(xy 379.044231 -214.286641) (xy 378.996625 -214.315695) (xy 378.945296 -214.337507) (xy 378.891339 -214.351613)
			(xy 378.835902 -214.357713) (xy 378.780168 -214.355676) (xy 378.725325 -214.345546) (xy 378.672541 -214.327539)
			(xy 378.622941 -214.302038) (xy 378.577583 -214.269587) (xy 378.537434 -214.230878) (xy 378.503348 -214.186735)
			(xy 378.476052 -214.1381) (xy 378.456129 -214.086009) (xy 378.444003 -214.031572) (xy 378.439932 -213.97595)
			(xy 377.37288 -213.97595) (xy 377.37288 -215.398096) (xy 377.373052 -215.404104) (xy 377.375885 -215.415782)
			(xy 377.378468 -215.42121) (xy 377.380306 -215.424685) (xy 377.384897 -215.431067) (xy 377.387612 -215.43391)
			(xy 377.79833 -215.844628) (xy 377.80518 -215.852025) (xy 377.812915 -215.870624) (xy 377.813316 -215.880696)
			(xy 377.813316 -218.40317) (xy 380.707644 -218.40317) (xy 380.711715 -218.347548) (xy 380.723841 -218.293111)
			(xy 380.743764 -218.24102) (xy 380.77106 -218.192385) (xy 380.805146 -218.148242) (xy 380.845295 -218.109533)
			(xy 380.890653 -218.077082) (xy 380.940253 -218.051581) (xy 380.993037 -218.033574) (xy 381.04788 -218.023444)
			(xy 381.103614 -218.021407) (xy 381.159051 -218.027507) (xy 381.213008 -218.041613) (xy 381.264337 -218.063425)
			(xy 381.311943 -218.092479) (xy 381.354811 -218.128154) (xy 381.392028 -218.169691) (xy 381.422801 -218.216204)
			(xy 381.446473 -218.266701) (xy 381.462541 -218.320108) (xy 381.469382 -218.366594) (xy 381.872234 -218.366594)
			(xy 381.876305 -218.310972) (xy 381.888431 -218.256535) (xy 381.908354 -218.204444) (xy 381.93565 -218.155809)
			(xy 381.969736 -218.111666) (xy 382.009885 -218.072957) (xy 382.055243 -218.040506) (xy 382.104843 -218.015005)
			(xy 382.157627 -217.996998) (xy 382.21247 -217.986868) (xy 382.268204 -217.984831) (xy 382.323641 -217.990931)
			(xy 382.377598 -218.005037) (xy 382.428927 -218.026849) (xy 382.476533 -218.055903) (xy 382.519401 -218.091578)
			(xy 382.556618 -218.133115) (xy 382.587391 -218.179628) (xy 382.611063 -218.230125) (xy 382.627131 -218.283532)
			(xy 382.635251 -218.338708) (xy 382.63576 -218.366594) (xy 382.635251 -218.39448) (xy 382.627131 -218.449656)
			(xy 382.611063 -218.503063) (xy 382.587391 -218.55356) (xy 382.556618 -218.600073) (xy 382.519401 -218.64161)
			(xy 382.476533 -218.677285) (xy 382.428927 -218.706339) (xy 382.377598 -218.728151) (xy 382.323641 -218.742257)
			(xy 382.268204 -218.748357) (xy 382.21247 -218.74632) (xy 382.157627 -218.73619) (xy 382.104843 -218.718183)
			(xy 382.055243 -218.692682) (xy 382.009885 -218.660231) (xy 381.969736 -218.621522) (xy 381.93565 -218.577379)
			(xy 381.908354 -218.528744) (xy 381.888431 -218.476653) (xy 381.876305 -218.422216) (xy 381.872234 -218.366594)
			(xy 381.469382 -218.366594) (xy 381.470661 -218.375284) (xy 381.47117 -218.40317) (xy 381.470661 -218.431056)
			(xy 381.462541 -218.486232) (xy 381.446473 -218.539639) (xy 381.422801 -218.590136) (xy 381.392028 -218.636649)
			(xy 381.354811 -218.678186) (xy 381.311943 -218.713861) (xy 381.264337 -218.742915) (xy 381.213008 -218.764727)
			(xy 381.159051 -218.778833) (xy 381.103614 -218.784933) (xy 381.04788 -218.782896) (xy 380.993037 -218.772766)
			(xy 380.940253 -218.754759) (xy 380.890653 -218.729258) (xy 380.845295 -218.696807) (xy 380.805146 -218.658098)
			(xy 380.77106 -218.613955) (xy 380.743764 -218.56532) (xy 380.723841 -218.513229) (xy 380.711715 -218.458792)
			(xy 380.707644 -218.40317) (xy 377.813316 -218.40317) (xy 377.813316 -220.324172) (xy 383.84683 -220.324172)
			(xy 383.850901 -220.26855) (xy 383.863027 -220.214113) (xy 383.88295 -220.162022) (xy 383.910246 -220.113387)
			(xy 383.944332 -220.069244) (xy 383.984481 -220.030535) (xy 384.029839 -219.998084) (xy 384.079439 -219.972583)
			(xy 384.132223 -219.954576) (xy 384.187066 -219.944446) (xy 384.2428 -219.942409) (xy 384.298237 -219.948509)
			(xy 384.352194 -219.962615) (xy 384.403523 -219.984427) (xy 384.451129 -220.013481) (xy 384.493997 -220.049156)
			(xy 384.531214 -220.090693) (xy 384.561987 -220.137206) (xy 384.585659 -220.187703) (xy 384.601727 -220.24111)
			(xy 384.609847 -220.296286) (xy 384.610356 -220.324172) (xy 384.609847 -220.352058) (xy 384.601727 -220.407234)
			(xy 384.585659 -220.460641) (xy 384.561987 -220.511138) (xy 384.531214 -220.557651) (xy 384.493997 -220.599188)
			(xy 384.451129 -220.634863) (xy 384.403523 -220.663917) (xy 384.352194 -220.685729) (xy 384.298237 -220.699835)
			(xy 384.2428 -220.705935) (xy 384.187066 -220.703898) (xy 384.132223 -220.693768) (xy 384.079439 -220.675761)
			(xy 384.029839 -220.65026) (xy 383.984481 -220.617809) (xy 383.944332 -220.5791) (xy 383.910246 -220.534957)
			(xy 383.88295 -220.486322) (xy 383.863027 -220.434231) (xy 383.850901 -220.379794) (xy 383.84683 -220.324172)
			(xy 377.813316 -220.324172) (xy 377.813316 -221.223586) (xy 377.813821 -221.237761) (xy 377.821686 -221.265)
			(xy 377.836732 -221.289031) (xy 377.857801 -221.308003) (xy 377.883272 -221.320458) (xy 377.911183 -221.325436)
			(xy 377.92533 -221.324424) (xy 377.927362 -221.32417) (xy 377.942188 -221.321997) (xy 377.972068 -221.319708)
			(xy 377.987052 -221.319598) (xy 378.014307 -221.320058) (xy 378.039395 -221.323662) (xy 417.33419 -221.323662)
			(xy 417.338261 -221.26804) (xy 417.350387 -221.213603) (xy 417.37031 -221.161512) (xy 417.397606 -221.112877)
			(xy 417.431692 -221.068734) (xy 417.471841 -221.030025) (xy 417.517199 -220.997574) (xy 417.566799 -220.972073)
			(xy 417.619583 -220.954066) (xy 417.674426 -220.943936) (xy 417.73016 -220.941899) (xy 417.785597 -220.947999)
			(xy 417.839554 -220.962105) (xy 417.890883 -220.983917) (xy 417.938489 -221.012971) (xy 417.981357 -221.048646)
			(xy 418.018574 -221.090183) (xy 418.049347 -221.136696) (xy 418.073019 -221.187193) (xy 418.089087 -221.2406)
			(xy 418.097207 -221.295776) (xy 418.097716 -221.323662) (xy 418.097207 -221.351548) (xy 418.089087 -221.406724)
			(xy 418.073019 -221.460131) (xy 418.049347 -221.510628) (xy 418.018574 -221.557141) (xy 417.981357 -221.598678)
			(xy 417.938489 -221.634353) (xy 417.890883 -221.663407) (xy 417.839554 -221.685219) (xy 417.785597 -221.699325)
			(xy 417.73016 -221.705425) (xy 417.674426 -221.703388) (xy 417.619583 -221.693258) (xy 417.566799 -221.675251)
			(xy 417.517199 -221.64975) (xy 417.471841 -221.617299) (xy 417.431692 -221.57859) (xy 417.397606 -221.534447)
			(xy 417.37031 -221.485812) (xy 417.350387 -221.433721) (xy 417.338261 -221.379284) (xy 417.33419 -221.323662)
			(xy 378.039395 -221.323662) (xy 378.068262 -221.327809) (xy 378.120565 -221.343161) (xy 378.17015 -221.3658)
			(xy 378.216009 -221.395267) (xy 378.257206 -221.43096) (xy 378.292905 -221.472153) (xy 378.322377 -221.518008)
			(xy 378.345022 -221.56759) (xy 378.36038 -221.619891) (xy 378.368139 -221.673845) (xy 378.368139 -221.728355)
			(xy 378.36038 -221.782309) (xy 378.345022 -221.83461) (xy 378.322377 -221.884192) (xy 378.292905 -221.930047)
			(xy 378.271188 -221.955106) (xy 380.780034 -221.955106) (xy 380.784105 -221.899484) (xy 380.796231 -221.845047)
			(xy 380.816154 -221.792956) (xy 380.84345 -221.744321) (xy 380.877536 -221.700178) (xy 380.917685 -221.661469)
			(xy 380.963043 -221.629018) (xy 381.012643 -221.603517) (xy 381.065427 -221.58551) (xy 381.12027 -221.57538)
			(xy 381.176004 -221.573343) (xy 381.231441 -221.579443) (xy 381.285398 -221.593549) (xy 381.336727 -221.615361)
			(xy 381.384333 -221.644415) (xy 381.427201 -221.68009) (xy 381.464418 -221.721627) (xy 381.495191 -221.76814)
			(xy 381.518863 -221.818637) (xy 381.534931 -221.872044) (xy 381.543051 -221.92722) (xy 381.543286 -221.94012)
			(xy 385.30479 -221.94012) (xy 385.308861 -221.884498) (xy 385.320987 -221.830061) (xy 385.34091 -221.77797)
			(xy 385.368206 -221.729335) (xy 385.402292 -221.685192) (xy 385.442441 -221.646483) (xy 385.487799 -221.614032)
			(xy 385.537399 -221.588531) (xy 385.590183 -221.570524) (xy 385.645026 -221.560394) (xy 385.70076 -221.558357)
			(xy 385.756197 -221.564457) (xy 385.810154 -221.578563) (xy 385.861483 -221.600375) (xy 385.909089 -221.629429)
			(xy 385.951957 -221.665104) (xy 385.989174 -221.706641) (xy 386.019947 -221.753154) (xy 386.043619 -221.803651)
			(xy 386.059687 -221.857058) (xy 386.067807 -221.912234) (xy 386.068316 -221.94012) (xy 386.067807 -221.968006)
			(xy 386.059687 -222.023182) (xy 386.043619 -222.076589) (xy 386.033769 -222.0976) (xy 451.742046 -222.0976)
			(xy 451.746117 -222.041978) (xy 451.758243 -221.987541) (xy 451.778166 -221.93545) (xy 451.805462 -221.886815)
			(xy 451.839548 -221.842672) (xy 451.879697 -221.803963) (xy 451.925055 -221.771512) (xy 451.974655 -221.746011)
			(xy 452.027439 -221.728004) (xy 452.082282 -221.717874) (xy 452.138016 -221.715837) (xy 452.193453 -221.721937)
			(xy 452.24741 -221.736043) (xy 452.298739 -221.757855) (xy 452.346345 -221.786909) (xy 452.389213 -221.822584)
			(xy 452.42643 -221.864121) (xy 452.457203 -221.910634) (xy 452.480875 -221.961131) (xy 452.496943 -222.014538)
			(xy 452.505063 -222.069714) (xy 452.505572 -222.0976) (xy 452.505063 -222.125486) (xy 452.496943 -222.180662)
			(xy 452.480875 -222.234069) (xy 452.457203 -222.284566) (xy 452.42643 -222.331079) (xy 452.389213 -222.372616)
			(xy 452.346345 -222.408291) (xy 452.298739 -222.437345) (xy 452.24741 -222.459157) (xy 452.193453 -222.473263)
			(xy 452.138016 -222.479363) (xy 452.082282 -222.477326) (xy 452.027439 -222.467196) (xy 451.974655 -222.449189)
			(xy 451.925055 -222.423688) (xy 451.879697 -222.391237) (xy 451.839548 -222.352528) (xy 451.805462 -222.308385)
			(xy 451.778166 -222.25975) (xy 451.758243 -222.207659) (xy 451.746117 -222.153222) (xy 451.742046 -222.0976)
			(xy 386.033769 -222.0976) (xy 386.019947 -222.127086) (xy 385.989174 -222.173599) (xy 385.951957 -222.215136)
			(xy 385.909089 -222.250811) (xy 385.861483 -222.279865) (xy 385.810154 -222.301677) (xy 385.756197 -222.315783)
			(xy 385.70076 -222.321883) (xy 385.645026 -222.319846) (xy 385.590183 -222.309716) (xy 385.537399 -222.291709)
			(xy 385.487799 -222.266208) (xy 385.442441 -222.233757) (xy 385.402292 -222.195048) (xy 385.368206 -222.150905)
			(xy 385.34091 -222.10227) (xy 385.320987 -222.050179) (xy 385.308861 -221.995742) (xy 385.30479 -221.94012)
			(xy 381.543286 -221.94012) (xy 381.54356 -221.955106) (xy 381.543051 -221.982992) (xy 381.534931 -222.038168)
			(xy 381.518863 -222.091575) (xy 381.495191 -222.142072) (xy 381.464418 -222.188585) (xy 381.427201 -222.230122)
			(xy 381.384333 -222.265797) (xy 381.336727 -222.294851) (xy 381.285398 -222.316663) (xy 381.231441 -222.330769)
			(xy 381.176004 -222.336869) (xy 381.12027 -222.334832) (xy 381.065427 -222.324702) (xy 381.012643 -222.306695)
			(xy 380.963043 -222.281194) (xy 380.917685 -222.248743) (xy 380.877536 -222.210034) (xy 380.84345 -222.165891)
			(xy 380.816154 -222.117256) (xy 380.796231 -222.065165) (xy 380.784105 -222.010728) (xy 380.780034 -221.955106)
			(xy 378.271188 -221.955106) (xy 378.257206 -221.97124) (xy 378.216009 -222.006933) (xy 378.17015 -222.0364)
			(xy 378.120565 -222.059039) (xy 378.068262 -222.074391) (xy 378.014307 -222.082142) (xy 377.987052 -222.082614)
			(xy 377.972068 -222.082497) (xy 377.942188 -222.080211) (xy 377.927362 -222.078042) (xy 377.92533 -222.077788)
			(xy 377.911181 -222.076797) (xy 377.883267 -222.081754) (xy 377.857793 -222.094199) (xy 377.836725 -222.113171)
			(xy 377.821688 -222.137207) (xy 377.813843 -222.164451) (xy 377.813316 -222.178626) (xy 377.813316 -222.620586)
			(xy 377.813821 -222.634761) (xy 377.821686 -222.662) (xy 377.836732 -222.686031) (xy 377.857801 -222.705003)
			(xy 377.883272 -222.717458) (xy 377.911183 -222.722436) (xy 377.92533 -222.721424) (xy 377.927362 -222.72117)
			(xy 377.942188 -222.718997) (xy 377.972068 -222.716708) (xy 377.987052 -222.716598) (xy 378.014307 -222.717058)
			(xy 378.068262 -222.724809) (xy 378.120565 -222.740161) (xy 378.17015 -222.7628) (xy 378.216009 -222.792267)
			(xy 378.257206 -222.82796) (xy 378.292905 -222.869153) (xy 378.322377 -222.915008) (xy 378.345022 -222.96459)
			(xy 378.36038 -223.016891) (xy 378.368139 -223.070845) (xy 378.368139 -223.125355) (xy 378.36038 -223.179309)
			(xy 378.345022 -223.23161) (xy 378.341148 -223.240092) (xy 385.3213 -223.240092) (xy 385.325371 -223.18447)
			(xy 385.337497 -223.130033) (xy 385.35742 -223.077942) (xy 385.384716 -223.029307) (xy 385.418802 -222.985164)
			(xy 385.458951 -222.946455) (xy 385.504309 -222.914004) (xy 385.553909 -222.888503) (xy 385.606693 -222.870496)
			(xy 385.661536 -222.860366) (xy 385.71727 -222.858329) (xy 385.772707 -222.864429) (xy 385.826664 -222.878535)
			(xy 385.877993 -222.900347) (xy 385.925599 -222.929401) (xy 385.968467 -222.965076) (xy 386.005684 -223.006613)
			(xy 386.036457 -223.053126) (xy 386.060129 -223.103623) (xy 386.076197 -223.15703) (xy 386.084317 -223.212206)
			(xy 386.084826 -223.240092) (xy 386.084317 -223.267978) (xy 386.076197 -223.323154) (xy 386.060129 -223.376561)
			(xy 386.036457 -223.427058) (xy 386.005684 -223.473571) (xy 385.968467 -223.515108) (xy 385.925599 -223.550783)
			(xy 385.877993 -223.579837) (xy 385.826664 -223.601649) (xy 385.772707 -223.615755) (xy 385.71727 -223.621855)
			(xy 385.661536 -223.619818) (xy 385.606693 -223.609688) (xy 385.553909 -223.591681) (xy 385.504309 -223.56618)
			(xy 385.458951 -223.533729) (xy 385.418802 -223.49502) (xy 385.384716 -223.450877) (xy 385.35742 -223.402242)
			(xy 385.337497 -223.350151) (xy 385.325371 -223.295714) (xy 385.3213 -223.240092) (xy 378.341148 -223.240092)
			(xy 378.322377 -223.281192) (xy 378.292905 -223.327047) (xy 378.257206 -223.36824) (xy 378.216009 -223.403933)
			(xy 378.17015 -223.4334) (xy 378.120565 -223.456039) (xy 378.068262 -223.471391) (xy 378.014307 -223.479142)
			(xy 377.987052 -223.479614) (xy 377.972068 -223.479497) (xy 377.942188 -223.477211) (xy 377.927362 -223.475042)
			(xy 377.92533 -223.474788) (xy 377.911181 -223.473797) (xy 377.883267 -223.478754) (xy 377.857793 -223.491199)
			(xy 377.836725 -223.510171) (xy 377.821688 -223.534207) (xy 377.813843 -223.561451) (xy 377.813316 -223.575626)
			(xy 377.813316 -223.89084) (xy 418.05809 -223.89084) (xy 418.062161 -223.835218) (xy 418.074287 -223.780781)
			(xy 418.09421 -223.72869) (xy 418.121506 -223.680055) (xy 418.155592 -223.635912) (xy 418.195741 -223.597203)
			(xy 418.241099 -223.564752) (xy 418.290699 -223.539251) (xy 418.343483 -223.521244) (xy 418.398326 -223.511114)
			(xy 418.45406 -223.509077) (xy 418.509497 -223.515177) (xy 418.563454 -223.529283) (xy 418.614783 -223.551095)
			(xy 418.662389 -223.580149) (xy 418.705257 -223.615824) (xy 418.742474 -223.657361) (xy 418.773247 -223.703874)
			(xy 418.796919 -223.754371) (xy 418.812987 -223.807778) (xy 418.821107 -223.862954) (xy 418.821616 -223.89084)
			(xy 418.821107 -223.918726) (xy 418.812987 -223.973902) (xy 418.796919 -224.027309) (xy 418.773247 -224.077806)
			(xy 418.742474 -224.124319) (xy 418.705257 -224.165856) (xy 418.662389 -224.201531) (xy 418.614783 -224.230585)
			(xy 418.563454 -224.252397) (xy 418.509497 -224.266503) (xy 418.45406 -224.272603) (xy 418.398326 -224.270566)
			(xy 418.343483 -224.260436) (xy 418.290699 -224.242429) (xy 418.241099 -224.216928) (xy 418.195741 -224.184477)
			(xy 418.155592 -224.145768) (xy 418.121506 -224.101625) (xy 418.09421 -224.05299) (xy 418.074287 -224.000899)
			(xy 418.062161 -223.946462) (xy 418.05809 -223.89084) (xy 377.813316 -223.89084) (xy 377.813316 -225.237294)
			(xy 414.952686 -225.237294) (xy 414.956757 -225.181672) (xy 414.968883 -225.127235) (xy 414.988806 -225.075144)
			(xy 415.016102 -225.026509) (xy 415.050188 -224.982366) (xy 415.090337 -224.943657) (xy 415.135695 -224.911206)
			(xy 415.185295 -224.885705) (xy 415.238079 -224.867698) (xy 415.292922 -224.857568) (xy 415.348656 -224.855531)
			(xy 415.404093 -224.861631) (xy 415.45805 -224.875737) (xy 415.509379 -224.897549) (xy 415.556985 -224.926603)
			(xy 415.599853 -224.962278) (xy 415.63707 -225.003815) (xy 415.667843 -225.050328) (xy 415.691515 -225.100825)
			(xy 415.707583 -225.154232) (xy 415.715703 -225.209408) (xy 415.716212 -225.237294) (xy 415.716189 -225.238564)
			(xy 418.305232 -225.238564) (xy 418.309303 -225.182942) (xy 418.321429 -225.128505) (xy 418.341352 -225.076414)
			(xy 418.368648 -225.027779) (xy 418.402734 -224.983636) (xy 418.442883 -224.944927) (xy 418.488241 -224.912476)
			(xy 418.537841 -224.886975) (xy 418.590625 -224.868968) (xy 418.645468 -224.858838) (xy 418.701202 -224.856801)
			(xy 418.756639 -224.862901) (xy 418.810596 -224.877007) (xy 418.861925 -224.898819) (xy 418.909531 -224.927873)
			(xy 418.952399 -224.963548) (xy 418.989616 -225.005085) (xy 419.020389 -225.051598) (xy 419.044061 -225.102095)
			(xy 419.060129 -225.155502) (xy 419.068249 -225.210678) (xy 419.068758 -225.238564) (xy 419.068249 -225.26645)
			(xy 419.060129 -225.321626) (xy 419.044061 -225.375033) (xy 419.020389 -225.42553) (xy 418.989616 -225.472043)
			(xy 418.952399 -225.51358) (xy 418.909531 -225.549255) (xy 418.861925 -225.578309) (xy 418.810596 -225.600121)
			(xy 418.756639 -225.614227) (xy 418.701202 -225.620327) (xy 418.645468 -225.61829) (xy 418.590625 -225.60816)
			(xy 418.537841 -225.590153) (xy 418.488241 -225.564652) (xy 418.442883 -225.532201) (xy 418.402734 -225.493492)
			(xy 418.368648 -225.449349) (xy 418.341352 -225.400714) (xy 418.321429 -225.348623) (xy 418.309303 -225.294186)
			(xy 418.305232 -225.238564) (xy 415.716189 -225.238564) (xy 415.715703 -225.26518) (xy 415.707583 -225.320356)
			(xy 415.691515 -225.373763) (xy 415.667843 -225.42426) (xy 415.63707 -225.470773) (xy 415.599853 -225.51231)
			(xy 415.556985 -225.547985) (xy 415.509379 -225.577039) (xy 415.45805 -225.598851) (xy 415.404093 -225.612957)
			(xy 415.348656 -225.619057) (xy 415.292922 -225.61702) (xy 415.238079 -225.60689) (xy 415.185295 -225.588883)
			(xy 415.135695 -225.563382) (xy 415.090337 -225.530931) (xy 415.050188 -225.492222) (xy 415.016102 -225.448079)
			(xy 414.988806 -225.399444) (xy 414.968883 -225.347353) (xy 414.956757 -225.292916) (xy 414.952686 -225.237294)
			(xy 377.813316 -225.237294) (xy 377.813316 -227.397056) (xy 379.336298 -227.397056) (xy 379.340369 -227.341434)
			(xy 379.352495 -227.286997) (xy 379.372418 -227.234906) (xy 379.399714 -227.186271) (xy 379.4338 -227.142128)
			(xy 379.473949 -227.103419) (xy 379.519307 -227.070968) (xy 379.568907 -227.045467) (xy 379.621691 -227.02746)
			(xy 379.676534 -227.01733) (xy 379.732268 -227.015293) (xy 379.787705 -227.021393) (xy 379.841662 -227.035499)
			(xy 379.892991 -227.057311) (xy 379.940597 -227.086365) (xy 379.983465 -227.12204) (xy 380.020682 -227.163577)
			(xy 380.051455 -227.21009) (xy 380.075127 -227.260587) (xy 380.091195 -227.313994) (xy 380.099315 -227.36917)
			(xy 380.099824 -227.397056) (xy 380.099315 -227.424942) (xy 380.091195 -227.480118) (xy 380.075127 -227.533525)
			(xy 380.051455 -227.584022) (xy 380.020682 -227.630535) (xy 379.983465 -227.672072) (xy 379.940597 -227.707747)
			(xy 379.892991 -227.736801) (xy 379.841662 -227.758613) (xy 379.787705 -227.772719) (xy 379.732268 -227.778819)
			(xy 379.676534 -227.776782) (xy 379.621691 -227.766652) (xy 379.568907 -227.748645) (xy 379.519307 -227.723144)
			(xy 379.473949 -227.690693) (xy 379.4338 -227.651984) (xy 379.399714 -227.607841) (xy 379.372418 -227.559206)
			(xy 379.352495 -227.507115) (xy 379.340369 -227.452678) (xy 379.336298 -227.397056) (xy 377.813316 -227.397056)
			(xy 377.813316 -228.467666) (xy 381.166114 -228.467666) (xy 381.170185 -228.412044) (xy 381.182311 -228.357607)
			(xy 381.202234 -228.305516) (xy 381.22953 -228.256881) (xy 381.263616 -228.212738) (xy 381.303765 -228.174029)
			(xy 381.349123 -228.141578) (xy 381.398723 -228.116077) (xy 381.451507 -228.09807) (xy 381.50635 -228.08794)
			(xy 381.562084 -228.085903) (xy 381.617521 -228.092003) (xy 381.671478 -228.106109) (xy 381.722807 -228.127921)
			(xy 381.770413 -228.156975) (xy 381.813281 -228.19265) (xy 381.850498 -228.234187) (xy 381.881271 -228.2807)
			(xy 381.904943 -228.331197) (xy 381.921011 -228.384604) (xy 381.929131 -228.43978) (xy 381.92964 -228.467666)
			(xy 381.929131 -228.495552) (xy 381.921011 -228.550728) (xy 381.904943 -228.604135) (xy 381.881271 -228.654632)
			(xy 381.850498 -228.701145) (xy 381.813281 -228.742682) (xy 381.770413 -228.778357) (xy 381.722807 -228.807411)
			(xy 381.671478 -228.829223) (xy 381.617521 -228.843329) (xy 381.562084 -228.849429) (xy 381.50635 -228.847392)
			(xy 381.451507 -228.837262) (xy 381.398723 -228.819255) (xy 381.349123 -228.793754) (xy 381.303765 -228.761303)
			(xy 381.263616 -228.722594) (xy 381.22953 -228.678451) (xy 381.202234 -228.629816) (xy 381.182311 -228.577725)
			(xy 381.170185 -228.523288) (xy 381.166114 -228.467666) (xy 377.813316 -228.467666) (xy 377.813316 -228.862636)
			(xy 386.430266 -228.862636) (xy 386.430729 -228.836217) (xy 386.43801 -228.783882) (xy 386.45245 -228.733056)
			(xy 386.473773 -228.684711) (xy 386.50157 -228.639775) (xy 386.535308 -228.59911) (xy 386.57434 -228.563496)
			(xy 386.595874 -228.548184) (xy 386.606928 -228.540017) (xy 386.6246 -228.518983) (xy 386.636016 -228.493996)
			(xy 386.640347 -228.466868) (xy 386.63728 -228.439568) (xy 386.627037 -228.414077) (xy 386.61036 -228.392246)
			(xy 386.599684 -228.383592) (xy 386.576676 -228.365401) (xy 386.535941 -228.323205) (xy 386.502137 -228.275277)
			(xy 386.476061 -228.222742) (xy 386.458325 -228.166838) (xy 386.449348 -228.108879) (xy 386.448808 -228.079554)
			(xy 386.449294 -228.052303) (xy 386.45705 -227.998355) (xy 386.472405 -227.94606) (xy 386.495047 -227.896483)
			(xy 386.524513 -227.850633) (xy 386.560204 -227.809442) (xy 386.601395 -227.773751) (xy 386.647245 -227.744285)
			(xy 386.696822 -227.721643) (xy 386.749117 -227.706288) (xy 386.803065 -227.698532) (xy 386.857567 -227.698532)
			(xy 386.911515 -227.706288) (xy 386.96381 -227.721643) (xy 387.013387 -227.744285) (xy 387.059237 -227.773751)
			(xy 387.100428 -227.809442) (xy 387.136119 -227.850633) (xy 387.165585 -227.896483) (xy 387.188227 -227.94606)
			(xy 387.203582 -227.998355) (xy 387.211338 -228.052303) (xy 387.211824 -228.079554) (xy 387.211358 -228.105973)
			(xy 387.204078 -228.158308) (xy 387.189639 -228.209135) (xy 387.168317 -228.257479) (xy 387.14052 -228.302415)
			(xy 387.106782 -228.34308) (xy 387.06775 -228.378694) (xy 387.046216 -228.394006) (xy 387.035172 -228.402186)
			(xy 387.017502 -228.423217) (xy 387.006087 -228.448201) (xy 387.001755 -228.475326) (xy 387.00482 -228.502624)
			(xy 387.01506 -228.528113) (xy 387.031732 -228.549943) (xy 387.042406 -228.558598) (xy 387.065455 -228.57674)
			(xy 387.106188 -228.618945) (xy 387.139987 -228.666884) (xy 387.140465 -228.667848) (xy 442.823618 -228.667848)
			(xy 442.823618 -228.613352) (xy 442.831374 -228.55941) (xy 442.846727 -228.50712) (xy 442.869366 -228.457548)
			(xy 442.898829 -228.411703) (xy 442.934517 -228.370517) (xy 442.975703 -228.334829) (xy 443.021548 -228.305366)
			(xy 443.07112 -228.282727) (xy 443.12341 -228.267374) (xy 443.177352 -228.259618) (xy 443.2046 -228.259132)
			(xy 443.233517 -228.259638) (xy 443.29069 -228.268368) (xy 443.345889 -228.285628) (xy 443.397851 -228.311022)
			(xy 443.445385 -228.343968) (xy 443.487401 -228.383711) (xy 443.50559 -228.406198) (xy 443.513161 -228.414951)
			(xy 443.533913 -228.425139) (xy 443.545468 -228.425756) (xy 443.625732 -228.425756) (xy 443.637297 -228.425162)
			(xy 443.658069 -228.414985) (xy 443.66561 -228.406198) (xy 443.683795 -228.383709) (xy 443.725816 -228.343975)
			(xy 443.773352 -228.311036) (xy 443.825315 -228.285649) (xy 443.880513 -228.268394) (xy 443.937684 -228.259666)
			(xy 443.9666 -228.259132) (xy 443.993854 -228.259538) (xy 444.047807 -228.267295) (xy 444.100108 -228.282652)
			(xy 444.14969 -228.305295) (xy 444.195545 -228.334765) (xy 444.23674 -228.37046) (xy 444.272435 -228.411655)
			(xy 444.301905 -228.45751) (xy 444.324548 -228.507092) (xy 444.339905 -228.559393) (xy 444.347662 -228.613346)
			(xy 444.347662 -228.667854) (xy 444.339905 -228.721807) (xy 444.324548 -228.774108) (xy 444.301905 -228.82369)
			(xy 444.272435 -228.869545) (xy 444.23674 -228.91074) (xy 444.195545 -228.946435) (xy 444.14969 -228.975905)
			(xy 444.100108 -228.998548) (xy 444.047807 -229.013905) (xy 443.993854 -229.021662) (xy 443.9666 -229.022148)
			(xy 443.937682 -229.021649) (xy 443.880509 -229.012919) (xy 443.825309 -228.995658) (xy 443.773347 -228.970263)
			(xy 443.725814 -228.937315) (xy 443.683799 -228.89757) (xy 443.66561 -228.875082) (xy 443.658043 -228.866326)
			(xy 443.637288 -228.85614) (xy 443.625732 -228.855524) (xy 443.545468 -228.855524) (xy 443.533904 -228.856125)
			(xy 443.513132 -228.866297) (xy 443.50559 -228.875082) (xy 443.4874 -228.897567) (xy 443.445381 -228.937302)
			(xy 443.397846 -228.970242) (xy 443.345884 -228.99563) (xy 443.290686 -229.012886) (xy 443.233516 -229.021614)
			(xy 443.2046 -229.022148) (xy 443.177352 -229.021582) (xy 443.12341 -229.013826) (xy 443.07112 -228.998473)
			(xy 443.021548 -228.975834) (xy 442.975703 -228.946371) (xy 442.934517 -228.910683) (xy 442.898829 -228.869497)
			(xy 442.869366 -228.823652) (xy 442.846727 -228.77408) (xy 442.831374 -228.72179) (xy 442.823618 -228.667848)
			(xy 387.140465 -228.667848) (xy 387.166057 -228.719428) (xy 387.183783 -228.775342) (xy 387.192749 -228.833308)
			(xy 387.193282 -228.862636) (xy 387.192796 -228.889887) (xy 387.18504 -228.943835) (xy 387.169685 -228.99613)
			(xy 387.147043 -229.045707) (xy 387.117577 -229.091557) (xy 387.081886 -229.132748) (xy 387.040695 -229.168439)
			(xy 386.994845 -229.197905) (xy 386.945268 -229.220547) (xy 386.892973 -229.235902) (xy 386.839025 -229.243658)
			(xy 386.784523 -229.243658) (xy 386.730575 -229.235902) (xy 386.67828 -229.220547) (xy 386.628703 -229.197905)
			(xy 386.582853 -229.168439) (xy 386.541662 -229.132748) (xy 386.505971 -229.091557) (xy 386.476505 -229.045707)
			(xy 386.453863 -228.99613) (xy 386.438508 -228.943835) (xy 386.430752 -228.889887) (xy 386.430266 -228.862636)
			(xy 377.813316 -228.862636) (xy 377.813316 -229.37724) (xy 392.719558 -229.37724) (xy 392.723629 -229.321618)
			(xy 392.735755 -229.267181) (xy 392.755678 -229.21509) (xy 392.782974 -229.166455) (xy 392.81706 -229.122312)
			(xy 392.857209 -229.083603) (xy 392.902567 -229.051152) (xy 392.952167 -229.025651) (xy 393.004951 -229.007644)
			(xy 393.059794 -228.997514) (xy 393.115528 -228.995477) (xy 393.170965 -229.001577) (xy 393.224922 -229.015683)
			(xy 393.276251 -229.037495) (xy 393.323857 -229.066549) (xy 393.366725 -229.102224) (xy 393.403942 -229.143761)
			(xy 393.434715 -229.190274) (xy 393.458387 -229.240771) (xy 393.474455 -229.294178) (xy 393.482575 -229.349354)
			(xy 393.483084 -229.37724) (xy 393.482575 -229.405126) (xy 393.474455 -229.460302) (xy 393.458387 -229.513709)
			(xy 393.434715 -229.564206) (xy 393.403942 -229.610719) (xy 393.366725 -229.652256) (xy 393.323857 -229.687931)
			(xy 393.276251 -229.716985) (xy 393.224922 -229.738797) (xy 393.170965 -229.752903) (xy 393.115528 -229.759003)
			(xy 393.059794 -229.756966) (xy 393.004951 -229.746836) (xy 392.952167 -229.728829) (xy 392.902567 -229.703328)
			(xy 392.857209 -229.670877) (xy 392.81706 -229.632168) (xy 392.782974 -229.588025) (xy 392.755678 -229.53939)
			(xy 392.735755 -229.487299) (xy 392.723629 -229.432862) (xy 392.719558 -229.37724) (xy 377.813316 -229.37724)
			(xy 377.813316 -231.07396) (xy 381.686814 -231.07396) (xy 381.690885 -231.018338) (xy 381.703011 -230.963901)
			(xy 381.722934 -230.91181) (xy 381.75023 -230.863175) (xy 381.784316 -230.819032) (xy 381.824465 -230.780323)
			(xy 381.869823 -230.747872) (xy 381.919423 -230.722371) (xy 381.972207 -230.704364) (xy 382.02705 -230.694234)
			(xy 382.082784 -230.692197) (xy 382.138221 -230.698297) (xy 382.192178 -230.712403) (xy 382.243507 -230.734215)
			(xy 382.291113 -230.763269) (xy 382.333981 -230.798944) (xy 382.371198 -230.840481) (xy 382.401971 -230.886994)
			(xy 382.40975 -230.903589) (xy 383.216061 -230.903589) (xy 383.216061 -230.843611) (xy 383.22389 -230.784147)
			(xy 383.239413 -230.726213) (xy 383.262366 -230.670801) (xy 383.292355 -230.618858) (xy 383.328867 -230.571275)
			(xy 383.371278 -230.528865) (xy 383.418862 -230.492353) (xy 383.470804 -230.462364) (xy 383.526216 -230.439412)
			(xy 383.584151 -230.423889) (xy 383.643615 -230.416061) (xy 383.673604 -230.415592) (xy 384.537204 -230.415592)
			(xy 384.567185 -230.416174) (xy 384.626634 -230.424001) (xy 384.684553 -230.439521) (xy 384.739951 -230.462468)
			(xy 384.79188 -230.492449) (xy 384.839451 -230.528952) (xy 384.88185 -230.571352) (xy 384.918353 -230.618924)
			(xy 384.948334 -230.670853) (xy 384.97128 -230.726251) (xy 384.986799 -230.78417) (xy 384.994626 -230.843619)
			(xy 384.994626 -230.903581) (xy 384.986799 -230.96303) (xy 384.97128 -231.020949) (xy 384.96847 -231.027732)
			(xy 386.97357 -231.027732) (xy 386.977641 -230.97211) (xy 386.989767 -230.917673) (xy 387.00969 -230.865582)
			(xy 387.036986 -230.816947) (xy 387.071072 -230.772804) (xy 387.111221 -230.734095) (xy 387.156579 -230.701644)
			(xy 387.206179 -230.676143) (xy 387.258963 -230.658136) (xy 387.313806 -230.648006) (xy 387.36954 -230.645969)
			(xy 387.424977 -230.652069) (xy 387.478934 -230.666175) (xy 387.530263 -230.687987) (xy 387.577869 -230.717041)
			(xy 387.620737 -230.752716) (xy 387.657954 -230.794253) (xy 387.688727 -230.840766) (xy 387.712399 -230.891263)
			(xy 387.728467 -230.94467) (xy 387.736587 -230.999846) (xy 387.737096 -231.027732) (xy 387.736587 -231.055618)
			(xy 387.728467 -231.110794) (xy 387.712399 -231.164201) (xy 387.688727 -231.214698) (xy 387.657954 -231.261211)
			(xy 387.620737 -231.302748) (xy 387.585253 -231.332278) (xy 392.830302 -231.332278) (xy 392.834373 -231.276656)
			(xy 392.846499 -231.222219) (xy 392.866422 -231.170128) (xy 392.893718 -231.121493) (xy 392.927804 -231.07735)
			(xy 392.967953 -231.038641) (xy 393.013311 -231.00619) (xy 393.062911 -230.980689) (xy 393.115695 -230.962682)
			(xy 393.170538 -230.952552) (xy 393.226272 -230.950515) (xy 393.247056 -230.952802) (xy 417.376354 -230.952802)
			(xy 417.380425 -230.89718) (xy 417.392551 -230.842743) (xy 417.412474 -230.790652) (xy 417.43977 -230.742017)
			(xy 417.473856 -230.697874) (xy 417.514005 -230.659165) (xy 417.559363 -230.626714) (xy 417.608963 -230.601213)
			(xy 417.661747 -230.583206) (xy 417.71659 -230.573076) (xy 417.772324 -230.571039) (xy 417.827761 -230.577139)
			(xy 417.881718 -230.591245) (xy 417.933047 -230.613057) (xy 417.980653 -230.642111) (xy 418.023521 -230.677786)
			(xy 418.060738 -230.719323) (xy 418.091511 -230.765836) (xy 418.115183 -230.816333) (xy 418.131251 -230.86974)
			(xy 418.139371 -230.924916) (xy 418.13988 -230.952802) (xy 418.139371 -230.980688) (xy 418.131251 -231.035864)
			(xy 418.115183 -231.089271) (xy 418.091511 -231.139768) (xy 418.060738 -231.186281) (xy 418.023521 -231.227818)
			(xy 417.980653 -231.263493) (xy 417.933047 -231.292547) (xy 417.881718 -231.314359) (xy 417.827761 -231.328465)
			(xy 417.772324 -231.334565) (xy 417.71659 -231.332528) (xy 417.661747 -231.322398) (xy 417.608963 -231.304391)
			(xy 417.559363 -231.27889) (xy 417.514005 -231.246439) (xy 417.473856 -231.20773) (xy 417.43977 -231.163587)
			(xy 417.412474 -231.114952) (xy 417.392551 -231.062861) (xy 417.380425 -231.008424) (xy 417.376354 -230.952802)
			(xy 393.247056 -230.952802) (xy 393.281709 -230.956615) (xy 393.335666 -230.970721) (xy 393.386995 -230.992533)
			(xy 393.434601 -231.021587) (xy 393.477469 -231.057262) (xy 393.514686 -231.098799) (xy 393.545459 -231.145312)
			(xy 393.569131 -231.195809) (xy 393.585199 -231.249216) (xy 393.593319 -231.304392) (xy 393.593828 -231.332278)
			(xy 393.593319 -231.360164) (xy 393.585199 -231.41534) (xy 393.569131 -231.468747) (xy 393.545459 -231.519244)
			(xy 393.514686 -231.565757) (xy 393.477469 -231.607294) (xy 393.434601 -231.642969) (xy 393.386995 -231.672023)
			(xy 393.335666 -231.693835) (xy 393.281709 -231.707941) (xy 393.226272 -231.714041) (xy 393.170538 -231.712004)
			(xy 393.115695 -231.701874) (xy 393.062911 -231.683867) (xy 393.013311 -231.658366) (xy 392.967953 -231.625915)
			(xy 392.927804 -231.587206) (xy 392.893718 -231.543063) (xy 392.866422 -231.494428) (xy 392.846499 -231.442337)
			(xy 392.834373 -231.3879) (xy 392.830302 -231.332278) (xy 387.585253 -231.332278) (xy 387.577869 -231.338423)
			(xy 387.530263 -231.367477) (xy 387.478934 -231.389289) (xy 387.424977 -231.403395) (xy 387.36954 -231.409495)
			(xy 387.313806 -231.407458) (xy 387.258963 -231.397328) (xy 387.206179 -231.379321) (xy 387.156579 -231.35382)
			(xy 387.111221 -231.321369) (xy 387.071072 -231.28266) (xy 387.036986 -231.238517) (xy 387.00969 -231.189882)
			(xy 386.989767 -231.137791) (xy 386.977641 -231.083354) (xy 386.97357 -231.027732) (xy 384.96847 -231.027732)
			(xy 384.948334 -231.076347) (xy 384.918353 -231.128276) (xy 384.88185 -231.175848) (xy 384.839451 -231.218248)
			(xy 384.79188 -231.254751) (xy 384.739951 -231.284732) (xy 384.684553 -231.307679) (xy 384.626634 -231.323199)
			(xy 384.567185 -231.331026) (xy 384.537204 -231.331516) (xy 383.673604 -231.331516) (xy 383.643615 -231.331139)
			(xy 383.584151 -231.323311) (xy 383.526216 -231.307788) (xy 383.470804 -231.284836) (xy 383.418862 -231.254847)
			(xy 383.371278 -231.218335) (xy 383.328867 -231.175925) (xy 383.292355 -231.128342) (xy 383.262366 -231.076399)
			(xy 383.239413 -231.020987) (xy 383.22389 -230.963053) (xy 383.216061 -230.903589) (xy 382.40975 -230.903589)
			(xy 382.425643 -230.937491) (xy 382.441711 -230.990898) (xy 382.449831 -231.046074) (xy 382.45034 -231.07396)
			(xy 382.449831 -231.101846) (xy 382.441711 -231.157022) (xy 382.425643 -231.210429) (xy 382.401971 -231.260926)
			(xy 382.371198 -231.307439) (xy 382.333981 -231.348976) (xy 382.291113 -231.384651) (xy 382.243507 -231.413705)
			(xy 382.192178 -231.435517) (xy 382.138221 -231.449623) (xy 382.082784 -231.455723) (xy 382.02705 -231.453686)
			(xy 381.972207 -231.443556) (xy 381.919423 -231.425549) (xy 381.869823 -231.400048) (xy 381.824465 -231.367597)
			(xy 381.784316 -231.328888) (xy 381.75023 -231.284745) (xy 381.722934 -231.23611) (xy 381.703011 -231.184019)
			(xy 381.690885 -231.129582) (xy 381.686814 -231.07396) (xy 377.813316 -231.07396) (xy 377.813316 -232.370376)
			(xy 377.81288 -232.38044) (xy 377.805148 -232.399026) (xy 377.79833 -232.406444) (xy 377.619768 -232.585006)
			(xy 392.937998 -232.585006) (xy 392.942069 -232.529384) (xy 392.954195 -232.474947) (xy 392.974118 -232.422856)
			(xy 393.001414 -232.374221) (xy 393.0355 -232.330078) (xy 393.075649 -232.291369) (xy 393.121007 -232.258918)
			(xy 393.170607 -232.233417) (xy 393.223391 -232.21541) (xy 393.278234 -232.20528) (xy 393.333968 -232.203243)
			(xy 393.389405 -232.209343) (xy 393.443362 -232.223449) (xy 393.494691 -232.245261) (xy 393.542297 -232.274315)
			(xy 393.585165 -232.30999) (xy 393.622382 -232.351527) (xy 393.653155 -232.39804) (xy 393.676827 -232.448537)
			(xy 393.692895 -232.501944) (xy 393.701015 -232.55712) (xy 393.701524 -232.585006) (xy 393.701015 -232.612892)
			(xy 393.692895 -232.668068) (xy 393.676827 -232.721475) (xy 393.653155 -232.771972) (xy 393.622382 -232.818485)
			(xy 393.585165 -232.860022) (xy 393.542297 -232.895697) (xy 393.494691 -232.924751) (xy 393.443362 -232.946563)
			(xy 393.389405 -232.960669) (xy 393.333968 -232.966769) (xy 393.278234 -232.964732) (xy 393.223391 -232.954602)
			(xy 393.170607 -232.936595) (xy 393.121007 -232.911094) (xy 393.075649 -232.878643) (xy 393.0355 -232.839934)
			(xy 393.001414 -232.795791) (xy 392.974118 -232.747156) (xy 392.954195 -232.695065) (xy 392.942069 -232.640628)
			(xy 392.937998 -232.585006) (xy 377.619768 -232.585006) (xy 377.364244 -232.84053) (xy 377.360726 -232.844263)
			(xy 377.355103 -232.852839) (xy 377.353068 -232.857548) (xy 377.349512 -232.866184) (xy 377.349512 -233.492802)
			(xy 414.907982 -233.492802) (xy 414.912053 -233.43718) (xy 414.924179 -233.382743) (xy 414.944102 -233.330652)
			(xy 414.971398 -233.282017) (xy 415.005484 -233.237874) (xy 415.045633 -233.199165) (xy 415.090991 -233.166714)
			(xy 415.140591 -233.141213) (xy 415.193375 -233.123206) (xy 415.248218 -233.113076) (xy 415.303952 -233.111039)
			(xy 415.359389 -233.117139) (xy 415.413346 -233.131245) (xy 415.464675 -233.153057) (xy 415.512281 -233.182111)
			(xy 415.555149 -233.217786) (xy 415.592366 -233.259323) (xy 415.623139 -233.305836) (xy 415.646811 -233.356333)
			(xy 415.662879 -233.40974) (xy 415.670999 -233.464916) (xy 415.671508 -233.492802) (xy 415.671485 -233.494072)
			(xy 418.149024 -233.494072) (xy 418.149621 -233.464003) (xy 418.159087 -233.404613) (xy 418.177719 -233.347432)
			(xy 418.20506 -233.293866) (xy 418.240436 -233.245232) (xy 418.261292 -233.223562) (xy 420.269924 -231.21493)
			(xy 420.291606 -231.194103) (xy 420.340252 -231.158778) (xy 420.393821 -231.131493) (xy 420.450998 -231.112918)
			(xy 420.510375 -231.103509) (xy 420.540434 -231.102916) (xy 441.742576 -231.102916) (xy 441.772641 -231.103449)
			(xy 441.832031 -231.112842) (xy 441.889219 -231.131417) (xy 441.942794 -231.158715) (xy 441.991436 -231.194063)
			(xy 442.013086 -231.21493) (xy 443.677548 -232.879392) (xy 443.685016 -232.886102) (xy 443.703586 -232.893681)
			(xy 443.713616 -232.894124) (xy 444.313818 -232.894124) (xy 444.341159 -232.894609) (xy 444.395285 -232.902393)
			(xy 444.447752 -232.917801) (xy 444.497492 -232.940519) (xy 444.543493 -232.970084) (xy 444.584818 -233.005894)
			(xy 444.620627 -233.047221) (xy 444.65019 -233.093224) (xy 444.672905 -233.142965) (xy 444.688311 -233.195433)
			(xy 444.696093 -233.249559) (xy 444.696093 -233.304241) (xy 444.688311 -233.358367) (xy 444.672905 -233.410835)
			(xy 444.65019 -233.460576) (xy 444.620627 -233.506579) (xy 444.584818 -233.547906) (xy 444.543493 -233.583716)
			(xy 444.497492 -233.613281) (xy 444.447752 -233.635999) (xy 444.395285 -233.651407) (xy 444.341159 -233.659191)
			(xy 444.313818 -233.65968) (xy 443.534038 -233.65968) (xy 443.50397 -233.659041) (xy 443.444582 -233.649585)
			(xy 443.387402 -233.630963) (xy 443.333835 -233.603632) (xy 443.285199 -233.568264) (xy 443.263528 -233.547412)
			(xy 442.947298 -233.231182) (xy 442.940965 -233.225324) (xy 442.925409 -233.217891) (xy 442.908266 -233.216062)
			(xy 442.8998 -233.21772) (xy 442.803026 -233.240326) (xy 442.783468 -233.257852) (xy 442.779404 -233.270298)
			(xy 442.770474 -233.295151) (xy 442.746654 -233.342285) (xy 442.716582 -233.385698) (xy 442.68083 -233.424568)
			(xy 442.640075 -233.458155) (xy 442.595092 -233.485823) (xy 442.546733 -233.507047) (xy 442.495916 -233.521424)
			(xy 442.443606 -233.528681) (xy 442.4172 -233.529124) (xy 442.387135 -233.528595) (xy 442.327745 -233.519199)
			(xy 442.270558 -233.500623) (xy 442.216983 -233.473324) (xy 442.168341 -233.437977) (xy 442.14669 -233.41711)
			(xy 441.142374 -232.412794) (xy 441.134978 -232.405949) (xy 441.116376 -232.398233) (xy 441.106306 -232.397808)
			(xy 422.497758 -232.397808) (xy 422.487686 -232.398209) (xy 422.469088 -232.405947) (xy 422.46169 -232.412794)
			(xy 419.42258 -235.451904) (xy 419.400943 -235.472799) (xy 419.352311 -235.508191) (xy 419.298738 -235.535536)
			(xy 419.241546 -235.554158) (xy 419.182144 -235.563598) (xy 419.15207 -235.564172) (xy 419.124727 -235.563718)
			(xy 419.070598 -235.555932) (xy 419.018128 -235.540521) (xy 418.968386 -235.517801) (xy 418.922382 -235.488233)
			(xy 418.881055 -235.452419) (xy 418.845245 -235.411089) (xy 418.815682 -235.365083) (xy 418.792966 -235.315338)
			(xy 418.777561 -235.262867) (xy 418.769779 -235.208737) (xy 418.769292 -235.181394) (xy 418.769912 -235.151326)
			(xy 418.779374 -235.091937) (xy 418.798001 -235.034757) (xy 418.825336 -234.981191) (xy 418.860707 -234.932555)
			(xy 418.88156 -234.910884) (xy 421.848534 -231.943656) (xy 421.85463 -231.913938) (xy 421.848534 -231.89946)
			(xy 421.844306 -231.89034) (xy 421.830132 -231.876108) (xy 421.811586 -231.868395) (xy 421.801544 -231.867964)
			(xy 420.720012 -231.867964) (xy 420.709941 -231.868379) (xy 420.691343 -231.876105) (xy 420.683944 -231.88295)
			(xy 418.802312 -233.764582) (xy 418.78066 -233.785442) (xy 418.732006 -233.820762) (xy 418.678429 -233.848041)
			(xy 418.621246 -233.866608) (xy 418.561863 -233.876008) (xy 418.531802 -233.876596) (xy 418.504472 -233.87609)
			(xy 418.450369 -233.868315) (xy 418.397922 -233.852922) (xy 418.348198 -233.830226) (xy 418.302208 -233.800687)
			(xy 418.260888 -233.764906) (xy 418.225077 -233.723612) (xy 418.195506 -233.677643) (xy 418.172774 -233.627935)
			(xy 418.157344 -233.575499) (xy 418.14953 -233.521401) (xy 418.149024 -233.494072) (xy 415.671485 -233.494072)
			(xy 415.670999 -233.520688) (xy 415.662879 -233.575864) (xy 415.646811 -233.629271) (xy 415.623139 -233.679768)
			(xy 415.592366 -233.726281) (xy 415.555149 -233.767818) (xy 415.512281 -233.803493) (xy 415.464675 -233.832547)
			(xy 415.413346 -233.854359) (xy 415.359389 -233.868465) (xy 415.303952 -233.874565) (xy 415.248218 -233.872528)
			(xy 415.193375 -233.862398) (xy 415.140591 -233.844391) (xy 415.090991 -233.81889) (xy 415.045633 -233.786439)
			(xy 415.005484 -233.74773) (xy 414.971398 -233.703587) (xy 414.944102 -233.654952) (xy 414.924179 -233.602861)
			(xy 414.912053 -233.548424) (xy 414.907982 -233.492802) (xy 377.349512 -233.492802) (xy 377.349512 -233.99496)
			(xy 381.97358 -233.99496) (xy 381.977651 -233.939338) (xy 381.989777 -233.884901) (xy 382.0097 -233.83281)
			(xy 382.036996 -233.784175) (xy 382.071082 -233.740032) (xy 382.111231 -233.701323) (xy 382.156589 -233.668872)
			(xy 382.206189 -233.643371) (xy 382.258973 -233.625364) (xy 382.313816 -233.615234) (xy 382.36955 -233.613197)
			(xy 382.424987 -233.619297) (xy 382.478944 -233.633403) (xy 382.530273 -233.655215) (xy 382.577879 -233.684269)
			(xy 382.620747 -233.719944) (xy 382.657964 -233.761481) (xy 382.688737 -233.807994) (xy 382.712409 -233.858491)
			(xy 382.728477 -233.911898) (xy 382.736597 -233.967074) (xy 382.737041 -233.991404) (xy 382.973578 -233.991404)
			(xy 382.977649 -233.935782) (xy 382.989775 -233.881345) (xy 383.009698 -233.829254) (xy 383.036994 -233.780619)
			(xy 383.07108 -233.736476) (xy 383.111229 -233.697767) (xy 383.156587 -233.665316) (xy 383.206187 -233.639815)
			(xy 383.258971 -233.621808) (xy 383.313814 -233.611678) (xy 383.369548 -233.609641) (xy 383.424985 -233.615741)
			(xy 383.478942 -233.629847) (xy 383.530271 -233.651659) (xy 383.577877 -233.680713) (xy 383.620745 -233.716388)
			(xy 383.657962 -233.757925) (xy 383.688735 -233.804438) (xy 383.712407 -233.854935) (xy 383.728475 -233.908342)
			(xy 383.735765 -233.957876) (xy 384.473448 -233.957876) (xy 384.477519 -233.902254) (xy 384.489645 -233.847817)
			(xy 384.509568 -233.795726) (xy 384.536864 -233.747091) (xy 384.57095 -233.702948) (xy 384.611099 -233.664239)
			(xy 384.656457 -233.631788) (xy 384.706057 -233.606287) (xy 384.758841 -233.58828) (xy 384.813684 -233.57815)
			(xy 384.869418 -233.576113) (xy 384.924855 -233.582213) (xy 384.978812 -233.596319) (xy 385.030141 -233.618131)
			(xy 385.077747 -233.647185) (xy 385.120615 -233.68286) (xy 385.157832 -233.724397) (xy 385.188605 -233.77091)
			(xy 385.212277 -233.821407) (xy 385.228345 -233.874814) (xy 385.236465 -233.92999) (xy 385.236974 -233.957876)
			(xy 385.973572 -233.957876) (xy 385.977643 -233.902254) (xy 385.989769 -233.847817) (xy 386.009692 -233.795726)
			(xy 386.036988 -233.747091) (xy 386.071074 -233.702948) (xy 386.111223 -233.664239) (xy 386.156581 -233.631788)
			(xy 386.206181 -233.606287) (xy 386.258965 -233.58828) (xy 386.313808 -233.57815) (xy 386.369542 -233.576113)
			(xy 386.424979 -233.582213) (xy 386.478936 -233.596319) (xy 386.530265 -233.618131) (xy 386.577871 -233.647185)
			(xy 386.620739 -233.68286) (xy 386.657956 -233.724397) (xy 386.688729 -233.77091) (xy 386.712401 -233.821407)
			(xy 386.728469 -233.874814) (xy 386.736589 -233.92999) (xy 386.737098 -233.957876) (xy 386.736589 -233.985762)
			(xy 386.728469 -234.040938) (xy 386.712401 -234.094345) (xy 386.688729 -234.144842) (xy 386.657956 -234.191355)
			(xy 386.620739 -234.232892) (xy 386.577871 -234.268567) (xy 386.530265 -234.297621) (xy 386.478936 -234.319433)
			(xy 386.424979 -234.333539) (xy 386.369542 -234.339639) (xy 386.313808 -234.337602) (xy 386.258965 -234.327472)
			(xy 386.206181 -234.309465) (xy 386.156581 -234.283964) (xy 386.111223 -234.251513) (xy 386.071074 -234.212804)
			(xy 386.036988 -234.168661) (xy 386.009692 -234.120026) (xy 385.989769 -234.067935) (xy 385.977643 -234.013498)
			(xy 385.973572 -233.957876) (xy 385.236974 -233.957876) (xy 385.236465 -233.985762) (xy 385.228345 -234.040938)
			(xy 385.212277 -234.094345) (xy 385.188605 -234.144842) (xy 385.157832 -234.191355) (xy 385.120615 -234.232892)
			(xy 385.077747 -234.268567) (xy 385.030141 -234.297621) (xy 384.978812 -234.319433) (xy 384.924855 -234.333539)
			(xy 384.869418 -234.339639) (xy 384.813684 -234.337602) (xy 384.758841 -234.327472) (xy 384.706057 -234.309465)
			(xy 384.656457 -234.283964) (xy 384.611099 -234.251513) (xy 384.57095 -234.212804) (xy 384.536864 -234.168661)
			(xy 384.509568 -234.120026) (xy 384.489645 -234.067935) (xy 384.477519 -234.013498) (xy 384.473448 -233.957876)
			(xy 383.735765 -233.957876) (xy 383.736595 -233.963518) (xy 383.737104 -233.991404) (xy 383.736595 -234.01929)
			(xy 383.728475 -234.074466) (xy 383.712407 -234.127873) (xy 383.688735 -234.17837) (xy 383.657962 -234.224883)
			(xy 383.620745 -234.26642) (xy 383.577877 -234.302095) (xy 383.530271 -234.331149) (xy 383.478942 -234.352961)
			(xy 383.424985 -234.367067) (xy 383.369548 -234.373167) (xy 383.313814 -234.37113) (xy 383.258971 -234.361)
			(xy 383.206187 -234.342993) (xy 383.156587 -234.317492) (xy 383.111229 -234.285041) (xy 383.07108 -234.246332)
			(xy 383.036994 -234.202189) (xy 383.009698 -234.153554) (xy 382.989775 -234.101463) (xy 382.977649 -234.047026)
			(xy 382.973578 -233.991404) (xy 382.737041 -233.991404) (xy 382.737106 -233.99496) (xy 382.736597 -234.022846)
			(xy 382.728477 -234.078022) (xy 382.712409 -234.131429) (xy 382.688737 -234.181926) (xy 382.657964 -234.228439)
			(xy 382.620747 -234.269976) (xy 382.577879 -234.305651) (xy 382.530273 -234.334705) (xy 382.478944 -234.356517)
			(xy 382.424987 -234.370623) (xy 382.36955 -234.376723) (xy 382.313816 -234.374686) (xy 382.258973 -234.364556)
			(xy 382.206189 -234.346549) (xy 382.156589 -234.321048) (xy 382.111231 -234.288597) (xy 382.071082 -234.249888)
			(xy 382.036996 -234.205745) (xy 382.0097 -234.15711) (xy 381.989777 -234.105019) (xy 381.977651 -234.050582)
			(xy 381.97358 -233.99496) (xy 377.349512 -233.99496) (xy 377.349512 -234.438444) (xy 377.349996 -234.44919)
			(xy 377.358821 -234.468786) (xy 377.36653 -234.47629) (xy 377.369253 -234.478629) (xy 377.375245 -234.482582)
			(xy 377.378468 -234.484164) (xy 377.452128 -234.519216) (xy 377.45729 -234.521542) (xy 377.468314 -234.524113)
			(xy 377.473972 -234.524296) (xy 377.48591 -234.524296) (xy 377.489918 -234.524225) (xy 377.49783 -234.522946)
			(xy 377.501658 -234.521756) (xy 377.514612 -234.517438) (xy 377.521724 -234.51185) (xy 377.542037 -234.496357)
			(xy 377.585991 -234.470323) (xy 377.633019 -234.450369) (xy 377.682284 -234.436849) (xy 377.732909 -234.430006)
			(xy 377.758452 -234.429554) (xy 377.75896 -234.429554) (xy 377.786217 -234.430014) (xy 377.840178 -234.437767)
			(xy 377.892486 -234.453121) (xy 377.942076 -234.475764) (xy 377.987939 -234.505234) (xy 378.029141 -234.540931)
			(xy 378.064842 -234.582129) (xy 378.094317 -234.627989) (xy 378.116965 -234.677576) (xy 378.132324 -234.729883)
			(xy 378.140083 -234.783843) (xy 378.140083 -234.838357) (xy 378.132324 -234.892317) (xy 378.116965 -234.944624)
			(xy 378.094317 -234.994211) (xy 378.064842 -235.040071) (xy 378.029141 -235.081269) (xy 377.987939 -235.116966)
			(xy 377.942076 -235.146436) (xy 377.892486 -235.169079) (xy 377.840178 -235.184433) (xy 377.786217 -235.192186)
			(xy 377.75896 -235.19257) (xy 377.758706 -235.19257) (xy 377.728797 -235.191966) (xy 377.669716 -235.18259)
			(xy 377.612821 -235.164115) (xy 377.559503 -235.136991) (xy 377.534932 -235.119926) (xy 377.526296 -235.113576)
			(xy 377.514358 -235.104432) (xy 377.506484 -235.101892) (xy 377.496578 -235.098336) (xy 377.472194 -235.098336)
			(xy 377.466675 -235.0985) (xy 377.455908 -235.100931) (xy 377.450858 -235.103162) (xy 377.450604 -235.103416)
			(xy 377.45035 -235.103416) (xy 377.378468 -235.137706) (xy 377.37001 -235.14216) (xy 377.356958 -235.156107)
			(xy 377.349946 -235.173875) (xy 377.349512 -235.183426) (xy 377.349512 -235.190284) (xy 377.350002 -235.200244)
			(xy 377.357595 -235.218663) (xy 377.364244 -235.226098) (xy 377.369578 -235.231432) (xy 377.372626 -235.233718)
			(xy 377.394014 -235.250149) (xy 377.432391 -235.288045) (xy 377.46505 -235.330966) (xy 377.49134 -235.378059)
			(xy 377.510737 -235.428384) (xy 377.522856 -235.480939) (xy 377.527453 -235.534676) (xy 377.524439 -235.588526)
			(xy 377.513873 -235.641414) (xy 377.503689 -235.670344) (xy 392.969748 -235.670344) (xy 392.973819 -235.614722)
			(xy 392.985945 -235.560285) (xy 393.005868 -235.508194) (xy 393.033164 -235.459559) (xy 393.06725 -235.415416)
			(xy 393.107399 -235.376707) (xy 393.152757 -235.344256) (xy 393.202357 -235.318755) (xy 393.255141 -235.300748)
			(xy 393.309984 -235.290618) (xy 393.365718 -235.288581) (xy 393.421155 -235.294681) (xy 393.475112 -235.308787)
			(xy 393.526441 -235.330599) (xy 393.574047 -235.359653) (xy 393.616915 -235.395328) (xy 393.654132 -235.436865)
			(xy 393.684905 -235.483378) (xy 393.708577 -235.533875) (xy 393.724645 -235.587282) (xy 393.732765 -235.642458)
			(xy 393.733274 -235.670344) (xy 393.732765 -235.69823) (xy 393.724645 -235.753406) (xy 393.708577 -235.806813)
			(xy 393.684905 -235.85731) (xy 393.654132 -235.903823) (xy 393.616915 -235.94536) (xy 393.574047 -235.981035)
			(xy 393.526441 -236.010089) (xy 393.475112 -236.031901) (xy 393.421155 -236.046007) (xy 393.365718 -236.052107)
			(xy 393.309984 -236.05007) (xy 393.255141 -236.03994) (xy 393.202357 -236.021933) (xy 393.152757 -235.996432)
			(xy 393.107399 -235.963981) (xy 393.06725 -235.925272) (xy 393.033164 -235.881129) (xy 393.005868 -235.832494)
			(xy 392.985945 -235.780403) (xy 392.973819 -235.725966) (xy 392.969748 -235.670344) (xy 377.503689 -235.670344)
			(xy 377.495965 -235.692288) (xy 377.471073 -235.740134) (xy 377.439691 -235.783999) (xy 377.402447 -235.823007)
			(xy 377.381516 -235.840016) (xy 377.37923 -235.841794) (xy 377.373896 -235.847128) (xy 377.371186 -235.849905)
			(xy 377.366591 -235.856157) (xy 377.364752 -235.859574) (xy 377.3551 -235.878116) (xy 377.3551 -235.878624)
			(xy 377.349512 -235.884212) (xy 377.349512 -236.431074) (xy 377.349853 -236.439768) (xy 377.355688 -236.456144)
			(xy 377.360942 -236.463078) (xy 377.36653 -236.469682) (xy 377.381516 -236.478826) (xy 377.390406 -236.480604)
			(xy 377.417461 -236.486411) (xy 377.469654 -236.504789) (xy 377.518644 -236.530515) (xy 377.563404 -236.563048)
			(xy 377.602995 -236.601706) (xy 377.636585 -236.645678) (xy 377.663472 -236.694041) (xy 377.68309 -236.74578)
			(xy 377.695028 -236.799811) (xy 377.699035 -236.855) (xy 377.695028 -236.910189) (xy 377.68309 -236.96422)
			(xy 377.663472 -237.015959) (xy 377.636585 -237.064322) (xy 377.602995 -237.108294) (xy 377.563404 -237.146952)
			(xy 377.518644 -237.179485) (xy 377.469654 -237.205211) (xy 377.417461 -237.223589) (xy 377.390406 -237.229396)
			(xy 377.38178 -237.231453) (xy 377.374167 -237.236) (xy 379.871984 -237.236) (xy 379.876055 -237.180378)
			(xy 379.888181 -237.125941) (xy 379.908104 -237.07385) (xy 379.9354 -237.025215) (xy 379.969486 -236.981072)
			(xy 380.009635 -236.942363) (xy 380.054993 -236.909912) (xy 380.104593 -236.884411) (xy 380.157377 -236.866404)
			(xy 380.21222 -236.856274) (xy 380.267954 -236.854237) (xy 380.323391 -236.860337) (xy 380.377348 -236.874443)
			(xy 380.419459 -236.892338) (xy 387.5438 -236.892338) (xy 387.547871 -236.836716) (xy 387.559997 -236.782279)
			(xy 387.57992 -236.730188) (xy 387.607216 -236.681553) (xy 387.641302 -236.63741) (xy 387.681451 -236.598701)
			(xy 387.726809 -236.56625) (xy 387.776409 -236.540749) (xy 387.829193 -236.522742) (xy 387.884036 -236.512612)
			(xy 387.93977 -236.510575) (xy 387.995207 -236.516675) (xy 388.049164 -236.530781) (xy 388.100493 -236.552593)
			(xy 388.148099 -236.581647) (xy 388.190967 -236.617322) (xy 388.199556 -236.626908) (xy 392.966446 -236.626908)
			(xy 392.970517 -236.571286) (xy 392.982643 -236.516849) (xy 393.002566 -236.464758) (xy 393.029862 -236.416123)
			(xy 393.063948 -236.37198) (xy 393.104097 -236.333271) (xy 393.149455 -236.30082) (xy 393.199055 -236.275319)
			(xy 393.251839 -236.257312) (xy 393.306682 -236.247182) (xy 393.362416 -236.245145) (xy 393.417853 -236.251245)
			(xy 393.47181 -236.265351) (xy 393.523139 -236.287163) (xy 393.570745 -236.316217) (xy 393.613613 -236.351892)
			(xy 393.65083 -236.393429) (xy 393.681603 -236.439942) (xy 393.705275 -236.490439) (xy 393.721343 -236.543846)
			(xy 393.729463 -236.599022) (xy 393.729972 -236.626908) (xy 393.729463 -236.654794) (xy 393.721343 -236.70997)
			(xy 393.705275 -236.763377) (xy 393.681603 -236.813874) (xy 393.65083 -236.860387) (xy 393.613613 -236.901924)
			(xy 393.570745 -236.937599) (xy 393.523139 -236.966653) (xy 393.47181 -236.988465) (xy 393.417853 -237.002571)
			(xy 393.362416 -237.008671) (xy 393.306682 -237.006634) (xy 393.251839 -236.996504) (xy 393.199055 -236.978497)
			(xy 393.149455 -236.952996) (xy 393.104097 -236.920545) (xy 393.063948 -236.881836) (xy 393.029862 -236.837693)
			(xy 393.002566 -236.789058) (xy 392.982643 -236.736967) (xy 392.970517 -236.68253) (xy 392.966446 -236.626908)
			(xy 388.199556 -236.626908) (xy 388.228184 -236.658859) (xy 388.258957 -236.705372) (xy 388.282629 -236.755869)
			(xy 388.298697 -236.809276) (xy 388.306817 -236.864452) (xy 388.307326 -236.892338) (xy 388.306817 -236.920224)
			(xy 388.298697 -236.9754) (xy 388.282629 -237.028807) (xy 388.258957 -237.079304) (xy 388.228184 -237.125817)
			(xy 388.190967 -237.167354) (xy 388.148099 -237.203029) (xy 388.100493 -237.232083) (xy 388.049164 -237.253895)
			(xy 387.995207 -237.268001) (xy 387.93977 -237.274101) (xy 387.884036 -237.272064) (xy 387.829193 -237.261934)
			(xy 387.776409 -237.243927) (xy 387.726809 -237.218426) (xy 387.681451 -237.185975) (xy 387.641302 -237.147266)
			(xy 387.607216 -237.103123) (xy 387.57992 -237.054488) (xy 387.559997 -237.002397) (xy 387.547871 -236.94796)
			(xy 387.5438 -236.892338) (xy 380.419459 -236.892338) (xy 380.428677 -236.896255) (xy 380.476283 -236.925309)
			(xy 380.519151 -236.960984) (xy 380.556368 -237.002521) (xy 380.587141 -237.049034) (xy 380.610813 -237.099531)
			(xy 380.626881 -237.152938) (xy 380.635001 -237.208114) (xy 380.63551 -237.236) (xy 380.635001 -237.263886)
			(xy 380.626881 -237.319062) (xy 380.610813 -237.372469) (xy 380.587141 -237.422966) (xy 380.556368 -237.469479)
			(xy 380.519151 -237.511016) (xy 380.476283 -237.546691) (xy 380.428677 -237.575745) (xy 380.377348 -237.597557)
			(xy 380.323391 -237.611663) (xy 380.267954 -237.617763) (xy 380.21222 -237.615726) (xy 380.157377 -237.605596)
			(xy 380.104593 -237.587589) (xy 380.054993 -237.562088) (xy 380.009635 -237.529637) (xy 379.969486 -237.490928)
			(xy 379.9354 -237.446785) (xy 379.908104 -237.39815) (xy 379.888181 -237.346059) (xy 379.876055 -237.291622)
			(xy 379.871984 -237.236) (xy 377.374167 -237.236) (xy 377.366568 -237.240539) (xy 377.360688 -237.247176)
			(xy 377.355354 -237.25378) (xy 377.349512 -237.270036) (xy 377.349512 -238.352838) (xy 381.07823 -238.352838)
			(xy 381.082301 -238.297216) (xy 381.094427 -238.242779) (xy 381.11435 -238.190688) (xy 381.141646 -238.142053)
			(xy 381.175732 -238.09791) (xy 381.215881 -238.059201) (xy 381.261239 -238.02675) (xy 381.310839 -238.001249)
			(xy 381.363623 -237.983242) (xy 381.418466 -237.973112) (xy 381.4742 -237.971075) (xy 381.529637 -237.977175)
			(xy 381.583594 -237.991281) (xy 381.599405 -237.998) (xy 383.030982 -237.998) (xy 383.035053 -237.942378)
			(xy 383.047179 -237.887941) (xy 383.067102 -237.83585) (xy 383.094398 -237.787215) (xy 383.128484 -237.743072)
			(xy 383.168633 -237.704363) (xy 383.213991 -237.671912) (xy 383.263591 -237.646411) (xy 383.316375 -237.628404)
			(xy 383.371218 -237.618274) (xy 383.426952 -237.616237) (xy 383.482389 -237.622337) (xy 383.536346 -237.636443)
			(xy 383.587675 -237.658255) (xy 383.635281 -237.687309) (xy 383.678149 -237.722984) (xy 383.715366 -237.764521)
			(xy 383.746139 -237.811034) (xy 383.769811 -237.861531) (xy 383.785879 -237.914938) (xy 383.793999 -237.970114)
			(xy 383.794508 -237.998) (xy 383.793999 -238.025886) (xy 383.785879 -238.081062) (xy 383.769811 -238.134469)
			(xy 383.746139 -238.184966) (xy 383.727668 -238.212884) (xy 386.259068 -238.212884) (xy 386.263139 -238.157262)
			(xy 386.275265 -238.102825) (xy 386.295188 -238.050734) (xy 386.322484 -238.002099) (xy 386.35657 -237.957956)
			(xy 386.396719 -237.919247) (xy 386.442077 -237.886796) (xy 386.491677 -237.861295) (xy 386.544461 -237.843288)
			(xy 386.599304 -237.833158) (xy 386.655038 -237.831121) (xy 386.710475 -237.837221) (xy 386.764432 -237.851327)
			(xy 386.815761 -237.873139) (xy 386.863367 -237.902193) (xy 386.906235 -237.937868) (xy 386.943452 -237.979405)
			(xy 386.974225 -238.025918) (xy 386.997897 -238.076415) (xy 387.013965 -238.129822) (xy 387.022085 -238.184998)
			(xy 387.022594 -238.212884) (xy 387.022085 -238.24077) (xy 387.013965 -238.295946) (xy 386.997897 -238.349353)
			(xy 386.974225 -238.39985) (xy 386.943452 -238.446363) (xy 386.906235 -238.4879) (xy 386.863367 -238.523575)
			(xy 386.815761 -238.552629) (xy 386.764432 -238.574441) (xy 386.710475 -238.588547) (xy 386.655038 -238.594647)
			(xy 386.599304 -238.59261) (xy 386.544461 -238.58248) (xy 386.491677 -238.564473) (xy 386.442077 -238.538972)
			(xy 386.396719 -238.506521) (xy 386.35657 -238.467812) (xy 386.322484 -238.423669) (xy 386.295188 -238.375034)
			(xy 386.275265 -238.322943) (xy 386.263139 -238.268506) (xy 386.259068 -238.212884) (xy 383.727668 -238.212884)
			(xy 383.715366 -238.231479) (xy 383.678149 -238.273016) (xy 383.635281 -238.308691) (xy 383.587675 -238.337745)
			(xy 383.536346 -238.359557) (xy 383.482389 -238.373663) (xy 383.426952 -238.379763) (xy 383.371218 -238.377726)
			(xy 383.316375 -238.367596) (xy 383.263591 -238.349589) (xy 383.213991 -238.324088) (xy 383.168633 -238.291637)
			(xy 383.128484 -238.252928) (xy 383.094398 -238.208785) (xy 383.067102 -238.16015) (xy 383.047179 -238.108059)
			(xy 383.035053 -238.053622) (xy 383.030982 -237.998) (xy 381.599405 -237.998) (xy 381.634923 -238.013093)
			(xy 381.682529 -238.042147) (xy 381.725397 -238.077822) (xy 381.762614 -238.119359) (xy 381.793387 -238.165872)
			(xy 381.817059 -238.216369) (xy 381.833127 -238.269776) (xy 381.841247 -238.324952) (xy 381.841756 -238.352838)
			(xy 381.841247 -238.380724) (xy 381.833127 -238.4359) (xy 381.817059 -238.489307) (xy 381.793387 -238.539804)
			(xy 381.762614 -238.586317) (xy 381.725397 -238.627854) (xy 381.682529 -238.663529) (xy 381.634923 -238.692583)
			(xy 381.583594 -238.714395) (xy 381.529637 -238.728501) (xy 381.4742 -238.734601) (xy 381.418466 -238.732564)
			(xy 381.363623 -238.722434) (xy 381.310839 -238.704427) (xy 381.261239 -238.678926) (xy 381.215881 -238.646475)
			(xy 381.175732 -238.607766) (xy 381.141646 -238.563623) (xy 381.11435 -238.514988) (xy 381.094427 -238.462897)
			(xy 381.082301 -238.40846) (xy 381.07823 -238.352838) (xy 377.349512 -238.352838) (xy 377.349512 -238.811054)
			(xy 379.62027 -238.811054) (xy 379.624341 -238.755432) (xy 379.636467 -238.700995) (xy 379.65639 -238.648904)
			(xy 379.683686 -238.600269) (xy 379.717772 -238.556126) (xy 379.757921 -238.517417) (xy 379.803279 -238.484966)
			(xy 379.852879 -238.459465) (xy 379.905663 -238.441458) (xy 379.960506 -238.431328) (xy 380.01624 -238.429291)
			(xy 380.071677 -238.435391) (xy 380.125634 -238.449497) (xy 380.176963 -238.471309) (xy 380.224569 -238.500363)
			(xy 380.267437 -238.536038) (xy 380.304654 -238.577575) (xy 380.335427 -238.624088) (xy 380.359099 -238.674585)
			(xy 380.375167 -238.727992) (xy 380.383287 -238.783168) (xy 380.383796 -238.811054) (xy 380.383287 -238.83894)
			(xy 380.375167 -238.894116) (xy 380.359099 -238.947523) (xy 380.335427 -238.99802) (xy 380.304654 -239.044533)
			(xy 380.267437 -239.08607) (xy 380.224569 -239.121745) (xy 380.176963 -239.150799) (xy 380.125634 -239.172611)
			(xy 380.071677 -239.186717) (xy 380.01624 -239.192817) (xy 379.960506 -239.19078) (xy 379.905663 -239.18065)
			(xy 379.852879 -239.162643) (xy 379.803279 -239.137142) (xy 379.757921 -239.104691) (xy 379.717772 -239.065982)
			(xy 379.683686 -239.021839) (xy 379.65639 -238.973204) (xy 379.636467 -238.921113) (xy 379.624341 -238.866676)
			(xy 379.62027 -238.811054) (xy 377.349512 -238.811054) (xy 377.349512 -239.29848) (xy 417.276532 -239.29848)
			(xy 417.280603 -239.242858) (xy 417.292729 -239.188421) (xy 417.312652 -239.13633) (xy 417.339948 -239.087695)
			(xy 417.374034 -239.043552) (xy 417.414183 -239.004843) (xy 417.459541 -238.972392) (xy 417.509141 -238.946891)
			(xy 417.561925 -238.928884) (xy 417.616768 -238.918754) (xy 417.672502 -238.916717) (xy 417.727939 -238.922817)
			(xy 417.781896 -238.936923) (xy 417.833225 -238.958735) (xy 417.880831 -238.987789) (xy 417.923699 -239.023464)
			(xy 417.960916 -239.065001) (xy 417.991689 -239.111514) (xy 418.015361 -239.162011) (xy 418.031429 -239.215418)
			(xy 418.039549 -239.270594) (xy 418.040058 -239.29848) (xy 418.039549 -239.326366) (xy 418.031429 -239.381542)
			(xy 418.015361 -239.434949) (xy 417.991689 -239.485446) (xy 417.960916 -239.531959) (xy 417.923699 -239.573496)
			(xy 417.880831 -239.609171) (xy 417.833225 -239.638225) (xy 417.781896 -239.660037) (xy 417.727939 -239.674143)
			(xy 417.672502 -239.680243) (xy 417.616768 -239.678206) (xy 417.561925 -239.668076) (xy 417.509141 -239.650069)
			(xy 417.459541 -239.624568) (xy 417.414183 -239.592117) (xy 417.374034 -239.553408) (xy 417.339948 -239.509265)
			(xy 417.312652 -239.46063) (xy 417.292729 -239.408539) (xy 417.280603 -239.354102) (xy 417.276532 -239.29848)
			(xy 377.349512 -239.29848) (xy 377.349512 -239.360202) (xy 377.349714 -239.367304) (xy 377.353591 -239.380966)
			(xy 377.357132 -239.387126) (xy 377.360942 -239.392714) (xy 377.371356 -239.402366) (xy 377.378468 -239.405668)
			(xy 377.402624 -239.4176) (xy 377.447608 -239.447251) (xy 377.487974 -239.482934) (xy 377.522918 -239.523942)
			(xy 377.551746 -239.569458) (xy 377.573885 -239.618576) (xy 377.588893 -239.67032) (xy 377.596472 -239.723662)
			(xy 377.596472 -239.777538) (xy 377.59171 -239.811052) (xy 383.030982 -239.811052) (xy 383.035053 -239.75543)
			(xy 383.047179 -239.700993) (xy 383.067102 -239.648902) (xy 383.094398 -239.600267) (xy 383.128484 -239.556124)
			(xy 383.168633 -239.517415) (xy 383.213991 -239.484964) (xy 383.263591 -239.459463) (xy 383.316375 -239.441456)
			(xy 383.371218 -239.431326) (xy 383.426952 -239.429289) (xy 383.482389 -239.435389) (xy 383.536346 -239.449495)
			(xy 383.587675 -239.471307) (xy 383.635281 -239.500361) (xy 383.678149 -239.536036) (xy 383.715366 -239.577573)
			(xy 383.746139 -239.624086) (xy 383.769811 -239.674583) (xy 383.785879 -239.72799) (xy 383.793999 -239.783166)
			(xy 383.794508 -239.811052) (xy 383.793999 -239.838938) (xy 383.785879 -239.894114) (xy 383.769811 -239.947521)
			(xy 383.746139 -239.998018) (xy 383.715366 -240.044531) (xy 383.678149 -240.086068) (xy 383.635281 -240.121743)
			(xy 383.587675 -240.150797) (xy 383.536346 -240.172609) (xy 383.482389 -240.186715) (xy 383.426952 -240.192815)
			(xy 383.371218 -240.190778) (xy 383.316375 -240.180648) (xy 383.263591 -240.162641) (xy 383.213991 -240.13714)
			(xy 383.168633 -240.104689) (xy 383.128484 -240.06598) (xy 383.094398 -240.021837) (xy 383.067102 -239.973202)
			(xy 383.047179 -239.921111) (xy 383.035053 -239.866674) (xy 383.030982 -239.811052) (xy 377.59171 -239.811052)
			(xy 377.588893 -239.83088) (xy 377.573885 -239.882624) (xy 377.551746 -239.931742) (xy 377.522918 -239.977258)
			(xy 377.487974 -240.018266) (xy 377.447608 -240.053949) (xy 377.402624 -240.0836) (xy 377.378468 -240.095532)
			(xy 377.372044 -240.09883) (xy 377.361215 -240.108372) (xy 377.357132 -240.114328) (xy 377.353322 -240.12017)
			(xy 377.349512 -240.133886) (xy 377.349512 -240.740438) (xy 377.349836 -240.748954) (xy 377.355415 -240.765046)
			(xy 377.360434 -240.771934) (xy 377.440952 -240.852452) (xy 377.447834 -240.857483) (xy 377.463929 -240.863071)
			(xy 377.472448 -240.863374) (xy 378.17044 -240.863374) (xy 378.180508 -240.863804) (xy 378.199104 -240.871525)
			(xy 378.206508 -240.87836) (xy 378.827792 -241.499644) (xy 378.830642 -241.502351) (xy 378.837019 -241.506947)
			(xy 378.840492 -241.508788) (xy 378.84592 -241.511366) (xy 378.857599 -241.51418) (xy 378.863606 -241.514376)
			(xy 380.655068 -241.514376) (xy 380.665058 -241.513844) (xy 380.683496 -241.506136) (xy 380.690882 -241.49939)
			(xy 381.348742 -240.84153) (xy 381.77724 -240.413286) (xy 381.784583 -240.406472) (xy 381.803047 -240.398741)
			(xy 381.813054 -240.3983) (xy 382.25984 -240.3983) (xy 382.269238 -240.397792) (xy 383.779776 -240.397792)
			(xy 383.788121 -240.396465) (xy 383.803303 -240.389066) (xy 383.809494 -240.383314) (xy 384.246374 -239.946434)
			(xy 384.247644 -239.945164) (xy 384.650488 -239.542574) (xy 384.657829 -239.535753) (xy 384.676292 -239.528005)
			(xy 384.686302 -239.527588) (xy 389.267954 -239.527588) (xy 389.277945 -239.528117) (xy 389.296391 -239.535817)
			(xy 389.303768 -239.542574) (xy 389.696452 -239.935258) (xy 389.697722 -239.936274) (xy 389.707628 -239.945672)
			(xy 389.707882 -239.94618) (xy 391.82802 -242.066318) (xy 391.833532 -242.070643) (xy 391.846283 -242.076435)
			(xy 391.853166 -242.077748) (xy 391.860786 -242.078256)
		)
		(stroke
			(width 0)
			(type solid)
		)
		(fill yes)
		(layer "In15.Cu")
		(net "GND")
	)
	(gr_poly
		(pts
			(xy 313.023504 -416.371532) (xy 313.032725 -416.371115) (xy 313.049958 -416.36454) (xy 313.063741 -416.352283)
			(xy 313.072282 -416.335935) (xy 313.073796 -416.326828) (xy 313.073796 -394.27912) (xy 326.479662 -394.27912)
			(xy 326.525636 -394.325094) (xy 326.525636 -397.82289) (xy 331.004928 -397.82289) (xy 331.004932 -397.757445)
			(xy 331.01373 -397.692593) (xy 331.031162 -397.629511) (xy 331.056912 -397.569344) (xy 331.073252 -397.540988)
			(xy 331.076567 -397.534964) (xy 331.080173 -397.5217) (xy 331.080364 -397.514826) (xy 331.080364 -396.765526)
			(xy 331.080167 -396.758653) (xy 331.076563 -396.74539) (xy 331.073252 -396.739364) (xy 331.056906 -396.711013)
			(xy 331.031162 -396.650845) (xy 331.013736 -396.587764) (xy 331.004944 -396.522913) (xy 331.004945 -396.45747)
			(xy 331.013739 -396.392619) (xy 331.031168 -396.329539) (xy 331.056914 -396.269372) (xy 331.073252 -396.241016)
			(xy 331.076557 -396.234987) (xy 331.080169 -396.221727) (xy 331.080364 -396.214854) (xy 331.080364 -395.92885)
			(xy 331.080805 -395.918678) (xy 331.088579 -395.89988) (xy 331.10296 -395.885492) (xy 331.121755 -395.87771)
			(xy 331.131926 -395.877288) (xy 331.848206 -395.877288) (xy 331.858384 -395.87766) (xy 331.877189 -395.885456)
			(xy 331.891575 -395.899859) (xy 331.899351 -395.918671) (xy 331.899768 -395.92885) (xy 331.899768 -396.214854)
			(xy 331.899981 -396.221726) (xy 331.903575 -396.234988) (xy 331.90688 -396.241016) (xy 331.923208 -396.269377)
			(xy 331.948952 -396.329543) (xy 331.966379 -396.392622) (xy 331.975172 -396.45747) (xy 331.975173 -396.522912)
			(xy 331.966382 -396.587761) (xy 331.948958 -396.650841) (xy 331.923216 -396.711008) (xy 331.90688 -396.739364)
			(xy 331.903577 -396.745394) (xy 331.899964 -396.758654) (xy 331.899768 -396.765526) (xy 331.899768 -397.514826)
			(xy 331.899954 -397.5217) (xy 331.903567 -397.534962) (xy 331.90688 -397.540988) (xy 331.916246 -397.557287)
			(xy 333.204849 -397.557287) (xy 333.213641 -397.492438) (xy 333.231066 -397.429359) (xy 333.256809 -397.369192)
			(xy 333.273146 -397.340836) (xy 333.276497 -397.334814) (xy 333.280241 -397.321559) (xy 333.280512 -397.314674)
			(xy 333.280512 -397.028924) (xy 333.280936 -397.018802) (xy 333.288678 -397.000096) (xy 333.302993 -396.985781)
			(xy 333.321698 -396.978037) (xy 333.33182 -396.977616) (xy 334.0481 -396.977616) (xy 334.058224 -396.978016)
			(xy 334.076931 -396.985768) (xy 334.091246 -397.000089) (xy 334.098988 -397.018799) (xy 334.099408 -397.028924)
			(xy 334.099408 -397.314674) (xy 334.09965 -397.321565) (xy 334.103386 -397.334831) (xy 334.106774 -397.340836)
			(xy 334.123119 -397.369188) (xy 334.148862 -397.429356) (xy 334.166287 -397.492437) (xy 334.175079 -397.557287)
			(xy 334.175077 -397.62273) (xy 334.166283 -397.68758) (xy 334.148856 -397.750661) (xy 334.123112 -397.810828)
			(xy 334.116162 -397.82289) (xy 335.404978 -397.82289) (xy 335.404982 -397.757445) (xy 335.413779 -397.692594)
			(xy 335.431209 -397.629512) (xy 335.456955 -397.569345) (xy 335.473294 -397.540988) (xy 335.476658 -397.534973)
			(xy 335.480394 -397.521713) (xy 335.48066 -397.514826) (xy 335.48066 -396.765526) (xy 335.480444 -396.758632)
			(xy 335.476704 -396.74536) (xy 335.473294 -396.739364) (xy 335.45695 -396.711012) (xy 335.431209 -396.650844)
			(xy 335.413785 -396.587763) (xy 335.404994 -396.522913) (xy 335.404995 -396.45747) (xy 335.413788 -396.39262)
			(xy 335.431215 -396.32954) (xy 335.456957 -396.269373) (xy 335.473294 -396.241016) (xy 335.476648 -396.234996)
			(xy 335.480391 -396.22174) (xy 335.48066 -396.214854) (xy 335.48066 -395.92885) (xy 335.481168 -395.918724)
			(xy 335.488883 -395.9) (xy 335.503164 -395.885642) (xy 335.521845 -395.877824) (xy 335.531968 -395.877288)
			(xy 336.248248 -395.877288) (xy 336.258404 -395.877682) (xy 336.277155 -395.885491) (xy 336.291476 -395.899896)
			(xy 336.299176 -395.918692) (xy 336.299556 -395.92885) (xy 336.299556 -396.214854) (xy 336.299778 -396.221748)
			(xy 336.303514 -396.23502) (xy 336.306922 -396.241016) (xy 336.323252 -396.269376) (xy 336.348999 -396.329542)
			(xy 336.366428 -396.392621) (xy 336.375222 -396.45747) (xy 336.375224 -396.522913) (xy 336.366431 -396.587762)
			(xy 336.349005 -396.650842) (xy 336.32326 -396.711008) (xy 336.306922 -396.739364) (xy 336.303568 -396.745384)
			(xy 336.299826 -396.758641) (xy 336.299556 -396.765526) (xy 336.299556 -397.514826) (xy 336.299788 -397.521719)
			(xy 336.303517 -397.534991) (xy 336.306922 -397.540988) (xy 336.316289 -397.557287) (xy 337.604885 -397.557287)
			(xy 337.613678 -397.492438) (xy 337.631105 -397.429358) (xy 337.65685 -397.369192) (xy 337.673188 -397.340836)
			(xy 337.676489 -397.334805) (xy 337.680104 -397.321546) (xy 337.6803 -397.314674) (xy 337.6803 -397.028924)
			(xy 337.680741 -397.018771) (xy 337.688529 -397.000019) (xy 337.70292 -396.985695) (xy 337.721708 -396.977995)
			(xy 337.731862 -396.977616) (xy 338.448142 -396.977616) (xy 338.458268 -396.978091) (xy 338.476986 -396.985829)
			(xy 338.49134 -397.000118) (xy 338.499162 -397.0188) (xy 338.499704 -397.028924) (xy 338.499704 -397.314674)
			(xy 338.499906 -397.321547) (xy 338.503507 -397.334809) (xy 338.506816 -397.340836) (xy 338.523163 -397.369187)
			(xy 338.548909 -397.429354) (xy 338.566336 -397.492436) (xy 338.575129 -397.557286) (xy 338.575127 -397.622731)
			(xy 338.566332 -397.687581) (xy 338.548903 -397.750662) (xy 338.523155 -397.810828) (xy 338.516205 -397.82289)
			(xy 339.805014 -397.82289) (xy 339.805019 -397.757445) (xy 339.813816 -397.692593) (xy 339.831247 -397.629512)
			(xy 339.856996 -397.569344) (xy 339.873336 -397.540988) (xy 339.87665 -397.534963) (xy 339.880257 -397.5217)
			(xy 339.880448 -397.514826) (xy 339.880448 -396.765526) (xy 339.880253 -396.758653) (xy 339.876647 -396.74539)
			(xy 339.873336 -396.739364) (xy 339.85699 -396.711012) (xy 339.831247 -396.650845) (xy 339.813822 -396.587764)
			(xy 339.80503 -396.522913) (xy 339.805031 -396.45747) (xy 339.813825 -396.39262) (xy 339.831253 -396.329539)
			(xy 339.856998 -396.269372) (xy 339.873336 -396.241016) (xy 339.87664 -396.234986) (xy 339.880253 -396.221727)
			(xy 339.880448 -396.214854) (xy 339.880448 -395.92885) (xy 339.880905 -395.91868) (xy 339.888675 -395.899885)
			(xy 339.903051 -395.885498) (xy 339.921841 -395.877713) (xy 339.93201 -395.877288) (xy 340.64829 -395.877288)
			(xy 340.658467 -395.877673) (xy 340.677271 -395.885464) (xy 340.691658 -395.899862) (xy 340.699435 -395.918672)
			(xy 340.699852 -395.92885) (xy 340.699852 -396.214854) (xy 340.700055 -396.221727) (xy 340.703655 -396.23499)
			(xy 340.706964 -396.241016) (xy 340.723293 -396.269377) (xy 340.749037 -396.329543) (xy 340.766465 -396.392622)
			(xy 340.775259 -396.45747) (xy 340.77526 -396.522913) (xy 340.766468 -396.587762) (xy 340.749043 -396.650841)
			(xy 340.723301 -396.711008) (xy 340.706964 -396.739364) (xy 340.703667 -396.745397) (xy 340.700049 -396.758654)
			(xy 340.699852 -396.765526) (xy 340.699852 -397.514826) (xy 340.700028 -397.521701) (xy 340.703646 -397.534964)
			(xy 340.706964 -397.540988) (xy 340.71633 -397.557287) (xy 342.004935 -397.557287) (xy 342.013727 -397.492439)
			(xy 342.031151 -397.429359) (xy 342.056894 -397.369192) (xy 342.07323 -397.340836) (xy 342.07658 -397.334814)
			(xy 342.080325 -397.321559) (xy 342.080596 -397.314674) (xy 342.080596 -397.028924) (xy 342.081035 -397.018804)
			(xy 342.088775 -397.000101) (xy 342.103084 -396.985786) (xy 342.121784 -396.978039) (xy 342.131904 -396.977616)
			(xy 342.848184 -396.977616) (xy 342.858307 -396.978029) (xy 342.877014 -396.985775) (xy 342.891329 -397.000093)
			(xy 342.899072 -397.0188) (xy 342.899492 -397.028924) (xy 342.899492 -397.314674) (xy 342.899736 -397.321564)
			(xy 342.903471 -397.33483) (xy 342.906858 -397.340836) (xy 342.923204 -397.369187) (xy 342.948947 -397.429355)
			(xy 342.966373 -397.492436) (xy 342.975165 -397.557287) (xy 342.975164 -397.62273) (xy 342.966369 -397.687581)
			(xy 342.948942 -397.750661) (xy 342.923196 -397.810828) (xy 342.916246 -397.82289) (xy 344.204804 -397.82289)
			(xy 344.204808 -397.757445) (xy 344.213606 -397.692593) (xy 344.231036 -397.629512) (xy 344.256785 -397.569344)
			(xy 344.273124 -397.540988) (xy 344.276445 -397.534966) (xy 344.280046 -397.5217) (xy 344.280236 -397.514826)
			(xy 344.280236 -396.765526) (xy 344.28003 -396.758654) (xy 344.276431 -396.745391) (xy 344.273124 -396.739364)
			(xy 344.256779 -396.711012) (xy 344.231036 -396.650844) (xy 344.213611 -396.587763) (xy 344.20482 -396.522913)
			(xy 344.204821 -396.45747) (xy 344.213615 -396.39262) (xy 344.231042 -396.329539) (xy 344.256786 -396.269372)
			(xy 344.273124 -396.241016) (xy 344.276435 -396.234989) (xy 344.280042 -396.221727) (xy 344.280236 -396.214854)
			(xy 344.280236 -395.92885) (xy 344.280705 -395.918682) (xy 344.288473 -395.899889) (xy 344.302845 -395.885502)
			(xy 344.32163 -395.877715) (xy 344.331798 -395.877288) (xy 345.048078 -395.877288) (xy 345.058254 -395.877683)
			(xy 345.077058 -395.88547) (xy 345.091445 -395.899866) (xy 345.099222 -395.918673) (xy 345.09964 -395.92885)
			(xy 345.09964 -396.214854) (xy 345.099844 -396.221726) (xy 345.103444 -396.234989) (xy 345.106752 -396.241016)
			(xy 345.123081 -396.269377) (xy 345.148826 -396.329542) (xy 345.166254 -396.392621) (xy 345.175048 -396.45747)
			(xy 345.175048 -396.49019) (xy 348.603832 -396.49019) (xy 348.607823 -396.428023) (xy 348.619732 -396.366876)
			(xy 348.639361 -396.307755) (xy 348.66639 -396.251629) (xy 348.700374 -396.19942) (xy 348.740756 -396.151985)
			(xy 348.786872 -396.110104) (xy 348.837964 -396.074464) (xy 348.893195 -396.04565) (xy 348.951657 -396.024136)
			(xy 349.012391 -396.010274) (xy 349.074398 -396.004292) (xy 349.136661 -396.006288) (xy 349.198158 -396.016231)
			(xy 349.257879 -396.033955) (xy 349.314842 -396.059172) (xy 349.322351 -396.063724) (xy 357.261158 -396.063724)
			(xy 357.265229 -396.008102) (xy 357.277355 -395.953665) (xy 357.297278 -395.901574) (xy 357.324574 -395.852939)
			(xy 357.35866 -395.808796) (xy 357.398809 -395.770087) (xy 357.444167 -395.737636) (xy 357.493767 -395.712135)
			(xy 357.546551 -395.694128) (xy 357.601394 -395.683998) (xy 357.657128 -395.681961) (xy 357.712565 -395.688061)
			(xy 357.766522 -395.702167) (xy 357.817851 -395.723979) (xy 357.865457 -395.753033) (xy 357.908325 -395.788708)
			(xy 357.945542 -395.830245) (xy 357.976315 -395.876758) (xy 357.999987 -395.927255) (xy 358.016055 -395.980662)
			(xy 358.024175 -396.035838) (xy 358.024684 -396.063724) (xy 358.024175 -396.09161) (xy 358.016055 -396.146786)
			(xy 357.999987 -396.200193) (xy 357.976315 -396.25069) (xy 357.945542 -396.297203) (xy 357.908325 -396.33874)
			(xy 357.865457 -396.374415) (xy 357.817851 -396.403469) (xy 357.766522 -396.425281) (xy 357.712565 -396.439387)
			(xy 357.657128 -396.445487) (xy 357.601394 -396.44345) (xy 357.546551 -396.43332) (xy 357.493767 -396.415313)
			(xy 357.444167 -396.389812) (xy 357.398809 -396.357361) (xy 357.35866 -396.318652) (xy 357.324574 -396.274509)
			(xy 357.297278 -396.225874) (xy 357.277355 -396.173783) (xy 357.265229 -396.119346) (xy 357.261158 -396.063724)
			(xy 349.322351 -396.063724) (xy 349.368113 -396.091465) (xy 349.416818 -396.130305) (xy 349.460155 -396.175055)
			(xy 349.497415 -396.224979) (xy 349.527984 -396.279258) (xy 349.551362 -396.337001) (xy 349.567163 -396.397259)
			(xy 349.575129 -396.459042) (xy 349.575628 -396.49019) (xy 349.575129 -396.521338) (xy 349.567163 -396.583121)
			(xy 349.551362 -396.643379) (xy 349.527984 -396.701122) (xy 349.497415 -396.755401) (xy 349.460155 -396.805325)
			(xy 349.416818 -396.850075) (xy 349.368113 -396.888915) (xy 349.314842 -396.921208) (xy 349.257879 -396.946425)
			(xy 349.198158 -396.964149) (xy 349.136661 -396.974092) (xy 349.074398 -396.976088) (xy 349.012391 -396.970106)
			(xy 348.951657 -396.956244) (xy 348.893195 -396.93473) (xy 348.837964 -396.905916) (xy 348.786872 -396.870276)
			(xy 348.740756 -396.828395) (xy 348.700374 -396.78096) (xy 348.66639 -396.728751) (xy 348.639361 -396.672625)
			(xy 348.619732 -396.613504) (xy 348.607823 -396.552357) (xy 348.603832 -396.49019) (xy 345.175048 -396.49019)
			(xy 345.175049 -396.522913) (xy 345.166257 -396.587762) (xy 345.148832 -396.650841) (xy 345.123089 -396.711008)
			(xy 345.106752 -396.739364) (xy 345.103454 -396.745397) (xy 345.099837 -396.758654) (xy 345.09964 -396.765526)
			(xy 345.09964 -397.514826) (xy 345.099817 -397.5217) (xy 345.103435 -397.534963) (xy 345.106752 -397.540988)
			(xy 345.116118 -397.557287) (xy 346.404971 -397.557287) (xy 346.413764 -397.492438) (xy 346.43119 -397.429358)
			(xy 346.456934 -397.369192) (xy 346.473272 -397.340836) (xy 346.476572 -397.334804) (xy 346.480187 -397.321546)
			(xy 346.480384 -397.314674) (xy 346.480384 -397.028924) (xy 346.480841 -397.018773) (xy 346.488625 -397.000025)
			(xy 346.503011 -396.985701) (xy 346.521794 -396.977997) (xy 346.531946 -396.977616) (xy 347.248226 -396.977616)
			(xy 347.258351 -396.978104) (xy 347.277069 -396.985836) (xy 347.291423 -397.000121) (xy 347.299246 -397.018801)
			(xy 347.299611 -397.025622) (xy 365.416844 -397.025622) (xy 365.420915 -396.97) (xy 365.433041 -396.915563)
			(xy 365.452964 -396.863472) (xy 365.48026 -396.814837) (xy 365.514346 -396.770694) (xy 365.554495 -396.731985)
			(xy 365.599853 -396.699534) (xy 365.649453 -396.674033) (xy 365.702237 -396.656026) (xy 365.75708 -396.645896)
			(xy 365.812814 -396.643859) (xy 365.868251 -396.649959) (xy 365.922208 -396.664065) (xy 365.973537 -396.685877)
			(xy 366.021143 -396.714931) (xy 366.064011 -396.750606) (xy 366.101048 -396.791942) (xy 366.335308 -396.791942)
			(xy 366.339379 -396.73632) (xy 366.351505 -396.681883) (xy 366.371428 -396.629792) (xy 366.398724 -396.581157)
			(xy 366.43281 -396.537014) (xy 366.472959 -396.498305) (xy 366.518317 -396.465854) (xy 366.567917 -396.440353)
			(xy 366.620701 -396.422346) (xy 366.675544 -396.412216) (xy 366.731278 -396.410179) (xy 366.786715 -396.416279)
			(xy 366.840672 -396.430385) (xy 366.892001 -396.452197) (xy 366.939607 -396.481251) (xy 366.982475 -396.516926)
			(xy 367.019692 -396.558463) (xy 367.050465 -396.604976) (xy 367.074137 -396.655473) (xy 367.090205 -396.70888)
			(xy 367.098325 -396.764056) (xy 367.098834 -396.791942) (xy 367.098325 -396.819828) (xy 367.090205 -396.875004)
			(xy 367.074137 -396.928411) (xy 367.050465 -396.978908) (xy 367.019692 -397.025421) (xy 366.982475 -397.066958)
			(xy 366.939607 -397.102633) (xy 366.892001 -397.131687) (xy 366.840672 -397.153499) (xy 366.786715 -397.167605)
			(xy 366.731278 -397.173705) (xy 366.675544 -397.171668) (xy 366.620701 -397.161538) (xy 366.567917 -397.143531)
			(xy 366.518317 -397.11803) (xy 366.472959 -397.085579) (xy 366.43281 -397.04687) (xy 366.398724 -397.002727)
			(xy 366.371428 -396.954092) (xy 366.351505 -396.902001) (xy 366.339379 -396.847564) (xy 366.335308 -396.791942)
			(xy 366.101048 -396.791942) (xy 366.101228 -396.792143) (xy 366.132001 -396.838656) (xy 366.155673 -396.889153)
			(xy 366.171741 -396.94256) (xy 366.179861 -396.997736) (xy 366.18037 -397.025622) (xy 366.179861 -397.053508)
			(xy 366.171741 -397.108684) (xy 366.155673 -397.162091) (xy 366.132001 -397.212588) (xy 366.101228 -397.259101)
			(xy 366.064011 -397.300638) (xy 366.021143 -397.336313) (xy 365.973537 -397.365367) (xy 365.922208 -397.387179)
			(xy 365.868251 -397.401285) (xy 365.812814 -397.407385) (xy 365.75708 -397.405348) (xy 365.702237 -397.395218)
			(xy 365.649453 -397.377211) (xy 365.599853 -397.35171) (xy 365.554495 -397.319259) (xy 365.514346 -397.28055)
			(xy 365.48026 -397.236407) (xy 365.452964 -397.187772) (xy 365.433041 -397.135681) (xy 365.420915 -397.081244)
			(xy 365.416844 -397.025622) (xy 347.299611 -397.025622) (xy 347.299788 -397.028924) (xy 347.299788 -397.314674)
			(xy 347.299991 -397.321546) (xy 347.303592 -397.334809) (xy 347.3069 -397.340836) (xy 347.323245 -397.369188)
			(xy 347.348986 -397.429356) (xy 347.36641 -397.492437) (xy 347.375201 -397.557287) (xy 347.3752 -397.62273)
			(xy 347.366406 -397.68758) (xy 347.34898 -397.75066) (xy 347.332079 -397.790162) (xy 348.603832 -397.790162)
			(xy 348.607823 -397.727995) (xy 348.619732 -397.666848) (xy 348.639361 -397.607727) (xy 348.66639 -397.551601)
			(xy 348.700374 -397.499392) (xy 348.740756 -397.451957) (xy 348.786872 -397.410076) (xy 348.837964 -397.374436)
			(xy 348.893195 -397.345622) (xy 348.951657 -397.324108) (xy 349.012391 -397.310246) (xy 349.074398 -397.304264)
			(xy 349.136661 -397.30626) (xy 349.198158 -397.316203) (xy 349.257879 -397.333927) (xy 349.314842 -397.359144)
			(xy 349.368113 -397.391437) (xy 349.416818 -397.430277) (xy 349.460155 -397.475027) (xy 349.497415 -397.524951)
			(xy 349.527984 -397.57923) (xy 349.532348 -397.59001) (xy 350.80398 -397.59001) (xy 350.807971 -397.527843)
			(xy 350.81988 -397.466696) (xy 350.839509 -397.407575) (xy 350.866538 -397.351449) (xy 350.900522 -397.29924)
			(xy 350.940904 -397.251805) (xy 350.98702 -397.209924) (xy 351.038112 -397.174284) (xy 351.093343 -397.14547)
			(xy 351.151805 -397.123956) (xy 351.212539 -397.110094) (xy 351.274546 -397.104112) (xy 351.336809 -397.106108)
			(xy 351.398306 -397.116051) (xy 351.458027 -397.133775) (xy 351.51499 -397.158992) (xy 351.568261 -397.191285)
			(xy 351.616966 -397.230125) (xy 351.660303 -397.274875) (xy 351.697563 -397.324799) (xy 351.728132 -397.379078)
			(xy 351.75151 -397.436821) (xy 351.767311 -397.497079) (xy 351.775277 -397.558862) (xy 351.775776 -397.59001)
			(xy 351.775277 -397.621158) (xy 351.767311 -397.682941) (xy 351.75151 -397.743199) (xy 351.728132 -397.800942)
			(xy 351.697563 -397.855221) (xy 351.660303 -397.905145) (xy 351.616966 -397.949895) (xy 351.568261 -397.988735)
			(xy 351.51499 -398.021028) (xy 351.458027 -398.046245) (xy 351.398306 -398.063969) (xy 351.336809 -398.073912)
			(xy 351.274546 -398.075908) (xy 351.212539 -398.069926) (xy 351.151805 -398.056064) (xy 351.093343 -398.03455)
			(xy 351.038112 -398.005736) (xy 350.98702 -397.970096) (xy 350.940904 -397.928215) (xy 350.900522 -397.88078)
			(xy 350.866538 -397.828571) (xy 350.839509 -397.772445) (xy 350.81988 -397.713324) (xy 350.807971 -397.652177)
			(xy 350.80398 -397.59001) (xy 349.532348 -397.59001) (xy 349.551362 -397.636973) (xy 349.567163 -397.697231)
			(xy 349.575129 -397.759014) (xy 349.575628 -397.790162) (xy 349.575129 -397.82131) (xy 349.567163 -397.883093)
			(xy 349.551362 -397.943351) (xy 349.527984 -398.001094) (xy 349.497415 -398.055373) (xy 349.460155 -398.105297)
			(xy 349.416818 -398.150047) (xy 349.368113 -398.188887) (xy 349.314842 -398.22118) (xy 349.257879 -398.246397)
			(xy 349.198158 -398.264121) (xy 349.136661 -398.274064) (xy 349.074398 -398.27606) (xy 349.012391 -398.270078)
			(xy 348.951657 -398.256216) (xy 348.893195 -398.234702) (xy 348.837964 -398.205888) (xy 348.786872 -398.170248)
			(xy 348.740756 -398.128367) (xy 348.700374 -398.080932) (xy 348.66639 -398.028723) (xy 348.639361 -397.972597)
			(xy 348.619732 -397.913476) (xy 348.607823 -397.852329) (xy 348.603832 -397.790162) (xy 347.332079 -397.790162)
			(xy 347.323237 -397.810827) (xy 347.3069 -397.839184) (xy 347.303591 -397.845211) (xy 347.299982 -397.858473)
			(xy 347.299788 -397.865346) (xy 347.299788 -398.6149) (xy 347.299981 -398.621773) (xy 347.303589 -398.635036)
			(xy 347.3069 -398.641062) (xy 347.323267 -398.669402) (xy 347.349006 -398.729573) (xy 347.366427 -398.792656)
			(xy 347.375216 -398.857508) (xy 347.375214 -398.890236) (xy 350.80398 -398.890236) (xy 350.807971 -398.828069)
			(xy 350.81988 -398.766922) (xy 350.839509 -398.707801) (xy 350.866538 -398.651675) (xy 350.900522 -398.599466)
			(xy 350.940904 -398.552031) (xy 350.98702 -398.51015) (xy 351.038112 -398.47451) (xy 351.093343 -398.445696)
			(xy 351.151805 -398.424182) (xy 351.212539 -398.41032) (xy 351.274546 -398.404338) (xy 351.336809 -398.406334)
			(xy 351.398306 -398.416277) (xy 351.458027 -398.434001) (xy 351.481667 -398.444466) (xy 363.577884 -398.444466)
			(xy 363.581955 -398.388844) (xy 363.594081 -398.334407) (xy 363.614004 -398.282316) (xy 363.6413 -398.233681)
			(xy 363.675386 -398.189538) (xy 363.715535 -398.150829) (xy 363.760893 -398.118378) (xy 363.810493 -398.092877)
			(xy 363.863277 -398.07487) (xy 363.91812 -398.06474) (xy 363.973854 -398.062703) (xy 364.029291 -398.068803)
			(xy 364.083248 -398.082909) (xy 364.134577 -398.104721) (xy 364.182183 -398.133775) (xy 364.225051 -398.16945)
			(xy 364.262268 -398.210987) (xy 364.293041 -398.2575) (xy 364.316713 -398.307997) (xy 364.332781 -398.361404)
			(xy 364.340901 -398.41658) (xy 364.34141 -398.444466) (xy 364.340901 -398.472352) (xy 364.332781 -398.527528)
			(xy 364.316713 -398.580935) (xy 364.293041 -398.631432) (xy 364.262268 -398.677945) (xy 364.225051 -398.719482)
			(xy 364.182183 -398.755157) (xy 364.134577 -398.784211) (xy 364.083248 -398.806023) (xy 364.029291 -398.820129)
			(xy 363.973854 -398.826229) (xy 363.91812 -398.824192) (xy 363.863277 -398.814062) (xy 363.810493 -398.796055)
			(xy 363.760893 -398.770554) (xy 363.715535 -398.738103) (xy 363.675386 -398.699394) (xy 363.6413 -398.655251)
			(xy 363.614004 -398.606616) (xy 363.594081 -398.554525) (xy 363.581955 -398.500088) (xy 363.577884 -398.444466)
			(xy 351.481667 -398.444466) (xy 351.51499 -398.459218) (xy 351.568261 -398.491511) (xy 351.616966 -398.530351)
			(xy 351.660303 -398.575101) (xy 351.697563 -398.625025) (xy 351.728132 -398.679304) (xy 351.75151 -398.737047)
			(xy 351.767311 -398.797305) (xy 351.775277 -398.859088) (xy 351.775776 -398.890236) (xy 351.775277 -398.921384)
			(xy 351.767311 -398.983167) (xy 351.75151 -399.043425) (xy 351.728132 -399.101168) (xy 351.697563 -399.155447)
			(xy 351.660303 -399.205371) (xy 351.646206 -399.219928) (xy 357.060752 -399.219928) (xy 357.064823 -399.164306)
			(xy 357.076949 -399.109869) (xy 357.096872 -399.057778) (xy 357.124168 -399.009143) (xy 357.158254 -398.965)
			(xy 357.198403 -398.926291) (xy 357.243761 -398.89384) (xy 357.293361 -398.868339) (xy 357.346145 -398.850332)
			(xy 357.400988 -398.840202) (xy 357.456722 -398.838165) (xy 357.512159 -398.844265) (xy 357.566116 -398.858371)
			(xy 357.617445 -398.880183) (xy 357.665051 -398.909237) (xy 357.707919 -398.944912) (xy 357.745136 -398.986449)
			(xy 357.775909 -399.032962) (xy 357.799581 -399.083459) (xy 357.815649 -399.136866) (xy 357.823769 -399.192042)
			(xy 357.824278 -399.219928) (xy 357.823769 -399.247814) (xy 357.815649 -399.30299) (xy 357.799581 -399.356397)
			(xy 357.775909 -399.406894) (xy 357.745136 -399.453407) (xy 357.707919 -399.494944) (xy 357.665051 -399.530619)
			(xy 357.617445 -399.559673) (xy 357.566116 -399.581485) (xy 357.512159 -399.595591) (xy 357.456722 -399.601691)
			(xy 357.400988 -399.599654) (xy 357.346145 -399.589524) (xy 357.293361 -399.571517) (xy 357.243761 -399.546016)
			(xy 357.198403 -399.513565) (xy 357.158254 -399.474856) (xy 357.124168 -399.430713) (xy 357.096872 -399.382078)
			(xy 357.076949 -399.329987) (xy 357.064823 -399.27555) (xy 357.060752 -399.219928) (xy 351.646206 -399.219928)
			(xy 351.616966 -399.250121) (xy 351.568261 -399.288961) (xy 351.51499 -399.321254) (xy 351.458027 -399.346471)
			(xy 351.398306 -399.364195) (xy 351.336809 -399.374138) (xy 351.274546 -399.376134) (xy 351.212539 -399.370152)
			(xy 351.151805 -399.35629) (xy 351.093343 -399.334776) (xy 351.038112 -399.305962) (xy 350.98702 -399.270322)
			(xy 350.940904 -399.228441) (xy 350.900522 -399.181006) (xy 350.866538 -399.128797) (xy 350.839509 -399.072671)
			(xy 350.81988 -399.01355) (xy 350.807971 -398.952403) (xy 350.80398 -398.890236) (xy 347.375214 -398.890236)
			(xy 347.375212 -398.922953) (xy 347.366415 -398.987804) (xy 347.348985 -399.050886) (xy 347.323239 -399.111053)
			(xy 347.3069 -399.13941) (xy 347.303582 -399.145433) (xy 347.299978 -399.158698) (xy 347.299788 -399.165572)
			(xy 347.299788 -399.451576) (xy 347.299359 -399.46173) (xy 347.291569 -399.480484) (xy 347.277174 -399.494809)
			(xy 347.258382 -399.502507) (xy 347.248226 -399.502884) (xy 346.531946 -399.502884) (xy 346.521825 -399.502336)
			(xy 346.50311 -399.494628) (xy 346.488753 -399.480361) (xy 346.480928 -399.461694) (xy 346.480384 -399.451576)
			(xy 346.480384 -399.165572) (xy 346.480205 -399.158698) (xy 346.476588 -399.145435) (xy 346.473272 -399.13941)
			(xy 346.456964 -399.111037) (xy 346.431216 -399.050875) (xy 346.413785 -398.987798) (xy 346.404987 -398.922951)
			(xy 346.404983 -398.85751) (xy 346.413772 -398.792662) (xy 346.431195 -398.729584) (xy 346.456936 -398.669418)
			(xy 346.473272 -398.641062) (xy 346.476598 -398.635043) (xy 346.480197 -398.621775) (xy 346.480384 -398.6149)
			(xy 346.480384 -397.865346) (xy 346.480176 -397.858474) (xy 346.476579 -397.845211) (xy 346.473272 -397.839184)
			(xy 346.456942 -397.810823) (xy 346.431196 -397.750658) (xy 346.413767 -397.687579) (xy 346.404972 -397.62273)
			(xy 346.404971 -397.557287) (xy 345.116118 -397.557287) (xy 345.123057 -397.569362) (xy 345.148805 -397.629524)
			(xy 345.166235 -397.692601) (xy 345.175032 -397.757447) (xy 345.175037 -397.822888) (xy 345.166248 -397.887735)
			(xy 345.148826 -397.950814) (xy 345.123087 -398.01098) (xy 345.106752 -398.039336) (xy 345.103429 -398.045356)
			(xy 345.099828 -398.058623) (xy 345.09964 -398.065498) (xy 345.09964 -398.351502) (xy 345.099237 -398.361676)
			(xy 345.091447 -398.380475) (xy 345.077055 -398.394861) (xy 345.058253 -398.402642) (xy 345.048078 -398.403064)
			(xy 344.331798 -398.403064) (xy 344.32164 -398.402568) (xy 344.302872 -398.394794) (xy 344.288506 -398.380428)
			(xy 344.280732 -398.36166) (xy 344.280236 -398.351502) (xy 344.280236 -398.065498) (xy 344.28004 -398.058625)
			(xy 344.276434 -398.045362) (xy 344.273124 -398.039336) (xy 344.256755 -398.010997) (xy 344.231015 -397.950826)
			(xy 344.213592 -397.887743) (xy 344.204804 -397.82289) (xy 342.916246 -397.82289) (xy 342.906858 -397.839184)
			(xy 342.9035 -397.845202) (xy 342.899761 -397.85846) (xy 342.899492 -397.865346) (xy 342.899492 -398.6149)
			(xy 342.899726 -398.621791) (xy 342.903468 -398.635057) (xy 342.906858 -398.641062) (xy 342.923226 -398.669401)
			(xy 342.948967 -398.729572) (xy 342.96639 -398.792656) (xy 342.97518 -398.857508) (xy 342.975175 -398.922954)
			(xy 342.966378 -398.987805) (xy 342.948947 -399.050886) (xy 342.923198 -399.111054) (xy 342.906858 -399.13941)
			(xy 342.903491 -399.145424) (xy 342.899757 -399.158685) (xy 342.899492 -399.165572) (xy 342.899492 -399.451576)
			(xy 342.899064 -399.461698) (xy 342.891323 -399.480403) (xy 342.877009 -399.494718) (xy 342.858306 -399.502463)
			(xy 342.848184 -399.502884) (xy 342.131904 -399.502884) (xy 342.12178 -399.50248) (xy 342.103073 -399.494731)
			(xy 342.088758 -399.48041) (xy 342.081016 -399.4617) (xy 342.080596 -399.451576) (xy 342.080596 -399.165572)
			(xy 342.080336 -399.158683) (xy 342.076612 -399.145417) (xy 342.07323 -399.13941) (xy 342.056923 -399.111037)
			(xy 342.031177 -399.050874) (xy 342.013748 -398.987797) (xy 342.004951 -398.922951) (xy 342.004947 -398.857511)
			(xy 342.013735 -398.792663) (xy 342.031157 -398.729584) (xy 342.056895 -398.669418) (xy 342.07323 -398.641062)
			(xy 342.076606 -398.635053) (xy 342.080334 -398.621788) (xy 342.080596 -398.6149) (xy 342.080596 -397.865346)
			(xy 342.080346 -397.858456) (xy 342.076615 -397.84519) (xy 342.07323 -397.839184) (xy 342.056901 -397.810823)
			(xy 342.031157 -397.750657) (xy 342.01373 -397.687578) (xy 342.004936 -397.62273) (xy 342.004935 -397.557287)
			(xy 340.71633 -397.557287) (xy 340.723269 -397.569362) (xy 340.749016 -397.629525) (xy 340.766446 -397.692601)
			(xy 340.775243 -397.757447) (xy 340.775247 -397.822888) (xy 340.766459 -397.887735) (xy 340.749037 -397.950814)
			(xy 340.723299 -398.01098) (xy 340.706964 -398.039336) (xy 340.703641 -398.045357) (xy 340.70004 -398.058623)
			(xy 340.699852 -398.065498) (xy 340.699852 -398.351502) (xy 340.699438 -398.361675) (xy 340.69165 -398.380472)
			(xy 340.677262 -398.394857) (xy 340.658463 -398.40264) (xy 340.64829 -398.403064) (xy 339.93201 -398.403064)
			(xy 339.921839 -398.402628) (xy 339.903045 -398.394847) (xy 339.88866 -398.380465) (xy 339.880874 -398.361673)
			(xy 339.880448 -398.351502) (xy 339.880448 -398.065498) (xy 339.880263 -398.058624) (xy 339.876651 -398.045361)
			(xy 339.873336 -398.039336) (xy 339.856967 -398.010998) (xy 339.831226 -397.950827) (xy 339.813803 -397.887743)
			(xy 339.805014 -397.82289) (xy 338.516205 -397.82289) (xy 338.506816 -397.839184) (xy 338.503508 -397.845212)
			(xy 338.499898 -397.858473) (xy 338.499704 -397.865346) (xy 338.499704 -398.6149) (xy 338.499895 -398.621773)
			(xy 338.503504 -398.635036) (xy 338.506816 -398.641062) (xy 338.523185 -398.669401) (xy 338.548929 -398.729571)
			(xy 338.566353 -398.792655) (xy 338.575143 -398.857508) (xy 338.575139 -398.922954) (xy 338.566341 -398.987806)
			(xy 338.548908 -399.050887) (xy 338.523157 -399.111054) (xy 338.506816 -399.13941) (xy 338.503499 -399.145433)
			(xy 338.499894 -399.158698) (xy 338.499704 -399.165572) (xy 338.499704 -399.451576) (xy 338.499259 -399.461728)
			(xy 338.491472 -399.480479) (xy 338.477082 -399.494803) (xy 338.458296 -399.502505) (xy 338.448142 -399.502884)
			(xy 337.731862 -399.502884) (xy 337.721736 -399.502405) (xy 337.703018 -399.494669) (xy 337.688664 -399.480381)
			(xy 337.680842 -399.4617) (xy 337.6803 -399.451576) (xy 337.6803 -399.165572) (xy 337.680119 -399.158698)
			(xy 337.676503 -399.145435) (xy 337.673188 -399.13941) (xy 337.65688 -399.111038) (xy 337.63113 -399.050875)
			(xy 337.613699 -398.987798) (xy 337.604901 -398.922951) (xy 337.604897 -398.85751) (xy 337.613686 -398.792662)
			(xy 337.63111 -398.729583) (xy 337.656852 -398.669418) (xy 337.673188 -398.641062) (xy 337.676515 -398.635044)
			(xy 337.680113 -398.621775) (xy 337.6803 -398.6149) (xy 337.6803 -397.865346) (xy 337.68009 -397.858474)
			(xy 337.676494 -397.845211) (xy 337.673188 -397.839184) (xy 337.656858 -397.810824) (xy 337.63111 -397.750658)
			(xy 337.613681 -397.687579) (xy 337.604886 -397.62273) (xy 337.604885 -397.557287) (xy 336.316289 -397.557287)
			(xy 336.323228 -397.569362) (xy 336.348977 -397.629524) (xy 336.366409 -397.6926) (xy 336.375206 -397.757447)
			(xy 336.375211 -397.822888) (xy 336.366422 -397.887736) (xy 336.348999 -397.950815) (xy 336.323258 -398.01098)
			(xy 336.306922 -398.039336) (xy 336.303543 -398.045344) (xy 336.299817 -398.05861) (xy 336.299556 -398.065498)
			(xy 336.299556 -398.351502) (xy 336.299075 -398.361629) (xy 336.291346 -398.380351) (xy 336.277058 -398.394708)
			(xy 336.258373 -398.402526) (xy 336.248248 -398.403064) (xy 335.531968 -398.403064) (xy 335.521807 -398.402704)
			(xy 335.503047 -398.394891) (xy 335.488724 -398.380475) (xy 335.481032 -398.361665) (xy 335.48066 -398.351502)
			(xy 335.48066 -398.065498) (xy 335.480433 -398.058606) (xy 335.476687 -398.04534) (xy 335.473294 -398.039336)
			(xy 335.456926 -398.010997) (xy 335.431187 -397.950826) (xy 335.413766 -397.887742) (xy 335.404978 -397.82289)
			(xy 334.116162 -397.82289) (xy 334.106774 -397.839184) (xy 334.103417 -397.845203) (xy 334.099677 -397.85846)
			(xy 334.099408 -397.865346) (xy 334.099408 -398.6149) (xy 334.09964 -398.621791) (xy 334.103383 -398.635057)
			(xy 334.106774 -398.641062) (xy 334.123141 -398.669401) (xy 334.148882 -398.729572) (xy 334.166304 -398.792656)
			(xy 334.175093 -398.857508) (xy 334.175089 -398.922953) (xy 334.166292 -398.987805) (xy 334.148861 -399.050886)
			(xy 334.123113 -399.111054) (xy 334.106774 -399.13941) (xy 334.103408 -399.145424) (xy 334.099673 -399.158685)
			(xy 334.099408 -399.165572) (xy 334.099408 -399.451576) (xy 334.098965 -399.461696) (xy 334.091226 -399.480398)
			(xy 334.076918 -399.494712) (xy 334.05822 -399.50246) (xy 334.0481 -399.502884) (xy 333.33182 -399.502884)
			(xy 333.321697 -399.502467) (xy 333.302991 -399.494723) (xy 333.288675 -399.480406) (xy 333.280932 -399.461699)
			(xy 333.280512 -399.451576) (xy 333.280512 -399.165572) (xy 333.280284 -399.158679) (xy 333.276553 -399.145407)
			(xy 333.273146 -399.13941) (xy 333.256839 -399.111037) (xy 333.231092 -399.050874) (xy 333.213662 -398.987798)
			(xy 333.204865 -398.922951) (xy 333.204861 -398.857511) (xy 333.213649 -398.792663) (xy 333.231071 -398.729584)
			(xy 333.256811 -398.669418) (xy 333.273146 -398.641062) (xy 333.276523 -398.635053) (xy 333.28025 -398.621788)
			(xy 333.280512 -398.6149) (xy 333.280512 -397.865346) (xy 333.280294 -397.858452) (xy 333.276556 -397.84518)
			(xy 333.273146 -397.839184) (xy 333.256817 -397.810823) (xy 333.231072 -397.750658) (xy 333.213644 -397.687579)
			(xy 333.20485 -397.62273) (xy 333.204849 -397.557287) (xy 331.916246 -397.557287) (xy 331.923185 -397.569362)
			(xy 331.94893 -397.629525) (xy 331.96636 -397.692601) (xy 331.975156 -397.757447) (xy 331.975161 -397.822887)
			(xy 331.966373 -397.887735) (xy 331.948952 -397.950813) (xy 331.923214 -398.01098) (xy 331.90688 -398.039336)
			(xy 331.903551 -398.045354) (xy 331.899955 -398.058623) (xy 331.899768 -398.065498) (xy 331.899768 -398.351502)
			(xy 331.899268 -398.361659) (xy 331.891494 -398.380427) (xy 331.877131 -398.394792) (xy 331.858363 -398.402568)
			(xy 331.848206 -398.403064) (xy 331.131926 -398.403064) (xy 331.121756 -398.402615) (xy 331.102963 -398.394839)
			(xy 331.088577 -398.380461) (xy 331.080791 -398.361671) (xy 331.080364 -398.351502) (xy 331.080364 -398.065498)
			(xy 331.080177 -398.058624) (xy 331.076566 -398.045361) (xy 331.073252 -398.039336) (xy 331.056882 -398.010998)
			(xy 331.03114 -397.950827) (xy 331.013717 -397.887743) (xy 331.004928 -397.82289) (xy 326.525636 -397.82289)
			(xy 326.525636 -401.722803) (xy 331.004937 -401.722803) (xy 331.00494 -401.657359) (xy 331.013735 -401.592508)
			(xy 331.031165 -401.529427) (xy 331.056913 -401.46926) (xy 331.073252 -401.440904) (xy 331.076561 -401.434877)
			(xy 331.080171 -401.421615) (xy 331.080364 -401.414742) (xy 331.080364 -400.665442) (xy 331.08016 -400.65857)
			(xy 331.076561 -400.645307) (xy 331.073252 -400.63928) (xy 331.056919 -400.610921) (xy 331.031174 -400.550755)
			(xy 331.013747 -400.487676) (xy 331.004953 -400.422826) (xy 331.004952 -400.357384) (xy 331.013745 -400.292534)
			(xy 331.031171 -400.229455) (xy 331.056915 -400.169288) (xy 331.073252 -400.140932) (xy 331.076552 -400.1349)
			(xy 331.080167 -400.121642) (xy 331.080364 -400.11477) (xy 331.080364 -399.828766) (xy 331.080806 -399.818603)
			(xy 331.088597 -399.799828) (xy 331.102978 -399.785463) (xy 331.121762 -399.777694) (xy 331.131926 -399.777204)
			(xy 331.848206 -399.777204) (xy 331.85836 -399.777728) (xy 331.877123 -399.785498) (xy 331.891486 -399.799854)
			(xy 331.899267 -399.818612) (xy 331.899768 -399.828766) (xy 331.899768 -400.11477) (xy 331.899975 -400.121642)
			(xy 331.903573 -400.134905) (xy 331.90688 -400.140932) (xy 331.923222 -400.169286) (xy 331.948964 -400.229453)
			(xy 331.966389 -400.292534) (xy 331.975181 -400.357384) (xy 331.975181 -400.422827) (xy 331.966387 -400.487676)
			(xy 331.948961 -400.550757) (xy 331.923217 -400.610924) (xy 331.90688 -400.63928) (xy 331.903571 -400.645307)
			(xy 331.899962 -400.658569) (xy 331.899768 -400.665442) (xy 331.899768 -401.414742) (xy 331.899986 -401.421613)
			(xy 331.903577 -401.434876) (xy 331.90688 -401.440904) (xy 331.923198 -401.469271) (xy 331.948943 -401.529435)
			(xy 331.966371 -401.592513) (xy 331.975165 -401.657361) (xy 331.975168 -401.722802) (xy 331.966378 -401.78765)
			(xy 331.948955 -401.850729) (xy 331.923215 -401.910896) (xy 331.90688 -401.939252) (xy 331.903545 -401.945267)
			(xy 331.899953 -401.958538) (xy 331.899768 -401.965414) (xy 331.899768 -402.251418) (xy 331.899282 -402.261576)
			(xy 331.891502 -402.280345) (xy 331.877135 -402.294709) (xy 331.858364 -402.302484) (xy 331.848206 -402.30298)
			(xy 331.131926 -402.30298) (xy 331.121758 -402.302515) (xy 331.102968 -402.294742) (xy 331.088583 -402.280369)
			(xy 331.080794 -402.261585) (xy 331.080364 -402.251418) (xy 331.080364 -401.965414) (xy 331.080171 -401.958541)
			(xy 331.076564 -401.945278) (xy 331.073252 -401.939252) (xy 331.056896 -401.910906) (xy 331.031153 -401.850737)
			(xy 331.013728 -401.787655) (xy 331.004937 -401.722803) (xy 326.525636 -401.722803) (xy 326.525636 -402.822882)
			(xy 333.204817 -402.822882) (xy 333.204823 -402.757436) (xy 333.213622 -402.692584) (xy 333.231055 -402.629502)
			(xy 333.256805 -402.569334) (xy 333.273146 -402.540978) (xy 333.276517 -402.534967) (xy 333.280248 -402.521703)
			(xy 333.280512 -402.514816) (xy 333.280512 -401.765516) (xy 333.280306 -401.758621) (xy 333.27656 -401.745349)
			(xy 333.273146 -401.739354) (xy 333.256791 -401.711007) (xy 333.231049 -401.650838) (xy 333.213624 -401.587756)
			(xy 333.204833 -401.522905) (xy 333.204835 -401.457461) (xy 333.213631 -401.39261) (xy 333.23106 -401.329529)
			(xy 333.256807 -401.269362) (xy 333.273146 -401.241006) (xy 333.276508 -401.23499) (xy 333.280245 -401.22173)
			(xy 333.280512 -401.214844) (xy 333.280512 -400.92884) (xy 333.280949 -400.918719) (xy 333.288686 -400.900014)
			(xy 333.302997 -400.885698) (xy 333.321699 -400.877953) (xy 333.33182 -400.877532) (xy 334.0481 -400.877532)
			(xy 334.058226 -400.877917) (xy 334.076936 -400.885671) (xy 334.091252 -400.899997) (xy 334.098991 -400.918713)
			(xy 334.099408 -400.92884) (xy 334.099408 -401.214844) (xy 334.099662 -401.221734) (xy 334.10339 -401.235)
			(xy 334.106774 -401.241006) (xy 334.123094 -401.269372) (xy 334.148839 -401.329536) (xy 334.166267 -401.392614)
			(xy 334.175061 -401.457462) (xy 334.175064 -401.522904) (xy 334.166274 -401.587752) (xy 334.14885 -401.650831)
			(xy 334.12311 -401.710998) (xy 334.116309 -401.722803) (xy 335.404987 -401.722803) (xy 335.40499 -401.657359)
			(xy 335.413784 -401.592509) (xy 335.431212 -401.529428) (xy 335.456957 -401.469261) (xy 335.473294 -401.440904)
			(xy 335.476652 -401.434886) (xy 335.480392 -401.421628) (xy 335.48066 -401.414742) (xy 335.48066 -400.665442)
			(xy 335.480438 -400.658548) (xy 335.476702 -400.645276) (xy 335.473294 -400.63928) (xy 335.456963 -400.610921)
			(xy 335.431221 -400.550754) (xy 335.413796 -400.487675) (xy 335.405003 -400.422826) (xy 335.405002 -400.357384)
			(xy 335.413794 -400.292535) (xy 335.431218 -400.229456) (xy 335.456958 -400.169289) (xy 335.473294 -400.140932)
			(xy 335.476643 -400.134909) (xy 335.480389 -400.121655) (xy 335.48066 -400.11477) (xy 335.48066 -399.828766)
			(xy 335.481099 -399.818635) (xy 335.488842 -399.799909) (xy 335.503143 -399.785553) (xy 335.521839 -399.777739)
			(xy 335.531968 -399.777204) (xy 336.248248 -399.777204) (xy 336.258406 -399.777583) (xy 336.27716 -399.785395)
			(xy 336.291482 -399.799804) (xy 336.299179 -399.818606) (xy 336.299556 -399.828766) (xy 336.299556 -400.11477)
			(xy 336.299771 -400.121664) (xy 336.303512 -400.134936) (xy 336.306922 -400.140932) (xy 336.323266 -400.169285)
			(xy 336.349011 -400.229452) (xy 336.366438 -400.292533) (xy 336.375232 -400.357383) (xy 336.375231 -400.422827)
			(xy 336.366436 -400.487677) (xy 336.349008 -400.550758) (xy 336.323261 -400.610924) (xy 336.306922 -400.63928)
			(xy 336.303563 -400.645297) (xy 336.299824 -400.658556) (xy 336.299556 -400.665442) (xy 336.299556 -401.414742)
			(xy 336.299782 -401.421635) (xy 336.303515 -401.434907) (xy 336.306922 -401.440904) (xy 336.323242 -401.46927)
			(xy 336.34899 -401.529434) (xy 336.36642 -401.592512) (xy 336.375216 -401.65736) (xy 336.375218 -401.722802)
			(xy 336.366427 -401.787651) (xy 336.349002 -401.85073) (xy 336.323259 -401.910896) (xy 336.306922 -401.939252)
			(xy 336.303537 -401.945257) (xy 336.299815 -401.958525) (xy 336.299556 -401.965414) (xy 336.299556 -402.251418)
			(xy 336.299088 -402.261546) (xy 336.291354 -402.280269) (xy 336.277062 -402.294625) (xy 336.258374 -402.302443)
			(xy 336.248248 -402.30298) (xy 335.531968 -402.30298) (xy 335.521809 -402.302604) (xy 335.503052 -402.294794)
			(xy 335.488729 -402.280384) (xy 335.481034 -402.261579) (xy 335.48066 -402.251418) (xy 335.48066 -401.965414)
			(xy 335.480449 -401.95852) (xy 335.476705 -401.945248) (xy 335.473294 -401.939252) (xy 335.456939 -401.910906)
			(xy 335.4312 -401.850736) (xy 335.413777 -401.787654) (xy 335.404987 -401.722803) (xy 334.116309 -401.722803)
			(xy 334.106774 -401.739354) (xy 334.103393 -401.745361) (xy 334.099668 -401.758627) (xy 334.099408 -401.765516)
			(xy 334.099408 -402.514816) (xy 334.099673 -402.521705) (xy 334.103394 -402.534971) (xy 334.106774 -402.540978)
			(xy 334.12307 -402.569357) (xy 334.148817 -402.629518) (xy 334.166248 -402.692594) (xy 334.175045 -402.757439)
			(xy 334.175051 -402.822879) (xy 334.175051 -402.822882) (xy 337.604853 -402.822882) (xy 337.604859 -402.757435)
			(xy 337.613659 -402.692583) (xy 337.631093 -402.629501) (xy 337.656846 -402.569334) (xy 337.673188 -402.540978)
			(xy 337.67651 -402.534957) (xy 337.680111 -402.52169) (xy 337.6803 -402.514816) (xy 337.6803 -401.765516)
			(xy 337.680102 -401.758643) (xy 337.676498 -401.74538) (xy 337.673188 -401.739354) (xy 337.656832 -401.711008)
			(xy 337.631087 -401.650839) (xy 337.613661 -401.587757) (xy 337.604869 -401.522905) (xy 337.604871 -401.45746)
			(xy 337.613668 -401.392609) (xy 337.631099 -401.329528) (xy 337.656848 -401.269362) (xy 337.673188 -401.241006)
			(xy 337.6765 -401.23498) (xy 337.680108 -401.221717) (xy 337.6803 -401.214844) (xy 337.6803 -400.92884)
			(xy 337.680755 -400.918688) (xy 337.688537 -400.899937) (xy 337.702924 -400.885612) (xy 337.721709 -400.877911)
			(xy 337.731862 -400.877532) (xy 338.448142 -400.877532) (xy 338.45827 -400.877992) (xy 338.476991 -400.885732)
			(xy 338.491346 -400.900026) (xy 338.499165 -400.918714) (xy 338.499704 -400.92884) (xy 338.499704 -401.214844)
			(xy 338.499917 -401.221716) (xy 338.503511 -401.234978) (xy 338.506816 -401.241006) (xy 338.523138 -401.269371)
			(xy 338.548886 -401.329535) (xy 338.566316 -401.392613) (xy 338.575112 -401.457462) (xy 338.575114 -401.522904)
			(xy 338.566323 -401.587753) (xy 338.548897 -401.650832) (xy 338.523153 -401.710998) (xy 338.516352 -401.722803)
			(xy 339.805023 -401.722803) (xy 339.805026 -401.657359) (xy 339.813821 -401.592508) (xy 339.831251 -401.529427)
			(xy 339.856997 -401.46926) (xy 339.873336 -401.440904) (xy 339.876644 -401.434876) (xy 339.880255 -401.421615)
			(xy 339.880448 -401.414742) (xy 339.880448 -400.665442) (xy 339.880247 -400.658569) (xy 339.876646 -400.645306)
			(xy 339.873336 -400.63928) (xy 339.857004 -400.610921) (xy 339.83126 -400.550755) (xy 339.813833 -400.487675)
			(xy 339.805039 -400.422826) (xy 339.805038 -400.357384) (xy 339.813831 -400.292535) (xy 339.831256 -400.229455)
			(xy 339.856999 -400.169288) (xy 339.873336 -400.140932) (xy 339.876634 -400.134899) (xy 339.880251 -400.121642)
			(xy 339.880448 -400.11477) (xy 339.880448 -399.828766) (xy 339.880906 -399.818605) (xy 339.888693 -399.799833)
			(xy 339.90307 -399.785469) (xy 339.921848 -399.777697) (xy 339.93201 -399.777204) (xy 340.64829 -399.777204)
			(xy 340.658443 -399.777741) (xy 340.677205 -399.785506) (xy 340.69157 -399.799858) (xy 340.699351 -399.818613)
			(xy 340.699852 -399.828766) (xy 340.699852 -400.11477) (xy 340.700049 -400.121643) (xy 340.703653 -400.134906)
			(xy 340.706964 -400.140932) (xy 340.723306 -400.169285) (xy 340.74905 -400.229453) (xy 340.766475 -400.292533)
			(xy 340.775268 -400.357383) (xy 340.775267 -400.422827) (xy 340.766473 -400.487677) (xy 340.749046 -400.550757)
			(xy 340.723302 -400.610924) (xy 340.706964 -400.63928) (xy 340.703661 -400.645311) (xy 340.700047 -400.65857)
			(xy 340.699852 -400.665442) (xy 340.699852 -401.414742) (xy 340.700059 -401.421614) (xy 340.703656 -401.434877)
			(xy 340.706964 -401.440904) (xy 340.723283 -401.46927) (xy 340.749028 -401.529435) (xy 340.766456 -401.592513)
			(xy 340.775252 -401.65736) (xy 340.775254 -401.722802) (xy 340.766464 -401.78765) (xy 340.749041 -401.850729)
			(xy 340.7233 -401.910896) (xy 340.706964 -401.939252) (xy 340.703636 -401.94527) (xy 340.700038 -401.958539)
			(xy 340.699852 -401.965414) (xy 340.699852 -402.251418) (xy 340.699381 -402.261578) (xy 340.691599 -402.28035)
			(xy 340.677226 -402.294715) (xy 340.65845 -402.302487) (xy 340.64829 -402.30298) (xy 339.93201 -402.30298)
			(xy 339.921855 -402.302459) (xy 339.90309 -402.294691) (xy 339.888725 -402.280334) (xy 339.880947 -402.261573)
			(xy 339.880448 -402.251418) (xy 339.880448 -401.965414) (xy 339.880257 -401.958541) (xy 339.876649 -401.945278)
			(xy 339.873336 -401.939252) (xy 339.85698 -401.910906) (xy 339.831238 -401.850737) (xy 339.813814 -401.787655)
			(xy 339.805023 -401.722803) (xy 338.516352 -401.722803) (xy 338.506816 -401.739354) (xy 338.503519 -401.745387)
			(xy 338.499902 -401.758644) (xy 338.499704 -401.765516) (xy 338.499704 -402.514816) (xy 338.499889 -402.52169)
			(xy 338.503502 -402.534953) (xy 338.506816 -402.540978) (xy 338.523114 -402.569356) (xy 338.548864 -402.629517)
			(xy 338.566297 -402.692593) (xy 338.575096 -402.757439) (xy 338.575101 -402.822879) (xy 338.575101 -402.822882)
			(xy 342.004903 -402.822882) (xy 342.004909 -402.757436) (xy 342.013708 -402.692584) (xy 342.03114 -402.629502)
			(xy 342.05689 -402.569334) (xy 342.07323 -402.540978) (xy 342.0766 -402.534966) (xy 342.080332 -402.521703)
			(xy 342.080596 -402.514816) (xy 342.080596 -401.765516) (xy 342.080357 -401.758625) (xy 342.076619 -401.745359)
			(xy 342.07323 -401.739354) (xy 342.056876 -401.711007) (xy 342.031134 -401.650838) (xy 342.01371 -401.587756)
			(xy 342.004919 -401.522905) (xy 342.004922 -401.457461) (xy 342.013717 -401.39261) (xy 342.031145 -401.329529)
			(xy 342.056892 -401.269362) (xy 342.07323 -401.241006) (xy 342.07659 -401.234989) (xy 342.080328 -401.22173)
			(xy 342.080596 -401.214844) (xy 342.080596 -400.92884) (xy 342.081049 -400.918721) (xy 342.088783 -400.900019)
			(xy 342.103088 -400.885703) (xy 342.121785 -400.877956) (xy 342.131904 -400.877532) (xy 342.848184 -400.877532)
			(xy 342.858309 -400.87793) (xy 342.877019 -400.885679) (xy 342.891335 -400.900001) (xy 342.899075 -400.918714)
			(xy 342.899492 -400.92884) (xy 342.899492 -401.214844) (xy 342.899748 -401.221734) (xy 342.903475 -401.234999)
			(xy 342.906858 -401.241006) (xy 342.923179 -401.269371) (xy 342.948924 -401.329536) (xy 342.966353 -401.392614)
			(xy 342.975148 -401.457462) (xy 342.97515 -401.522904) (xy 342.966359 -401.587752) (xy 342.948936 -401.650832)
			(xy 342.923194 -401.710998) (xy 342.916393 -401.722803) (xy 344.204813 -401.722803) (xy 344.204815 -401.657359)
			(xy 344.213611 -401.592508) (xy 344.23104 -401.529428) (xy 344.256786 -401.46926) (xy 344.273124 -401.440904)
			(xy 344.276439 -401.43488) (xy 344.280044 -401.421616) (xy 344.280236 -401.414742) (xy 344.280236 -400.665442)
			(xy 344.280024 -400.65857) (xy 344.276429 -400.645308) (xy 344.273124 -400.63928) (xy 344.256792 -400.610921)
			(xy 344.231049 -400.550755) (xy 344.213622 -400.487675) (xy 344.204829 -400.422826) (xy 344.204828 -400.357384)
			(xy 344.21362 -400.292535) (xy 344.231045 -400.229455) (xy 344.256787 -400.169288) (xy 344.273124 -400.140932)
			(xy 344.276429 -400.134903) (xy 344.28004 -400.121643) (xy 344.280236 -400.11477) (xy 344.280236 -399.828766)
			(xy 344.280705 -399.818606) (xy 344.288491 -399.799837) (xy 344.302864 -399.785473) (xy 344.321638 -399.777699)
			(xy 344.331798 -399.777204) (xy 345.048078 -399.777204) (xy 345.05823 -399.77775) (xy 345.076992 -399.785511)
			(xy 345.091357 -399.799861) (xy 345.099139 -399.818614) (xy 345.09964 -399.828766) (xy 345.09964 -400.11477)
			(xy 345.099838 -400.121643) (xy 345.103442 -400.134906) (xy 345.106752 -400.140932) (xy 345.123095 -400.169285)
			(xy 345.148839 -400.229453) (xy 345.166265 -400.292533) (xy 345.175057 -400.357383) (xy 345.175057 -400.390106)
			(xy 348.603832 -400.390106) (xy 348.607823 -400.327939) (xy 348.619732 -400.266792) (xy 348.639361 -400.207671)
			(xy 348.66639 -400.151545) (xy 348.700374 -400.099336) (xy 348.740756 -400.051901) (xy 348.786872 -400.01002)
			(xy 348.837964 -399.97438) (xy 348.893195 -399.945566) (xy 348.951657 -399.924052) (xy 349.012391 -399.91019)
			(xy 349.074398 -399.904208) (xy 349.136661 -399.906204) (xy 349.198158 -399.916147) (xy 349.257879 -399.933871)
			(xy 349.314842 -399.959088) (xy 349.368113 -399.991381) (xy 349.416818 -400.030221) (xy 349.460155 -400.074971)
			(xy 349.497415 -400.124895) (xy 349.527984 -400.179174) (xy 349.551362 -400.236917) (xy 349.567163 -400.297175)
			(xy 349.575129 -400.358958) (xy 349.575628 -400.390106) (xy 349.575129 -400.421254) (xy 349.567163 -400.483037)
			(xy 349.551362 -400.543295) (xy 349.527984 -400.601038) (xy 349.497415 -400.655317) (xy 349.460155 -400.705241)
			(xy 349.416818 -400.749991) (xy 349.368113 -400.788831) (xy 349.314842 -400.821124) (xy 349.257879 -400.846341)
			(xy 349.198158 -400.864065) (xy 349.136661 -400.874008) (xy 349.074398 -400.876004) (xy 349.012391 -400.870022)
			(xy 348.951657 -400.85616) (xy 348.893195 -400.834646) (xy 348.837964 -400.805832) (xy 348.786872 -400.770192)
			(xy 348.740756 -400.728311) (xy 348.700374 -400.680876) (xy 348.66639 -400.628667) (xy 348.639361 -400.572541)
			(xy 348.619732 -400.51342) (xy 348.607823 -400.452273) (xy 348.603832 -400.390106) (xy 345.175057 -400.390106)
			(xy 345.175057 -400.422827) (xy 345.166263 -400.487677) (xy 345.148835 -400.550757) (xy 345.12309 -400.610924)
			(xy 345.106752 -400.63928) (xy 345.103449 -400.64531) (xy 345.099835 -400.65857) (xy 345.09964 -400.665442)
			(xy 345.09964 -401.414742) (xy 345.099849 -401.421614) (xy 345.103445 -401.434877) (xy 345.106752 -401.440904)
			(xy 345.123071 -401.46927) (xy 345.148817 -401.529435) (xy 345.166246 -401.592513) (xy 345.175041 -401.65736)
			(xy 345.175044 -401.722802) (xy 345.166254 -401.78765) (xy 345.14883 -401.85073) (xy 345.123088 -401.910896)
			(xy 345.106752 -401.939252) (xy 345.103423 -401.94527) (xy 345.099826 -401.958539) (xy 345.09964 -401.965414)
			(xy 345.09964 -402.251418) (xy 345.09925 -402.261593) (xy 345.091455 -402.280393) (xy 345.077059 -402.294778)
			(xy 345.058254 -402.302558) (xy 345.048078 -402.30298) (xy 344.331798 -402.30298) (xy 344.321642 -402.302469)
			(xy 344.302877 -402.294697) (xy 344.288512 -402.280337) (xy 344.280735 -402.261574) (xy 344.280236 -402.251418)
			(xy 344.280236 -401.965414) (xy 344.280034 -401.958542) (xy 344.276432 -401.945279) (xy 344.273124 -401.939252)
			(xy 344.256768 -401.910906) (xy 344.231027 -401.850737) (xy 344.213603 -401.787655) (xy 344.204813 -401.722803)
			(xy 342.916393 -401.722803) (xy 342.906858 -401.739354) (xy 342.903476 -401.74536) (xy 342.899752 -401.758627)
			(xy 342.899492 -401.765516) (xy 342.899492 -402.514816) (xy 342.899759 -402.521705) (xy 342.903478 -402.534971)
			(xy 342.906858 -402.540978) (xy 342.923155 -402.569357) (xy 342.948903 -402.629518) (xy 342.966334 -402.692593)
			(xy 342.975132 -402.757439) (xy 342.975137 -402.822879) (xy 342.975137 -402.822882) (xy 346.404939 -402.822882)
			(xy 346.404945 -402.757436) (xy 346.413744 -402.692583) (xy 346.431178 -402.629501) (xy 346.45693 -402.569334)
			(xy 346.473272 -402.540978) (xy 346.476593 -402.534956) (xy 346.480195 -402.52169) (xy 346.480384 -402.514816)
			(xy 346.480384 -401.765516) (xy 346.480188 -401.758643) (xy 346.476583 -401.74538) (xy 346.473272 -401.739354)
			(xy 346.456917 -401.711008) (xy 346.431173 -401.650839) (xy 346.413747 -401.587757) (xy 346.404955 -401.522905)
			(xy 346.404958 -401.45746) (xy 346.413754 -401.39261) (xy 346.431184 -401.329529) (xy 346.456932 -401.269362)
			(xy 346.473272 -401.241006) (xy 346.476583 -401.234979) (xy 346.480191 -401.221717) (xy 346.480384 -401.214844)
			(xy 346.480384 -400.92884) (xy 346.480854 -400.91869) (xy 346.488634 -400.899942) (xy 346.503015 -400.885618)
			(xy 346.521795 -400.877914) (xy 346.531946 -400.877532) (xy 347.248226 -400.877532) (xy 347.258353 -400.878005)
			(xy 347.277074 -400.88574) (xy 347.291429 -400.90003) (xy 347.299249 -400.918715) (xy 347.299788 -400.92884)
			(xy 347.299788 -401.214844) (xy 347.300003 -401.221716) (xy 347.303596 -401.234978) (xy 347.3069 -401.241006)
			(xy 347.323219 -401.269372) (xy 347.348963 -401.329537) (xy 347.366389 -401.392615) (xy 347.375184 -401.457462)
			(xy 347.375186 -401.522903) (xy 347.366396 -401.587751) (xy 347.348974 -401.650831) (xy 347.332184 -401.690078)
			(xy 348.603832 -401.690078) (xy 348.607823 -401.627911) (xy 348.619732 -401.566764) (xy 348.639361 -401.507643)
			(xy 348.66639 -401.451517) (xy 348.700374 -401.399308) (xy 348.740756 -401.351873) (xy 348.786872 -401.309992)
			(xy 348.837964 -401.274352) (xy 348.893195 -401.245538) (xy 348.951657 -401.224024) (xy 349.012391 -401.210162)
			(xy 349.074398 -401.20418) (xy 349.136661 -401.206176) (xy 349.198158 -401.216119) (xy 349.257879 -401.233843)
			(xy 349.314842 -401.25906) (xy 349.368113 -401.291353) (xy 349.416818 -401.330193) (xy 349.460155 -401.374943)
			(xy 349.497415 -401.424867) (xy 349.527984 -401.479146) (xy 349.532451 -401.49018) (xy 350.80398 -401.49018)
			(xy 350.807971 -401.428013) (xy 350.81988 -401.366866) (xy 350.839509 -401.307745) (xy 350.866538 -401.251619)
			(xy 350.900522 -401.19941) (xy 350.940904 -401.151975) (xy 350.98702 -401.110094) (xy 351.038112 -401.074454)
			(xy 351.093343 -401.04564) (xy 351.151805 -401.024126) (xy 351.212539 -401.010264) (xy 351.274546 -401.004282)
			(xy 351.336809 -401.006278) (xy 351.398306 -401.016221) (xy 351.458027 -401.033945) (xy 351.51499 -401.059162)
			(xy 351.568261 -401.091455) (xy 351.616966 -401.130295) (xy 351.660303 -401.175045) (xy 351.697563 -401.224969)
			(xy 351.728132 -401.279248) (xy 351.75151 -401.336991) (xy 351.767311 -401.397249) (xy 351.775277 -401.459032)
			(xy 351.775776 -401.49018) (xy 351.775277 -401.521328) (xy 351.767311 -401.583111) (xy 351.75151 -401.643369)
			(xy 351.728132 -401.701112) (xy 351.697563 -401.755391) (xy 351.660303 -401.805315) (xy 351.616966 -401.850065)
			(xy 351.568261 -401.888905) (xy 351.51499 -401.921198) (xy 351.458027 -401.946415) (xy 351.398306 -401.964139)
			(xy 351.336809 -401.974082) (xy 351.274546 -401.976078) (xy 351.212539 -401.970096) (xy 351.151805 -401.956234)
			(xy 351.093343 -401.93472) (xy 351.038112 -401.905906) (xy 350.98702 -401.870266) (xy 350.940904 -401.828385)
			(xy 350.900522 -401.78095) (xy 350.866538 -401.728741) (xy 350.839509 -401.672615) (xy 350.81988 -401.613494)
			(xy 350.807971 -401.552347) (xy 350.80398 -401.49018) (xy 349.532451 -401.49018) (xy 349.551362 -401.536889)
			(xy 349.567163 -401.597147) (xy 349.575129 -401.65893) (xy 349.575628 -401.690078) (xy 349.575129 -401.721226)
			(xy 349.567163 -401.783009) (xy 349.551362 -401.843267) (xy 349.527984 -401.90101) (xy 349.497415 -401.955289)
			(xy 349.460155 -402.005213) (xy 349.416818 -402.049963) (xy 349.368113 -402.088803) (xy 349.314842 -402.121096)
			(xy 349.257879 -402.146313) (xy 349.198158 -402.164037) (xy 349.136661 -402.17398) (xy 349.074398 -402.175976)
			(xy 349.012391 -402.169994) (xy 348.951657 -402.156132) (xy 348.893195 -402.134618) (xy 348.837964 -402.105804)
			(xy 348.786872 -402.070164) (xy 348.740756 -402.028283) (xy 348.700374 -401.980848) (xy 348.66639 -401.928639)
			(xy 348.639361 -401.872513) (xy 348.619732 -401.813392) (xy 348.607823 -401.752245) (xy 348.603832 -401.690078)
			(xy 347.332184 -401.690078) (xy 347.323235 -401.710997) (xy 347.3069 -401.739354) (xy 347.303602 -401.745387)
			(xy 347.299986 -401.758644) (xy 347.299788 -401.765516) (xy 347.299788 -402.514816) (xy 347.299975 -402.52169)
			(xy 347.303587 -402.534952) (xy 347.3069 -402.540978) (xy 347.323195 -402.569357) (xy 347.348941 -402.629519)
			(xy 347.366371 -402.692594) (xy 347.375168 -402.757439) (xy 347.37517 -402.790152) (xy 350.80398 -402.790152)
			(xy 350.807971 -402.727985) (xy 350.81988 -402.666838) (xy 350.839509 -402.607717) (xy 350.866538 -402.551591)
			(xy 350.900522 -402.499382) (xy 350.940904 -402.451947) (xy 350.98702 -402.410066) (xy 351.038112 -402.374426)
			(xy 351.093343 -402.345612) (xy 351.151805 -402.324098) (xy 351.212539 -402.310236) (xy 351.274546 -402.304254)
			(xy 351.336809 -402.30625) (xy 351.398306 -402.316193) (xy 351.458027 -402.333917) (xy 351.51499 -402.359134)
			(xy 351.568261 -402.391427) (xy 351.616966 -402.430267) (xy 351.660303 -402.475017) (xy 351.697563 -402.524941)
			(xy 351.728132 -402.57922) (xy 351.75151 -402.636963) (xy 351.767311 -402.697221) (xy 351.775277 -402.759004)
			(xy 351.775776 -402.790152) (xy 351.775277 -402.8213) (xy 351.767311 -402.883083) (xy 351.75151 -402.943341)
			(xy 351.728132 -403.001084) (xy 351.697563 -403.055363) (xy 351.660303 -403.105287) (xy 351.616966 -403.150037)
			(xy 351.568261 -403.188877) (xy 351.51499 -403.22117) (xy 351.458027 -403.246387) (xy 351.398306 -403.264111)
			(xy 351.336809 -403.274054) (xy 351.274546 -403.27605) (xy 351.212539 -403.270068) (xy 351.151805 -403.256206)
			(xy 351.093343 -403.234692) (xy 351.038112 -403.205878) (xy 350.98702 -403.170238) (xy 350.940904 -403.128357)
			(xy 350.900522 -403.080922) (xy 350.866538 -403.028713) (xy 350.839509 -402.972587) (xy 350.81988 -402.913466)
			(xy 350.807971 -402.852319) (xy 350.80398 -402.790152) (xy 347.37517 -402.790152) (xy 347.375173 -402.822878)
			(xy 347.366387 -402.887725) (xy 347.348968 -402.950803) (xy 347.323233 -403.010969) (xy 347.3069 -403.039326)
			(xy 347.303576 -403.045346) (xy 347.299976 -403.058613) (xy 347.299788 -403.065488) (xy 347.299788 -403.351492)
			(xy 347.299372 -403.361647) (xy 347.291576 -403.380402) (xy 347.277178 -403.394726) (xy 347.258383 -403.402424)
			(xy 347.248226 -403.4028) (xy 346.531946 -403.4028) (xy 346.521827 -403.402237) (xy 346.503115 -403.394532)
			(xy 346.488758 -403.380269) (xy 346.48093 -403.361607) (xy 346.480384 -403.351492) (xy 346.480384 -403.065488)
			(xy 346.480199 -403.058614) (xy 346.476586 -403.045351) (xy 346.473272 -403.039326) (xy 346.456893 -403.010993)
			(xy 346.431151 -402.950821) (xy 346.413728 -402.887736) (xy 346.404939 -402.822882) (xy 342.975137 -402.822882)
			(xy 342.96635 -402.887726) (xy 342.94893 -402.950804) (xy 342.923192 -403.01097) (xy 342.906858 -403.039326)
			(xy 342.903486 -403.045337) (xy 342.899755 -403.0586) (xy 342.899492 -403.065488) (xy 342.899492 -403.351492)
			(xy 342.899077 -403.361615) (xy 342.89133 -403.38032) (xy 342.877013 -403.394635) (xy 342.858307 -403.402379)
			(xy 342.848184 -403.4028) (xy 342.131904 -403.4028) (xy 342.121782 -403.402381) (xy 342.103078 -403.394634)
			(xy 342.088764 -403.380318) (xy 342.081019 -403.361614) (xy 342.080596 -403.351492) (xy 342.080596 -403.065488)
			(xy 342.08033 -403.058599) (xy 342.07661 -403.045333) (xy 342.07323 -403.039326) (xy 342.056852 -403.010992)
			(xy 342.031113 -402.95082) (xy 342.013691 -402.887735) (xy 342.004903 -402.822882) (xy 338.575101 -402.822882)
			(xy 338.566313 -402.887726) (xy 338.548891 -402.950805) (xy 338.523152 -403.01097) (xy 338.506816 -403.039326)
			(xy 338.503493 -403.045347) (xy 338.499892 -403.058613) (xy 338.499704 -403.065488) (xy 338.499704 -403.351492)
			(xy 338.499272 -403.361645) (xy 338.49148 -403.380397) (xy 338.477086 -403.39472) (xy 338.458297 -403.402421)
			(xy 338.448142 -403.4028) (xy 337.731862 -403.4028) (xy 337.721738 -403.402306) (xy 337.703023 -403.394573)
			(xy 337.68867 -403.38029) (xy 337.680845 -403.361614) (xy 337.6803 -403.351492) (xy 337.6803 -403.065488)
			(xy 337.680113 -403.058614) (xy 337.676501 -403.045352) (xy 337.673188 -403.039326) (xy 337.656808 -403.010993)
			(xy 337.631066 -402.950821) (xy 337.613642 -402.887736) (xy 337.604853 -402.822882) (xy 334.175051 -402.822882)
			(xy 334.166264 -402.887725) (xy 334.148845 -402.950804) (xy 334.123108 -403.01097) (xy 334.106774 -403.039326)
			(xy 334.103403 -403.045338) (xy 334.099671 -403.058601) (xy 334.099408 -403.065488) (xy 334.099408 -403.351492)
			(xy 334.098978 -403.361613) (xy 334.091234 -403.380315) (xy 334.076922 -403.394629) (xy 334.058221 -403.402376)
			(xy 334.0481 -403.4028) (xy 333.33182 -403.4028) (xy 333.321699 -403.402368) (xy 333.302996 -403.394626)
			(xy 333.288681 -403.380315) (xy 333.280935 -403.361613) (xy 333.280512 -403.351492) (xy 333.280512 -403.065488)
			(xy 333.280278 -403.058595) (xy 333.276551 -403.045323) (xy 333.273146 -403.039326) (xy 333.256768 -403.010992)
			(xy 333.231027 -402.95082) (xy 333.213605 -402.887736) (xy 333.204817 -402.822882) (xy 326.525636 -402.822882)
			(xy 326.525636 -405.622717) (xy 331.004946 -405.622717) (xy 331.004947 -405.557273) (xy 331.013741 -405.492423)
			(xy 331.031168 -405.429343) (xy 331.056914 -405.369176) (xy 331.073252 -405.34082) (xy 331.076556 -405.33479)
			(xy 331.080169 -405.32153) (xy 331.080364 -405.314658) (xy 331.080364 -404.565358) (xy 331.080154 -404.558486)
			(xy 331.076559 -404.545223) (xy 331.073252 -404.539196) (xy 331.056933 -404.51083) (xy 331.031187 -404.450665)
			(xy 331.013758 -404.387587) (xy 331.004962 -404.32274) (xy 331.00496 -404.257298) (xy 331.01375 -404.19245)
			(xy 331.031174 -404.12937) (xy 331.056916 -404.069204) (xy 331.073252 -404.040848) (xy 331.076581 -404.03483)
			(xy 331.080178 -404.021561) (xy 331.080364 -404.014686) (xy 331.080364 -403.728682) (xy 331.08075 -403.718506)
			(xy 331.088546 -403.699706) (xy 331.102943 -403.685321) (xy 331.12175 -403.677541) (xy 331.131926 -403.67712)
			(xy 331.848206 -403.67712) (xy 331.858362 -403.677628) (xy 331.877128 -403.685401) (xy 331.891492 -403.699762)
			(xy 331.899269 -403.718526) (xy 331.899768 -403.728682) (xy 331.899768 -404.014686) (xy 331.899969 -404.021558)
			(xy 331.903572 -404.034821) (xy 331.90688 -404.040848) (xy 331.923235 -404.069194) (xy 331.948977 -404.129363)
			(xy 331.9664 -404.192446) (xy 331.975191 -404.257297) (xy 331.975188 -404.322741) (xy 331.966393 -404.387591)
			(xy 331.948964 -404.450672) (xy 331.923218 -404.51084) (xy 331.90688 -404.539196) (xy 331.903565 -404.545221)
			(xy 331.89996 -404.558484) (xy 331.899768 -404.565358) (xy 331.899768 -405.314658) (xy 331.89998 -405.32153)
			(xy 331.903575 -405.334792) (xy 331.90688 -405.34082) (xy 331.923212 -405.369179) (xy 331.948955 -405.429345)
			(xy 331.966381 -405.492425) (xy 331.975175 -405.557274) (xy 331.975175 -405.622716) (xy 331.966383 -405.687565)
			(xy 331.948958 -405.750645) (xy 331.923216 -405.810812) (xy 331.90688 -405.839168) (xy 331.903575 -405.845197)
			(xy 331.899964 -405.858458) (xy 331.899768 -405.86533) (xy 331.899768 -406.151334) (xy 331.899295 -406.161493)
			(xy 331.89151 -406.180262) (xy 331.877138 -406.194626) (xy 331.858365 -406.2024) (xy 331.848206 -406.202896)
			(xy 331.131926 -406.202896) (xy 331.121774 -406.202346) (xy 331.103012 -406.194587) (xy 331.088647 -406.180238)
			(xy 331.080865 -406.161485) (xy 331.080364 -406.151334) (xy 331.080364 -405.86533) (xy 331.080165 -405.858457)
			(xy 331.076562 -405.845194) (xy 331.073252 -405.839168) (xy 331.056909 -405.810815) (xy 331.031165 -405.750648)
			(xy 331.013739 -405.687567) (xy 331.004946 -405.622717) (xy 326.525636 -405.622717) (xy 326.525636 -406.722795)
			(xy 333.204826 -406.722795) (xy 333.20483 -406.65735) (xy 333.213627 -406.592499) (xy 333.231058 -406.529417)
			(xy 333.256806 -406.46925) (xy 333.273146 -406.440894) (xy 333.276512 -406.43488) (xy 333.280246 -406.421619)
			(xy 333.280512 -406.414732) (xy 333.280512 -405.665432) (xy 333.2803 -405.658538) (xy 333.276558 -405.645265)
			(xy 333.273146 -405.63927) (xy 333.256805 -405.610916) (xy 333.231061 -405.550749) (xy 333.213635 -405.487668)
			(xy 333.204842 -405.422818) (xy 333.204843 -405.357375) (xy 333.213636 -405.292525) (xy 333.231063 -405.229445)
			(xy 333.256808 -405.169278) (xy 333.273146 -405.140922) (xy 333.276502 -405.134903) (xy 333.280243 -405.121646)
			(xy 333.280512 -405.11476) (xy 333.280512 -404.828756) (xy 333.280949 -404.818643) (xy 333.288704 -404.799961)
			(xy 333.303015 -404.785668) (xy 333.321706 -404.777937) (xy 333.33182 -404.777448) (xy 334.0481 -404.777448)
			(xy 334.058202 -404.777984) (xy 334.076871 -404.785712) (xy 334.091163 -404.799993) (xy 334.098907 -404.818654)
			(xy 334.099408 -404.828756) (xy 334.099408 -405.11476) (xy 334.099656 -405.12165) (xy 334.103388 -405.134916)
			(xy 334.106774 -405.140922) (xy 334.123108 -405.16928) (xy 334.148851 -405.229447) (xy 334.166277 -405.292526)
			(xy 334.175071 -405.357375) (xy 334.175071 -405.422818) (xy 334.166279 -405.487667) (xy 334.148853 -405.550747)
			(xy 334.123111 -405.610914) (xy 334.116311 -405.622716) (xy 335.404996 -405.622716) (xy 335.404997 -405.557273)
			(xy 335.41379 -405.492424) (xy 335.431215 -405.429344) (xy 335.456958 -405.369177) (xy 335.473294 -405.34082)
			(xy 335.476647 -405.334799) (xy 335.48039 -405.321543) (xy 335.48066 -405.314658) (xy 335.48066 -404.565358)
			(xy 335.480432 -404.558465) (xy 335.4767 -404.545193) (xy 335.473294 -404.539196) (xy 335.456977 -404.510829)
			(xy 335.431233 -404.450664) (xy 335.413807 -404.387587) (xy 335.405012 -404.322739) (xy 335.40501 -404.257298)
			(xy 335.413799 -404.192451) (xy 335.431221 -404.129371) (xy 335.45696 -404.069205) (xy 335.473294 -404.040848)
			(xy 335.476672 -404.03484) (xy 335.4804 -404.021574) (xy 335.48066 -404.014686) (xy 335.48066 -403.728682)
			(xy 335.481112 -403.718552) (xy 335.48885 -403.699826) (xy 335.503147 -403.68547) (xy 335.52184 -403.677655)
			(xy 335.531968 -403.67712) (xy 336.248248 -403.67712) (xy 336.258408 -403.677483) (xy 336.277165 -403.685298)
			(xy 336.291487 -403.699713) (xy 336.299182 -403.71852) (xy 336.299556 -403.728682) (xy 336.299556 -404.014686)
			(xy 336.299765 -404.021581) (xy 336.30351 -404.034853) (xy 336.306922 -404.040848) (xy 336.323279 -404.069193)
			(xy 336.349023 -404.129362) (xy 336.366449 -404.192445) (xy 336.375241 -404.257296) (xy 336.375238 -404.322741)
			(xy 336.366442 -404.387592) (xy 336.349011 -404.450673) (xy 336.323262 -404.51084) (xy 336.306922 -404.539196)
			(xy 336.303557 -404.545211) (xy 336.299822 -404.558471) (xy 336.299556 -404.565358) (xy 336.299556 -405.314658)
			(xy 336.299776 -405.321552) (xy 336.303513 -405.334824) (xy 336.306922 -405.34082) (xy 336.323255 -405.369179)
			(xy 336.349002 -405.429344) (xy 336.36643 -405.492424) (xy 336.375225 -405.557273) (xy 336.375225 -405.622716)
			(xy 336.366432 -405.687566) (xy 336.349005 -405.750646) (xy 336.32326 -405.810812) (xy 336.306922 -405.839168)
			(xy 336.303567 -405.845187) (xy 336.299826 -405.858444) (xy 336.299556 -405.86533) (xy 336.299556 -406.151334)
			(xy 336.299101 -406.161463) (xy 336.291362 -406.180186) (xy 336.277066 -406.194541) (xy 336.258375 -406.202359)
			(xy 336.248248 -406.202896) (xy 335.531968 -406.202896) (xy 335.521811 -406.202505) (xy 335.503057 -406.194698)
			(xy 335.488735 -406.180292) (xy 335.481037 -406.161493) (xy 335.48066 -406.151334) (xy 335.48066 -405.86533)
			(xy 335.480442 -405.858436) (xy 335.476703 -405.845164) (xy 335.473294 -405.839168) (xy 335.456953 -405.810814)
			(xy 335.431212 -405.750646) (xy 335.413788 -405.687566) (xy 335.404996 -405.622716) (xy 334.116311 -405.622716)
			(xy 334.106774 -405.63927) (xy 334.103422 -405.645291) (xy 334.099679 -405.658547) (xy 334.099408 -405.665432)
			(xy 334.099408 -406.414732) (xy 334.099666 -406.421621) (xy 334.103391 -406.434887) (xy 334.106774 -406.440894)
			(xy 334.123084 -406.469265) (xy 334.14883 -406.529429) (xy 334.166259 -406.592506) (xy 334.175055 -406.657352)
			(xy 334.175058 -406.722793) (xy 334.175058 -406.722795) (xy 337.604862 -406.722795) (xy 337.604866 -406.65735)
			(xy 337.613664 -406.592498) (xy 337.631096 -406.529417) (xy 337.656847 -406.46925) (xy 337.673188 -406.440894)
			(xy 337.676504 -406.43487) (xy 337.680109 -406.421606) (xy 337.6803 -406.414732) (xy 337.6803 -405.665432)
			(xy 337.680096 -405.65856) (xy 337.676496 -405.645297) (xy 337.673188 -405.63927) (xy 337.656846 -405.610916)
			(xy 337.6311 -405.55075) (xy 337.613672 -405.487669) (xy 337.604878 -405.422818) (xy 337.604879 -405.357375)
			(xy 337.613673 -405.292524) (xy 337.631102 -405.229444) (xy 337.656849 -405.169278) (xy 337.673188 -405.140922)
			(xy 337.676494 -405.134893) (xy 337.680105 -405.121633) (xy 337.6803 -405.11476) (xy 337.6803 -404.828756)
			(xy 337.680686 -404.818599) (xy 337.688496 -404.799846) (xy 337.702903 -404.785524) (xy 337.721703 -404.777826)
			(xy 337.731862 -404.777448) (xy 338.448142 -404.777448) (xy 338.458272 -404.777892) (xy 338.476996 -404.785635)
			(xy 338.491351 -404.799934) (xy 338.499167 -404.818628) (xy 338.499704 -404.828756) (xy 338.499704 -405.11476)
			(xy 338.499911 -405.121632) (xy 338.503509 -405.134895) (xy 338.506816 -405.140922) (xy 338.523151 -405.16928)
			(xy 338.548898 -405.229445) (xy 338.566326 -405.292525) (xy 338.575121 -405.357375) (xy 338.575121 -405.422818)
			(xy 338.566328 -405.487668) (xy 338.5489 -405.550748) (xy 338.523155 -405.610914) (xy 338.516354 -405.622717)
			(xy 339.805032 -405.622717) (xy 339.805033 -405.557273) (xy 339.813827 -405.492423) (xy 339.831254 -405.429343)
			(xy 339.856998 -405.369176) (xy 339.873336 -405.34082) (xy 339.876639 -405.334789) (xy 339.880253 -405.32153)
			(xy 339.880448 -405.314658) (xy 339.880448 -404.565358) (xy 339.880241 -404.558486) (xy 339.876644 -404.545223)
			(xy 339.873336 -404.539196) (xy 339.857017 -404.51083) (xy 339.831272 -404.450665) (xy 339.813844 -404.387587)
			(xy 339.805048 -404.32274) (xy 339.805046 -404.257298) (xy 339.813836 -404.19245) (xy 339.831259 -404.129371)
			(xy 339.857 -404.069204) (xy 339.873336 -404.040848) (xy 339.876664 -404.03483) (xy 339.880262 -404.021561)
			(xy 339.880448 -404.014686) (xy 339.880448 -403.728682) (xy 339.880919 -403.718522) (xy 339.888701 -403.69975)
			(xy 339.903074 -403.685385) (xy 339.92185 -403.677613) (xy 339.93201 -403.67712) (xy 340.64829 -403.67712)
			(xy 340.658445 -403.677641) (xy 340.67721 -403.685409) (xy 340.691575 -403.699766) (xy 340.699353 -403.718527)
			(xy 340.699852 -403.728682) (xy 340.699852 -404.014686) (xy 340.700043 -404.021559) (xy 340.703651 -404.034822)
			(xy 340.706964 -404.040848) (xy 340.72332 -404.069194) (xy 340.749062 -404.129363) (xy 340.766486 -404.192445)
			(xy 340.775277 -404.257297) (xy 340.775274 -404.322741) (xy 340.766479 -404.387592) (xy 340.749049 -404.450673)
			(xy 340.723303 -404.51084) (xy 340.706964 -404.539196) (xy 340.703656 -404.545224) (xy 340.700045 -404.558485)
			(xy 340.699852 -404.565358) (xy 340.699852 -405.314658) (xy 340.700053 -405.321531) (xy 340.703654 -405.334794)
			(xy 340.706964 -405.34082) (xy 340.723296 -405.369179) (xy 340.74904 -405.429345) (xy 340.766467 -405.492425)
			(xy 340.775261 -405.557274) (xy 340.775262 -405.622716) (xy 340.766469 -405.687565) (xy 340.749044 -405.750645)
			(xy 340.723301 -405.810812) (xy 340.706964 -405.839168) (xy 340.703666 -405.845201) (xy 340.700049 -405.858458)
			(xy 340.699852 -405.86533) (xy 340.699852 -406.151334) (xy 340.699394 -406.161495) (xy 340.691607 -406.180267)
			(xy 340.67723 -406.194631) (xy 340.658452 -406.202403) (xy 340.64829 -406.202896) (xy 339.93201 -406.202896)
			(xy 339.921857 -406.202359) (xy 339.903095 -406.194594) (xy 339.88873 -406.180242) (xy 339.880949 -406.161487)
			(xy 339.880448 -406.151334) (xy 339.880448 -405.86533) (xy 339.880251 -405.858457) (xy 339.876647 -405.845194)
			(xy 339.873336 -405.839168) (xy 339.856994 -405.810815) (xy 339.83125 -405.750647) (xy 339.813825 -405.687567)
			(xy 339.805032 -405.622717) (xy 338.516354 -405.622717) (xy 338.506816 -405.63927) (xy 338.503513 -405.6453)
			(xy 338.4999 -405.65856) (xy 338.499704 -405.665432) (xy 338.499704 -406.414732) (xy 338.499883 -406.421606)
			(xy 338.5035 -406.434869) (xy 338.506816 -406.440894) (xy 338.523128 -406.469265) (xy 338.548876 -406.529427)
			(xy 338.566308 -406.592505) (xy 338.575105 -406.657352) (xy 338.575108 -406.722793) (xy 338.575108 -406.722795)
			(xy 342.004912 -406.722795) (xy 342.004916 -406.65735) (xy 342.013713 -406.592499) (xy 342.031143 -406.529418)
			(xy 342.056891 -406.46925) (xy 342.07323 -406.440894) (xy 342.076595 -406.434879) (xy 342.08033 -406.421619)
			(xy 342.080596 -406.414732) (xy 342.080596 -405.665432) (xy 342.080351 -405.658542) (xy 342.076617 -405.645276)
			(xy 342.07323 -405.63927) (xy 342.05689 -405.610916) (xy 342.031146 -405.550748) (xy 342.013721 -405.487668)
			(xy 342.004928 -405.422818) (xy 342.004929 -405.357375) (xy 342.013722 -405.292525) (xy 342.031149 -405.229445)
			(xy 342.056893 -405.169278) (xy 342.07323 -405.140922) (xy 342.076585 -405.134902) (xy 342.080326 -405.121646)
			(xy 342.080596 -405.11476) (xy 342.080596 -404.828756) (xy 342.081049 -404.818645) (xy 342.0888 -404.799967)
			(xy 342.103107 -404.785673) (xy 342.121793 -404.77794) (xy 342.131904 -404.777448) (xy 342.848184 -404.777448)
			(xy 342.858285 -404.777997) (xy 342.876953 -404.78572) (xy 342.891247 -404.799996) (xy 342.898991 -404.818655)
			(xy 342.899492 -404.828756) (xy 342.899492 -405.11476) (xy 342.899742 -405.12165) (xy 342.903473 -405.134916)
			(xy 342.906858 -405.140922) (xy 342.923192 -405.16928) (xy 342.948936 -405.229446) (xy 342.966363 -405.292526)
			(xy 342.975157 -405.357375) (xy 342.975157 -405.422818) (xy 342.966365 -405.487667) (xy 342.948939 -405.550747)
			(xy 342.923195 -405.610914) (xy 342.916395 -405.622716) (xy 344.204822 -405.622716) (xy 344.204823 -405.557273)
			(xy 344.213616 -405.492424) (xy 344.231043 -405.429343) (xy 344.256787 -405.369176) (xy 344.273124 -405.34082)
			(xy 344.276433 -405.334793) (xy 344.280042 -405.321531) (xy 344.280236 -405.314658) (xy 344.280236 -404.565358)
			(xy 344.280018 -404.558487) (xy 344.276427 -404.545224) (xy 344.273124 -404.539196) (xy 344.256806 -404.510829)
			(xy 344.231061 -404.450665) (xy 344.213633 -404.387587) (xy 344.204838 -404.322739) (xy 344.204835 -404.257298)
			(xy 344.213625 -404.19245) (xy 344.231048 -404.129371) (xy 344.256789 -404.069204) (xy 344.273124 -404.040848)
			(xy 344.276459 -404.034833) (xy 344.280051 -404.021562) (xy 344.280236 -404.014686) (xy 344.280236 -403.728682)
			(xy 344.280718 -403.718523) (xy 344.288498 -403.699754) (xy 344.302867 -403.685389) (xy 344.321639 -403.677615)
			(xy 344.331798 -403.67712) (xy 345.048078 -403.67712) (xy 345.058246 -403.677582) (xy 345.077037 -403.685356)
			(xy 345.091422 -403.69973) (xy 345.09921 -403.718514) (xy 345.09964 -403.728682) (xy 345.09964 -404.014686)
			(xy 345.099832 -404.021559) (xy 345.10344 -404.034822) (xy 345.106752 -404.040848) (xy 345.123108 -404.069194)
			(xy 345.148851 -404.129363) (xy 345.166276 -404.192445) (xy 345.175066 -404.257297) (xy 345.175065 -404.290022)
			(xy 348.603832 -404.290022) (xy 348.607823 -404.227855) (xy 348.619732 -404.166708) (xy 348.639361 -404.107587)
			(xy 348.66639 -404.051461) (xy 348.700374 -403.999252) (xy 348.740756 -403.951817) (xy 348.786872 -403.909936)
			(xy 348.837964 -403.874296) (xy 348.893195 -403.845482) (xy 348.951657 -403.823968) (xy 349.012391 -403.810106)
			(xy 349.074398 -403.804124) (xy 349.136661 -403.80612) (xy 349.198158 -403.816063) (xy 349.257879 -403.833787)
			(xy 349.314842 -403.859004) (xy 349.368113 -403.891297) (xy 349.416818 -403.930137) (xy 349.460155 -403.974887)
			(xy 349.497415 -404.024811) (xy 349.527984 -404.07909) (xy 349.551362 -404.136833) (xy 349.567163 -404.197091)
			(xy 349.575129 -404.258874) (xy 349.575628 -404.290022) (xy 349.575129 -404.32117) (xy 349.567163 -404.382953)
			(xy 349.551362 -404.443211) (xy 349.527984 -404.500954) (xy 349.497415 -404.555233) (xy 349.460155 -404.605157)
			(xy 349.416818 -404.649907) (xy 349.368113 -404.688747) (xy 349.314842 -404.72104) (xy 349.257879 -404.746257)
			(xy 349.198158 -404.763981) (xy 349.136661 -404.773924) (xy 349.074398 -404.77592) (xy 349.012391 -404.769938)
			(xy 348.951657 -404.756076) (xy 348.893195 -404.734562) (xy 348.837964 -404.705748) (xy 348.786872 -404.670108)
			(xy 348.740756 -404.628227) (xy 348.700374 -404.580792) (xy 348.66639 -404.528583) (xy 348.639361 -404.472457)
			(xy 348.619732 -404.413336) (xy 348.607823 -404.352189) (xy 348.603832 -404.290022) (xy 345.175065 -404.290022)
			(xy 345.175064 -404.322741) (xy 345.166268 -404.387592) (xy 345.148838 -404.450673) (xy 345.123091 -404.51084)
			(xy 345.106752 -404.539196) (xy 345.103443 -404.545223) (xy 345.099833 -404.558485) (xy 345.09964 -404.565358)
			(xy 345.09964 -405.314658) (xy 345.099843 -405.32153) (xy 345.103443 -405.334793) (xy 345.106752 -405.34082)
			(xy 345.123085 -405.369179) (xy 345.148829 -405.429345) (xy 345.166257 -405.492424) (xy 345.17505 -405.557274)
			(xy 345.175051 -405.622716) (xy 345.166259 -405.687566) (xy 345.148833 -405.750645) (xy 345.123089 -405.810812)
			(xy 345.106752 -405.839168) (xy 345.103453 -405.8452) (xy 345.099837 -405.858458) (xy 345.09964 -405.86533)
			(xy 345.09964 -406.151334) (xy 345.099194 -406.161497) (xy 345.091404 -406.180271) (xy 345.077024 -406.194636)
			(xy 345.058241 -406.202405) (xy 345.048078 -406.202896) (xy 344.331798 -406.202896) (xy 344.321644 -406.202369)
			(xy 344.302882 -406.1946) (xy 344.288518 -406.180245) (xy 344.280737 -406.161487) (xy 344.280236 -406.151334)
			(xy 344.280236 -405.86533) (xy 344.280028 -405.858458) (xy 344.27643 -405.845195) (xy 344.273124 -405.839168)
			(xy 344.256782 -405.810814) (xy 344.231039 -405.750647) (xy 344.213614 -405.687566) (xy 344.204822 -405.622716)
			(xy 342.916395 -405.622716) (xy 342.906858 -405.63927) (xy 342.903505 -405.645291) (xy 342.899763 -405.658547)
			(xy 342.899492 -405.665432) (xy 342.899492 -406.414732) (xy 342.899752 -406.421621) (xy 342.903476 -406.434887)
			(xy 342.906858 -406.440894) (xy 342.923168 -406.469265) (xy 342.948915 -406.529428) (xy 342.966344 -406.592505)
			(xy 342.975141 -406.657352) (xy 342.975145 -406.722793) (xy 342.975145 -406.722795) (xy 346.404949 -406.722795)
			(xy 346.404952 -406.65735) (xy 346.41375 -406.592498) (xy 346.431182 -406.529417) (xy 346.456931 -406.46925)
			(xy 346.473272 -406.440894) (xy 346.476587 -406.434869) (xy 346.480193 -406.421606) (xy 346.480384 -406.414732)
			(xy 346.480384 -405.665432) (xy 346.480182 -405.65856) (xy 346.476581 -405.645297) (xy 346.473272 -405.63927)
			(xy 346.45693 -405.610916) (xy 346.431185 -405.550749) (xy 346.413758 -405.487669) (xy 346.404964 -405.422818)
			(xy 346.404965 -405.357375) (xy 346.413759 -405.292525) (xy 346.431187 -405.229444) (xy 346.456933 -405.169278)
			(xy 346.473272 -405.140922) (xy 346.476577 -405.134893) (xy 346.480189 -405.121633) (xy 346.480384 -405.11476)
			(xy 346.480384 -404.828756) (xy 346.480785 -404.818601) (xy 346.488592 -404.799851) (xy 346.502995 -404.78553)
			(xy 346.521789 -404.777829) (xy 346.531946 -404.777448) (xy 347.248226 -404.777448) (xy 347.258355 -404.777905)
			(xy 347.277079 -404.785643) (xy 347.291434 -404.799938) (xy 347.299251 -404.818629) (xy 347.299788 -404.828756)
			(xy 347.299788 -405.11476) (xy 347.299997 -405.121632) (xy 347.303594 -405.134895) (xy 347.3069 -405.140922)
			(xy 347.323233 -405.16928) (xy 347.348975 -405.229447) (xy 347.3664 -405.292527) (xy 347.375193 -405.357375)
			(xy 347.375193 -405.422818) (xy 347.366402 -405.487667) (xy 347.348977 -405.550746) (xy 347.332186 -405.589994)
			(xy 348.603832 -405.589994) (xy 348.607823 -405.527827) (xy 348.619732 -405.46668) (xy 348.639361 -405.407559)
			(xy 348.66639 -405.351433) (xy 348.700374 -405.299224) (xy 348.740756 -405.251789) (xy 348.786872 -405.209908)
			(xy 348.837964 -405.174268) (xy 348.893195 -405.145454) (xy 348.951657 -405.12394) (xy 349.012391 -405.110078)
			(xy 349.074398 -405.104096) (xy 349.136661 -405.106092) (xy 349.198158 -405.116035) (xy 349.257879 -405.133759)
			(xy 349.314842 -405.158976) (xy 349.368113 -405.191269) (xy 349.416818 -405.230109) (xy 349.460155 -405.274859)
			(xy 349.497415 -405.324783) (xy 349.527984 -405.379062) (xy 349.532451 -405.390096) (xy 350.80398 -405.390096)
			(xy 350.807971 -405.327929) (xy 350.81988 -405.266782) (xy 350.839509 -405.207661) (xy 350.866538 -405.151535)
			(xy 350.900522 -405.099326) (xy 350.940904 -405.051891) (xy 350.98702 -405.01001) (xy 351.038112 -404.97437)
			(xy 351.093343 -404.945556) (xy 351.151805 -404.924042) (xy 351.212539 -404.91018) (xy 351.274546 -404.904198)
			(xy 351.336809 -404.906194) (xy 351.398306 -404.916137) (xy 351.458027 -404.933861) (xy 351.51499 -404.959078)
			(xy 351.568261 -404.991371) (xy 351.616966 -405.030211) (xy 351.660303 -405.074961) (xy 351.697563 -405.124885)
			(xy 351.728132 -405.179164) (xy 351.75151 -405.236907) (xy 351.767311 -405.297165) (xy 351.775277 -405.358948)
			(xy 351.775776 -405.390096) (xy 351.775277 -405.421244) (xy 351.767311 -405.483027) (xy 351.75151 -405.543285)
			(xy 351.728132 -405.601028) (xy 351.697563 -405.655307) (xy 351.660303 -405.705231) (xy 351.616966 -405.749981)
			(xy 351.568261 -405.788821) (xy 351.51499 -405.821114) (xy 351.458027 -405.846331) (xy 351.398306 -405.864055)
			(xy 351.336809 -405.873998) (xy 351.274546 -405.875994) (xy 351.212539 -405.870012) (xy 351.151805 -405.85615)
			(xy 351.093343 -405.834636) (xy 351.038112 -405.805822) (xy 350.98702 -405.770182) (xy 350.940904 -405.728301)
			(xy 350.900522 -405.680866) (xy 350.866538 -405.628657) (xy 350.839509 -405.572531) (xy 350.81988 -405.51341)
			(xy 350.807971 -405.452263) (xy 350.80398 -405.390096) (xy 349.532451 -405.390096) (xy 349.551362 -405.436805)
			(xy 349.567163 -405.497063) (xy 349.575129 -405.558846) (xy 349.575628 -405.589994) (xy 349.575129 -405.621142)
			(xy 349.567163 -405.682925) (xy 349.551362 -405.743183) (xy 349.527984 -405.800926) (xy 349.497415 -405.855205)
			(xy 349.460155 -405.905129) (xy 349.416818 -405.949879) (xy 349.368113 -405.988719) (xy 349.314842 -406.021012)
			(xy 349.257879 -406.046229) (xy 349.198158 -406.063953) (xy 349.136661 -406.073896) (xy 349.074398 -406.075892)
			(xy 349.012391 -406.06991) (xy 348.951657 -406.056048) (xy 348.893195 -406.034534) (xy 348.837964 -406.00572)
			(xy 348.786872 -405.97008) (xy 348.740756 -405.928199) (xy 348.700374 -405.880764) (xy 348.66639 -405.828555)
			(xy 348.639361 -405.772429) (xy 348.619732 -405.713308) (xy 348.607823 -405.652161) (xy 348.603832 -405.589994)
			(xy 347.332186 -405.589994) (xy 347.323236 -405.610913) (xy 347.3069 -405.63927) (xy 347.303596 -405.6453)
			(xy 347.299984 -405.65856) (xy 347.299788 -405.665432) (xy 347.299788 -406.414732) (xy 347.299969 -406.421606)
			(xy 347.303585 -406.434869) (xy 347.3069 -406.440894) (xy 347.323209 -406.469266) (xy 347.348953 -406.529429)
			(xy 347.366381 -406.592506) (xy 347.375177 -406.657352) (xy 347.375179 -406.690068) (xy 350.80398 -406.690068)
			(xy 350.807971 -406.627901) (xy 350.81988 -406.566754) (xy 350.839509 -406.507633) (xy 350.866538 -406.451507)
			(xy 350.900522 -406.399298) (xy 350.940904 -406.351863) (xy 350.98702 -406.309982) (xy 351.038112 -406.274342)
			(xy 351.093343 -406.245528) (xy 351.151805 -406.224014) (xy 351.212539 -406.210152) (xy 351.274546 -406.20417)
			(xy 351.336809 -406.206166) (xy 351.398306 -406.216109) (xy 351.458027 -406.233833) (xy 351.51499 -406.25905)
			(xy 351.568261 -406.291343) (xy 351.616966 -406.330183) (xy 351.660303 -406.374933) (xy 351.697563 -406.424857)
			(xy 351.728132 -406.479136) (xy 351.75151 -406.536879) (xy 351.767311 -406.597137) (xy 351.775277 -406.65892)
			(xy 351.775776 -406.690068) (xy 351.775277 -406.721216) (xy 351.767311 -406.782999) (xy 351.75151 -406.843257)
			(xy 351.728132 -406.901) (xy 351.697563 -406.955279) (xy 351.660303 -407.005203) (xy 351.616966 -407.049953)
			(xy 351.568261 -407.088793) (xy 351.51499 -407.121086) (xy 351.458027 -407.146303) (xy 351.398306 -407.164027)
			(xy 351.336809 -407.17397) (xy 351.274546 -407.175966) (xy 351.212539 -407.169984) (xy 351.151805 -407.156122)
			(xy 351.093343 -407.134608) (xy 351.038112 -407.105794) (xy 350.98702 -407.070154) (xy 350.940904 -407.028273)
			(xy 350.900522 -406.980838) (xy 350.866538 -406.928629) (xy 350.839509 -406.872503) (xy 350.81988 -406.813382)
			(xy 350.807971 -406.752235) (xy 350.80398 -406.690068) (xy 347.375179 -406.690068) (xy 347.375181 -406.722793)
			(xy 347.366392 -406.78764) (xy 347.348972 -406.850719) (xy 347.323234 -406.910885) (xy 347.3069 -406.939242)
			(xy 347.30357 -406.945259) (xy 347.299974 -406.958529) (xy 347.299788 -406.965404) (xy 347.299788 -407.251408)
			(xy 347.299385 -407.261564) (xy 347.291584 -407.280319) (xy 347.277182 -407.294642) (xy 347.258384 -407.30234)
			(xy 347.248226 -407.302716) (xy 346.531946 -407.302716) (xy 346.521817 -407.302234) (xy 346.503088 -407.294514)
			(xy 346.488729 -407.280225) (xy 346.480916 -407.261535) (xy 346.480384 -407.251408) (xy 346.480384 -406.965404)
			(xy 346.480192 -406.958531) (xy 346.476584 -406.945268) (xy 346.473272 -406.939242) (xy 346.456906 -406.910901)
			(xy 346.431163 -406.850731) (xy 346.413739 -406.787648) (xy 346.404949 -406.722795) (xy 342.975145 -406.722795)
			(xy 342.966355 -406.787641) (xy 342.948933 -406.85072) (xy 342.923193 -406.910886) (xy 342.906858 -406.939242)
			(xy 342.90348 -406.94525) (xy 342.899753 -406.958516) (xy 342.899492 -406.965404) (xy 342.899492 -407.251408)
			(xy 342.89909 -407.261532) (xy 342.891338 -407.280237) (xy 342.877017 -407.294551) (xy 342.858308 -407.302295)
			(xy 342.848184 -407.302716) (xy 342.131904 -407.302716) (xy 342.121798 -407.302212) (xy 342.103122 -407.294479)
			(xy 342.088828 -407.280188) (xy 342.08109 -407.261514) (xy 342.080596 -407.251408) (xy 342.080596 -406.965404)
			(xy 342.080362 -406.958513) (xy 342.07662 -406.945247) (xy 342.07323 -406.939242) (xy 342.056866 -406.910901)
			(xy 342.031125 -406.85073) (xy 342.013702 -406.787647) (xy 342.004912 -406.722795) (xy 338.575108 -406.722795)
			(xy 338.566319 -406.787642) (xy 338.548895 -406.850721) (xy 338.523153 -406.910886) (xy 338.506816 -406.939242)
			(xy 338.503487 -406.94526) (xy 338.49989 -406.958529) (xy 338.499704 -406.965404) (xy 338.499704 -407.251408)
			(xy 338.499285 -407.261562) (xy 338.491487 -407.280314) (xy 338.47709 -407.294637) (xy 338.458298 -407.302337)
			(xy 338.448142 -407.302716) (xy 337.731862 -407.302716) (xy 337.721727 -407.302303) (xy 337.702997 -407.294555)
			(xy 337.688641 -407.280246) (xy 337.68083 -407.261541) (xy 337.6803 -407.251408) (xy 337.6803 -406.965404)
			(xy 337.680107 -406.958531) (xy 337.6765 -406.945268) (xy 337.673188 -406.939242) (xy 337.656822 -406.910901)
			(xy 337.631078 -406.850732) (xy 337.613653 -406.787648) (xy 337.604862 -406.722795) (xy 334.175058 -406.722795)
			(xy 334.16627 -406.787641) (xy 334.148848 -406.850719) (xy 334.123109 -406.910886) (xy 334.106774 -406.939242)
			(xy 334.103397 -406.945251) (xy 334.099669 -406.958516) (xy 334.099408 -406.965404) (xy 334.099408 -407.251408)
			(xy 334.098921 -407.261516) (xy 334.091183 -407.280193) (xy 334.076886 -407.294487) (xy 334.058208 -407.302223)
			(xy 334.0481 -407.302716) (xy 333.33182 -407.302716) (xy 333.321701 -407.302268) (xy 333.303001 -407.29453)
			(xy 333.288686 -407.280223) (xy 333.280937 -407.261527) (xy 333.280512 -407.251408) (xy 333.280512 -406.965404)
			(xy 333.280311 -406.958509) (xy 333.276561 -406.945236) (xy 333.273146 -406.939242) (xy 333.256781 -406.910901)
			(xy 333.23104 -406.850731) (xy 333.213616 -406.787648) (xy 333.204826 -406.722795) (xy 326.525636 -406.722795)
			(xy 326.525636 -409.522892) (xy 331.004929 -409.522892) (xy 331.004933 -409.457446) (xy 331.013731 -409.392595)
			(xy 331.031162 -409.329513) (xy 331.056912 -409.269346) (xy 331.073252 -409.24099) (xy 331.076566 -409.234965)
			(xy 331.080173 -409.221702) (xy 331.080364 -409.214828) (xy 331.080364 -408.465528) (xy 331.080166 -408.458655)
			(xy 331.076562 -408.445392) (xy 331.073252 -408.439366) (xy 331.056907 -408.411014) (xy 331.031163 -408.350846)
			(xy 331.013737 -408.287765) (xy 331.004945 -408.222915) (xy 331.004946 -408.157471) (xy 331.01374 -408.092621)
			(xy 331.031168 -408.029541) (xy 331.056914 -407.969374) (xy 331.073252 -407.941018) (xy 331.076556 -407.934988)
			(xy 331.080169 -407.921729) (xy 331.080364 -407.914856) (xy 331.080364 -407.628852) (xy 331.080782 -407.618699)
			(xy 331.088586 -407.599953) (xy 331.102983 -407.585633) (xy 331.121771 -407.577928) (xy 331.131926 -407.577544)
			(xy 331.848206 -407.577544) (xy 331.858334 -407.578022) (xy 331.877056 -407.585752) (xy 331.891412 -407.600041)
			(xy 331.89923 -407.618727) (xy 331.899768 -407.628852) (xy 331.899768 -407.914856) (xy 331.899981 -407.921728)
			(xy 331.903575 -407.93499) (xy 331.90688 -407.941018) (xy 331.92321 -407.969378) (xy 331.948954 -408.029544)
			(xy 331.96638 -408.092623) (xy 331.975173 -408.157472) (xy 331.975174 -408.222914) (xy 331.966383 -408.287763)
			(xy 331.948958 -408.350843) (xy 331.923216 -408.41101) (xy 331.90688 -408.439366) (xy 331.903576 -408.445396)
			(xy 331.899964 -408.458656) (xy 331.899768 -408.465528) (xy 331.899768 -409.214828) (xy 331.899953 -409.221702)
			(xy 331.903567 -409.234964) (xy 331.90688 -409.24099) (xy 331.923186 -409.269363) (xy 331.948932 -409.329526)
			(xy 331.966361 -409.392603) (xy 331.975157 -409.457449) (xy 331.975162 -409.522889) (xy 331.966374 -409.587737)
			(xy 331.948952 -409.650815) (xy 331.923214 -409.710982) (xy 331.90688 -409.739338) (xy 331.90355 -409.745355)
			(xy 331.899954 -409.758625) (xy 331.899768 -409.7655) (xy 331.899768 -410.051504) (xy 331.899381 -410.061662)
			(xy 331.891578 -410.080421) (xy 331.87717 -410.094745) (xy 331.858367 -410.102439) (xy 331.848206 -410.102812)
			(xy 331.131926 -410.102812) (xy 331.121807 -410.102254) (xy 331.103097 -410.094544) (xy 331.088741 -410.08028)
			(xy 331.080912 -410.061619) (xy 331.080364 -410.051504) (xy 331.080364 -409.7655) (xy 331.080176 -409.758626)
			(xy 331.076566 -409.745363) (xy 331.073252 -409.739338) (xy 331.056884 -409.710999) (xy 331.031142 -409.650828)
			(xy 331.013718 -409.587745) (xy 331.004929 -409.522892) (xy 326.525636 -409.522892) (xy 326.525636 -410.622708)
			(xy 333.204835 -410.622708) (xy 333.204837 -410.557264) (xy 333.213632 -410.492414) (xy 333.231061 -410.429333)
			(xy 333.256807 -410.369166) (xy 333.273146 -410.34081) (xy 333.276506 -410.334793) (xy 333.280244 -410.321534)
			(xy 333.280512 -410.314648) (xy 333.280512 -409.565348) (xy 333.280294 -409.558454) (xy 333.276556 -409.545182)
			(xy 333.273146 -409.539186) (xy 333.256819 -409.510824) (xy 333.231073 -409.450659) (xy 333.213646 -409.38758)
			(xy 333.204851 -409.322731) (xy 333.20485 -409.257289) (xy 333.213641 -409.19244) (xy 333.231067 -409.129361)
			(xy 333.256809 -409.069194) (xy 333.273146 -409.040838) (xy 333.276531 -409.034834) (xy 333.280253 -409.021565)
			(xy 333.280512 -409.014676) (xy 333.280512 -408.728672) (xy 333.280962 -408.71856) (xy 333.288711 -408.699879)
			(xy 333.303019 -408.685585) (xy 333.321708 -408.677853) (xy 333.33182 -408.677364) (xy 334.0481 -408.677364)
			(xy 334.058204 -408.677884) (xy 334.076876 -408.685615) (xy 334.091169 -408.699901) (xy 334.09891 -408.718568)
			(xy 334.099408 -408.728672) (xy 334.099408 -409.014676) (xy 334.099649 -409.021567) (xy 334.103386 -409.034833)
			(xy 334.106774 -409.040838) (xy 334.123121 -409.069189) (xy 334.148863 -409.129357) (xy 334.166288 -409.192438)
			(xy 334.17508 -409.257288) (xy 334.175078 -409.322732) (xy 334.166284 -409.387582) (xy 334.148857 -409.450663)
			(xy 334.123112 -409.51083) (xy 334.116162 -409.522892) (xy 335.404979 -409.522892) (xy 335.404983 -409.457447)
			(xy 335.41378 -409.392596) (xy 335.431209 -409.329514) (xy 335.456956 -409.269347) (xy 335.473294 -409.24099)
			(xy 335.476657 -409.234974) (xy 335.480394 -409.221715) (xy 335.48066 -409.214828) (xy 335.48066 -408.465528)
			(xy 335.480443 -408.458634) (xy 335.476704 -408.445362) (xy 335.473294 -408.439366) (xy 335.456951 -408.411013)
			(xy 335.43121 -408.350845) (xy 335.413786 -408.287764) (xy 335.404995 -408.222915) (xy 335.404996 -408.157472)
			(xy 335.413789 -408.092622) (xy 335.431215 -408.029542) (xy 335.456957 -407.969375) (xy 335.473294 -407.941018)
			(xy 335.476648 -407.934998) (xy 335.480391 -407.921741) (xy 335.48066 -407.914856) (xy 335.48066 -407.628852)
			(xy 335.481145 -407.618745) (xy 335.488891 -407.600074) (xy 335.503187 -407.585782) (xy 335.521861 -407.578042)
			(xy 335.531968 -407.577544) (xy 336.248248 -407.577544) (xy 336.258353 -407.578045) (xy 336.277021 -407.585788)
			(xy 336.291312 -407.600079) (xy 336.299055 -407.618747) (xy 336.299556 -407.628852) (xy 336.299556 -407.914856)
			(xy 336.299777 -407.92175) (xy 336.303513 -407.935022) (xy 336.306922 -407.941018) (xy 336.323254 -407.969378)
			(xy 336.349 -408.029543) (xy 336.366429 -408.092622) (xy 336.375224 -408.157472) (xy 336.375224 -408.222915)
			(xy 336.366432 -408.287764) (xy 336.349005 -408.350844) (xy 336.32326 -408.41101) (xy 336.306922 -408.439366)
			(xy 336.303567 -408.445386) (xy 336.299826 -408.458643) (xy 336.299556 -408.465528) (xy 336.299556 -409.214828)
			(xy 336.299787 -409.221721) (xy 336.303517 -409.234993) (xy 336.306922 -409.24099) (xy 336.32323 -409.269363)
			(xy 336.348979 -409.329525) (xy 336.36641 -409.392602) (xy 336.375208 -409.457449) (xy 336.375212 -409.52289)
			(xy 336.366423 -409.587738) (xy 336.348999 -409.650817) (xy 336.323258 -409.710982) (xy 336.306922 -409.739338)
			(xy 336.303542 -409.745345) (xy 336.299817 -409.758612) (xy 336.299556 -409.7655) (xy 336.299556 -410.051504)
			(xy 336.299019 -410.061606) (xy 336.291291 -410.080274) (xy 336.277011 -410.094566) (xy 336.25835 -410.102311)
			(xy 336.248248 -410.102812) (xy 335.531968 -410.102812) (xy 335.521859 -410.102341) (xy 335.503182 -410.094595)
			(xy 335.488889 -410.080294) (xy 335.481153 -410.061614) (xy 335.48066 -410.051504) (xy 335.48066 -409.7655)
			(xy 335.480432 -409.758608) (xy 335.476687 -409.745342) (xy 335.473294 -409.739338) (xy 335.456928 -409.710998)
			(xy 335.431189 -409.650827) (xy 335.413767 -409.587744) (xy 335.404979 -409.522892) (xy 334.116162 -409.522892)
			(xy 334.106774 -409.539186) (xy 334.103417 -409.545205) (xy 334.099677 -409.558462) (xy 334.099408 -409.565348)
			(xy 334.099408 -410.314648) (xy 334.09966 -410.321538) (xy 334.103389 -410.334804) (xy 334.106774 -410.34081)
			(xy 334.123097 -410.369174) (xy 334.148842 -410.429339) (xy 334.166269 -410.492417) (xy 334.175064 -410.557265)
			(xy 334.175066 -410.622707) (xy 334.175066 -410.622709) (xy 337.604871 -410.622709) (xy 337.604873 -410.557264)
			(xy 337.613669 -410.492413) (xy 337.631099 -410.429332) (xy 337.656848 -410.369166) (xy 337.673188 -410.34081)
			(xy 337.676498 -410.334783) (xy 337.680107 -410.321521) (xy 337.6803 -410.314648) (xy 337.6803 -409.565348)
			(xy 337.68009 -409.558476) (xy 337.676494 -409.545213) (xy 337.673188 -409.539186) (xy 337.656859 -409.510825)
			(xy 337.631112 -409.45066) (xy 337.613682 -409.387581) (xy 337.604887 -409.322732) (xy 337.604886 -409.257289)
			(xy 337.613678 -409.19244) (xy 337.631105 -409.12936) (xy 337.65685 -409.069194) (xy 337.673188 -409.040838)
			(xy 337.676488 -409.034806) (xy 337.680103 -409.021548) (xy 337.6803 -409.014676) (xy 337.6803 -408.728672)
			(xy 337.680699 -408.718516) (xy 337.688503 -408.699763) (xy 337.702907 -408.685441) (xy 337.721704 -408.677742)
			(xy 337.731862 -408.677364) (xy 338.448142 -408.677364) (xy 338.458274 -408.677793) (xy 338.477001 -408.685539)
			(xy 338.491357 -408.699843) (xy 338.49917 -408.718542) (xy 338.499704 -408.728672) (xy 338.499704 -409.014676)
			(xy 338.499905 -409.021549) (xy 338.503507 -409.034811) (xy 338.506816 -409.040838) (xy 338.523165 -409.069188)
			(xy 338.54891 -409.129356) (xy 338.566337 -409.192437) (xy 338.57513 -409.257288) (xy 338.575128 -409.322732)
			(xy 338.566333 -409.387583) (xy 338.548903 -409.450664) (xy 338.523156 -409.51083) (xy 338.516205 -409.522892)
			(xy 339.805015 -409.522892) (xy 339.805019 -409.457446) (xy 339.813817 -409.392595) (xy 339.831248 -409.329514)
			(xy 339.856996 -409.269346) (xy 339.873336 -409.24099) (xy 339.876649 -409.234965) (xy 339.880257 -409.221702)
			(xy 339.880448 -409.214828) (xy 339.880448 -408.465528) (xy 339.880252 -408.458655) (xy 339.876647 -408.445392)
			(xy 339.873336 -408.439366) (xy 339.856992 -408.411014) (xy 339.831249 -408.350846) (xy 339.813823 -408.287765)
			(xy 339.805031 -408.222915) (xy 339.805032 -408.157471) (xy 339.813826 -408.092621) (xy 339.831253 -408.029541)
			(xy 339.856998 -407.969374) (xy 339.873336 -407.941018) (xy 339.876639 -407.934988) (xy 339.880253 -407.921728)
			(xy 339.880448 -407.914856) (xy 339.880448 -407.628852) (xy 339.880881 -407.618701) (xy 339.888683 -407.599958)
			(xy 339.903075 -407.585638) (xy 339.921857 -407.577931) (xy 339.93201 -407.577544) (xy 340.64829 -407.577544)
			(xy 340.658417 -407.578035) (xy 340.677138 -407.58576) (xy 340.691495 -407.600045) (xy 340.699314 -407.618728)
			(xy 340.699852 -407.628852) (xy 340.699852 -407.914856) (xy 340.700054 -407.921729) (xy 340.703655 -407.934992)
			(xy 340.706964 -407.941018) (xy 340.723294 -407.969378) (xy 340.749039 -408.029544) (xy 340.766466 -408.092623)
			(xy 340.77526 -408.157472) (xy 340.775261 -408.222914) (xy 340.766469 -408.287763) (xy 340.749043 -408.350843)
			(xy 340.723301 -408.41101) (xy 340.706964 -408.439366) (xy 340.703666 -408.445399) (xy 340.700049 -408.458656)
			(xy 340.699852 -408.465528) (xy 340.699852 -409.214828) (xy 340.700027 -409.221703) (xy 340.703646 -409.234966)
			(xy 340.706964 -409.24099) (xy 340.723271 -409.269363) (xy 340.749017 -409.329526) (xy 340.766447 -409.392602)
			(xy 340.775244 -409.457449) (xy 340.775248 -409.522889) (xy 340.766459 -409.587737) (xy 340.749038 -409.650816)
			(xy 340.723299 -409.710982) (xy 340.706964 -409.739338) (xy 340.703641 -409.745359) (xy 340.70004 -409.758625)
			(xy 340.699852 -409.7655) (xy 340.699852 -410.051504) (xy 340.699383 -410.061652) (xy 340.691595 -410.080394)
			(xy 340.677214 -410.094716) (xy 340.65844 -410.102424) (xy 340.64829 -410.102812) (xy 339.93201 -410.102812)
			(xy 339.92189 -410.102267) (xy 339.903179 -410.094552) (xy 339.888824 -410.080284) (xy 339.880996 -410.061621)
			(xy 339.880448 -410.051504) (xy 339.880448 -409.7655) (xy 339.880263 -409.758626) (xy 339.876651 -409.745363)
			(xy 339.873336 -409.739338) (xy 339.856968 -409.710999) (xy 339.831227 -409.650828) (xy 339.813804 -409.587744)
			(xy 339.805015 -409.522892) (xy 338.516205 -409.522892) (xy 338.506816 -409.539186) (xy 338.503507 -409.545214)
			(xy 338.499898 -409.558475) (xy 338.499704 -409.565348) (xy 338.499704 -410.314648) (xy 338.499915 -410.32152)
			(xy 338.50351 -410.334783) (xy 338.506816 -410.34081) (xy 338.523141 -410.369173) (xy 338.548889 -410.429338)
			(xy 338.566318 -410.492416) (xy 338.575114 -410.557265) (xy 338.575116 -410.622707) (xy 338.575116 -410.622708)
			(xy 342.004921 -410.622708) (xy 342.004923 -410.557264) (xy 342.013718 -410.492414) (xy 342.031146 -410.429333)
			(xy 342.056892 -410.369166) (xy 342.07323 -410.34081) (xy 342.076589 -410.334792) (xy 342.080328 -410.321534)
			(xy 342.080596 -410.314648) (xy 342.080596 -409.565348) (xy 342.080345 -409.558458) (xy 342.076615 -409.545192)
			(xy 342.07323 -409.539186) (xy 342.056903 -409.510824) (xy 342.031159 -409.450659) (xy 342.013731 -409.38758)
			(xy 342.004937 -409.322731) (xy 342.004936 -409.257289) (xy 342.013727 -409.19244) (xy 342.031152 -409.129361)
			(xy 342.056894 -409.069194) (xy 342.07323 -409.040838) (xy 342.076614 -409.034833) (xy 342.080337 -409.021565)
			(xy 342.080596 -409.014676) (xy 342.080596 -408.728672) (xy 342.081062 -408.718562) (xy 342.088808 -408.699884)
			(xy 342.103111 -408.68559) (xy 342.121794 -408.677856) (xy 342.131904 -408.677364) (xy 342.848184 -408.677364)
			(xy 342.858287 -408.677897) (xy 342.876958 -408.685623) (xy 342.891252 -408.699905) (xy 342.898994 -408.718569)
			(xy 342.899492 -408.728672) (xy 342.899492 -409.014676) (xy 342.899736 -409.021567) (xy 342.903471 -409.034832)
			(xy 342.906858 -409.040838) (xy 342.923206 -409.069189) (xy 342.948949 -409.129357) (xy 342.966374 -409.192438)
			(xy 342.975166 -409.257288) (xy 342.975165 -409.322732) (xy 342.96637 -409.387582) (xy 342.948942 -409.450663)
			(xy 342.923196 -409.51083) (xy 342.916246 -409.522892) (xy 344.204805 -409.522892) (xy 344.204809 -409.457447)
			(xy 344.213606 -409.392595) (xy 344.231037 -409.329514) (xy 344.256785 -409.269346) (xy 344.273124 -409.24099)
			(xy 344.276444 -409.234968) (xy 344.280046 -409.221702) (xy 344.280236 -409.214828) (xy 344.280236 -408.465528)
			(xy 344.280029 -408.458656) (xy 344.276431 -408.445393) (xy 344.273124 -408.439366) (xy 344.25678 -408.411013)
			(xy 344.231038 -408.350846) (xy 344.213613 -408.287765) (xy 344.204821 -408.222915) (xy 344.204822 -408.157471)
			(xy 344.213615 -408.092622) (xy 344.231042 -408.029541) (xy 344.256787 -407.969374) (xy 344.273124 -407.941018)
			(xy 344.276434 -407.934991) (xy 344.280042 -407.921729) (xy 344.280236 -407.914856) (xy 344.280236 -407.628852)
			(xy 344.280583 -407.61869) (xy 344.288401 -407.59993) (xy 344.302821 -407.585607) (xy 344.321634 -407.577916)
			(xy 344.331798 -407.577544) (xy 345.048078 -407.577544) (xy 345.058204 -407.578045) (xy 345.076925 -407.585766)
			(xy 345.091283 -407.600048) (xy 345.099102 -407.618729) (xy 345.09964 -407.628852) (xy 345.09964 -407.914856)
			(xy 345.099844 -407.921728) (xy 345.103443 -407.934991) (xy 345.106752 -407.941018) (xy 345.123083 -407.969378)
			(xy 345.148828 -408.029544) (xy 345.166255 -408.092623) (xy 345.175049 -408.157472) (xy 345.175049 -408.190192)
			(xy 348.603832 -408.190192) (xy 348.607823 -408.128025) (xy 348.619732 -408.066878) (xy 348.639361 -408.007757)
			(xy 348.66639 -407.951631) (xy 348.700374 -407.899422) (xy 348.740756 -407.851987) (xy 348.786872 -407.810106)
			(xy 348.837964 -407.774466) (xy 348.893195 -407.745652) (xy 348.951657 -407.724138) (xy 349.012391 -407.710276)
			(xy 349.074398 -407.704294) (xy 349.136661 -407.70629) (xy 349.198158 -407.716233) (xy 349.257879 -407.733957)
			(xy 349.314842 -407.759174) (xy 349.368113 -407.791467) (xy 349.416818 -407.830307) (xy 349.460155 -407.875057)
			(xy 349.497415 -407.924981) (xy 349.527984 -407.97926) (xy 349.551362 -408.037003) (xy 349.567163 -408.097261)
			(xy 349.575129 -408.159044) (xy 349.575628 -408.190192) (xy 349.575129 -408.22134) (xy 349.567163 -408.283123)
			(xy 349.551362 -408.343381) (xy 349.527984 -408.401124) (xy 349.497415 -408.455403) (xy 349.460155 -408.505327)
			(xy 349.416818 -408.550077) (xy 349.368113 -408.588917) (xy 349.314842 -408.62121) (xy 349.257879 -408.646427)
			(xy 349.198158 -408.664151) (xy 349.136661 -408.674094) (xy 349.074398 -408.67609) (xy 349.012391 -408.670108)
			(xy 348.951657 -408.656246) (xy 348.893195 -408.634732) (xy 348.837964 -408.605918) (xy 348.786872 -408.570278)
			(xy 348.740756 -408.528397) (xy 348.700374 -408.480962) (xy 348.66639 -408.428753) (xy 348.639361 -408.372627)
			(xy 348.619732 -408.313506) (xy 348.607823 -408.252359) (xy 348.603832 -408.190192) (xy 345.175049 -408.190192)
			(xy 345.17505 -408.222914) (xy 345.166258 -408.287764) (xy 345.148832 -408.350843) (xy 345.123089 -408.41101)
			(xy 345.106752 -408.439366) (xy 345.103453 -408.445399) (xy 345.099837 -408.458656) (xy 345.09964 -408.465528)
			(xy 345.09964 -409.214828) (xy 345.099816 -409.221702) (xy 345.103435 -409.234965) (xy 345.106752 -409.24099)
			(xy 345.123059 -409.269363) (xy 345.148806 -409.329526) (xy 345.166236 -409.392602) (xy 345.175033 -409.457449)
			(xy 345.175038 -409.522889) (xy 345.166249 -409.587737) (xy 345.148827 -409.650816) (xy 345.123087 -409.710982)
			(xy 345.106752 -409.739338) (xy 345.103428 -409.745358) (xy 345.099828 -409.758625) (xy 345.09964 -409.7655)
			(xy 345.09964 -410.051504) (xy 345.099182 -410.061653) (xy 345.091393 -410.080398) (xy 345.077008 -410.09472)
			(xy 345.058229 -410.102427) (xy 345.048078 -410.102812) (xy 344.331798 -410.102812) (xy 344.321678 -410.102277)
			(xy 344.302966 -410.094558) (xy 344.288612 -410.080287) (xy 344.280784 -410.061621) (xy 344.280236 -410.051504)
			(xy 344.280236 -409.7655) (xy 344.28004 -409.758627) (xy 344.276434 -409.745365) (xy 344.273124 -409.739338)
			(xy 344.256757 -409.710999) (xy 344.231016 -409.650828) (xy 344.213594 -409.587744) (xy 344.204805 -409.522892)
			(xy 342.916246 -409.522892) (xy 342.906858 -409.539186) (xy 342.9035 -409.545204) (xy 342.89976 -409.558462)
			(xy 342.899492 -409.565348) (xy 342.899492 -410.314648) (xy 342.899746 -410.321538) (xy 342.903474 -410.334804)
			(xy 342.906858 -410.34081) (xy 342.923182 -410.369174) (xy 342.948927 -410.429339) (xy 342.966355 -410.492417)
			(xy 342.97515 -410.557265) (xy 342.975152 -410.622707) (xy 342.975152 -410.622709) (xy 346.404958 -410.622709)
			(xy 346.404959 -410.557264) (xy 346.413755 -410.492413) (xy 346.431185 -410.429333) (xy 346.456933 -410.369166)
			(xy 346.473272 -410.34081) (xy 346.476581 -410.334783) (xy 346.480191 -410.321521) (xy 346.480384 -410.314648)
			(xy 346.480384 -409.565348) (xy 346.480176 -409.558476) (xy 346.476579 -409.545213) (xy 346.473272 -409.539186)
			(xy 346.456944 -409.510825) (xy 346.431197 -409.450659) (xy 346.413768 -409.38758) (xy 346.404974 -409.322732)
			(xy 346.404972 -409.257289) (xy 346.413764 -409.19244) (xy 346.43119 -409.12936) (xy 346.456934 -409.069194)
			(xy 346.473272 -409.040838) (xy 346.476571 -409.034806) (xy 346.480187 -409.021548) (xy 346.480384 -409.014676)
			(xy 346.480384 -408.728672) (xy 346.480798 -408.718518) (xy 346.4886 -408.699768) (xy 346.502999 -408.685446)
			(xy 346.52179 -408.677745) (xy 346.531946 -408.677364) (xy 347.248226 -408.677364) (xy 347.258357 -408.677806)
			(xy 347.277084 -408.685547) (xy 347.29144 -408.699847) (xy 347.299254 -408.718543) (xy 347.299788 -408.728672)
			(xy 347.299788 -409.014676) (xy 347.29999 -409.021548) (xy 347.303592 -409.034811) (xy 347.3069 -409.040838)
			(xy 347.323246 -409.069189) (xy 347.348987 -409.129357) (xy 347.366411 -409.192438) (xy 347.375202 -409.257289)
			(xy 347.375201 -409.322732) (xy 347.366407 -409.387582) (xy 347.34898 -409.450662) (xy 347.332079 -409.490164)
			(xy 348.603832 -409.490164) (xy 348.607823 -409.427997) (xy 348.619732 -409.36685) (xy 348.639361 -409.307729)
			(xy 348.66639 -409.251603) (xy 348.700374 -409.199394) (xy 348.740756 -409.151959) (xy 348.786872 -409.110078)
			(xy 348.837964 -409.074438) (xy 348.893195 -409.045624) (xy 348.951657 -409.02411) (xy 349.012391 -409.010248)
			(xy 349.074398 -409.004266) (xy 349.136661 -409.006262) (xy 349.198158 -409.016205) (xy 349.257879 -409.033929)
			(xy 349.314842 -409.059146) (xy 349.368113 -409.091439) (xy 349.416818 -409.130279) (xy 349.460155 -409.175029)
			(xy 349.497415 -409.224953) (xy 349.527984 -409.279232) (xy 349.532348 -409.290012) (xy 350.80398 -409.290012)
			(xy 350.807971 -409.227845) (xy 350.81988 -409.166698) (xy 350.839509 -409.107577) (xy 350.866538 -409.051451)
			(xy 350.900522 -408.999242) (xy 350.940904 -408.951807) (xy 350.98702 -408.909926) (xy 351.038112 -408.874286)
			(xy 351.093343 -408.845472) (xy 351.151805 -408.823958) (xy 351.212539 -408.810096) (xy 351.274546 -408.804114)
			(xy 351.336809 -408.80611) (xy 351.398306 -408.816053) (xy 351.458027 -408.833777) (xy 351.51499 -408.858994)
			(xy 351.568261 -408.891287) (xy 351.616966 -408.930127) (xy 351.660303 -408.974877) (xy 351.697563 -409.024801)
			(xy 351.728132 -409.07908) (xy 351.75151 -409.136823) (xy 351.767311 -409.197081) (xy 351.775277 -409.258864)
			(xy 351.775776 -409.290012) (xy 351.775277 -409.32116) (xy 351.767311 -409.382943) (xy 351.75151 -409.443201)
			(xy 351.728132 -409.500944) (xy 351.697563 -409.555223) (xy 351.660303 -409.605147) (xy 351.616966 -409.649897)
			(xy 351.568261 -409.688737) (xy 351.51499 -409.72103) (xy 351.458027 -409.746247) (xy 351.398306 -409.763971)
			(xy 351.336809 -409.773914) (xy 351.274546 -409.77591) (xy 351.212539 -409.769928) (xy 351.151805 -409.756066)
			(xy 351.093343 -409.734552) (xy 351.038112 -409.705738) (xy 350.98702 -409.670098) (xy 350.940904 -409.628217)
			(xy 350.900522 -409.580782) (xy 350.866538 -409.528573) (xy 350.839509 -409.472447) (xy 350.81988 -409.413326)
			(xy 350.807971 -409.352179) (xy 350.80398 -409.290012) (xy 349.532348 -409.290012) (xy 349.551362 -409.336975)
			(xy 349.567163 -409.397233) (xy 349.575129 -409.459016) (xy 349.575628 -409.490164) (xy 349.575129 -409.521312)
			(xy 349.567163 -409.583095) (xy 349.551362 -409.643353) (xy 349.527984 -409.701096) (xy 349.497415 -409.755375)
			(xy 349.460155 -409.805299) (xy 349.416818 -409.850049) (xy 349.368113 -409.888889) (xy 349.314842 -409.921182)
			(xy 349.257879 -409.946399) (xy 349.198158 -409.964123) (xy 349.136661 -409.974066) (xy 349.074398 -409.976062)
			(xy 349.012391 -409.97008) (xy 348.951657 -409.956218) (xy 348.893195 -409.934704) (xy 348.837964 -409.90589)
			(xy 348.786872 -409.87025) (xy 348.740756 -409.828369) (xy 348.700374 -409.780934) (xy 348.66639 -409.728725)
			(xy 348.639361 -409.672599) (xy 348.619732 -409.613478) (xy 348.607823 -409.552331) (xy 348.603832 -409.490164)
			(xy 347.332079 -409.490164) (xy 347.323237 -409.510829) (xy 347.3069 -409.539186) (xy 347.30359 -409.545213)
			(xy 347.299981 -409.558475) (xy 347.299788 -409.565348) (xy 347.299788 -410.314648) (xy 347.300002 -410.32152)
			(xy 347.303595 -410.334782) (xy 347.3069 -410.34081) (xy 347.323223 -410.369174) (xy 347.348966 -410.429339)
			(xy 347.366392 -410.492418) (xy 347.375186 -410.557266) (xy 347.375187 -410.589984) (xy 350.80398 -410.589984)
			(xy 350.807971 -410.527817) (xy 350.81988 -410.46667) (xy 350.839509 -410.407549) (xy 350.866538 -410.351423)
			(xy 350.900522 -410.299214) (xy 350.940904 -410.251779) (xy 350.98702 -410.209898) (xy 351.038112 -410.174258)
			(xy 351.093343 -410.145444) (xy 351.151805 -410.12393) (xy 351.212539 -410.110068) (xy 351.274546 -410.104086)
			(xy 351.336809 -410.106082) (xy 351.398306 -410.116025) (xy 351.458027 -410.133749) (xy 351.51499 -410.158966)
			(xy 351.568261 -410.191259) (xy 351.616966 -410.230099) (xy 351.660303 -410.274849) (xy 351.697563 -410.324773)
			(xy 351.728132 -410.379052) (xy 351.75151 -410.436795) (xy 351.767311 -410.497053) (xy 351.775277 -410.558836)
			(xy 351.775776 -410.589984) (xy 351.775277 -410.621132) (xy 351.767311 -410.682915) (xy 351.75151 -410.743173)
			(xy 351.728132 -410.800916) (xy 351.697563 -410.855195) (xy 351.660303 -410.905119) (xy 351.616966 -410.949869)
			(xy 351.568261 -410.988709) (xy 351.51499 -411.021002) (xy 351.458027 -411.046219) (xy 351.398306 -411.063943)
			(xy 351.336809 -411.073886) (xy 351.274546 -411.075882) (xy 351.212539 -411.0699) (xy 351.151805 -411.056038)
			(xy 351.093343 -411.034524) (xy 351.038112 -411.00571) (xy 350.98702 -410.97007) (xy 350.940904 -410.928189)
			(xy 350.900522 -410.880754) (xy 350.866538 -410.828545) (xy 350.839509 -410.772419) (xy 350.81988 -410.713298)
			(xy 350.807971 -410.652151) (xy 350.80398 -410.589984) (xy 347.375187 -410.589984) (xy 347.375188 -410.622707)
			(xy 347.366398 -410.687555) (xy 347.348975 -410.750635) (xy 347.323235 -410.810801) (xy 347.3069 -410.839158)
			(xy 347.3036 -410.84519) (xy 347.299985 -410.858448) (xy 347.299788 -410.86532) (xy 347.299788 -411.151324)
			(xy 347.299398 -411.161481) (xy 347.291592 -411.180236) (xy 347.277186 -411.194559) (xy 347.258386 -411.202256)
			(xy 347.248226 -411.202632) (xy 346.531946 -411.202632) (xy 346.521819 -411.202135) (xy 346.503093 -411.194417)
			(xy 346.488735 -411.180133) (xy 346.480919 -411.161449) (xy 346.480384 -411.151324) (xy 346.480384 -410.86532)
			(xy 346.480186 -410.858447) (xy 346.476582 -410.845184) (xy 346.473272 -410.839158) (xy 346.45692 -410.81081)
			(xy 346.431176 -410.750642) (xy 346.41375 -410.68756) (xy 346.404958 -410.622709) (xy 342.975152 -410.622709)
			(xy 342.966361 -410.687556) (xy 342.948936 -410.750635) (xy 342.923194 -410.810802) (xy 342.906858 -410.839158)
			(xy 342.903474 -410.845163) (xy 342.899751 -410.858431) (xy 342.899492 -410.86532) (xy 342.899492 -411.151324)
			(xy 342.899034 -411.161435) (xy 342.891287 -411.180116) (xy 342.876982 -411.19441) (xy 342.858296 -411.202142)
			(xy 342.848184 -411.202632) (xy 342.131904 -411.202632) (xy 342.121799 -411.202112) (xy 342.103128 -411.194382)
			(xy 342.088834 -411.180096) (xy 342.081093 -411.161428) (xy 342.080596 -411.151324) (xy 342.080596 -410.86532)
			(xy 342.080356 -410.858429) (xy 342.076618 -410.845163) (xy 342.07323 -410.839158) (xy 342.056879 -410.810809)
			(xy 342.031137 -410.750641) (xy 342.013713 -410.687559) (xy 342.004921 -410.622708) (xy 338.575116 -410.622708)
			(xy 338.566324 -410.687557) (xy 338.548898 -410.750636) (xy 338.523154 -410.810802) (xy 338.506816 -410.839158)
			(xy 338.503517 -410.845191) (xy 338.499901 -410.858448) (xy 338.499704 -410.86532) (xy 338.499704 -411.151324)
			(xy 338.499298 -411.161479) (xy 338.491495 -411.180231) (xy 338.477094 -411.194554) (xy 338.458299 -411.202253)
			(xy 338.448142 -411.202632) (xy 337.731862 -411.202632) (xy 337.721729 -411.202204) (xy 337.703002 -411.194458)
			(xy 337.688646 -411.180154) (xy 337.680833 -411.161455) (xy 337.6803 -411.151324) (xy 337.6803 -410.86532)
			(xy 337.6801 -410.858447) (xy 337.676497 -410.845185) (xy 337.673188 -410.839158) (xy 337.656836 -410.81081)
			(xy 337.63109 -410.750642) (xy 337.613664 -410.68756) (xy 337.604871 -410.622709) (xy 334.175066 -410.622709)
			(xy 334.166275 -410.687556) (xy 334.148851 -410.750635) (xy 334.12311 -410.810802) (xy 334.106774 -410.839158)
			(xy 334.103391 -410.845164) (xy 334.099667 -410.858431) (xy 334.099408 -410.86532) (xy 334.099408 -411.151324)
			(xy 334.098935 -411.161433) (xy 334.091191 -411.180111) (xy 334.07689 -411.194404) (xy 334.05821 -411.20214)
			(xy 334.0481 -411.202632) (xy 333.33182 -411.202632) (xy 333.321716 -411.202099) (xy 333.303045 -411.194374)
			(xy 333.28875 -411.180092) (xy 333.281009 -411.161427) (xy 333.280512 -411.151324) (xy 333.280512 -410.86532)
			(xy 333.280305 -410.858425) (xy 333.276559 -410.845153) (xy 333.273146 -410.839158) (xy 333.256795 -410.810809)
			(xy 333.231052 -410.750641) (xy 333.213627 -410.687559) (xy 333.204835 -410.622708) (xy 326.525636 -410.622708)
			(xy 326.525636 -412.090108) (xy 331.003918 -412.090108) (xy 331.007909 -412.027941) (xy 331.019818 -411.966794)
			(xy 331.039447 -411.907673) (xy 331.066476 -411.851547) (xy 331.10046 -411.799338) (xy 331.140842 -411.751903)
			(xy 331.186958 -411.710022) (xy 331.23805 -411.674382) (xy 331.293281 -411.645568) (xy 331.351743 -411.624054)
			(xy 331.412477 -411.610192) (xy 331.474484 -411.60421) (xy 331.536747 -411.606206) (xy 331.598244 -411.616149)
			(xy 331.657965 -411.633873) (xy 331.714928 -411.65909) (xy 331.768199 -411.691383) (xy 331.816904 -411.730223)
			(xy 331.860241 -411.774973) (xy 331.897501 -411.824897) (xy 331.92807 -411.879176) (xy 331.951448 -411.936919)
			(xy 331.967249 -411.997177) (xy 331.975215 -412.05896) (xy 331.975714 -412.090108) (xy 335.40396 -412.090108)
			(xy 335.407951 -412.027941) (xy 335.41986 -411.966794) (xy 335.439489 -411.907673) (xy 335.466518 -411.851547)
			(xy 335.500502 -411.799338) (xy 335.540884 -411.751903) (xy 335.587 -411.710022) (xy 335.638092 -411.674382)
			(xy 335.693323 -411.645568) (xy 335.751785 -411.624054) (xy 335.812519 -411.610192) (xy 335.874526 -411.60421)
			(xy 335.936789 -411.606206) (xy 335.998286 -411.616149) (xy 336.058007 -411.633873) (xy 336.11497 -411.65909)
			(xy 336.168241 -411.691383) (xy 336.216946 -411.730223) (xy 336.260283 -411.774973) (xy 336.297543 -411.824897)
			(xy 336.328112 -411.879176) (xy 336.35149 -411.936919) (xy 336.367291 -411.997177) (xy 336.375257 -412.05896)
			(xy 336.375756 -412.090108) (xy 339.804002 -412.090108) (xy 339.807993 -412.027941) (xy 339.819902 -411.966794)
			(xy 339.839531 -411.907673) (xy 339.86656 -411.851547) (xy 339.900544 -411.799338) (xy 339.940926 -411.751903)
			(xy 339.987042 -411.710022) (xy 340.038134 -411.674382) (xy 340.093365 -411.645568) (xy 340.151827 -411.624054)
			(xy 340.212561 -411.610192) (xy 340.274568 -411.60421) (xy 340.336831 -411.606206) (xy 340.398328 -411.616149)
			(xy 340.458049 -411.633873) (xy 340.515012 -411.65909) (xy 340.568283 -411.691383) (xy 340.616988 -411.730223)
			(xy 340.660325 -411.774973) (xy 340.697585 -411.824897) (xy 340.728154 -411.879176) (xy 340.751532 -411.936919)
			(xy 340.767333 -411.997177) (xy 340.775299 -412.05896) (xy 340.775798 -412.090108) (xy 344.20379 -412.090108)
			(xy 344.207781 -412.027941) (xy 344.21969 -411.966794) (xy 344.239319 -411.907673) (xy 344.266348 -411.851547)
			(xy 344.300332 -411.799338) (xy 344.340714 -411.751903) (xy 344.38683 -411.710022) (xy 344.437922 -411.674382)
			(xy 344.493153 -411.645568) (xy 344.551615 -411.624054) (xy 344.612349 -411.610192) (xy 344.674356 -411.60421)
			(xy 344.736619 -411.606206) (xy 344.798116 -411.616149) (xy 344.857837 -411.633873) (xy 344.9148 -411.65909)
			(xy 344.968071 -411.691383) (xy 345.016776 -411.730223) (xy 345.060113 -411.774973) (xy 345.097373 -411.824897)
			(xy 345.127942 -411.879176) (xy 345.15132 -411.936919) (xy 345.167121 -411.997177) (xy 345.175087 -412.05896)
			(xy 345.175586 -412.090108) (xy 348.603832 -412.090108) (xy 348.607823 -412.027941) (xy 348.619732 -411.966794)
			(xy 348.639361 -411.907673) (xy 348.66639 -411.851547) (xy 348.700374 -411.799338) (xy 348.740756 -411.751903)
			(xy 348.786872 -411.710022) (xy 348.837964 -411.674382) (xy 348.893195 -411.645568) (xy 348.951657 -411.624054)
			(xy 349.012391 -411.610192) (xy 349.074398 -411.60421) (xy 349.136661 -411.606206) (xy 349.198158 -411.616149)
			(xy 349.257879 -411.633873) (xy 349.314842 -411.65909) (xy 349.368113 -411.691383) (xy 349.416818 -411.730223)
			(xy 349.460155 -411.774973) (xy 349.497415 -411.824897) (xy 349.527984 -411.879176) (xy 349.551362 -411.936919)
			(xy 349.567163 -411.997177) (xy 349.575129 -412.05896) (xy 349.575628 -412.090108) (xy 349.575129 -412.121256)
			(xy 349.567163 -412.183039) (xy 349.551362 -412.243297) (xy 349.527984 -412.30104) (xy 349.497415 -412.355319)
			(xy 349.460155 -412.405243) (xy 349.416818 -412.449993) (xy 349.368113 -412.488833) (xy 349.314842 -412.521126)
			(xy 349.257879 -412.546343) (xy 349.198158 -412.564067) (xy 349.136661 -412.57401) (xy 349.074398 -412.576006)
			(xy 349.012391 -412.570024) (xy 348.951657 -412.556162) (xy 348.893195 -412.534648) (xy 348.837964 -412.505834)
			(xy 348.786872 -412.470194) (xy 348.740756 -412.428313) (xy 348.700374 -412.380878) (xy 348.66639 -412.328669)
			(xy 348.639361 -412.272543) (xy 348.619732 -412.213422) (xy 348.607823 -412.152275) (xy 348.603832 -412.090108)
			(xy 345.175586 -412.090108) (xy 345.175087 -412.121256) (xy 345.167121 -412.183039) (xy 345.15132 -412.243297)
			(xy 345.127942 -412.30104) (xy 345.097373 -412.355319) (xy 345.060113 -412.405243) (xy 345.016776 -412.449993)
			(xy 344.968071 -412.488833) (xy 344.9148 -412.521126) (xy 344.857837 -412.546343) (xy 344.798116 -412.564067)
			(xy 344.736619 -412.57401) (xy 344.674356 -412.576006) (xy 344.612349 -412.570024) (xy 344.551615 -412.556162)
			(xy 344.493153 -412.534648) (xy 344.437922 -412.505834) (xy 344.38683 -412.470194) (xy 344.340714 -412.428313)
			(xy 344.300332 -412.380878) (xy 344.266348 -412.328669) (xy 344.239319 -412.272543) (xy 344.21969 -412.213422)
			(xy 344.207781 -412.152275) (xy 344.20379 -412.090108) (xy 340.775798 -412.090108) (xy 340.775299 -412.121256)
			(xy 340.767333 -412.183039) (xy 340.751532 -412.243297) (xy 340.728154 -412.30104) (xy 340.697585 -412.355319)
			(xy 340.660325 -412.405243) (xy 340.616988 -412.449993) (xy 340.568283 -412.488833) (xy 340.515012 -412.521126)
			(xy 340.458049 -412.546343) (xy 340.398328 -412.564067) (xy 340.336831 -412.57401) (xy 340.274568 -412.576006)
			(xy 340.212561 -412.570024) (xy 340.151827 -412.556162) (xy 340.093365 -412.534648) (xy 340.038134 -412.505834)
			(xy 339.987042 -412.470194) (xy 339.940926 -412.428313) (xy 339.900544 -412.380878) (xy 339.86656 -412.328669)
			(xy 339.839531 -412.272543) (xy 339.819902 -412.213422) (xy 339.807993 -412.152275) (xy 339.804002 -412.090108)
			(xy 336.375756 -412.090108) (xy 336.375257 -412.121256) (xy 336.367291 -412.183039) (xy 336.35149 -412.243297)
			(xy 336.328112 -412.30104) (xy 336.297543 -412.355319) (xy 336.260283 -412.405243) (xy 336.216946 -412.449993)
			(xy 336.168241 -412.488833) (xy 336.11497 -412.521126) (xy 336.058007 -412.546343) (xy 335.998286 -412.564067)
			(xy 335.936789 -412.57401) (xy 335.874526 -412.576006) (xy 335.812519 -412.570024) (xy 335.751785 -412.556162)
			(xy 335.693323 -412.534648) (xy 335.638092 -412.505834) (xy 335.587 -412.470194) (xy 335.540884 -412.428313)
			(xy 335.500502 -412.380878) (xy 335.466518 -412.328669) (xy 335.439489 -412.272543) (xy 335.41986 -412.213422)
			(xy 335.407951 -412.152275) (xy 335.40396 -412.090108) (xy 331.975714 -412.090108) (xy 331.975215 -412.121256)
			(xy 331.967249 -412.183039) (xy 331.951448 -412.243297) (xy 331.92807 -412.30104) (xy 331.897501 -412.355319)
			(xy 331.860241 -412.405243) (xy 331.816904 -412.449993) (xy 331.768199 -412.488833) (xy 331.714928 -412.521126)
			(xy 331.657965 -412.546343) (xy 331.598244 -412.564067) (xy 331.536747 -412.57401) (xy 331.474484 -412.576006)
			(xy 331.412477 -412.570024) (xy 331.351743 -412.556162) (xy 331.293281 -412.534648) (xy 331.23805 -412.505834)
			(xy 331.186958 -412.470194) (xy 331.140842 -412.428313) (xy 331.10046 -412.380878) (xy 331.066476 -412.328669)
			(xy 331.039447 -412.272543) (xy 331.019818 -412.213422) (xy 331.007909 -412.152275) (xy 331.003918 -412.090108)
			(xy 326.525636 -412.090108) (xy 326.525636 -416.324288) (xy 326.526756 -416.333797) (xy 326.535061 -416.351033)
			(xy 326.549075 -416.36406) (xy 326.566871 -416.371087) (xy 326.576436 -416.371532) (xy 371.984778 -416.371532)
			(xy 371.994829 -416.371027) (xy 372.013391 -416.363307) (xy 372.020846 -416.356546) (xy 372.587266 -415.790126)
			(xy 372.594105 -415.782725) (xy 372.601817 -415.764126) (xy 372.602252 -415.754058) (xy 372.602252 -399.75536)
			(xy 372.60182 -399.745294) (xy 372.59409 -399.726705) (xy 372.587266 -399.719292) (xy 366.057942 -393.189968)
			(xy 366.051096 -393.18257) (xy 366.043367 -393.163971) (xy 366.042956 -393.1539) (xy 366.042956 -391.674604)
			(xy 366.018064 -391.645902) (xy 365.999014 -391.643362) (xy 365.971953 -391.639178) (xy 365.919324 -391.624065)
			(xy 365.869396 -391.601583) (xy 365.823195 -391.572194) (xy 365.781671 -391.536501) (xy 365.745676 -391.495238)
			(xy 365.71595 -391.449253) (xy 365.693104 -391.399491) (xy 365.677608 -391.346973) (xy 365.669779 -391.292779)
			(xy 365.669779 -391.238023) (xy 365.677607 -391.18383) (xy 365.693103 -391.131312) (xy 365.715949 -391.081549)
			(xy 365.745674 -391.035564) (xy 365.781669 -390.994301) (xy 365.823193 -390.958608) (xy 365.869394 -390.929218)
			(xy 365.919321 -390.906736) (xy 365.971951 -390.891623) (xy 365.999014 -390.887458) (xy 366.018064 -390.884918)
			(xy 366.042956 -390.856216) (xy 366.042956 -382.166368) (xy 365.628936 -371.246146) (xy 365.628428 -371.2083)
			(xy 365.628428 -371.19687) (xy 365.758476 -359.785158) (xy 365.757996 -359.77392) (xy 365.748637 -359.753494)
			(xy 365.740442 -359.745788) (xy 365.672116 -359.687622) (xy 365.650272 -359.68178) (xy 365.639096 -359.683812)
			(xy 365.622348 -359.686644) (xy 365.588516 -359.6897) (xy 365.571532 -359.689908) (xy 365.544278 -359.689447)
			(xy 365.490323 -359.681694) (xy 365.438022 -359.66634) (xy 365.388437 -359.6437) (xy 365.34258 -359.614233)
			(xy 365.301384 -359.578539) (xy 365.265687 -359.537345) (xy 365.236216 -359.491491) (xy 365.213571 -359.441908)
			(xy 365.198213 -359.389608) (xy 365.190455 -359.335654) (xy 365.190455 -359.281146) (xy 365.198213 -359.227192)
			(xy 365.213571 -359.174892) (xy 365.236216 -359.125309) (xy 365.265687 -359.079455) (xy 365.301384 -359.038261)
			(xy 365.34258 -359.002567) (xy 365.388437 -358.9731) (xy 365.438022 -358.95046) (xy 365.490323 -358.935106)
			(xy 365.544278 -358.927353) (xy 365.571532 -358.926892) (xy 365.571786 -358.926892) (xy 365.59084 -358.927142)
			(xy 365.628757 -358.930955) (xy 365.647478 -358.934512) (xy 365.658654 -358.936798) (xy 365.680752 -358.931464)
			(xy 365.750348 -358.875076) (xy 365.758753 -358.8676) (xy 365.768663 -358.847436) (xy 365.769398 -358.836214)
			(xy 365.963454 -341.823548) (xy 365.96433 -341.782172) (xy 365.972089 -341.699769) (xy 365.978948 -341.658956)
			(xy 366.063784 -341.1855) (xy 366.072087 -341.142054) (xy 366.095401 -341.056722) (xy 366.126177 -340.973789)
			(xy 366.164175 -340.893906) (xy 366.186212 -340.855554) (xy 367.110264 -339.286088) (xy 367.11128 -339.274404)
			(xy 367.114101 -339.245771) (xy 367.127258 -339.189762) (xy 367.148675 -339.136363) (xy 367.177868 -339.086785)
			(xy 367.214173 -339.042153) (xy 367.256768 -339.003477) (xy 367.280444 -338.98713) (xy 367.28527 -338.983828)
			(xy 367.293144 -338.975446) (xy 367.62309 -338.41563) (xy 367.645946 -338.377728) (xy 367.697419 -338.305716)
			(xy 367.755072 -338.23855) (xy 367.818453 -338.17676) (xy 367.852452 -338.148422) (xy 369.602004 -336.722974)
			(xy 369.610396 -336.715354) (xy 369.620143 -336.694921) (xy 369.6208 -336.683604) (xy 369.6208 -328.555858)
			(xy 369.620369 -328.545791) (xy 369.612644 -328.527198) (xy 369.605814 -328.51979) (xy 369.33759 -328.251566)
			(xy 369.330194 -328.244714) (xy 369.311595 -328.236973) (xy 369.301522 -328.23658) (xy 335.176876 -328.23658)
			(xy 335.165744 -328.237205) (xy 335.145592 -328.246689) (xy 335.138014 -328.254868) (xy 335.119814 -328.275989)
			(xy 335.078296 -328.313201) (xy 335.031802 -328.343969) (xy 334.981322 -328.367639) (xy 334.927934 -328.383705)
			(xy 334.872775 -328.391824) (xy 334.817021 -328.391824) (xy 334.761862 -328.383705) (xy 334.708474 -328.367639)
			(xy 334.657994 -328.343969) (xy 334.6115 -328.313201) (xy 334.569982 -328.275989) (xy 334.551782 -328.254868)
			(xy 334.544226 -328.24666) (xy 334.524061 -328.237178) (xy 334.51292 -328.23658) (xy 329.629008 -328.23658)
			(xy 329.618937 -328.237001) (xy 329.600328 -328.244711) (xy 329.59294 -328.251566) (xy 329.509374 -328.335132)
			(xy 329.500992 -328.346054) (xy 329.115693 -329.026774) (xy 334.46288 -329.026774) (xy 334.466951 -328.971152)
			(xy 334.479077 -328.916715) (xy 334.499 -328.864624) (xy 334.526296 -328.815989) (xy 334.560382 -328.771846)
			(xy 334.600531 -328.733137) (xy 334.645889 -328.700686) (xy 334.695489 -328.675185) (xy 334.748273 -328.657178)
			(xy 334.803116 -328.647048) (xy 334.85885 -328.645011) (xy 334.914287 -328.651111) (xy 334.968244 -328.665217)
			(xy 335.019573 -328.687029) (xy 335.067179 -328.716083) (xy 335.110047 -328.751758) (xy 335.147264 -328.793295)
			(xy 335.178037 -328.839808) (xy 335.201709 -328.890305) (xy 335.217777 -328.943712) (xy 335.225897 -328.998888)
			(xy 335.226406 -329.026774) (xy 335.225897 -329.05466) (xy 335.217777 -329.109836) (xy 335.201709 -329.163243)
			(xy 335.178037 -329.21374) (xy 335.147264 -329.260253) (xy 335.110047 -329.30179) (xy 335.067179 -329.337465)
			(xy 335.019573 -329.366519) (xy 334.968244 -329.388331) (xy 334.914287 -329.402437) (xy 334.85885 -329.408537)
			(xy 334.803116 -329.4065) (xy 334.748273 -329.39637) (xy 334.695489 -329.378363) (xy 334.645889 -329.352862)
			(xy 334.600531 -329.320411) (xy 334.560382 -329.281702) (xy 334.526296 -329.237559) (xy 334.499 -329.188924)
			(xy 334.479077 -329.136833) (xy 334.466951 -329.082396) (xy 334.46288 -329.026774) (xy 329.115693 -329.026774)
			(xy 328.000339 -330.997306) (xy 351.42119 -330.997306) (xy 351.425261 -330.941684) (xy 351.437387 -330.887247)
			(xy 351.45731 -330.835156) (xy 351.484606 -330.786521) (xy 351.518692 -330.742378) (xy 351.558841 -330.703669)
			(xy 351.604199 -330.671218) (xy 351.653799 -330.645717) (xy 351.706583 -330.62771) (xy 351.761426 -330.61758)
			(xy 351.81716 -330.615543) (xy 351.872597 -330.621643) (xy 351.926554 -330.635749) (xy 351.977883 -330.657561)
			(xy 352.025489 -330.686615) (xy 352.068357 -330.72229) (xy 352.105574 -330.763827) (xy 352.136347 -330.81034)
			(xy 352.160019 -330.860837) (xy 352.176087 -330.914244) (xy 352.184207 -330.96942) (xy 352.184716 -330.997306)
			(xy 352.43719 -330.997306) (xy 352.441261 -330.941684) (xy 352.453387 -330.887247) (xy 352.47331 -330.835156)
			(xy 352.500606 -330.786521) (xy 352.534692 -330.742378) (xy 352.574841 -330.703669) (xy 352.620199 -330.671218)
			(xy 352.669799 -330.645717) (xy 352.722583 -330.62771) (xy 352.777426 -330.61758) (xy 352.83316 -330.615543)
			(xy 352.888597 -330.621643) (xy 352.942554 -330.635749) (xy 352.950595 -330.639166) (xy 359.716576 -330.639166)
			(xy 359.720647 -330.583544) (xy 359.732773 -330.529107) (xy 359.752696 -330.477016) (xy 359.779992 -330.428381)
			(xy 359.814078 -330.384238) (xy 359.854227 -330.345529) (xy 359.899585 -330.313078) (xy 359.949185 -330.287577)
			(xy 360.001969 -330.26957) (xy 360.056812 -330.25944) (xy 360.112546 -330.257403) (xy 360.167983 -330.263503)
			(xy 360.22194 -330.277609) (xy 360.273269 -330.299421) (xy 360.320875 -330.328475) (xy 360.363743 -330.36415)
			(xy 360.40096 -330.405687) (xy 360.431733 -330.4522) (xy 360.455405 -330.502697) (xy 360.471473 -330.556104)
			(xy 360.479593 -330.61128) (xy 360.480023 -330.634848) (xy 360.612434 -330.634848) (xy 360.616505 -330.579226)
			(xy 360.628631 -330.524789) (xy 360.648554 -330.472698) (xy 360.67585 -330.424063) (xy 360.709936 -330.37992)
			(xy 360.750085 -330.341211) (xy 360.795443 -330.30876) (xy 360.845043 -330.283259) (xy 360.897827 -330.265252)
			(xy 360.95267 -330.255122) (xy 361.008404 -330.253085) (xy 361.063841 -330.259185) (xy 361.117798 -330.273291)
			(xy 361.169127 -330.295103) (xy 361.216733 -330.324157) (xy 361.259601 -330.359832) (xy 361.296818 -330.401369)
			(xy 361.327591 -330.447882) (xy 361.351263 -330.498379) (xy 361.367331 -330.551786) (xy 361.375451 -330.606962)
			(xy 361.375953 -330.634457) (xy 361.500817 -330.634457) (xy 361.500817 -330.579943) (xy 361.508575 -330.525984)
			(xy 361.523934 -330.473679) (xy 361.546581 -330.424092) (xy 361.576055 -330.378233) (xy 361.611755 -330.337035)
			(xy 361.652955 -330.301338) (xy 361.698817 -330.271868) (xy 361.748405 -330.249225) (xy 361.800712 -330.23387)
			(xy 361.854671 -330.226115) (xy 361.881928 -330.225654) (xy 361.907882 -330.226066) (xy 361.959312 -330.233101)
			(xy 362.00931 -330.24705) (xy 362.056954 -330.267655) (xy 362.10136 -330.294536) (xy 362.141708 -330.327193)
			(xy 362.17725 -330.365025) (xy 362.20733 -330.407329) (xy 362.219748 -330.430124) (xy 362.226098 -330.442062)
			(xy 362.248704 -330.45654) (xy 362.363512 -330.462128) (xy 362.387388 -330.449682) (xy 362.394754 -330.438506)
			(xy 362.409906 -330.416079) (xy 362.445615 -330.375404) (xy 362.48671 -330.340181) (xy 362.532369 -330.311115)
			(xy 362.581676 -330.288789) (xy 362.633641 -330.273651) (xy 362.687223 -330.266005) (xy 362.714286 -330.265532)
			(xy 362.743578 -330.266126) (xy 362.801473 -330.275085) (xy 362.857321 -330.292781) (xy 362.909811 -330.318797)
			(xy 362.957713 -330.352524) (xy 362.999902 -330.39317) (xy 363.01807 -330.416154) (xy 363.025436 -330.42606)
			(xy 363.047026 -330.436474) (xy 363.153706 -330.434442) (xy 363.175042 -330.423266) (xy 363.182154 -330.413106)
			(xy 363.197551 -330.391988) (xy 363.233128 -330.353707) (xy 363.273599 -330.320643) (xy 363.318205 -330.293413)
			(xy 363.366111 -330.272529) (xy 363.41642 -330.258381) (xy 363.46819 -330.251235) (xy 363.49432 -330.2508)
			(xy 363.521571 -330.251271) (xy 363.575518 -330.25903) (xy 363.627811 -330.274387) (xy 363.677387 -330.29703)
			(xy 363.723236 -330.326498) (xy 363.764424 -330.36219) (xy 363.800114 -330.40338) (xy 363.82958 -330.449231)
			(xy 363.85222 -330.498808) (xy 363.867574 -330.551102) (xy 363.87533 -330.605049) (xy 363.87533 -330.659551)
			(xy 363.867574 -330.713498) (xy 363.85222 -330.765792) (xy 363.829579 -330.815369) (xy 363.800114 -330.86122)
			(xy 363.764424 -330.90241) (xy 363.723236 -330.938102) (xy 363.677387 -330.96757) (xy 363.627811 -330.990213)
			(xy 363.575518 -331.00557) (xy 363.521571 -331.013329) (xy 363.49432 -331.013816) (xy 363.465025 -331.01331)
			(xy 363.407125 -331.004335) (xy 363.351274 -330.986624) (xy 363.298784 -330.960591) (xy 363.250885 -330.926847)
			(xy 363.2087 -330.886185) (xy 363.190536 -330.863194) (xy 363.18317 -330.853288) (xy 363.16158 -330.842874)
			(xy 363.0549 -330.844906) (xy 363.033564 -330.856082) (xy 363.026452 -330.866242) (xy 363.011066 -330.887368)
			(xy 362.975485 -330.925646) (xy 362.935012 -330.958709) (xy 362.890404 -330.985936) (xy 362.842497 -331.006819)
			(xy 362.792187 -331.020966) (xy 362.740416 -331.028113) (xy 362.714286 -331.028548) (xy 362.688332 -331.028123)
			(xy 362.636903 -331.02109) (xy 362.586905 -331.007143) (xy 362.539262 -330.98654) (xy 362.494855 -330.959661)
			(xy 362.454507 -330.927005) (xy 362.418965 -330.889175) (xy 362.388885 -330.846872) (xy 362.376466 -330.824078)
			(xy 362.370116 -330.81214) (xy 362.34751 -330.797662) (xy 362.232702 -330.792074) (xy 362.208826 -330.80452)
			(xy 362.20146 -330.815696) (xy 362.186267 -330.838095) (xy 362.150569 -330.878775) (xy 362.109482 -330.914003)
			(xy 362.06383 -330.943074) (xy 362.014529 -330.965405) (xy 361.962568 -330.980547) (xy 361.908989 -330.988196)
			(xy 361.881928 -330.98867) (xy 361.854671 -330.988285) (xy 361.800712 -330.98053) (xy 361.748405 -330.965175)
			(xy 361.698817 -330.942532) (xy 361.652955 -330.913062) (xy 361.611755 -330.877365) (xy 361.576055 -330.836167)
			(xy 361.546581 -330.790308) (xy 361.523934 -330.740721) (xy 361.508576 -330.688416) (xy 361.500817 -330.634457)
			(xy 361.375953 -330.634457) (xy 361.37596 -330.634848) (xy 361.375451 -330.662734) (xy 361.367331 -330.71791)
			(xy 361.351263 -330.771317) (xy 361.327591 -330.821814) (xy 361.296818 -330.868327) (xy 361.259601 -330.909864)
			(xy 361.216733 -330.945539) (xy 361.169127 -330.974593) (xy 361.117798 -330.996405) (xy 361.063841 -331.010511)
			(xy 361.008404 -331.016611) (xy 360.95267 -331.014574) (xy 360.897827 -331.004444) (xy 360.845043 -330.986437)
			(xy 360.795443 -330.960936) (xy 360.750085 -330.928485) (xy 360.709936 -330.889776) (xy 360.67585 -330.845633)
			(xy 360.648554 -330.796998) (xy 360.628631 -330.744907) (xy 360.616505 -330.69047) (xy 360.612434 -330.634848)
			(xy 360.480023 -330.634848) (xy 360.480102 -330.639166) (xy 360.479593 -330.667052) (xy 360.471473 -330.722228)
			(xy 360.455405 -330.775635) (xy 360.431733 -330.826132) (xy 360.40096 -330.872645) (xy 360.363743 -330.914182)
			(xy 360.320875 -330.949857) (xy 360.273269 -330.978911) (xy 360.22194 -331.000723) (xy 360.167983 -331.014829)
			(xy 360.112546 -331.020929) (xy 360.056812 -331.018892) (xy 360.001969 -331.008762) (xy 359.949185 -330.990755)
			(xy 359.899585 -330.965254) (xy 359.854227 -330.932803) (xy 359.814078 -330.894094) (xy 359.779992 -330.849951)
			(xy 359.752696 -330.801316) (xy 359.732773 -330.749225) (xy 359.720647 -330.694788) (xy 359.716576 -330.639166)
			(xy 352.950595 -330.639166) (xy 352.993883 -330.657561) (xy 353.041489 -330.686615) (xy 353.084357 -330.72229)
			(xy 353.121574 -330.763827) (xy 353.152347 -330.81034) (xy 353.176019 -330.860837) (xy 353.192087 -330.914244)
			(xy 353.200207 -330.96942) (xy 353.200716 -330.997306) (xy 353.200207 -331.025192) (xy 353.192087 -331.080368)
			(xy 353.176019 -331.133775) (xy 353.152347 -331.184272) (xy 353.121574 -331.230785) (xy 353.084357 -331.272322)
			(xy 353.041489 -331.307997) (xy 352.993883 -331.337051) (xy 352.942554 -331.358863) (xy 352.888597 -331.372969)
			(xy 352.83316 -331.379069) (xy 352.777426 -331.377032) (xy 352.722583 -331.366902) (xy 352.669799 -331.348895)
			(xy 352.620199 -331.323394) (xy 352.574841 -331.290943) (xy 352.534692 -331.252234) (xy 352.500606 -331.208091)
			(xy 352.47331 -331.159456) (xy 352.453387 -331.107365) (xy 352.441261 -331.052928) (xy 352.43719 -330.997306)
			(xy 352.184716 -330.997306) (xy 352.184207 -331.025192) (xy 352.176087 -331.080368) (xy 352.160019 -331.133775)
			(xy 352.136347 -331.184272) (xy 352.105574 -331.230785) (xy 352.068357 -331.272322) (xy 352.025489 -331.307997)
			(xy 351.977883 -331.337051) (xy 351.926554 -331.358863) (xy 351.872597 -331.372969) (xy 351.81716 -331.379069)
			(xy 351.761426 -331.377032) (xy 351.706583 -331.366902) (xy 351.653799 -331.348895) (xy 351.604199 -331.323394)
			(xy 351.558841 -331.290943) (xy 351.518692 -331.252234) (xy 351.484606 -331.208091) (xy 351.45731 -331.159456)
			(xy 351.437387 -331.107365) (xy 351.425261 -331.052928) (xy 351.42119 -330.997306) (xy 328.000339 -330.997306)
			(xy 327.672835 -331.575918) (xy 357.9655 -331.575918) (xy 357.969571 -331.520296) (xy 357.981697 -331.465859)
			(xy 358.00162 -331.413768) (xy 358.028916 -331.365133) (xy 358.063002 -331.32099) (xy 358.103151 -331.282281)
			(xy 358.148509 -331.24983) (xy 358.198109 -331.224329) (xy 358.250893 -331.206322) (xy 358.305736 -331.196192)
			(xy 358.36147 -331.194155) (xy 358.416907 -331.200255) (xy 358.470864 -331.214361) (xy 358.522193 -331.236173)
			(xy 358.569799 -331.265227) (xy 358.612667 -331.300902) (xy 358.649884 -331.342439) (xy 358.680657 -331.388952)
			(xy 358.704329 -331.439449) (xy 358.720397 -331.492856) (xy 358.728517 -331.548032) (xy 358.729026 -331.575918)
			(xy 358.728517 -331.603804) (xy 358.720397 -331.65898) (xy 358.704329 -331.712387) (xy 358.680657 -331.762884)
			(xy 358.649884 -331.809397) (xy 358.612667 -331.850934) (xy 358.569799 -331.886609) (xy 358.522193 -331.915663)
			(xy 358.470864 -331.937475) (xy 358.416907 -331.951581) (xy 358.36147 -331.957681) (xy 358.305736 -331.955644)
			(xy 358.250893 -331.945514) (xy 358.198109 -331.927507) (xy 358.148509 -331.902006) (xy 358.103151 -331.869555)
			(xy 358.063002 -331.830846) (xy 358.028916 -331.786703) (xy 358.00162 -331.738068) (xy 357.981697 -331.685977)
			(xy 357.969571 -331.63154) (xy 357.9655 -331.575918) (xy 327.672835 -331.575918) (xy 326.896627 -332.947271)
			(xy 365.368753 -332.947271) (xy 365.368753 -332.887329) (xy 365.376578 -332.827899) (xy 365.392093 -332.77)
			(xy 365.415033 -332.71462) (xy 365.445006 -332.66271) (xy 365.481498 -332.615155) (xy 365.523886 -332.572772)
			(xy 365.571443 -332.536283) (xy 365.623356 -332.506315) (xy 365.678737 -332.48338) (xy 365.736639 -332.46787)
			(xy 365.796069 -332.460051) (xy 365.82604 -332.459584) (xy 366.68964 -332.459584) (xy 366.719605 -332.460093)
			(xy 366.779023 -332.46792) (xy 366.836911 -332.483435) (xy 366.892278 -332.506374) (xy 366.944178 -332.536342)
			(xy 366.991723 -332.572828) (xy 367.034098 -332.615207) (xy 367.07058 -332.662755) (xy 367.100544 -332.714658)
			(xy 367.123478 -332.770027) (xy 367.138988 -332.827916) (xy 367.14681 -332.887335) (xy 367.14681 -332.947265)
			(xy 367.138988 -333.006684) (xy 367.123478 -333.064573) (xy 367.100544 -333.119942) (xy 367.07058 -333.171845)
			(xy 367.034098 -333.219393) (xy 366.991723 -333.261772) (xy 366.944178 -333.298258) (xy 366.892278 -333.328226)
			(xy 366.836911 -333.351165) (xy 366.779023 -333.36668) (xy 366.719605 -333.374507) (xy 366.68964 -333.375)
			(xy 365.82604 -333.375) (xy 365.796069 -333.374549) (xy 365.736639 -333.36673) (xy 365.678737 -333.35122)
			(xy 365.623356 -333.328285) (xy 365.571443 -333.298317) (xy 365.523886 -333.261828) (xy 365.481498 -333.219445)
			(xy 365.445006 -333.17189) (xy 365.415033 -333.11998) (xy 365.392093 -333.0646) (xy 365.376578 -333.006701)
			(xy 365.368753 -332.947271) (xy 326.896627 -332.947271) (xy 322.887798 -340.0298) (xy 365.682782 -340.0298)
			(xy 365.686853 -339.974178) (xy 365.698979 -339.919741) (xy 365.718902 -339.86765) (xy 365.746198 -339.819015)
			(xy 365.780284 -339.774872) (xy 365.820433 -339.736163) (xy 365.865791 -339.703712) (xy 365.915391 -339.678211)
			(xy 365.968175 -339.660204) (xy 366.023018 -339.650074) (xy 366.078752 -339.648037) (xy 366.134189 -339.654137)
			(xy 366.188146 -339.668243) (xy 366.239475 -339.690055) (xy 366.287081 -339.719109) (xy 366.329949 -339.754784)
			(xy 366.367166 -339.796321) (xy 366.397939 -339.842834) (xy 366.421611 -339.893331) (xy 366.437679 -339.946738)
			(xy 366.445799 -340.001914) (xy 366.446308 -340.0298) (xy 366.445799 -340.057686) (xy 366.437679 -340.112862)
			(xy 366.421611 -340.166269) (xy 366.397939 -340.216766) (xy 366.367166 -340.263279) (xy 366.329949 -340.304816)
			(xy 366.287081 -340.340491) (xy 366.239475 -340.369545) (xy 366.188146 -340.391357) (xy 366.134189 -340.405463)
			(xy 366.078752 -340.411563) (xy 366.023018 -340.409526) (xy 365.968175 -340.399396) (xy 365.915391 -340.381389)
			(xy 365.865791 -340.355888) (xy 365.820433 -340.323437) (xy 365.780284 -340.284728) (xy 365.746198 -340.240585)
			(xy 365.718902 -340.19195) (xy 365.698979 -340.139859) (xy 365.686853 -340.085422) (xy 365.682782 -340.0298)
			(xy 322.887798 -340.0298) (xy 322.585885 -340.5632) (xy 364.336582 -340.5632) (xy 364.340653 -340.507578)
			(xy 364.352779 -340.453141) (xy 364.372702 -340.40105) (xy 364.399998 -340.352415) (xy 364.434084 -340.308272)
			(xy 364.474233 -340.269563) (xy 364.519591 -340.237112) (xy 364.569191 -340.211611) (xy 364.621975 -340.193604)
			(xy 364.676818 -340.183474) (xy 364.732552 -340.181437) (xy 364.787989 -340.187537) (xy 364.841946 -340.201643)
			(xy 364.893275 -340.223455) (xy 364.940881 -340.252509) (xy 364.983749 -340.288184) (xy 365.020966 -340.329721)
			(xy 365.051739 -340.376234) (xy 365.075411 -340.426731) (xy 365.091479 -340.480138) (xy 365.099599 -340.535314)
			(xy 365.100108 -340.5632) (xy 365.099599 -340.591086) (xy 365.091479 -340.646262) (xy 365.075411 -340.699669)
			(xy 365.051739 -340.750166) (xy 365.020966 -340.796679) (xy 364.983749 -340.838216) (xy 364.940881 -340.873891)
			(xy 364.893275 -340.902945) (xy 364.841946 -340.924757) (xy 364.787989 -340.938863) (xy 364.732552 -340.944963)
			(xy 364.676818 -340.942926) (xy 364.621975 -340.932796) (xy 364.569191 -340.914789) (xy 364.519591 -340.889288)
			(xy 364.474233 -340.856837) (xy 364.434084 -340.818128) (xy 364.399998 -340.773985) (xy 364.372702 -340.72535)
			(xy 364.352779 -340.673259) (xy 364.340653 -340.618822) (xy 364.336582 -340.5632) (xy 322.585885 -340.5632)
			(xy 322.461382 -340.783164) (xy 322.458331 -340.78893) (xy 322.454995 -340.801536) (xy 322.454778 -340.808056)
			(xy 322.454778 -342.006936) (xy 322.455272 -342.016941) (xy 322.462937 -342.035424) (xy 322.477088 -342.049571)
			(xy 322.495573 -342.057231) (xy 322.505578 -342.057736) (xy 322.693284 -342.057736) (xy 322.720556 -342.058198)
			(xy 322.774545 -342.065959) (xy 322.82688 -342.081324) (xy 322.876495 -342.10398) (xy 322.922381 -342.133468)
			(xy 322.963603 -342.169185) (xy 322.999323 -342.210406) (xy 323.028812 -342.256291) (xy 323.051471 -342.305905)
			(xy 323.066838 -342.35824) (xy 323.0746 -342.412228) (xy 323.0746 -342.466772) (xy 323.0746 -342.466773)
			(xy 324.5573 -342.466773) (xy 324.5573 -342.412227) (xy 324.565063 -342.358236) (xy 324.580432 -342.305899)
			(xy 324.603092 -342.256283) (xy 324.632584 -342.210397) (xy 324.668307 -342.169176) (xy 324.709532 -342.133458)
			(xy 324.755422 -342.103971) (xy 324.805041 -342.081316) (xy 324.857379 -342.065954) (xy 324.911371 -342.058196)
			(xy 324.938644 -342.057736) (xy 325.802244 -342.057736) (xy 325.829511 -342.058229) (xy 325.88349 -342.065996)
			(xy 325.935814 -342.081365) (xy 325.985418 -342.104024) (xy 326.031293 -342.133511) (xy 326.072505 -342.169226)
			(xy 326.108216 -342.210442) (xy 326.137697 -342.256321) (xy 326.16035 -342.305928) (xy 326.175713 -342.358253)
			(xy 326.183474 -342.412233) (xy 326.183474 -342.466767) (xy 326.183473 -342.466771) (xy 327.6663 -342.466771)
			(xy 327.6663 -342.412229) (xy 327.674062 -342.358241) (xy 327.689428 -342.305908) (xy 327.712086 -342.256294)
			(xy 327.741574 -342.21041) (xy 327.777293 -342.16919) (xy 327.818513 -342.133472) (xy 327.864398 -342.103984)
			(xy 327.914012 -342.081327) (xy 327.966345 -342.065961) (xy 328.020333 -342.058199) (xy 328.047604 -342.057736)
			(xy 328.911204 -342.057736) (xy 328.938473 -342.058227) (xy 328.992456 -342.065989) (xy 329.044785 -342.081354)
			(xy 329.094394 -342.104011) (xy 329.140274 -342.133497) (xy 329.181491 -342.169212) (xy 329.217206 -342.210429)
			(xy 329.246691 -342.256309) (xy 329.269347 -342.305919) (xy 329.284712 -342.358248) (xy 329.292474 -342.412231)
			(xy 329.292474 -342.466768) (xy 330.775322 -342.466768) (xy 330.775322 -342.412232) (xy 330.783083 -342.358251)
			(xy 330.798447 -342.305924) (xy 330.8211 -342.256316) (xy 330.850583 -342.210437) (xy 330.886295 -342.16922)
			(xy 330.927508 -342.133505) (xy 330.973385 -342.104018) (xy 331.022991 -342.081359) (xy 331.075316 -342.065991)
			(xy 331.129296 -342.058225) (xy 331.156564 -342.057736) (xy 332.020164 -342.057736) (xy 332.047437 -342.058201)
			(xy 332.101427 -342.065959) (xy 332.153764 -342.081322) (xy 332.203381 -342.103977) (xy 332.249269 -342.133464)
			(xy 332.290493 -342.169181) (xy 332.326214 -342.210402) (xy 332.355705 -342.256287) (xy 332.378365 -342.305902)
			(xy 332.393733 -342.358238) (xy 332.401496 -342.412228) (xy 332.401496 -342.466772) (xy 333.8842 -342.466772)
			(xy 333.8842 -342.412228) (xy 333.891962 -342.358239) (xy 333.90733 -342.305904) (xy 333.929989 -342.256289)
			(xy 333.959479 -342.210404) (xy 333.9952 -342.169183) (xy 334.036423 -342.133465) (xy 334.08231 -342.103978)
			(xy 334.131926 -342.081322) (xy 334.184262 -342.065957) (xy 334.238252 -342.058198) (xy 334.265524 -342.057736)
			(xy 335.129124 -342.057736) (xy 335.156392 -342.058228) (xy 335.210373 -342.065992) (xy 335.262699 -342.08136)
			(xy 335.312306 -342.104017) (xy 335.358184 -342.133504) (xy 335.399398 -342.169219) (xy 335.435111 -342.210435)
			(xy 335.464594 -342.256315) (xy 335.487249 -342.305923) (xy 335.502613 -342.358251) (xy 335.510374 -342.412232)
			(xy 335.510374 -342.466768) (xy 335.510374 -342.466769) (xy 336.993222 -342.466769) (xy 336.993222 -342.412231)
			(xy 337.000984 -342.358249) (xy 337.016348 -342.30592) (xy 337.039003 -342.256311) (xy 337.068488 -342.21043)
			(xy 337.104202 -342.169213) (xy 337.145418 -342.133498) (xy 337.191297 -342.104011) (xy 337.240905 -342.081354)
			(xy 337.293233 -342.065987) (xy 337.347215 -342.058224) (xy 337.374484 -342.057736) (xy 338.238084 -342.057736)
			(xy 338.265356 -342.058202) (xy 338.319344 -342.065963) (xy 338.371678 -342.081327) (xy 338.421293 -342.103984)
			(xy 338.467179 -342.133471) (xy 338.5084 -342.169188) (xy 338.544119 -342.210409) (xy 338.573608 -342.256293)
			(xy 338.596267 -342.305907) (xy 338.611634 -342.35824) (xy 338.619396 -342.412228) (xy 338.619396 -342.466772)
			(xy 338.619396 -342.466773) (xy 340.1021 -342.466773) (xy 340.1021 -342.412227) (xy 340.109863 -342.358236)
			(xy 340.125232 -342.305899) (xy 340.147892 -342.256283) (xy 340.177384 -342.210397) (xy 340.213107 -342.169176)
			(xy 340.254332 -342.133458) (xy 340.300222 -342.103971) (xy 340.349841 -342.081316) (xy 340.402179 -342.065954)
			(xy 340.456171 -342.058196) (xy 340.483444 -342.057736) (xy 341.347044 -342.057736) (xy 341.374311 -342.058229)
			(xy 341.42829 -342.065996) (xy 341.480614 -342.081365) (xy 341.530218 -342.104024) (xy 341.576093 -342.133511)
			(xy 341.617305 -342.169226) (xy 341.653016 -342.210442) (xy 341.682497 -342.256321) (xy 341.70515 -342.305928)
			(xy 341.720513 -342.358253) (xy 341.728274 -342.412233) (xy 341.728274 -342.466767) (xy 341.728273 -342.466771)
			(xy 343.2111 -342.466771) (xy 343.2111 -342.412229) (xy 343.218862 -342.358241) (xy 343.234228 -342.305908)
			(xy 343.256886 -342.256294) (xy 343.286374 -342.21041) (xy 343.322093 -342.16919) (xy 343.363313 -342.133472)
			(xy 343.409198 -342.103984) (xy 343.458812 -342.081327) (xy 343.511145 -342.065961) (xy 343.565133 -342.058199)
			(xy 343.592404 -342.057736) (xy 344.456004 -342.057736) (xy 344.483273 -342.058227) (xy 344.537256 -342.065989)
			(xy 344.589585 -342.081354) (xy 344.639194 -342.104011) (xy 344.685074 -342.133497) (xy 344.726291 -342.169212)
			(xy 344.762006 -342.210429) (xy 344.791491 -342.256309) (xy 344.814147 -342.305919) (xy 344.829512 -342.358248)
			(xy 344.837274 -342.412231) (xy 344.837274 -342.466769) (xy 344.829512 -342.520752) (xy 344.814147 -342.573081)
			(xy 344.791491 -342.622691) (xy 344.762006 -342.668571) (xy 344.726291 -342.709788) (xy 344.685074 -342.745503)
			(xy 344.639194 -342.774989) (xy 344.589585 -342.797646) (xy 344.537256 -342.813011) (xy 344.483273 -342.820773)
			(xy 344.456004 -342.82126) (xy 343.592404 -342.82126) (xy 343.565133 -342.820801) (xy 343.511145 -342.813039)
			(xy 343.458812 -342.797673) (xy 343.409198 -342.775016) (xy 343.363313 -342.745528) (xy 343.322093 -342.70981)
			(xy 343.286374 -342.66859) (xy 343.256886 -342.622706) (xy 343.234228 -342.573092) (xy 343.218862 -342.520759)
			(xy 343.2111 -342.466771) (xy 341.728273 -342.466771) (xy 341.720513 -342.520747) (xy 341.70515 -342.573072)
			(xy 341.682497 -342.622679) (xy 341.653016 -342.668558) (xy 341.617305 -342.709774) (xy 341.576093 -342.745489)
			(xy 341.530218 -342.774976) (xy 341.480614 -342.797635) (xy 341.42829 -342.813004) (xy 341.374311 -342.820771)
			(xy 341.347044 -342.82126) (xy 340.483444 -342.82126) (xy 340.456171 -342.820804) (xy 340.402179 -342.813046)
			(xy 340.349841 -342.797684) (xy 340.300222 -342.775029) (xy 340.254332 -342.745542) (xy 340.213107 -342.709824)
			(xy 340.177384 -342.668603) (xy 340.147892 -342.622717) (xy 340.125232 -342.573101) (xy 340.109863 -342.520764)
			(xy 340.1021 -342.466773) (xy 338.619396 -342.466773) (xy 338.611634 -342.52076) (xy 338.596267 -342.573093)
			(xy 338.573608 -342.622707) (xy 338.544119 -342.668591) (xy 338.5084 -342.709812) (xy 338.467179 -342.745529)
			(xy 338.421293 -342.775016) (xy 338.371678 -342.797673) (xy 338.319344 -342.813037) (xy 338.265356 -342.820798)
			(xy 338.238084 -342.82126) (xy 337.374484 -342.82126) (xy 337.347215 -342.820776) (xy 337.293233 -342.813013)
			(xy 337.240905 -342.797646) (xy 337.191297 -342.774989) (xy 337.145418 -342.745502) (xy 337.104202 -342.709787)
			(xy 337.068488 -342.66857) (xy 337.039003 -342.622689) (xy 337.016348 -342.57308) (xy 337.000984 -342.520751)
			(xy 336.993222 -342.466769) (xy 335.510374 -342.466769) (xy 335.502613 -342.520749) (xy 335.487249 -342.573077)
			(xy 335.464594 -342.622685) (xy 335.435111 -342.668565) (xy 335.399398 -342.709781) (xy 335.358184 -342.745496)
			(xy 335.312306 -342.774983) (xy 335.262699 -342.79764) (xy 335.210373 -342.813008) (xy 335.156392 -342.820772)
			(xy 335.129124 -342.82126) (xy 334.265524 -342.82126) (xy 334.238252 -342.820802) (xy 334.184262 -342.813043)
			(xy 334.131926 -342.797678) (xy 334.08231 -342.775022) (xy 334.036423 -342.745535) (xy 333.9952 -342.709817)
			(xy 333.959479 -342.668596) (xy 333.929989 -342.622711) (xy 333.90733 -342.573096) (xy 333.891962 -342.520761)
			(xy 333.8842 -342.466772) (xy 332.401496 -342.466772) (xy 332.393733 -342.520762) (xy 332.378365 -342.573098)
			(xy 332.355705 -342.622713) (xy 332.326214 -342.668598) (xy 332.290493 -342.709819) (xy 332.249269 -342.745536)
			(xy 332.203381 -342.775023) (xy 332.153764 -342.797678) (xy 332.101427 -342.813041) (xy 332.047437 -342.820799)
			(xy 332.020164 -342.82126) (xy 331.156564 -342.82126) (xy 331.129296 -342.820775) (xy 331.075316 -342.813009)
			(xy 331.022991 -342.797641) (xy 330.973385 -342.774982) (xy 330.927508 -342.745495) (xy 330.886295 -342.70978)
			(xy 330.850583 -342.668563) (xy 330.8211 -342.622684) (xy 330.798447 -342.573076) (xy 330.783083 -342.520749)
			(xy 330.775322 -342.466768) (xy 329.292474 -342.466768) (xy 329.292474 -342.466769) (xy 329.284712 -342.520752)
			(xy 329.269347 -342.573081) (xy 329.246691 -342.622691) (xy 329.217206 -342.668571) (xy 329.181491 -342.709788)
			(xy 329.140274 -342.745503) (xy 329.094394 -342.774989) (xy 329.044785 -342.797646) (xy 328.992456 -342.813011)
			(xy 328.938473 -342.820773) (xy 328.911204 -342.82126) (xy 328.047604 -342.82126) (xy 328.020333 -342.820801)
			(xy 327.966345 -342.813039) (xy 327.914012 -342.797673) (xy 327.864398 -342.775016) (xy 327.818513 -342.745528)
			(xy 327.777293 -342.70981) (xy 327.741574 -342.66859) (xy 327.712086 -342.622706) (xy 327.689428 -342.573092)
			(xy 327.674062 -342.520759) (xy 327.6663 -342.466771) (xy 326.183473 -342.466771) (xy 326.175713 -342.520747)
			(xy 326.16035 -342.573072) (xy 326.137697 -342.622679) (xy 326.108216 -342.668558) (xy 326.072505 -342.709774)
			(xy 326.031293 -342.745489) (xy 325.985418 -342.774976) (xy 325.935814 -342.797635) (xy 325.88349 -342.813004)
			(xy 325.829511 -342.820771) (xy 325.802244 -342.82126) (xy 324.938644 -342.82126) (xy 324.911371 -342.820804)
			(xy 324.857379 -342.813046) (xy 324.805041 -342.797684) (xy 324.755422 -342.775029) (xy 324.709532 -342.745542)
			(xy 324.668307 -342.709824) (xy 324.632584 -342.668603) (xy 324.603092 -342.622717) (xy 324.580432 -342.573101)
			(xy 324.565063 -342.520764) (xy 324.5573 -342.466773) (xy 323.0746 -342.466773) (xy 323.066838 -342.52076)
			(xy 323.051471 -342.573095) (xy 323.028812 -342.622709) (xy 322.999323 -342.668594) (xy 322.963603 -342.709815)
			(xy 322.922381 -342.745532) (xy 322.876495 -342.77502) (xy 322.82688 -342.797676) (xy 322.774545 -342.813041)
			(xy 322.720556 -342.820802) (xy 322.693284 -342.82126) (xy 322.505578 -342.82126) (xy 322.49557 -342.821751)
			(xy 322.477079 -342.829413) (xy 322.462923 -342.843564) (xy 322.455255 -342.862053) (xy 322.454778 -342.87206)
			(xy 322.454778 -345.032584) (xy 322.455263 -345.042595) (xy 322.462919 -345.061097) (xy 322.477072 -345.07526)
			(xy 322.495567 -345.08293) (xy 322.505578 -345.083384) (xy 322.693284 -345.083384) (xy 322.720552 -345.083846)
			(xy 322.774535 -345.091606) (xy 322.826863 -345.106969) (xy 322.876472 -345.129623) (xy 322.922352 -345.159106)
			(xy 322.963569 -345.194819) (xy 322.999284 -345.236035) (xy 323.02877 -345.281914) (xy 323.051426 -345.331522)
			(xy 323.066791 -345.38385) (xy 323.074553 -345.437832) (xy 323.074553 -345.492368) (xy 323.074553 -345.49237)
			(xy 324.557348 -345.49237) (xy 324.557348 -345.43783) (xy 324.56511 -345.383846) (xy 324.580476 -345.331516)
			(xy 324.603135 -345.281906) (xy 324.632623 -345.236026) (xy 324.668341 -345.194809) (xy 324.709561 -345.159096)
			(xy 324.755445 -345.129613) (xy 324.805057 -345.106961) (xy 324.857389 -345.0916) (xy 324.911374 -345.083844)
			(xy 324.938644 -345.083384) (xy 325.802244 -345.083384) (xy 325.829515 -345.083782) (xy 325.8835 -345.091549)
			(xy 325.93583 -345.10692) (xy 325.985441 -345.129582) (xy 326.031322 -345.159072) (xy 326.072539 -345.194792)
			(xy 326.108254 -345.236013) (xy 326.137739 -345.281898) (xy 326.160395 -345.331511) (xy 326.17576 -345.383843)
			(xy 326.183522 -345.437829) (xy 326.183522 -345.492368) (xy 327.666347 -345.492368) (xy 327.666347 -345.437832)
			(xy 327.674109 -345.383851) (xy 327.689473 -345.331525) (xy 327.712128 -345.281917) (xy 327.741613 -345.236039)
			(xy 327.777326 -345.194824) (xy 327.818542 -345.159111) (xy 327.864421 -345.129627) (xy 327.914028 -345.106972)
			(xy 327.966355 -345.091608) (xy 328.020336 -345.083847) (xy 328.047604 -345.083384) (xy 328.911204 -345.083384)
			(xy 328.938476 -345.083779) (xy 328.992466 -345.091542) (xy 329.044801 -345.106909) (xy 329.094417 -345.129569)
			(xy 329.140303 -345.159058) (xy 329.181525 -345.194778) (xy 329.217244 -345.236) (xy 329.246733 -345.281886)
			(xy 329.269392 -345.331502) (xy 329.284759 -345.383838) (xy 329.292521 -345.437828) (xy 329.292521 -345.492364)
			(xy 330.77537 -345.492364) (xy 330.77537 -345.437836) (xy 330.78313 -345.383862) (xy 330.798492 -345.331541)
			(xy 330.821143 -345.281939) (xy 330.850621 -345.236066) (xy 330.886329 -345.194854) (xy 330.927537 -345.159143)
			(xy 330.973408 -345.12966) (xy 331.023007 -345.107004) (xy 331.075326 -345.091638) (xy 331.1293 -345.083873)
			(xy 331.156564 -345.083384) (xy 332.020164 -345.083384) (xy 332.04744 -345.083753) (xy 332.101437 -345.091512)
			(xy 332.153781 -345.106877) (xy 332.203404 -345.129535) (xy 332.249298 -345.159026) (xy 332.290527 -345.194747)
			(xy 332.326253 -345.235973) (xy 332.355747 -345.281864) (xy 332.37841 -345.331486) (xy 332.39378 -345.383828)
			(xy 332.401544 -345.437824) (xy 332.401544 -345.492369) (xy 333.884247 -345.492369) (xy 333.884247 -345.437831)
			(xy 333.892009 -345.383849) (xy 333.907375 -345.33152) (xy 333.930031 -345.281912) (xy 333.959518 -345.236032)
			(xy 333.995234 -345.194817) (xy 334.036452 -345.159103) (xy 334.082333 -345.12962) (xy 334.131943 -345.106966)
			(xy 334.184272 -345.091604) (xy 334.238255 -345.083846) (xy 334.265524 -345.083384) (xy 335.129124 -345.083384)
			(xy 335.156396 -345.08378) (xy 335.210383 -345.091546) (xy 335.262716 -345.106915) (xy 335.312329 -345.129575)
			(xy 335.358213 -345.159065) (xy 335.399432 -345.194785) (xy 335.435149 -345.236007) (xy 335.464636 -345.281892)
			(xy 335.487294 -345.331507) (xy 335.50266 -345.38384) (xy 335.510422 -345.437828) (xy 335.510422 -345.492365)
			(xy 336.99327 -345.492365) (xy 336.99327 -345.437835) (xy 337.001031 -345.383859) (xy 337.016393 -345.331537)
			(xy 337.039046 -345.281934) (xy 337.068526 -345.236059) (xy 337.104236 -345.194847) (xy 337.145446 -345.159136)
			(xy 337.19132 -345.129653) (xy 337.240922 -345.106999) (xy 337.293243 -345.091634) (xy 337.347219 -345.083871)
			(xy 337.374484 -345.083384) (xy 338.238084 -345.083384) (xy 338.265359 -345.083755) (xy 338.319354 -345.091516)
			(xy 338.371695 -345.106882) (xy 338.421316 -345.129542) (xy 338.467207 -345.159033) (xy 338.508434 -345.194754)
			(xy 338.544158 -345.23598) (xy 338.57365 -345.28187) (xy 338.596312 -345.33149) (xy 338.611681 -345.38383)
			(xy 338.619444 -345.437825) (xy 338.619444 -345.49237) (xy 340.102148 -345.49237) (xy 340.102148 -345.43783)
			(xy 340.10991 -345.383846) (xy 340.125276 -345.331516) (xy 340.147935 -345.281906) (xy 340.177423 -345.236026)
			(xy 340.213141 -345.194809) (xy 340.254361 -345.159096) (xy 340.300245 -345.129613) (xy 340.349857 -345.106961)
			(xy 340.402189 -345.0916) (xy 340.456174 -345.083844) (xy 340.483444 -345.083384) (xy 341.347044 -345.083384)
			(xy 341.374315 -345.083782) (xy 341.4283 -345.091549) (xy 341.48063 -345.10692) (xy 341.530241 -345.129582)
			(xy 341.576122 -345.159072) (xy 341.617339 -345.194792) (xy 341.653054 -345.236013) (xy 341.682539 -345.281898)
			(xy 341.705195 -345.331511) (xy 341.72056 -345.383843) (xy 341.728322 -345.437829) (xy 341.728322 -345.492368)
			(xy 343.211147 -345.492368) (xy 343.211147 -345.437832) (xy 343.218909 -345.383851) (xy 343.234273 -345.331525)
			(xy 343.256928 -345.281917) (xy 343.286413 -345.236039) (xy 343.322126 -345.194824) (xy 343.363342 -345.159111)
			(xy 343.409221 -345.129627) (xy 343.458828 -345.106972) (xy 343.511155 -345.091608) (xy 343.565136 -345.083847)
			(xy 343.592404 -345.083384) (xy 344.456004 -345.083384) (xy 344.483276 -345.083779) (xy 344.537266 -345.091542)
			(xy 344.589601 -345.106909) (xy 344.639217 -345.129569) (xy 344.685103 -345.159058) (xy 344.726325 -345.194778)
			(xy 344.762044 -345.236) (xy 344.791533 -345.281886) (xy 344.814192 -345.331502) (xy 344.829559 -345.383838)
			(xy 344.837321 -345.437828) (xy 344.837321 -345.492372) (xy 344.829559 -345.546362) (xy 344.814192 -345.598698)
			(xy 344.791533 -345.648314) (xy 344.762044 -345.6942) (xy 344.726325 -345.735422) (xy 344.685103 -345.771142)
			(xy 344.639217 -345.800631) (xy 344.589601 -345.823291) (xy 344.537266 -345.838658) (xy 344.483276 -345.846421)
			(xy 344.456004 -345.846908) (xy 343.592404 -345.846908) (xy 343.565136 -345.846353) (xy 343.511155 -345.838592)
			(xy 343.458828 -345.823228) (xy 343.409221 -345.800573) (xy 343.363342 -345.771089) (xy 343.322126 -345.735376)
			(xy 343.286413 -345.694161) (xy 343.256928 -345.648283) (xy 343.234273 -345.598675) (xy 343.218909 -345.546349)
			(xy 343.211147 -345.492368) (xy 341.728322 -345.492368) (xy 341.728322 -345.492371) (xy 341.72056 -345.546357)
			(xy 341.705195 -345.598689) (xy 341.682539 -345.648302) (xy 341.653054 -345.694187) (xy 341.617339 -345.735408)
			(xy 341.576122 -345.771128) (xy 341.530241 -345.800618) (xy 341.48063 -345.82328) (xy 341.4283 -345.838651)
			(xy 341.374315 -345.846418) (xy 341.347044 -345.846908) (xy 340.483444 -345.846908) (xy 340.456174 -345.846356)
			(xy 340.402189 -345.8386) (xy 340.349857 -345.823239) (xy 340.300245 -345.800587) (xy 340.254361 -345.771104)
			(xy 340.213141 -345.735391) (xy 340.177423 -345.694174) (xy 340.147935 -345.648294) (xy 340.125276 -345.598684)
			(xy 340.10991 -345.546354) (xy 340.102148 -345.49237) (xy 338.619444 -345.49237) (xy 338.619444 -345.492375)
			(xy 338.611681 -345.54637) (xy 338.596312 -345.59871) (xy 338.57365 -345.64833) (xy 338.544158 -345.69422)
			(xy 338.508434 -345.735446) (xy 338.467207 -345.771167) (xy 338.421316 -345.800658) (xy 338.371695 -345.823318)
			(xy 338.319354 -345.838684) (xy 338.265359 -345.846445) (xy 338.238084 -345.846908) (xy 337.374484 -345.846908)
			(xy 337.347219 -345.846329) (xy 337.293243 -345.838566) (xy 337.240922 -345.823201) (xy 337.19132 -345.800547)
			(xy 337.145446 -345.771064) (xy 337.104236 -345.735353) (xy 337.068526 -345.694141) (xy 337.039046 -345.648266)
			(xy 337.016393 -345.598663) (xy 337.001031 -345.546341) (xy 336.99327 -345.492365) (xy 335.510422 -345.492365)
			(xy 335.510422 -345.492372) (xy 335.50266 -345.54636) (xy 335.487294 -345.598693) (xy 335.464636 -345.648308)
			(xy 335.435149 -345.694193) (xy 335.399432 -345.735415) (xy 335.358213 -345.771135) (xy 335.312329 -345.800625)
			(xy 335.262716 -345.823285) (xy 335.210383 -345.838654) (xy 335.156396 -345.84642) (xy 335.129124 -345.846908)
			(xy 334.265524 -345.846908) (xy 334.238255 -345.846354) (xy 334.184272 -345.838596) (xy 334.131943 -345.823234)
			(xy 334.082333 -345.80058) (xy 334.036452 -345.771097) (xy 333.995234 -345.735383) (xy 333.959518 -345.694168)
			(xy 333.930031 -345.648288) (xy 333.907375 -345.59868) (xy 333.892009 -345.546351) (xy 333.884247 -345.492369)
			(xy 332.401544 -345.492369) (xy 332.401544 -345.492376) (xy 332.39378 -345.546372) (xy 332.37841 -345.598714)
			(xy 332.355747 -345.648336) (xy 332.326253 -345.694227) (xy 332.290527 -345.735453) (xy 332.249298 -345.771174)
			(xy 332.203404 -345.800665) (xy 332.153781 -345.823323) (xy 332.101437 -345.838688) (xy 332.04744 -345.846447)
			(xy 332.020164 -345.846908) (xy 331.156564 -345.846908) (xy 331.1293 -345.846327) (xy 331.075326 -345.838562)
			(xy 331.023007 -345.823196) (xy 330.973408 -345.80054) (xy 330.927537 -345.771057) (xy 330.886329 -345.735346)
			(xy 330.850622 -345.694134) (xy 330.821143 -345.648261) (xy 330.798492 -345.598659) (xy 330.78313 -345.546338)
			(xy 330.77537 -345.492364) (xy 329.292521 -345.492364) (xy 329.292521 -345.492372) (xy 329.284759 -345.546362)
			(xy 329.269392 -345.598698) (xy 329.246733 -345.648314) (xy 329.217244 -345.6942) (xy 329.181525 -345.735422)
			(xy 329.140303 -345.771142) (xy 329.094417 -345.800631) (xy 329.044801 -345.823291) (xy 328.992466 -345.838658)
			(xy 328.938476 -345.846421) (xy 328.911204 -345.846908) (xy 328.047604 -345.846908) (xy 328.020336 -345.846353)
			(xy 327.966355 -345.838592) (xy 327.914028 -345.823228) (xy 327.864421 -345.800573) (xy 327.818542 -345.771089)
			(xy 327.777326 -345.735376) (xy 327.741613 -345.694161) (xy 327.712128 -345.648283) (xy 327.689473 -345.598675)
			(xy 327.674109 -345.546349) (xy 327.666347 -345.492368) (xy 326.183522 -345.492368) (xy 326.183522 -345.492371)
			(xy 326.17576 -345.546357) (xy 326.160395 -345.598689) (xy 326.137739 -345.648302) (xy 326.108254 -345.694187)
			(xy 326.072539 -345.735408) (xy 326.031322 -345.771128) (xy 325.985441 -345.800618) (xy 325.93583 -345.82328)
			(xy 325.8835 -345.838651) (xy 325.829515 -345.846418) (xy 325.802244 -345.846908) (xy 324.938644 -345.846908)
			(xy 324.911374 -345.846356) (xy 324.857389 -345.8386) (xy 324.805057 -345.823239) (xy 324.755445 -345.800587)
			(xy 324.709561 -345.771104) (xy 324.668341 -345.735391) (xy 324.632623 -345.694174) (xy 324.603135 -345.648294)
			(xy 324.580476 -345.598684) (xy 324.56511 -345.546354) (xy 324.557348 -345.49237) (xy 323.074553 -345.49237)
			(xy 323.066791 -345.54635) (xy 323.051426 -345.598678) (xy 323.02877 -345.648286) (xy 322.999284 -345.694165)
			(xy 322.963569 -345.735381) (xy 322.922352 -345.771094) (xy 322.876472 -345.800577) (xy 322.826863 -345.823231)
			(xy 322.774535 -345.838594) (xy 322.720552 -345.846354) (xy 322.693284 -345.846908) (xy 322.505578 -345.846908)
			(xy 322.495574 -345.8474) (xy 322.477091 -345.855064) (xy 322.462947 -345.869216) (xy 322.455294 -345.887704)
			(xy 322.454778 -345.897708) (xy 322.454778 -348.153228) (xy 322.45527 -348.163234) (xy 322.462934 -348.18172)
			(xy 322.477085 -348.195869) (xy 322.495572 -348.203531) (xy 322.505578 -348.204028) (xy 322.693284 -348.204028)
			(xy 322.720556 -348.20449) (xy 322.774546 -348.212251) (xy 322.826882 -348.227616) (xy 322.876499 -348.250273)
			(xy 322.922386 -348.279761) (xy 322.963609 -348.31548) (xy 322.999329 -348.356701) (xy 323.028819 -348.402587)
			(xy 323.051478 -348.452203) (xy 323.066846 -348.504538) (xy 323.074608 -348.558528) (xy 323.074608 -348.613072)
			(xy 323.074608 -348.613074) (xy 324.557292 -348.613074) (xy 324.557292 -348.558526) (xy 324.565055 -348.504534)
			(xy 324.580424 -348.452197) (xy 324.603085 -348.402579) (xy 324.632578 -348.356692) (xy 324.668301 -348.31547)
			(xy 324.709527 -348.279751) (xy 324.755418 -348.250264) (xy 324.805038 -348.227609) (xy 324.857377 -348.212246)
			(xy 324.91137 -348.204489) (xy 324.938644 -348.204028) (xy 325.802244 -348.204028) (xy 325.829511 -348.204537)
			(xy 325.883488 -348.212304) (xy 325.935811 -348.227673) (xy 325.985414 -348.250331) (xy 326.031288 -348.279817)
			(xy 326.0725 -348.315531) (xy 326.108209 -348.356747) (xy 326.13769 -348.402624) (xy 326.160343 -348.45223)
			(xy 326.175705 -348.504555) (xy 326.183466 -348.558533) (xy 326.183466 -348.613067) (xy 326.183465 -348.613072)
			(xy 327.666292 -348.613072) (xy 327.666292 -348.558528) (xy 327.674054 -348.504539) (xy 327.689421 -348.452205)
			(xy 327.712079 -348.40259) (xy 327.741568 -348.356705) (xy 327.777287 -348.315484) (xy 327.818509 -348.279766)
			(xy 327.864394 -348.250277) (xy 327.914009 -348.227619) (xy 327.966343 -348.212253) (xy 328.020332 -348.204491)
			(xy 328.047604 -348.204028) (xy 328.911204 -348.204028) (xy 328.938472 -348.204535) (xy 328.992454 -348.212297)
			(xy 329.044782 -348.227662) (xy 329.09439 -348.250318) (xy 329.140269 -348.279803) (xy 329.181486 -348.315517)
			(xy 329.217199 -348.356734) (xy 329.246684 -348.402613) (xy 329.26934 -348.452222) (xy 329.284704 -348.50455)
			(xy 329.292466 -348.558532) (xy 329.292466 -348.613068) (xy 330.775314 -348.613068) (xy 330.775314 -348.558532)
			(xy 330.783075 -348.50455) (xy 330.798439 -348.452222) (xy 330.821093 -348.402613) (xy 330.850577 -348.356732)
			(xy 330.886289 -348.315514) (xy 330.927503 -348.279798) (xy 330.973381 -348.250311) (xy 331.022988 -348.227652)
			(xy 331.075314 -348.212283) (xy 331.129296 -348.204517) (xy 331.156564 -348.204028) (xy 332.020164 -348.204028)
			(xy 332.047436 -348.204509) (xy 332.101425 -348.212267) (xy 332.153761 -348.22763) (xy 332.203377 -348.250284)
			(xy 332.249264 -348.27977) (xy 332.290488 -348.315487) (xy 332.326208 -348.356707) (xy 332.355698 -348.402591)
			(xy 332.378358 -348.452205) (xy 332.393726 -348.504539) (xy 332.401488 -348.558528) (xy 332.401488 -348.613072)
			(xy 332.401488 -348.613073) (xy 333.884192 -348.613073) (xy 333.884192 -348.558527) (xy 333.891955 -348.504537)
			(xy 333.907322 -348.452201) (xy 333.929982 -348.402585) (xy 333.959473 -348.356699) (xy 333.995194 -348.315477)
			(xy 334.036418 -348.279759) (xy 334.082306 -348.250271) (xy 334.131923 -348.227614) (xy 334.18426 -348.212249)
			(xy 334.238251 -348.20449) (xy 334.265524 -348.204028) (xy 335.129124 -348.204028) (xy 335.156392 -348.204536)
			(xy 335.210371 -348.2123) (xy 335.262696 -348.227667) (xy 335.312302 -348.250324) (xy 335.358179 -348.27981)
			(xy 335.399393 -348.315524) (xy 335.435104 -348.35674) (xy 335.464587 -348.402619) (xy 335.487241 -348.452226)
			(xy 335.502605 -348.504552) (xy 335.510366 -348.558532) (xy 335.510366 -348.613068) (xy 335.510366 -348.613069)
			(xy 336.993214 -348.613069) (xy 336.993214 -348.558531) (xy 337.000976 -348.504547) (xy 337.016341 -348.452217)
			(xy 337.038996 -348.402607) (xy 337.068482 -348.356726) (xy 337.104196 -348.315507) (xy 337.145413 -348.279791)
			(xy 337.191293 -348.250304) (xy 337.240902 -348.227646) (xy 337.293231 -348.212279) (xy 337.347215 -348.204516)
			(xy 337.374484 -348.204028) (xy 338.238084 -348.204028) (xy 338.265355 -348.20451) (xy 338.319342 -348.21227)
			(xy 338.371675 -348.227635) (xy 338.421289 -348.250291) (xy 338.467174 -348.279777) (xy 338.508395 -348.315494)
			(xy 338.544113 -348.356713) (xy 338.573601 -348.402597) (xy 338.596259 -348.45221) (xy 338.611626 -348.504542)
			(xy 338.619388 -348.558529) (xy 338.619388 -348.613071) (xy 338.619388 -348.613074) (xy 340.102092 -348.613074)
			(xy 340.102092 -348.558526) (xy 340.109855 -348.504534) (xy 340.125224 -348.452197) (xy 340.147885 -348.402579)
			(xy 340.177378 -348.356692) (xy 340.213101 -348.31547) (xy 340.254327 -348.279751) (xy 340.300218 -348.250264)
			(xy 340.349838 -348.227609) (xy 340.402177 -348.212246) (xy 340.45617 -348.204489) (xy 340.483444 -348.204028)
			(xy 341.347044 -348.204028) (xy 341.374311 -348.204537) (xy 341.428288 -348.212304) (xy 341.480611 -348.227673)
			(xy 341.530214 -348.250331) (xy 341.576088 -348.279817) (xy 341.6173 -348.315531) (xy 341.653009 -348.356747)
			(xy 341.68249 -348.402624) (xy 341.705143 -348.45223) (xy 341.720505 -348.504555) (xy 341.728266 -348.558533)
			(xy 341.728266 -348.613067) (xy 341.728265 -348.613072) (xy 343.211092 -348.613072) (xy 343.211092 -348.558528)
			(xy 343.218854 -348.504539) (xy 343.234221 -348.452205) (xy 343.256879 -348.40259) (xy 343.286368 -348.356705)
			(xy 343.322087 -348.315484) (xy 343.363309 -348.279766) (xy 343.409194 -348.250277) (xy 343.458809 -348.227619)
			(xy 343.511143 -348.212253) (xy 343.565132 -348.204491) (xy 343.592404 -348.204028) (xy 344.456004 -348.204028)
			(xy 344.483272 -348.204535) (xy 344.537254 -348.212297) (xy 344.589582 -348.227662) (xy 344.63919 -348.250318)
			(xy 344.685069 -348.279803) (xy 344.726286 -348.315517) (xy 344.761999 -348.356734) (xy 344.791484 -348.402613)
			(xy 344.81414 -348.452222) (xy 344.829504 -348.50455) (xy 344.837266 -348.558532) (xy 344.837266 -348.613068)
			(xy 344.829504 -348.66705) (xy 344.81414 -348.719378) (xy 344.791484 -348.768987) (xy 344.761999 -348.814866)
			(xy 344.726286 -348.856083) (xy 344.685069 -348.891797) (xy 344.63919 -348.921282) (xy 344.589582 -348.943938)
			(xy 344.537254 -348.959303) (xy 344.483272 -348.967065) (xy 344.456004 -348.967552) (xy 343.592404 -348.967552)
			(xy 343.565132 -348.967109) (xy 343.511143 -348.959347) (xy 343.458809 -348.943981) (xy 343.409194 -348.921323)
			(xy 343.363309 -348.891834) (xy 343.322087 -348.856116) (xy 343.286368 -348.814895) (xy 343.256879 -348.76901)
			(xy 343.234221 -348.719395) (xy 343.218854 -348.667061) (xy 343.211092 -348.613072) (xy 341.728265 -348.613072)
			(xy 341.720505 -348.667045) (xy 341.705143 -348.71937) (xy 341.68249 -348.768976) (xy 341.653009 -348.814853)
			(xy 341.6173 -348.856069) (xy 341.576088 -348.891783) (xy 341.530214 -348.921269) (xy 341.480611 -348.943927)
			(xy 341.428288 -348.959296) (xy 341.374311 -348.967063) (xy 341.347044 -348.967552) (xy 340.483444 -348.967552)
			(xy 340.45617 -348.967111) (xy 340.402177 -348.959354) (xy 340.349838 -348.943991) (xy 340.300218 -348.921336)
			(xy 340.254327 -348.891849) (xy 340.213101 -348.85613) (xy 340.177378 -348.814908) (xy 340.147885 -348.769021)
			(xy 340.125224 -348.719403) (xy 340.109855 -348.667066) (xy 340.102092 -348.613074) (xy 338.619388 -348.613074)
			(xy 338.611626 -348.667058) (xy 338.596259 -348.71939) (xy 338.573601 -348.769003) (xy 338.544113 -348.814887)
			(xy 338.508395 -348.856106) (xy 338.467174 -348.891823) (xy 338.421289 -348.921309) (xy 338.371675 -348.943965)
			(xy 338.319342 -348.95933) (xy 338.265355 -348.96709) (xy 338.238084 -348.967552) (xy 337.374484 -348.967552)
			(xy 337.347215 -348.967084) (xy 337.293231 -348.959321) (xy 337.240902 -348.943954) (xy 337.191293 -348.921296)
			(xy 337.145413 -348.891809) (xy 337.104196 -348.856093) (xy 337.068482 -348.814874) (xy 337.038996 -348.768993)
			(xy 337.016341 -348.719383) (xy 337.000976 -348.667053) (xy 336.993214 -348.613069) (xy 335.510366 -348.613069)
			(xy 335.502605 -348.667048) (xy 335.487241 -348.719374) (xy 335.464587 -348.768981) (xy 335.435104 -348.81486)
			(xy 335.399393 -348.856076) (xy 335.358179 -348.89179) (xy 335.312302 -348.921276) (xy 335.262696 -348.943933)
			(xy 335.210371 -348.9593) (xy 335.156392 -348.967064) (xy 335.129124 -348.967552) (xy 334.265524 -348.967552)
			(xy 334.238251 -348.96711) (xy 334.18426 -348.959351) (xy 334.131923 -348.943986) (xy 334.082306 -348.921329)
			(xy 334.036418 -348.891841) (xy 333.995194 -348.856123) (xy 333.959473 -348.814901) (xy 333.929982 -348.769015)
			(xy 333.907322 -348.719399) (xy 333.891955 -348.667063) (xy 333.884192 -348.613073) (xy 332.401488 -348.613073)
			(xy 332.393726 -348.667061) (xy 332.378358 -348.719395) (xy 332.355698 -348.769009) (xy 332.326208 -348.814893)
			(xy 332.290488 -348.856113) (xy 332.249264 -348.89183) (xy 332.203377 -348.921316) (xy 332.153761 -348.94397)
			(xy 332.101425 -348.959333) (xy 332.047436 -348.967091) (xy 332.020164 -348.967552) (xy 331.156564 -348.967552)
			(xy 331.129296 -348.967083) (xy 331.075314 -348.959317) (xy 331.022988 -348.943948) (xy 330.973381 -348.921289)
			(xy 330.927503 -348.891802) (xy 330.886289 -348.856086) (xy 330.850577 -348.814868) (xy 330.821093 -348.768987)
			(xy 330.798439 -348.719378) (xy 330.783075 -348.66705) (xy 330.775314 -348.613068) (xy 329.292466 -348.613068)
			(xy 329.284704 -348.66705) (xy 329.26934 -348.719378) (xy 329.246684 -348.768987) (xy 329.217199 -348.814866)
			(xy 329.181486 -348.856083) (xy 329.140269 -348.891797) (xy 329.09439 -348.921282) (xy 329.044782 -348.943938)
			(xy 328.992454 -348.959303) (xy 328.938472 -348.967065) (xy 328.911204 -348.967552) (xy 328.047604 -348.967552)
			(xy 328.020332 -348.967109) (xy 327.966343 -348.959347) (xy 327.914009 -348.943981) (xy 327.864394 -348.921323)
			(xy 327.818509 -348.891834) (xy 327.777287 -348.856116) (xy 327.741568 -348.814895) (xy 327.712079 -348.76901)
			(xy 327.689421 -348.719395) (xy 327.674054 -348.667061) (xy 327.666292 -348.613072) (xy 326.183465 -348.613072)
			(xy 326.175705 -348.667045) (xy 326.160343 -348.71937) (xy 326.13769 -348.768976) (xy 326.108209 -348.814853)
			(xy 326.0725 -348.856069) (xy 326.031288 -348.891783) (xy 325.985414 -348.921269) (xy 325.935811 -348.943927)
			(xy 325.883488 -348.959296) (xy 325.829511 -348.967063) (xy 325.802244 -348.967552) (xy 324.938644 -348.967552)
			(xy 324.91137 -348.967111) (xy 324.857377 -348.959354) (xy 324.805038 -348.943991) (xy 324.755418 -348.921336)
			(xy 324.709527 -348.891849) (xy 324.668301 -348.85613) (xy 324.632578 -348.814908) (xy 324.603085 -348.769021)
			(xy 324.580424 -348.719403) (xy 324.565055 -348.667066) (xy 324.557292 -348.613074) (xy 323.074608 -348.613074)
			(xy 323.066846 -348.667062) (xy 323.051478 -348.719397) (xy 323.028819 -348.769013) (xy 322.999329 -348.814899)
			(xy 322.963609 -348.85612) (xy 322.922386 -348.891839) (xy 322.876499 -348.921327) (xy 322.826882 -348.943984)
			(xy 322.774546 -348.959349) (xy 322.720556 -348.96711) (xy 322.693284 -348.967552) (xy 322.505578 -348.967552)
			(xy 322.49557 -348.968043) (xy 322.477077 -348.975705) (xy 322.46292 -348.989855) (xy 322.455248 -349.008344)
			(xy 322.454778 -349.018352) (xy 322.454778 -351.178876) (xy 322.455193 -351.188902) (xy 322.462858 -351.207431)
			(xy 322.47703 -351.221616) (xy 322.495552 -351.229298) (xy 322.505578 -351.229676) (xy 322.693284 -351.229676)
			(xy 322.720553 -351.230138) (xy 322.774536 -351.237898) (xy 322.826866 -351.253261) (xy 322.876476 -351.275916)
			(xy 322.922357 -351.3054) (xy 322.963575 -351.341114) (xy 322.999291 -351.38233) (xy 323.028777 -351.42821)
			(xy 323.051433 -351.477819) (xy 323.066799 -351.530148) (xy 323.074561 -351.584131) (xy 323.074561 -351.638669)
			(xy 323.074561 -351.63867) (xy 324.55734 -351.63867) (xy 324.55734 -351.58413) (xy 324.565102 -351.530144)
			(xy 324.580469 -351.477813) (xy 324.603128 -351.428202) (xy 324.632616 -351.382321) (xy 324.668335 -351.341104)
			(xy 324.709556 -351.30539) (xy 324.755441 -351.275906) (xy 324.805055 -351.253254) (xy 324.857387 -351.237893)
			(xy 324.911374 -351.230136) (xy 324.938644 -351.229676) (xy 325.802244 -351.229676) (xy 325.829514 -351.23009)
			(xy 325.883498 -351.237857) (xy 325.935828 -351.253228) (xy 325.985437 -351.275889) (xy 326.031317 -351.305379)
			(xy 326.072534 -351.341097) (xy 326.108248 -351.382318) (xy 326.137732 -351.428201) (xy 326.160388 -351.477814)
			(xy 326.175752 -351.530145) (xy 326.183514 -351.58413) (xy 326.183514 -351.638668) (xy 327.666339 -351.638668)
			(xy 327.666339 -351.584132) (xy 327.674101 -351.53015) (xy 327.689466 -351.477822) (xy 327.712121 -351.428213)
			(xy 327.741607 -351.382334) (xy 327.777321 -351.341118) (xy 327.818537 -351.305404) (xy 327.864417 -351.27592)
			(xy 327.914026 -351.253264) (xy 327.966354 -351.2379) (xy 328.020336 -351.230139) (xy 328.047604 -351.229676)
			(xy 328.911204 -351.229676) (xy 328.938476 -351.230087) (xy 328.992464 -351.23785) (xy 329.044799 -351.253217)
			(xy 329.094413 -351.275876) (xy 329.140298 -351.305365) (xy 329.18152 -351.341083) (xy 329.217238 -351.382305)
			(xy 329.246726 -351.42819) (xy 329.269384 -351.477805) (xy 329.284751 -351.530139) (xy 329.292513 -351.584128)
			(xy 329.292513 -351.638665) (xy 330.775362 -351.638665) (xy 330.775362 -351.584135) (xy 330.783122 -351.53016)
			(xy 330.798484 -351.477838) (xy 330.821135 -351.428236) (xy 330.850615 -351.382361) (xy 330.886323 -351.341148)
			(xy 330.927532 -351.305437) (xy 330.973404 -351.275953) (xy 331.023005 -351.253297) (xy 331.075325 -351.23793)
			(xy 331.129299 -351.230165) (xy 331.156564 -351.229676) (xy 332.020164 -351.229676) (xy 332.047439 -351.230061)
			(xy 332.101436 -351.23782) (xy 332.153778 -351.253185) (xy 332.2034 -351.275842) (xy 332.249293 -351.305332)
			(xy 332.290522 -351.341053) (xy 332.326246 -351.382278) (xy 332.35574 -351.428168) (xy 332.378403 -351.477788)
			(xy 332.393772 -351.530129) (xy 332.401536 -351.584125) (xy 332.401536 -351.638669) (xy 333.884239 -351.638669)
			(xy 333.884239 -351.584131) (xy 333.892001 -351.530147) (xy 333.907367 -351.477818) (xy 333.930024 -351.428208)
			(xy 333.959511 -351.382328) (xy 333.995228 -351.341111) (xy 334.036447 -351.305397) (xy 334.082329 -351.275913)
			(xy 334.13194 -351.253259) (xy 334.18427 -351.237896) (xy 334.238255 -351.230138) (xy 334.265524 -351.229676)
			(xy 335.129124 -351.229676) (xy 335.156395 -351.230088) (xy 335.210381 -351.237853) (xy 335.262713 -351.253222)
			(xy 335.312325 -351.275882) (xy 335.358208 -351.305372) (xy 335.399427 -351.34109) (xy 335.435143 -351.382312)
			(xy 335.464629 -351.428196) (xy 335.487286 -351.477809) (xy 335.502652 -351.530142) (xy 335.510414 -351.584129)
			(xy 335.510414 -351.638666) (xy 336.993262 -351.638666) (xy 336.993262 -351.584134) (xy 337.001023 -351.530157)
			(xy 337.016386 -351.477834) (xy 337.039039 -351.42823) (xy 337.06852 -351.382354) (xy 337.10423 -351.341141)
			(xy 337.145442 -351.30543) (xy 337.191316 -351.275946) (xy 337.240919 -351.253291) (xy 337.293242 -351.237926)
			(xy 337.347218 -351.230163) (xy 337.374484 -351.229676) (xy 338.238084 -351.229676) (xy 338.265358 -351.230062)
			(xy 338.319352 -351.237824) (xy 338.371692 -351.25319) (xy 338.421312 -351.275849) (xy 338.467203 -351.305339)
			(xy 338.508429 -351.34106) (xy 338.544151 -351.382285) (xy 338.573643 -351.428174) (xy 338.596304 -351.477793)
			(xy 338.611673 -351.530132) (xy 338.619436 -351.584126) (xy 338.619436 -351.63867) (xy 340.10214 -351.63867)
			(xy 340.10214 -351.58413) (xy 340.109902 -351.530144) (xy 340.125269 -351.477813) (xy 340.147928 -351.428202)
			(xy 340.177416 -351.382321) (xy 340.213135 -351.341104) (xy 340.254356 -351.30539) (xy 340.300241 -351.275906)
			(xy 340.349855 -351.253254) (xy 340.402187 -351.237893) (xy 340.456174 -351.230136) (xy 340.483444 -351.229676)
			(xy 341.347044 -351.229676) (xy 341.374314 -351.23009) (xy 341.428298 -351.237857) (xy 341.480628 -351.253228)
			(xy 341.530237 -351.275889) (xy 341.576117 -351.305379) (xy 341.617334 -351.341097) (xy 341.653048 -351.382318)
			(xy 341.682532 -351.428201) (xy 341.705188 -351.477814) (xy 341.720552 -351.530145) (xy 341.728314 -351.58413)
			(xy 341.728314 -351.638668) (xy 343.211139 -351.638668) (xy 343.211139 -351.584132) (xy 343.218901 -351.53015)
			(xy 343.234266 -351.477822) (xy 343.256921 -351.428213) (xy 343.286407 -351.382334) (xy 343.322121 -351.341118)
			(xy 343.363337 -351.305404) (xy 343.409217 -351.27592) (xy 343.458826 -351.253264) (xy 343.511154 -351.2379)
			(xy 343.565136 -351.230139) (xy 343.592404 -351.229676) (xy 344.456004 -351.229676) (xy 344.483276 -351.230087)
			(xy 344.537264 -351.23785) (xy 344.589599 -351.253217) (xy 344.639213 -351.275876) (xy 344.685098 -351.305365)
			(xy 344.72632 -351.341083) (xy 344.762038 -351.382305) (xy 344.791526 -351.42819) (xy 344.814184 -351.477805)
			(xy 344.829551 -351.530139) (xy 344.837313 -351.584128) (xy 344.837313 -351.638672) (xy 344.829551 -351.692661)
			(xy 344.814184 -351.744995) (xy 344.791526 -351.79461) (xy 344.762038 -351.840495) (xy 344.726319 -351.881717)
			(xy 344.685098 -351.917435) (xy 344.639213 -351.946924) (xy 344.589599 -351.969583) (xy 344.537264 -351.98495)
			(xy 344.483276 -351.992713) (xy 344.456004 -351.9932) (xy 343.592404 -351.9932) (xy 343.565136 -351.992661)
			(xy 343.511154 -351.9849) (xy 343.458826 -351.969536) (xy 343.409217 -351.94688) (xy 343.363337 -351.917396)
			(xy 343.322121 -351.881682) (xy 343.286407 -351.840466) (xy 343.256921 -351.794587) (xy 343.234266 -351.744978)
			(xy 343.218901 -351.69265) (xy 343.211139 -351.638668) (xy 341.728314 -351.638668) (xy 341.728314 -351.63867)
			(xy 341.720552 -351.692655) (xy 341.705188 -351.744986) (xy 341.682532 -351.794599) (xy 341.653048 -351.840482)
			(xy 341.617334 -351.881703) (xy 341.576117 -351.917421) (xy 341.530237 -351.946911) (xy 341.480628 -351.969572)
			(xy 341.428298 -351.984943) (xy 341.374314 -351.99271) (xy 341.347044 -351.9932) (xy 340.483444 -351.9932)
			(xy 340.456174 -351.992664) (xy 340.402187 -351.984907) (xy 340.349855 -351.969546) (xy 340.300241 -351.946894)
			(xy 340.254356 -351.91741) (xy 340.213135 -351.881696) (xy 340.177416 -351.840479) (xy 340.147928 -351.794598)
			(xy 340.125269 -351.744987) (xy 340.109902 -351.692656) (xy 340.10214 -351.63867) (xy 338.619436 -351.63867)
			(xy 338.619436 -351.638674) (xy 338.611673 -351.692668) (xy 338.596304 -351.745007) (xy 338.573643 -351.794626)
			(xy 338.544151 -351.840515) (xy 338.508429 -351.88174) (xy 338.467203 -351.917461) (xy 338.421312 -351.946951)
			(xy 338.371692 -351.96961) (xy 338.319352 -351.984976) (xy 338.265358 -351.992738) (xy 338.238084 -351.9932)
			(xy 337.374484 -351.9932) (xy 337.347218 -351.992637) (xy 337.293242 -351.984874) (xy 337.240919 -351.969509)
			(xy 337.191316 -351.946854) (xy 337.145442 -351.91737) (xy 337.10423 -351.881659) (xy 337.06852 -351.840446)
			(xy 337.039039 -351.79457) (xy 337.016386 -351.744966) (xy 337.001023 -351.692643) (xy 336.993262 -351.638666)
			(xy 335.510414 -351.638666) (xy 335.510414 -351.638671) (xy 335.502652 -351.692658) (xy 335.487286 -351.744991)
			(xy 335.464629 -351.794604) (xy 335.435143 -351.840488) (xy 335.399427 -351.88171) (xy 335.358208 -351.917428)
			(xy 335.312325 -351.946918) (xy 335.262713 -351.969578) (xy 335.210381 -351.984947) (xy 335.156395 -351.992712)
			(xy 335.129124 -351.9932) (xy 334.265524 -351.9932) (xy 334.238255 -351.992662) (xy 334.18427 -351.984904)
			(xy 334.13194 -351.969541) (xy 334.082329 -351.946887) (xy 334.036447 -351.917403) (xy 333.995228 -351.881689)
			(xy 333.959511 -351.840472) (xy 333.930024 -351.794592) (xy 333.907367 -351.744982) (xy 333.892001 -351.692653)
			(xy 333.884239 -351.638669) (xy 332.401536 -351.638669) (xy 332.401536 -351.638675) (xy 332.393772 -351.692671)
			(xy 332.378403 -351.745011) (xy 332.35574 -351.794632) (xy 332.326246 -351.840522) (xy 332.290522 -351.881747)
			(xy 332.249293 -351.917468) (xy 332.2034 -351.946958) (xy 332.153778 -351.969615) (xy 332.101436 -351.98498)
			(xy 332.047439 -351.992739) (xy 332.020164 -351.9932) (xy 331.156564 -351.9932) (xy 331.129299 -351.992635)
			(xy 331.075325 -351.98487) (xy 331.023005 -351.969503) (xy 330.973404 -351.946847) (xy 330.927532 -351.917363)
			(xy 330.886323 -351.881652) (xy 330.850615 -351.840439) (xy 330.821136 -351.794564) (xy 330.798484 -351.744962)
			(xy 330.783122 -351.69264) (xy 330.775362 -351.638665) (xy 329.292513 -351.638665) (xy 329.292513 -351.638672)
			(xy 329.284751 -351.692661) (xy 329.269384 -351.744995) (xy 329.246726 -351.79461) (xy 329.217238 -351.840495)
			(xy 329.181519 -351.881717) (xy 329.140298 -351.917435) (xy 329.094413 -351.946924) (xy 329.044799 -351.969583)
			(xy 328.992464 -351.98495) (xy 328.938476 -351.992713) (xy 328.911204 -351.9932) (xy 328.047604 -351.9932)
			(xy 328.020336 -351.992661) (xy 327.966354 -351.9849) (xy 327.914026 -351.969536) (xy 327.864417 -351.94688)
			(xy 327.818537 -351.917396) (xy 327.777321 -351.881682) (xy 327.741607 -351.840466) (xy 327.712121 -351.794587)
			(xy 327.689466 -351.744978) (xy 327.674101 -351.69265) (xy 327.666339 -351.638668) (xy 326.183514 -351.638668)
			(xy 326.183514 -351.63867) (xy 326.175752 -351.692655) (xy 326.160388 -351.744986) (xy 326.137732 -351.794599)
			(xy 326.108248 -351.840482) (xy 326.072534 -351.881703) (xy 326.031317 -351.917421) (xy 325.985437 -351.946911)
			(xy 325.935828 -351.969572) (xy 325.883498 -351.984943) (xy 325.829514 -351.99271) (xy 325.802244 -351.9932)
			(xy 324.938644 -351.9932) (xy 324.911374 -351.992664) (xy 324.857387 -351.984907) (xy 324.805055 -351.969546)
			(xy 324.755441 -351.946894) (xy 324.709556 -351.91741) (xy 324.668335 -351.881696) (xy 324.632616 -351.840479)
			(xy 324.603128 -351.794598) (xy 324.580469 -351.744987) (xy 324.565102 -351.692656) (xy 324.55734 -351.63867)
			(xy 323.074561 -351.63867) (xy 323.066799 -351.692652) (xy 323.051433 -351.744981) (xy 323.028777 -351.79459)
			(xy 322.999291 -351.84047) (xy 322.963575 -351.881686) (xy 322.922357 -351.9174) (xy 322.876476 -351.946884)
			(xy 322.826866 -351.969539) (xy 322.774536 -351.984902) (xy 322.720553 -351.992662) (xy 322.693284 -351.9932)
			(xy 322.505578 -351.9932) (xy 322.495573 -351.993692) (xy 322.477089 -352.001355) (xy 322.462943 -352.015508)
			(xy 322.455288 -352.033995) (xy 322.454778 -352.044) (xy 322.454778 -354.29952) (xy 322.455269 -354.309527)
			(xy 322.462931 -354.328015) (xy 322.477083 -354.342168) (xy 322.495571 -354.349831) (xy 322.505578 -354.35032)
			(xy 322.693284 -354.35032) (xy 322.720557 -354.350782) (xy 322.774548 -354.358543) (xy 322.826885 -354.373909)
			(xy 322.876503 -354.396566) (xy 322.922391 -354.426055) (xy 322.963615 -354.461774) (xy 322.999335 -354.502997)
			(xy 323.028826 -354.548883) (xy 323.051486 -354.5985) (xy 323.066854 -354.650836) (xy 323.074616 -354.704827)
			(xy 323.074616 -354.759373) (xy 323.074616 -354.759374) (xy 324.557284 -354.759374) (xy 324.557284 -354.704826)
			(xy 324.565047 -354.650832) (xy 324.580417 -354.598494) (xy 324.603078 -354.548875) (xy 324.632571 -354.502987)
			(xy 324.668295 -354.461764) (xy 324.709523 -354.426045) (xy 324.755414 -354.396557) (xy 324.805035 -354.373901)
			(xy 324.857375 -354.358538) (xy 324.91137 -354.350781) (xy 324.938644 -354.35032) (xy 325.802244 -354.35032)
			(xy 325.82951 -354.350845) (xy 325.883486 -354.358612) (xy 325.935808 -354.37398) (xy 325.98541 -354.396638)
			(xy 326.031284 -354.426124) (xy 326.072494 -354.461837) (xy 326.108203 -354.503052) (xy 326.137683 -354.548928)
			(xy 326.160335 -354.598533) (xy 326.175698 -354.650857) (xy 326.183458 -354.704834) (xy 326.183458 -354.759366)
			(xy 326.183457 -354.759372) (xy 327.666284 -354.759372) (xy 327.666284 -354.704828) (xy 327.674046 -354.650838)
			(xy 327.689413 -354.598502) (xy 327.712072 -354.548887) (xy 327.741562 -354.503001) (xy 327.777281 -354.461778)
			(xy 327.818504 -354.426059) (xy 327.86439 -354.39657) (xy 327.914006 -354.373912) (xy 327.966342 -354.358545)
			(xy 328.020332 -354.350783) (xy 328.047604 -354.35032) (xy 328.911204 -354.35032) (xy 328.938472 -354.350843)
			(xy 328.992453 -354.358604) (xy 329.044779 -354.373969) (xy 329.094386 -354.396625) (xy 329.140265 -354.426109)
			(xy 329.18148 -354.461823) (xy 329.217193 -354.503039) (xy 329.246677 -354.548917) (xy 329.269332 -354.598525)
			(xy 329.284696 -354.650851) (xy 329.292458 -354.704832) (xy 329.292458 -354.759368) (xy 329.292458 -354.759369)
			(xy 330.775306 -354.759369) (xy 330.775306 -354.704831) (xy 330.783067 -354.650848) (xy 330.798432 -354.598519)
			(xy 330.821086 -354.548909) (xy 330.85057 -354.503027) (xy 330.886283 -354.461809) (xy 330.927499 -354.426092)
			(xy 330.973377 -354.396604) (xy 331.022985 -354.373944) (xy 331.075313 -354.358575) (xy 331.129295 -354.350809)
			(xy 331.156564 -354.35032) (xy 332.020164 -354.35032) (xy 332.047435 -354.350817) (xy 332.101424 -354.358575)
			(xy 332.153758 -354.373937) (xy 332.203374 -354.396591) (xy 332.24926 -354.426077) (xy 332.290482 -354.461793)
			(xy 332.326202 -354.503012) (xy 332.355691 -354.548895) (xy 332.37835 -354.598508) (xy 332.393718 -354.650841)
			(xy 332.40148 -354.704829) (xy 332.40148 -354.759371) (xy 332.40148 -354.759373) (xy 333.884184 -354.759373)
			(xy 333.884184 -354.704827) (xy 333.891947 -354.650835) (xy 333.907315 -354.598498) (xy 333.929975 -354.548881)
			(xy 333.959467 -354.502994) (xy 333.995188 -354.461771) (xy 334.036413 -354.426052) (xy 334.082302 -354.396564)
			(xy 334.131921 -354.373907) (xy 334.184259 -354.358542) (xy 334.238251 -354.350782) (xy 334.265524 -354.35032)
			(xy 335.129124 -354.35032) (xy 335.156391 -354.350844) (xy 335.210369 -354.358608) (xy 335.262694 -354.373975)
			(xy 335.312298 -354.396631) (xy 335.358174 -354.426116) (xy 335.399387 -354.46183) (xy 335.435098 -354.503045)
			(xy 335.46458 -354.548923) (xy 335.487234 -354.598529) (xy 335.502597 -354.650854) (xy 335.510358 -354.704833)
			(xy 335.510358 -354.759367) (xy 335.510358 -354.75937) (xy 336.993206 -354.75937) (xy 336.993206 -354.70483)
			(xy 337.000968 -354.650845) (xy 337.016333 -354.598515) (xy 337.038989 -354.548903) (xy 337.068475 -354.503021)
			(xy 337.10419 -354.461802) (xy 337.145408 -354.426085) (xy 337.191289 -354.396597) (xy 337.2409 -354.373939)
			(xy 337.29323 -354.358571) (xy 337.347214 -354.350808) (xy 337.374484 -354.35032) (xy 338.238084 -354.35032)
			(xy 338.265354 -354.350818) (xy 338.319341 -354.358578) (xy 338.371673 -354.373942) (xy 338.421285 -354.396598)
			(xy 338.467169 -354.426084) (xy 338.508389 -354.4618) (xy 338.544107 -354.503018) (xy 338.573594 -354.5489)
			(xy 338.596252 -354.598512) (xy 338.611618 -354.650844) (xy 338.619381 -354.70483) (xy 338.619381 -354.75937)
			(xy 338.61938 -354.759374) (xy 340.102084 -354.759374) (xy 340.102084 -354.704826) (xy 340.109847 -354.650832)
			(xy 340.125217 -354.598494) (xy 340.147878 -354.548875) (xy 340.177371 -354.502987) (xy 340.213095 -354.461764)
			(xy 340.254323 -354.426045) (xy 340.300214 -354.396557) (xy 340.349835 -354.373901) (xy 340.402175 -354.358538)
			(xy 340.45617 -354.350781) (xy 340.483444 -354.35032) (xy 341.347044 -354.35032) (xy 341.37431 -354.350845)
			(xy 341.428286 -354.358612) (xy 341.480608 -354.37398) (xy 341.53021 -354.396638) (xy 341.576084 -354.426124)
			(xy 341.617294 -354.461837) (xy 341.653003 -354.503052) (xy 341.682483 -354.548928) (xy 341.705135 -354.598533)
			(xy 341.720498 -354.650857) (xy 341.728258 -354.704834) (xy 341.728258 -354.759366) (xy 341.728257 -354.759372)
			(xy 343.211084 -354.759372) (xy 343.211084 -354.704828) (xy 343.218846 -354.650838) (xy 343.234213 -354.598502)
			(xy 343.256872 -354.548887) (xy 343.286362 -354.503001) (xy 343.322081 -354.461778) (xy 343.363304 -354.426059)
			(xy 343.40919 -354.39657) (xy 343.458806 -354.373912) (xy 343.511142 -354.358545) (xy 343.565132 -354.350783)
			(xy 343.592404 -354.35032) (xy 344.456004 -354.35032) (xy 344.483272 -354.350843) (xy 344.537253 -354.358604)
			(xy 344.589579 -354.373969) (xy 344.639186 -354.396625) (xy 344.685065 -354.426109) (xy 344.72628 -354.461823)
			(xy 344.761993 -354.503039) (xy 344.791477 -354.548917) (xy 344.814132 -354.598525) (xy 344.829496 -354.650851)
			(xy 344.837258 -354.704832) (xy 344.837258 -354.759368) (xy 344.829496 -354.813349) (xy 344.814132 -354.865675)
			(xy 344.791477 -354.915283) (xy 344.761993 -354.961161) (xy 344.72628 -355.002377) (xy 344.685065 -355.038091)
			(xy 344.639186 -355.067575) (xy 344.589579 -355.090231) (xy 344.537253 -355.105596) (xy 344.483272 -355.113357)
			(xy 344.456004 -355.113844) (xy 343.592404 -355.113844) (xy 343.565132 -355.113417) (xy 343.511142 -355.105655)
			(xy 343.458806 -355.090288) (xy 343.40919 -355.06763) (xy 343.363304 -355.038141) (xy 343.322081 -355.002422)
			(xy 343.286362 -354.961199) (xy 343.256872 -354.915313) (xy 343.234213 -354.865698) (xy 343.218846 -354.813362)
			(xy 343.211084 -354.759372) (xy 341.728257 -354.759372) (xy 341.720498 -354.813343) (xy 341.705135 -354.865667)
			(xy 341.682483 -354.915272) (xy 341.653003 -354.961148) (xy 341.617294 -355.002363) (xy 341.576084 -355.038076)
			(xy 341.53021 -355.067562) (xy 341.480608 -355.09022) (xy 341.428286 -355.105588) (xy 341.37431 -355.113355)
			(xy 341.347044 -355.113844) (xy 340.483444 -355.113844) (xy 340.45617 -355.113419) (xy 340.402175 -355.105662)
			(xy 340.349835 -355.090299) (xy 340.300214 -355.067643) (xy 340.254323 -355.038155) (xy 340.213095 -355.002436)
			(xy 340.177371 -354.961213) (xy 340.147878 -354.915325) (xy 340.125217 -354.865706) (xy 340.109847 -354.813368)
			(xy 340.102084 -354.759374) (xy 338.61938 -354.759374) (xy 338.611618 -354.813356) (xy 338.596252 -354.865688)
			(xy 338.573594 -354.9153) (xy 338.544107 -354.961182) (xy 338.508389 -355.0024) (xy 338.467169 -355.038116)
			(xy 338.421285 -355.067602) (xy 338.371673 -355.090258) (xy 338.319341 -355.105622) (xy 338.265354 -355.113382)
			(xy 338.238084 -355.113844) (xy 337.374484 -355.113844) (xy 337.347214 -355.113392) (xy 337.29323 -355.105629)
			(xy 337.2409 -355.090261) (xy 337.191289 -355.067603) (xy 337.145408 -355.038115) (xy 337.10419 -355.002398)
			(xy 337.068475 -354.961179) (xy 337.038989 -354.915297) (xy 337.016333 -354.865685) (xy 337.000968 -354.813355)
			(xy 336.993206 -354.75937) (xy 335.510358 -354.75937) (xy 335.502597 -354.813346) (xy 335.487234 -354.865671)
			(xy 335.46458 -354.915277) (xy 335.435098 -354.961155) (xy 335.399387 -355.00237) (xy 335.358174 -355.038084)
			(xy 335.312298 -355.067569) (xy 335.262694 -355.090225) (xy 335.210369 -355.105592) (xy 335.156391 -355.113356)
			(xy 335.129124 -355.113844) (xy 334.265524 -355.113844) (xy 334.238251 -355.113418) (xy 334.184259 -355.105658)
			(xy 334.131921 -355.090293) (xy 334.082302 -355.067636) (xy 334.036413 -355.038148) (xy 333.995188 -355.002429)
			(xy 333.959467 -354.961206) (xy 333.929975 -354.915319) (xy 333.907315 -354.865702) (xy 333.891947 -354.813365)
			(xy 333.884184 -354.759373) (xy 332.40148 -354.759373) (xy 332.393718 -354.813359) (xy 332.37835 -354.865692)
			(xy 332.355691 -354.915305) (xy 332.326202 -354.961188) (xy 332.290482 -355.002407) (xy 332.24926 -355.038123)
			(xy 332.203374 -355.067609) (xy 332.153758 -355.090263) (xy 332.101424 -355.105625) (xy 332.047435 -355.113383)
			(xy 332.020164 -355.113844) (xy 331.156564 -355.113844) (xy 331.129295 -355.113391) (xy 331.075313 -355.105625)
			(xy 331.022985 -355.090256) (xy 330.973377 -355.067596) (xy 330.927499 -355.038108) (xy 330.886283 -355.002391)
			(xy 330.85057 -354.961173) (xy 330.821086 -354.915291) (xy 330.798432 -354.865681) (xy 330.783067 -354.813352)
			(xy 330.775306 -354.759369) (xy 329.292458 -354.759369) (xy 329.284696 -354.813349) (xy 329.269332 -354.865675)
			(xy 329.246677 -354.915283) (xy 329.217193 -354.961161) (xy 329.18148 -355.002377) (xy 329.140265 -355.038091)
			(xy 329.094386 -355.067575) (xy 329.044779 -355.090231) (xy 328.992453 -355.105596) (xy 328.938472 -355.113357)
			(xy 328.911204 -355.113844) (xy 328.047604 -355.113844) (xy 328.020332 -355.113417) (xy 327.966342 -355.105655)
			(xy 327.914006 -355.090288) (xy 327.86439 -355.06763) (xy 327.818504 -355.038141) (xy 327.777281 -355.002422)
			(xy 327.741562 -354.961199) (xy 327.712072 -354.915313) (xy 327.689413 -354.865698) (xy 327.674046 -354.813362)
			(xy 327.666284 -354.759372) (xy 326.183457 -354.759372) (xy 326.175698 -354.813343) (xy 326.160335 -354.865667)
			(xy 326.137683 -354.915272) (xy 326.108203 -354.961148) (xy 326.072494 -355.002363) (xy 326.031284 -355.038076)
			(xy 325.98541 -355.067562) (xy 325.935808 -355.09022) (xy 325.883486 -355.105588) (xy 325.82951 -355.113355)
			(xy 325.802244 -355.113844) (xy 324.938644 -355.113844) (xy 324.91137 -355.113419) (xy 324.857375 -355.105662)
			(xy 324.805035 -355.090299) (xy 324.755414 -355.067643) (xy 324.709523 -355.038155) (xy 324.668295 -355.002436)
			(xy 324.632571 -354.961213) (xy 324.603078 -354.915325) (xy 324.580417 -354.865706) (xy 324.565047 -354.813368)
			(xy 324.557284 -354.759374) (xy 323.074616 -354.759374) (xy 323.066853 -354.813364) (xy 323.051486 -354.8657)
			(xy 323.028826 -354.915317) (xy 322.999335 -354.961203) (xy 322.963615 -355.002426) (xy 322.922391 -355.038145)
			(xy 322.876503 -355.067634) (xy 322.826885 -355.090291) (xy 322.774548 -355.105657) (xy 322.720557 -355.113418)
			(xy 322.693284 -355.113844) (xy 322.505578 -355.113844) (xy 322.495563 -355.114268) (xy 322.477061 -355.121943)
			(xy 322.462906 -355.136117) (xy 322.455255 -355.154628) (xy 322.454778 -355.164644) (xy 322.454778 -355.538024)
			(xy 322.45435 -355.548092) (xy 322.446627 -355.566688) (xy 322.439792 -355.574092) (xy 320.666618 -357.347266)
			(xy 320.659217 -357.354103) (xy 320.640618 -357.361813) (xy 320.63055 -357.362252) (xy 320.068194 -357.362252)
			(xy 320.03238 -357.376984) (xy 320.015185 -357.39343) (xy 319.977214 -357.422101) (xy 319.956688 -357.434134)
			(xy 319.947544 -357.439214) (xy 319.935352 -357.454708) (xy 319.91046 -357.543354) (xy 319.912746 -357.562912)
			(xy 319.917826 -357.572056) (xy 319.932892 -357.600526) (xy 319.95428 -357.661278) (xy 319.965131 -357.724765)
			(xy 319.965832 -357.756968) (xy 319.965832 -357.75773) (xy 319.965344 -357.784967) (xy 321.448454 -357.784967)
			(xy 321.448454 -357.730434) (xy 321.456215 -357.676456) (xy 321.471578 -357.624131) (xy 321.494232 -357.574526)
			(xy 321.523714 -357.52865) (xy 321.559424 -357.487436) (xy 321.600637 -357.451723) (xy 321.646512 -357.422239)
			(xy 321.696116 -357.399584) (xy 321.74844 -357.384218) (xy 321.802418 -357.376455) (xy 321.829684 -357.375968)
			(xy 322.693284 -357.375968) (xy 322.720558 -357.37637) (xy 322.774551 -357.384131) (xy 322.826889 -357.399497)
			(xy 322.876508 -357.422156) (xy 322.922398 -357.451645) (xy 322.963623 -357.487366) (xy 322.999345 -357.528589)
			(xy 323.028836 -357.574477) (xy 323.051497 -357.624096) (xy 323.066865 -357.676434) (xy 323.074628 -357.730426)
			(xy 323.074628 -357.784971) (xy 324.557332 -357.784971) (xy 324.557332 -357.730429) (xy 324.565094 -357.676443)
			(xy 324.580461 -357.624111) (xy 324.603121 -357.574498) (xy 324.63261 -357.528616) (xy 324.668329 -357.487398)
			(xy 324.709551 -357.451684) (xy 324.755437 -357.422199) (xy 324.805052 -357.399546) (xy 324.857386 -357.384185)
			(xy 324.911373 -357.376428) (xy 324.938644 -357.375968) (xy 325.802244 -357.375968) (xy 325.829513 -357.376398)
			(xy 325.883497 -357.384165) (xy 325.935825 -357.399535) (xy 325.985433 -357.422196) (xy 326.031312 -357.451685)
			(xy 326.072528 -357.487403) (xy 326.108241 -357.528623) (xy 326.137725 -357.574505) (xy 326.16038 -357.624116)
			(xy 326.175744 -357.676447) (xy 326.183506 -357.73043) (xy 326.183506 -357.784969) (xy 327.666331 -357.784969)
			(xy 327.666331 -357.730431) (xy 327.674093 -357.676448) (xy 327.689458 -357.624119) (xy 327.712114 -357.57451)
			(xy 327.7416 -357.528629) (xy 327.777315 -357.487412) (xy 327.818533 -357.451698) (xy 327.864413 -357.422212)
			(xy 327.914023 -357.399557) (xy 327.966352 -357.384192) (xy 328.020335 -357.376431) (xy 328.047604 -357.375968)
			(xy 328.911204 -357.375968) (xy 328.938475 -357.376395) (xy 328.992463 -357.384158) (xy 329.044796 -357.399524)
			(xy 329.094409 -357.422183) (xy 329.140293 -357.451671) (xy 329.181514 -357.487389) (xy 329.217231 -357.52861)
			(xy 329.246719 -357.574494) (xy 329.269377 -357.624108) (xy 329.284743 -357.676441) (xy 329.292506 -357.730429)
			(xy 329.292506 -357.784966) (xy 330.775354 -357.784966) (xy 330.775354 -357.730434) (xy 330.783114 -357.676458)
			(xy 330.798477 -357.624136) (xy 330.821128 -357.574532) (xy 330.850609 -357.528656) (xy 330.886317 -357.487443)
			(xy 330.927527 -357.45173) (xy 330.9734 -357.422246) (xy 331.023002 -357.399589) (xy 331.075323 -357.384222)
			(xy 331.129298 -357.376457) (xy 331.156564 -357.375968) (xy 332.020164 -357.375968) (xy 332.047439 -357.376369)
			(xy 332.101434 -357.384128) (xy 332.153775 -357.399492) (xy 332.203397 -357.422149) (xy 332.249288 -357.451638)
			(xy 332.290516 -357.487359) (xy 332.32624 -357.528583) (xy 332.355733 -357.574472) (xy 332.378395 -357.624091)
			(xy 332.393765 -357.676431) (xy 332.401528 -357.730425) (xy 332.401528 -357.78497) (xy 333.884231 -357.78497)
			(xy 333.884231 -357.73043) (xy 333.891994 -357.676445) (xy 333.90736 -357.624115) (xy 333.930017 -357.574504)
			(xy 333.959505 -357.528623) (xy 333.995222 -357.487405) (xy 334.036442 -357.451691) (xy 334.082325 -357.422206)
			(xy 334.131937 -357.399552) (xy 334.184269 -357.384189) (xy 334.238254 -357.37643) (xy 334.265524 -357.375968)
			(xy 335.129124 -357.375968) (xy 335.156394 -357.376396) (xy 335.21038 -357.384161) (xy 335.26271 -357.39953)
			(xy 335.312321 -357.422189) (xy 335.358203 -357.451678) (xy 335.399421 -357.487396) (xy 335.435136 -357.528616)
			(xy 335.464622 -357.5745) (xy 335.487279 -357.624112) (xy 335.502644 -357.676444) (xy 335.510406 -357.73043)
			(xy 335.510406 -357.784967) (xy 336.993254 -357.784967) (xy 336.993254 -357.730434) (xy 337.001015 -357.676456)
			(xy 337.016378 -357.624131) (xy 337.039032 -357.574526) (xy 337.068514 -357.52865) (xy 337.104224 -357.487436)
			(xy 337.145437 -357.451723) (xy 337.191312 -357.422239) (xy 337.240916 -357.399584) (xy 337.29324 -357.384218)
			(xy 337.347218 -357.376455) (xy 337.374484 -357.375968) (xy 338.238084 -357.375968) (xy 338.265358 -357.37637)
			(xy 338.319351 -357.384131) (xy 338.371689 -357.399497) (xy 338.421308 -357.422156) (xy 338.467198 -357.451645)
			(xy 338.508423 -357.487366) (xy 338.544145 -357.528589) (xy 338.573636 -357.574477) (xy 338.596297 -357.624096)
			(xy 338.611665 -357.676434) (xy 338.619428 -357.730426) (xy 338.619428 -357.784971) (xy 340.102132 -357.784971)
			(xy 340.102132 -357.730429) (xy 340.109894 -357.676443) (xy 340.125261 -357.624111) (xy 340.147921 -357.574498)
			(xy 340.17741 -357.528616) (xy 340.213129 -357.487398) (xy 340.254351 -357.451684) (xy 340.300237 -357.422199)
			(xy 340.349852 -357.399546) (xy 340.402186 -357.384185) (xy 340.456173 -357.376428) (xy 340.483444 -357.375968)
			(xy 341.347044 -357.375968) (xy 341.374313 -357.376398) (xy 341.428297 -357.384165) (xy 341.480625 -357.399535)
			(xy 341.530233 -357.422196) (xy 341.576112 -357.451685) (xy 341.617328 -357.487403) (xy 341.653041 -357.528623)
			(xy 341.682525 -357.574505) (xy 341.70518 -357.624116) (xy 341.720544 -357.676447) (xy 341.728306 -357.73043)
			(xy 341.728306 -357.784969) (xy 343.211131 -357.784969) (xy 343.211131 -357.730431) (xy 343.218893 -357.676448)
			(xy 343.234258 -357.624119) (xy 343.256914 -357.57451) (xy 343.2864 -357.528629) (xy 343.322115 -357.487412)
			(xy 343.363333 -357.451698) (xy 343.409213 -357.422212) (xy 343.458823 -357.399557) (xy 343.511152 -357.384192)
			(xy 343.565135 -357.376431) (xy 343.592404 -357.375968) (xy 344.456004 -357.375968) (xy 344.483275 -357.376395)
			(xy 344.537263 -357.384158) (xy 344.589596 -357.399524) (xy 344.639209 -357.422183) (xy 344.685093 -357.451671)
			(xy 344.726314 -357.487389) (xy 344.762031 -357.52861) (xy 344.791519 -357.574494) (xy 344.814177 -357.624108)
			(xy 344.829543 -357.676441) (xy 344.837306 -357.730429) (xy 344.837306 -357.784971) (xy 344.829543 -357.838959)
			(xy 344.814177 -357.891292) (xy 344.791519 -357.940906) (xy 344.762031 -357.98679) (xy 344.726314 -358.028011)
			(xy 344.685093 -358.063729) (xy 344.639209 -358.093217) (xy 344.589596 -358.115876) (xy 344.537263 -358.131242)
			(xy 344.483275 -358.139005) (xy 344.456004 -358.139492) (xy 343.592404 -358.139492) (xy 343.565135 -358.138969)
			(xy 343.511152 -358.131208) (xy 343.458823 -358.115843) (xy 343.409213 -358.093188) (xy 343.363333 -358.063702)
			(xy 343.322115 -358.027988) (xy 343.2864 -357.986771) (xy 343.256914 -357.94089) (xy 343.234258 -357.891281)
			(xy 343.218893 -357.838952) (xy 343.211131 -357.784969) (xy 341.728306 -357.784969) (xy 341.728306 -357.78497)
			(xy 341.720544 -357.838953) (xy 341.70518 -357.891284) (xy 341.682525 -357.940895) (xy 341.653041 -357.986777)
			(xy 341.617328 -358.027997) (xy 341.576112 -358.063715) (xy 341.530233 -358.093204) (xy 341.480625 -358.115865)
			(xy 341.428297 -358.131235) (xy 341.374313 -358.139002) (xy 341.347044 -358.139492) (xy 340.483444 -358.139492)
			(xy 340.456173 -358.138972) (xy 340.402186 -358.131215) (xy 340.349852 -358.115854) (xy 340.300237 -358.093201)
			(xy 340.254351 -358.063716) (xy 340.213129 -358.028002) (xy 340.17741 -357.986784) (xy 340.147921 -357.940902)
			(xy 340.125261 -357.891289) (xy 340.109894 -357.838957) (xy 340.102132 -357.784971) (xy 338.619428 -357.784971)
			(xy 338.619428 -357.784974) (xy 338.611665 -357.838966) (xy 338.596297 -357.891304) (xy 338.573636 -357.940923)
			(xy 338.544145 -357.986811) (xy 338.508423 -358.028034) (xy 338.467198 -358.063755) (xy 338.421308 -358.093244)
			(xy 338.371689 -358.115903) (xy 338.319351 -358.131269) (xy 338.265358 -358.13903) (xy 338.238084 -358.139492)
			(xy 337.374484 -358.139492) (xy 337.347218 -358.138945) (xy 337.29324 -358.131182) (xy 337.240916 -358.115816)
			(xy 337.191312 -358.093161) (xy 337.145437 -358.063677) (xy 337.104224 -358.027964) (xy 337.068514 -357.98675)
			(xy 337.039032 -357.940874) (xy 337.016378 -357.891269) (xy 337.001015 -357.838944) (xy 336.993254 -357.784967)
			(xy 335.510406 -357.784967) (xy 335.510406 -357.78497) (xy 335.502644 -357.838956) (xy 335.487279 -357.891288)
			(xy 335.464622 -357.9409) (xy 335.435136 -357.986784) (xy 335.399421 -358.028004) (xy 335.358203 -358.063722)
			(xy 335.312321 -358.093211) (xy 335.26271 -358.11587) (xy 335.21038 -358.131239) (xy 335.156394 -358.139004)
			(xy 335.129124 -358.139492) (xy 334.265524 -358.139492) (xy 334.238254 -358.13897) (xy 334.184269 -358.131211)
			(xy 334.131937 -358.115848) (xy 334.082325 -358.093194) (xy 334.036442 -358.063709) (xy 333.995222 -358.027995)
			(xy 333.959505 -357.986777) (xy 333.930017 -357.940896) (xy 333.90736 -357.891285) (xy 333.891994 -357.838955)
			(xy 333.884231 -357.78497) (xy 332.401528 -357.78497) (xy 332.401528 -357.784975) (xy 332.393765 -357.838969)
			(xy 332.378395 -357.891309) (xy 332.355733 -357.940928) (xy 332.32624 -357.986817) (xy 332.290516 -358.028041)
			(xy 332.249288 -358.063762) (xy 332.203397 -358.093251) (xy 332.153775 -358.115908) (xy 332.101434 -358.131272)
			(xy 332.047439 -358.139031) (xy 332.020164 -358.139492) (xy 331.156564 -358.139492) (xy 331.129298 -358.138943)
			(xy 331.075323 -358.131178) (xy 331.023002 -358.115811) (xy 330.9734 -358.093154) (xy 330.927527 -358.06367)
			(xy 330.886317 -358.027957) (xy 330.850609 -357.986744) (xy 330.821128 -357.940868) (xy 330.798477 -357.891264)
			(xy 330.783114 -357.838942) (xy 330.775354 -357.784966) (xy 329.292506 -357.784966) (xy 329.292506 -357.784971)
			(xy 329.284743 -357.838959) (xy 329.269377 -357.891292) (xy 329.246719 -357.940906) (xy 329.217231 -357.98679)
			(xy 329.181514 -358.028011) (xy 329.140293 -358.063729) (xy 329.094409 -358.093217) (xy 329.044796 -358.115876)
			(xy 328.992463 -358.131242) (xy 328.938475 -358.139005) (xy 328.911204 -358.139492) (xy 328.047604 -358.139492)
			(xy 328.020335 -358.138969) (xy 327.966352 -358.131208) (xy 327.914023 -358.115843) (xy 327.864413 -358.093188)
			(xy 327.818533 -358.063702) (xy 327.777315 -358.027988) (xy 327.7416 -357.986771) (xy 327.712114 -357.94089)
			(xy 327.689458 -357.891281) (xy 327.674093 -357.838952) (xy 327.666331 -357.784969) (xy 326.183506 -357.784969)
			(xy 326.183506 -357.78497) (xy 326.175744 -357.838953) (xy 326.16038 -357.891284) (xy 326.137725 -357.940895)
			(xy 326.108241 -357.986777) (xy 326.072528 -358.027997) (xy 326.031312 -358.063715) (xy 325.985433 -358.093204)
			(xy 325.935825 -358.115865) (xy 325.883497 -358.131235) (xy 325.829513 -358.139002) (xy 325.802244 -358.139492)
			(xy 324.938644 -358.139492) (xy 324.911373 -358.138972) (xy 324.857386 -358.131215) (xy 324.805052 -358.115854)
			(xy 324.755437 -358.093201) (xy 324.709551 -358.063716) (xy 324.668329 -358.028002) (xy 324.63261 -357.986784)
			(xy 324.603121 -357.940902) (xy 324.580461 -357.891289) (xy 324.565094 -357.838957) (xy 324.557332 -357.784971)
			(xy 323.074628 -357.784971) (xy 323.074628 -357.784974) (xy 323.066865 -357.838966) (xy 323.051497 -357.891304)
			(xy 323.028836 -357.940923) (xy 322.999345 -357.986811) (xy 322.963623 -358.028034) (xy 322.922398 -358.063755)
			(xy 322.876508 -358.093244) (xy 322.826889 -358.115903) (xy 322.774551 -358.131269) (xy 322.720558 -358.13903)
			(xy 322.693284 -358.139492) (xy 321.829684 -358.139492) (xy 321.802418 -358.138945) (xy 321.74844 -358.131182)
			(xy 321.696116 -358.115816) (xy 321.646512 -358.093161) (xy 321.600637 -358.063677) (xy 321.559424 -358.027964)
			(xy 321.523714 -357.98675) (xy 321.494232 -357.940874) (xy 321.471578 -357.891269) (xy 321.456215 -357.838944)
			(xy 321.448454 -357.784967) (xy 319.965344 -357.784967) (xy 319.965344 -357.784986) (xy 319.957586 -357.838942)
			(xy 319.94223 -357.891246) (xy 319.91959 -357.940834) (xy 319.890127 -357.986696) (xy 319.854439 -358.027901)
			(xy 319.813252 -358.06361) (xy 319.767404 -358.093097) (xy 319.717828 -358.115762) (xy 319.665532 -358.131144)
			(xy 319.611579 -358.13893) (xy 319.584324 -358.139492) (xy 318.720724 -358.139492) (xy 318.690672 -358.13893)
			(xy 318.631311 -358.129504) (xy 318.574165 -358.110881) (xy 318.520647 -358.083524) (xy 318.472085 -358.048109)
			(xy 318.450468 -358.027224) (xy 318.417702 -358.012238) (xy 318.38646 -358.010206) (xy 318.377333 -358.010032)
			(xy 318.359886 -358.015363) (xy 318.352424 -358.02062) (xy 318.32988 -358.037101) (xy 318.280427 -358.063035)
			(xy 318.227313 -358.080268) (xy 318.19977 -358.084882) (xy 318.191388 -358.086152) (xy 318.177164 -358.093264)
			(xy 316.962028 -359.3084) (xy 363.411514 -359.3084) (xy 363.415585 -359.252778) (xy 363.427711 -359.198341)
			(xy 363.447634 -359.14625) (xy 363.47493 -359.097615) (xy 363.509016 -359.053472) (xy 363.549165 -359.014763)
			(xy 363.594523 -358.982312) (xy 363.644123 -358.956811) (xy 363.696907 -358.938804) (xy 363.75175 -358.928674)
			(xy 363.807484 -358.926637) (xy 363.862921 -358.932737) (xy 363.916878 -358.946843) (xy 363.968207 -358.968655)
			(xy 364.015813 -358.997709) (xy 364.058681 -359.033384) (xy 364.095898 -359.074921) (xy 364.126671 -359.121434)
			(xy 364.150343 -359.171931) (xy 364.166411 -359.225338) (xy 364.174531 -359.280514) (xy 364.17504 -359.3084)
			(xy 364.174531 -359.336286) (xy 364.166411 -359.391462) (xy 364.150343 -359.444869) (xy 364.126671 -359.495366)
			(xy 364.095898 -359.541879) (xy 364.058681 -359.583416) (xy 364.015813 -359.619091) (xy 363.968207 -359.648145)
			(xy 363.916878 -359.669957) (xy 363.862921 -359.684063) (xy 363.807484 -359.690163) (xy 363.75175 -359.688126)
			(xy 363.696907 -359.677996) (xy 363.644123 -359.659989) (xy 363.594523 -359.634488) (xy 363.549165 -359.602037)
			(xy 363.509016 -359.563328) (xy 363.47493 -359.519185) (xy 363.447634 -359.47055) (xy 363.427711 -359.418459)
			(xy 363.415585 -359.364022) (xy 363.411514 -359.3084) (xy 316.962028 -359.3084) (xy 313.818778 -362.45165)
			(xy 357.205532 -362.45165) (xy 357.209603 -362.396028) (xy 357.221729 -362.341591) (xy 357.241652 -362.2895)
			(xy 357.268948 -362.240865) (xy 357.303034 -362.196722) (xy 357.343183 -362.158013) (xy 357.388541 -362.125562)
			(xy 357.438141 -362.100061) (xy 357.490925 -362.082054) (xy 357.545768 -362.071924) (xy 357.601502 -362.069887)
			(xy 357.656939 -362.075987) (xy 357.710896 -362.090093) (xy 357.762225 -362.111905) (xy 357.809831 -362.140959)
			(xy 357.852699 -362.176634) (xy 357.889916 -362.218171) (xy 357.920689 -362.264684) (xy 357.944361 -362.315181)
			(xy 357.960429 -362.368588) (xy 357.968549 -362.423764) (xy 357.969058 -362.45165) (xy 357.968549 -362.479536)
			(xy 357.960429 -362.534712) (xy 357.944361 -362.588119) (xy 357.920689 -362.638616) (xy 357.889916 -362.685129)
			(xy 357.852699 -362.726666) (xy 357.809831 -362.762341) (xy 357.762225 -362.791395) (xy 357.710896 -362.813207)
			(xy 357.656939 -362.827313) (xy 357.601502 -362.833413) (xy 357.545768 -362.831376) (xy 357.490925 -362.821246)
			(xy 357.438141 -362.803239) (xy 357.388541 -362.777738) (xy 357.343183 -362.745287) (xy 357.303034 -362.706578)
			(xy 357.268948 -362.662435) (xy 357.241652 -362.6138) (xy 357.221729 -362.561709) (xy 357.209603 -362.507272)
			(xy 357.205532 -362.45165) (xy 313.818778 -362.45165) (xy 308.990492 -367.279936) (xy 308.983652 -367.287337)
			(xy 308.975932 -367.305935) (xy 308.975506 -367.316004) (xy 308.975506 -368.990118) (xy 333.203812 -368.990118)
			(xy 333.207803 -368.927951) (xy 333.219712 -368.866804) (xy 333.239341 -368.807683) (xy 333.26637 -368.751557)
			(xy 333.300354 -368.699348) (xy 333.340736 -368.651913) (xy 333.386852 -368.610032) (xy 333.437944 -368.574392)
			(xy 333.493175 -368.545578) (xy 333.551637 -368.524064) (xy 333.612371 -368.510202) (xy 333.674378 -368.50422)
			(xy 333.736641 -368.506216) (xy 333.798138 -368.516159) (xy 333.857859 -368.533883) (xy 333.914822 -368.5591)
			(xy 333.968093 -368.591393) (xy 334.016798 -368.630233) (xy 334.060135 -368.674983) (xy 334.097395 -368.724907)
			(xy 334.127964 -368.779186) (xy 334.151342 -368.836929) (xy 334.167143 -368.897187) (xy 334.175109 -368.95897)
			(xy 334.175608 -368.990118) (xy 337.603854 -368.990118) (xy 337.607845 -368.927951) (xy 337.619754 -368.866804)
			(xy 337.639383 -368.807683) (xy 337.666412 -368.751557) (xy 337.700396 -368.699348) (xy 337.740778 -368.651913)
			(xy 337.786894 -368.610032) (xy 337.837986 -368.574392) (xy 337.893217 -368.545578) (xy 337.951679 -368.524064)
			(xy 338.012413 -368.510202) (xy 338.07442 -368.50422) (xy 338.136683 -368.506216) (xy 338.19818 -368.516159)
			(xy 338.257901 -368.533883) (xy 338.314864 -368.5591) (xy 338.368135 -368.591393) (xy 338.41684 -368.630233)
			(xy 338.460177 -368.674983) (xy 338.497437 -368.724907) (xy 338.528006 -368.779186) (xy 338.551384 -368.836929)
			(xy 338.567185 -368.897187) (xy 338.575151 -368.95897) (xy 338.57565 -368.990118) (xy 342.003896 -368.990118)
			(xy 342.007887 -368.927951) (xy 342.019796 -368.866804) (xy 342.039425 -368.807683) (xy 342.066454 -368.751557)
			(xy 342.100438 -368.699348) (xy 342.14082 -368.651913) (xy 342.186936 -368.610032) (xy 342.238028 -368.574392)
			(xy 342.293259 -368.545578) (xy 342.351721 -368.524064) (xy 342.412455 -368.510202) (xy 342.474462 -368.50422)
			(xy 342.536725 -368.506216) (xy 342.598222 -368.516159) (xy 342.657943 -368.533883) (xy 342.714906 -368.5591)
			(xy 342.768177 -368.591393) (xy 342.816882 -368.630233) (xy 342.860219 -368.674983) (xy 342.897479 -368.724907)
			(xy 342.928048 -368.779186) (xy 342.951426 -368.836929) (xy 342.967227 -368.897187) (xy 342.975193 -368.95897)
			(xy 342.975692 -368.990118) (xy 346.403938 -368.990118) (xy 346.407929 -368.927951) (xy 346.419838 -368.866804)
			(xy 346.439467 -368.807683) (xy 346.466496 -368.751557) (xy 346.50048 -368.699348) (xy 346.540862 -368.651913)
			(xy 346.586978 -368.610032) (xy 346.63807 -368.574392) (xy 346.693301 -368.545578) (xy 346.751763 -368.524064)
			(xy 346.812497 -368.510202) (xy 346.874504 -368.50422) (xy 346.936767 -368.506216) (xy 346.998264 -368.516159)
			(xy 347.057985 -368.533883) (xy 347.114948 -368.5591) (xy 347.168219 -368.591393) (xy 347.216924 -368.630233)
			(xy 347.260261 -368.674983) (xy 347.297521 -368.724907) (xy 347.32809 -368.779186) (xy 347.351468 -368.836929)
			(xy 347.367269 -368.897187) (xy 347.375235 -368.95897) (xy 347.375734 -368.990118) (xy 350.80398 -368.990118)
			(xy 350.807971 -368.927951) (xy 350.81988 -368.866804) (xy 350.839509 -368.807683) (xy 350.866538 -368.751557)
			(xy 350.900522 -368.699348) (xy 350.940904 -368.651913) (xy 350.98702 -368.610032) (xy 351.038112 -368.574392)
			(xy 351.093343 -368.545578) (xy 351.151805 -368.524064) (xy 351.212539 -368.510202) (xy 351.274546 -368.50422)
			(xy 351.336809 -368.506216) (xy 351.398306 -368.516159) (xy 351.458027 -368.533883) (xy 351.51499 -368.5591)
			(xy 351.568261 -368.591393) (xy 351.616966 -368.630233) (xy 351.660303 -368.674983) (xy 351.697563 -368.724907)
			(xy 351.728132 -368.779186) (xy 351.75151 -368.836929) (xy 351.767311 -368.897187) (xy 351.775277 -368.95897)
			(xy 351.775776 -368.990118) (xy 351.775277 -369.021266) (xy 351.767311 -369.083049) (xy 351.75151 -369.143307)
			(xy 351.728132 -369.20105) (xy 351.697563 -369.255329) (xy 351.660303 -369.305253) (xy 351.616966 -369.350003)
			(xy 351.568261 -369.388843) (xy 351.51499 -369.421136) (xy 351.458027 -369.446353) (xy 351.398306 -369.464077)
			(xy 351.336809 -369.47402) (xy 351.274546 -369.476016) (xy 351.212539 -369.470034) (xy 351.151805 -369.456172)
			(xy 351.093343 -369.434658) (xy 351.038112 -369.405844) (xy 350.98702 -369.370204) (xy 350.940904 -369.328323)
			(xy 350.900522 -369.280888) (xy 350.866538 -369.228679) (xy 350.839509 -369.172553) (xy 350.81988 -369.113432)
			(xy 350.807971 -369.052285) (xy 350.80398 -368.990118) (xy 347.375734 -368.990118) (xy 347.375235 -369.021266)
			(xy 347.367269 -369.083049) (xy 347.351468 -369.143307) (xy 347.32809 -369.20105) (xy 347.297521 -369.255329)
			(xy 347.260261 -369.305253) (xy 347.216924 -369.350003) (xy 347.168219 -369.388843) (xy 347.114948 -369.421136)
			(xy 347.057985 -369.446353) (xy 346.998264 -369.464077) (xy 346.936767 -369.47402) (xy 346.874504 -369.476016)
			(xy 346.812497 -369.470034) (xy 346.751763 -369.456172) (xy 346.693301 -369.434658) (xy 346.63807 -369.405844)
			(xy 346.586978 -369.370204) (xy 346.540862 -369.328323) (xy 346.50048 -369.280888) (xy 346.466496 -369.228679)
			(xy 346.439467 -369.172553) (xy 346.419838 -369.113432) (xy 346.407929 -369.052285) (xy 346.403938 -368.990118)
			(xy 342.975692 -368.990118) (xy 342.975193 -369.021266) (xy 342.967227 -369.083049) (xy 342.951426 -369.143307)
			(xy 342.928048 -369.20105) (xy 342.897479 -369.255329) (xy 342.860219 -369.305253) (xy 342.816882 -369.350003)
			(xy 342.768177 -369.388843) (xy 342.714906 -369.421136) (xy 342.657943 -369.446353) (xy 342.598222 -369.464077)
			(xy 342.536725 -369.47402) (xy 342.474462 -369.476016) (xy 342.412455 -369.470034) (xy 342.351721 -369.456172)
			(xy 342.293259 -369.434658) (xy 342.238028 -369.405844) (xy 342.186936 -369.370204) (xy 342.14082 -369.328323)
			(xy 342.100438 -369.280888) (xy 342.066454 -369.228679) (xy 342.039425 -369.172553) (xy 342.019796 -369.113432)
			(xy 342.007887 -369.052285) (xy 342.003896 -368.990118) (xy 338.57565 -368.990118) (xy 338.575151 -369.021266)
			(xy 338.567185 -369.083049) (xy 338.551384 -369.143307) (xy 338.528006 -369.20105) (xy 338.497437 -369.255329)
			(xy 338.460177 -369.305253) (xy 338.41684 -369.350003) (xy 338.368135 -369.388843) (xy 338.314864 -369.421136)
			(xy 338.257901 -369.446353) (xy 338.19818 -369.464077) (xy 338.136683 -369.47402) (xy 338.07442 -369.476016)
			(xy 338.012413 -369.470034) (xy 337.951679 -369.456172) (xy 337.893217 -369.434658) (xy 337.837986 -369.405844)
			(xy 337.786894 -369.370204) (xy 337.740778 -369.328323) (xy 337.700396 -369.280888) (xy 337.666412 -369.228679)
			(xy 337.639383 -369.172553) (xy 337.619754 -369.113432) (xy 337.607845 -369.052285) (xy 337.603854 -368.990118)
			(xy 334.175608 -368.990118) (xy 334.175109 -369.021266) (xy 334.167143 -369.083049) (xy 334.151342 -369.143307)
			(xy 334.127964 -369.20105) (xy 334.097395 -369.255329) (xy 334.060135 -369.305253) (xy 334.016798 -369.350003)
			(xy 333.968093 -369.388843) (xy 333.914822 -369.421136) (xy 333.857859 -369.446353) (xy 333.798138 -369.464077)
			(xy 333.736641 -369.47402) (xy 333.674378 -369.476016) (xy 333.612371 -369.470034) (xy 333.551637 -369.456172)
			(xy 333.493175 -369.434658) (xy 333.437944 -369.405844) (xy 333.386852 -369.370204) (xy 333.340736 -369.328323)
			(xy 333.300354 -369.280888) (xy 333.26637 -369.228679) (xy 333.239341 -369.172553) (xy 333.219712 -369.113432)
			(xy 333.207803 -369.052285) (xy 333.203812 -368.990118) (xy 308.975506 -368.990118) (xy 308.975506 -370.522712)
			(xy 331.004943 -370.522712) (xy 331.004944 -370.457268) (xy 331.013739 -370.392417) (xy 331.031167 -370.329337)
			(xy 331.056913 -370.26917) (xy 331.073252 -370.240814) (xy 331.076558 -370.234785) (xy 331.08017 -370.221525)
			(xy 331.080364 -370.214652) (xy 331.080364 -369.928902) (xy 331.080766 -369.918727) (xy 331.088555 -369.899928)
			(xy 331.102948 -369.885542) (xy 331.121751 -369.877761) (xy 331.131926 -369.87734) (xy 331.848206 -369.87734)
			(xy 331.858364 -369.877829) (xy 331.877134 -369.885605) (xy 331.891499 -369.899973) (xy 331.899273 -369.918744)
			(xy 331.899768 -369.928902) (xy 331.899768 -370.214652) (xy 331.899982 -370.221524) (xy 331.903576 -370.234786)
			(xy 331.90688 -370.240814) (xy 331.923207 -370.269176) (xy 331.94895 -370.329342) (xy 331.966377 -370.39242)
			(xy 331.975171 -370.457269) (xy 331.975173 -370.522711) (xy 335.404993 -370.522711) (xy 335.404994 -370.457268)
			(xy 335.413788 -370.392418) (xy 335.431214 -370.329338) (xy 335.456957 -370.269171) (xy 335.473294 -370.240814)
			(xy 335.476649 -370.234794) (xy 335.480391 -370.221538) (xy 335.48066 -370.214652) (xy 335.48066 -369.928902)
			(xy 335.481129 -369.918773) (xy 335.48886 -369.900048) (xy 335.503152 -369.885691) (xy 335.521841 -369.877875)
			(xy 335.531968 -369.87734) (xy 336.248248 -369.87734) (xy 336.25841 -369.877683) (xy 336.277171 -369.885502)
			(xy 336.291494 -369.899923) (xy 336.299185 -369.918737) (xy 336.299556 -369.928902) (xy 336.299556 -370.214652)
			(xy 336.299778 -370.221546) (xy 336.303514 -370.234818) (xy 336.306922 -370.240814) (xy 336.32325 -370.269175)
			(xy 336.348997 -370.32934) (xy 336.366426 -370.392419) (xy 336.375221 -370.457268) (xy 336.375223 -370.522711)
			(xy 336.375223 -370.522712) (xy 339.805029 -370.522712) (xy 339.80503 -370.457268) (xy 339.813825 -370.392418)
			(xy 339.831253 -370.329337) (xy 339.856998 -370.26917) (xy 339.873336 -370.240814) (xy 339.876641 -370.234784)
			(xy 339.880254 -370.221525) (xy 339.880448 -370.214652) (xy 339.880448 -369.928902) (xy 339.880866 -369.918729)
			(xy 339.888652 -369.899933) (xy 339.903039 -369.885547) (xy 339.921837 -369.877764) (xy 339.93201 -369.87734)
			(xy 340.64829 -369.87734) (xy 340.658461 -369.877772) (xy 340.677256 -369.885554) (xy 340.691641 -369.899937)
			(xy 340.699426 -369.918731) (xy 340.699852 -369.928902) (xy 340.699852 -370.214652) (xy 340.700056 -370.221524)
			(xy 340.703655 -370.234788) (xy 340.706964 -370.240814) (xy 340.723291 -370.269176) (xy 340.749036 -370.329341)
			(xy 340.766463 -370.39242) (xy 340.775257 -370.457269) (xy 340.775259 -370.522711) (xy 340.775259 -370.522712)
			(xy 344.204819 -370.522712) (xy 344.20482 -370.457268) (xy 344.213614 -370.392418) (xy 344.231042 -370.329337)
			(xy 344.256786 -370.26917) (xy 344.273124 -370.240814) (xy 344.276435 -370.234788) (xy 344.280043 -370.221525)
			(xy 344.280236 -370.214652) (xy 344.280236 -369.928902) (xy 344.280735 -369.918745) (xy 344.288508 -369.899976)
			(xy 344.302873 -369.885611) (xy 344.321641 -369.877836) (xy 344.331798 -369.87734) (xy 345.048078 -369.87734)
			(xy 345.058248 -369.877782) (xy 345.077043 -369.88556) (xy 345.091429 -369.89994) (xy 345.099214 -369.918732)
			(xy 345.09964 -369.928902) (xy 345.09964 -370.214652) (xy 345.099845 -370.221524) (xy 345.103444 -370.234787)
			(xy 345.106752 -370.240814) (xy 345.123079 -370.269176) (xy 345.148825 -370.329341) (xy 345.166253 -370.39242)
			(xy 345.175047 -370.457269) (xy 345.175047 -370.489988) (xy 348.603832 -370.489988) (xy 348.607823 -370.427821)
			(xy 348.619732 -370.366674) (xy 348.639361 -370.307553) (xy 348.66639 -370.251427) (xy 348.700374 -370.199218)
			(xy 348.740756 -370.151783) (xy 348.786872 -370.109902) (xy 348.837964 -370.074262) (xy 348.893195 -370.045448)
			(xy 348.951657 -370.023934) (xy 349.012391 -370.010072) (xy 349.074398 -370.00409) (xy 349.136661 -370.006086)
			(xy 349.198158 -370.016029) (xy 349.257879 -370.033753) (xy 349.314842 -370.05897) (xy 349.368113 -370.091263)
			(xy 349.416818 -370.130103) (xy 349.460155 -370.174853) (xy 349.497415 -370.224777) (xy 349.527984 -370.279056)
			(xy 349.551362 -370.336799) (xy 349.567163 -370.397057) (xy 349.575129 -370.45884) (xy 349.575628 -370.489988)
			(xy 349.575129 -370.521136) (xy 349.567163 -370.582919) (xy 349.551362 -370.643177) (xy 349.527984 -370.70092)
			(xy 349.497415 -370.755199) (xy 349.460155 -370.805123) (xy 349.416818 -370.849873) (xy 349.368113 -370.888713)
			(xy 349.314842 -370.921006) (xy 349.257879 -370.946223) (xy 349.198158 -370.963947) (xy 349.136661 -370.97389)
			(xy 349.074398 -370.975886) (xy 349.012391 -370.969904) (xy 348.951657 -370.956042) (xy 348.893195 -370.934528)
			(xy 348.837964 -370.905714) (xy 348.786872 -370.870074) (xy 348.740756 -370.828193) (xy 348.700374 -370.780758)
			(xy 348.66639 -370.728549) (xy 348.639361 -370.672423) (xy 348.619732 -370.613302) (xy 348.607823 -370.552155)
			(xy 348.603832 -370.489988) (xy 345.175047 -370.489988) (xy 345.175048 -370.522711) (xy 345.166257 -370.58756)
			(xy 345.148832 -370.65064) (xy 345.123089 -370.710806) (xy 345.106752 -370.739162) (xy 345.103455 -370.745195)
			(xy 345.099837 -370.758452) (xy 345.09964 -370.765324) (xy 345.09964 -371.514878) (xy 345.099835 -371.521751)
			(xy 345.103441 -371.535014) (xy 345.106752 -371.54104) (xy 345.123102 -371.56939) (xy 345.145949 -371.62279)
			(xy 346.404945 -371.62279) (xy 346.404949 -371.557344) (xy 346.413748 -371.492493) (xy 346.43118 -371.429411)
			(xy 346.456931 -371.369244) (xy 346.473272 -371.340888) (xy 346.476589 -371.334864) (xy 346.480194 -371.3216)
			(xy 346.480384 -371.314726) (xy 346.480384 -371.028722) (xy 346.480783 -371.018546) (xy 346.488569 -370.999743)
			(xy 346.502963 -370.985356) (xy 346.52177 -370.977578) (xy 346.531946 -370.97716) (xy 347.248226 -370.97716)
			(xy 347.258388 -370.977612) (xy 347.277162 -370.9854) (xy 347.291527 -370.999778) (xy 347.299297 -371.018559)
			(xy 347.299788 -371.028722) (xy 347.299788 -371.314726) (xy 347.299971 -371.3216) (xy 347.303586 -371.334863)
			(xy 347.3069 -371.340888) (xy 347.323204 -371.369262) (xy 347.348949 -371.429425) (xy 347.366377 -371.492502)
			(xy 347.375174 -371.557348) (xy 347.375178 -371.622787) (xy 347.36639 -371.687634) (xy 347.34897 -371.750713)
			(xy 347.332073 -371.790214) (xy 348.603832 -371.790214) (xy 348.607823 -371.728047) (xy 348.619732 -371.6669)
			(xy 348.639361 -371.607779) (xy 348.66639 -371.551653) (xy 348.700374 -371.499444) (xy 348.740756 -371.452009)
			(xy 348.786872 -371.410128) (xy 348.837964 -371.374488) (xy 348.893195 -371.345674) (xy 348.951657 -371.32416)
			(xy 349.012391 -371.310298) (xy 349.074398 -371.304316) (xy 349.136661 -371.306312) (xy 349.198158 -371.316255)
			(xy 349.257879 -371.333979) (xy 349.314842 -371.359196) (xy 349.368113 -371.391489) (xy 349.416818 -371.430329)
			(xy 349.460155 -371.475079) (xy 349.497415 -371.525003) (xy 349.527984 -371.579282) (xy 349.532348 -371.590062)
			(xy 350.80398 -371.590062) (xy 350.807971 -371.527895) (xy 350.81988 -371.466748) (xy 350.839509 -371.407627)
			(xy 350.866538 -371.351501) (xy 350.900522 -371.299292) (xy 350.940904 -371.251857) (xy 350.98702 -371.209976)
			(xy 351.038112 -371.174336) (xy 351.093343 -371.145522) (xy 351.151805 -371.124008) (xy 351.212539 -371.110146)
			(xy 351.274546 -371.104164) (xy 351.336809 -371.10616) (xy 351.398306 -371.116103) (xy 351.458027 -371.133827)
			(xy 351.51499 -371.159044) (xy 351.568261 -371.191337) (xy 351.616966 -371.230177) (xy 351.660303 -371.274927)
			(xy 351.697563 -371.324851) (xy 351.728132 -371.37913) (xy 351.75151 -371.436873) (xy 351.767311 -371.497131)
			(xy 351.775277 -371.558914) (xy 351.775776 -371.590062) (xy 351.775277 -371.62121) (xy 351.767311 -371.682993)
			(xy 351.75151 -371.743251) (xy 351.728132 -371.800994) (xy 351.697563 -371.855273) (xy 351.660303 -371.905197)
			(xy 351.616966 -371.949947) (xy 351.568261 -371.988787) (xy 351.51499 -372.02108) (xy 351.458027 -372.046297)
			(xy 351.398306 -372.064021) (xy 351.336809 -372.073964) (xy 351.274546 -372.07596) (xy 351.212539 -372.069978)
			(xy 351.151805 -372.056116) (xy 351.093343 -372.034602) (xy 351.038112 -372.005788) (xy 350.98702 -371.970148)
			(xy 350.940904 -371.928267) (xy 350.900522 -371.880832) (xy 350.866538 -371.828623) (xy 350.839509 -371.772497)
			(xy 350.81988 -371.713376) (xy 350.807971 -371.652229) (xy 350.80398 -371.590062) (xy 349.532348 -371.590062)
			(xy 349.551362 -371.637025) (xy 349.567163 -371.697283) (xy 349.575129 -371.759066) (xy 349.575628 -371.790214)
			(xy 349.575129 -371.821362) (xy 349.567163 -371.883145) (xy 349.551362 -371.943403) (xy 349.527984 -372.001146)
			(xy 349.497415 -372.055425) (xy 349.460155 -372.105349) (xy 349.416818 -372.150099) (xy 349.368113 -372.188939)
			(xy 349.314842 -372.221232) (xy 349.257879 -372.246449) (xy 349.198158 -372.264173) (xy 349.136661 -372.274116)
			(xy 349.074398 -372.276112) (xy 349.012391 -372.27013) (xy 348.951657 -372.256268) (xy 348.893195 -372.234754)
			(xy 348.837964 -372.20594) (xy 348.786872 -372.1703) (xy 348.740756 -372.128419) (xy 348.700374 -372.080984)
			(xy 348.66639 -372.028775) (xy 348.639361 -371.972649) (xy 348.619732 -371.913528) (xy 348.607823 -371.852381)
			(xy 348.603832 -371.790214) (xy 347.332073 -371.790214) (xy 347.323234 -371.810879) (xy 347.3069 -371.839236)
			(xy 347.303572 -371.845254) (xy 347.299975 -371.858523) (xy 347.299788 -371.865398) (xy 347.299788 -372.614698)
			(xy 347.299982 -372.621571) (xy 347.303589 -372.634834) (xy 347.3069 -372.64086) (xy 347.323265 -372.669201)
			(xy 347.349004 -372.729371) (xy 347.366426 -372.792455) (xy 347.375215 -372.857307) (xy 347.375213 -372.890034)
			(xy 350.80398 -372.890034) (xy 350.807971 -372.827867) (xy 350.81988 -372.76672) (xy 350.839509 -372.707599)
			(xy 350.866538 -372.651473) (xy 350.900522 -372.599264) (xy 350.940904 -372.551829) (xy 350.98702 -372.509948)
			(xy 351.038112 -372.474308) (xy 351.093343 -372.445494) (xy 351.151805 -372.42398) (xy 351.212539 -372.410118)
			(xy 351.274546 -372.404136) (xy 351.336809 -372.406132) (xy 351.398306 -372.416075) (xy 351.458027 -372.433799)
			(xy 351.51499 -372.459016) (xy 351.568261 -372.491309) (xy 351.616966 -372.530149) (xy 351.660303 -372.574899)
			(xy 351.697563 -372.624823) (xy 351.728132 -372.679102) (xy 351.75151 -372.736845) (xy 351.767311 -372.797103)
			(xy 351.775277 -372.858886) (xy 351.775776 -372.890034) (xy 351.775277 -372.921182) (xy 351.767311 -372.982965)
			(xy 351.75151 -373.043223) (xy 351.728132 -373.100966) (xy 351.697563 -373.155245) (xy 351.660303 -373.205169)
			(xy 351.616966 -373.249919) (xy 351.568261 -373.288759) (xy 351.51499 -373.321052) (xy 351.458027 -373.346269)
			(xy 351.398306 -373.363993) (xy 351.336809 -373.373936) (xy 351.274546 -373.375932) (xy 351.212539 -373.36995)
			(xy 351.151805 -373.356088) (xy 351.093343 -373.334574) (xy 351.038112 -373.30576) (xy 350.98702 -373.27012)
			(xy 350.940904 -373.228239) (xy 350.900522 -373.180804) (xy 350.866538 -373.128595) (xy 350.839509 -373.072469)
			(xy 350.81988 -373.013348) (xy 350.807971 -372.952201) (xy 350.80398 -372.890034) (xy 347.375213 -372.890034)
			(xy 347.375211 -372.922752) (xy 347.366414 -372.987603) (xy 347.348985 -373.050684) (xy 347.323238 -373.110851)
			(xy 347.3069 -373.139208) (xy 347.303582 -373.145231) (xy 347.299979 -373.158496) (xy 347.299788 -373.16537)
			(xy 347.299788 -373.451374) (xy 347.299246 -373.461527) (xy 347.291485 -373.480291) (xy 347.277134 -373.494656)
			(xy 347.258378 -373.502436) (xy 347.248226 -373.502936) (xy 346.531946 -373.502936) (xy 346.521774 -373.502498)
			(xy 346.502975 -373.494723) (xy 346.488588 -373.480341) (xy 346.480806 -373.461546) (xy 346.480384 -373.451374)
			(xy 346.480384 -373.16537) (xy 346.480206 -373.158496) (xy 346.476588 -373.145233) (xy 346.473272 -373.139208)
			(xy 346.456962 -373.110836) (xy 346.431214 -373.050674) (xy 346.413783 -372.987597) (xy 346.404986 -372.92275)
			(xy 346.404982 -372.857309) (xy 346.413772 -372.792461) (xy 346.431195 -372.729382) (xy 346.456936 -372.669216)
			(xy 346.473272 -372.64086) (xy 346.476599 -372.634841) (xy 346.480197 -372.621573) (xy 346.480384 -372.614698)
			(xy 346.480384 -371.865398) (xy 346.480195 -371.858525) (xy 346.476585 -371.845262) (xy 346.473272 -371.839236)
			(xy 346.456901 -371.810898) (xy 346.431159 -371.750727) (xy 346.413735 -371.687644) (xy 346.404945 -371.62279)
			(xy 345.145949 -371.62279) (xy 345.148845 -371.629558) (xy 345.16627 -371.692639) (xy 345.175062 -371.75749)
			(xy 345.17506 -371.822934) (xy 345.166265 -371.887784) (xy 345.148837 -371.950865) (xy 345.123091 -372.011032)
			(xy 345.106752 -372.039388) (xy 345.103446 -372.045417) (xy 345.099834 -372.058677) (xy 345.09964 -372.06555)
			(xy 345.09964 -372.351554) (xy 345.099198 -372.361725) (xy 345.091424 -372.380523) (xy 345.077043 -372.394911)
			(xy 345.058249 -372.402693) (xy 345.048078 -372.403116) (xy 344.331798 -372.403116) (xy 344.321621 -372.402737)
			(xy 344.302817 -372.394942) (xy 344.288431 -372.380543) (xy 344.280654 -372.361732) (xy 344.280236 -372.351554)
			(xy 344.280236 -372.06555) (xy 344.280021 -372.058679) (xy 344.276428 -372.045416) (xy 344.273124 -372.039388)
			(xy 344.256799 -372.011025) (xy 344.231055 -371.95086) (xy 344.213628 -371.887781) (xy 344.204833 -371.822933)
			(xy 344.204832 -371.757491) (xy 344.213623 -371.692642) (xy 344.231047 -371.629563) (xy 344.256788 -371.569396)
			(xy 344.273124 -371.54104) (xy 344.276426 -371.535009) (xy 344.280039 -371.52175) (xy 344.280236 -371.514878)
			(xy 344.280236 -370.765324) (xy 344.28003 -370.758452) (xy 344.276431 -370.745189) (xy 344.273124 -370.739162)
			(xy 344.256777 -370.710811) (xy 344.231035 -370.650643) (xy 344.21361 -370.587562) (xy 344.204819 -370.522712)
			(xy 340.775259 -370.522712) (xy 340.766467 -370.58756) (xy 340.749043 -370.650639) (xy 340.7233 -370.710806)
			(xy 340.706964 -370.739162) (xy 340.703668 -370.745196) (xy 340.70005 -370.758452) (xy 340.699852 -370.765324)
			(xy 340.699852 -371.514878) (xy 340.700046 -371.521751) (xy 340.703652 -371.535014) (xy 340.706964 -371.54104)
			(xy 340.723313 -371.56939) (xy 340.74616 -371.62279) (xy 342.004909 -371.62279) (xy 342.004913 -371.557345)
			(xy 342.013711 -371.492493) (xy 342.031142 -371.429412) (xy 342.05689 -371.369244) (xy 342.07323 -371.340888)
			(xy 342.076597 -371.334874) (xy 342.080331 -371.321613) (xy 342.080596 -371.314726) (xy 342.080596 -371.028722)
			(xy 342.081143 -371.018602) (xy 342.088856 -370.99989) (xy 342.103123 -370.985534) (xy 342.121787 -370.977706)
			(xy 342.131904 -370.97716) (xy 342.848184 -370.97716) (xy 342.858332 -370.977634) (xy 342.877076 -370.985417)
			(xy 342.891399 -370.999797) (xy 342.899106 -371.018572) (xy 342.899492 -371.028722) (xy 342.899492 -371.314726)
			(xy 342.899755 -371.321615) (xy 342.903477 -371.334881) (xy 342.906858 -371.340888) (xy 342.923163 -371.369262)
			(xy 342.94891 -371.429424) (xy 342.96634 -371.492501) (xy 342.975137 -371.557347) (xy 342.975142 -371.622788)
			(xy 342.966354 -371.687635) (xy 342.948932 -371.750714) (xy 342.923193 -371.81088) (xy 342.906858 -371.839236)
			(xy 342.903482 -371.845245) (xy 342.899754 -371.85851) (xy 342.899492 -371.865398) (xy 342.899492 -372.614698)
			(xy 342.899727 -372.621589) (xy 342.903468 -372.634855) (xy 342.906858 -372.64086) (xy 342.923224 -372.6692)
			(xy 342.948966 -372.729371) (xy 342.966389 -372.792454) (xy 342.975178 -372.857306) (xy 342.975175 -372.922752)
			(xy 342.966377 -372.987603) (xy 342.948946 -373.050685) (xy 342.923198 -373.110852) (xy 342.906858 -373.139208)
			(xy 342.903492 -373.145222) (xy 342.899758 -373.158483) (xy 342.899492 -373.16537) (xy 342.899492 -373.451374)
			(xy 342.898953 -373.461495) (xy 342.89124 -373.48021) (xy 342.87697 -373.494566) (xy 342.858302 -373.502392)
			(xy 342.848184 -373.502936) (xy 342.131904 -373.502936) (xy 342.121755 -373.502476) (xy 342.103009 -373.494688)
			(xy 342.088687 -373.480304) (xy 342.080981 -373.461525) (xy 342.080596 -373.451374) (xy 342.080596 -373.16537)
			(xy 342.080336 -373.158481) (xy 342.076612 -373.145215) (xy 342.07323 -373.139208) (xy 342.056922 -373.110836)
			(xy 342.031176 -373.050673) (xy 342.013746 -372.987596) (xy 342.00495 -372.922749) (xy 342.004946 -372.857309)
			(xy 342.013735 -372.792461) (xy 342.031156 -372.729382) (xy 342.056895 -372.669216) (xy 342.07323 -372.64086)
			(xy 342.076606 -372.634851) (xy 342.080334 -372.621586) (xy 342.080596 -372.614698) (xy 342.080596 -371.865398)
			(xy 342.080364 -371.858507) (xy 342.076621 -371.845241) (xy 342.07323 -371.839236) (xy 342.056861 -371.810898)
			(xy 342.03112 -371.750727) (xy 342.013698 -371.687643) (xy 342.004909 -371.62279) (xy 340.74616 -371.62279)
			(xy 340.749056 -371.629558) (xy 340.766481 -371.692639) (xy 340.775272 -371.75749) (xy 340.775271 -371.822934)
			(xy 340.766476 -371.887784) (xy 340.749048 -371.950865) (xy 340.723302 -372.011032) (xy 340.706964 -372.039388)
			(xy 340.703659 -372.045417) (xy 340.700046 -372.058677) (xy 340.699852 -372.06555) (xy 340.699852 -372.351554)
			(xy 340.699398 -372.361724) (xy 340.691627 -372.380519) (xy 340.67725 -372.394906) (xy 340.65846 -372.402691)
			(xy 340.64829 -372.403116) (xy 339.93201 -372.403116) (xy 339.921833 -372.402727) (xy 339.90303 -372.394937)
			(xy 339.888643 -372.38054) (xy 339.880866 -372.361731) (xy 339.880448 -372.351554) (xy 339.880448 -372.06555)
			(xy 339.880244 -372.058678) (xy 339.876645 -372.045415) (xy 339.873336 -372.039388) (xy 339.857011 -372.011025)
			(xy 339.831266 -371.95086) (xy 339.813838 -371.887781) (xy 339.805044 -371.822933) (xy 339.805042 -371.757491)
			(xy 339.813833 -371.692642) (xy 339.831258 -371.629563) (xy 339.857 -371.569396) (xy 339.873336 -371.54104)
			(xy 339.876632 -371.535006) (xy 339.88025 -371.52175) (xy 339.880448 -371.514878) (xy 339.880448 -370.765324)
			(xy 339.880253 -370.758451) (xy 339.876648 -370.745188) (xy 339.873336 -370.739162) (xy 339.856989 -370.710811)
			(xy 339.831246 -370.650643) (xy 339.813821 -370.587562) (xy 339.805029 -370.522712) (xy 336.375223 -370.522712)
			(xy 336.36643 -370.58756) (xy 336.349004 -370.65064) (xy 336.32326 -370.710806) (xy 336.306922 -370.739162)
			(xy 336.303534 -370.745165) (xy 336.299814 -370.758435) (xy 336.299556 -370.765324) (xy 336.299556 -371.514878)
			(xy 336.299768 -371.521772) (xy 336.303511 -371.535044) (xy 336.306922 -371.54104) (xy 336.323272 -371.569389)
			(xy 336.346122 -371.622791) (xy 337.604859 -371.622791) (xy 337.604863 -371.557344) (xy 337.613662 -371.492492)
			(xy 337.631095 -371.429411) (xy 337.656847 -371.369244) (xy 337.673188 -371.340888) (xy 337.676506 -371.334865)
			(xy 337.68011 -371.3216) (xy 337.6803 -371.314726) (xy 337.6803 -371.028722) (xy 337.68085 -371.01857)
			(xy 337.68861 -370.999809) (xy 337.702958 -370.985444) (xy 337.721711 -370.977662) (xy 337.731862 -370.97716)
			(xy 338.448142 -370.97716) (xy 338.458305 -370.9776) (xy 338.477079 -370.985392) (xy 338.491444 -370.999774)
			(xy 338.499213 -371.018558) (xy 338.499704 -371.028722) (xy 338.499704 -371.314726) (xy 338.499885 -371.3216)
			(xy 338.503501 -371.334863) (xy 338.506816 -371.340888) (xy 338.523123 -371.369261) (xy 338.548872 -371.429424)
			(xy 338.566303 -371.4925) (xy 338.575101 -371.557347) (xy 338.575106 -371.622788) (xy 338.566317 -371.687636)
			(xy 338.548893 -371.750715) (xy 338.523152 -371.81088) (xy 338.506816 -371.839236) (xy 338.50349 -371.845255)
			(xy 338.499891 -371.858523) (xy 338.499704 -371.865398) (xy 338.499704 -372.614698) (xy 338.499896 -372.621571)
			(xy 338.503504 -372.634834) (xy 338.506816 -372.64086) (xy 338.523184 -372.6692) (xy 338.548927 -372.72937)
			(xy 338.566352 -372.792453) (xy 338.575142 -372.857306) (xy 338.575138 -372.922752) (xy 338.56634 -372.987604)
			(xy 338.548908 -373.050685) (xy 338.523157 -373.110852) (xy 338.506816 -373.139208) (xy 338.5035 -373.145232)
			(xy 338.499895 -373.158496) (xy 338.499704 -373.16537) (xy 338.499704 -373.451374) (xy 338.499147 -373.461525)
			(xy 338.491388 -373.480286) (xy 338.477043 -373.49465) (xy 338.458292 -373.502433) (xy 338.448142 -373.502936)
			(xy 337.731862 -373.502936) (xy 337.721699 -373.502497) (xy 337.702924 -373.494705) (xy 337.688559 -373.480323)
			(xy 337.68079 -373.461538) (xy 337.6803 -373.451374) (xy 337.6803 -373.16537) (xy 337.68012 -373.158496)
			(xy 337.676504 -373.145233) (xy 337.673188 -373.139208) (xy 337.656878 -373.110836) (xy 337.631129 -373.050674)
			(xy 337.613697 -372.987597) (xy 337.6049 -372.92275) (xy 337.604896 -372.857309) (xy 337.613686 -372.79246)
			(xy 337.631109 -372.729381) (xy 337.656851 -372.669216) (xy 337.673188 -372.64086) (xy 337.676516 -372.634842)
			(xy 337.680114 -372.621573) (xy 337.6803 -372.614698) (xy 337.6803 -371.865398) (xy 337.680109 -371.858525)
			(xy 337.6765 -371.845262) (xy 337.673188 -371.839236) (xy 337.656817 -371.810898) (xy 337.631073 -371.750728)
			(xy 337.613649 -371.687644) (xy 337.604859 -371.622791) (xy 336.346122 -371.622791) (xy 336.349017 -371.629557)
			(xy 336.366444 -371.692639) (xy 336.375236 -371.75749) (xy 336.375234 -371.822934) (xy 336.366439 -371.887785)
			(xy 336.349009 -371.950866) (xy 336.323262 -372.011032) (xy 336.306922 -372.039388) (xy 336.30356 -372.045404)
			(xy 336.299823 -372.058664) (xy 336.299556 -372.06555) (xy 336.299556 -372.351554) (xy 336.299036 -372.361678)
			(xy 336.291322 -372.380399) (xy 336.277046 -372.394757) (xy 336.258369 -372.402577) (xy 336.248248 -372.403116)
			(xy 335.531968 -372.403116) (xy 335.521814 -372.402705) (xy 335.503064 -372.394902) (xy 335.488742 -372.380502)
			(xy 335.481041 -372.36171) (xy 335.48066 -372.351554) (xy 335.48066 -372.06555) (xy 335.480435 -372.058657)
			(xy 335.476701 -372.045385) (xy 335.473294 -372.039388) (xy 335.45697 -372.011025) (xy 335.431227 -371.950859)
			(xy 335.413801 -371.887781) (xy 335.405008 -371.822933) (xy 335.405006 -371.757491) (xy 335.413796 -371.692643)
			(xy 335.431219 -371.629563) (xy 335.456959 -371.569397) (xy 335.473294 -371.54104) (xy 335.476675 -371.535033)
			(xy 335.480401 -371.521767) (xy 335.48066 -371.514878) (xy 335.48066 -370.765324) (xy 335.480445 -370.75843)
			(xy 335.476704 -370.745158) (xy 335.473294 -370.739162) (xy 335.456948 -370.710811) (xy 335.431207 -370.650643)
			(xy 335.413784 -370.587561) (xy 335.404993 -370.522711) (xy 331.975173 -370.522711) (xy 331.966381 -370.587559)
			(xy 331.948957 -370.650639) (xy 331.923216 -370.710806) (xy 331.90688 -370.739162) (xy 331.903577 -370.745193)
			(xy 331.899964 -370.758452) (xy 331.899768 -370.765324) (xy 331.899768 -371.514878) (xy 331.899972 -371.52175)
			(xy 331.903573 -371.535013) (xy 331.90688 -371.54104) (xy 331.923229 -371.56939) (xy 331.946075 -371.62279)
			(xy 333.204823 -371.62279) (xy 333.204827 -371.557345) (xy 333.213625 -371.492493) (xy 333.231057 -371.429411)
			(xy 333.256806 -371.369244) (xy 333.273146 -371.340888) (xy 333.276514 -371.334875) (xy 333.280247 -371.321613)
			(xy 333.280512 -371.314726) (xy 333.280512 -371.028722) (xy 333.281044 -371.0186) (xy 333.288759 -370.999885)
			(xy 333.303031 -370.985529) (xy 333.321701 -370.977704) (xy 333.33182 -370.97716) (xy 334.0481 -370.97716)
			(xy 334.058249 -370.977621) (xy 334.076994 -370.985409) (xy 334.091316 -370.999793) (xy 334.099023 -371.018571)
			(xy 334.099408 -371.028722) (xy 334.099408 -371.314726) (xy 334.099669 -371.321615) (xy 334.103392 -371.334881)
			(xy 334.106774 -371.340888) (xy 334.123079 -371.369262) (xy 334.148825 -371.429425) (xy 334.166254 -371.492501)
			(xy 334.175051 -371.557347) (xy 334.175056 -371.622788) (xy 334.166268 -371.687635) (xy 334.148847 -371.750714)
			(xy 334.123108 -371.81088) (xy 334.106774 -371.839236) (xy 334.103399 -371.845246) (xy 334.09967 -371.85851)
			(xy 334.099408 -371.865398) (xy 334.099408 -372.614698) (xy 334.099641 -372.621589) (xy 334.103383 -372.634855)
			(xy 334.106774 -372.64086) (xy 334.12314 -372.6692) (xy 334.14888 -372.729371) (xy 334.166303 -372.792454)
			(xy 334.175092 -372.857307) (xy 334.175088 -372.922752) (xy 334.166291 -372.987603) (xy 334.148861 -373.050684)
			(xy 334.123113 -373.110852) (xy 334.106774 -373.139208) (xy 334.103409 -373.145223) (xy 334.099674 -373.158483)
			(xy 334.099408 -373.16537) (xy 334.099408 -373.451374) (xy 334.098854 -373.461493) (xy 334.091143 -373.480205)
			(xy 334.076878 -373.49456) (xy 334.058216 -373.502389) (xy 334.0481 -373.502936) (xy 333.33182 -373.502936)
			(xy 333.321672 -373.502463) (xy 333.302927 -373.494681) (xy 333.288604 -373.4803) (xy 333.280897 -373.461524)
			(xy 333.280512 -373.451374) (xy 333.280512 -373.16537) (xy 333.280285 -373.158477) (xy 333.276553 -373.145205)
			(xy 333.273146 -373.139208) (xy 333.256837 -373.110836) (xy 333.23109 -373.050673) (xy 333.21366 -372.987596)
			(xy 333.204864 -372.922749) (xy 333.20486 -372.857309) (xy 333.213649 -372.792461) (xy 333.231071 -372.729382)
			(xy 333.256811 -372.669216) (xy 333.273146 -372.64086) (xy 333.276524 -372.634852) (xy 333.280251 -372.621586)
			(xy 333.280512 -372.614698) (xy 333.280512 -371.865398) (xy 333.280313 -371.858502) (xy 333.276562 -371.84523)
			(xy 333.273146 -371.839236) (xy 333.256776 -371.810898) (xy 333.231035 -371.750727) (xy 333.213612 -371.687643)
			(xy 333.204823 -371.62279) (xy 331.946075 -371.62279) (xy 331.94897 -371.629558) (xy 331.966395 -371.69264)
			(xy 331.975186 -371.75749) (xy 331.975184 -371.822934) (xy 331.96639 -371.887784) (xy 331.948962 -371.950864)
			(xy 331.923218 -372.011032) (xy 331.90688 -372.039388) (xy 331.903568 -372.045414) (xy 331.899961 -372.058677)
			(xy 331.899768 -372.06555) (xy 331.899768 -372.351554) (xy 331.899299 -372.361722) (xy 331.89153 -372.380514)
			(xy 331.877158 -372.394901) (xy 331.858373 -372.402688) (xy 331.848206 -372.403116) (xy 331.131926 -372.403116)
			(xy 331.12175 -372.402714) (xy 331.102948 -372.394929) (xy 331.08856 -372.380536) (xy 331.080783 -372.36173)
			(xy 331.080364 -372.351554) (xy 331.080364 -372.06555) (xy 331.080157 -372.058678) (xy 331.07656 -372.045415)
			(xy 331.073252 -372.039388) (xy 331.056926 -372.011025) (xy 331.03118 -371.95086) (xy 331.013752 -371.887782)
			(xy 331.004958 -371.822933) (xy 331.004956 -371.757491) (xy 331.013747 -371.692642) (xy 331.031172 -371.629562)
			(xy 331.056915 -371.569396) (xy 331.073252 -371.54104) (xy 331.076549 -371.535006) (xy 331.080166 -371.52175)
			(xy 331.080364 -371.514878) (xy 331.080364 -370.765324) (xy 331.080167 -370.758451) (xy 331.076563 -370.745188)
			(xy 331.073252 -370.739162) (xy 331.056904 -370.710812) (xy 331.03116 -370.650644) (xy 331.013735 -370.587562)
			(xy 331.004943 -370.522712) (xy 308.975506 -370.522712) (xy 308.975506 -374.422887) (xy 331.004926 -374.422887)
			(xy 331.00493 -374.357441) (xy 331.013729 -374.292589) (xy 331.031161 -374.229507) (xy 331.056911 -374.16934)
			(xy 331.073252 -374.140984) (xy 331.076569 -374.13496) (xy 331.080174 -374.121696) (xy 331.080364 -374.114822)
			(xy 331.080364 -373.828818) (xy 331.080779 -373.818644) (xy 331.088563 -373.799845) (xy 331.102952 -373.785458)
			(xy 331.121752 -373.777677) (xy 331.131926 -373.777256) (xy 331.848206 -373.777256) (xy 331.85838 -373.777659)
			(xy 331.877178 -373.78545) (xy 331.891564 -373.799842) (xy 331.899345 -373.818644) (xy 331.899768 -373.828818)
			(xy 331.899768 -374.114822) (xy 331.899956 -374.121695) (xy 331.903567 -374.134958) (xy 331.90688 -374.140984)
			(xy 331.923181 -374.16936) (xy 331.948927 -374.229522) (xy 331.966357 -374.292598) (xy 331.975154 -374.357444)
			(xy 331.975159 -374.422884) (xy 331.975159 -374.422887) (xy 335.404976 -374.422887) (xy 335.404981 -374.357441)
			(xy 335.413778 -374.29259) (xy 335.431208 -374.229509) (xy 335.456955 -374.169341) (xy 335.473294 -374.140984)
			(xy 335.476659 -374.134969) (xy 335.480395 -374.121709) (xy 335.48066 -374.114822) (xy 335.48066 -373.828818)
			(xy 335.481142 -373.81869) (xy 335.488867 -373.799965) (xy 335.503156 -373.785608) (xy 335.521842 -373.777791)
			(xy 335.531968 -373.777256) (xy 336.248248 -373.777256) (xy 336.2584 -373.777682) (xy 336.277145 -373.785485)
			(xy 336.291465 -373.799879) (xy 336.299171 -373.818664) (xy 336.299556 -373.828818) (xy 336.299556 -374.114822)
			(xy 336.29979 -374.121715) (xy 336.303517 -374.134987) (xy 336.306922 -374.140984) (xy 336.323225 -374.169359)
			(xy 336.348974 -374.229521) (xy 336.366406 -374.292597) (xy 336.375204 -374.357444) (xy 336.375209 -374.422884)
			(xy 336.375209 -374.422887) (xy 339.805012 -374.422887) (xy 339.805017 -374.357441) (xy 339.813815 -374.292589)
			(xy 339.831247 -374.229508) (xy 339.856996 -374.16934) (xy 339.873336 -374.140984) (xy 339.876651 -374.13496)
			(xy 339.880257 -374.121696) (xy 339.880448 -374.114822) (xy 339.880448 -373.828818) (xy 339.880879 -373.818646)
			(xy 339.88866 -373.79985) (xy 339.903043 -373.785464) (xy 339.921838 -373.77768) (xy 339.93201 -373.777256)
			(xy 340.64829 -373.777256) (xy 340.658463 -373.777672) (xy 340.677261 -373.785457) (xy 340.691647 -373.799846)
			(xy 340.699429 -373.818645) (xy 340.699852 -373.828818) (xy 340.699852 -374.114822) (xy 340.700029 -374.121696)
			(xy 340.703647 -374.134959) (xy 340.706964 -374.140984) (xy 340.723266 -374.16936) (xy 340.749013 -374.229522)
			(xy 340.766443 -374.292598) (xy 340.77524 -374.357444) (xy 340.775245 -374.422884) (xy 340.775245 -374.422887)
			(xy 344.204802 -374.422887) (xy 344.204806 -374.357441) (xy 344.213604 -374.29259) (xy 344.231036 -374.229508)
			(xy 344.256784 -374.16934) (xy 344.273124 -374.140984) (xy 344.276446 -374.134963) (xy 344.280047 -374.121696)
			(xy 344.280236 -374.114822) (xy 344.280236 -373.828818) (xy 344.280678 -373.818648) (xy 344.288457 -373.799854)
			(xy 344.302837 -373.785468) (xy 344.321628 -373.777682) (xy 344.331798 -373.777256) (xy 345.048078 -373.777256)
			(xy 345.05825 -373.777683) (xy 345.077048 -373.785464) (xy 345.091434 -373.799849) (xy 345.099217 -373.818646)
			(xy 345.09964 -373.828818) (xy 345.09964 -374.114822) (xy 345.099819 -374.121696) (xy 345.103436 -374.134959)
			(xy 345.106752 -374.140984) (xy 345.123054 -374.16936) (xy 345.148802 -374.229522) (xy 345.166232 -374.292598)
			(xy 345.17503 -374.357444) (xy 345.175032 -374.390158) (xy 348.603832 -374.390158) (xy 348.607823 -374.327991)
			(xy 348.619732 -374.266844) (xy 348.639361 -374.207723) (xy 348.66639 -374.151597) (xy 348.700374 -374.099388)
			(xy 348.740756 -374.051953) (xy 348.786872 -374.010072) (xy 348.837964 -373.974432) (xy 348.893195 -373.945618)
			(xy 348.951657 -373.924104) (xy 349.012391 -373.910242) (xy 349.074398 -373.90426) (xy 349.136661 -373.906256)
			(xy 349.198158 -373.916199) (xy 349.257879 -373.933923) (xy 349.314842 -373.95914) (xy 349.368113 -373.991433)
			(xy 349.416818 -374.030273) (xy 349.460155 -374.075023) (xy 349.497415 -374.124947) (xy 349.527984 -374.179226)
			(xy 349.551362 -374.236969) (xy 349.567163 -374.297227) (xy 349.575129 -374.35901) (xy 349.575628 -374.390158)
			(xy 349.575129 -374.421306) (xy 349.567163 -374.483089) (xy 349.551362 -374.543347) (xy 349.527984 -374.60109)
			(xy 349.497415 -374.655369) (xy 349.460155 -374.705293) (xy 349.416818 -374.750043) (xy 349.368113 -374.788883)
			(xy 349.314842 -374.821176) (xy 349.257879 -374.846393) (xy 349.198158 -374.864117) (xy 349.136661 -374.87406)
			(xy 349.074398 -374.876056) (xy 349.012391 -374.870074) (xy 348.951657 -374.856212) (xy 348.893195 -374.834698)
			(xy 348.837964 -374.805884) (xy 348.786872 -374.770244) (xy 348.740756 -374.728363) (xy 348.700374 -374.680928)
			(xy 348.66639 -374.628719) (xy 348.639361 -374.572593) (xy 348.619732 -374.513472) (xy 348.607823 -374.452325)
			(xy 348.603832 -374.390158) (xy 345.175032 -374.390158) (xy 345.175035 -374.422884) (xy 345.166247 -374.487731)
			(xy 345.148826 -374.55081) (xy 345.123087 -374.610976) (xy 345.106752 -374.639332) (xy 345.10343 -374.645353)
			(xy 345.099828 -374.65862) (xy 345.09964 -374.665494) (xy 345.09964 -375.414794) (xy 345.099829 -375.421667)
			(xy 345.103439 -375.43493) (xy 345.106752 -375.440956) (xy 345.123115 -375.469298) (xy 345.148857 -375.529468)
			(xy 345.166281 -375.592551) (xy 345.175071 -375.657403) (xy 345.175068 -375.722848) (xy 345.166271 -375.7877)
			(xy 345.14884 -375.850781) (xy 345.123092 -375.910948) (xy 345.106752 -375.939304) (xy 345.10344 -375.94533)
			(xy 345.099832 -375.958593) (xy 345.09964 -375.965466) (xy 345.09964 -376.25147) (xy 345.099211 -376.261642)
			(xy 345.091432 -376.280441) (xy 345.077047 -376.294827) (xy 345.05825 -376.302609) (xy 345.048078 -376.303032)
			(xy 344.331798 -376.303032) (xy 344.321623 -376.302637) (xy 344.302822 -376.294846) (xy 344.288436 -376.280451)
			(xy 344.280657 -376.261646) (xy 344.280236 -376.25147) (xy 344.280236 -375.965466) (xy 344.280052 -375.958592)
			(xy 344.276438 -375.94533) (xy 344.273124 -375.939304) (xy 344.256813 -375.910934) (xy 344.231067 -375.85077)
			(xy 344.213638 -375.787693) (xy 344.204843 -375.722846) (xy 344.204839 -375.657405) (xy 344.213628 -375.592558)
			(xy 344.23105 -375.529479) (xy 344.256789 -375.469312) (xy 344.273124 -375.440956) (xy 344.276456 -375.43494)
			(xy 344.28005 -375.42167) (xy 344.280236 -375.414794) (xy 344.280236 -374.665494) (xy 344.280042 -374.658621)
			(xy 344.276435 -374.645358) (xy 344.273124 -374.639332) (xy 344.256751 -374.610995) (xy 344.231012 -374.550824)
			(xy 344.21359 -374.48774) (xy 344.204802 -374.422887) (xy 340.775245 -374.422887) (xy 340.766457 -374.487731)
			(xy 340.749037 -374.55081) (xy 340.723298 -374.610976) (xy 340.706964 -374.639332) (xy 340.703643 -374.645354)
			(xy 340.70004 -374.65862) (xy 340.699852 -374.665494) (xy 340.699852 -375.414794) (xy 340.70004 -375.421668)
			(xy 340.70365 -375.434931) (xy 340.706964 -375.440956) (xy 340.723327 -375.469298) (xy 340.749068 -375.529468)
			(xy 340.766492 -375.592551) (xy 340.775281 -375.657403) (xy 340.775278 -375.722848) (xy 340.766481 -375.787699)
			(xy 340.749051 -375.85078) (xy 340.723303 -375.910948) (xy 340.706964 -375.939304) (xy 340.703653 -375.94533)
			(xy 340.700044 -375.958593) (xy 340.699852 -375.965466) (xy 340.699852 -376.25147) (xy 340.699411 -376.261641)
			(xy 340.691634 -376.280437) (xy 340.677254 -376.294823) (xy 340.658461 -376.302607) (xy 340.64829 -376.303032)
			(xy 339.93201 -376.303032) (xy 339.921835 -376.302627) (xy 339.903035 -376.29484) (xy 339.888649 -376.280448)
			(xy 339.880869 -376.261645) (xy 339.880448 -376.25147) (xy 339.880448 -375.965466) (xy 339.880275 -375.958591)
			(xy 339.876655 -375.945328) (xy 339.873336 -375.939304) (xy 339.857024 -375.910934) (xy 339.831278 -375.85077)
			(xy 339.813849 -375.787693) (xy 339.805053 -375.722846) (xy 339.805049 -375.657405) (xy 339.813839 -375.592557)
			(xy 339.831261 -375.529478) (xy 339.857001 -375.469312) (xy 339.873336 -375.440956) (xy 339.876661 -375.434936)
			(xy 339.880261 -375.421669) (xy 339.880448 -375.414794) (xy 339.880448 -374.665494) (xy 339.880265 -374.65862)
			(xy 339.876651 -374.645357) (xy 339.873336 -374.639332) (xy 339.856963 -374.610995) (xy 339.831223 -374.550824)
			(xy 339.8138 -374.48774) (xy 339.805012 -374.422887) (xy 336.375209 -374.422887) (xy 336.366421 -374.487732)
			(xy 336.348998 -374.550811) (xy 336.323258 -374.610976) (xy 336.306922 -374.639332) (xy 336.303544 -374.64534)
			(xy 336.299818 -374.658606) (xy 336.299556 -374.665494) (xy 336.299556 -375.414794) (xy 336.299762 -375.421689)
			(xy 336.303509 -375.434961) (xy 336.306922 -375.440956) (xy 336.323286 -375.469298) (xy 336.34903 -375.529467)
			(xy 336.366455 -375.59255) (xy 336.375245 -375.657403) (xy 336.375242 -375.722848) (xy 336.366444 -375.7877)
			(xy 336.349013 -375.850781) (xy 336.323263 -375.910948) (xy 336.306922 -375.939304) (xy 336.303554 -375.945317)
			(xy 336.299821 -375.958579) (xy 336.299556 -375.965466) (xy 336.299556 -376.25147) (xy 336.299049 -376.261595)
			(xy 336.29133 -376.280317) (xy 336.27705 -376.294674) (xy 336.258371 -376.302494) (xy 336.248248 -376.303032)
			(xy 335.531968 -376.303032) (xy 335.521816 -376.302605) (xy 335.503069 -376.294805) (xy 335.488748 -376.280411)
			(xy 335.481043 -376.261624) (xy 335.48066 -376.25147) (xy 335.48066 -375.965466) (xy 335.480429 -375.958573)
			(xy 335.476699 -375.945301) (xy 335.473294 -375.939304) (xy 335.456983 -375.910933) (xy 335.43124 -375.850769)
			(xy 335.413812 -375.787692) (xy 335.405017 -375.722846) (xy 335.405013 -375.657406) (xy 335.413802 -375.592558)
			(xy 335.431223 -375.529479) (xy 335.45696 -375.469313) (xy 335.473294 -375.440956) (xy 335.476669 -375.434946)
			(xy 335.480399 -375.421682) (xy 335.48066 -375.414794) (xy 335.48066 -374.665494) (xy 335.480434 -374.658602)
			(xy 335.476687 -374.645336) (xy 335.473294 -374.639332) (xy 335.456922 -374.610995) (xy 335.431184 -374.550823)
			(xy 335.413763 -374.487739) (xy 335.404976 -374.422887) (xy 331.975159 -374.422887) (xy 331.966372 -374.487731)
			(xy 331.948951 -374.55081) (xy 331.923214 -374.610976) (xy 331.90688 -374.639332) (xy 331.903552 -374.64535)
			(xy 331.899955 -374.658619) (xy 331.899768 -374.665494) (xy 331.899768 -375.414794) (xy 331.899966 -375.421667)
			(xy 331.903571 -375.434929) (xy 331.90688 -375.440956) (xy 331.923242 -375.469298) (xy 331.948983 -375.529468)
			(xy 331.966406 -375.592551) (xy 331.975195 -375.657403) (xy 331.975192 -375.722848) (xy 331.966395 -375.787699)
			(xy 331.948966 -375.85078) (xy 331.923219 -375.910948) (xy 331.90688 -375.939304) (xy 331.903562 -375.945327)
			(xy 331.899959 -375.958592) (xy 331.899768 -375.965466) (xy 331.899768 -376.25147) (xy 331.899312 -376.261639)
			(xy 331.891538 -376.280432) (xy 331.877162 -376.294817) (xy 331.858375 -376.302604) (xy 331.848206 -376.303032)
			(xy 331.131926 -376.303032) (xy 331.121752 -376.302614) (xy 331.102953 -376.294832) (xy 331.088566 -376.280444)
			(xy 331.080785 -376.261644) (xy 331.080364 -376.25147) (xy 331.080364 -375.965466) (xy 331.080189 -375.958591)
			(xy 331.07657 -375.945329) (xy 331.073252 -375.939304) (xy 331.05694 -375.910934) (xy 331.031193 -375.850771)
			(xy 331.013763 -375.787693) (xy 331.004967 -375.722846) (xy 331.004963 -375.657405) (xy 331.013753 -375.592557)
			(xy 331.031176 -375.529478) (xy 331.056916 -375.469312) (xy 331.073252 -375.440956) (xy 331.076579 -375.434937)
			(xy 331.080177 -375.421669) (xy 331.080364 -375.414794) (xy 331.080364 -374.665494) (xy 331.080179 -374.65862)
			(xy 331.076566 -374.645357) (xy 331.073252 -374.639332) (xy 331.056879 -374.610996) (xy 331.031137 -374.550824)
			(xy 331.013714 -374.48774) (xy 331.004926 -374.422887) (xy 308.975506 -374.422887) (xy 308.975506 -376.757482)
			(xy 333.204846 -376.757482) (xy 333.213639 -376.692633) (xy 333.231065 -376.629553) (xy 333.256809 -376.569386)
			(xy 333.273146 -376.54103) (xy 333.276499 -376.535009) (xy 333.280242 -376.521753) (xy 333.280512 -376.514868)
			(xy 333.280512 -375.765568) (xy 333.280286 -375.758675) (xy 333.276553 -375.745402) (xy 333.273146 -375.739406)
			(xy 333.256836 -375.711035) (xy 333.231089 -375.650872) (xy 333.213659 -375.587795) (xy 333.204863 -375.522948)
			(xy 333.204859 -375.457507) (xy 333.213648 -375.392659) (xy 333.231071 -375.32958) (xy 333.256811 -375.269414)
			(xy 333.273146 -375.241058) (xy 333.276524 -375.23505) (xy 333.280251 -375.221784) (xy 333.280512 -375.214896)
			(xy 333.280512 -374.928638) (xy 333.281057 -374.918517) (xy 333.288767 -374.899802) (xy 333.303035 -374.885446)
			(xy 333.321702 -374.87762) (xy 333.33182 -374.877076) (xy 334.0481 -374.877076) (xy 334.058251 -374.877521)
			(xy 334.076999 -374.885312) (xy 334.091321 -374.899701) (xy 334.099025 -374.918485) (xy 334.099408 -374.928638)
			(xy 334.099408 -375.214896) (xy 334.099642 -375.221787) (xy 334.103384 -375.235053) (xy 334.106774 -375.241058)
			(xy 334.123138 -375.269399) (xy 334.148879 -375.32957) (xy 334.166302 -375.392653) (xy 334.175091 -375.457505)
			(xy 334.175087 -375.52295) (xy 334.166291 -375.587801) (xy 334.148861 -375.650882) (xy 334.123113 -375.71105)
			(xy 334.106774 -375.739406) (xy 334.10341 -375.745421) (xy 334.099674 -375.758681) (xy 334.099408 -375.765568)
			(xy 334.099408 -376.514868) (xy 334.099653 -376.521758) (xy 334.103387 -376.535024) (xy 334.106774 -376.54103)
			(xy 334.123114 -376.569384) (xy 334.148857 -376.629552) (xy 334.166283 -376.692632) (xy 334.175075 -376.757482)
			(xy 337.604882 -376.757482) (xy 337.613676 -376.692632) (xy 337.631103 -376.629552) (xy 337.656849 -376.569386)
			(xy 337.673188 -376.54103) (xy 337.676491 -376.535) (xy 337.680104 -376.52174) (xy 337.6803 -376.514868)
			(xy 337.6803 -375.765568) (xy 337.68012 -375.758694) (xy 337.676504 -375.745431) (xy 337.673188 -375.739406)
			(xy 337.656876 -375.711035) (xy 337.631127 -375.650873) (xy 337.613696 -375.587795) (xy 337.604899 -375.522948)
			(xy 337.604895 -375.457507) (xy 337.613685 -375.392658) (xy 337.631109 -375.329579) (xy 337.656851 -375.269414)
			(xy 337.673188 -375.241058) (xy 337.676517 -375.23504) (xy 337.680114 -375.221771) (xy 337.6803 -375.214896)
			(xy 337.6803 -374.928638) (xy 337.680864 -374.918487) (xy 337.688619 -374.899726) (xy 337.702963 -374.885361)
			(xy 337.721712 -374.877579) (xy 337.731862 -374.877076) (xy 338.448142 -374.877076) (xy 338.458307 -374.8775)
			(xy 338.477085 -374.885295) (xy 338.49145 -374.899683) (xy 338.499216 -374.918472) (xy 338.499704 -374.928638)
			(xy 338.499704 -375.214896) (xy 338.499897 -375.221769) (xy 338.503504 -375.235032) (xy 338.506816 -375.241058)
			(xy 338.523182 -375.269399) (xy 338.548926 -375.329569) (xy 338.566351 -375.392652) (xy 338.575141 -375.457505)
			(xy 338.575137 -375.52295) (xy 338.56634 -375.587802) (xy 338.548907 -375.650883) (xy 338.523157 -375.71105)
			(xy 338.506816 -375.739406) (xy 338.5035 -375.74543) (xy 338.499895 -375.758694) (xy 338.499704 -375.765568)
			(xy 338.499704 -376.514868) (xy 338.499908 -376.52174) (xy 338.503508 -376.535003) (xy 338.506816 -376.54103)
			(xy 338.523158 -376.569384) (xy 338.548904 -376.629551) (xy 338.566332 -376.692631) (xy 338.575125 -376.757482)
			(xy 342.004932 -376.757482) (xy 342.013725 -376.692633) (xy 342.03115 -376.629553) (xy 342.056893 -376.569386)
			(xy 342.07323 -376.54103) (xy 342.076582 -376.535009) (xy 342.080325 -376.521753) (xy 342.080596 -376.514868)
			(xy 342.080596 -375.765568) (xy 342.080337 -375.758679) (xy 342.076612 -375.745413) (xy 342.07323 -375.739406)
			(xy 342.05692 -375.711035) (xy 342.031174 -375.650871) (xy 342.013745 -375.587795) (xy 342.004949 -375.522948)
			(xy 342.004945 -375.457507) (xy 342.013734 -375.392659) (xy 342.031156 -375.32958) (xy 342.056895 -375.269414)
			(xy 342.07323 -375.241058) (xy 342.076607 -375.235049) (xy 342.080335 -375.221784) (xy 342.080596 -375.214896)
			(xy 342.080596 -374.928638) (xy 342.081157 -374.918519) (xy 342.088864 -374.899807) (xy 342.103127 -374.885451)
			(xy 342.121789 -374.877623) (xy 342.131904 -374.877076) (xy 342.848184 -374.877076) (xy 342.858334 -374.877534)
			(xy 342.877082 -374.88532) (xy 342.891405 -374.899705) (xy 342.899109 -374.918486) (xy 342.899492 -374.928638)
			(xy 342.899492 -375.214896) (xy 342.899728 -375.221787) (xy 342.903469 -375.235053) (xy 342.906858 -375.241058)
			(xy 342.923223 -375.269399) (xy 342.948964 -375.329569) (xy 342.966388 -375.392653) (xy 342.975177 -375.457505)
			(xy 342.975174 -375.52295) (xy 342.966377 -375.587801) (xy 342.948946 -375.650883) (xy 342.923198 -375.71105)
			(xy 342.906858 -375.739406) (xy 342.903493 -375.74542) (xy 342.899758 -375.758681) (xy 342.899492 -375.765568)
			(xy 342.899492 -376.514868) (xy 342.899739 -376.521758) (xy 342.903472 -376.535024) (xy 342.906858 -376.54103)
			(xy 342.923199 -376.569384) (xy 342.948943 -376.629551) (xy 342.966369 -376.692632) (xy 342.975161 -376.757482)
			(xy 342.975161 -376.822925) (xy 346.404969 -376.822925) (xy 346.404969 -376.757482) (xy 346.413762 -376.692632)
			(xy 346.431189 -376.629552) (xy 346.456934 -376.569386) (xy 346.473272 -376.54103) (xy 346.476574 -376.534999)
			(xy 346.480188 -376.52174) (xy 346.480384 -376.514868) (xy 346.480384 -375.765568) (xy 346.480206 -375.758694)
			(xy 346.476589 -375.745431) (xy 346.473272 -375.739406) (xy 346.456961 -375.711035) (xy 346.431213 -375.650872)
			(xy 346.413782 -375.587795) (xy 346.404985 -375.522948) (xy 346.404981 -375.457507) (xy 346.413771 -375.392659)
			(xy 346.431194 -375.32958) (xy 346.456936 -375.269414) (xy 346.473272 -375.241058) (xy 346.4766 -375.23504)
			(xy 346.480198 -375.221771) (xy 346.480384 -375.214896) (xy 346.480384 -374.928638) (xy 346.480796 -374.918463)
			(xy 346.488577 -374.899661) (xy 346.502967 -374.885273) (xy 346.521771 -374.877495) (xy 346.531946 -374.877076)
			(xy 347.248226 -374.877076) (xy 347.258404 -374.877443) (xy 347.277207 -374.885244) (xy 347.291592 -374.899647)
			(xy 347.299369 -374.918459) (xy 347.299788 -374.928638) (xy 347.299788 -375.214896) (xy 347.299983 -375.221769)
			(xy 347.303589 -375.235032) (xy 347.3069 -375.241058) (xy 347.323263 -375.2694) (xy 347.349003 -375.32957)
			(xy 347.366425 -375.392653) (xy 347.375213 -375.457505) (xy 347.37521 -375.52295) (xy 347.366414 -375.587801)
			(xy 347.348984 -375.650882) (xy 347.332189 -375.69013) (xy 348.603832 -375.69013) (xy 348.607823 -375.627963)
			(xy 348.619732 -375.566816) (xy 348.639361 -375.507695) (xy 348.66639 -375.451569) (xy 348.700374 -375.39936)
			(xy 348.740756 -375.351925) (xy 348.786872 -375.310044) (xy 348.837964 -375.274404) (xy 348.893195 -375.24559)
			(xy 348.951657 -375.224076) (xy 349.012391 -375.210214) (xy 349.074398 -375.204232) (xy 349.136661 -375.206228)
			(xy 349.198158 -375.216171) (xy 349.257879 -375.233895) (xy 349.314842 -375.259112) (xy 349.368113 -375.291405)
			(xy 349.416818 -375.330245) (xy 349.460155 -375.374995) (xy 349.497415 -375.424919) (xy 349.527984 -375.479198)
			(xy 349.532451 -375.490232) (xy 350.80398 -375.490232) (xy 350.807971 -375.428065) (xy 350.81988 -375.366918)
			(xy 350.839509 -375.307797) (xy 350.866538 -375.251671) (xy 350.900522 -375.199462) (xy 350.940904 -375.152027)
			(xy 350.98702 -375.110146) (xy 351.038112 -375.074506) (xy 351.093343 -375.045692) (xy 351.151805 -375.024178)
			(xy 351.212539 -375.010316) (xy 351.274546 -375.004334) (xy 351.336809 -375.00633) (xy 351.398306 -375.016273)
			(xy 351.458027 -375.033997) (xy 351.51499 -375.059214) (xy 351.568261 -375.091507) (xy 351.616966 -375.130347)
			(xy 351.660303 -375.175097) (xy 351.697563 -375.225021) (xy 351.728132 -375.2793) (xy 351.75151 -375.337043)
			(xy 351.767311 -375.397301) (xy 351.775277 -375.459084) (xy 351.775776 -375.490232) (xy 351.775277 -375.52138)
			(xy 351.767311 -375.583163) (xy 351.75151 -375.643421) (xy 351.728132 -375.701164) (xy 351.697563 -375.755443)
			(xy 351.660303 -375.805367) (xy 351.616966 -375.850117) (xy 351.568261 -375.888957) (xy 351.51499 -375.92125)
			(xy 351.458027 -375.946467) (xy 351.398306 -375.964191) (xy 351.336809 -375.974134) (xy 351.274546 -375.97613)
			(xy 351.212539 -375.970148) (xy 351.151805 -375.956286) (xy 351.093343 -375.934772) (xy 351.038112 -375.905958)
			(xy 350.98702 -375.870318) (xy 350.940904 -375.828437) (xy 350.900522 -375.781002) (xy 350.866538 -375.728793)
			(xy 350.839509 -375.672667) (xy 350.81988 -375.613546) (xy 350.807971 -375.552399) (xy 350.80398 -375.490232)
			(xy 349.532451 -375.490232) (xy 349.551362 -375.536941) (xy 349.567163 -375.597199) (xy 349.575129 -375.658982)
			(xy 349.575628 -375.69013) (xy 349.575129 -375.721278) (xy 349.567163 -375.783061) (xy 349.551362 -375.843319)
			(xy 349.527984 -375.901062) (xy 349.497415 -375.955341) (xy 349.460155 -376.005265) (xy 349.416818 -376.050015)
			(xy 349.368113 -376.088855) (xy 349.314842 -376.121148) (xy 349.257879 -376.146365) (xy 349.198158 -376.164089)
			(xy 349.136661 -376.174032) (xy 349.074398 -376.176028) (xy 349.012391 -376.170046) (xy 348.951657 -376.156184)
			(xy 348.893195 -376.13467) (xy 348.837964 -376.105856) (xy 348.786872 -376.070216) (xy 348.740756 -376.028335)
			(xy 348.700374 -375.9809) (xy 348.66639 -375.928691) (xy 348.639361 -375.872565) (xy 348.619732 -375.813444)
			(xy 348.607823 -375.752297) (xy 348.603832 -375.69013) (xy 347.332189 -375.69013) (xy 347.323238 -375.711049)
			(xy 347.3069 -375.739406) (xy 347.303583 -375.74543) (xy 347.299979 -375.758694) (xy 347.299788 -375.765568)
			(xy 347.299788 -376.514868) (xy 347.299993 -376.52174) (xy 347.303593 -376.535003) (xy 347.3069 -376.54103)
			(xy 347.32324 -376.569385) (xy 347.348981 -376.629552) (xy 347.366406 -376.692633) (xy 347.375197 -376.757482)
			(xy 347.375197 -376.790204) (xy 350.80398 -376.790204) (xy 350.807971 -376.728037) (xy 350.81988 -376.66689)
			(xy 350.839509 -376.607769) (xy 350.866538 -376.551643) (xy 350.900522 -376.499434) (xy 350.940904 -376.451999)
			(xy 350.98702 -376.410118) (xy 351.038112 -376.374478) (xy 351.093343 -376.345664) (xy 351.151805 -376.32415)
			(xy 351.212539 -376.310288) (xy 351.274546 -376.304306) (xy 351.336809 -376.306302) (xy 351.398306 -376.316245)
			(xy 351.458027 -376.333969) (xy 351.51499 -376.359186) (xy 351.568261 -376.391479) (xy 351.616966 -376.430319)
			(xy 351.660303 -376.475069) (xy 351.697563 -376.524993) (xy 351.728132 -376.579272) (xy 351.75151 -376.637015)
			(xy 351.767311 -376.697273) (xy 351.775277 -376.759056) (xy 351.775776 -376.790204) (xy 351.775277 -376.821352)
			(xy 351.767311 -376.883135) (xy 351.75151 -376.943393) (xy 351.728132 -377.001136) (xy 351.697563 -377.055415)
			(xy 351.660303 -377.105339) (xy 351.616966 -377.150089) (xy 351.568261 -377.188929) (xy 351.51499 -377.221222)
			(xy 351.458027 -377.246439) (xy 351.398306 -377.264163) (xy 351.336809 -377.274106) (xy 351.274546 -377.276102)
			(xy 351.212539 -377.27012) (xy 351.151805 -377.256258) (xy 351.093343 -377.234744) (xy 351.038112 -377.20593)
			(xy 350.98702 -377.17029) (xy 350.940904 -377.128409) (xy 350.900522 -377.080974) (xy 350.866538 -377.028765)
			(xy 350.839509 -376.972639) (xy 350.81988 -376.913518) (xy 350.807971 -376.852371) (xy 350.80398 -376.790204)
			(xy 347.375197 -376.790204) (xy 347.375197 -376.822925) (xy 347.366404 -376.887774) (xy 347.348979 -376.950854)
			(xy 347.323236 -377.011021) (xy 347.3069 -377.039378) (xy 347.303593 -377.045406) (xy 347.299983 -377.058667)
			(xy 347.299788 -377.06554) (xy 347.299788 -377.35129) (xy 347.299259 -377.361444) (xy 347.291493 -377.380208)
			(xy 347.277138 -377.394573) (xy 347.25838 -377.402352) (xy 347.248226 -377.402852) (xy 346.531946 -377.402852)
			(xy 346.521776 -377.402398) (xy 346.502981 -377.394627) (xy 346.488594 -377.38025) (xy 346.480809 -377.36146)
			(xy 346.480384 -377.35129) (xy 346.480384 -377.06554) (xy 346.480179 -377.058668) (xy 346.47658 -377.045405)
			(xy 346.473272 -377.039378) (xy 346.456937 -377.01102) (xy 346.431191 -376.950854) (xy 346.413763 -376.887775)
			(xy 346.404969 -376.822925) (xy 342.975161 -376.822925) (xy 342.966367 -376.887775) (xy 342.94894 -376.950855)
			(xy 342.923196 -377.011022) (xy 342.906858 -377.039378) (xy 342.903502 -377.045397) (xy 342.899761 -377.058654)
			(xy 342.899492 -377.06554) (xy 342.899492 -377.35129) (xy 342.898966 -377.361412) (xy 342.891248 -377.380127)
			(xy 342.876974 -377.394483) (xy 342.858303 -377.402308) (xy 342.848184 -377.402852) (xy 342.131904 -377.402852)
			(xy 342.121757 -377.402376) (xy 342.103014 -377.394592) (xy 342.088693 -377.380212) (xy 342.080984 -377.361439)
			(xy 342.080596 -377.35129) (xy 342.080596 -377.06554) (xy 342.080348 -377.05865) (xy 342.076616 -377.045384)
			(xy 342.07323 -377.039378) (xy 342.056896 -377.01102) (xy 342.031153 -376.950854) (xy 342.013726 -376.887774)
			(xy 342.004933 -376.822925) (xy 342.004932 -376.757482) (xy 338.575125 -376.757482) (xy 338.575125 -376.822925)
			(xy 338.56633 -376.887776) (xy 338.548902 -376.950856) (xy 338.523155 -377.011022) (xy 338.506816 -377.039378)
			(xy 338.50351 -377.045407) (xy 338.499899 -377.058667) (xy 338.499704 -377.06554) (xy 338.499704 -377.35129)
			(xy 338.49916 -377.361442) (xy 338.491396 -377.380203) (xy 338.477047 -377.394567) (xy 338.458293 -377.402349)
			(xy 338.448142 -377.402852) (xy 337.731862 -377.402852) (xy 337.721701 -377.402397) (xy 337.702929 -377.394609)
			(xy 337.688564 -377.380231) (xy 337.680793 -377.361452) (xy 337.6803 -377.35129) (xy 337.6803 -377.06554)
			(xy 337.680093 -377.058668) (xy 337.676495 -377.045405) (xy 337.673188 -377.039378) (xy 337.656852 -377.01102)
			(xy 337.631106 -376.950855) (xy 337.613677 -376.887775) (xy 337.604883 -376.822925) (xy 337.604882 -376.757482)
			(xy 334.175075 -376.757482) (xy 334.175075 -376.822925) (xy 334.166281 -376.887775) (xy 334.148855 -376.950855)
			(xy 334.123111 -377.011022) (xy 334.106774 -377.039378) (xy 334.10342 -377.045398) (xy 334.099678 -377.058654)
			(xy 334.099408 -377.06554) (xy 334.099408 -377.35129) (xy 334.098867 -377.36141) (xy 334.091151 -377.380122)
			(xy 334.076882 -377.394477) (xy 334.058217 -377.402305) (xy 334.0481 -377.402852) (xy 333.33182 -377.402852)
			(xy 333.321674 -377.402363) (xy 333.302932 -377.394584) (xy 333.288609 -377.380209) (xy 333.2809 -377.361438)
			(xy 333.280512 -377.35129) (xy 333.280512 -377.06554) (xy 333.280297 -377.058646) (xy 333.276557 -377.045374)
			(xy 333.273146 -377.039378) (xy 333.256812 -377.01102) (xy 333.231067 -376.950854) (xy 333.21364 -376.887774)
			(xy 333.204847 -376.822925) (xy 333.204846 -376.757482) (xy 308.975506 -376.757482) (xy 308.975506 -378.3228)
			(xy 331.004935 -378.3228) (xy 331.004938 -378.257355) (xy 331.013734 -378.192504) (xy 331.031164 -378.129423)
			(xy 331.056912 -378.069256) (xy 331.073252 -378.0409) (xy 331.076563 -378.034873) (xy 331.080172 -378.021611)
			(xy 331.080364 -378.014738) (xy 331.080364 -377.728734) (xy 331.080792 -377.718561) (xy 331.088571 -377.699763)
			(xy 331.102956 -377.685376) (xy 331.121753 -377.677594) (xy 331.131926 -377.677172) (xy 331.848206 -377.677172)
			(xy 331.858382 -377.67756) (xy 331.877184 -377.685353) (xy 331.891569 -377.69975) (xy 331.899348 -377.718557)
			(xy 331.899768 -377.728734) (xy 331.899768 -378.014738) (xy 331.899987 -378.021609) (xy 331.903577 -378.034872)
			(xy 331.90688 -378.0409) (xy 331.923195 -378.069269) (xy 331.94894 -378.129433) (xy 331.966368 -378.19251)
			(xy 331.975163 -378.257357) (xy 331.975166 -378.322798) (xy 331.975166 -378.3228) (xy 335.404985 -378.3228)
			(xy 335.404988 -378.257356) (xy 335.413783 -378.192505) (xy 335.431211 -378.129424) (xy 335.456956 -378.069257)
			(xy 335.473294 -378.0409) (xy 335.476654 -378.034883) (xy 335.480393 -378.021624) (xy 335.48066 -378.014738)
			(xy 335.48066 -377.728734) (xy 335.481155 -377.718607) (xy 335.488875 -377.699883) (xy 335.50316 -377.685525)
			(xy 335.521844 -377.677708) (xy 335.531968 -377.677172) (xy 336.248248 -377.677172) (xy 336.258402 -377.677582)
			(xy 336.27715 -377.685388) (xy 336.29147 -377.699787) (xy 336.299173 -377.718578) (xy 336.299556 -377.728734)
			(xy 336.299556 -378.014738) (xy 336.299784 -378.021631) (xy 336.303516 -378.034903) (xy 336.306922 -378.0409)
			(xy 336.323239 -378.069268) (xy 336.348987 -378.129431) (xy 336.366417 -378.192509) (xy 336.375213 -378.257357)
			(xy 336.375216 -378.322799) (xy 336.375216 -378.3228) (xy 339.805021 -378.3228) (xy 339.805024 -378.257355)
			(xy 339.81382 -378.192504) (xy 339.83125 -378.129423) (xy 339.856997 -378.069256) (xy 339.873336 -378.0409)
			(xy 339.876646 -378.034873) (xy 339.880255 -378.021611) (xy 339.880448 -378.014738) (xy 339.880448 -377.728734)
			(xy 339.880892 -377.718563) (xy 339.888668 -377.699768) (xy 339.903047 -377.685381) (xy 339.92184 -377.677597)
			(xy 339.93201 -377.677172) (xy 340.64829 -377.677172) (xy 340.658465 -377.677573) (xy 340.677266 -377.685361)
			(xy 340.691653 -377.699754) (xy 340.699432 -377.718559) (xy 340.699852 -377.728734) (xy 340.699852 -378.014738)
			(xy 340.700061 -378.02161) (xy 340.703657 -378.034873) (xy 340.706964 -378.0409) (xy 340.723279 -378.069268)
			(xy 340.749025 -378.129432) (xy 340.766454 -378.19251) (xy 340.775249 -378.257357) (xy 340.775252 -378.322798)
			(xy 340.775252 -378.3228) (xy 344.204811 -378.3228) (xy 344.204814 -378.257355) (xy 344.21361 -378.192505)
			(xy 344.231039 -378.129424) (xy 344.256785 -378.069256) (xy 344.273124 -378.0409) (xy 344.27644 -378.034876)
			(xy 344.280045 -378.021612) (xy 344.280236 -378.014738) (xy 344.280236 -377.728734) (xy 344.280692 -377.718565)
			(xy 344.288465 -377.699771) (xy 344.302841 -377.685385) (xy 344.321629 -377.677599) (xy 344.331798 -377.677172)
			(xy 345.048078 -377.677172) (xy 345.058252 -377.677583) (xy 345.077053 -377.685367) (xy 345.09144 -377.699757)
			(xy 345.099219 -377.71856) (xy 345.09964 -377.728734) (xy 345.09964 -378.014738) (xy 345.099851 -378.02161)
			(xy 345.103446 -378.034873) (xy 345.106752 -378.0409) (xy 345.123068 -378.069268) (xy 345.148814 -378.129432)
			(xy 345.166243 -378.19251) (xy 345.175039 -378.257357) (xy 345.17504 -378.290074) (xy 348.603832 -378.290074)
			(xy 348.607823 -378.227907) (xy 348.619732 -378.16676) (xy 348.639361 -378.107639) (xy 348.66639 -378.051513)
			(xy 348.700374 -377.999304) (xy 348.740756 -377.951869) (xy 348.786872 -377.909988) (xy 348.837964 -377.874348)
			(xy 348.893195 -377.845534) (xy 348.951657 -377.82402) (xy 349.012391 -377.810158) (xy 349.074398 -377.804176)
			(xy 349.136661 -377.806172) (xy 349.198158 -377.816115) (xy 349.257879 -377.833839) (xy 349.314842 -377.859056)
			(xy 349.368113 -377.891349) (xy 349.416818 -377.930189) (xy 349.460155 -377.974939) (xy 349.497415 -378.024863)
			(xy 349.527984 -378.079142) (xy 349.551362 -378.136885) (xy 349.567163 -378.197143) (xy 349.575129 -378.258926)
			(xy 349.575628 -378.290074) (xy 349.575129 -378.321222) (xy 349.567163 -378.383005) (xy 349.551362 -378.443263)
			(xy 349.527984 -378.501006) (xy 349.497415 -378.555285) (xy 349.460155 -378.605209) (xy 349.416818 -378.649959)
			(xy 349.368113 -378.688799) (xy 349.314842 -378.721092) (xy 349.257879 -378.746309) (xy 349.198158 -378.764033)
			(xy 349.136661 -378.773976) (xy 349.074398 -378.775972) (xy 349.012391 -378.76999) (xy 348.951657 -378.756128)
			(xy 348.893195 -378.734614) (xy 348.837964 -378.7058) (xy 348.786872 -378.67016) (xy 348.740756 -378.628279)
			(xy 348.700374 -378.580844) (xy 348.66639 -378.528635) (xy 348.639361 -378.472509) (xy 348.619732 -378.413388)
			(xy 348.607823 -378.352241) (xy 348.603832 -378.290074) (xy 345.17504 -378.290074) (xy 345.175042 -378.322798)
			(xy 345.166252 -378.387647) (xy 345.148829 -378.450726) (xy 345.123088 -378.510892) (xy 345.106752 -378.539248)
			(xy 345.103424 -378.545266) (xy 345.099826 -378.558535) (xy 345.09964 -378.56541) (xy 345.09964 -379.31471)
			(xy 345.099823 -379.321584) (xy 345.103437 -379.334847) (xy 345.106752 -379.340872) (xy 345.123129 -379.369207)
			(xy 345.148869 -379.429378) (xy 345.166292 -379.492463) (xy 345.17508 -379.557316) (xy 345.175075 -379.622763)
			(xy 345.166276 -379.687615) (xy 345.148843 -379.750696) (xy 345.123093 -379.810864) (xy 345.106752 -379.83922)
			(xy 345.103434 -379.845243) (xy 345.09983 -379.858508) (xy 345.09964 -379.865382) (xy 345.09964 -380.151386)
			(xy 345.099224 -380.161559) (xy 345.09144 -380.180358) (xy 345.077051 -380.194744) (xy 345.058252 -380.202526)
			(xy 345.048078 -380.202948) (xy 344.331798 -380.202948) (xy 344.321625 -380.202537) (xy 344.302827 -380.194749)
			(xy 344.288442 -380.180359) (xy 344.280659 -380.16156) (xy 344.280236 -380.151386) (xy 344.280236 -379.865382)
			(xy 344.280046 -379.858509) (xy 344.276436 -379.845246) (xy 344.273124 -379.83922) (xy 344.256826 -379.810842)
			(xy 344.231079 -379.75068) (xy 344.213649 -379.687605) (xy 344.204852 -379.622759) (xy 344.204846 -379.55732)
			(xy 344.213633 -379.492473) (xy 344.231053 -379.429394) (xy 344.25679 -379.369228) (xy 344.273124 -379.340872)
			(xy 344.27645 -379.334853) (xy 344.280048 -379.321585) (xy 344.280236 -379.31471) (xy 344.280236 -378.56541)
			(xy 344.280036 -378.558537) (xy 344.276433 -378.545275) (xy 344.273124 -378.539248) (xy 344.256765 -378.510904)
			(xy 344.231024 -378.450734) (xy 344.213601 -378.387652) (xy 344.204811 -378.3228) (xy 340.775252 -378.3228)
			(xy 340.766463 -378.387646) (xy 340.74904 -378.450726) (xy 340.7233 -378.510892) (xy 340.706964 -378.539248)
			(xy 340.703637 -378.545267) (xy 340.700038 -378.558535) (xy 340.699852 -378.56541) (xy 340.699852 -379.31471)
			(xy 340.700034 -379.321584) (xy 340.703648 -379.334847) (xy 340.706964 -379.340872) (xy 340.72334 -379.369207)
			(xy 340.74908 -379.429378) (xy 340.766502 -379.492463) (xy 340.77529 -379.557316) (xy 340.775285 -379.622762)
			(xy 340.766487 -379.687614) (xy 340.749054 -379.750696) (xy 340.723304 -379.810864) (xy 340.706964 -379.83922)
			(xy 340.703647 -379.845244) (xy 340.700042 -379.858508) (xy 340.699852 -379.865382) (xy 340.699852 -380.151386)
			(xy 340.699425 -380.161558) (xy 340.691642 -380.180354) (xy 340.677258 -380.19474) (xy 340.658462 -380.202524)
			(xy 340.64829 -380.202948) (xy 339.93201 -380.202948) (xy 339.921837 -380.202528) (xy 339.90304 -380.194743)
			(xy 339.888654 -380.180357) (xy 339.880871 -380.161559) (xy 339.880448 -380.151386) (xy 339.880448 -379.865382)
			(xy 339.880269 -379.858508) (xy 339.876653 -379.845245) (xy 339.873336 -379.83922) (xy 339.857038 -379.810842)
			(xy 339.83129 -379.750681) (xy 339.81386 -379.687605) (xy 339.805062 -379.622759) (xy 339.805057 -379.55732)
			(xy 339.813844 -379.492472) (xy 339.831264 -379.429394) (xy 339.857002 -379.369228) (xy 339.873336 -379.340872)
			(xy 339.876656 -379.33485) (xy 339.880259 -379.321584) (xy 339.880448 -379.31471) (xy 339.880448 -378.56541)
			(xy 339.880259 -378.558536) (xy 339.876649 -378.545273) (xy 339.873336 -378.539248) (xy 339.856977 -378.510904)
			(xy 339.831235 -378.450734) (xy 339.813811 -378.387652) (xy 339.805021 -378.3228) (xy 336.375216 -378.3228)
			(xy 336.366426 -378.387647) (xy 336.349001 -378.450726) (xy 336.323259 -378.510892) (xy 336.306922 -378.539248)
			(xy 336.303539 -378.545253) (xy 336.299816 -378.558521) (xy 336.299556 -378.56541) (xy 336.299556 -379.31471)
			(xy 336.299756 -379.321605) (xy 336.303507 -379.334877) (xy 336.306922 -379.340872) (xy 336.3233 -379.369206)
			(xy 336.349042 -379.429378) (xy 336.366465 -379.492462) (xy 336.375254 -379.557316) (xy 336.375249 -379.622763)
			(xy 336.36645 -379.687615) (xy 336.349016 -379.750697) (xy 336.323264 -379.810864) (xy 336.306922 -379.83922)
			(xy 336.303549 -379.84523) (xy 336.299819 -379.858494) (xy 336.299556 -379.865382) (xy 336.299556 -380.151386)
			(xy 336.299062 -380.161512) (xy 336.291338 -380.180234) (xy 336.277054 -380.194591) (xy 336.258372 -380.20241)
			(xy 336.248248 -380.202948) (xy 335.531968 -380.202948) (xy 335.521818 -380.202506) (xy 335.503074 -380.194708)
			(xy 335.488753 -380.180319) (xy 335.481046 -380.161538) (xy 335.48066 -380.151386) (xy 335.48066 -379.865382)
			(xy 335.480422 -379.85849) (xy 335.476697 -379.845218) (xy 335.473294 -379.83922) (xy 335.456997 -379.810842)
			(xy 335.431252 -379.75068) (xy 335.413823 -379.687604) (xy 335.405026 -379.622759) (xy 335.405021 -379.55732)
			(xy 335.413807 -379.492473) (xy 335.431226 -379.429395) (xy 335.456961 -379.369229) (xy 335.473294 -379.340872)
			(xy 335.476664 -379.33486) (xy 335.480397 -379.321597) (xy 335.48066 -379.31471) (xy 335.48066 -378.56541)
			(xy 335.48045 -378.558515) (xy 335.476706 -378.545244) (xy 335.473294 -378.539248) (xy 335.456936 -378.510904)
			(xy 335.431197 -378.450734) (xy 335.413774 -378.387651) (xy 335.404985 -378.3228) (xy 331.975166 -378.3228)
			(xy 331.966377 -378.387646) (xy 331.948954 -378.450725) (xy 331.923215 -378.510892) (xy 331.90688 -378.539248)
			(xy 331.903547 -378.545264) (xy 331.899953 -378.558534) (xy 331.899768 -378.56541) (xy 331.899768 -379.31471)
			(xy 331.89996 -379.321583) (xy 331.903569 -379.334846) (xy 331.90688 -379.340872) (xy 331.923256 -379.369207)
			(xy 331.948995 -379.429379) (xy 331.966416 -379.492463) (xy 331.975204 -379.557316) (xy 331.975199 -379.622762)
			(xy 331.966401 -379.687614) (xy 331.948969 -379.750696) (xy 331.92322 -379.810864) (xy 331.90688 -379.83922)
			(xy 331.903557 -379.84524) (xy 331.899957 -379.858507) (xy 331.899768 -379.865382) (xy 331.899768 -380.151386)
			(xy 331.899325 -380.161556) (xy 331.891546 -380.180349) (xy 331.877166 -380.194734) (xy 331.858376 -380.202521)
			(xy 331.848206 -380.202948) (xy 331.131926 -380.202948) (xy 331.121754 -380.202514) (xy 331.102958 -380.194735)
			(xy 331.088571 -380.180352) (xy 331.080788 -380.161558) (xy 331.080364 -380.151386) (xy 331.080364 -379.865382)
			(xy 331.080183 -379.858508) (xy 331.076568 -379.845245) (xy 331.073252 -379.83922) (xy 331.056953 -379.810842)
			(xy 331.031205 -379.750681) (xy 331.013774 -379.687605) (xy 331.004976 -379.622759) (xy 331.00497 -379.557319)
			(xy 331.013758 -379.492472) (xy 331.031179 -379.429394) (xy 331.056917 -379.369228) (xy 331.073252 -379.340872)
			(xy 331.076573 -379.33485) (xy 331.080175 -379.321584) (xy 331.080364 -379.31471) (xy 331.080364 -378.56541)
			(xy 331.080173 -378.558537) (xy 331.076564 -378.545274) (xy 331.073252 -378.539248) (xy 331.056892 -378.510904)
			(xy 331.03115 -378.450735) (xy 331.013725 -378.387652) (xy 331.004935 -378.3228) (xy 308.975506 -378.3228)
			(xy 308.975506 -380.657396) (xy 333.204853 -380.657396) (xy 333.213644 -380.592548) (xy 333.231068 -380.529468)
			(xy 333.25681 -380.469302) (xy 333.273146 -380.440946) (xy 333.276529 -380.43494) (xy 333.280252 -380.421673)
			(xy 333.280512 -380.414784) (xy 333.280512 -379.665484) (xy 333.28028 -379.658591) (xy 333.276551 -379.645319)
			(xy 333.273146 -379.639322) (xy 333.256849 -379.610943) (xy 333.231101 -379.550782) (xy 333.21367 -379.487707)
			(xy 333.204872 -379.422861) (xy 333.204866 -379.357421) (xy 333.213653 -379.292574) (xy 333.231074 -379.229496)
			(xy 333.256812 -379.16933) (xy 333.273146 -379.140974) (xy 333.276519 -379.134963) (xy 333.280249 -379.1217)
			(xy 333.280512 -379.114812) (xy 333.280512 -378.828554) (xy 333.280988 -378.818428) (xy 333.288726 -378.799711)
			(xy 333.303015 -378.785357) (xy 333.321696 -378.777535) (xy 333.33182 -378.776992) (xy 334.0481 -378.776992)
			(xy 334.058253 -378.777422) (xy 334.077004 -378.785216) (xy 334.091327 -378.79961) (xy 334.099028 -378.818399)
			(xy 334.099408 -378.828554) (xy 334.099408 -379.114812) (xy 334.099674 -379.121701) (xy 334.103394 -379.134967)
			(xy 334.106774 -379.140974) (xy 334.123152 -379.169308) (xy 334.148891 -379.22948) (xy 334.166313 -379.292565)
			(xy 334.1751 -379.357418) (xy 334.175095 -379.422864) (xy 334.166296 -379.487716) (xy 334.148864 -379.550798)
			(xy 334.123114 -379.610966) (xy 334.106774 -379.639322) (xy 334.103404 -379.645334) (xy 334.099672 -379.658597)
			(xy 334.099408 -379.665484) (xy 334.099408 -380.414784) (xy 334.099646 -380.421675) (xy 334.103385 -380.434941)
			(xy 334.106774 -380.440946) (xy 334.123128 -380.469293) (xy 334.14887 -380.529462) (xy 334.166294 -380.592544)
			(xy 334.175084 -380.657395) (xy 334.175084 -380.657396) (xy 337.60489 -380.657396) (xy 337.613681 -380.592547)
			(xy 337.631107 -380.529468) (xy 337.65685 -380.469302) (xy 337.673188 -380.440946) (xy 337.676486 -380.434913)
			(xy 337.680102 -380.421656) (xy 337.6803 -380.414784) (xy 337.6803 -379.665484) (xy 337.680114 -379.65861)
			(xy 337.676502 -379.645347) (xy 337.673188 -379.639322) (xy 337.65689 -379.610944) (xy 337.63114 -379.550783)
			(xy 337.613707 -379.487707) (xy 337.604908 -379.422861) (xy 337.604902 -379.357421) (xy 337.61369 -379.292574)
			(xy 337.631112 -379.229495) (xy 337.656852 -379.16933) (xy 337.673188 -379.140974) (xy 337.676511 -379.134953)
			(xy 337.680112 -379.121687) (xy 337.6803 -379.114812) (xy 337.6803 -378.828554) (xy 337.680795 -378.818398)
			(xy 337.688577 -378.799635) (xy 337.702942 -378.785273) (xy 337.721706 -378.777493) (xy 337.731862 -378.776992)
			(xy 338.448142 -378.776992) (xy 338.458297 -378.777498) (xy 338.477058 -378.785278) (xy 338.49142 -378.799639)
			(xy 338.499201 -378.818399) (xy 338.499704 -378.828554) (xy 338.499704 -379.114812) (xy 338.499891 -379.121686)
			(xy 338.503502 -379.134948) (xy 338.506816 -379.140974) (xy 338.523195 -379.169307) (xy 338.548938 -379.229479)
			(xy 338.566362 -379.292564) (xy 338.57515 -379.357418) (xy 338.575145 -379.422865) (xy 338.566345 -379.487717)
			(xy 338.548911 -379.550799) (xy 338.523158 -379.610966) (xy 338.506816 -379.639322) (xy 338.503495 -379.645343)
			(xy 338.499893 -379.65861) (xy 338.499704 -379.665484) (xy 338.499704 -380.414784) (xy 338.499902 -380.421657)
			(xy 338.503506 -380.43492) (xy 338.506816 -380.440946) (xy 338.523172 -380.469292) (xy 338.548916 -380.529461)
			(xy 338.566343 -380.592543) (xy 338.575134 -380.657395) (xy 338.575134 -380.657396) (xy 342.00494 -380.657396)
			(xy 342.01373 -380.592548) (xy 342.031153 -380.529469) (xy 342.056894 -380.469302) (xy 342.07323 -380.440946)
			(xy 342.076611 -380.43494) (xy 342.080336 -380.421673) (xy 342.080596 -380.414784) (xy 342.080596 -379.665484)
			(xy 342.080331 -379.658595) (xy 342.07661 -379.645329) (xy 342.07323 -379.639322) (xy 342.056934 -379.610943)
			(xy 342.031186 -379.550782) (xy 342.013756 -379.487706) (xy 342.004958 -379.422861) (xy 342.004952 -379.357421)
			(xy 342.013739 -379.292574) (xy 342.031159 -379.229496) (xy 342.056896 -379.16933) (xy 342.07323 -379.140974)
			(xy 342.076602 -379.134963) (xy 342.080333 -379.121699) (xy 342.080596 -379.114812) (xy 342.080596 -378.828554)
			(xy 342.081088 -378.81843) (xy 342.088822 -378.799716) (xy 342.103106 -378.785363) (xy 342.121782 -378.777538)
			(xy 342.131904 -378.776992) (xy 342.848184 -378.776992) (xy 342.858336 -378.777434) (xy 342.877087 -378.785223)
			(xy 342.89141 -378.799614) (xy 342.899112 -378.8184) (xy 342.899492 -378.828554) (xy 342.899492 -379.114812)
			(xy 342.89976 -379.121701) (xy 342.903479 -379.134967) (xy 342.906858 -379.140974) (xy 342.923236 -379.169308)
			(xy 342.948976 -379.22948) (xy 342.966398 -379.292564) (xy 342.975186 -379.357418) (xy 342.975181 -379.422864)
			(xy 342.966382 -379.487716) (xy 342.948949 -379.550798) (xy 342.923199 -379.610966) (xy 342.906858 -379.639322)
			(xy 342.903487 -379.645334) (xy 342.899756 -379.658597) (xy 342.899492 -379.665484) (xy 342.899492 -380.414784)
			(xy 342.899733 -380.421675) (xy 342.90347 -380.434941) (xy 342.906858 -380.440946) (xy 342.923212 -380.469293)
			(xy 342.948955 -380.529462) (xy 342.96638 -380.592544) (xy 342.97517 -380.657395) (xy 342.97517 -380.657396)
			(xy 346.404976 -380.657396) (xy 346.413767 -380.592547) (xy 346.431192 -380.529468) (xy 346.456935 -380.469302)
			(xy 346.473272 -380.440946) (xy 346.476568 -380.434912) (xy 346.480186 -380.421656) (xy 346.480384 -380.414784)
			(xy 346.480384 -379.665484) (xy 346.4802 -379.65861) (xy 346.476587 -379.645347) (xy 346.473272 -379.639322)
			(xy 346.456974 -379.610944) (xy 346.431225 -379.550783) (xy 346.413793 -379.487707) (xy 346.404994 -379.422861)
			(xy 346.404989 -379.357421) (xy 346.413776 -379.292574) (xy 346.431198 -379.229495) (xy 346.456937 -379.16933)
			(xy 346.473272 -379.140974) (xy 346.476594 -379.134953) (xy 346.480196 -379.121686) (xy 346.480384 -379.114812)
			(xy 346.480384 -378.828554) (xy 346.480797 -378.818388) (xy 346.488595 -378.799609) (xy 346.502986 -378.785243)
			(xy 346.521779 -378.777479) (xy 346.531946 -378.776992) (xy 347.248226 -378.776992) (xy 347.25838 -378.777511)
			(xy 347.277141 -378.785285) (xy 347.291504 -378.799642) (xy 347.299285 -378.8184) (xy 347.299788 -378.828554)
			(xy 347.299788 -379.114812) (xy 347.299977 -379.121685) (xy 347.303587 -379.134948) (xy 347.3069 -379.140974)
			(xy 347.323277 -379.169308) (xy 347.349015 -379.22948) (xy 347.366435 -379.292565) (xy 347.375223 -379.357418)
			(xy 347.375217 -379.422864) (xy 347.366419 -379.487716) (xy 347.348988 -379.550797) (xy 347.332191 -379.590046)
			(xy 348.603832 -379.590046) (xy 348.607823 -379.527879) (xy 348.619732 -379.466732) (xy 348.639361 -379.407611)
			(xy 348.66639 -379.351485) (xy 348.700374 -379.299276) (xy 348.740756 -379.251841) (xy 348.786872 -379.20996)
			(xy 348.837964 -379.17432) (xy 348.893195 -379.145506) (xy 348.951657 -379.123992) (xy 349.012391 -379.11013)
			(xy 349.074398 -379.104148) (xy 349.136661 -379.106144) (xy 349.198158 -379.116087) (xy 349.257879 -379.133811)
			(xy 349.314842 -379.159028) (xy 349.368113 -379.191321) (xy 349.416818 -379.230161) (xy 349.460155 -379.274911)
			(xy 349.497415 -379.324835) (xy 349.527984 -379.379114) (xy 349.532451 -379.390148) (xy 350.80398 -379.390148)
			(xy 350.807971 -379.327981) (xy 350.81988 -379.266834) (xy 350.839509 -379.207713) (xy 350.866538 -379.151587)
			(xy 350.900522 -379.099378) (xy 350.940904 -379.051943) (xy 350.98702 -379.010062) (xy 351.038112 -378.974422)
			(xy 351.093343 -378.945608) (xy 351.151805 -378.924094) (xy 351.212539 -378.910232) (xy 351.274546 -378.90425)
			(xy 351.336809 -378.906246) (xy 351.398306 -378.916189) (xy 351.458027 -378.933913) (xy 351.51499 -378.95913)
			(xy 351.568261 -378.991423) (xy 351.616966 -379.030263) (xy 351.660303 -379.075013) (xy 351.670291 -379.088396)
			(xy 362.932978 -379.088396) (xy 362.937049 -379.032774) (xy 362.949175 -378.978337) (xy 362.969098 -378.926246)
			(xy 362.996394 -378.877611) (xy 363.03048 -378.833468) (xy 363.070629 -378.794759) (xy 363.115987 -378.762308)
			(xy 363.165587 -378.736807) (xy 363.218371 -378.7188) (xy 363.273214 -378.70867) (xy 363.328948 -378.706633)
			(xy 363.384385 -378.712733) (xy 363.438342 -378.726839) (xy 363.489671 -378.748651) (xy 363.537277 -378.777705)
			(xy 363.580145 -378.81338) (xy 363.617362 -378.854917) (xy 363.648135 -378.90143) (xy 363.671807 -378.951927)
			(xy 363.687875 -379.005334) (xy 363.695995 -379.06051) (xy 363.696504 -379.088396) (xy 363.695995 -379.116282)
			(xy 363.687875 -379.171458) (xy 363.671807 -379.224865) (xy 363.648135 -379.275362) (xy 363.617362 -379.321875)
			(xy 363.580145 -379.363412) (xy 363.537277 -379.399087) (xy 363.489671 -379.428141) (xy 363.438342 -379.449953)
			(xy 363.384385 -379.464059) (xy 363.328948 -379.470159) (xy 363.273214 -379.468122) (xy 363.218371 -379.457992)
			(xy 363.165587 -379.439985) (xy 363.115987 -379.414484) (xy 363.070629 -379.382033) (xy 363.03048 -379.343324)
			(xy 362.996394 -379.299181) (xy 362.969098 -379.250546) (xy 362.949175 -379.198455) (xy 362.937049 -379.144018)
			(xy 362.932978 -379.088396) (xy 351.670291 -379.088396) (xy 351.697563 -379.124937) (xy 351.728132 -379.179216)
			(xy 351.75151 -379.236959) (xy 351.767311 -379.297217) (xy 351.775277 -379.359) (xy 351.775776 -379.390148)
			(xy 351.775277 -379.421296) (xy 351.767311 -379.483079) (xy 351.75151 -379.543337) (xy 351.728132 -379.60108)
			(xy 351.697583 -379.655324) (xy 360.52074 -379.655324) (xy 360.524811 -379.599702) (xy 360.536937 -379.545265)
			(xy 360.55686 -379.493174) (xy 360.584156 -379.444539) (xy 360.618242 -379.400396) (xy 360.658391 -379.361687)
			(xy 360.703749 -379.329236) (xy 360.753349 -379.303735) (xy 360.806133 -379.285728) (xy 360.860976 -379.275598)
			(xy 360.91671 -379.273561) (xy 360.972147 -379.279661) (xy 361.026104 -379.293767) (xy 361.077433 -379.315579)
			(xy 361.125039 -379.344633) (xy 361.167907 -379.380308) (xy 361.205124 -379.421845) (xy 361.235897 -379.468358)
			(xy 361.259569 -379.518855) (xy 361.275637 -379.572262) (xy 361.283757 -379.627438) (xy 361.284266 -379.655324)
			(xy 361.283757 -379.68321) (xy 361.275637 -379.738386) (xy 361.259569 -379.791793) (xy 361.235897 -379.84229)
			(xy 361.205124 -379.888803) (xy 361.167907 -379.93034) (xy 361.125039 -379.966015) (xy 361.077433 -379.995069)
			(xy 361.026104 -380.016881) (xy 360.972147 -380.030987) (xy 360.91671 -380.037087) (xy 360.860976 -380.03505)
			(xy 360.806133 -380.02492) (xy 360.753349 -380.006913) (xy 360.703749 -379.981412) (xy 360.658391 -379.948961)
			(xy 360.618242 -379.910252) (xy 360.584156 -379.866109) (xy 360.55686 -379.817474) (xy 360.536937 -379.765383)
			(xy 360.524811 -379.710946) (xy 360.52074 -379.655324) (xy 351.697583 -379.655324) (xy 351.697563 -379.655359)
			(xy 351.660303 -379.705283) (xy 351.616966 -379.750033) (xy 351.568261 -379.788873) (xy 351.51499 -379.821166)
			(xy 351.458027 -379.846383) (xy 351.398306 -379.864107) (xy 351.336809 -379.87405) (xy 351.274546 -379.876046)
			(xy 351.212539 -379.870064) (xy 351.151805 -379.856202) (xy 351.093343 -379.834688) (xy 351.038112 -379.805874)
			(xy 350.98702 -379.770234) (xy 350.940904 -379.728353) (xy 350.900522 -379.680918) (xy 350.866538 -379.628709)
			(xy 350.839509 -379.572583) (xy 350.81988 -379.513462) (xy 350.807971 -379.452315) (xy 350.80398 -379.390148)
			(xy 349.532451 -379.390148) (xy 349.551362 -379.436857) (xy 349.567163 -379.497115) (xy 349.575129 -379.558898)
			(xy 349.575628 -379.590046) (xy 349.575129 -379.621194) (xy 349.567163 -379.682977) (xy 349.551362 -379.743235)
			(xy 349.527984 -379.800978) (xy 349.497415 -379.855257) (xy 349.460155 -379.905181) (xy 349.416818 -379.949931)
			(xy 349.368113 -379.988771) (xy 349.314842 -380.021064) (xy 349.257879 -380.046281) (xy 349.198158 -380.064005)
			(xy 349.136661 -380.073948) (xy 349.074398 -380.075944) (xy 349.012391 -380.069962) (xy 348.951657 -380.0561)
			(xy 348.893195 -380.034586) (xy 348.837964 -380.005772) (xy 348.786872 -379.970132) (xy 348.740756 -379.928251)
			(xy 348.700374 -379.880816) (xy 348.66639 -379.828607) (xy 348.639361 -379.772481) (xy 348.619732 -379.71336)
			(xy 348.607823 -379.652213) (xy 348.603832 -379.590046) (xy 347.332191 -379.590046) (xy 347.323239 -379.610965)
			(xy 347.3069 -379.639322) (xy 347.303577 -379.645343) (xy 347.299977 -379.65861) (xy 347.299788 -379.665484)
			(xy 347.299788 -380.414784) (xy 347.299987 -380.421657) (xy 347.303591 -380.434919) (xy 347.3069 -380.440946)
			(xy 347.323253 -380.469293) (xy 347.348993 -380.529462) (xy 347.366417 -380.592544) (xy 347.375207 -380.657395)
			(xy 347.375205 -380.69012) (xy 350.80398 -380.69012) (xy 350.807971 -380.627953) (xy 350.81988 -380.566806)
			(xy 350.839509 -380.507685) (xy 350.866538 -380.451559) (xy 350.900522 -380.39935) (xy 350.940904 -380.351915)
			(xy 350.98702 -380.310034) (xy 351.038112 -380.274394) (xy 351.093343 -380.24558) (xy 351.151805 -380.224066)
			(xy 351.212539 -380.210204) (xy 351.274546 -380.204222) (xy 351.336809 -380.206218) (xy 351.398306 -380.216161)
			(xy 351.458027 -380.233885) (xy 351.51499 -380.259102) (xy 351.568261 -380.291395) (xy 351.616966 -380.330235)
			(xy 351.660303 -380.374985) (xy 351.697563 -380.424909) (xy 351.728132 -380.479188) (xy 351.75151 -380.536931)
			(xy 351.767311 -380.597189) (xy 351.775277 -380.658972) (xy 351.775776 -380.69012) (xy 351.775277 -380.721268)
			(xy 351.767311 -380.783051) (xy 351.75151 -380.843309) (xy 351.728132 -380.901052) (xy 351.697563 -380.955331)
			(xy 351.660303 -381.005255) (xy 351.616966 -381.050005) (xy 351.568261 -381.088845) (xy 351.51499 -381.121138)
			(xy 351.458027 -381.146355) (xy 351.398306 -381.164079) (xy 351.336809 -381.174022) (xy 351.274546 -381.176018)
			(xy 351.212539 -381.170036) (xy 351.151805 -381.156174) (xy 351.093343 -381.13466) (xy 351.038112 -381.105846)
			(xy 350.98702 -381.070206) (xy 350.940904 -381.028325) (xy 350.900522 -380.98089) (xy 350.866538 -380.928681)
			(xy 350.839509 -380.872555) (xy 350.81988 -380.813434) (xy 350.807971 -380.752287) (xy 350.80398 -380.69012)
			(xy 347.375205 -380.69012) (xy 347.375204 -380.722839) (xy 347.36641 -380.787689) (xy 347.348982 -380.85077)
			(xy 347.323237 -380.910937) (xy 347.3069 -380.939294) (xy 347.303587 -380.94532) (xy 347.29998 -380.958583)
			(xy 347.299788 -380.965456) (xy 347.299788 -381.251206) (xy 347.299272 -381.261361) (xy 347.2915 -381.280125)
			(xy 347.277142 -381.294489) (xy 347.258381 -381.302268) (xy 347.248226 -381.302768) (xy 346.531946 -381.302768)
			(xy 346.521778 -381.302299) (xy 346.502986 -381.29453) (xy 346.488599 -381.280158) (xy 346.480812 -381.261373)
			(xy 346.480384 -381.251206) (xy 346.480384 -380.965456) (xy 346.480173 -380.958584) (xy 346.476578 -380.945321)
			(xy 346.473272 -380.939294) (xy 346.456951 -380.910929) (xy 346.431203 -380.850765) (xy 346.413774 -380.787686)
			(xy 346.404978 -380.722838) (xy 346.404976 -380.657396) (xy 342.97517 -380.657396) (xy 342.975168 -380.722839)
			(xy 342.966373 -380.78769) (xy 342.948944 -380.850771) (xy 342.923197 -380.910938) (xy 342.906858 -380.939294)
			(xy 342.903497 -380.94531) (xy 342.899759 -380.95857) (xy 342.899492 -380.965456) (xy 342.899492 -381.251206)
			(xy 342.898979 -381.261329) (xy 342.891255 -381.280044) (xy 342.876978 -381.294399) (xy 342.858304 -381.302224)
			(xy 342.848184 -381.302768) (xy 342.131904 -381.302768) (xy 342.121746 -381.302374) (xy 342.102988 -381.294574)
			(xy 342.088663 -381.280168) (xy 342.080969 -381.261366) (xy 342.080596 -381.251206) (xy 342.080596 -380.965456)
			(xy 342.080342 -380.958566) (xy 342.076614 -380.9453) (xy 342.07323 -380.939294) (xy 342.05691 -380.910928)
			(xy 342.031165 -380.850764) (xy 342.013737 -380.787686) (xy 342.004942 -380.722838) (xy 342.00494 -380.657396)
			(xy 338.575134 -380.657396) (xy 338.575132 -380.72284) (xy 338.566336 -380.787691) (xy 338.548905 -380.850772)
			(xy 338.523156 -380.910938) (xy 338.506816 -380.939294) (xy 338.503505 -380.94532) (xy 338.499897 -380.958583)
			(xy 338.499704 -380.965456) (xy 338.499704 -381.251206) (xy 338.499172 -381.261359) (xy 338.491404 -381.28012)
			(xy 338.47705 -381.294484) (xy 338.458295 -381.302265) (xy 338.448142 -381.302768) (xy 337.731862 -381.302768)
			(xy 337.721703 -381.302298) (xy 337.702934 -381.294512) (xy 337.68857 -381.280139) (xy 337.680796 -381.261366)
			(xy 337.6803 -381.251206) (xy 337.6803 -380.965456) (xy 337.680086 -380.958584) (xy 337.676493 -380.945322)
			(xy 337.673188 -380.939294) (xy 337.656866 -380.910929) (xy 337.631118 -380.850765) (xy 337.613688 -380.787687)
			(xy 337.604892 -380.722838) (xy 337.60489 -380.657396) (xy 334.175084 -380.657396) (xy 334.175082 -380.722839)
			(xy 334.166287 -380.78769) (xy 334.148858 -380.85077) (xy 334.123112 -380.910938) (xy 334.106774 -380.939294)
			(xy 334.103414 -380.945311) (xy 334.099676 -380.95857) (xy 334.099408 -380.965456) (xy 334.099408 -381.251206)
			(xy 334.09888 -381.261327) (xy 334.091159 -381.280039) (xy 334.076886 -381.294394) (xy 334.058218 -381.302221)
			(xy 334.0481 -381.302768) (xy 333.33182 -381.302768) (xy 333.321663 -381.302362) (xy 333.302905 -381.294567)
			(xy 333.28858 -381.280165) (xy 333.280885 -381.261365) (xy 333.280512 -381.251206) (xy 333.280512 -380.965456)
			(xy 333.28029 -380.958562) (xy 333.276555 -380.94529) (xy 333.273146 -380.939294) (xy 333.256825 -380.910929)
			(xy 333.23108 -380.850764) (xy 333.213651 -380.787686) (xy 333.204856 -380.722838) (xy 333.204853 -380.657396)
			(xy 308.975506 -380.657396) (xy 308.975506 -382.222713) (xy 331.004944 -382.222713) (xy 331.004945 -382.15727)
			(xy 331.013739 -382.092419) (xy 331.031168 -382.029339) (xy 331.056914 -381.969172) (xy 331.073252 -381.940816)
			(xy 331.076557 -381.934787) (xy 331.080169 -381.921527) (xy 331.080364 -381.914654) (xy 331.080364 -381.628904)
			(xy 331.080824 -381.618755) (xy 331.088612 -381.600009) (xy 331.102996 -381.585687) (xy 331.121775 -381.577981)
			(xy 331.131926 -381.577596) (xy 331.848206 -381.577596) (xy 331.858328 -381.57812) (xy 331.877041 -381.585842)
			(xy 331.891395 -381.600116) (xy 331.899222 -381.618785) (xy 331.899768 -381.628904) (xy 331.899768 -381.914654)
			(xy 331.899981 -381.921526) (xy 331.903575 -381.934788) (xy 331.90688 -381.940816) (xy 331.923208 -381.969177)
			(xy 331.948952 -382.029343) (xy 331.966379 -382.092422) (xy 331.975172 -382.15727) (xy 331.975173 -382.222712)
			(xy 331.975173 -382.222713) (xy 335.404994 -382.222713) (xy 335.404995 -382.15727) (xy 335.413788 -382.09242)
			(xy 335.431215 -382.02934) (xy 335.456957 -381.969173) (xy 335.473294 -381.940816) (xy 335.476648 -381.934796)
			(xy 335.480391 -381.92154) (xy 335.48066 -381.914654) (xy 335.48066 -381.628904) (xy 335.481187 -381.6188)
			(xy 335.488916 -381.60013) (xy 335.5032 -381.585837) (xy 335.521865 -381.578095) (xy 335.531968 -381.577596)
			(xy 336.248248 -381.577596) (xy 336.258359 -381.578046) (xy 336.277038 -381.585799) (xy 336.291331 -381.600106)
			(xy 336.299064 -381.618792) (xy 336.299556 -381.628904) (xy 336.299556 -381.914654) (xy 336.299778 -381.921548)
			(xy 336.303514 -381.93482) (xy 336.306922 -381.940816) (xy 336.323252 -381.969176) (xy 336.348999 -382.029342)
			(xy 336.366428 -382.092421) (xy 336.375222 -382.15727) (xy 336.375224 -382.222713) (xy 339.80503 -382.222713)
			(xy 339.805031 -382.15727) (xy 339.813825 -382.09242) (xy 339.831253 -382.029339) (xy 339.856998 -381.969172)
			(xy 339.873336 -381.940816) (xy 339.87664 -381.934786) (xy 339.880253 -381.921527) (xy 339.880448 -381.914654)
			(xy 339.880448 -381.628904) (xy 339.880924 -381.618757) (xy 339.888708 -381.600014) (xy 339.903088 -381.585693)
			(xy 339.921861 -381.577984) (xy 339.93201 -381.577596) (xy 340.64829 -381.577596) (xy 340.658411 -381.578133)
			(xy 340.677123 -381.58585) (xy 340.691478 -381.60012) (xy 340.699306 -381.618786) (xy 340.699852 -381.628904)
			(xy 340.699852 -381.914654) (xy 340.700055 -381.921527) (xy 340.703655 -381.93479) (xy 340.706964 -381.940816)
			(xy 340.723293 -381.969177) (xy 340.749037 -382.029343) (xy 340.766465 -382.092422) (xy 340.775259 -382.15727)
			(xy 340.77526 -382.222713) (xy 344.20482 -382.222713) (xy 344.204821 -382.15727) (xy 344.213615 -382.09242)
			(xy 344.231042 -382.029339) (xy 344.256786 -381.969172) (xy 344.273124 -381.940816) (xy 344.276435 -381.934789)
			(xy 344.280042 -381.921527) (xy 344.280236 -381.914654) (xy 344.280236 -381.628904) (xy 344.280626 -381.618746)
			(xy 344.288427 -381.599986) (xy 344.302834 -381.585662) (xy 344.321637 -381.577968) (xy 344.331798 -381.577596)
			(xy 345.048078 -381.577596) (xy 345.058198 -381.578143) (xy 345.07691 -381.585856) (xy 345.091266 -381.600123)
			(xy 345.099094 -381.618787) (xy 345.09964 -381.628904) (xy 345.09964 -381.914654) (xy 345.099844 -381.921526)
			(xy 345.103444 -381.934789) (xy 345.106752 -381.940816) (xy 345.123081 -381.969177) (xy 345.148826 -382.029342)
			(xy 345.166254 -382.092421) (xy 345.175048 -382.15727) (xy 345.175048 -382.18999) (xy 348.603832 -382.18999)
			(xy 348.607823 -382.127823) (xy 348.619732 -382.066676) (xy 348.639361 -382.007555) (xy 348.66639 -381.951429)
			(xy 348.700374 -381.89922) (xy 348.740756 -381.851785) (xy 348.786872 -381.809904) (xy 348.837964 -381.774264)
			(xy 348.893195 -381.74545) (xy 348.951657 -381.723936) (xy 349.012391 -381.710074) (xy 349.074398 -381.704092)
			(xy 349.136661 -381.706088) (xy 349.188701 -381.714502) (xy 360.796838 -381.714502) (xy 360.800909 -381.65888)
			(xy 360.813035 -381.604443) (xy 360.832958 -381.552352) (xy 360.860254 -381.503717) (xy 360.89434 -381.459574)
			(xy 360.934489 -381.420865) (xy 360.979847 -381.388414) (xy 361.029447 -381.362913) (xy 361.082231 -381.344906)
			(xy 361.137074 -381.334776) (xy 361.192808 -381.332739) (xy 361.248245 -381.338839) (xy 361.302202 -381.352945)
			(xy 361.353531 -381.374757) (xy 361.401137 -381.403811) (xy 361.444005 -381.439486) (xy 361.481222 -381.481023)
			(xy 361.511995 -381.527536) (xy 361.535667 -381.578033) (xy 361.551735 -381.63144) (xy 361.559855 -381.686616)
			(xy 361.560364 -381.714502) (xy 361.559855 -381.742388) (xy 361.551735 -381.797564) (xy 361.535667 -381.850971)
			(xy 361.511995 -381.901468) (xy 361.481222 -381.947981) (xy 361.444005 -381.989518) (xy 361.401137 -382.025193)
			(xy 361.353531 -382.054247) (xy 361.302202 -382.076059) (xy 361.248245 -382.090165) (xy 361.192808 -382.096265)
			(xy 361.137074 -382.094228) (xy 361.082231 -382.084098) (xy 361.029447 -382.066091) (xy 360.979847 -382.04059)
			(xy 360.934489 -382.008139) (xy 360.89434 -381.96943) (xy 360.860254 -381.925287) (xy 360.832958 -381.876652)
			(xy 360.813035 -381.824561) (xy 360.800909 -381.770124) (xy 360.796838 -381.714502) (xy 349.188701 -381.714502)
			(xy 349.198158 -381.716031) (xy 349.257879 -381.733755) (xy 349.314842 -381.758972) (xy 349.368113 -381.791265)
			(xy 349.416818 -381.830105) (xy 349.460155 -381.874855) (xy 349.497415 -381.924779) (xy 349.527984 -381.979058)
			(xy 349.551362 -382.036801) (xy 349.567163 -382.097059) (xy 349.575129 -382.158842) (xy 349.575628 -382.18999)
			(xy 349.575129 -382.221138) (xy 349.567163 -382.282921) (xy 349.551362 -382.343179) (xy 349.527984 -382.400922)
			(xy 349.497415 -382.455201) (xy 349.460155 -382.505125) (xy 349.416818 -382.549875) (xy 349.368113 -382.588715)
			(xy 349.314842 -382.621008) (xy 349.257879 -382.646225) (xy 349.198158 -382.663949) (xy 349.136661 -382.673892)
			(xy 349.074398 -382.675888) (xy 349.012391 -382.669906) (xy 348.951657 -382.656044) (xy 348.893195 -382.63453)
			(xy 348.837964 -382.605716) (xy 348.786872 -382.570076) (xy 348.740756 -382.528195) (xy 348.700374 -382.48076)
			(xy 348.66639 -382.428551) (xy 348.639361 -382.372425) (xy 348.619732 -382.313304) (xy 348.607823 -382.252157)
			(xy 348.603832 -382.18999) (xy 345.175048 -382.18999) (xy 345.175049 -382.222713) (xy 345.166257 -382.287562)
			(xy 345.148832 -382.350641) (xy 345.123089 -382.410808) (xy 345.106752 -382.439164) (xy 345.103454 -382.445197)
			(xy 345.099837 -382.458454) (xy 345.09964 -382.465326) (xy 345.09964 -383.21488) (xy 345.099835 -383.221753)
			(xy 345.103441 -383.235016) (xy 345.106752 -383.241042) (xy 345.123103 -383.269391) (xy 345.145951 -383.322792)
			(xy 346.404946 -383.322792) (xy 346.40495 -383.257346) (xy 346.413748 -383.192494) (xy 346.431181 -383.129413)
			(xy 346.456931 -383.069246) (xy 346.473272 -383.04089) (xy 346.476588 -383.034866) (xy 346.480193 -383.021602)
			(xy 346.480384 -383.014728) (xy 346.480384 -382.728724) (xy 346.480841 -382.718573) (xy 346.488625 -382.699825)
			(xy 346.503011 -382.685501) (xy 346.521794 -382.677797) (xy 346.531946 -382.677416) (xy 347.248226 -382.677416)
			(xy 347.258351 -382.677904) (xy 347.277069 -382.685636) (xy 347.291423 -382.699921) (xy 347.299246 -382.718601)
			(xy 347.299788 -382.728724) (xy 347.299788 -383.014728) (xy 347.299971 -383.021602) (xy 347.303585 -383.034865)
			(xy 347.3069 -383.04089) (xy 347.323206 -383.069263) (xy 347.34895 -383.129427) (xy 347.366379 -383.192503)
			(xy 347.375175 -383.257349) (xy 347.375179 -383.322789) (xy 347.366391 -383.387636) (xy 347.348971 -383.450715)
			(xy 347.332074 -383.490216) (xy 348.603832 -383.490216) (xy 348.607823 -383.428049) (xy 348.619732 -383.366902)
			(xy 348.639361 -383.307781) (xy 348.66639 -383.251655) (xy 348.700374 -383.199446) (xy 348.740756 -383.152011)
			(xy 348.786872 -383.11013) (xy 348.837964 -383.07449) (xy 348.893195 -383.045676) (xy 348.951657 -383.024162)
			(xy 349.012391 -383.0103) (xy 349.074398 -383.004318) (xy 349.136661 -383.006314) (xy 349.198158 -383.016257)
			(xy 349.257879 -383.033981) (xy 349.314842 -383.059198) (xy 349.368113 -383.091491) (xy 349.416818 -383.130331)
			(xy 349.460155 -383.175081) (xy 349.497415 -383.225005) (xy 349.527984 -383.279284) (xy 349.532348 -383.290064)
			(xy 350.80398 -383.290064) (xy 350.807971 -383.227897) (xy 350.81988 -383.16675) (xy 350.839509 -383.107629)
			(xy 350.866538 -383.051503) (xy 350.900522 -382.999294) (xy 350.940904 -382.951859) (xy 350.98702 -382.909978)
			(xy 351.038112 -382.874338) (xy 351.093343 -382.845524) (xy 351.151805 -382.82401) (xy 351.212539 -382.810148)
			(xy 351.274546 -382.804166) (xy 351.336809 -382.806162) (xy 351.398306 -382.816105) (xy 351.458027 -382.833829)
			(xy 351.51499 -382.859046) (xy 351.568261 -382.891339) (xy 351.616966 -382.930179) (xy 351.660303 -382.974929)
			(xy 351.697563 -383.024853) (xy 351.728132 -383.079132) (xy 351.75151 -383.136875) (xy 351.767311 -383.197133)
			(xy 351.775277 -383.258916) (xy 351.775776 -383.290064) (xy 351.775277 -383.321212) (xy 351.767311 -383.382995)
			(xy 351.75151 -383.443253) (xy 351.728132 -383.500996) (xy 351.697563 -383.555275) (xy 351.660303 -383.605199)
			(xy 351.616966 -383.649949) (xy 351.568261 -383.688789) (xy 351.51499 -383.721082) (xy 351.458027 -383.746299)
			(xy 351.398306 -383.764023) (xy 351.336809 -383.773966) (xy 351.274546 -383.775962) (xy 351.212539 -383.76998)
			(xy 351.151805 -383.756118) (xy 351.093343 -383.734604) (xy 351.038112 -383.70579) (xy 350.98702 -383.67015)
			(xy 350.940904 -383.628269) (xy 350.900522 -383.580834) (xy 350.866538 -383.528625) (xy 350.839509 -383.472499)
			(xy 350.81988 -383.413378) (xy 350.807971 -383.352231) (xy 350.80398 -383.290064) (xy 349.532348 -383.290064)
			(xy 349.551362 -383.337027) (xy 349.567163 -383.397285) (xy 349.575129 -383.459068) (xy 349.575628 -383.490216)
			(xy 349.575129 -383.521364) (xy 349.567163 -383.583147) (xy 349.551362 -383.643405) (xy 349.527984 -383.701148)
			(xy 349.497415 -383.755427) (xy 349.460155 -383.805351) (xy 349.416818 -383.850101) (xy 349.368113 -383.888941)
			(xy 349.314842 -383.921234) (xy 349.257879 -383.946451) (xy 349.198158 -383.964175) (xy 349.136661 -383.974118)
			(xy 349.074398 -383.976114) (xy 349.012391 -383.970132) (xy 348.951657 -383.95627) (xy 348.893195 -383.934756)
			(xy 348.837964 -383.905942) (xy 348.786872 -383.870302) (xy 348.740756 -383.828421) (xy 348.700374 -383.780986)
			(xy 348.66639 -383.728777) (xy 348.639361 -383.672651) (xy 348.619732 -383.61353) (xy 348.607823 -383.552383)
			(xy 348.603832 -383.490216) (xy 347.332074 -383.490216) (xy 347.323234 -383.510881) (xy 347.3069 -383.539238)
			(xy 347.303572 -383.545256) (xy 347.299975 -383.558525) (xy 347.299788 -383.5654) (xy 347.299788 -384.3147)
			(xy 347.299981 -384.321573) (xy 347.303589 -384.334836) (xy 347.3069 -384.340862) (xy 347.323267 -384.369202)
			(xy 347.349006 -384.429373) (xy 347.366427 -384.492456) (xy 347.375216 -384.557308) (xy 347.375214 -384.590036)
			(xy 350.80398 -384.590036) (xy 350.807971 -384.527869) (xy 350.81988 -384.466722) (xy 350.839509 -384.407601)
			(xy 350.866538 -384.351475) (xy 350.900522 -384.299266) (xy 350.940904 -384.251831) (xy 350.98702 -384.20995)
			(xy 351.038112 -384.17431) (xy 351.093343 -384.145496) (xy 351.151805 -384.123982) (xy 351.212539 -384.11012)
			(xy 351.274546 -384.104138) (xy 351.336809 -384.106134) (xy 351.398306 -384.116077) (xy 351.458027 -384.133801)
			(xy 351.51499 -384.159018) (xy 351.568261 -384.191311) (xy 351.616966 -384.230151) (xy 351.660303 -384.274901)
			(xy 351.697563 -384.324825) (xy 351.728132 -384.379104) (xy 351.75151 -384.436847) (xy 351.767311 -384.497105)
			(xy 351.775277 -384.558888) (xy 351.775776 -384.590036) (xy 351.775277 -384.621184) (xy 351.767311 -384.682967)
			(xy 351.75151 -384.743225) (xy 351.728132 -384.800968) (xy 351.697563 -384.855247) (xy 351.660303 -384.905171)
			(xy 351.616966 -384.949921) (xy 351.568261 -384.988761) (xy 351.51499 -385.021054) (xy 351.458027 -385.046271)
			(xy 351.398306 -385.063995) (xy 351.336809 -385.073938) (xy 351.274546 -385.075934) (xy 351.212539 -385.069952)
			(xy 351.151805 -385.05609) (xy 351.093343 -385.034576) (xy 351.038112 -385.005762) (xy 350.98702 -384.970122)
			(xy 350.940904 -384.928241) (xy 350.900522 -384.880806) (xy 350.866538 -384.828597) (xy 350.839509 -384.772471)
			(xy 350.81988 -384.71335) (xy 350.807971 -384.652203) (xy 350.80398 -384.590036) (xy 347.375214 -384.590036)
			(xy 347.375212 -384.622753) (xy 347.366415 -384.687604) (xy 347.348985 -384.750686) (xy 347.323239 -384.810853)
			(xy 347.3069 -384.83921) (xy 347.303582 -384.845233) (xy 347.299978 -384.858498) (xy 347.299788 -384.865372)
			(xy 347.299788 -385.151376) (xy 347.299359 -385.16153) (xy 347.291569 -385.180284) (xy 347.277174 -385.194609)
			(xy 347.258382 -385.202307) (xy 347.248226 -385.202684) (xy 346.531946 -385.202684) (xy 346.521825 -385.202136)
			(xy 346.50311 -385.194428) (xy 346.488753 -385.180161) (xy 346.480928 -385.161494) (xy 346.480384 -385.151376)
			(xy 346.480384 -384.865372) (xy 346.480205 -384.858498) (xy 346.476588 -384.845235) (xy 346.473272 -384.83921)
			(xy 346.456964 -384.810837) (xy 346.431216 -384.750675) (xy 346.413785 -384.687598) (xy 346.404987 -384.622751)
			(xy 346.404983 -384.55731) (xy 346.413772 -384.492462) (xy 346.431195 -384.429384) (xy 346.456936 -384.369218)
			(xy 346.473272 -384.340862) (xy 346.476598 -384.334843) (xy 346.480197 -384.321575) (xy 346.480384 -384.3147)
			(xy 346.480384 -383.5654) (xy 346.480194 -383.558527) (xy 346.476584 -383.545264) (xy 346.473272 -383.539238)
			(xy 346.456903 -383.510899) (xy 346.43116 -383.450729) (xy 346.413736 -383.387645) (xy 346.404946 -383.322792)
			(xy 345.145951 -383.322792) (xy 345.148846 -383.329559) (xy 345.166272 -383.392641) (xy 345.175063 -383.457492)
			(xy 345.175061 -383.522936) (xy 345.166266 -383.587786) (xy 345.148837 -383.650867) (xy 345.123091 -383.711034)
			(xy 345.106752 -383.73939) (xy 345.103445 -383.745418) (xy 345.099834 -383.758679) (xy 345.09964 -383.765552)
			(xy 345.09964 -384.051556) (xy 345.099143 -384.061702) (xy 345.09137 -384.080446) (xy 345.076996 -384.094769)
			(xy 345.058226 -384.102478) (xy 345.048078 -384.102864) (xy 344.331798 -384.102864) (xy 344.321672 -384.102375)
			(xy 344.302951 -384.094647) (xy 344.288595 -384.080362) (xy 344.280775 -384.06168) (xy 344.280236 -384.051556)
			(xy 344.280236 -383.765552) (xy 344.28002 -383.758681) (xy 344.276428 -383.745418) (xy 344.273124 -383.73939)
			(xy 344.256801 -383.711026) (xy 344.231056 -383.650861) (xy 344.213629 -383.587783) (xy 344.204835 -383.522935)
			(xy 344.204833 -383.457493) (xy 344.213623 -383.392644) (xy 344.231047 -383.329565) (xy 344.256788 -383.269398)
			(xy 344.273124 -383.241042) (xy 344.276426 -383.235011) (xy 344.280039 -383.221752) (xy 344.280236 -383.21488)
			(xy 344.280236 -382.465326) (xy 344.28003 -382.458454) (xy 344.276431 -382.445191) (xy 344.273124 -382.439164)
			(xy 344.256779 -382.410812) (xy 344.231036 -382.350644) (xy 344.213611 -382.287563) (xy 344.20482 -382.222713)
			(xy 340.77526 -382.222713) (xy 340.766468 -382.287562) (xy 340.749043 -382.350641) (xy 340.723301 -382.410808)
			(xy 340.706964 -382.439164) (xy 340.703667 -382.445197) (xy 340.700049 -382.458454) (xy 340.699852 -382.465326)
			(xy 340.699852 -383.21488) (xy 340.700045 -383.221753) (xy 340.703652 -383.235016) (xy 340.706964 -383.241042)
			(xy 340.723315 -383.269391) (xy 340.746162 -383.322792) (xy 342.00491 -383.322792) (xy 342.004914 -383.257346)
			(xy 342.013711 -383.192495) (xy 342.031142 -383.129414) (xy 342.056891 -383.069246) (xy 342.07323 -383.04089)
			(xy 342.076596 -383.034876) (xy 342.080331 -383.021615) (xy 342.080596 -383.014728) (xy 342.080596 -382.728724)
			(xy 342.081035 -382.718604) (xy 342.088775 -382.699901) (xy 342.103084 -382.685586) (xy 342.121784 -382.677839)
			(xy 342.131904 -382.677416) (xy 342.848184 -382.677416) (xy 342.858307 -382.677829) (xy 342.877014 -382.685575)
			(xy 342.891329 -382.699893) (xy 342.899072 -382.7186) (xy 342.899492 -382.728724) (xy 342.899492 -383.014728)
			(xy 342.899754 -383.021617) (xy 342.903477 -383.034883) (xy 342.906858 -383.04089) (xy 342.923165 -383.069263)
			(xy 342.948912 -383.129426) (xy 342.966342 -383.192502) (xy 342.975139 -383.257349) (xy 342.975143 -383.322789)
			(xy 342.966354 -383.387637) (xy 342.948932 -383.450716) (xy 342.923193 -383.510882) (xy 342.906858 -383.539238)
			(xy 342.903481 -383.545247) (xy 342.899754 -383.558512) (xy 342.899492 -383.5654) (xy 342.899492 -384.3147)
			(xy 342.899726 -384.321591) (xy 342.903468 -384.334857) (xy 342.906858 -384.340862) (xy 342.923226 -384.369201)
			(xy 342.948967 -384.429372) (xy 342.96639 -384.492456) (xy 342.97518 -384.557308) (xy 342.975175 -384.622754)
			(xy 342.966378 -384.687605) (xy 342.948947 -384.750686) (xy 342.923198 -384.810854) (xy 342.906858 -384.83921)
			(xy 342.903491 -384.845224) (xy 342.899757 -384.858485) (xy 342.899492 -384.865372) (xy 342.899492 -385.151376)
			(xy 342.899064 -385.161498) (xy 342.891323 -385.180203) (xy 342.877009 -385.194518) (xy 342.858306 -385.202263)
			(xy 342.848184 -385.202684) (xy 342.131904 -385.202684) (xy 342.12178 -385.20228) (xy 342.103073 -385.194531)
			(xy 342.088758 -385.18021) (xy 342.081016 -385.1615) (xy 342.080596 -385.151376) (xy 342.080596 -384.865372)
			(xy 342.080336 -384.858483) (xy 342.076612 -384.845217) (xy 342.07323 -384.83921) (xy 342.056923 -384.810837)
			(xy 342.031177 -384.750674) (xy 342.013748 -384.687597) (xy 342.004951 -384.622751) (xy 342.004947 -384.557311)
			(xy 342.013735 -384.492463) (xy 342.031157 -384.429384) (xy 342.056895 -384.369218) (xy 342.07323 -384.340862)
			(xy 342.076606 -384.334853) (xy 342.080334 -384.321588) (xy 342.080596 -384.3147) (xy 342.080596 -383.5654)
			(xy 342.080363 -383.558509) (xy 342.076621 -383.545243) (xy 342.07323 -383.539238) (xy 342.056862 -383.510899)
			(xy 342.031122 -383.450728) (xy 342.013699 -383.387644) (xy 342.00491 -383.322792) (xy 340.746162 -383.322792)
			(xy 340.749057 -383.329559) (xy 340.766482 -383.392641) (xy 340.775273 -383.457492) (xy 340.775271 -383.522936)
			(xy 340.766477 -383.587786) (xy 340.749048 -383.650867) (xy 340.723302 -383.711034) (xy 340.706964 -383.73939)
			(xy 340.703658 -383.745419) (xy 340.700046 -383.758679) (xy 340.699852 -383.765552) (xy 340.699852 -384.051556)
			(xy 340.699343 -384.061701) (xy 340.691572 -384.080442) (xy 340.677202 -384.094765) (xy 340.658436 -384.102476)
			(xy 340.64829 -384.102864) (xy 339.93201 -384.102864) (xy 339.921884 -384.102365) (xy 339.903164 -384.094642)
			(xy 339.888808 -384.080359) (xy 339.880987 -384.061679) (xy 339.880448 -384.051556) (xy 339.880448 -383.765552)
			(xy 339.880243 -383.75868) (xy 339.876644 -383.745417) (xy 339.873336 -383.73939) (xy 339.857012 -383.711026)
			(xy 339.831267 -383.650861) (xy 339.813839 -383.587783) (xy 339.805045 -383.522935) (xy 339.805043 -383.457493)
			(xy 339.813834 -383.392644) (xy 339.831258 -383.329565) (xy 339.857 -383.269398) (xy 339.873336 -383.241042)
			(xy 339.876631 -383.235007) (xy 339.88025 -383.221751) (xy 339.880448 -383.21488) (xy 339.880448 -382.465326)
			(xy 339.880253 -382.458453) (xy 339.876647 -382.44519) (xy 339.873336 -382.439164) (xy 339.85699 -382.410812)
			(xy 339.831247 -382.350645) (xy 339.813822 -382.287564) (xy 339.80503 -382.222713) (xy 336.375224 -382.222713)
			(xy 336.366431 -382.287562) (xy 336.349005 -382.350642) (xy 336.32326 -382.410808) (xy 336.306922 -382.439164)
			(xy 336.303568 -382.445184) (xy 336.299826 -382.458441) (xy 336.299556 -382.465326) (xy 336.299556 -383.21488)
			(xy 336.299768 -383.221775) (xy 336.303511 -383.235046) (xy 336.306922 -383.241042) (xy 336.323274 -383.26939)
			(xy 336.346124 -383.322792) (xy 337.60486 -383.322792) (xy 337.604864 -383.257346) (xy 337.613662 -383.192494)
			(xy 337.631095 -383.129413) (xy 337.656847 -383.069246) (xy 337.673188 -383.04089) (xy 337.676505 -383.034867)
			(xy 337.68011 -383.021602) (xy 337.6803 -383.014728) (xy 337.6803 -382.728724) (xy 337.680741 -382.718571)
			(xy 337.688529 -382.699819) (xy 337.70292 -382.685495) (xy 337.721708 -382.677795) (xy 337.731862 -382.677416)
			(xy 338.448142 -382.677416) (xy 338.458268 -382.677891) (xy 338.476986 -382.685629) (xy 338.49134 -382.699918)
			(xy 338.499162 -382.7186) (xy 338.499704 -382.728724) (xy 338.499704 -383.014728) (xy 338.499885 -383.021602)
			(xy 338.5035 -383.034865) (xy 338.506816 -383.04089) (xy 338.523124 -383.069263) (xy 338.548873 -383.129425)
			(xy 338.566305 -383.192502) (xy 338.575102 -383.257349) (xy 338.575107 -383.32279) (xy 338.566317 -383.387638)
			(xy 338.548894 -383.450717) (xy 338.523152 -383.510882) (xy 338.506816 -383.539238) (xy 338.503489 -383.545257)
			(xy 338.499891 -383.558525) (xy 338.499704 -383.5654) (xy 338.499704 -384.3147) (xy 338.499895 -384.321573)
			(xy 338.503504 -384.334836) (xy 338.506816 -384.340862) (xy 338.523185 -384.369201) (xy 338.548929 -384.429371)
			(xy 338.566353 -384.492455) (xy 338.575143 -384.557308) (xy 338.575139 -384.622754) (xy 338.566341 -384.687606)
			(xy 338.548908 -384.750687) (xy 338.523157 -384.810854) (xy 338.506816 -384.83921) (xy 338.503499 -384.845233)
			(xy 338.499894 -384.858498) (xy 338.499704 -384.865372) (xy 338.499704 -385.151376) (xy 338.499259 -385.161528)
			(xy 338.491472 -385.180279) (xy 338.477082 -385.194603) (xy 338.458296 -385.202305) (xy 338.448142 -385.202684)
			(xy 337.731862 -385.202684) (xy 337.721736 -385.202205) (xy 337.703018 -385.194469) (xy 337.688664 -385.180181)
			(xy 337.680842 -385.1615) (xy 337.6803 -385.151376) (xy 337.6803 -384.865372) (xy 337.680119 -384.858498)
			(xy 337.676503 -384.845235) (xy 337.673188 -384.83921) (xy 337.65688 -384.810838) (xy 337.63113 -384.750675)
			(xy 337.613699 -384.687598) (xy 337.604901 -384.622751) (xy 337.604897 -384.55731) (xy 337.613686 -384.492462)
			(xy 337.63111 -384.429383) (xy 337.656852 -384.369218) (xy 337.673188 -384.340862) (xy 337.676515 -384.334844)
			(xy 337.680113 -384.321575) (xy 337.6803 -384.3147) (xy 337.6803 -383.5654) (xy 337.680108 -383.558527)
			(xy 337.6765 -383.545264) (xy 337.673188 -383.539238) (xy 337.656819 -383.510899) (xy 337.631075 -383.450729)
			(xy 337.61365 -383.387645) (xy 337.60486 -383.322792) (xy 336.346124 -383.322792) (xy 336.349019 -383.329558)
			(xy 336.366445 -383.39264) (xy 336.375237 -383.457491) (xy 336.375235 -383.522936) (xy 336.36644 -383.587787)
			(xy 336.34901 -383.650868) (xy 336.323262 -383.711034) (xy 336.306922 -383.73939) (xy 336.303559 -383.745406)
			(xy 336.299823 -383.758666) (xy 336.299556 -383.765552) (xy 336.299556 -384.051556) (xy 336.29898 -384.061655)
			(xy 336.291267 -384.080321) (xy 336.276999 -384.094616) (xy 336.258346 -384.102362) (xy 336.248248 -384.102864)
			(xy 335.531968 -384.102864) (xy 335.521839 -384.102509) (xy 335.503128 -384.094744) (xy 335.488813 -384.080408)
			(xy 335.481076 -384.061686) (xy 335.48066 -384.051556) (xy 335.48066 -383.765552) (xy 335.480434 -383.758659)
			(xy 335.476701 -383.745387) (xy 335.473294 -383.73939) (xy 335.456972 -383.711026) (xy 335.431229 -383.650861)
			(xy 335.413803 -383.587782) (xy 335.405009 -383.522934) (xy 335.405007 -383.457493) (xy 335.413797 -383.392645)
			(xy 335.43122 -383.329565) (xy 335.456959 -383.269399) (xy 335.473294 -383.241042) (xy 335.476674 -383.235035)
			(xy 335.4804 -383.221769) (xy 335.48066 -383.21488) (xy 335.48066 -382.465326) (xy 335.480444 -382.458432)
			(xy 335.476704 -382.44516) (xy 335.473294 -382.439164) (xy 335.45695 -382.410812) (xy 335.431209 -382.350644)
			(xy 335.413785 -382.287563) (xy 335.404994 -382.222713) (xy 331.975173 -382.222713) (xy 331.966382 -382.287561)
			(xy 331.948958 -382.350641) (xy 331.923216 -382.410808) (xy 331.90688 -382.439164) (xy 331.903577 -382.445194)
			(xy 331.899964 -382.458454) (xy 331.899768 -382.465326) (xy 331.899768 -383.21488) (xy 331.899972 -383.221752)
			(xy 331.903572 -383.235015) (xy 331.90688 -383.241042) (xy 331.92323 -383.269391) (xy 331.946076 -383.322792)
			(xy 333.204824 -383.322792) (xy 333.204828 -383.257346) (xy 333.213626 -383.192495) (xy 333.231057 -383.129413)
			(xy 333.256806 -383.069246) (xy 333.273146 -383.04089) (xy 333.276513 -383.034876) (xy 333.280247 -383.021615)
			(xy 333.280512 -383.014728) (xy 333.280512 -382.728724) (xy 333.280936 -382.718602) (xy 333.288678 -382.699896)
			(xy 333.302993 -382.685581) (xy 333.321698 -382.677837) (xy 333.33182 -382.677416) (xy 334.0481 -382.677416)
			(xy 334.058224 -382.677816) (xy 334.076931 -382.685568) (xy 334.091246 -382.699889) (xy 334.098988 -382.718599)
			(xy 334.099408 -382.728724) (xy 334.099408 -383.014728) (xy 334.099668 -383.021617) (xy 334.103392 -383.034883)
			(xy 334.106774 -383.04089) (xy 334.12308 -383.069263) (xy 334.148827 -383.129426) (xy 334.166256 -383.192503)
			(xy 334.175052 -383.257349) (xy 334.175056 -383.322789) (xy 334.166268 -383.387637) (xy 334.148847 -383.450716)
			(xy 334.123109 -383.510882) (xy 334.106774 -383.539238) (xy 334.103398 -383.545247) (xy 334.09967 -383.558512)
			(xy 334.099408 -383.5654) (xy 334.099408 -384.3147) (xy 334.09964 -384.321591) (xy 334.103383 -384.334857)
			(xy 334.106774 -384.340862) (xy 334.123141 -384.369201) (xy 334.148882 -384.429372) (xy 334.166304 -384.492456)
			(xy 334.175093 -384.557308) (xy 334.175089 -384.622753) (xy 334.166292 -384.687605) (xy 334.148861 -384.750686)
			(xy 334.123113 -384.810854) (xy 334.106774 -384.83921) (xy 334.103408 -384.845224) (xy 334.099673 -384.858485)
			(xy 334.099408 -384.865372) (xy 334.099408 -385.151376) (xy 334.098965 -385.161496) (xy 334.091226 -385.180198)
			(xy 334.076918 -385.194512) (xy 334.05822 -385.20226) (xy 334.0481 -385.202684) (xy 333.33182 -385.202684)
			(xy 333.321697 -385.202267) (xy 333.302991 -385.194523) (xy 333.288675 -385.180206) (xy 333.280932 -385.161499)
			(xy 333.280512 -385.151376) (xy 333.280512 -384.865372) (xy 333.280284 -384.858479) (xy 333.276553 -384.845207)
			(xy 333.273146 -384.83921) (xy 333.256839 -384.810837) (xy 333.231092 -384.750674) (xy 333.213662 -384.687598)
			(xy 333.204865 -384.622751) (xy 333.204861 -384.557311) (xy 333.213649 -384.492463) (xy 333.231071 -384.429384)
			(xy 333.256811 -384.369218) (xy 333.273146 -384.340862) (xy 333.276523 -384.334853) (xy 333.28025 -384.321588)
			(xy 333.280512 -384.3147) (xy 333.280512 -383.5654) (xy 333.280312 -383.558504) (xy 333.276562 -383.545232)
			(xy 333.273146 -383.539238) (xy 333.256778 -383.510899) (xy 333.231036 -383.450728) (xy 333.213613 -383.387645)
			(xy 333.204824 -383.322792) (xy 331.946076 -383.322792) (xy 331.948972 -383.32956) (xy 331.966396 -383.392641)
			(xy 331.975187 -383.457492) (xy 331.975185 -383.522936) (xy 331.966391 -383.587786) (xy 331.948963 -383.650866)
			(xy 331.923218 -383.711034) (xy 331.90688 -383.73939) (xy 331.903567 -383.745416) (xy 331.899961 -383.758679)
			(xy 331.899768 -383.765552) (xy 331.899768 -384.051556) (xy 331.899342 -384.061711) (xy 331.891555 -384.080469)
			(xy 331.877159 -384.094795) (xy 331.858363 -384.10249) (xy 331.848206 -384.102864) (xy 331.131926 -384.102864)
			(xy 331.121801 -384.102352) (xy 331.103082 -384.094634) (xy 331.088724 -384.080355) (xy 331.080904 -384.061678)
			(xy 331.080364 -384.051556) (xy 331.080364 -383.765552) (xy 331.080157 -383.75868) (xy 331.076559 -383.745417)
			(xy 331.073252 -383.73939) (xy 331.056928 -383.711026) (xy 331.031182 -383.650862) (xy 331.013754 -383.587783)
			(xy 331.004959 -383.522935) (xy 331.004957 -383.457493) (xy 331.013748 -383.392644) (xy 331.031173 -383.329564)
			(xy 331.056915 -383.269398) (xy 331.073252 -383.241042) (xy 331.076548 -383.235008) (xy 331.080166 -383.221752)
			(xy 331.080364 -383.21488) (xy 331.080364 -382.465326) (xy 331.080167 -382.458453) (xy 331.076563 -382.44519)
			(xy 331.073252 -382.439164) (xy 331.056906 -382.410813) (xy 331.031162 -382.350645) (xy 331.013736 -382.287564)
			(xy 331.004944 -382.222713) (xy 308.975506 -382.222713) (xy 308.975506 -385.98983) (xy 318.109598 -385.98983)
			(xy 318.113669 -385.934208) (xy 318.125795 -385.879771) (xy 318.145718 -385.82768) (xy 318.173014 -385.779045)
			(xy 318.2071 -385.734902) (xy 318.247249 -385.696193) (xy 318.292607 -385.663742) (xy 318.342207 -385.638241)
			(xy 318.394991 -385.620234) (xy 318.449834 -385.610104) (xy 318.505568 -385.608067) (xy 318.561005 -385.614167)
			(xy 318.614962 -385.628273) (xy 318.666291 -385.650085) (xy 318.713897 -385.679139) (xy 318.756765 -385.714814)
			(xy 318.793982 -385.756351) (xy 318.824755 -385.802864) (xy 318.848427 -385.853361) (xy 318.864495 -385.906768)
			(xy 318.872615 -385.961944) (xy 318.873124 -385.98983) (xy 318.872615 -386.017716) (xy 318.864495 -386.072892)
			(xy 318.848427 -386.126299) (xy 318.82679 -386.172456) (xy 361.296202 -386.172456) (xy 361.300273 -386.116834)
			(xy 361.312399 -386.062397) (xy 361.332322 -386.010306) (xy 361.359618 -385.961671) (xy 361.393704 -385.917528)
			(xy 361.433853 -385.878819) (xy 361.479211 -385.846368) (xy 361.528811 -385.820867) (xy 361.581595 -385.80286)
			(xy 361.636438 -385.79273) (xy 361.692172 -385.790693) (xy 361.747609 -385.796793) (xy 361.801566 -385.810899)
			(xy 361.852895 -385.832711) (xy 361.900501 -385.861765) (xy 361.943369 -385.89744) (xy 361.980586 -385.938977)
			(xy 362.011359 -385.98549) (xy 362.035031 -386.035987) (xy 362.051099 -386.089394) (xy 362.059219 -386.14457)
			(xy 362.059728 -386.172456) (xy 362.059219 -386.200342) (xy 362.051099 -386.255518) (xy 362.035031 -386.308925)
			(xy 362.011359 -386.359422) (xy 361.980586 -386.405935) (xy 361.943369 -386.447472) (xy 361.900501 -386.483147)
			(xy 361.852895 -386.512201) (xy 361.801566 -386.534013) (xy 361.747609 -386.548119) (xy 361.692172 -386.554219)
			(xy 361.636438 -386.552182) (xy 361.581595 -386.542052) (xy 361.528811 -386.524045) (xy 361.479211 -386.498544)
			(xy 361.433853 -386.466093) (xy 361.393704 -386.427384) (xy 361.359618 -386.383241) (xy 361.332322 -386.334606)
			(xy 361.312399 -386.282515) (xy 361.300273 -386.228078) (xy 361.296202 -386.172456) (xy 318.82679 -386.172456)
			(xy 318.824755 -386.176796) (xy 318.793982 -386.223309) (xy 318.756765 -386.264846) (xy 318.713897 -386.300521)
			(xy 318.666291 -386.329575) (xy 318.614962 -386.351387) (xy 318.561005 -386.365493) (xy 318.505568 -386.371593)
			(xy 318.449834 -386.369556) (xy 318.394991 -386.359426) (xy 318.342207 -386.341419) (xy 318.292607 -386.315918)
			(xy 318.247249 -386.283467) (xy 318.2071 -386.244758) (xy 318.173014 -386.200615) (xy 318.145718 -386.15198)
			(xy 318.125795 -386.099889) (xy 318.113669 -386.045452) (xy 318.109598 -385.98983) (xy 308.975506 -385.98983)
			(xy 308.975506 -388.06247) (xy 317.091058 -388.06247) (xy 317.095129 -388.006848) (xy 317.107255 -387.952411)
			(xy 317.127178 -387.90032) (xy 317.154474 -387.851685) (xy 317.18856 -387.807542) (xy 317.228709 -387.768833)
			(xy 317.274067 -387.736382) (xy 317.323667 -387.710881) (xy 317.376451 -387.692874) (xy 317.431294 -387.682744)
			(xy 317.487028 -387.680707) (xy 317.542465 -387.686807) (xy 317.596422 -387.700913) (xy 317.647751 -387.722725)
			(xy 317.695357 -387.751779) (xy 317.738225 -387.787454) (xy 317.775442 -387.828991) (xy 317.806215 -387.875504)
			(xy 317.829887 -387.926001) (xy 317.834952 -387.942836) (xy 320.392296 -387.942836) (xy 320.396367 -387.887214)
			(xy 320.408493 -387.832777) (xy 320.428416 -387.780686) (xy 320.455712 -387.732051) (xy 320.489798 -387.687908)
			(xy 320.529947 -387.649199) (xy 320.575305 -387.616748) (xy 320.624905 -387.591247) (xy 320.677689 -387.57324)
			(xy 320.732532 -387.56311) (xy 320.788266 -387.561073) (xy 320.843703 -387.567173) (xy 320.89766 -387.581279)
			(xy 320.948989 -387.603091) (xy 320.996595 -387.632145) (xy 321.039463 -387.66782) (xy 321.07668 -387.709357)
			(xy 321.107453 -387.75587) (xy 321.131125 -387.806367) (xy 321.147193 -387.859774) (xy 321.155313 -387.91495)
			(xy 321.155822 -387.942836) (xy 321.155313 -387.970722) (xy 321.155081 -387.9723) (xy 362.73308 -387.9723)
			(xy 362.737151 -387.916678) (xy 362.749277 -387.862241) (xy 362.7692 -387.81015) (xy 362.796496 -387.761515)
			(xy 362.830582 -387.717372) (xy 362.870731 -387.678663) (xy 362.916089 -387.646212) (xy 362.965689 -387.620711)
			(xy 363.018473 -387.602704) (xy 363.073316 -387.592574) (xy 363.12905 -387.590537) (xy 363.184487 -387.596637)
			(xy 363.238444 -387.610743) (xy 363.289773 -387.632555) (xy 363.337379 -387.661609) (xy 363.380247 -387.697284)
			(xy 363.417464 -387.738821) (xy 363.448237 -387.785334) (xy 363.471909 -387.835831) (xy 363.487977 -387.889238)
			(xy 363.496097 -387.944414) (xy 363.496606 -387.9723) (xy 363.496097 -388.000186) (xy 363.487977 -388.055362)
			(xy 363.471909 -388.108769) (xy 363.448237 -388.159266) (xy 363.417464 -388.205779) (xy 363.380247 -388.247316)
			(xy 363.337379 -388.282991) (xy 363.289773 -388.312045) (xy 363.238444 -388.333857) (xy 363.184487 -388.347963)
			(xy 363.12905 -388.354063) (xy 363.073316 -388.352026) (xy 363.018473 -388.341896) (xy 362.965689 -388.323889)
			(xy 362.916089 -388.298388) (xy 362.870731 -388.265937) (xy 362.830582 -388.227228) (xy 362.796496 -388.183085)
			(xy 362.7692 -388.13445) (xy 362.749277 -388.082359) (xy 362.737151 -388.027922) (xy 362.73308 -387.9723)
			(xy 321.155081 -387.9723) (xy 321.147193 -388.025898) (xy 321.131125 -388.079305) (xy 321.107453 -388.129802)
			(xy 321.07668 -388.176315) (xy 321.039463 -388.217852) (xy 320.996595 -388.253527) (xy 320.948989 -388.282581)
			(xy 320.89766 -388.304393) (xy 320.843703 -388.318499) (xy 320.788266 -388.324599) (xy 320.732532 -388.322562)
			(xy 320.677689 -388.312432) (xy 320.624905 -388.294425) (xy 320.575305 -388.268924) (xy 320.529947 -388.236473)
			(xy 320.489798 -388.197764) (xy 320.455712 -388.153621) (xy 320.428416 -388.104986) (xy 320.408493 -388.052895)
			(xy 320.396367 -387.998458) (xy 320.392296 -387.942836) (xy 317.834952 -387.942836) (xy 317.845955 -387.979408)
			(xy 317.854075 -388.034584) (xy 317.854584 -388.06247) (xy 317.854075 -388.090356) (xy 317.845955 -388.145532)
			(xy 317.829887 -388.198939) (xy 317.806215 -388.249436) (xy 317.775442 -388.295949) (xy 317.738225 -388.337486)
			(xy 317.695357 -388.373161) (xy 317.647751 -388.402215) (xy 317.596422 -388.424027) (xy 317.542465 -388.438133)
			(xy 317.487028 -388.444233) (xy 317.431294 -388.442196) (xy 317.376451 -388.432066) (xy 317.323667 -388.414059)
			(xy 317.274067 -388.388558) (xy 317.228709 -388.356107) (xy 317.18856 -388.317398) (xy 317.154474 -388.273255)
			(xy 317.127178 -388.22462) (xy 317.107255 -388.172529) (xy 317.095129 -388.118092) (xy 317.091058 -388.06247)
			(xy 308.975506 -388.06247) (xy 308.975506 -388.958836) (xy 318.203832 -388.958836) (xy 318.207903 -388.903214)
			(xy 318.220029 -388.848777) (xy 318.239952 -388.796686) (xy 318.267248 -388.748051) (xy 318.301334 -388.703908)
			(xy 318.341483 -388.665199) (xy 318.386841 -388.632748) (xy 318.436441 -388.607247) (xy 318.489225 -388.58924)
			(xy 318.544068 -388.57911) (xy 318.599802 -388.577073) (xy 318.655239 -388.583173) (xy 318.709196 -388.597279)
			(xy 318.760525 -388.619091) (xy 318.808131 -388.648145) (xy 318.850999 -388.68382) (xy 318.888216 -388.725357)
			(xy 318.918989 -388.77187) (xy 318.942661 -388.822367) (xy 318.958729 -388.875774) (xy 318.966849 -388.93095)
			(xy 318.967358 -388.958836) (xy 321.520564 -388.958836) (xy 321.524635 -388.903214) (xy 321.536761 -388.848777)
			(xy 321.556684 -388.796686) (xy 321.58398 -388.748051) (xy 321.618066 -388.703908) (xy 321.658215 -388.665199)
			(xy 321.703573 -388.632748) (xy 321.753173 -388.607247) (xy 321.805957 -388.58924) (xy 321.8608 -388.57911)
			(xy 321.916534 -388.577073) (xy 321.971971 -388.583173) (xy 322.025928 -388.597279) (xy 322.077257 -388.619091)
			(xy 322.124863 -388.648145) (xy 322.167731 -388.68382) (xy 322.204948 -388.725357) (xy 322.235721 -388.77187)
			(xy 322.259393 -388.822367) (xy 322.275461 -388.875774) (xy 322.283581 -388.93095) (xy 322.28409 -388.958836)
			(xy 322.283581 -388.986722) (xy 322.275461 -389.041898) (xy 322.259393 -389.095305) (xy 322.235721 -389.145802)
			(xy 322.204948 -389.192315) (xy 322.167731 -389.233852) (xy 322.124863 -389.269527) (xy 322.077257 -389.298581)
			(xy 322.025928 -389.320393) (xy 321.971971 -389.334499) (xy 321.916534 -389.340599) (xy 321.8608 -389.338562)
			(xy 321.805957 -389.328432) (xy 321.753173 -389.310425) (xy 321.703573 -389.284924) (xy 321.658215 -389.252473)
			(xy 321.618066 -389.213764) (xy 321.58398 -389.169621) (xy 321.556684 -389.120986) (xy 321.536761 -389.068895)
			(xy 321.524635 -389.014458) (xy 321.520564 -388.958836) (xy 318.967358 -388.958836) (xy 318.966849 -388.986722)
			(xy 318.958729 -389.041898) (xy 318.942661 -389.095305) (xy 318.918989 -389.145802) (xy 318.888216 -389.192315)
			(xy 318.850999 -389.233852) (xy 318.808131 -389.269527) (xy 318.760525 -389.298581) (xy 318.709196 -389.320393)
			(xy 318.655239 -389.334499) (xy 318.599802 -389.340599) (xy 318.544068 -389.338562) (xy 318.489225 -389.328432)
			(xy 318.436441 -389.310425) (xy 318.386841 -389.284924) (xy 318.341483 -389.252473) (xy 318.301334 -389.213764)
			(xy 318.267248 -389.169621) (xy 318.239952 -389.120986) (xy 318.220029 -389.068895) (xy 318.207903 -389.014458)
			(xy 318.203832 -388.958836) (xy 308.975506 -388.958836) (xy 308.975506 -389.974836) (xy 317.228218 -389.974836)
			(xy 317.232289 -389.919214) (xy 317.244415 -389.864777) (xy 317.264338 -389.812686) (xy 317.291634 -389.764051)
			(xy 317.32572 -389.719908) (xy 317.365869 -389.681199) (xy 317.411227 -389.648748) (xy 317.460827 -389.623247)
			(xy 317.513611 -389.60524) (xy 317.568454 -389.59511) (xy 317.624188 -389.593073) (xy 317.679625 -389.599173)
			(xy 317.733582 -389.613279) (xy 317.784911 -389.635091) (xy 317.832517 -389.664145) (xy 317.875385 -389.69982)
			(xy 317.912602 -389.741357) (xy 317.943375 -389.78787) (xy 317.967047 -389.838367) (xy 317.983115 -389.891774)
			(xy 317.991235 -389.94695) (xy 317.991744 -389.974836) (xy 320.392296 -389.974836) (xy 320.396367 -389.919214)
			(xy 320.408493 -389.864777) (xy 320.428416 -389.812686) (xy 320.455712 -389.764051) (xy 320.489798 -389.719908)
			(xy 320.529947 -389.681199) (xy 320.575305 -389.648748) (xy 320.624905 -389.623247) (xy 320.677689 -389.60524)
			(xy 320.732532 -389.59511) (xy 320.788266 -389.593073) (xy 320.843703 -389.599173) (xy 320.89766 -389.613279)
			(xy 320.948989 -389.635091) (xy 320.996595 -389.664145) (xy 321.039463 -389.69982) (xy 321.07668 -389.741357)
			(xy 321.107453 -389.78787) (xy 321.131125 -389.838367) (xy 321.147193 -389.891774) (xy 321.155313 -389.94695)
			(xy 321.155822 -389.974836) (xy 321.155313 -390.002722) (xy 321.147193 -390.057898) (xy 321.131125 -390.111305)
			(xy 321.107453 -390.161802) (xy 321.07668 -390.208315) (xy 321.039463 -390.249852) (xy 320.996595 -390.285527)
			(xy 320.991265 -390.28878) (xy 357.386126 -390.28878) (xy 357.390197 -390.233158) (xy 357.402323 -390.178721)
			(xy 357.422246 -390.12663) (xy 357.449542 -390.077995) (xy 357.483628 -390.033852) (xy 357.523777 -389.995143)
			(xy 357.569135 -389.962692) (xy 357.618735 -389.937191) (xy 357.671519 -389.919184) (xy 357.726362 -389.909054)
			(xy 357.782096 -389.907017) (xy 357.837533 -389.913117) (xy 357.89149 -389.927223) (xy 357.942819 -389.949035)
			(xy 357.990425 -389.978089) (xy 358.033293 -390.013764) (xy 358.07051 -390.055301) (xy 358.101283 -390.101814)
			(xy 358.124955 -390.152311) (xy 358.141023 -390.205718) (xy 358.149143 -390.260894) (xy 358.149652 -390.28878)
			(xy 358.149143 -390.316666) (xy 358.141023 -390.371842) (xy 358.124955 -390.425249) (xy 358.101283 -390.475746)
			(xy 358.07051 -390.522259) (xy 358.033293 -390.563796) (xy 357.990425 -390.599471) (xy 357.942819 -390.628525)
			(xy 357.89149 -390.650337) (xy 357.837533 -390.664443) (xy 357.782096 -390.670543) (xy 357.726362 -390.668506)
			(xy 357.671519 -390.658376) (xy 357.618735 -390.640369) (xy 357.569135 -390.614868) (xy 357.523777 -390.582417)
			(xy 357.483628 -390.543708) (xy 357.449542 -390.499565) (xy 357.422246 -390.45093) (xy 357.402323 -390.398839)
			(xy 357.390197 -390.344402) (xy 357.386126 -390.28878) (xy 320.991265 -390.28878) (xy 320.948989 -390.314581)
			(xy 320.89766 -390.336393) (xy 320.843703 -390.350499) (xy 320.788266 -390.356599) (xy 320.732532 -390.354562)
			(xy 320.677689 -390.344432) (xy 320.624905 -390.326425) (xy 320.575305 -390.300924) (xy 320.529947 -390.268473)
			(xy 320.489798 -390.229764) (xy 320.455712 -390.185621) (xy 320.428416 -390.136986) (xy 320.408493 -390.084895)
			(xy 320.396367 -390.030458) (xy 320.392296 -389.974836) (xy 317.991744 -389.974836) (xy 317.991235 -390.002722)
			(xy 317.983115 -390.057898) (xy 317.967047 -390.111305) (xy 317.943375 -390.161802) (xy 317.912602 -390.208315)
			(xy 317.875385 -390.249852) (xy 317.832517 -390.285527) (xy 317.784911 -390.314581) (xy 317.733582 -390.336393)
			(xy 317.679625 -390.350499) (xy 317.624188 -390.356599) (xy 317.568454 -390.354562) (xy 317.513611 -390.344432)
			(xy 317.460827 -390.326425) (xy 317.411227 -390.300924) (xy 317.365869 -390.268473) (xy 317.32572 -390.229764)
			(xy 317.291634 -390.185621) (xy 317.264338 -390.136986) (xy 317.244415 -390.084895) (xy 317.232289 -390.030458)
			(xy 317.228218 -389.974836) (xy 308.975506 -389.974836) (xy 308.975506 -390.990836) (xy 318.203832 -390.990836)
			(xy 318.207903 -390.935214) (xy 318.220029 -390.880777) (xy 318.239952 -390.828686) (xy 318.267248 -390.780051)
			(xy 318.301334 -390.735908) (xy 318.341483 -390.697199) (xy 318.386841 -390.664748) (xy 318.436441 -390.639247)
			(xy 318.489225 -390.62124) (xy 318.544068 -390.61111) (xy 318.599802 -390.609073) (xy 318.655239 -390.615173)
			(xy 318.709196 -390.629279) (xy 318.760525 -390.651091) (xy 318.808131 -390.680145) (xy 318.850999 -390.71582)
			(xy 318.888216 -390.757357) (xy 318.918989 -390.80387) (xy 318.942661 -390.854367) (xy 318.958729 -390.907774)
			(xy 318.966849 -390.96295) (xy 318.967358 -390.990836) (xy 321.482464 -390.990836) (xy 321.486535 -390.935214)
			(xy 321.498661 -390.880777) (xy 321.518584 -390.828686) (xy 321.54588 -390.780051) (xy 321.579966 -390.735908)
			(xy 321.620115 -390.697199) (xy 321.665473 -390.664748) (xy 321.715073 -390.639247) (xy 321.767857 -390.62124)
			(xy 321.8227 -390.61111) (xy 321.878434 -390.609073) (xy 321.933871 -390.615173) (xy 321.987828 -390.629279)
			(xy 322.039157 -390.651091) (xy 322.086763 -390.680145) (xy 322.129631 -390.71582) (xy 322.166848 -390.757357)
			(xy 322.197621 -390.80387) (xy 322.221293 -390.854367) (xy 322.237361 -390.907774) (xy 322.245481 -390.96295)
			(xy 322.24599 -390.990836) (xy 322.245481 -391.018722) (xy 322.237361 -391.073898) (xy 322.221293 -391.127305)
			(xy 322.197621 -391.177802) (xy 322.166848 -391.224315) (xy 322.129631 -391.265852) (xy 322.086763 -391.301527)
			(xy 322.039157 -391.330581) (xy 321.987828 -391.352393) (xy 321.933871 -391.366499) (xy 321.878434 -391.372599)
			(xy 321.8227 -391.370562) (xy 321.767857 -391.360432) (xy 321.715073 -391.342425) (xy 321.665473 -391.316924)
			(xy 321.620115 -391.284473) (xy 321.579966 -391.245764) (xy 321.54588 -391.201621) (xy 321.518584 -391.152986)
			(xy 321.498661 -391.100895) (xy 321.486535 -391.046458) (xy 321.482464 -390.990836) (xy 318.967358 -390.990836)
			(xy 318.966849 -391.018722) (xy 318.958729 -391.073898) (xy 318.942661 -391.127305) (xy 318.918989 -391.177802)
			(xy 318.888216 -391.224315) (xy 318.850999 -391.265852) (xy 318.808131 -391.301527) (xy 318.760525 -391.330581)
			(xy 318.709196 -391.352393) (xy 318.655239 -391.366499) (xy 318.599802 -391.372599) (xy 318.544068 -391.370562)
			(xy 318.489225 -391.360432) (xy 318.436441 -391.342425) (xy 318.386841 -391.316924) (xy 318.341483 -391.284473)
			(xy 318.301334 -391.245764) (xy 318.267248 -391.201621) (xy 318.239952 -391.152986) (xy 318.220029 -391.100895)
			(xy 318.207903 -391.046458) (xy 318.203832 -390.990836) (xy 308.975506 -390.990836) (xy 308.975506 -392.684254)
			(xy 363.702852 -392.684254) (xy 363.706923 -392.628632) (xy 363.719049 -392.574195) (xy 363.738972 -392.522104)
			(xy 363.766268 -392.473469) (xy 363.800354 -392.429326) (xy 363.840503 -392.390617) (xy 363.885861 -392.358166)
			(xy 363.935461 -392.332665) (xy 363.988245 -392.314658) (xy 364.043088 -392.304528) (xy 364.098822 -392.302491)
			(xy 364.154259 -392.308591) (xy 364.208216 -392.322697) (xy 364.259545 -392.344509) (xy 364.307151 -392.373563)
			(xy 364.350019 -392.409238) (xy 364.387236 -392.450775) (xy 364.418009 -392.497288) (xy 364.441681 -392.547785)
			(xy 364.457749 -392.601192) (xy 364.465869 -392.656368) (xy 364.466378 -392.684254) (xy 364.465869 -392.71214)
			(xy 364.457749 -392.767316) (xy 364.441681 -392.820723) (xy 364.418009 -392.87122) (xy 364.387236 -392.917733)
			(xy 364.350019 -392.95927) (xy 364.307151 -392.994945) (xy 364.259545 -393.023999) (xy 364.208216 -393.045811)
			(xy 364.154259 -393.059917) (xy 364.098822 -393.066017) (xy 364.043088 -393.06398) (xy 363.988245 -393.05385)
			(xy 363.935461 -393.035843) (xy 363.885861 -393.010342) (xy 363.840503 -392.977891) (xy 363.800354 -392.939182)
			(xy 363.766268 -392.895039) (xy 363.738972 -392.846404) (xy 363.719049 -392.794313) (xy 363.706923 -392.739876)
			(xy 363.702852 -392.684254) (xy 308.975506 -392.684254) (xy 308.975506 -393.459716) (xy 357.18572 -393.459716)
			(xy 357.189791 -393.404094) (xy 357.201917 -393.349657) (xy 357.22184 -393.297566) (xy 357.249136 -393.248931)
			(xy 357.283222 -393.204788) (xy 357.323371 -393.166079) (xy 357.368729 -393.133628) (xy 357.418329 -393.108127)
			(xy 357.471113 -393.09012) (xy 357.525956 -393.07999) (xy 357.58169 -393.077953) (xy 357.637127 -393.084053)
			(xy 357.691084 -393.098159) (xy 357.742413 -393.119971) (xy 357.790019 -393.149025) (xy 357.832887 -393.1847)
			(xy 357.870104 -393.226237) (xy 357.900877 -393.27275) (xy 357.924549 -393.323247) (xy 357.940617 -393.376654)
			(xy 357.948737 -393.43183) (xy 357.949246 -393.459716) (xy 357.948737 -393.487602) (xy 357.940617 -393.542778)
			(xy 357.924549 -393.596185) (xy 357.900877 -393.646682) (xy 357.870104 -393.693195) (xy 357.832887 -393.734732)
			(xy 357.790019 -393.770407) (xy 357.742413 -393.799461) (xy 357.691084 -393.821273) (xy 357.637127 -393.835379)
			(xy 357.58169 -393.841479) (xy 357.525956 -393.839442) (xy 357.471113 -393.829312) (xy 357.418329 -393.811305)
			(xy 357.368729 -393.785804) (xy 357.323371 -393.753353) (xy 357.283222 -393.714644) (xy 357.249136 -393.670501)
			(xy 357.22184 -393.621866) (xy 357.201917 -393.569775) (xy 357.189791 -393.515338) (xy 357.18572 -393.459716)
			(xy 308.975506 -393.459716) (xy 308.975506 -413.54756) (xy 308.97594 -413.557625) (xy 308.983671 -413.576213)
			(xy 308.990492 -413.583628) (xy 311.76341 -416.356546) (xy 311.770806 -416.363397) (xy 311.789405 -416.371136)
			(xy 311.799478 -416.371532)
		)
		(stroke
			(width 0)
			(type solid)
		)
		(fill yes)
		(layer "In15.Cu")
		(net "GND")
	)
	(gr_poly
		(pts
			(xy 104.617266 -327.733406) (xy 104.626156 -327.73307) (xy 104.642862 -327.726983) (xy 104.656466 -327.715535)
			(xy 104.661208 -327.708006) (xy 104.712008 -327.620122) (xy 104.712008 -327.59269) (xy 104.70515 -327.581006)
			(xy 104.693009 -327.559209) (xy 104.673905 -327.513115) (xy 104.660983 -327.464922) (xy 104.654467 -327.415454)
			(xy 104.654096 -327.390506) (xy 104.654096 -327.390252) (xy 104.654582 -327.363001) (xy 104.662338 -327.309053)
			(xy 104.677693 -327.256758) (xy 104.700335 -327.207181) (xy 104.729801 -327.161331) (xy 104.765492 -327.12014)
			(xy 104.806683 -327.084449) (xy 104.852533 -327.054983) (xy 104.90211 -327.032341) (xy 104.954405 -327.016986)
			(xy 105.008353 -327.00923) (xy 105.062855 -327.00923) (xy 105.116803 -327.016986) (xy 105.169098 -327.032341)
			(xy 105.218675 -327.054983) (xy 105.264525 -327.084449) (xy 105.305716 -327.12014) (xy 105.341407 -327.161331)
			(xy 105.370873 -327.207181) (xy 105.393515 -327.256758) (xy 105.40887 -327.309053) (xy 105.416626 -327.363001)
			(xy 105.417112 -327.390252) (xy 105.417112 -327.390506) (xy 105.416688 -327.41545) (xy 105.410159 -327.464911)
			(xy 105.397252 -327.513102) (xy 105.378186 -327.559205) (xy 105.366058 -327.581006) (xy 105.3592 -327.59269)
			(xy 105.3592 -327.620122) (xy 105.41 -327.708006) (xy 105.414777 -327.715504) (xy 105.428379 -327.72693)
			(xy 105.445061 -327.733036) (xy 105.453942 -327.733406) (xy 106.270806 -327.733406) (xy 106.279944 -327.733024)
			(xy 106.297057 -327.726608) (xy 106.310831 -327.714595) (xy 106.31551 -327.706736) (xy 106.357928 -327.627742)
			(xy 106.361867 -327.619579) (xy 106.364285 -327.60163) (xy 106.360282 -327.583966) (xy 106.355642 -327.57618)
			(xy 106.355642 -327.575926) (xy 106.340765 -327.552454) (xy 106.317232 -327.502113) (xy 106.30126 -327.448888)
			(xy 106.293186 -327.393907) (xy 106.29265 -327.366122) (xy 106.293136 -327.338871) (xy 106.300892 -327.284923)
			(xy 106.316247 -327.232628) (xy 106.338889 -327.183051) (xy 106.368355 -327.137201) (xy 106.404046 -327.09601)
			(xy 106.445237 -327.060319) (xy 106.491087 -327.030853) (xy 106.540664 -327.008211) (xy 106.592959 -326.992856)
			(xy 106.646907 -326.9851) (xy 106.701409 -326.9851) (xy 106.755357 -326.992856) (xy 106.807652 -327.008211)
			(xy 106.857229 -327.030853) (xy 106.903079 -327.060319) (xy 106.94427 -327.09601) (xy 106.979961 -327.137201)
			(xy 107.009427 -327.183051) (xy 107.032069 -327.232628) (xy 107.047424 -327.284923) (xy 107.05518 -327.338871)
			(xy 107.055666 -327.366122) (xy 107.055143 -327.393906) (xy 107.047045 -327.448882) (xy 107.031065 -327.502104)
			(xy 107.007543 -327.552449) (xy 106.992674 -327.575926) (xy 106.992674 -327.57618) (xy 106.988037 -327.583966)
			(xy 106.984048 -327.60163) (xy 106.986457 -327.619577) (xy 106.990388 -327.627742) (xy 107.032806 -327.706736)
			(xy 107.037483 -327.714595) (xy 107.051259 -327.726604) (xy 107.068372 -327.733015) (xy 107.07751 -327.733406)
			(xy 108.00207 -327.733406) (xy 108.007912 -327.731882) (xy 108.03005 -327.726861) (xy 108.07513 -327.721508)
			(xy 108.097828 -327.721214) (xy 108.120525 -327.72154) (xy 108.165601 -327.726889) (xy 108.187744 -327.731882)
			(xy 108.193586 -327.733406) (xy 108.90377 -327.733406) (xy 108.916251 -327.73283) (xy 108.938353 -327.72124)
			(xy 108.945934 -327.711308) (xy 109.00029 -327.631298) (xy 109.003084 -327.606914) (xy 108.998512 -327.594976)
			(xy 108.990223 -327.572805) (xy 108.978574 -327.526927) (xy 108.972705 -327.479959) (xy 108.97235 -327.456292)
			(xy 108.972836 -327.429041) (xy 108.980592 -327.375093) (xy 108.995947 -327.322798) (xy 109.018589 -327.273221)
			(xy 109.048055 -327.227371) (xy 109.083746 -327.18618) (xy 109.124937 -327.150489) (xy 109.170787 -327.121023)
			(xy 109.220364 -327.098381) (xy 109.272659 -327.083026) (xy 109.326607 -327.07527) (xy 109.381109 -327.07527)
			(xy 109.435057 -327.083026) (xy 109.487352 -327.098381) (xy 109.536929 -327.121023) (xy 109.582779 -327.150489)
			(xy 109.62397 -327.18618) (xy 109.659661 -327.227371) (xy 109.689127 -327.273221) (xy 109.711769 -327.322798)
			(xy 109.727124 -327.375093) (xy 109.73488 -327.429041) (xy 109.735366 -327.456292) (xy 109.734988 -327.479957)
			(xy 109.729099 -327.526919) (xy 109.717462 -327.572795) (xy 109.709204 -327.594976) (xy 109.704632 -327.606914)
			(xy 109.707426 -327.631298) (xy 109.761782 -327.711308) (xy 109.769356 -327.721247) (xy 109.791463 -327.732833)
			(xy 109.803946 -327.733406) (xy 109.907578 -327.733406) (xy 109.912126 -327.733281) (xy 109.921069 -327.73162)
			(xy 109.925358 -327.730104) (xy 109.949488 -327.721214) (xy 109.956092 -327.71588) (xy 109.978974 -327.697811)
			(xy 110.029142 -327.668108) (xy 110.083244 -327.646382) (xy 110.140022 -327.633142) (xy 110.198154 -327.628693)
			(xy 110.256286 -327.633142) (xy 110.313064 -327.646382) (xy 110.367166 -327.668108) (xy 110.417334 -327.697811)
			(xy 110.440216 -327.71588) (xy 110.44682 -327.721214) (xy 110.47095 -327.730104) (xy 110.475237 -327.731628)
			(xy 110.484182 -327.733284) (xy 110.48873 -327.733406) (xy 111.540036 -327.733406) (xy 111.552521 -327.732838)
			(xy 111.574635 -327.721256) (xy 111.5822 -327.711308) (xy 111.636556 -327.631298) (xy 111.63935 -327.606914)
			(xy 111.634778 -327.594976) (xy 111.62649 -327.572805) (xy 111.614842 -327.526927) (xy 111.608973 -327.479959)
			(xy 111.608616 -327.456292) (xy 111.609102 -327.429041) (xy 111.616858 -327.375093) (xy 111.632213 -327.322798)
			(xy 111.654855 -327.273221) (xy 111.684321 -327.227371) (xy 111.720012 -327.18618) (xy 111.761203 -327.150489)
			(xy 111.807053 -327.121023) (xy 111.85663 -327.098381) (xy 111.908925 -327.083026) (xy 111.962873 -327.07527)
			(xy 112.017375 -327.07527) (xy 112.071323 -327.083026) (xy 112.123618 -327.098381) (xy 112.173195 -327.121023)
			(xy 112.219045 -327.150489) (xy 112.260236 -327.18618) (xy 112.295927 -327.227371) (xy 112.325393 -327.273221)
			(xy 112.348035 -327.322798) (xy 112.36339 -327.375093) (xy 112.371146 -327.429041) (xy 112.371632 -327.456292)
			(xy 112.371254 -327.479957) (xy 112.365367 -327.526919) (xy 112.353731 -327.572796) (xy 112.34547 -327.594976)
			(xy 112.340898 -327.606914) (xy 112.343692 -327.631298) (xy 112.398048 -327.711308) (xy 112.405619 -327.721253)
			(xy 112.427727 -327.732854) (xy 112.440212 -327.733406) (xy 135.662924 -327.733406) (xy 135.672576 -327.73239)
			(xy 135.679819 -327.73076) (xy 135.692985 -327.723916) (xy 135.698484 -327.718928) (xy 136.328404 -327.089008)
			(xy 136.333395 -327.083511) (xy 136.340247 -327.070346) (xy 136.341866 -327.0631) (xy 136.342882 -327.053448)
			(xy 136.342882 -319.478152) (xy 136.34245 -319.468086) (xy 136.334721 -319.449496) (xy 136.327896 -319.442084)
			(xy 135.057388 -318.171576) (xy 135.049992 -318.164723) (xy 135.031394 -318.156981) (xy 135.02132 -318.15659)
			(xy 118.989348 -318.15659) (xy 118.979282 -318.156157) (xy 118.960692 -318.148428) (xy 118.95328 -318.141604)
			(xy 118.438422 -317.626746) (xy 118.431582 -317.619345) (xy 118.423864 -317.600747) (xy 118.423436 -317.590678)
			(xy 118.423436 -314.80125) (xy 118.41988 -314.78855) (xy 118.41734 -314.783978) (xy 118.413295 -314.777568)
			(xy 118.408788 -314.763103) (xy 118.40845 -314.75553) (xy 118.40845 -304.640742) (xy 118.40845 -304.63744)
			(xy 118.407779 -304.630501) (xy 118.403127 -304.617364) (xy 118.399306 -304.611532) (xy 118.393718 -304.604928)
			(xy 118.342918 -304.553874) (xy 118.339346 -304.550474) (xy 118.331157 -304.544982) (xy 118.326662 -304.542952)
			(xy 118.317772 -304.539142) (xy 118.307358 -304.539142) (xy 118.2802 -304.538517) (xy 118.226468 -304.530525)
			(xy 118.174413 -304.514992) (xy 118.125088 -304.492234) (xy 118.079489 -304.462709) (xy 118.038539 -304.427016)
			(xy 118.003065 -304.385875) (xy 117.973785 -304.340119) (xy 117.95129 -304.290672) (xy 117.936037 -304.238535)
			(xy 117.928332 -304.184762) (xy 117.928332 -304.130439) (xy 117.936037 -304.076665) (xy 117.95129 -304.024528)
			(xy 117.973785 -303.975082) (xy 118.003065 -303.929325) (xy 118.038538 -303.888185) (xy 118.079489 -303.852491)
			(xy 118.125088 -303.822966) (xy 118.174413 -303.800208) (xy 118.226468 -303.784675) (xy 118.280199 -303.776683)
			(xy 118.307358 -303.776126) (xy 118.317772 -303.776126) (xy 118.326662 -303.772316) (xy 118.331168 -303.770306)
			(xy 118.339358 -303.764809) (xy 118.342918 -303.761394) (xy 118.393718 -303.71034) (xy 118.399306 -303.703736)
			(xy 118.403114 -303.697898) (xy 118.407761 -303.684763) (xy 118.40845 -303.677828) (xy 118.40845 -303.624742)
			(xy 118.40845 -303.62144) (xy 118.407779 -303.614501) (xy 118.403127 -303.601364) (xy 118.399306 -303.595532)
			(xy 118.393718 -303.588928) (xy 118.342918 -303.537874) (xy 118.339346 -303.534474) (xy 118.331157 -303.528982)
			(xy 118.326662 -303.526952) (xy 118.317772 -303.523142) (xy 118.307358 -303.523142) (xy 118.2802 -303.522517)
			(xy 118.226468 -303.514525) (xy 118.174413 -303.498992) (xy 118.125088 -303.476234) (xy 118.079489 -303.446709)
			(xy 118.038539 -303.411016) (xy 118.003065 -303.369875) (xy 117.973785 -303.324119) (xy 117.95129 -303.274672)
			(xy 117.936037 -303.222535) (xy 117.928332 -303.168762) (xy 117.928332 -303.114439) (xy 117.936037 -303.060665)
			(xy 117.95129 -303.008528) (xy 117.973785 -302.959082) (xy 118.003065 -302.913325) (xy 118.038538 -302.872185)
			(xy 118.079489 -302.836491) (xy 118.125088 -302.806966) (xy 118.174413 -302.784208) (xy 118.226468 -302.768675)
			(xy 118.280199 -302.760683) (xy 118.307358 -302.760126) (xy 118.317772 -302.760126) (xy 118.326662 -302.756316)
			(xy 118.331168 -302.754306) (xy 118.339358 -302.748809) (xy 118.342918 -302.745394) (xy 118.393718 -302.69434)
			(xy 118.399306 -302.687736) (xy 118.403114 -302.681898) (xy 118.407761 -302.668763) (xy 118.40845 -302.661828)
			(xy 118.40845 -294.215312) (xy 118.408872 -294.205242) (xy 118.416589 -294.186639) (xy 118.423436 -294.179244)
			(xy 118.910608 -293.692072) (xy 118.918004 -293.685219) (xy 118.936602 -293.677476) (xy 118.946676 -293.677086)
			(xy 134.210552 -293.677086) (xy 134.220618 -293.676653) (xy 134.239207 -293.668924) (xy 134.24662 -293.6621)
			(xy 134.273036 -293.635684) (xy 135.876284 -292.03269) (xy 135.88313 -292.025292) (xy 135.890864 -292.006694)
			(xy 135.89127 -291.996622) (xy 135.89127 -279.414986) (xy 135.890911 -279.40573) (xy 135.884393 -279.388408)
			(xy 135.87857 -279.381204) (xy 135.872474 -279.374346) (xy 135.855964 -279.36571) (xy 135.846566 -279.364694)
			(xy 135.765487 -279.354455) (xy 135.604346 -279.327121) (xy 135.444716 -279.292027) (xy 135.286968 -279.249255)
			(xy 135.131474 -279.198907) (xy 134.978596 -279.141098) (xy 134.828692 -279.075966) (xy 134.682112 -279.003661)
			(xy 134.5392 -278.924353) (xy 134.40029 -278.838228) (xy 134.265707 -278.745487) (xy 134.135765 -278.646347)
			(xy 134.010769 -278.54104) (xy 133.891011 -278.429812) (xy 133.776771 -278.312924) (xy 133.668317 -278.190649)
			(xy 133.565902 -278.063273) (xy 133.469766 -277.931094) (xy 133.380133 -277.794421) (xy 133.297213 -277.653574)
			(xy 133.221201 -277.508882) (xy 133.152274 -277.360684) (xy 133.090593 -277.209327) (xy 133.036303 -277.055164)
			(xy 132.989531 -276.898557) (xy 132.950385 -276.739871) (xy 132.918958 -276.579478) (xy 132.895323 -276.417753)
			(xy 132.879536 -276.255075) (xy 132.871633 -276.091823) (xy 132.871633 -275.928381) (xy 132.879536 -275.765129)
			(xy 132.895323 -275.60245) (xy 132.918958 -275.440725) (xy 132.950384 -275.280332) (xy 132.98953 -275.121647)
			(xy 133.036302 -274.965039) (xy 133.090592 -274.810876) (xy 133.152272 -274.659519) (xy 133.221199 -274.511321)
			(xy 133.297211 -274.366629) (xy 133.380131 -274.225782) (xy 133.469763 -274.089109) (xy 133.5659 -273.95693)
			(xy 133.668315 -273.829554) (xy 133.776769 -273.707278) (xy 133.891008 -273.59039) (xy 134.010766 -273.479162)
			(xy 134.135762 -273.373855) (xy 134.265704 -273.274715) (xy 134.400287 -273.181974) (xy 134.539197 -273.095849)
			(xy 134.682109 -273.016541) (xy 134.828688 -272.944236) (xy 134.978592 -272.879103) (xy 135.13147 -272.821295)
			(xy 135.286965 -272.770946) (xy 135.444712 -272.728174) (xy 135.604343 -272.69308) (xy 135.765483 -272.665746)
			(xy 135.846566 -272.655538) (xy 135.855774 -272.65405) (xy 135.872307 -272.645448) (xy 135.878824 -272.638774)
			(xy 135.884666 -272.631916) (xy 135.89127 -272.614644) (xy 135.89127 -268.68755) (xy 135.890762 -268.680184)
			(xy 135.889272 -268.669386) (xy 135.887621 -268.647649) (xy 135.88746 -268.63675) (xy 135.88746 -268.41958)
			(xy 135.887009 -268.410321) (xy 135.879938 -268.393205) (xy 135.873744 -268.386306) (xy 135.005318 -267.51788)
			(xy 134.998434 -267.511664) (xy 134.981308 -267.504592) (xy 134.972044 -267.504164) (xy 134.754874 -267.504164)
			(xy 134.743974 -267.504016) (xy 134.722237 -267.502361) (xy 134.71144 -267.500862) (xy 134.704074 -267.500354)
			(xy 128.891792 -267.500354) (xy 128.882942 -267.500744) (xy 128.866297 -267.506768) (xy 128.852672 -267.518069)
			(xy 128.84785 -267.5255) (xy 128.83303 -267.54962) (xy 128.797388 -267.593599) (xy 128.75564 -267.63183)
			(xy 128.708701 -267.663474) (xy 128.657603 -267.687834) (xy 128.603466 -267.704378) (xy 128.547478 -267.712742)
			(xy 128.49087 -267.712742) (xy 128.434882 -267.704378) (xy 128.380745 -267.687834) (xy 128.329647 -267.663474)
			(xy 128.282708 -267.63183) (xy 128.24096 -267.593599) (xy 128.205318 -267.54962) (xy 128.190498 -267.5255)
			(xy 128.185747 -267.518003) (xy 128.172119 -267.50665) (xy 128.155426 -267.500654) (xy 128.146556 -267.500354)
			(xy 106.411776 -267.500354) (xy 106.401026 -267.500833) (xy 106.381418 -267.509646) (xy 106.37393 -267.517372)
			(xy 106.355766 -267.536953) (xy 106.314906 -267.571349) (xy 106.26965 -267.599712) (xy 106.220879 -267.621485)
			(xy 106.169549 -267.636244) (xy 106.116663 -267.643701) (xy 106.089958 -267.644118) (xy 106.063224 -267.643666)
			(xy 106.010282 -267.636197) (xy 105.958899 -267.621411) (xy 105.910084 -267.599598) (xy 105.864792 -267.571184)
			(xy 105.823909 -267.536726) (xy 105.805732 -267.517118) (xy 105.798136 -267.509569) (xy 105.778581 -267.500898)
			(xy 105.767886 -267.500354) (xy 102.729792 -267.500354) (xy 102.719895 -267.500876) (xy 102.701608 -267.508465)
			(xy 102.694232 -267.515086) (xy 100.79228 -269.417038) (xy 102.50043 -269.417038) (xy 102.500935 -269.388299)
			(xy 102.509565 -269.331471) (xy 102.52662 -269.276581) (xy 102.551716 -269.22487) (xy 102.584283 -269.177507)
			(xy 102.603554 -269.15618) (xy 102.610158 -269.149322) (xy 102.61727 -269.131288) (xy 102.61727 -269.042388)
			(xy 102.610158 -269.024354) (xy 102.603554 -269.017496) (xy 102.584304 -268.996151) (xy 102.551734 -268.948794)
			(xy 102.526638 -268.897087) (xy 102.509582 -268.8422) (xy 102.500954 -268.785376) (xy 102.50043 -268.756638)
			(xy 102.500891 -268.729384) (xy 102.508644 -268.675431) (xy 102.523997 -268.623131) (xy 102.546638 -268.573549)
			(xy 102.576105 -268.527693) (xy 102.611799 -268.486499) (xy 102.652993 -268.450805) (xy 102.698849 -268.421338)
			(xy 102.748431 -268.398697) (xy 102.800731 -268.383344) (xy 102.854684 -268.375591) (xy 102.881938 -268.37513)
			(xy 102.909307 -268.375625) (xy 102.963485 -268.383435) (xy 103.015988 -268.398917) (xy 103.065736 -268.421752)
			(xy 103.111704 -268.451471) (xy 103.132636 -268.46911) (xy 103.13289 -268.469364) (xy 103.13997 -268.47496)
			(xy 103.156892 -268.481199) (xy 103.16591 -268.481556) (xy 103.232966 -268.481556) (xy 103.241982 -268.481192)
			(xy 103.2589 -268.47495) (xy 103.265986 -268.469364) (xy 103.265986 -268.46911) (xy 103.26624 -268.46911)
			(xy 103.287173 -268.451469) (xy 103.333141 -268.421745) (xy 103.382887 -268.398899) (xy 103.435389 -268.383403)
			(xy 103.489567 -268.375574) (xy 103.544309 -268.375574) (xy 103.598487 -268.383403) (xy 103.650989 -268.398899)
			(xy 103.700735 -268.421745) (xy 103.746703 -268.451469) (xy 103.767636 -268.46911) (xy 103.76789 -268.469364)
			(xy 103.77497 -268.47496) (xy 103.791892 -268.481199) (xy 103.80091 -268.481556) (xy 103.867966 -268.481556)
			(xy 103.876982 -268.481192) (xy 103.8939 -268.47495) (xy 103.900986 -268.469364) (xy 103.900986 -268.46911)
			(xy 103.90124 -268.46911) (xy 103.922173 -268.451469) (xy 103.968141 -268.421745) (xy 104.017887 -268.398899)
			(xy 104.070389 -268.383403) (xy 104.124567 -268.375574) (xy 104.179309 -268.375574) (xy 104.233487 -268.383403)
			(xy 104.285989 -268.398899) (xy 104.335735 -268.421745) (xy 104.381703 -268.451469) (xy 104.402636 -268.46911)
			(xy 104.40289 -268.469364) (xy 104.40997 -268.47496) (xy 104.426892 -268.481199) (xy 104.43591 -268.481556)
			(xy 104.502966 -268.481556) (xy 104.511982 -268.481192) (xy 104.5289 -268.47495) (xy 104.535986 -268.469364)
			(xy 104.535986 -268.46911) (xy 104.53624 -268.46911) (xy 104.557173 -268.451469) (xy 104.603141 -268.421745)
			(xy 104.652887 -268.398899) (xy 104.705389 -268.383403) (xy 104.759567 -268.375574) (xy 104.814309 -268.375574)
			(xy 104.868487 -268.383403) (xy 104.920989 -268.398899) (xy 104.970735 -268.421745) (xy 105.016703 -268.451469)
			(xy 105.037636 -268.46911) (xy 105.03789 -268.469364) (xy 105.04497 -268.47496) (xy 105.061892 -268.481199)
			(xy 105.07091 -268.481556) (xy 105.137966 -268.481556) (xy 105.146982 -268.481192) (xy 105.1639 -268.47495)
			(xy 105.170986 -268.469364) (xy 105.170986 -268.46911) (xy 105.17124 -268.46911) (xy 105.192185 -268.451487)
			(xy 105.238154 -268.421773) (xy 105.287898 -268.398933) (xy 105.340396 -268.383438) (xy 105.39457 -268.375606)
			(xy 105.421938 -268.37513) (xy 105.449192 -268.375543) (xy 105.503144 -268.383305) (xy 105.555443 -268.398667)
			(xy 105.605023 -268.421315) (xy 105.650875 -268.450789) (xy 105.692065 -268.486488) (xy 105.727756 -268.527686)
			(xy 105.757221 -268.573544) (xy 105.779859 -268.623129) (xy 105.795211 -268.67543) (xy 105.802963 -268.729384)
			(xy 105.803446 -268.756638) (xy 105.802933 -268.785377) (xy 105.794306 -268.842204) (xy 105.777253 -268.897095)
			(xy 105.752159 -268.948806) (xy 105.719593 -268.996169) (xy 105.700322 -269.017496) (xy 105.693718 -269.024354)
			(xy 105.686606 -269.042388) (xy 105.686606 -269.131288) (xy 105.693718 -269.149322) (xy 105.700322 -269.15618)
			(xy 105.719604 -269.177497) (xy 105.75217 -269.224861) (xy 105.777261 -269.276575) (xy 105.794309 -269.331468)
			(xy 105.802928 -269.388298) (xy 105.803446 -269.417038) (xy 124.88545 -269.417038) (xy 124.885949 -269.388298)
			(xy 124.89458 -269.33147) (xy 124.911636 -269.27658) (xy 124.936733 -269.224869) (xy 124.969302 -269.177507)
			(xy 124.988574 -269.15618) (xy 124.995178 -269.149322) (xy 125.00229 -269.131288) (xy 125.00229 -269.042388)
			(xy 124.995178 -269.024354) (xy 124.988574 -269.017496) (xy 124.969327 -268.996148) (xy 124.936756 -268.948792)
			(xy 124.911659 -268.897086) (xy 124.894602 -268.8422) (xy 124.885974 -268.785376) (xy 124.88545 -268.756638)
			(xy 124.886013 -268.72939) (xy 124.893764 -268.675447) (xy 124.909112 -268.623156) (xy 124.931746 -268.573582)
			(xy 124.961204 -268.527733) (xy 124.996887 -268.486544) (xy 125.038069 -268.450852) (xy 125.083912 -268.421384)
			(xy 125.133481 -268.39874) (xy 125.185769 -268.383381) (xy 125.23971 -268.375619) (xy 125.266958 -268.37513)
			(xy 125.294328 -268.375613) (xy 125.348506 -268.383426) (xy 125.40101 -268.398911) (xy 125.450757 -268.421749)
			(xy 125.496724 -268.45147) (xy 125.517656 -268.46911) (xy 125.51791 -268.469364) (xy 125.524984 -268.474968)
			(xy 125.541911 -268.481203) (xy 125.55093 -268.481556) (xy 125.617986 -268.481556) (xy 125.627003 -268.481202)
			(xy 125.643921 -268.474953) (xy 125.651006 -268.469364) (xy 125.651006 -268.46911) (xy 125.65126 -268.46911)
			(xy 125.672193 -268.451469) (xy 125.718161 -268.421745) (xy 125.767907 -268.398899) (xy 125.820409 -268.383403)
			(xy 125.874587 -268.375574) (xy 125.929329 -268.375574) (xy 125.983507 -268.383403) (xy 126.036009 -268.398899)
			(xy 126.085755 -268.421745) (xy 126.131723 -268.451469) (xy 126.152656 -268.46911) (xy 126.15291 -268.469364)
			(xy 126.159984 -268.474968) (xy 126.176911 -268.481203) (xy 126.18593 -268.481556) (xy 126.252986 -268.481556)
			(xy 126.262003 -268.481202) (xy 126.278921 -268.474953) (xy 126.286006 -268.469364) (xy 126.286006 -268.46911)
			(xy 126.28626 -268.46911) (xy 126.307193 -268.451469) (xy 126.353161 -268.421745) (xy 126.402907 -268.398899)
			(xy 126.455409 -268.383403) (xy 126.509587 -268.375574) (xy 126.564329 -268.375574) (xy 126.618507 -268.383403)
			(xy 126.671009 -268.398899) (xy 126.720755 -268.421745) (xy 126.766723 -268.451469) (xy 126.787656 -268.46911)
			(xy 126.78791 -268.469364) (xy 126.794984 -268.474968) (xy 126.811911 -268.481203) (xy 126.82093 -268.481556)
			(xy 126.887986 -268.481556) (xy 126.897003 -268.481202) (xy 126.913921 -268.474953) (xy 126.921006 -268.469364)
			(xy 126.921006 -268.46911) (xy 126.92126 -268.46911) (xy 126.942193 -268.451469) (xy 126.988161 -268.421745)
			(xy 127.037907 -268.398899) (xy 127.090409 -268.383403) (xy 127.144587 -268.375574) (xy 127.199329 -268.375574)
			(xy 127.253507 -268.383403) (xy 127.306009 -268.398899) (xy 127.355755 -268.421745) (xy 127.401723 -268.451469)
			(xy 127.422656 -268.46911) (xy 127.42291 -268.469364) (xy 127.429984 -268.474968) (xy 127.446911 -268.481203)
			(xy 127.45593 -268.481556) (xy 127.522986 -268.481556) (xy 127.532003 -268.481202) (xy 127.548921 -268.474953)
			(xy 127.556006 -268.469364) (xy 127.556006 -268.46911) (xy 127.55626 -268.46911) (xy 127.577198 -268.451478)
			(xy 127.623169 -268.421765) (xy 127.672915 -268.398927) (xy 127.725414 -268.383434) (xy 127.779589 -268.375605)
			(xy 127.806958 -268.37513) (xy 127.834212 -268.375594) (xy 127.888164 -268.383347) (xy 127.940465 -268.398699)
			(xy 127.990047 -268.42134) (xy 128.035902 -268.450807) (xy 128.077096 -268.486501) (xy 128.112791 -268.527695)
			(xy 128.142258 -268.573549) (xy 128.164899 -268.623132) (xy 128.180252 -268.675432) (xy 128.188005 -268.729384)
			(xy 128.188466 -268.756638) (xy 128.187948 -268.785377) (xy 128.179321 -268.842204) (xy 128.162269 -268.897094)
			(xy 128.137177 -268.948805) (xy 128.104612 -268.996168) (xy 128.085342 -269.017496) (xy 128.078738 -269.024354)
			(xy 128.071626 -269.042388) (xy 128.071626 -269.131288) (xy 128.078738 -269.149322) (xy 128.085342 -269.15618)
			(xy 128.104627 -269.177494) (xy 128.137192 -269.224859) (xy 128.162282 -269.276574) (xy 128.17933 -269.331468)
			(xy 128.187948 -269.388298) (xy 128.188466 -269.417038) (xy 128.18808 -269.444294) (xy 128.180317 -269.49825)
			(xy 128.164954 -269.550552) (xy 128.142304 -269.600135) (xy 128.112828 -269.64599) (xy 128.077126 -269.687183)
			(xy 128.035926 -269.722876) (xy 127.990064 -269.752343) (xy 127.940477 -269.774982) (xy 127.888171 -269.790334)
			(xy 127.834214 -269.798086) (xy 127.806958 -269.798546) (xy 127.779588 -269.798059) (xy 127.72541 -269.790248)
			(xy 127.672906 -269.774765) (xy 127.623159 -269.751927) (xy 127.577192 -269.722206) (xy 127.55626 -269.704566)
			(xy 127.556006 -269.704312) (xy 127.548921 -269.698723) (xy 127.532003 -269.692477) (xy 127.522986 -269.69212)
			(xy 127.45593 -269.69212) (xy 127.446914 -269.692487) (xy 127.429997 -269.698727) (xy 127.42291 -269.704312)
			(xy 127.422656 -269.704566) (xy 127.401723 -269.722207) (xy 127.355755 -269.751931) (xy 127.306009 -269.774777)
			(xy 127.253507 -269.790273) (xy 127.199329 -269.798102) (xy 127.144587 -269.798102) (xy 127.090409 -269.790273)
			(xy 127.037907 -269.774777) (xy 126.988161 -269.751931) (xy 126.942193 -269.722207) (xy 126.92126 -269.704566)
			(xy 126.921006 -269.704312) (xy 126.913921 -269.698723) (xy 126.897003 -269.692477) (xy 126.887986 -269.69212)
			(xy 126.82093 -269.69212) (xy 126.811914 -269.692487) (xy 126.794997 -269.698727) (xy 126.78791 -269.704312)
			(xy 126.78791 -269.704566) (xy 126.787656 -269.704566) (xy 126.766723 -269.722207) (xy 126.720755 -269.751931)
			(xy 126.671009 -269.774777) (xy 126.618507 -269.790273) (xy 126.564329 -269.798102) (xy 126.509587 -269.798102)
			(xy 126.455409 -269.790273) (xy 126.402907 -269.774777) (xy 126.353161 -269.751931) (xy 126.307193 -269.722207)
			(xy 126.28626 -269.704566) (xy 126.286006 -269.704312) (xy 126.278921 -269.698723) (xy 126.262003 -269.692477)
			(xy 126.252986 -269.69212) (xy 126.18593 -269.69212) (xy 126.176914 -269.692487) (xy 126.159997 -269.698727)
			(xy 126.15291 -269.704312) (xy 126.15291 -269.704566) (xy 126.152656 -269.704566) (xy 126.131723 -269.722207)
			(xy 126.085755 -269.751931) (xy 126.036009 -269.774777) (xy 125.983507 -269.790273) (xy 125.929329 -269.798102)
			(xy 125.874587 -269.798102) (xy 125.820409 -269.790273) (xy 125.767907 -269.774777) (xy 125.718161 -269.751931)
			(xy 125.672193 -269.722207) (xy 125.65126 -269.704566) (xy 125.651006 -269.704312) (xy 125.643921 -269.698723)
			(xy 125.627003 -269.692477) (xy 125.617986 -269.69212) (xy 125.55093 -269.69212) (xy 125.541914 -269.692487)
			(xy 125.524997 -269.698727) (xy 125.51791 -269.704312) (xy 125.51791 -269.704566) (xy 125.517656 -269.704566)
			(xy 125.496709 -269.722187) (xy 125.450741 -269.751903) (xy 125.400997 -269.774743) (xy 125.3485 -269.790238)
			(xy 125.294326 -269.79807) (xy 125.266958 -269.798546) (xy 125.239707 -269.798061) (xy 125.185762 -269.7903)
			(xy 125.133469 -269.774942) (xy 125.083894 -269.752298) (xy 125.038046 -269.722831) (xy 124.996857 -269.68714)
			(xy 124.961166 -269.645951) (xy 124.9317 -269.600102) (xy 124.909057 -269.550527) (xy 124.893699 -269.498234)
			(xy 124.885938 -269.444289) (xy 124.88545 -269.417038) (xy 105.803446 -269.417038) (xy 105.802958 -269.444288)
			(xy 105.795197 -269.498234) (xy 105.779839 -269.550526) (xy 105.757196 -269.600101) (xy 105.727729 -269.64595)
			(xy 105.692038 -269.687138) (xy 105.65085 -269.722829) (xy 105.605001 -269.752296) (xy 105.555426 -269.774939)
			(xy 105.503134 -269.790297) (xy 105.449188 -269.798058) (xy 105.421938 -269.798546) (xy 105.394568 -269.798071)
			(xy 105.340389 -269.790257) (xy 105.287885 -269.774771) (xy 105.238138 -269.751931) (xy 105.192171 -269.722207)
			(xy 105.17124 -269.704566) (xy 105.170986 -269.704312) (xy 105.163907 -269.698715) (xy 105.146984 -269.692474)
			(xy 105.137966 -269.69212) (xy 105.07091 -269.69212) (xy 105.061893 -269.692477) (xy 105.044976 -269.698724)
			(xy 105.03789 -269.704312) (xy 105.037636 -269.704566) (xy 105.016703 -269.722207) (xy 104.970735 -269.751931)
			(xy 104.920989 -269.774777) (xy 104.868487 -269.790273) (xy 104.814309 -269.798102) (xy 104.759567 -269.798102)
			(xy 104.705389 -269.790273) (xy 104.652887 -269.774777) (xy 104.603141 -269.751931) (xy 104.557173 -269.722207)
			(xy 104.53624 -269.704566) (xy 104.535986 -269.704312) (xy 104.528907 -269.698715) (xy 104.511984 -269.692474)
			(xy 104.502966 -269.69212) (xy 104.43591 -269.69212) (xy 104.426893 -269.692477) (xy 104.409976 -269.698724)
			(xy 104.40289 -269.704312) (xy 104.40289 -269.704566) (xy 104.402636 -269.704566) (xy 104.381703 -269.722207)
			(xy 104.335735 -269.751931) (xy 104.285989 -269.774777) (xy 104.233487 -269.790273) (xy 104.179309 -269.798102)
			(xy 104.124567 -269.798102) (xy 104.070389 -269.790273) (xy 104.017887 -269.774777) (xy 103.968141 -269.751931)
			(xy 103.922173 -269.722207) (xy 103.90124 -269.704566) (xy 103.900986 -269.704312) (xy 103.893907 -269.698715)
			(xy 103.876984 -269.692474) (xy 103.867966 -269.69212) (xy 103.80091 -269.69212) (xy 103.791893 -269.692477)
			(xy 103.774976 -269.698724) (xy 103.76789 -269.704312) (xy 103.76789 -269.704566) (xy 103.767636 -269.704566)
			(xy 103.746703 -269.722207) (xy 103.700735 -269.751931) (xy 103.650989 -269.774777) (xy 103.598487 -269.790273)
			(xy 103.544309 -269.798102) (xy 103.489567 -269.798102) (xy 103.435389 -269.790273) (xy 103.382887 -269.774777)
			(xy 103.333141 -269.751931) (xy 103.287173 -269.722207) (xy 103.26624 -269.704566) (xy 103.265986 -269.704312)
			(xy 103.258907 -269.698715) (xy 103.241984 -269.692474) (xy 103.232966 -269.69212) (xy 103.16591 -269.69212)
			(xy 103.156893 -269.692477) (xy 103.139976 -269.698724) (xy 103.13289 -269.704312) (xy 103.13289 -269.704566)
			(xy 103.132636 -269.704566) (xy 103.111697 -269.722196) (xy 103.065727 -269.751911) (xy 103.015981 -269.774749)
			(xy 102.963482 -269.790242) (xy 102.909307 -269.798071) (xy 102.881938 -269.798546) (xy 102.854689 -269.797987)
			(xy 102.800746 -269.790236) (xy 102.748455 -269.774888) (xy 102.698881 -269.752254) (xy 102.653032 -269.722795)
			(xy 102.611843 -269.687111) (xy 102.57615 -269.645929) (xy 102.546683 -269.600086) (xy 102.524039 -269.550516)
			(xy 102.50868 -269.498228) (xy 102.500919 -269.444286) (xy 102.50043 -269.417038) (xy 100.79228 -269.417038)
			(xy 100.344732 -269.864586) (xy 100.338078 -269.87194) (xy 100.330487 -269.890241) (xy 100.33 -269.900146)
			(xy 100.33 -277.864824) (xy 103.46563 -277.864824) (xy 103.466154 -277.835907) (xy 103.47488 -277.778736)
			(xy 103.492136 -277.723537) (xy 103.517527 -277.671575) (xy 103.55047 -277.624041) (xy 103.590211 -277.582024)
			(xy 103.612696 -277.563834) (xy 103.621477 -277.556202) (xy 103.631675 -277.53532) (xy 103.632254 -277.523702)
			(xy 103.632254 -277.443946) (xy 103.631748 -277.43231) (xy 103.621537 -277.411399) (xy 103.612696 -277.403814)
			(xy 103.590218 -277.385616) (xy 103.550483 -277.343598) (xy 103.517543 -277.296064) (xy 103.492154 -277.244104)
			(xy 103.474896 -277.188908) (xy 103.466166 -277.13174) (xy 103.46563 -277.102824) (xy 103.466211 -277.073416)
			(xy 103.475241 -277.015298) (xy 103.493076 -276.959253) (xy 103.519295 -276.906604) (xy 103.553276 -276.858599)
			(xy 103.594217 -276.816372) (xy 103.641148 -276.780922) (xy 103.666798 -276.766528) (xy 103.678736 -276.760178)
			(xy 103.69296 -276.737826) (xy 103.698802 -276.624288) (xy 103.686864 -276.600412) (xy 103.675942 -276.593046)
			(xy 103.654185 -276.577733) (xy 103.614705 -276.54207) (xy 103.580561 -276.50127) (xy 103.552414 -276.456123)
			(xy 103.530809 -276.407504) (xy 103.516166 -276.356357) (xy 103.508768 -276.303671) (xy 103.508302 -276.27707)
			(xy 103.50875 -276.249699) (xy 103.516572 -276.195519) (xy 103.532065 -276.143016) (xy 103.554911 -276.093269)
			(xy 103.584639 -276.047303) (xy 103.602282 -276.026372) (xy 103.602536 -276.026118) (xy 103.608125 -276.019033)
			(xy 103.614369 -276.002115) (xy 103.614728 -275.993098) (xy 103.614728 -275.926042) (xy 103.614345 -275.917028)
			(xy 103.608115 -275.900111) (xy 103.602536 -275.893022) (xy 103.602282 -275.893022) (xy 103.602282 -275.892768)
			(xy 103.584659 -275.871823) (xy 103.554945 -275.825854) (xy 103.532106 -275.776109) (xy 103.516611 -275.723612)
			(xy 103.508779 -275.669438) (xy 103.508302 -275.64207) (xy 103.508302 -275.641816) (xy 103.508871 -275.612017)
			(xy 103.518149 -275.553146) (xy 103.536467 -275.496433) (xy 103.563378 -275.443257) (xy 103.598228 -275.394912)
			(xy 103.618792 -275.373338) (xy 103.626158 -275.365972) (xy 103.633778 -275.34743) (xy 103.632762 -275.25472)
			(xy 103.624888 -275.236178) (xy 103.617522 -275.229066) (xy 103.599566 -275.211014) (xy 103.568068 -275.171012)
			(xy 103.542169 -275.127176) (xy 103.522329 -275.080286) (xy 103.508902 -275.031173) (xy 103.502124 -274.980711)
			(xy 103.501698 -274.955254) (xy 103.502135 -274.928001) (xy 103.509898 -274.874052) (xy 103.525259 -274.821756)
			(xy 103.547906 -274.772178) (xy 103.577378 -274.726327) (xy 103.613074 -274.685137) (xy 103.654269 -274.649447)
			(xy 103.700123 -274.619981) (xy 103.749704 -274.597341) (xy 103.802002 -274.581987) (xy 103.855953 -274.574231)
			(xy 103.883206 -274.573746) (xy 103.912124 -274.574243) (xy 103.969297 -274.582974) (xy 104.024497 -274.600235)
			(xy 104.076459 -274.62563) (xy 104.123992 -274.658579) (xy 104.166007 -274.698324) (xy 104.184196 -274.720812)
			(xy 104.191813 -274.729609) (xy 104.212706 -274.739798) (xy 104.224328 -274.74037) (xy 104.304084 -274.74037)
			(xy 104.315715 -274.739818) (xy 104.336625 -274.729639) (xy 104.344216 -274.720812) (xy 104.360969 -274.700029)
			(xy 104.399323 -274.662899) (xy 104.442477 -274.631477) (xy 104.489591 -274.606378) (xy 104.539743 -274.588092)
			(xy 104.591954 -274.576975) (xy 104.645206 -274.573245) (xy 104.698458 -274.576975) (xy 104.750669 -274.588092)
			(xy 104.800821 -274.606378) (xy 104.847935 -274.631477) (xy 104.891089 -274.662899) (xy 104.929443 -274.700029)
			(xy 104.946196 -274.720812) (xy 104.953813 -274.729609) (xy 104.974706 -274.739798) (xy 104.986328 -274.74037)
			(xy 105.066084 -274.74037) (xy 105.077715 -274.739818) (xy 105.098625 -274.729639) (xy 105.106216 -274.720812)
			(xy 105.124401 -274.698323) (xy 105.166422 -274.658588) (xy 105.213958 -274.625649) (xy 105.26592 -274.600262)
			(xy 105.321119 -274.583007) (xy 105.37829 -274.57428) (xy 105.407206 -274.573746) (xy 105.434455 -274.574272)
			(xy 105.488399 -274.582028) (xy 105.54069 -274.597382) (xy 105.590265 -274.62002) (xy 105.636113 -274.649483)
			(xy 105.677302 -274.68517) (xy 105.712993 -274.726355) (xy 105.742461 -274.7722) (xy 105.765104 -274.821772)
			(xy 105.780463 -274.874062) (xy 105.788225 -274.928005) (xy 105.788714 -274.955254) (xy 105.788714 -274.955508)
			(xy 105.788155 -274.985307) (xy 105.778874 -275.044178) (xy 105.760554 -275.100891) (xy 105.733641 -275.154067)
			(xy 105.698789 -275.202412) (xy 105.678224 -275.223986) (xy 105.670858 -275.231352) (xy 105.663238 -275.249894)
			(xy 105.664254 -275.342604) (xy 105.672128 -275.361146) (xy 105.679494 -275.368258) (xy 105.697465 -275.386296)
			(xy 105.728961 -275.426301) (xy 105.754857 -275.47014) (xy 105.774694 -275.517034) (xy 105.788119 -275.566148)
			(xy 105.794894 -275.616612) (xy 105.795318 -275.64207) (xy 105.794809 -275.670988) (xy 105.786083 -275.728161)
			(xy 105.768825 -275.783361) (xy 105.743432 -275.835324) (xy 105.710485 -275.882857) (xy 105.67074 -275.924872)
			(xy 105.648252 -275.94306) (xy 105.639465 -275.950686) (xy 105.629272 -275.971573) (xy 105.628694 -275.983192)
			(xy 105.628694 -276.051264) (xy 109.061504 -276.051264) (xy 109.061948 -276.023893) (xy 109.069771 -275.969713)
			(xy 109.085265 -275.917209) (xy 109.108112 -275.867463) (xy 109.137841 -275.821497) (xy 109.155484 -275.800566)
			(xy 109.155738 -275.800312) (xy 109.16133 -275.793229) (xy 109.167572 -275.776309) (xy 109.16793 -275.767292)
			(xy 109.16793 -275.700236) (xy 109.167549 -275.691222) (xy 109.161317 -275.674305) (xy 109.155738 -275.667216)
			(xy 109.155484 -275.667216) (xy 109.155484 -275.666962) (xy 109.13781 -275.646057) (xy 109.10809 -275.600083)
			(xy 109.085249 -275.550332) (xy 109.069757 -275.497826) (xy 109.061933 -275.443645) (xy 109.061937 -275.388901)
			(xy 109.069769 -275.334721) (xy 109.085268 -275.282217) (xy 109.108116 -275.232469) (xy 109.137843 -275.1865)
			(xy 109.155484 -275.165566) (xy 109.155738 -275.165312) (xy 109.16133 -275.158229) (xy 109.167572 -275.141309)
			(xy 109.16793 -275.132292) (xy 109.16793 -275.065236) (xy 109.167549 -275.056222) (xy 109.161317 -275.039305)
			(xy 109.155738 -275.032216) (xy 109.155484 -275.032216) (xy 109.155484 -275.031962) (xy 109.137858 -275.011019)
			(xy 109.108145 -274.965049) (xy 109.085307 -274.915304) (xy 109.069812 -274.862806) (xy 109.06198 -274.808632)
			(xy 109.061504 -274.781264) (xy 109.061944 -274.754011) (xy 109.069706 -274.700061) (xy 109.085066 -274.647765)
			(xy 109.107713 -274.598187) (xy 109.137184 -274.552336) (xy 109.17288 -274.511146) (xy 109.214075 -274.475455)
			(xy 109.259929 -274.44599) (xy 109.30951 -274.42335) (xy 109.361808 -274.407996) (xy 109.415759 -274.400241)
			(xy 109.443012 -274.399756) (xy 109.470383 -274.400201) (xy 109.524564 -274.408022) (xy 109.577068 -274.423515)
			(xy 109.626814 -274.446362) (xy 109.67278 -274.476092) (xy 109.69371 -274.493736) (xy 109.693964 -274.49399)
			(xy 109.701058 -274.499567) (xy 109.717969 -274.50582) (xy 109.726984 -274.506182) (xy 109.79404 -274.506182)
			(xy 109.803059 -274.505848) (xy 109.819976 -274.499585) (xy 109.82706 -274.49399) (xy 109.82706 -274.493736)
			(xy 109.827314 -274.493736) (xy 109.848272 -274.476129) (xy 109.894237 -274.446411) (xy 109.943978 -274.423569)
			(xy 109.996473 -274.40807) (xy 110.050645 -274.400234) (xy 110.078012 -274.399756) (xy 110.105262 -274.400267)
			(xy 110.159207 -274.408024) (xy 110.211499 -274.423379) (xy 110.261074 -274.446018) (xy 110.306922 -274.475483)
			(xy 110.348112 -274.511171) (xy 110.383803 -274.552358) (xy 110.41327 -274.598205) (xy 110.435913 -274.647779)
			(xy 110.451271 -274.70007) (xy 110.459032 -274.754014) (xy 110.45952 -274.781264) (xy 110.459052 -274.808634)
			(xy 110.451238 -274.862814) (xy 110.43575 -274.915318) (xy 110.412908 -274.965065) (xy 110.383182 -275.011031)
			(xy 110.36554 -275.031962) (xy 110.365286 -275.032216) (xy 110.359685 -275.039293) (xy 110.353447 -275.056217)
			(xy 110.353094 -275.065236) (xy 110.353094 -275.132292) (xy 110.353456 -275.141308) (xy 110.3597 -275.158225)
			(xy 110.365286 -275.165312) (xy 110.36554 -275.165312) (xy 110.36554 -275.165566) (xy 110.383147 -275.186527)
			(xy 110.412876 -275.232489) (xy 110.435725 -275.28223) (xy 110.451226 -275.334728) (xy 110.459058 -275.388904)
			(xy 110.459062 -275.443642) (xy 110.451237 -275.497819) (xy 110.435744 -275.550319) (xy 110.412902 -275.600064)
			(xy 110.38318 -275.64603) (xy 110.36554 -275.666962) (xy 110.365286 -275.667216) (xy 110.359685 -275.674293)
			(xy 110.353447 -275.691217) (xy 110.353094 -275.700236) (xy 110.353094 -275.767292) (xy 110.353456 -275.776308)
			(xy 110.3597 -275.793225) (xy 110.365286 -275.800312) (xy 110.36554 -275.800312) (xy 110.36554 -275.800566)
			(xy 110.383147 -275.821527) (xy 110.412876 -275.867489) (xy 110.435725 -275.91723) (xy 110.451226 -275.969728)
			(xy 110.459058 -276.023904) (xy 110.459062 -276.078642) (xy 110.451237 -276.132819) (xy 110.435744 -276.185319)
			(xy 110.412902 -276.235064) (xy 110.38318 -276.28103) (xy 110.36554 -276.301962) (xy 110.365286 -276.302216)
			(xy 110.359685 -276.309293) (xy 110.353447 -276.326217) (xy 110.353094 -276.335236) (xy 110.353094 -276.402292)
			(xy 110.353456 -276.411308) (xy 110.3597 -276.428225) (xy 110.365286 -276.435312) (xy 110.36554 -276.435312)
			(xy 110.36554 -276.43582) (xy 110.38169 -276.454875) (xy 110.409357 -276.496465) (xy 110.431359 -276.54131)
			(xy 110.439708 -276.564852) (xy 110.443518 -276.576282) (xy 110.460028 -276.593046) (xy 110.547912 -276.622764)
			(xy 110.559214 -276.626032) (xy 110.582519 -276.622965) (xy 110.592616 -276.616922) (xy 110.59287 -276.616668)
			(xy 110.616626 -276.601325) (xy 110.667684 -276.577015) (xy 110.721771 -276.560506) (xy 110.777701 -276.552158)
			(xy 110.805976 -276.551644) (xy 110.833224 -276.5522) (xy 110.887167 -276.559952) (xy 110.939458 -276.575302)
			(xy 110.989031 -276.597937) (xy 111.03488 -276.627396) (xy 111.076069 -276.66308) (xy 111.111761 -276.704263)
			(xy 111.141229 -276.750105) (xy 111.163873 -276.799675) (xy 111.179232 -276.851962) (xy 111.186994 -276.905904)
			(xy 111.187484 -276.933152) (xy 111.187056 -276.959467) (xy 111.179814 -277.011598) (xy 111.165488 -277.062241)
			(xy 111.144348 -277.11044) (xy 111.116794 -277.155283) (xy 111.083349 -277.195921) (xy 111.064294 -277.214076)
			(xy 111.0569 -277.221604) (xy 111.048372 -277.240879) (xy 111.047784 -277.251414) (xy 111.047784 -277.32609)
			(xy 111.04831 -277.33664) (xy 111.056848 -277.355935) (xy 111.064294 -277.363428) (xy 111.083355 -277.381578)
			(xy 111.116812 -277.422209) (xy 111.14437 -277.46705) (xy 111.165508 -277.515252) (xy 111.179824 -277.565901)
			(xy 111.187047 -277.618036) (xy 111.187315 -277.634192) (xy 120.08485 -277.634192) (xy 120.085348 -277.606122)
			(xy 120.093588 -277.550589) (xy 120.109875 -277.496862) (xy 120.133856 -277.446101) (xy 120.165015 -277.3994)
			(xy 120.202679 -277.357769) (xy 120.224042 -277.339552) (xy 120.232678 -277.33244) (xy 120.24233 -277.312628)
			(xy 120.24487 -277.213568) (xy 120.23598 -277.193248) (xy 120.227852 -277.185882) (xy 120.208519 -277.167737)
			(xy 120.174597 -277.126988) (xy 120.146643 -277.081936) (xy 120.125194 -277.033447) (xy 120.110665 -276.982456)
			(xy 120.103334 -276.929944) (xy 120.102884 -276.903434) (xy 120.103387 -276.876182) (xy 120.111139 -276.822233)
			(xy 120.12649 -276.769937) (xy 120.149128 -276.720357) (xy 120.178592 -276.674504) (xy 120.214282 -276.633311)
			(xy 120.255471 -276.597617) (xy 120.30132 -276.568148) (xy 120.350897 -276.545505) (xy 120.403192 -276.530148)
			(xy 120.45714 -276.52239) (xy 120.484392 -276.521926) (xy 120.510644 -276.52235) (xy 120.562654 -276.529537)
			(xy 120.613186 -276.543791) (xy 120.661285 -276.564842) (xy 120.706042 -276.592292) (xy 120.74661 -276.625622)
			(xy 120.782223 -276.664202) (xy 120.797574 -276.685502) (xy 120.802902 -276.692457) (xy 120.817178 -276.702589)
			(xy 120.834029 -276.707332) (xy 120.842786 -276.707092) (xy 120.94337 -276.69998) (xy 120.965468 -276.685248)
			(xy 120.971564 -276.67331) (xy 120.983825 -276.650017) (xy 121.013792 -276.606742) (xy 121.049423 -276.567996)
			(xy 121.09004 -276.534514) (xy 121.134873 -276.506933) (xy 121.183072 -276.485774) (xy 121.233721 -276.47144)
			(xy 121.285859 -276.464203) (xy 121.312178 -276.46376) (xy 121.345706 -276.465284) (xy 121.355779 -276.465774)
			(xy 121.374985 -276.459662) (xy 121.390363 -276.446633) (xy 121.399547 -276.428692) (xy 121.401125 -276.408599)
			(xy 121.394855 -276.389444) (xy 121.381699 -276.374175) (xy 121.372884 -276.369272) (xy 121.351374 -276.358095)
			(xy 121.311121 -276.331087) (xy 121.29262 -276.315424) (xy 121.292366 -276.31517) (xy 121.285267 -276.309602)
			(xy 121.26836 -276.303345) (xy 121.259346 -276.302978) (xy 121.19229 -276.302978) (xy 121.183273 -276.303335)
			(xy 121.166357 -276.309583) (xy 121.15927 -276.31517) (xy 121.15927 -276.315424) (xy 121.159016 -276.315424)
			(xy 121.138092 -276.333073) (xy 121.092116 -276.362782) (xy 121.042367 -276.385616) (xy 120.989865 -276.401105)
			(xy 120.935688 -276.408931) (xy 120.908318 -276.409404) (xy 120.881065 -276.408928) (xy 120.827115 -276.401173)
			(xy 120.774817 -276.385819) (xy 120.725237 -276.363179) (xy 120.679383 -276.333712) (xy 120.63819 -276.29802)
			(xy 120.602496 -276.256828) (xy 120.573028 -276.210976) (xy 120.550386 -276.161396) (xy 120.53503 -276.109099)
			(xy 120.527273 -276.055149) (xy 120.52681 -276.027896) (xy 120.527271 -276.000526) (xy 120.53509 -275.946346)
			(xy 120.55058 -275.893843) (xy 120.573423 -275.844096) (xy 120.603148 -275.79813) (xy 120.62079 -275.777198)
			(xy 120.621044 -275.776944) (xy 120.626624 -275.769853) (xy 120.632873 -275.752939) (xy 120.633236 -275.743924)
			(xy 120.633236 -275.676868) (xy 120.632887 -275.667851) (xy 120.626633 -275.650934) (xy 120.621044 -275.643848)
			(xy 120.62079 -275.643848) (xy 120.62079 -275.643594) (xy 120.603147 -275.622664) (xy 120.573425 -275.576695)
			(xy 120.550582 -275.526948) (xy 120.535088 -275.474446) (xy 120.52726 -275.420267) (xy 120.527261 -275.365527)
			(xy 120.535089 -275.311349) (xy 120.550584 -275.258847) (xy 120.573428 -275.2091) (xy 120.603151 -275.163131)
			(xy 120.62079 -275.142198) (xy 120.621044 -275.141944) (xy 120.626624 -275.134853) (xy 120.632873 -275.117939)
			(xy 120.633236 -275.108924) (xy 120.633236 -275.041868) (xy 120.632887 -275.032851) (xy 120.626633 -275.015934)
			(xy 120.621044 -275.008848) (xy 120.62079 -275.008848) (xy 120.62079 -275.008594) (xy 120.603133 -274.987676)
			(xy 120.573424 -274.941699) (xy 120.550592 -274.891948) (xy 120.535105 -274.839444) (xy 120.527282 -274.785266)
			(xy 120.52681 -274.757896) (xy 120.527252 -274.730642) (xy 120.53501 -274.67669) (xy 120.550367 -274.62439)
			(xy 120.573011 -274.574809) (xy 120.602481 -274.528955) (xy 120.638177 -274.487762) (xy 120.679373 -274.452068)
			(xy 120.725228 -274.422601) (xy 120.774811 -274.399959) (xy 120.827111 -274.384605) (xy 120.881064 -274.37685)
			(xy 120.908318 -274.376388) (xy 120.935688 -274.376846) (xy 120.989868 -274.384667) (xy 121.042371 -274.400158)
			(xy 121.092118 -274.423001) (xy 121.138084 -274.452726) (xy 121.159016 -274.470368) (xy 121.15927 -274.470622)
			(xy 121.166359 -274.476205) (xy 121.183274 -274.482453) (xy 121.19229 -274.482814) (xy 121.259346 -274.482814)
			(xy 121.26836 -274.482428) (xy 121.285277 -274.4762) (xy 121.292366 -274.470622) (xy 121.292366 -274.470368)
			(xy 121.29262 -274.470368) (xy 121.313567 -274.452748) (xy 121.359536 -274.423034) (xy 121.40928 -274.400195)
			(xy 121.461777 -274.3847) (xy 121.51595 -274.376865) (xy 121.543318 -274.376388) (xy 121.57057 -274.376861)
			(xy 121.624517 -274.38462) (xy 121.676812 -274.399977) (xy 121.726389 -274.42262) (xy 121.772239 -274.452088)
			(xy 121.813429 -274.487781) (xy 121.849121 -274.528972) (xy 121.878587 -274.574823) (xy 121.901228 -274.624401)
			(xy 121.916583 -274.676696) (xy 121.92434 -274.730644) (xy 121.924826 -274.757896) (xy 121.924376 -274.785267)
			(xy 121.916557 -274.839447) (xy 121.901065 -274.891951) (xy 121.878219 -274.941698) (xy 121.84849 -274.987664)
			(xy 121.830846 -275.008594) (xy 121.830592 -275.008848) (xy 121.82502 -275.015945) (xy 121.818765 -275.032854)
			(xy 121.8184 -275.041868) (xy 121.8184 -275.108924) (xy 121.818746 -275.117942) (xy 121.825001 -275.134859)
			(xy 121.830592 -275.141944) (xy 121.830846 -275.141944) (xy 121.830846 -275.142198) (xy 121.848484 -275.163133)
			(xy 121.878211 -275.2091) (xy 121.901058 -275.258846) (xy 121.916556 -275.311348) (xy 121.924385 -275.365526)
			(xy 121.924386 -275.420268) (xy 121.916557 -275.474447) (xy 121.90106 -275.526949) (xy 121.878214 -275.576695)
			(xy 121.848488 -275.622662) (xy 121.830846 -275.643594) (xy 121.830592 -275.643848) (xy 121.82502 -275.650945)
			(xy 121.818765 -275.667854) (xy 121.8184 -275.676868) (xy 121.8184 -275.743924) (xy 121.818746 -275.752942)
			(xy 121.825001 -275.769859) (xy 121.830592 -275.776944) (xy 121.830846 -275.776944) (xy 121.830846 -275.777198)
			(xy 121.848489 -275.798127) (xy 121.878202 -275.8441) (xy 121.901038 -275.893848) (xy 121.916528 -275.94635)
			(xy 121.924354 -276.000526) (xy 121.924826 -276.027896) (xy 121.924546 -276.046184) (xy 124.460254 -276.046184)
			(xy 124.460698 -276.018813) (xy 124.468519 -275.964632) (xy 124.484012 -275.912128) (xy 124.506859 -275.862382)
			(xy 124.53659 -275.816416) (xy 124.554234 -275.795486) (xy 124.554488 -275.795232) (xy 124.560066 -275.788139)
			(xy 124.566318 -275.771227) (xy 124.56668 -275.762212) (xy 124.56668 -275.695156) (xy 124.5663 -275.686141)
			(xy 124.560069 -275.669224) (xy 124.554488 -275.662136) (xy 124.554234 -275.662136) (xy 124.554234 -275.661882)
			(xy 124.536625 -275.640925) (xy 124.506908 -275.59496) (xy 124.484065 -275.545219) (xy 124.468567 -275.492723)
			(xy 124.460732 -275.438552) (xy 124.460254 -275.411184) (xy 124.460763 -275.383934) (xy 124.46852 -275.329989)
			(xy 124.483876 -275.277697) (xy 124.506516 -275.228122) (xy 124.53598 -275.182274) (xy 124.571669 -275.141085)
			(xy 124.612856 -275.105394) (xy 124.658703 -275.075927) (xy 124.708277 -275.053283) (xy 124.760568 -275.037925)
			(xy 124.814512 -275.030164) (xy 124.841762 -275.029676) (xy 124.869132 -275.030146) (xy 124.923312 -275.03796)
			(xy 124.975816 -275.053447) (xy 125.025563 -275.076288) (xy 125.071529 -275.106014) (xy 125.09246 -275.123656)
			(xy 125.092714 -275.12391) (xy 125.099792 -275.12951) (xy 125.116715 -275.135748) (xy 125.125734 -275.136102)
			(xy 125.19279 -275.136102) (xy 125.201806 -275.13574) (xy 125.218723 -275.129496) (xy 125.22581 -275.12391)
			(xy 125.22581 -275.123656) (xy 125.226064 -275.123656) (xy 125.246997 -275.106015) (xy 125.292965 -275.076291)
			(xy 125.342711 -275.053445) (xy 125.395213 -275.037949) (xy 125.449391 -275.03012) (xy 125.504133 -275.03012)
			(xy 125.558311 -275.037949) (xy 125.610813 -275.053445) (xy 125.660559 -275.076291) (xy 125.706527 -275.106015)
			(xy 125.72746 -275.123656) (xy 125.727714 -275.12391) (xy 125.734792 -275.12951) (xy 125.751715 -275.135748)
			(xy 125.760734 -275.136102) (xy 125.82779 -275.136102) (xy 125.836806 -275.13574) (xy 125.853723 -275.129496)
			(xy 125.86081 -275.12391) (xy 125.86081 -275.123656) (xy 125.861064 -275.123656) (xy 125.881997 -275.106015)
			(xy 125.927965 -275.076291) (xy 125.977711 -275.053445) (xy 126.030213 -275.037949) (xy 126.084391 -275.03012)
			(xy 126.139133 -275.03012) (xy 126.193311 -275.037949) (xy 126.245813 -275.053445) (xy 126.295559 -275.076291)
			(xy 126.341527 -275.106015) (xy 126.36246 -275.123656) (xy 126.362714 -275.12391) (xy 126.369792 -275.12951)
			(xy 126.386715 -275.135748) (xy 126.395734 -275.136102) (xy 126.46279 -275.136102) (xy 126.471806 -275.13574)
			(xy 126.488723 -275.129496) (xy 126.49581 -275.12391) (xy 126.49581 -275.123656) (xy 126.496064 -275.123656)
			(xy 126.516997 -275.106015) (xy 126.562965 -275.076291) (xy 126.612711 -275.053445) (xy 126.665213 -275.037949)
			(xy 126.719391 -275.03012) (xy 126.774133 -275.03012) (xy 126.828311 -275.037949) (xy 126.880813 -275.053445)
			(xy 126.930559 -275.076291) (xy 126.976527 -275.106015) (xy 126.99746 -275.123656) (xy 126.997714 -275.12391)
			(xy 127.004792 -275.12951) (xy 127.021715 -275.135748) (xy 127.030734 -275.136102) (xy 127.09779 -275.136102)
			(xy 127.106806 -275.13574) (xy 127.123723 -275.129496) (xy 127.13081 -275.12391) (xy 127.13081 -275.123656)
			(xy 127.131064 -275.123656) (xy 127.151993 -275.106013) (xy 127.197967 -275.076303) (xy 127.247716 -275.053469)
			(xy 127.300217 -275.037978) (xy 127.354393 -275.03015) (xy 127.381762 -275.029676) (xy 127.409013 -275.030191)
			(xy 127.462961 -275.037942) (xy 127.515257 -275.053292) (xy 127.564836 -275.075929) (xy 127.610689 -275.105392)
			(xy 127.651882 -275.14108) (xy 127.687576 -275.182268) (xy 127.717045 -275.228116) (xy 127.739689 -275.277692)
			(xy 127.755047 -275.329986) (xy 127.762806 -275.383933) (xy 127.76327 -275.411184) (xy 127.762802 -275.438554)
			(xy 127.754986 -275.492734) (xy 127.739497 -275.545237) (xy 127.716656 -275.594984) (xy 127.686931 -275.640951)
			(xy 127.66929 -275.661882) (xy 127.669036 -275.662136) (xy 127.663463 -275.669231) (xy 127.65721 -275.686142)
			(xy 127.656844 -275.695156) (xy 127.656844 -275.762212) (xy 127.657186 -275.771231) (xy 127.663443 -275.788148)
			(xy 127.669036 -275.795232) (xy 127.66929 -275.795232) (xy 127.66929 -275.795486) (xy 127.686934 -275.816414)
			(xy 127.716646 -275.862388) (xy 127.739481 -275.912136) (xy 127.754971 -275.964638) (xy 127.762797 -276.018815)
			(xy 127.76327 -276.046184) (xy 127.76283 -276.073438) (xy 127.755074 -276.127392) (xy 127.739718 -276.179693)
			(xy 127.717075 -276.229275) (xy 127.687605 -276.27513) (xy 127.651908 -276.316324) (xy 127.610713 -276.352018)
			(xy 127.564856 -276.381485) (xy 127.515272 -276.404126) (xy 127.46297 -276.419479) (xy 127.409016 -276.427231)
			(xy 127.381762 -276.427692) (xy 127.354393 -276.427192) (xy 127.300215 -276.419382) (xy 127.247712 -276.403901)
			(xy 127.197965 -276.381067) (xy 127.151997 -276.35135) (xy 127.131064 -276.333712) (xy 127.13081 -276.333458)
			(xy 127.123728 -276.327864) (xy 127.106808 -276.321623) (xy 127.09779 -276.321266) (xy 127.030734 -276.321266)
			(xy 127.02172 -276.321647) (xy 127.004803 -276.327879) (xy 126.997714 -276.333458) (xy 126.99746 -276.333712)
			(xy 126.976527 -276.351353) (xy 126.930559 -276.381077) (xy 126.880813 -276.403923) (xy 126.828311 -276.419419)
			(xy 126.774133 -276.427248) (xy 126.719391 -276.427248) (xy 126.665213 -276.419419) (xy 126.612711 -276.403923)
			(xy 126.562965 -276.381077) (xy 126.516997 -276.351353) (xy 126.496064 -276.333712) (xy 126.49581 -276.333458)
			(xy 126.488728 -276.327864) (xy 126.471808 -276.321623) (xy 126.46279 -276.321266) (xy 126.395734 -276.321266)
			(xy 126.38672 -276.321647) (xy 126.369803 -276.327879) (xy 126.362714 -276.333458) (xy 126.362714 -276.333712)
			(xy 126.36246 -276.333712) (xy 126.341527 -276.351353) (xy 126.295559 -276.381077) (xy 126.245813 -276.403923)
			(xy 126.193311 -276.419419) (xy 126.139133 -276.427248) (xy 126.084391 -276.427248) (xy 126.030213 -276.419419)
			(xy 125.977711 -276.403923) (xy 125.927965 -276.381077) (xy 125.881997 -276.351353) (xy 125.861064 -276.333712)
			(xy 125.86081 -276.333458) (xy 125.853728 -276.327864) (xy 125.836808 -276.321623) (xy 125.82779 -276.321266)
			(xy 125.760734 -276.321266) (xy 125.75172 -276.321647) (xy 125.734803 -276.327879) (xy 125.727714 -276.333458)
			(xy 125.727714 -276.333712) (xy 125.72746 -276.333712) (xy 125.706527 -276.351353) (xy 125.660559 -276.381077)
			(xy 125.610813 -276.403923) (xy 125.558311 -276.419419) (xy 125.504133 -276.427248) (xy 125.449391 -276.427248)
			(xy 125.395213 -276.419419) (xy 125.342711 -276.403923) (xy 125.292965 -276.381077) (xy 125.246997 -276.351353)
			(xy 125.226064 -276.333712) (xy 125.22581 -276.333458) (xy 125.218728 -276.327864) (xy 125.201808 -276.321623)
			(xy 125.19279 -276.321266) (xy 125.125734 -276.321266) (xy 125.11672 -276.321647) (xy 125.099803 -276.327879)
			(xy 125.092714 -276.333458) (xy 125.092714 -276.333712) (xy 125.09246 -276.333712) (xy 125.071518 -276.351338)
			(xy 125.025547 -276.381052) (xy 124.975803 -276.40389) (xy 124.923304 -276.419384) (xy 124.86913 -276.427216)
			(xy 124.841762 -276.427692) (xy 124.814509 -276.427257) (xy 124.760559 -276.419495) (xy 124.708262 -276.404135)
			(xy 124.658684 -276.381488) (xy 124.612833 -276.352016) (xy 124.571642 -276.316319) (xy 124.535951 -276.275124)
			(xy 124.506486 -276.229269) (xy 124.483846 -276.179687) (xy 124.468493 -276.127388) (xy 124.460739 -276.073437)
			(xy 124.460254 -276.046184) (xy 121.924546 -276.046184) (xy 121.924387 -276.056524) (xy 121.915839 -276.113137)
			(xy 121.898921 -276.167835) (xy 121.874013 -276.219388) (xy 121.841674 -276.266636) (xy 121.802633 -276.308517)
			(xy 121.757768 -276.344087) (xy 121.708088 -276.372547) (xy 121.654709 -276.393257) (xy 121.626884 -276.400006)
			(xy 121.62663 -276.400006) (xy 121.617871 -276.402419) (xy 121.602755 -276.41248) (xy 121.592088 -276.427174)
			(xy 121.589292 -276.43582) (xy 121.561098 -276.535388) (xy 121.56821 -276.562058) (xy 121.57837 -276.571964)
			(xy 121.596267 -276.58999) (xy 121.627628 -276.629949) (xy 121.653411 -276.673716) (xy 121.673158 -276.720517)
			(xy 121.686522 -276.769523) (xy 121.693266 -276.81987) (xy 121.693686 -276.845268) (xy 121.693215 -276.872521)
			(xy 121.685462 -276.926473) (xy 121.670109 -276.978772) (xy 121.647468 -277.028353) (xy 121.618001 -277.074208)
			(xy 121.582308 -277.115401) (xy 121.541116 -277.151095) (xy 121.495262 -277.180563) (xy 121.445681 -277.203205)
			(xy 121.393383 -277.21856) (xy 121.339431 -277.226314) (xy 121.312178 -277.226776) (xy 121.285925 -277.226374)
			(xy 121.233915 -277.219182) (xy 121.183382 -277.204925) (xy 121.135283 -277.18387) (xy 121.090527 -277.156417)
			(xy 121.049959 -277.123084) (xy 121.014347 -277.084501) (xy 120.998996 -277.0632) (xy 120.993685 -277.05623)
			(xy 120.979402 -277.046101) (xy 120.962543 -277.041365) (xy 120.953784 -277.04161) (xy 120.8532 -277.048722)
			(xy 120.831102 -277.063454) (xy 120.825006 -277.075392) (xy 120.812694 -277.098751) (xy 120.782606 -277.142141)
			(xy 120.746822 -277.180968) (xy 120.726708 -277.198074) (xy 120.718072 -277.205186) (xy 120.70842 -277.224998)
			(xy 120.70588 -277.324058) (xy 120.71477 -277.344378) (xy 120.722898 -277.351744) (xy 120.742185 -277.369935)
			(xy 120.776113 -277.410673) (xy 120.804075 -277.455716) (xy 120.825531 -277.504195) (xy 120.84007 -277.555179)
			(xy 120.847411 -277.607684) (xy 120.847866 -277.634192) (xy 120.84738 -277.661443) (xy 120.839624 -277.715391)
			(xy 120.834827 -277.731728) (xy 120.970292 -277.731728) (xy 120.974363 -277.676106) (xy 120.986489 -277.621669)
			(xy 121.006412 -277.569578) (xy 121.033708 -277.520943) (xy 121.067794 -277.4768) (xy 121.107943 -277.438091)
			(xy 121.153301 -277.40564) (xy 121.202901 -277.380139) (xy 121.255685 -277.362132) (xy 121.310528 -277.352002)
			(xy 121.366262 -277.349965) (xy 121.421699 -277.356065) (xy 121.475656 -277.370171) (xy 121.526985 -277.391983)
			(xy 121.574591 -277.421037) (xy 121.617459 -277.456712) (xy 121.654676 -277.498249) (xy 121.685449 -277.544762)
			(xy 121.709121 -277.595259) (xy 121.723891 -277.644352) (xy 127.083566 -277.644352) (xy 127.084012 -277.618037)
			(xy 127.091253 -277.565908) (xy 127.105577 -277.515266) (xy 127.126713 -277.467067) (xy 127.154263 -277.422224)
			(xy 127.187704 -277.381585) (xy 127.206756 -277.363428) (xy 127.214141 -277.355892) (xy 127.222676 -277.336623)
			(xy 127.223266 -277.32609) (xy 127.223266 -277.251414) (xy 127.222753 -277.240862) (xy 127.214208 -277.221566)
			(xy 127.206756 -277.214076) (xy 127.187687 -277.195934) (xy 127.154233 -277.1553) (xy 127.126677 -277.110457)
			(xy 127.105541 -277.062254) (xy 127.091226 -277.011604) (xy 127.084004 -276.959469) (xy 127.083566 -276.933152)
			(xy 127.084052 -276.905901) (xy 127.091808 -276.851953) (xy 127.107163 -276.799658) (xy 127.129805 -276.750081)
			(xy 127.159271 -276.704231) (xy 127.194962 -276.66304) (xy 127.236153 -276.627349) (xy 127.282003 -276.597883)
			(xy 127.33158 -276.575241) (xy 127.383875 -276.559886) (xy 127.437823 -276.55213) (xy 127.492325 -276.55213)
			(xy 127.546273 -276.559886) (xy 127.598568 -276.575241) (xy 127.648145 -276.597883) (xy 127.693995 -276.627349)
			(xy 127.735186 -276.66304) (xy 127.770877 -276.704231) (xy 127.800343 -276.750081) (xy 127.822985 -276.799658)
			(xy 127.83834 -276.851953) (xy 127.846096 -276.905901) (xy 127.846582 -276.933152) (xy 127.846155 -276.959467)
			(xy 127.838913 -277.011598) (xy 127.824586 -277.062242) (xy 127.803446 -277.110441) (xy 127.775893 -277.155283)
			(xy 127.742447 -277.195921) (xy 127.723392 -277.214076) (xy 127.715998 -277.221604) (xy 127.70747 -277.240879)
			(xy 127.706882 -277.251414) (xy 127.706882 -277.32609) (xy 127.707408 -277.33664) (xy 127.715946 -277.355935)
			(xy 127.723392 -277.363428) (xy 127.742453 -277.381579) (xy 127.77591 -277.422209) (xy 127.803468 -277.46705)
			(xy 127.824606 -277.515252) (xy 127.838922 -277.565901) (xy 127.846145 -277.618036) (xy 127.846582 -277.644352)
			(xy 127.846096 -277.671603) (xy 127.83834 -277.725551) (xy 127.822985 -277.777846) (xy 127.800343 -277.827423)
			(xy 127.770877 -277.873273) (xy 127.735186 -277.914464) (xy 127.693995 -277.950155) (xy 127.648145 -277.979621)
			(xy 127.598568 -278.002263) (xy 127.546273 -278.017618) (xy 127.492325 -278.025374) (xy 127.437823 -278.025374)
			(xy 127.383875 -278.017618) (xy 127.33158 -278.002263) (xy 127.282003 -277.979621) (xy 127.236153 -277.950155)
			(xy 127.194962 -277.914464) (xy 127.159271 -277.873273) (xy 127.129805 -277.827423) (xy 127.107163 -277.777846)
			(xy 127.091808 -277.725551) (xy 127.084052 -277.671603) (xy 127.083566 -277.644352) (xy 121.723891 -277.644352)
			(xy 121.725189 -277.648666) (xy 121.733309 -277.703842) (xy 121.733818 -277.731728) (xy 121.733309 -277.759614)
			(xy 121.725189 -277.81479) (xy 121.709121 -277.868197) (xy 121.685449 -277.918694) (xy 121.654676 -277.965207)
			(xy 121.617459 -278.006744) (xy 121.574591 -278.042419) (xy 121.526985 -278.071473) (xy 121.475656 -278.093285)
			(xy 121.421699 -278.107391) (xy 121.366262 -278.113491) (xy 121.310528 -278.111454) (xy 121.255685 -278.101324)
			(xy 121.202901 -278.083317) (xy 121.153301 -278.057816) (xy 121.107943 -278.025365) (xy 121.067794 -277.986656)
			(xy 121.033708 -277.942513) (xy 121.006412 -277.893878) (xy 120.986489 -277.841787) (xy 120.974363 -277.78735)
			(xy 120.970292 -277.731728) (xy 120.834827 -277.731728) (xy 120.824269 -277.767686) (xy 120.801627 -277.817263)
			(xy 120.772161 -277.863113) (xy 120.73647 -277.904304) (xy 120.695279 -277.939995) (xy 120.649429 -277.969461)
			(xy 120.599852 -277.992103) (xy 120.547557 -278.007458) (xy 120.493609 -278.015214) (xy 120.439107 -278.015214)
			(xy 120.385159 -278.007458) (xy 120.332864 -277.992103) (xy 120.283287 -277.969461) (xy 120.237437 -277.939995)
			(xy 120.196246 -277.904304) (xy 120.160555 -277.863113) (xy 120.131089 -277.817263) (xy 120.108447 -277.767686)
			(xy 120.093092 -277.715391) (xy 120.085336 -277.661443) (xy 120.08485 -277.634192) (xy 111.187315 -277.634192)
			(xy 111.187484 -277.644352) (xy 111.187 -277.671605) (xy 111.179249 -277.725556) (xy 111.163898 -277.777855)
			(xy 111.141259 -277.827437) (xy 111.111794 -277.873291) (xy 111.076102 -277.914485) (xy 111.03491 -277.950179)
			(xy 110.989058 -277.979648) (xy 110.939478 -278.002289) (xy 110.88718 -278.017644) (xy 110.833229 -278.025398)
			(xy 110.805976 -278.02586) (xy 110.779505 -278.025464) (xy 110.72707 -278.018167) (xy 110.676147 -278.003687)
			(xy 110.627717 -277.982304) (xy 110.582709 -277.954428) (xy 110.541989 -277.920596) (xy 110.506339 -277.881457)
			(xy 110.476445 -277.837763) (xy 110.452882 -277.790355) (xy 110.436101 -277.740144) (xy 110.430818 -277.714202)
			(xy 110.428532 -277.701756) (xy 110.413292 -277.682452) (xy 110.31347 -277.638002) (xy 110.288578 -277.63978)
			(xy 110.27791 -277.646384) (xy 110.255311 -277.659729) (xy 110.207243 -277.680797) (xy 110.156742 -277.695082)
			(xy 110.104761 -277.702314) (xy 110.07852 -277.702772) (xy 110.078012 -277.702772) (xy 110.050758 -277.702333)
			(xy 109.996804 -277.694577) (xy 109.944504 -277.679221) (xy 109.894921 -277.656577) (xy 109.849066 -277.627107)
			(xy 109.807872 -277.591411) (xy 109.772179 -277.550215) (xy 109.742711 -277.504358) (xy 109.720071 -277.454774)
			(xy 109.704718 -277.402472) (xy 109.696965 -277.348518) (xy 109.696504 -277.321264) (xy 109.696948 -277.293893)
			(xy 109.704771 -277.239713) (xy 109.720265 -277.187209) (xy 109.743112 -277.137463) (xy 109.772841 -277.091497)
			(xy 109.790484 -277.070566) (xy 109.790738 -277.070312) (xy 109.79633 -277.063229) (xy 109.802572 -277.046309)
			(xy 109.80293 -277.037292) (xy 109.80293 -276.970236) (xy 109.802549 -276.961222) (xy 109.796317 -276.944305)
			(xy 109.790738 -276.937216) (xy 109.790484 -276.937216) (xy 109.790484 -276.936962) (xy 109.772858 -276.916019)
			(xy 109.743145 -276.870049) (xy 109.720307 -276.820304) (xy 109.704812 -276.767806) (xy 109.69698 -276.713632)
			(xy 109.696504 -276.686264) (xy 109.697083 -276.656788) (xy 109.706142 -276.598536) (xy 109.724056 -276.542372)
			(xy 109.750396 -276.489632) (xy 109.784537 -276.441572) (xy 109.804708 -276.420072) (xy 109.811249 -276.412742)
			(xy 109.81869 -276.394578) (xy 109.819186 -276.384766) (xy 109.819186 -276.331426) (xy 109.81182 -276.324568)
			(xy 109.804477 -276.318045) (xy 109.786323 -276.310594) (xy 109.776514 -276.31009) (xy 109.74451 -276.31009)
			(xy 109.734698 -276.310593) (xy 109.716533 -276.318027) (xy 109.709204 -276.324568) (xy 109.687705 -276.344742)
			(xy 109.639645 -276.378886) (xy 109.586906 -276.405232) (xy 109.530741 -276.423153) (xy 109.472489 -276.432223)
			(xy 109.443012 -276.432772) (xy 109.415758 -276.432333) (xy 109.361804 -276.424577) (xy 109.309504 -276.409221)
			(xy 109.259921 -276.386577) (xy 109.214066 -276.357107) (xy 109.172872 -276.321411) (xy 109.137179 -276.280215)
			(xy 109.107711 -276.234358) (xy 109.085071 -276.184774) (xy 109.069718 -276.132472) (xy 109.061965 -276.078518)
			(xy 109.061504 -276.051264) (xy 105.628694 -276.051264) (xy 105.628694 -276.062948) (xy 105.629222 -276.074581)
			(xy 105.639419 -276.09549) (xy 105.648252 -276.10308) (xy 105.670737 -276.121269) (xy 105.710469 -276.163291)
			(xy 105.743407 -276.210827) (xy 105.768794 -276.262788) (xy 105.786051 -276.317985) (xy 105.794782 -276.375154)
			(xy 105.795318 -276.40407) (xy 105.794817 -276.431322) (xy 105.787064 -276.485271) (xy 105.771712 -276.537567)
			(xy 105.749074 -276.587147) (xy 105.71961 -276.632999) (xy 105.68392 -276.674192) (xy 105.642731 -276.709886)
			(xy 105.596882 -276.739355) (xy 105.547305 -276.761998) (xy 105.49501 -276.777356) (xy 105.441062 -276.785114)
			(xy 105.41381 -276.785578) (xy 105.384893 -276.785061) (xy 105.327721 -276.776333) (xy 105.272522 -276.759075)
			(xy 105.22056 -276.733683) (xy 105.173026 -276.700739) (xy 105.13101 -276.660998) (xy 105.11282 -276.638512)
			(xy 105.105192 -276.629726) (xy 105.084307 -276.61953) (xy 105.072688 -276.618954) (xy 104.992932 -276.618954)
			(xy 104.981301 -276.619507) (xy 104.96039 -276.629684) (xy 104.9528 -276.638512) (xy 104.942769 -276.651117)
			(xy 104.920893 -276.674769) (xy 104.909112 -276.685756) (xy 104.900222 -276.693884) (xy 104.891586 -276.715982)
			(xy 104.900222 -276.808692) (xy 104.901916 -276.820318) (xy 104.914226 -276.840299) (xy 104.923844 -276.847046)
			(xy 104.924098 -276.8473) (xy 104.947407 -276.862306) (xy 104.989845 -276.897971) (xy 105.026673 -276.939405)
			(xy 105.057113 -276.985734) (xy 105.080524 -277.035983) (xy 105.096413 -277.089091) (xy 105.104446 -277.143941)
			(xy 105.104946 -277.171658) (xy 105.10446 -277.198909) (xy 105.096704 -277.252857) (xy 105.081349 -277.305152)
			(xy 105.058707 -277.354729) (xy 105.029241 -277.400579) (xy 104.99355 -277.44177) (xy 104.952359 -277.477461)
			(xy 104.906509 -277.506927) (xy 104.856932 -277.529569) (xy 104.804637 -277.544924) (xy 104.750689 -277.55268)
			(xy 104.696187 -277.55268) (xy 104.642239 -277.544924) (xy 104.589944 -277.529569) (xy 104.540367 -277.506927)
			(xy 104.494517 -277.477461) (xy 104.453326 -277.44177) (xy 104.417635 -277.400579) (xy 104.388169 -277.354729)
			(xy 104.365527 -277.305152) (xy 104.350172 -277.252857) (xy 104.342416 -277.198909) (xy 104.34193 -277.171658)
			(xy 104.342402 -277.14524) (xy 104.349686 -277.09291) (xy 104.364122 -277.042085) (xy 104.385435 -276.99374)
			(xy 104.413216 -276.948798) (xy 104.446934 -276.908121) (xy 104.466136 -276.889972) (xy 104.475026 -276.881844)
			(xy 104.483662 -276.859746) (xy 104.475026 -276.767036) (xy 104.473338 -276.755409) (xy 104.461026 -276.735426)
			(xy 104.451404 -276.728682) (xy 104.45115 -276.728428) (xy 104.429535 -276.714589) (xy 104.389877 -276.68201)
			(xy 104.354959 -276.644394) (xy 104.325417 -276.602424) (xy 104.313228 -276.579838) (xy 104.30764 -276.56917)
			(xy 104.28859 -276.5552) (xy 104.196388 -276.539706) (xy 104.184684 -276.53846) (xy 104.162198 -276.54532)
			(xy 104.153208 -276.552914) (xy 104.152954 -276.553168) (xy 104.1341 -276.57061) (xy 104.09256 -276.600817)
			(xy 104.07015 -276.613366) (xy 104.058212 -276.619716) (xy 104.043988 -276.642068) (xy 104.038146 -276.755606)
			(xy 104.050084 -276.779482) (xy 104.061006 -276.786848) (xy 104.082749 -276.802181) (xy 104.122231 -276.837839)
			(xy 104.156378 -276.878635) (xy 104.184528 -276.923778) (xy 104.206135 -276.972394) (xy 104.22078 -277.02354)
			(xy 104.22818 -277.076224) (xy 104.228646 -277.102824) (xy 104.228093 -277.13174) (xy 104.219374 -277.18891)
			(xy 104.202124 -277.244109) (xy 104.176739 -277.296072) (xy 104.143801 -277.343606) (xy 104.104064 -277.385623)
			(xy 104.08158 -277.403814) (xy 104.072773 -277.411421) (xy 104.06259 -277.432322) (xy 104.062022 -277.443946)
			(xy 104.062022 -277.523702) (xy 104.062567 -277.535333) (xy 104.072751 -277.556243) (xy 104.08158 -277.563834)
			(xy 104.104076 -277.582011) (xy 104.143811 -277.624033) (xy 104.176749 -277.671571) (xy 104.202136 -277.723535)
			(xy 104.219389 -277.778735) (xy 104.228114 -277.835907) (xy 104.228646 -277.864824) (xy 104.22816 -277.892075)
			(xy 104.220404 -277.946023) (xy 104.205049 -277.998318) (xy 104.182407 -278.047895) (xy 104.152941 -278.093745)
			(xy 104.11725 -278.134936) (xy 104.076059 -278.170627) (xy 104.030209 -278.200093) (xy 103.980632 -278.222735)
			(xy 103.928337 -278.23809) (xy 103.874389 -278.245846) (xy 103.819887 -278.245846) (xy 103.765939 -278.23809)
			(xy 103.713644 -278.222735) (xy 103.664067 -278.200093) (xy 103.618217 -278.170627) (xy 103.577026 -278.134936)
			(xy 103.541335 -278.093745) (xy 103.511869 -278.047895) (xy 103.489227 -277.998318) (xy 103.473872 -277.946023)
			(xy 103.466116 -277.892075) (xy 103.46563 -277.864824) (xy 100.33 -277.864824) (xy 100.33 -280.617168)
			(xy 105.533444 -280.617168) (xy 105.53393 -280.589917) (xy 105.541686 -280.535969) (xy 105.557041 -280.483674)
			(xy 105.579683 -280.434097) (xy 105.609149 -280.388247) (xy 105.64484 -280.347056) (xy 105.686031 -280.311365)
			(xy 105.731881 -280.281899) (xy 105.781458 -280.259257) (xy 105.833753 -280.243902) (xy 105.887701 -280.236146)
			(xy 105.942203 -280.236146) (xy 105.996151 -280.243902) (xy 106.048446 -280.259257) (xy 106.098023 -280.281899)
			(xy 106.143873 -280.311365) (xy 106.185064 -280.347056) (xy 106.220755 -280.388247) (xy 106.250221 -280.434097)
			(xy 106.272863 -280.483674) (xy 106.288218 -280.535969) (xy 106.295974 -280.589917) (xy 106.29646 -280.617168)
			(xy 106.296402 -280.627794) (xy 106.295259 -280.649015) (xy 106.294174 -280.659586) (xy 106.293158 -280.668984)
			(xy 106.297984 -280.687272) (xy 106.343958 -280.750772) (xy 106.349792 -280.758054) (xy 106.365413 -280.768223)
			(xy 106.374438 -280.770584) (xy 106.374692 -280.770584) (xy 106.390186 -280.77414) (xy 106.399706 -280.776059)
			(xy 106.418913 -280.773299) (xy 106.427524 -280.768806) (xy 106.488738 -280.733754) (xy 106.497011 -280.728552)
			(xy 106.50916 -280.713269) (xy 106.51236 -280.704036) (xy 106.51236 -280.703782) (xy 106.520447 -280.677692)
			(xy 106.542991 -280.627942) (xy 106.572402 -280.581917) (xy 106.60808 -280.54056) (xy 106.649294 -280.504717)
			(xy 106.6952 -280.475122) (xy 106.74486 -280.452379) (xy 106.797257 -280.436956) (xy 106.851318 -280.429166)
			(xy 106.878628 -280.4287) (xy 106.9038 -280.429089) (xy 106.953707 -280.435711) (xy 107.002311 -280.448836)
			(xy 107.025694 -280.458164) (xy 107.035838 -280.461861) (xy 107.057402 -280.461342) (xy 107.06735 -280.457148)
			(xy 107.145328 -280.420064) (xy 107.159298 -280.403808) (xy 107.162346 -280.39314) (xy 107.171111 -280.365228)
			(xy 107.196048 -280.312306) (xy 107.228773 -280.263812) (xy 107.26852 -280.220885) (xy 107.314357 -280.184531)
			(xy 107.365207 -280.155603) (xy 107.419879 -280.13478) (xy 107.477089 -280.12255) (xy 107.506262 -280.120344)
			(xy 107.506516 -280.120344) (xy 107.517791 -280.118996) (xy 107.537578 -280.107919) (xy 107.544616 -280.099008)
			(xy 107.597448 -280.02484) (xy 107.601258 -280.002234) (xy 107.59821 -279.991058) (xy 107.591446 -279.965556)
			(xy 107.584179 -279.913298) (xy 107.583732 -279.886918) (xy 107.584218 -279.859667) (xy 107.591974 -279.805719)
			(xy 107.607329 -279.753424) (xy 107.629971 -279.703847) (xy 107.659437 -279.657997) (xy 107.695128 -279.616806)
			(xy 107.736319 -279.581115) (xy 107.782169 -279.551649) (xy 107.831746 -279.529007) (xy 107.884041 -279.513652)
			(xy 107.937989 -279.505896) (xy 107.992491 -279.505896) (xy 108.046439 -279.513652) (xy 108.098734 -279.529007)
			(xy 108.148311 -279.551649) (xy 108.194161 -279.581115) (xy 108.235352 -279.616806) (xy 108.271043 -279.657997)
			(xy 108.300509 -279.703847) (xy 108.323151 -279.753424) (xy 108.338506 -279.805719) (xy 108.346262 -279.859667)
			(xy 108.346748 -279.886918) (xy 108.346265 -279.915793) (xy 108.337582 -279.972885) (xy 108.320385 -280.028015)
			(xy 108.295069 -280.07992) (xy 108.262214 -280.127412) (xy 108.222571 -280.169404) (xy 108.177046 -280.204936)
			(xy 108.126683 -280.233195) (xy 108.072634 -280.253533) (xy 108.016135 -280.265486) (xy 107.987338 -280.267664)
			(xy 107.987084 -280.267664) (xy 107.975816 -280.269046) (xy 107.95603 -280.280102) (xy 107.948984 -280.289)
			(xy 107.896152 -280.363168) (xy 107.892342 -280.385774) (xy 107.89539 -280.39695) (xy 107.902155 -280.422452)
			(xy 107.909422 -280.47471) (xy 107.909868 -280.50109) (xy 107.9091 -280.535173) (xy 107.896969 -280.602251)
			(xy 107.891764 -280.617168) (xy 113.693956 -280.617168) (xy 113.694442 -280.589917) (xy 113.702198 -280.535969)
			(xy 113.717553 -280.483674) (xy 113.740195 -280.434097) (xy 113.769661 -280.388247) (xy 113.805352 -280.347056)
			(xy 113.846543 -280.311365) (xy 113.892393 -280.281899) (xy 113.94197 -280.259257) (xy 113.994265 -280.243902)
			(xy 114.048213 -280.236146) (xy 114.102715 -280.236146) (xy 114.156663 -280.243902) (xy 114.208958 -280.259257)
			(xy 114.258535 -280.281899) (xy 114.304385 -280.311365) (xy 114.345576 -280.347056) (xy 114.381267 -280.388247)
			(xy 114.410733 -280.434097) (xy 114.433375 -280.483674) (xy 114.44873 -280.535969) (xy 114.456486 -280.589917)
			(xy 114.456972 -280.617168) (xy 114.456914 -280.627794) (xy 114.455771 -280.649015) (xy 114.454686 -280.659586)
			(xy 114.45367 -280.668984) (xy 114.458496 -280.687272) (xy 114.50447 -280.750772) (xy 114.510299 -280.758058)
			(xy 114.525923 -280.768225) (xy 114.53495 -280.770584) (xy 114.535204 -280.770584) (xy 114.550698 -280.77414)
			(xy 114.560224 -280.77601) (xy 114.579424 -280.773283) (xy 114.588036 -280.768806) (xy 114.64925 -280.733754)
			(xy 114.657525 -280.728556) (xy 114.669674 -280.71327) (xy 114.672872 -280.704036) (xy 114.672872 -280.703782)
			(xy 114.680948 -280.677689) (xy 114.703493 -280.627938) (xy 114.732906 -280.581913) (xy 114.768585 -280.540556)
			(xy 114.8098 -280.504713) (xy 114.855708 -280.475118) (xy 114.905369 -280.452376) (xy 114.957767 -280.436953)
			(xy 115.01183 -280.429165) (xy 115.03914 -280.4287) (xy 115.064312 -280.429085) (xy 115.114219 -280.435709)
			(xy 115.162823 -280.448835) (xy 115.186206 -280.458164) (xy 115.196348 -280.461869) (xy 115.217914 -280.461345)
			(xy 115.227862 -280.457148) (xy 115.30584 -280.420064) (xy 115.31981 -280.403808) (xy 115.322858 -280.39314)
			(xy 115.331613 -280.365225) (xy 115.356551 -280.312302) (xy 115.389277 -280.263808) (xy 115.429026 -280.220881)
			(xy 115.474864 -280.184527) (xy 115.525716 -280.1556) (xy 115.580389 -280.134778) (xy 115.6376 -280.122549)
			(xy 115.666774 -280.120344) (xy 115.667028 -280.120344) (xy 115.678304 -280.119002) (xy 115.698091 -280.107921)
			(xy 115.705128 -280.099008) (xy 115.75796 -280.02484) (xy 115.76177 -280.002234) (xy 115.758722 -279.991058)
			(xy 115.751959 -279.965556) (xy 115.744691 -279.913298) (xy 115.744244 -279.886918) (xy 115.74473 -279.859667)
			(xy 115.752486 -279.805719) (xy 115.767841 -279.753424) (xy 115.790483 -279.703847) (xy 115.819949 -279.657997)
			(xy 115.85564 -279.616806) (xy 115.896831 -279.581115) (xy 115.942681 -279.551649) (xy 115.992258 -279.529007)
			(xy 116.044553 -279.513652) (xy 116.098501 -279.505896) (xy 116.153003 -279.505896) (xy 116.206951 -279.513652)
			(xy 116.259246 -279.529007) (xy 116.308823 -279.551649) (xy 116.354673 -279.581115) (xy 116.395864 -279.616806)
			(xy 116.431555 -279.657997) (xy 116.461021 -279.703847) (xy 116.483663 -279.753424) (xy 116.499018 -279.805719)
			(xy 116.506774 -279.859667) (xy 116.50726 -279.886918) (xy 116.506766 -279.915792) (xy 116.498083 -279.972884)
			(xy 116.480887 -280.028012) (xy 116.455572 -280.079916) (xy 116.422718 -280.127408) (xy 116.383076 -280.1694)
			(xy 116.337553 -280.204933) (xy 116.287192 -280.233192) (xy 116.233144 -280.253531) (xy 116.176647 -280.265485)
			(xy 116.14785 -280.267664) (xy 116.147596 -280.267664) (xy 116.136329 -280.269052) (xy 116.116543 -280.280104)
			(xy 116.109496 -280.289) (xy 116.056664 -280.363168) (xy 116.052854 -280.385774) (xy 116.055902 -280.39695)
			(xy 116.062667 -280.422452) (xy 116.069934 -280.47471) (xy 116.07038 -280.50109) (xy 116.069612 -280.535173)
			(xy 116.05748 -280.602251) (xy 116.052276 -280.617168) (xy 122.192542 -280.617168) (xy 122.193028 -280.589917)
			(xy 122.200784 -280.535969) (xy 122.216139 -280.483674) (xy 122.238781 -280.434097) (xy 122.268247 -280.388247)
			(xy 122.303938 -280.347056) (xy 122.345129 -280.311365) (xy 122.390979 -280.281899) (xy 122.440556 -280.259257)
			(xy 122.492851 -280.243902) (xy 122.546799 -280.236146) (xy 122.601301 -280.236146) (xy 122.655249 -280.243902)
			(xy 122.707544 -280.259257) (xy 122.757121 -280.281899) (xy 122.802971 -280.311365) (xy 122.844162 -280.347056)
			(xy 122.879853 -280.388247) (xy 122.909319 -280.434097) (xy 122.931961 -280.483674) (xy 122.947316 -280.535969)
			(xy 122.955072 -280.589917) (xy 122.955558 -280.617168) (xy 122.9555 -280.627794) (xy 122.954357 -280.649015)
			(xy 122.953272 -280.659586) (xy 122.952256 -280.668984) (xy 122.957082 -280.687272) (xy 123.003056 -280.750772)
			(xy 123.00889 -280.758053) (xy 123.024511 -280.768223) (xy 123.033536 -280.770584) (xy 123.03379 -280.770584)
			(xy 123.049284 -280.77414) (xy 123.058804 -280.776058) (xy 123.078011 -280.773299) (xy 123.086622 -280.768806)
			(xy 123.147836 -280.733754) (xy 123.156108 -280.728552) (xy 123.168258 -280.713269) (xy 123.171458 -280.704036)
			(xy 123.171458 -280.703782) (xy 123.179458 -280.677663) (xy 123.202009 -280.627907) (xy 123.23143 -280.58188)
			(xy 123.267119 -280.540521) (xy 123.308344 -280.50468) (xy 123.354262 -280.475088) (xy 123.403934 -280.452352)
			(xy 123.456341 -280.436937) (xy 123.510412 -280.429159) (xy 123.537726 -280.4287) (xy 123.562898 -280.42909)
			(xy 123.612805 -280.435711) (xy 123.661409 -280.448836) (xy 123.684792 -280.458164) (xy 123.694936 -280.46186)
			(xy 123.7165 -280.461342) (xy 123.726448 -280.457148) (xy 123.804426 -280.420064) (xy 123.818396 -280.403808)
			(xy 123.821444 -280.39314) (xy 123.830211 -280.365229) (xy 123.855147 -280.312307) (xy 123.887872 -280.263813)
			(xy 123.927619 -280.220886) (xy 123.973456 -280.184532) (xy 124.024306 -280.155604) (xy 124.078977 -280.134781)
			(xy 124.136187 -280.12255) (xy 124.16536 -280.120344) (xy 124.165614 -280.120344) (xy 124.176889 -280.118995)
			(xy 124.196676 -280.107919) (xy 124.203714 -280.099008) (xy 124.256546 -280.02484) (xy 124.260356 -280.002234)
			(xy 124.257308 -279.991058) (xy 124.250544 -279.965556) (xy 124.243277 -279.913298) (xy 124.24283 -279.886918)
			(xy 124.243316 -279.859667) (xy 124.251072 -279.805719) (xy 124.266427 -279.753424) (xy 124.289069 -279.703847)
			(xy 124.318535 -279.657997) (xy 124.354226 -279.616806) (xy 124.395417 -279.581115) (xy 124.441267 -279.551649)
			(xy 124.490844 -279.529007) (xy 124.543139 -279.513652) (xy 124.597087 -279.505896) (xy 124.651589 -279.505896)
			(xy 124.705537 -279.513652) (xy 124.757832 -279.529007) (xy 124.807409 -279.551649) (xy 124.853259 -279.581115)
			(xy 124.89445 -279.616806) (xy 124.930141 -279.657997) (xy 124.959607 -279.703847) (xy 124.982249 -279.753424)
			(xy 124.997604 -279.805719) (xy 125.00536 -279.859667) (xy 125.005846 -279.886918) (xy 125.005365 -279.915793)
			(xy 124.996681 -279.972886) (xy 124.979485 -280.028015) (xy 124.954169 -280.07992) (xy 124.921313 -280.127412)
			(xy 124.88167 -280.169405) (xy 124.836145 -280.204937) (xy 124.785782 -280.233195) (xy 124.731732 -280.253533)
			(xy 124.675233 -280.265486) (xy 124.646436 -280.267664) (xy 124.646182 -280.267664) (xy 124.634914 -280.269045)
			(xy 124.615128 -280.280102) (xy 124.608082 -280.289) (xy 124.55525 -280.363168) (xy 124.55144 -280.385774)
			(xy 124.554488 -280.39695) (xy 124.561253 -280.422452) (xy 124.56852 -280.47471) (xy 124.568966 -280.50109)
			(xy 124.568199 -280.535173) (xy 124.556067 -280.602251) (xy 124.550862 -280.617168) (xy 130.353054 -280.617168)
			(xy 130.35354 -280.589917) (xy 130.361296 -280.535969) (xy 130.376651 -280.483674) (xy 130.399293 -280.434097)
			(xy 130.428759 -280.388247) (xy 130.46445 -280.347056) (xy 130.505641 -280.311365) (xy 130.551491 -280.281899)
			(xy 130.601068 -280.259257) (xy 130.653363 -280.243902) (xy 130.707311 -280.236146) (xy 130.761813 -280.236146)
			(xy 130.815761 -280.243902) (xy 130.868056 -280.259257) (xy 130.917633 -280.281899) (xy 130.963483 -280.311365)
			(xy 131.004674 -280.347056) (xy 131.040365 -280.388247) (xy 131.069831 -280.434097) (xy 131.092473 -280.483674)
			(xy 131.107828 -280.535969) (xy 131.115584 -280.589917) (xy 131.11607 -280.617168) (xy 131.116012 -280.627794)
			(xy 131.114869 -280.649015) (xy 131.113784 -280.659586) (xy 131.112768 -280.668984) (xy 131.117594 -280.687272)
			(xy 131.163568 -280.750772) (xy 131.169398 -280.758057) (xy 131.185022 -280.768225) (xy 131.194048 -280.770584)
			(xy 131.194302 -280.770584) (xy 131.209796 -280.77414) (xy 131.219322 -280.776009) (xy 131.238522 -280.773282)
			(xy 131.247134 -280.768806) (xy 131.308348 -280.733754) (xy 131.316623 -280.728555) (xy 131.328771 -280.71327)
			(xy 131.33197 -280.704036) (xy 131.33197 -280.703782) (xy 131.340048 -280.677689) (xy 131.362592 -280.627938)
			(xy 131.392005 -280.581913) (xy 131.427684 -280.540556) (xy 131.468899 -280.504713) (xy 131.514807 -280.475118)
			(xy 131.564468 -280.452377) (xy 131.616865 -280.436954) (xy 131.670928 -280.429165) (xy 131.698238 -280.4287)
			(xy 131.72341 -280.429086) (xy 131.773317 -280.435709) (xy 131.821921 -280.448835) (xy 131.845304 -280.458164)
			(xy 131.855446 -280.461868) (xy 131.877012 -280.461345) (xy 131.88696 -280.457148) (xy 131.964938 -280.420064)
			(xy 131.978908 -280.403808) (xy 131.981956 -280.39314) (xy 131.990713 -280.365225) (xy 132.01565 -280.312303)
			(xy 132.048377 -280.263809) (xy 132.088125 -280.220881) (xy 132.133963 -280.184528) (xy 132.184814 -280.155601)
			(xy 132.239487 -280.134778) (xy 132.296699 -280.12255) (xy 132.325872 -280.120344) (xy 132.326126 -280.120344)
			(xy 132.337402 -280.119001) (xy 132.357188 -280.10792) (xy 132.364226 -280.099008) (xy 132.417058 -280.02484)
			(xy 132.420868 -280.002234) (xy 132.41782 -279.991058) (xy 132.411057 -279.965556) (xy 132.403789 -279.913298)
			(xy 132.403342 -279.886918) (xy 132.403828 -279.859667) (xy 132.411584 -279.805719) (xy 132.426939 -279.753424)
			(xy 132.449581 -279.703847) (xy 132.479047 -279.657997) (xy 132.514738 -279.616806) (xy 132.555929 -279.581115)
			(xy 132.601779 -279.551649) (xy 132.651356 -279.529007) (xy 132.703651 -279.513652) (xy 132.757599 -279.505896)
			(xy 132.812101 -279.505896) (xy 132.866049 -279.513652) (xy 132.918344 -279.529007) (xy 132.967921 -279.551649)
			(xy 133.013771 -279.581115) (xy 133.054962 -279.616806) (xy 133.090653 -279.657997) (xy 133.120119 -279.703847)
			(xy 133.142761 -279.753424) (xy 133.158116 -279.805719) (xy 133.165872 -279.859667) (xy 133.166358 -279.886918)
			(xy 133.165866 -279.915792) (xy 133.157183 -279.972884) (xy 133.139987 -280.028013) (xy 133.114672 -280.079917)
			(xy 133.081817 -280.127408) (xy 133.042175 -280.169401) (xy 132.996652 -280.204933) (xy 132.94629 -280.233192)
			(xy 132.892242 -280.253531) (xy 132.835745 -280.265485) (xy 132.806948 -280.267664) (xy 132.806694 -280.267664)
			(xy 132.795427 -280.269051) (xy 132.77564 -280.280104) (xy 132.768594 -280.289) (xy 132.715762 -280.363168)
			(xy 132.711952 -280.385774) (xy 132.715 -280.39695) (xy 132.721765 -280.422452) (xy 132.729032 -280.47471)
			(xy 132.729478 -280.50109) (xy 132.72871 -280.535173) (xy 132.716578 -280.602251) (xy 132.705348 -280.63444)
			(xy 132.70103 -280.64587) (xy 132.70357 -280.669492) (xy 132.760974 -280.758138) (xy 132.781802 -280.77033)
			(xy 132.79374 -280.771092) (xy 132.822349 -280.773546) (xy 132.878415 -280.785926) (xy 132.931995 -280.806566)
			(xy 132.981878 -280.835) (xy 133.026939 -280.870584) (xy 133.06616 -280.912518) (xy 133.098658 -280.959854)
			(xy 133.123698 -281.011523) (xy 133.125308 -281.01671) (xy 133.856982 -281.01671) (xy 133.861053 -280.961088)
			(xy 133.873179 -280.906651) (xy 133.893102 -280.85456) (xy 133.920398 -280.805925) (xy 133.954484 -280.761782)
			(xy 133.994633 -280.723073) (xy 134.039991 -280.690622) (xy 134.089591 -280.665121) (xy 134.142375 -280.647114)
			(xy 134.197218 -280.636984) (xy 134.252952 -280.634947) (xy 134.308389 -280.641047) (xy 134.362346 -280.655153)
			(xy 134.413675 -280.676965) (xy 134.461281 -280.706019) (xy 134.504149 -280.741694) (xy 134.541366 -280.783231)
			(xy 134.572139 -280.829744) (xy 134.595811 -280.880241) (xy 134.611879 -280.933648) (xy 134.619999 -280.988824)
			(xy 134.620508 -281.01671) (xy 134.619999 -281.044596) (xy 134.611879 -281.099772) (xy 134.595811 -281.153179)
			(xy 134.572139 -281.203676) (xy 134.541366 -281.250189) (xy 134.504149 -281.291726) (xy 134.461281 -281.327401)
			(xy 134.413675 -281.356455) (xy 134.362346 -281.378267) (xy 134.308389 -281.392373) (xy 134.252952 -281.398473)
			(xy 134.197218 -281.396436) (xy 134.142375 -281.386306) (xy 134.089591 -281.368299) (xy 134.039991 -281.342798)
			(xy 133.994633 -281.310347) (xy 133.954484 -281.271638) (xy 133.920398 -281.227495) (xy 133.893102 -281.17886)
			(xy 133.873179 -281.126769) (xy 133.861053 -281.072332) (xy 133.856982 -281.01671) (xy 133.125308 -281.01671)
			(xy 133.140715 -281.066361) (xy 133.149325 -281.123129) (xy 133.149848 -281.151838) (xy 133.149362 -281.179089)
			(xy 133.141606 -281.233037) (xy 133.126251 -281.285332) (xy 133.103609 -281.334909) (xy 133.074143 -281.380759)
			(xy 133.038452 -281.42195) (xy 132.997261 -281.457641) (xy 132.951411 -281.487107) (xy 132.901834 -281.509749)
			(xy 132.849539 -281.525104) (xy 132.795591 -281.53286) (xy 132.741089 -281.53286) (xy 132.687141 -281.525104)
			(xy 132.634846 -281.509749) (xy 132.585269 -281.487107) (xy 132.539419 -281.457641) (xy 132.498228 -281.42195)
			(xy 132.462537 -281.380759) (xy 132.433071 -281.334909) (xy 132.410429 -281.285332) (xy 132.395074 -281.233037)
			(xy 132.387318 -281.179089) (xy 132.386832 -281.151838) (xy 132.387581 -281.117754) (xy 132.399725 -281.050676)
			(xy 132.410962 -281.018488) (xy 132.41528 -281.007058) (xy 132.41274 -280.983436) (xy 132.355336 -280.89479)
			(xy 132.334508 -280.882598) (xy 132.32257 -280.881836) (xy 132.291272 -280.87909) (xy 132.230127 -280.86467)
			(xy 132.200904 -280.853134) (xy 132.190761 -280.849435) (xy 132.169196 -280.849955) (xy 132.159248 -280.85415)
			(xy 132.08127 -280.891234) (xy 132.0673 -280.90749) (xy 132.064252 -280.918158) (xy 132.056057 -280.944129)
			(xy 132.033378 -280.993638) (xy 132.003889 -281.03942) (xy 131.968191 -281.080544) (xy 131.927007 -281.116173)
			(xy 131.881176 -281.145585) (xy 131.831628 -281.168181) (xy 131.779371 -281.183502) (xy 131.725466 -281.191236)
			(xy 131.698238 -281.191716) (xy 131.674882 -281.191348) (xy 131.628524 -281.185619) (xy 131.605782 -281.180286)
			(xy 131.596258 -281.178401) (xy 131.577055 -281.181138) (xy 131.568444 -281.18562) (xy 131.50723 -281.220672)
			(xy 131.498962 -281.225881) (xy 131.486808 -281.241158) (xy 131.483608 -281.25039) (xy 131.483608 -281.250644)
			(xy 131.475566 -281.276749) (xy 131.453016 -281.3265) (xy 131.423599 -281.372525) (xy 131.387915 -281.413882)
			(xy 131.346695 -281.449723) (xy 131.300783 -281.479317) (xy 131.251118 -281.502056) (xy 131.198717 -281.517477)
			(xy 131.144652 -281.525262) (xy 131.11734 -281.525726) (xy 131.090089 -281.525208) (xy 131.036141 -281.517456)
			(xy 130.983845 -281.502106) (xy 130.934266 -281.47947) (xy 130.888414 -281.450008) (xy 130.847221 -281.41432)
			(xy 130.811527 -281.373133) (xy 130.782058 -281.327285) (xy 130.759414 -281.277709) (xy 130.744056 -281.225416)
			(xy 130.736297 -281.171469) (xy 130.735832 -281.144218) (xy 130.735889 -281.133592) (xy 130.737032 -281.112371)
			(xy 130.738118 -281.1018) (xy 130.739134 -281.092402) (xy 130.734308 -281.074114) (xy 130.688334 -281.010614)
			(xy 130.682506 -281.003327) (xy 130.666881 -280.993161) (xy 130.657854 -280.990802) (xy 130.6576 -280.990802)
			(xy 130.6293 -280.984437) (xy 130.574912 -280.964276) (xy 130.524204 -280.936113) (xy 130.478344 -280.900597)
			(xy 130.43839 -280.858547) (xy 130.405263 -280.810934) (xy 130.379727 -280.758853) (xy 130.36237 -280.703506)
			(xy 130.353593 -280.64617) (xy 130.353054 -280.617168) (xy 124.550862 -280.617168) (xy 124.544836 -280.63444)
			(xy 124.540518 -280.64587) (xy 124.543058 -280.669492) (xy 124.600462 -280.758138) (xy 124.62129 -280.77033)
			(xy 124.633228 -280.771092) (xy 124.661836 -280.773556) (xy 124.717902 -280.785935) (xy 124.771482 -280.806573)
			(xy 124.821365 -280.835005) (xy 124.866426 -280.870589) (xy 124.905648 -280.912521) (xy 124.938145 -280.959856)
			(xy 124.95745 -280.999692) (xy 125.69647 -280.999692) (xy 125.700541 -280.94407) (xy 125.712667 -280.889633)
			(xy 125.73259 -280.837542) (xy 125.759886 -280.788907) (xy 125.793972 -280.744764) (xy 125.834121 -280.706055)
			(xy 125.879479 -280.673604) (xy 125.929079 -280.648103) (xy 125.981863 -280.630096) (xy 126.036706 -280.619966)
			(xy 126.09244 -280.617929) (xy 126.147877 -280.624029) (xy 126.201834 -280.638135) (xy 126.253163 -280.659947)
			(xy 126.300769 -280.689001) (xy 126.343637 -280.724676) (xy 126.380854 -280.766213) (xy 126.411627 -280.812726)
			(xy 126.435299 -280.863223) (xy 126.451367 -280.91663) (xy 126.459487 -280.971806) (xy 126.459996 -280.999692)
			(xy 126.459487 -281.027578) (xy 126.451367 -281.082754) (xy 126.435299 -281.136161) (xy 126.411627 -281.186658)
			(xy 126.380854 -281.233171) (xy 126.343637 -281.274708) (xy 126.300769 -281.310383) (xy 126.253163 -281.339437)
			(xy 126.201834 -281.361249) (xy 126.147877 -281.375355) (xy 126.09244 -281.381455) (xy 126.036706 -281.379418)
			(xy 125.981863 -281.369288) (xy 125.929079 -281.351281) (xy 125.879479 -281.32578) (xy 125.834121 -281.293329)
			(xy 125.793972 -281.25462) (xy 125.759886 -281.210477) (xy 125.73259 -281.161842) (xy 125.712667 -281.109751)
			(xy 125.700541 -281.055314) (xy 125.69647 -280.999692) (xy 124.95745 -280.999692) (xy 124.963185 -281.011525)
			(xy 124.980203 -281.066362) (xy 124.988813 -281.12313) (xy 124.989336 -281.151838) (xy 124.98885 -281.179089)
			(xy 124.981094 -281.233037) (xy 124.965739 -281.285332) (xy 124.943097 -281.334909) (xy 124.913631 -281.380759)
			(xy 124.87794 -281.42195) (xy 124.836749 -281.457641) (xy 124.790899 -281.487107) (xy 124.741322 -281.509749)
			(xy 124.689027 -281.525104) (xy 124.635079 -281.53286) (xy 124.580577 -281.53286) (xy 124.526629 -281.525104)
			(xy 124.474334 -281.509749) (xy 124.424757 -281.487107) (xy 124.378907 -281.457641) (xy 124.337716 -281.42195)
			(xy 124.302025 -281.380759) (xy 124.272559 -281.334909) (xy 124.249917 -281.285332) (xy 124.234562 -281.233037)
			(xy 124.226806 -281.179089) (xy 124.22632 -281.151838) (xy 124.22707 -281.117754) (xy 124.239214 -281.050676)
			(xy 124.25045 -281.018488) (xy 124.254768 -281.007058) (xy 124.252228 -280.983436) (xy 124.194824 -280.89479)
			(xy 124.173996 -280.882598) (xy 124.162058 -280.881836) (xy 124.13076 -280.879093) (xy 124.069615 -280.864671)
			(xy 124.040392 -280.853134) (xy 124.030251 -280.849428) (xy 124.008684 -280.849952) (xy 123.998736 -280.85415)
			(xy 123.920758 -280.891234) (xy 123.906788 -280.90749) (xy 123.90374 -280.918158) (xy 123.895555 -280.944132)
			(xy 123.872875 -280.993643) (xy 123.843386 -281.039425) (xy 123.807686 -281.080549) (xy 123.766501 -281.116178)
			(xy 123.720668 -281.145589) (xy 123.671119 -281.168184) (xy 123.618861 -281.183504) (xy 123.564955 -281.191237)
			(xy 123.537726 -281.191716) (xy 123.51437 -281.19135) (xy 123.468011 -281.18562) (xy 123.44527 -281.180286)
			(xy 123.435747 -281.178395) (xy 123.416543 -281.181135) (xy 123.407932 -281.18562) (xy 123.346718 -281.220672)
			(xy 123.338448 -281.225878) (xy 123.326295 -281.241157) (xy 123.323096 -281.25039) (xy 123.323096 -281.250644)
			(xy 123.315064 -281.276752) (xy 123.292514 -281.326504) (xy 123.263095 -281.37253) (xy 123.22741 -281.413886)
			(xy 123.186189 -281.449728) (xy 123.140276 -281.479321) (xy 123.090609 -281.50206) (xy 123.038207 -281.517479)
			(xy 122.98414 -281.525263) (xy 122.956828 -281.525726) (xy 122.929577 -281.525219) (xy 122.875628 -281.517466)
			(xy 122.823332 -281.502114) (xy 122.773753 -281.479477) (xy 122.727901 -281.450013) (xy 122.686709 -281.414324)
			(xy 122.651015 -281.373136) (xy 122.621546 -281.327287) (xy 122.598902 -281.277711) (xy 122.583544 -281.225417)
			(xy 122.575785 -281.171469) (xy 122.57532 -281.144218) (xy 122.575377 -281.133592) (xy 122.57652 -281.112371)
			(xy 122.577606 -281.1018) (xy 122.578622 -281.092402) (xy 122.573796 -281.074114) (xy 122.527822 -281.010614)
			(xy 122.521998 -281.003323) (xy 122.50637 -280.993159) (xy 122.497342 -280.990802) (xy 122.497088 -280.990802)
			(xy 122.468786 -280.984445) (xy 122.414398 -280.964282) (xy 122.36369 -280.936118) (xy 122.317831 -280.900601)
			(xy 122.277877 -280.85855) (xy 122.24475 -280.810936) (xy 122.219214 -280.758854) (xy 122.201858 -280.703507)
			(xy 122.193081 -280.64617) (xy 122.192542 -280.617168) (xy 116.052276 -280.617168) (xy 116.04625 -280.63444)
			(xy 116.041932 -280.64587) (xy 116.044472 -280.669492) (xy 116.101876 -280.758138) (xy 116.122704 -280.77033)
			(xy 116.134642 -280.771092) (xy 116.163251 -280.773544) (xy 116.219318 -280.785925) (xy 116.272897 -280.806565)
			(xy 116.32278 -280.834999) (xy 116.367841 -280.870584) (xy 116.407062 -280.912517) (xy 116.43956 -280.959853)
			(xy 116.4646 -281.011523) (xy 116.46621 -281.01671) (xy 117.197884 -281.01671) (xy 117.201955 -280.961088)
			(xy 117.214081 -280.906651) (xy 117.234004 -280.85456) (xy 117.2613 -280.805925) (xy 117.295386 -280.761782)
			(xy 117.335535 -280.723073) (xy 117.380893 -280.690622) (xy 117.430493 -280.665121) (xy 117.483277 -280.647114)
			(xy 117.53812 -280.636984) (xy 117.593854 -280.634947) (xy 117.649291 -280.641047) (xy 117.703248 -280.655153)
			(xy 117.754577 -280.676965) (xy 117.802183 -280.706019) (xy 117.845051 -280.741694) (xy 117.882268 -280.783231)
			(xy 117.913041 -280.829744) (xy 117.936713 -280.880241) (xy 117.952781 -280.933648) (xy 117.960901 -280.988824)
			(xy 117.96141 -281.01671) (xy 117.960901 -281.044596) (xy 117.952781 -281.099772) (xy 117.936713 -281.153179)
			(xy 117.913041 -281.203676) (xy 117.882268 -281.250189) (xy 117.845051 -281.291726) (xy 117.802183 -281.327401)
			(xy 117.754577 -281.356455) (xy 117.703248 -281.378267) (xy 117.649291 -281.392373) (xy 117.593854 -281.398473)
			(xy 117.53812 -281.396436) (xy 117.483277 -281.386306) (xy 117.430493 -281.368299) (xy 117.380893 -281.342798)
			(xy 117.335535 -281.310347) (xy 117.295386 -281.271638) (xy 117.2613 -281.227495) (xy 117.234004 -281.17886)
			(xy 117.214081 -281.126769) (xy 117.201955 -281.072332) (xy 117.197884 -281.01671) (xy 116.46621 -281.01671)
			(xy 116.481617 -281.066361) (xy 116.490227 -281.123129) (xy 116.49075 -281.151838) (xy 116.490264 -281.179089)
			(xy 116.482508 -281.233037) (xy 116.467153 -281.285332) (xy 116.444511 -281.334909) (xy 116.415045 -281.380759)
			(xy 116.379354 -281.42195) (xy 116.338163 -281.457641) (xy 116.292313 -281.487107) (xy 116.242736 -281.509749)
			(xy 116.190441 -281.525104) (xy 116.136493 -281.53286) (xy 116.081991 -281.53286) (xy 116.028043 -281.525104)
			(xy 115.975748 -281.509749) (xy 115.926171 -281.487107) (xy 115.880321 -281.457641) (xy 115.83913 -281.42195)
			(xy 115.803439 -281.380759) (xy 115.773973 -281.334909) (xy 115.751331 -281.285332) (xy 115.735976 -281.233037)
			(xy 115.72822 -281.179089) (xy 115.727734 -281.151838) (xy 115.728483 -281.117754) (xy 115.740627 -281.050676)
			(xy 115.751864 -281.018488) (xy 115.756182 -281.007058) (xy 115.753642 -280.983436) (xy 115.696238 -280.89479)
			(xy 115.67541 -280.882598) (xy 115.663472 -280.881836) (xy 115.632174 -280.879089) (xy 115.571029 -280.86467)
			(xy 115.541806 -280.853134) (xy 115.531662 -280.849436) (xy 115.510098 -280.849955) (xy 115.50015 -280.85415)
			(xy 115.422172 -280.891234) (xy 115.408202 -280.90749) (xy 115.405154 -280.918158) (xy 115.396957 -280.944128)
			(xy 115.374278 -280.993638) (xy 115.34479 -281.039419) (xy 115.309091 -281.080543) (xy 115.267908 -281.116173)
			(xy 115.222077 -281.145584) (xy 115.17253 -281.16818) (xy 115.120273 -281.183501) (xy 115.066368 -281.191236)
			(xy 115.03914 -281.191716) (xy 115.015784 -281.191347) (xy 114.969426 -281.185619) (xy 114.946684 -281.180286)
			(xy 114.93716 -281.178402) (xy 114.917957 -281.181138) (xy 114.909346 -281.18562) (xy 114.848132 -281.220672)
			(xy 114.839865 -281.225882) (xy 114.82771 -281.241158) (xy 114.82451 -281.25039) (xy 114.82451 -281.250644)
			(xy 114.816466 -281.276748) (xy 114.793917 -281.326499) (xy 114.764499 -281.372524) (xy 114.728816 -281.413881)
			(xy 114.687596 -281.449723) (xy 114.641685 -281.479316) (xy 114.59202 -281.502056) (xy 114.539619 -281.517476)
			(xy 114.485554 -281.525262) (xy 114.458242 -281.525726) (xy 114.430991 -281.525206) (xy 114.377043 -281.517455)
			(xy 114.324747 -281.502105) (xy 114.275169 -281.479469) (xy 114.229316 -281.450007) (xy 114.188123 -281.414319)
			(xy 114.152429 -281.373132) (xy 114.12296 -281.327284) (xy 114.100316 -281.277709) (xy 114.084958 -281.225416)
			(xy 114.077199 -281.171469) (xy 114.076734 -281.144218) (xy 114.076791 -281.133592) (xy 114.077934 -281.112371)
			(xy 114.07902 -281.1018) (xy 114.080036 -281.092402) (xy 114.07521 -281.074114) (xy 114.029236 -281.010614)
			(xy 114.023407 -281.003328) (xy 114.007783 -280.993161) (xy 113.998756 -280.990802) (xy 113.998502 -280.990802)
			(xy 113.970202 -280.984435) (xy 113.915815 -280.964275) (xy 113.865106 -280.936112) (xy 113.819246 -280.900596)
			(xy 113.779292 -280.858547) (xy 113.746165 -280.810933) (xy 113.720629 -280.758853) (xy 113.703272 -280.703506)
			(xy 113.694495 -280.64617) (xy 113.693956 -280.617168) (xy 107.891764 -280.617168) (xy 107.885738 -280.63444)
			(xy 107.88142 -280.64587) (xy 107.88396 -280.669492) (xy 107.941364 -280.758138) (xy 107.962192 -280.77033)
			(xy 107.97413 -280.771092) (xy 108.002738 -280.773554) (xy 108.058804 -280.785934) (xy 108.112384 -280.806572)
			(xy 108.162267 -280.835004) (xy 108.207328 -280.870588) (xy 108.24655 -280.912521) (xy 108.279047 -280.959856)
			(xy 108.304087 -281.011525) (xy 108.321105 -281.066362) (xy 108.329715 -281.12313) (xy 108.330238 -281.151838)
			(xy 108.329975 -281.16657) (xy 108.75594 -281.16657) (xy 108.760011 -281.110948) (xy 108.772137 -281.056511)
			(xy 108.79206 -281.00442) (xy 108.819356 -280.955785) (xy 108.853442 -280.911642) (xy 108.893591 -280.872933)
			(xy 108.938949 -280.840482) (xy 108.988549 -280.814981) (xy 109.041333 -280.796974) (xy 109.096176 -280.786844)
			(xy 109.15191 -280.784807) (xy 109.207347 -280.790907) (xy 109.261304 -280.805013) (xy 109.312633 -280.826825)
			(xy 109.360239 -280.855879) (xy 109.403107 -280.891554) (xy 109.440324 -280.933091) (xy 109.471097 -280.979604)
			(xy 109.494769 -281.030101) (xy 109.510837 -281.083508) (xy 109.518957 -281.138684) (xy 109.519466 -281.16657)
			(xy 109.518957 -281.194456) (xy 109.510837 -281.249632) (xy 109.494769 -281.303039) (xy 109.471097 -281.353536)
			(xy 109.440324 -281.400049) (xy 109.403107 -281.441586) (xy 109.360239 -281.477261) (xy 109.312633 -281.506315)
			(xy 109.261304 -281.528127) (xy 109.207347 -281.542233) (xy 109.15191 -281.548333) (xy 109.096176 -281.546296)
			(xy 109.041333 -281.536166) (xy 108.988549 -281.518159) (xy 108.938949 -281.492658) (xy 108.893591 -281.460207)
			(xy 108.853442 -281.421498) (xy 108.819356 -281.377355) (xy 108.79206 -281.32872) (xy 108.772137 -281.276629)
			(xy 108.760011 -281.222192) (xy 108.75594 -281.16657) (xy 108.329975 -281.16657) (xy 108.329752 -281.179089)
			(xy 108.321996 -281.233037) (xy 108.306641 -281.285332) (xy 108.283999 -281.334909) (xy 108.254533 -281.380759)
			(xy 108.218842 -281.42195) (xy 108.177651 -281.457641) (xy 108.131801 -281.487107) (xy 108.082224 -281.509749)
			(xy 108.029929 -281.525104) (xy 107.975981 -281.53286) (xy 107.921479 -281.53286) (xy 107.867531 -281.525104)
			(xy 107.815236 -281.509749) (xy 107.765659 -281.487107) (xy 107.719809 -281.457641) (xy 107.678618 -281.42195)
			(xy 107.642927 -281.380759) (xy 107.613461 -281.334909) (xy 107.590819 -281.285332) (xy 107.575464 -281.233037)
			(xy 107.567708 -281.179089) (xy 107.567222 -281.151838) (xy 107.567971 -281.117754) (xy 107.580116 -281.050676)
			(xy 107.591352 -281.018488) (xy 107.59567 -281.007058) (xy 107.59313 -280.983436) (xy 107.535726 -280.89479)
			(xy 107.514898 -280.882598) (xy 107.50296 -280.881836) (xy 107.471662 -280.879092) (xy 107.410517 -280.864671)
			(xy 107.381294 -280.853134) (xy 107.371152 -280.849429) (xy 107.349586 -280.849953) (xy 107.339638 -280.85415)
			(xy 107.26166 -280.891234) (xy 107.24769 -280.90749) (xy 107.244642 -280.918158) (xy 107.236455 -280.944132)
			(xy 107.213776 -280.993642) (xy 107.184286 -281.039424) (xy 107.148587 -281.080548) (xy 107.107402 -281.116177)
			(xy 107.06157 -281.145588) (xy 107.012021 -281.168184) (xy 106.959763 -281.183504) (xy 106.905857 -281.191237)
			(xy 106.878628 -281.191716) (xy 106.855272 -281.19135) (xy 106.808913 -281.185619) (xy 106.786172 -281.180286)
			(xy 106.776649 -281.178396) (xy 106.757445 -281.181136) (xy 106.748834 -281.18562) (xy 106.68762 -281.220672)
			(xy 106.679351 -281.225879) (xy 106.667197 -281.241157) (xy 106.663998 -281.25039) (xy 106.663998 -281.250644)
			(xy 106.655965 -281.276752) (xy 106.633414 -281.326504) (xy 106.603996 -281.372529) (xy 106.568311 -281.413886)
			(xy 106.52709 -281.449727) (xy 106.481177 -281.47932) (xy 106.431511 -281.502059) (xy 106.379109 -281.517479)
			(xy 106.325042 -281.525263) (xy 106.29773 -281.525726) (xy 106.270479 -281.525217) (xy 106.21653 -281.517464)
			(xy 106.164234 -281.502113) (xy 106.114656 -281.479475) (xy 106.068803 -281.450012) (xy 106.027611 -281.414323)
			(xy 105.991917 -281.373135) (xy 105.962448 -281.327287) (xy 105.939804 -281.277711) (xy 105.924446 -281.225417)
			(xy 105.916687 -281.171469) (xy 105.916222 -281.144218) (xy 105.916279 -281.133592) (xy 105.917422 -281.112371)
			(xy 105.918508 -281.1018) (xy 105.919524 -281.092402) (xy 105.914698 -281.074114) (xy 105.868724 -281.010614)
			(xy 105.8629 -281.003324) (xy 105.847272 -280.993159) (xy 105.838244 -280.990802) (xy 105.83799 -280.990802)
			(xy 105.809688 -280.984444) (xy 105.755301 -280.964281) (xy 105.704593 -280.936117) (xy 105.658733 -280.9006)
			(xy 105.618779 -280.85855) (xy 105.585652 -280.810935) (xy 105.560116 -280.758854) (xy 105.54276 -280.703507)
			(xy 105.533983 -280.64617) (xy 105.533444 -280.617168) (xy 100.33 -280.617168) (xy 100.33 -282.904438)
			(xy 101.903022 -282.904438) (xy 101.903506 -282.876864) (xy 101.911454 -282.822292) (xy 101.927175 -282.769432)
			(xy 101.950341 -282.719386) (xy 101.980471 -282.673196) (xy 102.016936 -282.631824) (xy 102.037642 -282.613608)
			(xy 102.045721 -282.606056) (xy 102.055071 -282.586042) (xy 102.055676 -282.575) (xy 102.055676 -282.497276)
			(xy 102.055073 -282.486231) (xy 102.045733 -282.466209) (xy 102.037642 -282.458668) (xy 102.016921 -282.440468)
			(xy 101.980449 -282.399098) (xy 101.950317 -282.352906) (xy 101.927153 -282.302856) (xy 101.911439 -282.249991)
			(xy 101.903504 -282.195414) (xy 101.903022 -282.167838) (xy 101.903506 -282.140264) (xy 101.911454 -282.085692)
			(xy 101.927175 -282.032832) (xy 101.950341 -281.982786) (xy 101.980471 -281.936596) (xy 102.016936 -281.895224)
			(xy 102.037642 -281.877008) (xy 102.045721 -281.869456) (xy 102.055071 -281.849442) (xy 102.055676 -281.8384)
			(xy 102.055676 -281.760676) (xy 102.055073 -281.749631) (xy 102.045733 -281.729609) (xy 102.037642 -281.722068)
			(xy 102.016921 -281.703868) (xy 101.980449 -281.662498) (xy 101.950317 -281.616306) (xy 101.927153 -281.566256)
			(xy 101.911439 -281.513391) (xy 101.903504 -281.458814) (xy 101.903022 -281.431238) (xy 101.903491 -281.403985)
			(xy 101.911243 -281.350032) (xy 101.926596 -281.297733) (xy 101.949236 -281.248151) (xy 101.978703 -281.202296)
			(xy 102.014397 -281.161102) (xy 102.05559 -281.125408) (xy 102.101444 -281.09594) (xy 102.151025 -281.073299)
			(xy 102.203325 -281.057945) (xy 102.257277 -281.050191) (xy 102.28453 -281.04973) (xy 102.312387 -281.050204)
			(xy 102.367506 -281.058332) (xy 102.420859 -281.074383) (xy 102.471313 -281.098016) (xy 102.517798 -281.128729)
			(xy 102.559327 -281.165871) (xy 102.595019 -281.208652) (xy 102.624116 -281.256165) (xy 102.646 -281.307402)
			(xy 102.653592 -281.33421) (xy 102.655878 -281.3431) (xy 102.666546 -281.35834) (xy 102.738428 -281.406092)
			(xy 102.756462 -281.410156) (xy 102.765606 -281.408886) (xy 102.778623 -281.407218) (xy 102.804807 -281.405437)
			(xy 102.81793 -281.40533) (xy 102.831053 -281.405425) (xy 102.857239 -281.407203) (xy 102.870254 -281.408886)
			(xy 102.879398 -281.410156) (xy 102.897432 -281.406092) (xy 102.969314 -281.35834) (xy 102.979982 -281.3431)
			(xy 102.982268 -281.33421) (xy 102.989866 -281.307402) (xy 103.011728 -281.256153) (xy 103.040812 -281.208628)
			(xy 103.076499 -281.165839) (xy 103.118029 -281.128694) (xy 103.16452 -281.097985) (xy 103.214983 -281.074364)
			(xy 103.268345 -281.058334) (xy 103.323471 -281.050234) (xy 103.35133 -281.04973) (xy 103.378585 -281.050127)
			(xy 103.432541 -281.057889) (xy 103.484842 -281.073251) (xy 103.534425 -281.0959) (xy 103.58028 -281.125374)
			(xy 103.621473 -281.161075) (xy 103.657166 -281.202275) (xy 103.686633 -281.248135) (xy 103.709273 -281.297722)
			(xy 103.724625 -281.350026) (xy 103.732378 -281.403983) (xy 103.732838 -281.431238) (xy 103.732367 -281.458537)
			(xy 103.724591 -281.512579) (xy 103.709189 -281.564959) (xy 103.686476 -281.614609) (xy 103.656915 -281.660512)
			(xy 103.639366 -281.681428) (xy 103.633016 -281.688794) (xy 103.626666 -281.706574) (xy 103.629968 -281.795728)
			(xy 103.637842 -281.813508) (xy 103.6447 -281.820112) (xy 103.665831 -281.841741) (xy 103.701631 -281.89047)
			(xy 103.729295 -281.944237) (xy 103.735566 -281.963368) (xy 108.281722 -281.963368) (xy 108.285793 -281.907746)
			(xy 108.297919 -281.853309) (xy 108.317842 -281.801218) (xy 108.345138 -281.752583) (xy 108.379224 -281.70844)
			(xy 108.419373 -281.669731) (xy 108.464731 -281.63728) (xy 108.514331 -281.611779) (xy 108.567115 -281.593772)
			(xy 108.621958 -281.583642) (xy 108.677692 -281.581605) (xy 108.733129 -281.587705) (xy 108.787086 -281.601811)
			(xy 108.838415 -281.623623) (xy 108.886021 -281.652677) (xy 108.928889 -281.688352) (xy 108.966106 -281.729889)
			(xy 108.996879 -281.776402) (xy 109.020551 -281.826899) (xy 109.036619 -281.880306) (xy 109.044739 -281.935482)
			(xy 109.045248 -281.963368) (xy 109.044739 -281.991254) (xy 109.036619 -282.04643) (xy 109.020551 -282.099837)
			(xy 108.996879 -282.150334) (xy 108.966106 -282.196847) (xy 108.928889 -282.238384) (xy 108.886021 -282.274059)
			(xy 108.838415 -282.303113) (xy 108.787086 -282.324925) (xy 108.733129 -282.339031) (xy 108.677692 -282.345131)
			(xy 108.621958 -282.343094) (xy 108.567115 -282.332964) (xy 108.514331 -282.314957) (xy 108.464731 -282.289456)
			(xy 108.419373 -282.257005) (xy 108.379224 -282.218296) (xy 108.345138 -282.174153) (xy 108.317842 -282.125518)
			(xy 108.297919 -282.073427) (xy 108.285793 -282.01899) (xy 108.281722 -281.963368) (xy 103.735566 -281.963368)
			(xy 103.74813 -282.001695) (xy 103.757663 -282.061405) (xy 103.758238 -282.091638) (xy 103.757742 -282.119276)
			(xy 103.74975 -282.173971) (xy 103.733952 -282.226942) (xy 103.710681 -282.277081) (xy 103.680421 -282.323338)
			(xy 103.66248 -282.344368) (xy 103.654098 -282.353766) (xy 103.648256 -282.37815) (xy 103.672386 -282.47213)
			(xy 103.676088 -282.484075) (xy 103.692864 -282.502584) (xy 103.70439 -282.507436) (xy 103.731799 -282.517772)
			(xy 103.783314 -282.545654) (xy 103.829959 -282.581086) (xy 103.870637 -282.623235) (xy 103.904391 -282.671108)
			(xy 103.930427 -282.72358) (xy 103.948133 -282.779416) (xy 103.957092 -282.837304) (xy 103.957628 -282.866592)
			(xy 103.957115 -282.893842) (xy 103.957113 -282.893854) (xy 104.287247 -282.893854) (xy 104.287247 -282.839346)
			(xy 104.295005 -282.785392) (xy 104.310362 -282.733091) (xy 104.333007 -282.683509) (xy 104.362477 -282.637654)
			(xy 104.398174 -282.59646) (xy 104.43937 -282.560765) (xy 104.485226 -282.531297) (xy 104.53481 -282.508655)
			(xy 104.587111 -282.493301) (xy 104.641066 -282.485546) (xy 104.66832 -282.485084) (xy 104.695692 -282.485518)
			(xy 104.749873 -282.49334) (xy 104.802377 -282.508836) (xy 104.852124 -282.531685) (xy 104.898088 -282.561418)
			(xy 104.919018 -282.579064) (xy 104.919272 -282.579318) (xy 104.926361 -282.584901) (xy 104.943276 -282.591149)
			(xy 104.952292 -282.59151) (xy 105.019348 -282.59151) (xy 105.028362 -282.591126) (xy 105.045279 -282.584897)
			(xy 105.052368 -282.579318) (xy 105.052368 -282.579064) (xy 105.052622 -282.579064) (xy 105.073568 -282.561442)
			(xy 105.119538 -282.531729) (xy 105.169282 -282.50889) (xy 105.221779 -282.493395) (xy 105.275952 -282.485561)
			(xy 105.30332 -282.485084) (xy 105.33057 -282.485587) (xy 105.384514 -282.493346) (xy 105.436805 -282.508702)
			(xy 105.486379 -282.531344) (xy 105.532226 -282.56081) (xy 105.573413 -282.596501) (xy 105.609102 -282.63769)
			(xy 105.638565 -282.683538) (xy 105.661205 -282.733113) (xy 105.676558 -282.785405) (xy 105.684314 -282.83935)
			(xy 105.684314 -282.89385) (xy 105.682792 -282.904438) (xy 110.063534 -282.904438) (xy 110.064014 -282.876864)
			(xy 110.071962 -282.822291) (xy 110.087683 -282.769431) (xy 110.110851 -282.719385) (xy 110.140981 -282.673195)
			(xy 110.177447 -282.631824) (xy 110.198154 -282.613608) (xy 110.206234 -282.606058) (xy 110.215583 -282.586042)
			(xy 110.216188 -282.575) (xy 110.216188 -282.497276) (xy 110.215581 -282.486231) (xy 110.206244 -282.46621)
			(xy 110.198154 -282.458668) (xy 110.177415 -282.440487) (xy 110.140949 -282.399111) (xy 110.110821 -282.352914)
			(xy 110.087661 -282.302861) (xy 110.07195 -282.249993) (xy 110.064016 -282.195414) (xy 110.063534 -282.167838)
			(xy 110.064014 -282.140264) (xy 110.071962 -282.085691) (xy 110.087683 -282.032831) (xy 110.110851 -281.982785)
			(xy 110.140981 -281.936595) (xy 110.177447 -281.895224) (xy 110.198154 -281.877008) (xy 110.206234 -281.869458)
			(xy 110.215583 -281.849442) (xy 110.216188 -281.8384) (xy 110.216188 -281.760676) (xy 110.215581 -281.749631)
			(xy 110.206244 -281.72961) (xy 110.198154 -281.722068) (xy 110.177415 -281.703887) (xy 110.140949 -281.662511)
			(xy 110.110821 -281.616314) (xy 110.087661 -281.566261) (xy 110.07195 -281.513393) (xy 110.064016 -281.458814)
			(xy 110.063534 -281.431238) (xy 110.063991 -281.403984) (xy 110.071744 -281.350031) (xy 110.087097 -281.29773)
			(xy 110.109738 -281.248147) (xy 110.139206 -281.202292) (xy 110.174901 -281.161098) (xy 110.216095 -281.125404)
			(xy 110.261951 -281.095936) (xy 110.311534 -281.073296) (xy 110.363835 -281.057943) (xy 110.417788 -281.050191)
			(xy 110.445042 -281.04973) (xy 110.4729 -281.050193) (xy 110.528019 -281.058323) (xy 110.581372 -281.074376)
			(xy 110.631826 -281.09801) (xy 110.678311 -281.128725) (xy 110.71984 -281.165867) (xy 110.755531 -281.20865)
			(xy 110.784628 -281.256164) (xy 110.806512 -281.307402) (xy 110.814104 -281.33421) (xy 110.81639 -281.3431)
			(xy 110.827058 -281.35834) (xy 110.89894 -281.406092) (xy 110.916974 -281.410156) (xy 110.926118 -281.408886)
			(xy 110.939135 -281.407217) (xy 110.965319 -281.405437) (xy 110.978442 -281.40533) (xy 110.991565 -281.405424)
			(xy 111.017751 -281.407203) (xy 111.030766 -281.408886) (xy 111.03991 -281.410156) (xy 111.057944 -281.406092)
			(xy 111.129826 -281.35834) (xy 111.140494 -281.3431) (xy 111.14278 -281.33421) (xy 111.150367 -281.307399)
			(xy 111.17223 -281.256149) (xy 111.201315 -281.208623) (xy 111.237003 -281.165834) (xy 111.278535 -281.12869)
			(xy 111.325028 -281.097981) (xy 111.375492 -281.074361) (xy 111.428855 -281.058331) (xy 111.483983 -281.050233)
			(xy 111.511842 -281.04973) (xy 111.539096 -281.050139) (xy 111.593048 -281.057902) (xy 111.645347 -281.073264)
			(xy 111.694927 -281.095913) (xy 111.740779 -281.125387) (xy 111.78197 -281.161087) (xy 111.817661 -281.202285)
			(xy 111.847125 -281.248143) (xy 111.869764 -281.297728) (xy 111.885115 -281.35003) (xy 111.892867 -281.403984)
			(xy 111.89335 -281.431238) (xy 111.892876 -281.458537) (xy 111.8851 -281.512578) (xy 111.869699 -281.564959)
			(xy 111.846986 -281.614608) (xy 111.817427 -281.660512) (xy 111.799878 -281.681428) (xy 111.793528 -281.688794)
			(xy 111.787178 -281.706574) (xy 111.79048 -281.795728) (xy 111.798354 -281.813508) (xy 111.805212 -281.820112)
			(xy 111.826328 -281.841756) (xy 111.862133 -281.890479) (xy 111.889802 -281.944242) (xy 111.896073 -281.963368)
			(xy 116.442234 -281.963368) (xy 116.446305 -281.907746) (xy 116.458431 -281.853309) (xy 116.478354 -281.801218)
			(xy 116.50565 -281.752583) (xy 116.539736 -281.70844) (xy 116.579885 -281.669731) (xy 116.625243 -281.63728)
			(xy 116.674843 -281.611779) (xy 116.727627 -281.593772) (xy 116.78247 -281.583642) (xy 116.838204 -281.581605)
			(xy 116.893641 -281.587705) (xy 116.947598 -281.601811) (xy 116.998927 -281.623623) (xy 117.046533 -281.652677)
			(xy 117.089401 -281.688352) (xy 117.126618 -281.729889) (xy 117.157391 -281.776402) (xy 117.181063 -281.826899)
			(xy 117.197131 -281.880306) (xy 117.205251 -281.935482) (xy 117.20576 -281.963368) (xy 117.205251 -281.991254)
			(xy 117.197131 -282.04643) (xy 117.181063 -282.099837) (xy 117.157391 -282.150334) (xy 117.126618 -282.196847)
			(xy 117.089401 -282.238384) (xy 117.046533 -282.274059) (xy 116.998927 -282.303113) (xy 116.947598 -282.324925)
			(xy 116.893641 -282.339031) (xy 116.838204 -282.345131) (xy 116.78247 -282.343094) (xy 116.727627 -282.332964)
			(xy 116.674843 -282.314957) (xy 116.625243 -282.289456) (xy 116.579885 -282.257005) (xy 116.539736 -282.218296)
			(xy 116.50565 -282.174153) (xy 116.478354 -282.125518) (xy 116.458431 -282.073427) (xy 116.446305 -282.01899)
			(xy 116.442234 -281.963368) (xy 111.896073 -281.963368) (xy 111.90864 -282.001697) (xy 111.918175 -282.061406)
			(xy 111.91875 -282.091638) (xy 111.918251 -282.119276) (xy 111.910259 -282.173971) (xy 111.894462 -282.226942)
			(xy 111.871191 -282.27708) (xy 111.840932 -282.323338) (xy 111.822992 -282.344368) (xy 111.81461 -282.353766)
			(xy 111.808768 -282.37815) (xy 111.832898 -282.47213) (xy 111.836594 -282.484078) (xy 111.853374 -282.502586)
			(xy 111.864902 -282.507436) (xy 111.892314 -282.517765) (xy 111.943828 -282.545649) (xy 111.990473 -282.581082)
			(xy 112.03115 -282.623232) (xy 112.064904 -282.671106) (xy 112.09094 -282.723579) (xy 112.108645 -282.779416)
			(xy 112.117604 -282.837304) (xy 112.11814 -282.866592) (xy 112.117605 -282.893855) (xy 112.447747 -282.893855)
			(xy 112.447747 -282.839345) (xy 112.455505 -282.78539) (xy 112.470863 -282.733089) (xy 112.493509 -282.683505)
			(xy 112.52298 -282.63765) (xy 112.558678 -282.596455) (xy 112.599876 -282.560761) (xy 112.645734 -282.531293)
			(xy 112.695319 -282.508652) (xy 112.747622 -282.493299) (xy 112.801577 -282.485545) (xy 112.828832 -282.485084)
			(xy 112.856204 -282.485511) (xy 112.910385 -282.493335) (xy 112.96289 -282.508832) (xy 113.012636 -282.531683)
			(xy 113.0586 -282.561418) (xy 113.07953 -282.579064) (xy 113.079784 -282.579318) (xy 113.086869 -282.584906)
			(xy 113.103787 -282.591151) (xy 113.112804 -282.59151) (xy 113.17986 -282.59151) (xy 113.188875 -282.591132)
			(xy 113.205792 -282.584899) (xy 113.21288 -282.579318) (xy 113.21288 -282.579064) (xy 113.213134 -282.579064)
			(xy 113.234076 -282.561437) (xy 113.280046 -282.531724) (xy 113.329791 -282.508887) (xy 113.38229 -282.493393)
			(xy 113.436464 -282.48556) (xy 113.463832 -282.485084) (xy 113.491081 -282.485588) (xy 113.545024 -282.493348)
			(xy 113.597314 -282.508706) (xy 113.646886 -282.531348) (xy 113.692732 -282.560815) (xy 113.733917 -282.596505)
			(xy 113.769605 -282.637694) (xy 113.799067 -282.683542) (xy 113.821706 -282.733116) (xy 113.837059 -282.785407)
			(xy 113.844814 -282.839351) (xy 113.844814 -282.893849) (xy 113.843292 -282.904438) (xy 118.56212 -282.904438)
			(xy 118.562605 -282.876864) (xy 118.570552 -282.822292) (xy 118.586273 -282.769432) (xy 118.60944 -282.719386)
			(xy 118.639569 -282.673196) (xy 118.676034 -282.631824) (xy 118.69674 -282.613608) (xy 118.704818 -282.606056)
			(xy 118.714169 -282.586042) (xy 118.714774 -282.575) (xy 118.714774 -282.497276) (xy 118.714172 -282.486231)
			(xy 118.704832 -282.466209) (xy 118.69674 -282.458668) (xy 118.676018 -282.440468) (xy 118.639547 -282.399098)
			(xy 118.609415 -282.352906) (xy 118.586251 -282.302856) (xy 118.570537 -282.249991) (xy 118.562602 -282.195414)
			(xy 118.56212 -282.167838) (xy 118.562605 -282.140264) (xy 118.570552 -282.085692) (xy 118.586273 -282.032832)
			(xy 118.60944 -281.982786) (xy 118.639569 -281.936596) (xy 118.676034 -281.895224) (xy 118.69674 -281.877008)
			(xy 118.704818 -281.869456) (xy 118.714169 -281.849442) (xy 118.714774 -281.8384) (xy 118.714774 -281.760676)
			(xy 118.714172 -281.749631) (xy 118.704832 -281.729609) (xy 118.69674 -281.722068) (xy 118.676018 -281.703868)
			(xy 118.639547 -281.662498) (xy 118.609415 -281.616306) (xy 118.586251 -281.566256) (xy 118.570537 -281.513391)
			(xy 118.562602 -281.458814) (xy 118.56212 -281.431238) (xy 118.562591 -281.403985) (xy 118.570343 -281.350033)
			(xy 118.585696 -281.297733) (xy 118.608336 -281.248151) (xy 118.637803 -281.202297) (xy 118.673496 -281.161103)
			(xy 118.714689 -281.125409) (xy 118.760543 -281.095941) (xy 118.810124 -281.073299) (xy 118.862423 -281.057945)
			(xy 118.916375 -281.050191) (xy 118.943628 -281.04973) (xy 118.971485 -281.050206) (xy 119.026604 -281.058334)
			(xy 119.079956 -281.074385) (xy 119.130411 -281.098017) (xy 119.176896 -281.12873) (xy 119.218425 -281.165871)
			(xy 119.254117 -281.208652) (xy 119.283214 -281.256166) (xy 119.305098 -281.307402) (xy 119.31269 -281.33421)
			(xy 119.314976 -281.3431) (xy 119.325644 -281.35834) (xy 119.397526 -281.406092) (xy 119.41556 -281.410156)
			(xy 119.424704 -281.408886) (xy 119.437721 -281.407218) (xy 119.463905 -281.405438) (xy 119.477028 -281.40533)
			(xy 119.490151 -281.405425) (xy 119.516337 -281.407203) (xy 119.529352 -281.408886) (xy 119.538496 -281.410156)
			(xy 119.55653 -281.406092) (xy 119.628412 -281.35834) (xy 119.63908 -281.3431) (xy 119.641366 -281.33421)
			(xy 119.648875 -281.307374) (xy 119.670745 -281.25612) (xy 119.699839 -281.208591) (xy 119.735536 -281.1658)
			(xy 119.777078 -281.128657) (xy 119.823581 -281.097951) (xy 119.874056 -281.074336) (xy 119.927429 -281.058315)
			(xy 119.982565 -281.050227) (xy 120.010428 -281.04973) (xy 120.037683 -281.050129) (xy 120.091639 -281.057891)
			(xy 120.14394 -281.073252) (xy 120.193523 -281.095901) (xy 120.239378 -281.125375) (xy 120.280571 -281.161076)
			(xy 120.316264 -281.202275) (xy 120.345731 -281.248135) (xy 120.368371 -281.297722) (xy 120.383723 -281.350026)
			(xy 120.391476 -281.403983) (xy 120.391936 -281.431238) (xy 120.391466 -281.458537) (xy 120.383689 -281.512579)
			(xy 120.368287 -281.564959) (xy 120.345574 -281.614609) (xy 120.316013 -281.660512) (xy 120.298464 -281.681428)
			(xy 120.292114 -281.688794) (xy 120.285764 -281.706574) (xy 120.289066 -281.795728) (xy 120.29694 -281.813508)
			(xy 120.303798 -281.820112) (xy 120.324929 -281.841741) (xy 120.360729 -281.89047) (xy 120.388393 -281.944237)
			(xy 120.394664 -281.963368) (xy 124.94082 -281.963368) (xy 124.944891 -281.907746) (xy 124.957017 -281.853309)
			(xy 124.97694 -281.801218) (xy 125.004236 -281.752583) (xy 125.038322 -281.70844) (xy 125.078471 -281.669731)
			(xy 125.123829 -281.63728) (xy 125.173429 -281.611779) (xy 125.226213 -281.593772) (xy 125.281056 -281.583642)
			(xy 125.33679 -281.581605) (xy 125.392227 -281.587705) (xy 125.446184 -281.601811) (xy 125.497513 -281.623623)
			(xy 125.545119 -281.652677) (xy 125.587987 -281.688352) (xy 125.625204 -281.729889) (xy 125.655977 -281.776402)
			(xy 125.679649 -281.826899) (xy 125.695717 -281.880306) (xy 125.703837 -281.935482) (xy 125.704346 -281.963368)
			(xy 125.703837 -281.991254) (xy 125.695717 -282.04643) (xy 125.679649 -282.099837) (xy 125.655977 -282.150334)
			(xy 125.625204 -282.196847) (xy 125.587987 -282.238384) (xy 125.545119 -282.274059) (xy 125.497513 -282.303113)
			(xy 125.446184 -282.324925) (xy 125.392227 -282.339031) (xy 125.33679 -282.345131) (xy 125.281056 -282.343094)
			(xy 125.226213 -282.332964) (xy 125.173429 -282.314957) (xy 125.123829 -282.289456) (xy 125.078471 -282.257005)
			(xy 125.038322 -282.218296) (xy 125.004236 -282.174153) (xy 124.97694 -282.125518) (xy 124.957017 -282.073427)
			(xy 124.944891 -282.01899) (xy 124.94082 -281.963368) (xy 120.394664 -281.963368) (xy 120.407228 -282.001695)
			(xy 120.416761 -282.061405) (xy 120.417336 -282.091638) (xy 120.41684 -282.119276) (xy 120.408848 -282.173971)
			(xy 120.393051 -282.226942) (xy 120.369779 -282.277081) (xy 120.339519 -282.323339) (xy 120.321578 -282.344368)
			(xy 120.313196 -282.353766) (xy 120.307354 -282.37815) (xy 120.331484 -282.47213) (xy 120.335187 -282.484075)
			(xy 120.351962 -282.502584) (xy 120.363488 -282.507436) (xy 120.390896 -282.517773) (xy 120.442411 -282.545655)
			(xy 120.489057 -282.581087) (xy 120.529735 -282.623235) (xy 120.563489 -282.671108) (xy 120.589525 -282.72358)
			(xy 120.607231 -282.779417) (xy 120.61619 -282.837304) (xy 120.616726 -282.866592) (xy 120.616192 -282.893854)
			(xy 120.946347 -282.893854) (xy 120.946347 -282.839346) (xy 120.954105 -282.785392) (xy 120.969462 -282.733092)
			(xy 120.992107 -282.683509) (xy 121.021577 -282.637654) (xy 121.057273 -282.59646) (xy 121.098469 -282.560766)
			(xy 121.144325 -282.531298) (xy 121.193909 -282.508656) (xy 121.24621 -282.493301) (xy 121.300164 -282.485546)
			(xy 121.327418 -282.485084) (xy 121.35479 -282.485519) (xy 121.408971 -282.493341) (xy 121.461475 -282.508836)
			(xy 121.511222 -282.531686) (xy 121.557186 -282.561418) (xy 121.578116 -282.579064) (xy 121.57837 -282.579318)
			(xy 121.58546 -282.5849) (xy 121.602374 -282.591149) (xy 121.61139 -282.59151) (xy 121.678446 -282.59151)
			(xy 121.68746 -282.591125) (xy 121.704377 -282.584897) (xy 121.711466 -282.579318) (xy 121.711466 -282.579064)
			(xy 121.71172 -282.579064) (xy 121.732667 -282.561443) (xy 121.778636 -282.53173) (xy 121.82838 -282.508891)
			(xy 121.880877 -282.493396) (xy 121.93505 -282.485561) (xy 121.962418 -282.485084) (xy 121.989668 -282.485587)
			(xy 122.043612 -282.493345) (xy 122.095904 -282.508702) (xy 122.145478 -282.531343) (xy 122.191325 -282.56081)
			(xy 122.232512 -282.5965) (xy 122.268201 -282.637689) (xy 122.297665 -282.683538) (xy 122.320305 -282.733113)
			(xy 122.335658 -282.785405) (xy 122.343414 -282.83935) (xy 122.343414 -282.89385) (xy 122.341892 -282.904438)
			(xy 126.722632 -282.904438) (xy 126.723113 -282.876864) (xy 126.731061 -282.822291) (xy 126.746782 -282.769431)
			(xy 126.769949 -282.719385) (xy 126.800079 -282.673195) (xy 126.836545 -282.631824) (xy 126.857252 -282.613608)
			(xy 126.865332 -282.606058) (xy 126.874681 -282.586042) (xy 126.875286 -282.575) (xy 126.875286 -282.497276)
			(xy 126.87468 -282.486231) (xy 126.865342 -282.46621) (xy 126.857252 -282.458668) (xy 126.836513 -282.440488)
			(xy 126.800046 -282.399111) (xy 126.769919 -282.352915) (xy 126.746759 -282.302861) (xy 126.731048 -282.249993)
			(xy 126.723114 -282.195414) (xy 126.722632 -282.167838) (xy 126.723113 -282.140264) (xy 126.731061 -282.085691)
			(xy 126.746782 -282.032831) (xy 126.769949 -281.982785) (xy 126.800079 -281.936595) (xy 126.836545 -281.895224)
			(xy 126.857252 -281.877008) (xy 126.865332 -281.869458) (xy 126.874681 -281.849442) (xy 126.875286 -281.8384)
			(xy 126.875286 -281.760676) (xy 126.87468 -281.749631) (xy 126.865342 -281.72961) (xy 126.857252 -281.722068)
			(xy 126.836513 -281.703888) (xy 126.800046 -281.662511) (xy 126.769919 -281.616315) (xy 126.746759 -281.566261)
			(xy 126.731048 -281.513393) (xy 126.723114 -281.458814) (xy 126.722632 -281.431238) (xy 126.723091 -281.403984)
			(xy 126.730844 -281.350031) (xy 126.746197 -281.297731) (xy 126.768838 -281.248148) (xy 126.798306 -281.202293)
			(xy 126.834 -281.161099) (xy 126.875194 -281.125404) (xy 126.92105 -281.095937) (xy 126.970633 -281.073296)
			(xy 127.022933 -281.057943) (xy 127.076886 -281.050191) (xy 127.10414 -281.04973) (xy 127.131997 -281.050195)
			(xy 127.187117 -281.058325) (xy 127.240469 -281.074377) (xy 127.290924 -281.098011) (xy 127.337409 -281.128725)
			(xy 127.378938 -281.165868) (xy 127.414629 -281.20865) (xy 127.443726 -281.256164) (xy 127.46561 -281.307402)
			(xy 127.473202 -281.33421) (xy 127.475488 -281.3431) (xy 127.486156 -281.35834) (xy 127.558038 -281.406092)
			(xy 127.576072 -281.410156) (xy 127.585216 -281.408886) (xy 127.598233 -281.407217) (xy 127.624417 -281.405437)
			(xy 127.63754 -281.40533) (xy 127.650663 -281.405424) (xy 127.676849 -281.407203) (xy 127.689864 -281.408886)
			(xy 127.699008 -281.410156) (xy 127.717042 -281.406092) (xy 127.788924 -281.35834) (xy 127.799592 -281.3431)
			(xy 127.801878 -281.33421) (xy 127.809467 -281.307399) (xy 127.83133 -281.256149) (xy 127.860415 -281.208624)
			(xy 127.896103 -281.165835) (xy 127.937634 -281.12869) (xy 127.984126 -281.097982) (xy 128.034591 -281.074361)
			(xy 128.087954 -281.058332) (xy 128.143081 -281.050234) (xy 128.17094 -281.04973) (xy 128.198194 -281.050141)
			(xy 128.252146 -281.057904) (xy 128.304445 -281.073266) (xy 128.354025 -281.095914) (xy 128.399877 -281.125388)
			(xy 128.441068 -281.161088) (xy 128.476758 -281.202286) (xy 128.506223 -281.248144) (xy 128.528862 -281.297728)
			(xy 128.544213 -281.35003) (xy 128.551965 -281.403984) (xy 128.552448 -281.431238) (xy 128.551975 -281.458537)
			(xy 128.544199 -281.512578) (xy 128.528797 -281.564959) (xy 128.506085 -281.614608) (xy 128.476525 -281.660512)
			(xy 128.458976 -281.681428) (xy 128.452626 -281.688794) (xy 128.446276 -281.706574) (xy 128.449578 -281.795728)
			(xy 128.457452 -281.813508) (xy 128.46431 -281.820112) (xy 128.485426 -281.841756) (xy 128.521231 -281.890479)
			(xy 128.5489 -281.944242) (xy 128.555171 -281.963368) (xy 133.101332 -281.963368) (xy 133.105403 -281.907746)
			(xy 133.117529 -281.853309) (xy 133.137452 -281.801218) (xy 133.164748 -281.752583) (xy 133.198834 -281.70844)
			(xy 133.238983 -281.669731) (xy 133.284341 -281.63728) (xy 133.333941 -281.611779) (xy 133.386725 -281.593772)
			(xy 133.441568 -281.583642) (xy 133.497302 -281.581605) (xy 133.552739 -281.587705) (xy 133.606696 -281.601811)
			(xy 133.658025 -281.623623) (xy 133.705631 -281.652677) (xy 133.748499 -281.688352) (xy 133.785716 -281.729889)
			(xy 133.816489 -281.776402) (xy 133.840161 -281.826899) (xy 133.856229 -281.880306) (xy 133.864349 -281.935482)
			(xy 133.864858 -281.963368) (xy 133.864349 -281.991254) (xy 133.856229 -282.04643) (xy 133.840161 -282.099837)
			(xy 133.816489 -282.150334) (xy 133.785716 -282.196847) (xy 133.748499 -282.238384) (xy 133.705631 -282.274059)
			(xy 133.658025 -282.303113) (xy 133.606696 -282.324925) (xy 133.552739 -282.339031) (xy 133.497302 -282.345131)
			(xy 133.441568 -282.343094) (xy 133.386725 -282.332964) (xy 133.333941 -282.314957) (xy 133.284341 -282.289456)
			(xy 133.238983 -282.257005) (xy 133.198834 -282.218296) (xy 133.164748 -282.174153) (xy 133.137452 -282.125518)
			(xy 133.117529 -282.073427) (xy 133.105403 -282.01899) (xy 133.101332 -281.963368) (xy 128.555171 -281.963368)
			(xy 128.567738 -282.001697) (xy 128.577273 -282.061406) (xy 128.577848 -282.091638) (xy 128.577349 -282.119276)
			(xy 128.569357 -282.173971) (xy 128.553561 -282.226942) (xy 128.530289 -282.27708) (xy 128.50003 -282.323338)
			(xy 128.48209 -282.344368) (xy 128.473708 -282.353766) (xy 128.467866 -282.37815) (xy 128.491996 -282.47213)
			(xy 128.495693 -282.484077) (xy 128.512472 -282.502586) (xy 128.524 -282.507436) (xy 128.551411 -282.517766)
			(xy 128.602926 -282.54565) (xy 128.64957 -282.581083) (xy 128.690248 -282.623232) (xy 128.724002 -282.671106)
			(xy 128.750038 -282.723579) (xy 128.767743 -282.779416) (xy 128.776702 -282.837304) (xy 128.777238 -282.866592)
			(xy 128.776703 -282.893855) (xy 129.106847 -282.893855) (xy 129.106847 -282.839345) (xy 129.114605 -282.785391)
			(xy 129.129963 -282.733089) (xy 129.152608 -282.683506) (xy 129.18208 -282.637651) (xy 129.217777 -282.596456)
			(xy 129.258975 -282.560762) (xy 129.304832 -282.531294) (xy 129.354417 -282.508653) (xy 129.40672 -282.493299)
			(xy 129.460675 -282.485545) (xy 129.48793 -282.485084) (xy 129.515302 -282.485512) (xy 129.569483 -282.493336)
			(xy 129.621988 -282.508833) (xy 129.671734 -282.531683) (xy 129.717698 -282.561418) (xy 129.738628 -282.579064)
			(xy 129.738882 -282.579318) (xy 129.745968 -282.584905) (xy 129.762885 -282.591151) (xy 129.771902 -282.59151)
			(xy 129.838958 -282.59151) (xy 129.847973 -282.591131) (xy 129.86489 -282.584898) (xy 129.871978 -282.579318)
			(xy 129.871978 -282.579064) (xy 129.872232 -282.579064) (xy 129.893174 -282.561438) (xy 129.939145 -282.531725)
			(xy 129.98889 -282.508887) (xy 130.041388 -282.493393) (xy 130.095562 -282.485561) (xy 130.12293 -282.485084)
			(xy 130.150179 -282.485588) (xy 130.204123 -282.493348) (xy 130.256413 -282.508705) (xy 130.305985 -282.531347)
			(xy 130.351831 -282.560814) (xy 130.393017 -282.596505) (xy 130.428704 -282.637693) (xy 130.458167 -282.683541)
			(xy 130.480805 -282.733115) (xy 130.496159 -282.785407) (xy 130.503914 -282.839351) (xy 130.503914 -282.893849)
			(xy 130.496159 -282.947793) (xy 130.480805 -283.000085) (xy 130.458167 -283.049659) (xy 130.428704 -283.095507)
			(xy 130.393017 -283.136695) (xy 130.351831 -283.172386) (xy 130.305985 -283.201853) (xy 130.256413 -283.224495)
			(xy 130.204123 -283.239852) (xy 130.150179 -283.247612) (xy 130.12293 -283.2481) (xy 130.09556 -283.247616)
			(xy 130.041382 -283.239803) (xy 129.988879 -283.224318) (xy 129.939132 -283.20148) (xy 129.893164 -283.171759)
			(xy 129.872232 -283.15412) (xy 129.871978 -283.153866) (xy 129.864905 -283.14826) (xy 129.847978 -283.142026)
			(xy 129.838958 -283.141674) (xy 129.771902 -283.141674) (xy 129.762886 -283.142038) (xy 129.745969 -283.148281)
			(xy 129.738882 -283.153866) (xy 129.738882 -283.15412) (xy 129.738628 -283.15412) (xy 129.717699 -283.171763)
			(xy 129.671725 -283.201473) (xy 129.621977 -283.224308) (xy 129.569475 -283.239798) (xy 129.515299 -283.247626)
			(xy 129.48793 -283.2481) (xy 129.460675 -283.247655) (xy 129.40672 -283.239901) (xy 129.354417 -283.224547)
			(xy 129.304832 -283.201906) (xy 129.258975 -283.172438) (xy 129.217777 -283.136744) (xy 129.18208 -283.095549)
			(xy 129.152608 -283.049694) (xy 129.129963 -283.000111) (xy 129.114605 -282.947809) (xy 129.106847 -282.893855)
			(xy 128.776703 -282.893855) (xy 128.776652 -282.89643) (xy 128.767344 -282.955376) (xy 128.758696 -282.98394)
			(xy 128.755394 -282.994354) (xy 128.75768 -283.015944) (xy 128.807972 -283.100526) (xy 128.825244 -283.112972)
			(xy 128.836166 -283.115004) (xy 128.861983 -283.120344) (xy 128.911899 -283.137313) (xy 128.959003 -283.160993)
			(xy 129.002398 -283.190934) (xy 129.041256 -283.226565) (xy 129.074838 -283.267208) (xy 129.102503 -283.312087)
			(xy 129.123725 -283.360349) (xy 129.138099 -283.411073) (xy 129.145351 -283.463293) (xy 129.145792 -283.489654)
			(xy 129.145209 -283.519777) (xy 129.135733 -283.579274) (xy 129.117026 -283.636542) (xy 129.089553 -283.690159)
			(xy 129.053995 -283.738793) (xy 129.033016 -283.760418) (xy 129.026178 -283.76782) (xy 129.018456 -283.786418)
			(xy 129.01803 -283.796486) (xy 129.01803 -283.868622) (xy 129.018436 -283.878694) (xy 129.02617 -283.897292)
			(xy 129.033016 -283.90469) (xy 129.054019 -283.926293) (xy 129.089584 -283.974928) (xy 129.117059 -284.02855)
			(xy 129.131438 -284.072584) (xy 134.033006 -284.072584) (xy 134.033461 -284.045213) (xy 134.041281 -283.991034)
			(xy 134.056773 -283.93853) (xy 134.079617 -283.888784) (xy 134.109344 -283.842817) (xy 134.126986 -283.821886)
			(xy 134.12724 -283.821632) (xy 134.132824 -283.814544) (xy 134.139071 -283.797628) (xy 134.139432 -283.788612)
			(xy 134.139432 -283.721556) (xy 134.139041 -283.712543) (xy 134.132816 -283.695626) (xy 134.12724 -283.688536)
			(xy 134.126986 -283.688536) (xy 134.126986 -283.688282) (xy 134.10937 -283.667332) (xy 134.079655 -283.621364)
			(xy 134.056815 -283.571621) (xy 134.041318 -283.519124) (xy 134.033484 -283.464952) (xy 134.033006 -283.437584)
			(xy 134.033492 -283.410333) (xy 134.041248 -283.356385) (xy 134.056603 -283.30409) (xy 134.079245 -283.254513)
			(xy 134.108711 -283.208663) (xy 134.144402 -283.167472) (xy 134.185593 -283.131781) (xy 134.231443 -283.102315)
			(xy 134.28102 -283.079673) (xy 134.333315 -283.064318) (xy 134.387263 -283.056562) (xy 134.441765 -283.056562)
			(xy 134.495713 -283.064318) (xy 134.548008 -283.079673) (xy 134.597585 -283.102315) (xy 134.643435 -283.131781)
			(xy 134.684626 -283.167472) (xy 134.720317 -283.208663) (xy 134.749783 -283.254513) (xy 134.772425 -283.30409)
			(xy 134.78778 -283.356385) (xy 134.795536 -283.410333) (xy 134.796022 -283.437584) (xy 134.795566 -283.464955)
			(xy 134.787748 -283.519135) (xy 134.772258 -283.571639) (xy 134.749414 -283.621386) (xy 134.719685 -283.667351)
			(xy 134.702042 -283.688282) (xy 134.701788 -283.688536) (xy 134.696221 -283.695636) (xy 134.689963 -283.712542)
			(xy 134.689596 -283.721556) (xy 134.689596 -283.788612) (xy 134.689948 -283.797629) (xy 134.696199 -283.814546)
			(xy 134.701788 -283.821632) (xy 134.702042 -283.821632) (xy 134.702042 -283.821886) (xy 134.719695 -283.842807)
			(xy 134.749403 -283.888783) (xy 134.772236 -283.938534) (xy 134.787724 -283.991037) (xy 134.79555 -284.045214)
			(xy 134.796022 -284.072584) (xy 134.795536 -284.099835) (xy 134.78778 -284.153783) (xy 134.772425 -284.206078)
			(xy 134.749783 -284.255655) (xy 134.720317 -284.301505) (xy 134.684626 -284.342696) (xy 134.643435 -284.378387)
			(xy 134.597585 -284.407853) (xy 134.548008 -284.430495) (xy 134.495713 -284.44585) (xy 134.441765 -284.453606)
			(xy 134.387263 -284.453606) (xy 134.333315 -284.44585) (xy 134.28102 -284.430495) (xy 134.231443 -284.407853)
			(xy 134.185593 -284.378387) (xy 134.144402 -284.342696) (xy 134.108711 -284.301505) (xy 134.079245 -284.255655)
			(xy 134.056603 -284.206078) (xy 134.041248 -284.153783) (xy 134.033492 -284.099835) (xy 134.033006 -284.072584)
			(xy 129.131438 -284.072584) (xy 129.135762 -284.085825) (xy 129.145227 -284.145328) (xy 129.145792 -284.175454)
			(xy 129.145306 -284.202705) (xy 129.13755 -284.256653) (xy 129.122195 -284.308948) (xy 129.099553 -284.358525)
			(xy 129.070087 -284.404375) (xy 129.034396 -284.445566) (xy 128.993205 -284.481257) (xy 128.947355 -284.510723)
			(xy 128.897778 -284.533365) (xy 128.845483 -284.54872) (xy 128.791535 -284.556476) (xy 128.737033 -284.556476)
			(xy 128.683085 -284.54872) (xy 128.63079 -284.533365) (xy 128.581213 -284.510723) (xy 128.535363 -284.481257)
			(xy 128.494172 -284.445566) (xy 128.458481 -284.404375) (xy 128.429015 -284.358525) (xy 128.406373 -284.308948)
			(xy 128.391018 -284.256653) (xy 128.383262 -284.202705) (xy 128.382776 -284.175454) (xy 128.383374 -284.145332)
			(xy 128.392847 -284.085836) (xy 128.411551 -284.028568) (xy 128.439021 -283.974951) (xy 128.474575 -283.926316)
			(xy 128.495552 -283.90469) (xy 128.502382 -283.897282) (xy 128.510109 -283.878689) (xy 128.510538 -283.868622)
			(xy 128.510538 -283.796486) (xy 128.510136 -283.786414) (xy 128.502401 -283.767815) (xy 128.495552 -283.760418)
			(xy 128.474564 -283.7388) (xy 128.438995 -283.69017) (xy 128.411515 -283.636552) (xy 128.392809 -283.57928)
			(xy 128.383342 -283.519779) (xy 128.382776 -283.489654) (xy 128.383349 -283.459815) (xy 128.392666 -283.400869)
			(xy 128.401318 -283.372306) (xy 128.40462 -283.361892) (xy 128.402334 -283.340302) (xy 128.352042 -283.25572)
			(xy 128.33477 -283.243274) (xy 128.323848 -283.241242) (xy 128.295998 -283.235391) (xy 128.242335 -283.216454)
			(xy 128.192078 -283.18976) (xy 128.146341 -283.155899) (xy 128.106139 -283.115622) (xy 128.072363 -283.069823)
			(xy 128.045761 -283.019516) (xy 128.026924 -282.965818) (xy 128.02108 -282.937966) (xy 128.01854 -282.92552)
			(xy 128.0033 -282.906216) (xy 127.902208 -282.862528) (xy 127.87757 -282.864306) (xy 127.866902 -282.871164)
			(xy 127.843932 -282.885202) (xy 127.794858 -282.907333) (xy 127.743156 -282.922329) (xy 127.689857 -282.929892)
			(xy 127.66294 -282.930346) (xy 127.644921 -282.930129) (xy 127.609046 -282.926692) (xy 127.591312 -282.923488)
			(xy 127.58166 -282.92171) (xy 127.56261 -282.925266) (xy 127.48768 -282.973272) (xy 127.47625 -282.98902)
			(xy 127.473964 -282.998418) (xy 127.466566 -283.025463) (xy 127.444939 -283.07719) (xy 127.415976 -283.125197)
			(xy 127.380301 -283.16845) (xy 127.338682 -283.206018) (xy 127.292014 -283.237092) (xy 127.241301 -283.261004)
			(xy 127.187636 -283.27724) (xy 127.132173 -283.285449) (xy 127.10414 -283.285946) (xy 127.07689 -283.285408)
			(xy 127.022944 -283.277657) (xy 126.970649 -283.262308) (xy 126.921072 -283.239673) (xy 126.875221 -283.210213)
			(xy 126.834028 -283.174527) (xy 126.798334 -283.133342) (xy 126.768864 -283.087497) (xy 126.746219 -283.037924)
			(xy 126.73086 -282.985633) (xy 126.723098 -282.931688) (xy 126.722632 -282.904438) (xy 122.341892 -282.904438)
			(xy 122.335658 -282.947795) (xy 122.320305 -283.000087) (xy 122.297665 -283.049662) (xy 122.268201 -283.095511)
			(xy 122.232512 -283.1367) (xy 122.191325 -283.17239) (xy 122.145478 -283.201857) (xy 122.095904 -283.224498)
			(xy 122.043612 -283.239855) (xy 121.989668 -283.247613) (xy 121.962418 -283.2481) (xy 121.935048 -283.247623)
			(xy 121.88087 -283.239808) (xy 121.828367 -283.224321) (xy 121.778619 -283.201482) (xy 121.732652 -283.17176)
			(xy 121.71172 -283.15412) (xy 121.711466 -283.153866) (xy 121.704367 -283.148297) (xy 121.68746 -283.142041)
			(xy 121.678446 -283.141674) (xy 121.61139 -283.141674) (xy 121.602373 -283.142032) (xy 121.585457 -283.14828)
			(xy 121.57837 -283.153866) (xy 121.57837 -283.15412) (xy 121.578116 -283.15412) (xy 121.557191 -283.171768)
			(xy 121.511216 -283.201478) (xy 121.461467 -283.224312) (xy 121.408965 -283.239801) (xy 121.354788 -283.247627)
			(xy 121.327418 -283.2481) (xy 121.300164 -283.247654) (xy 121.24621 -283.239899) (xy 121.193909 -283.224544)
			(xy 121.144325 -283.201902) (xy 121.098469 -283.172434) (xy 121.057273 -283.13674) (xy 121.021577 -283.095546)
			(xy 120.992107 -283.049691) (xy 120.969462 -283.000108) (xy 120.954105 -282.947808) (xy 120.946347 -282.893854)
			(xy 120.616192 -282.893854) (xy 120.616141 -282.89643) (xy 120.606832 -282.955376) (xy 120.598184 -282.98394)
			(xy 120.594882 -282.994354) (xy 120.597168 -283.015944) (xy 120.64746 -283.100526) (xy 120.664732 -283.112972)
			(xy 120.675654 -283.115004) (xy 120.701469 -283.120353) (xy 120.751385 -283.13732) (xy 120.798489 -283.160999)
			(xy 120.841884 -283.190938) (xy 120.880743 -283.226569) (xy 120.914325 -283.26721) (xy 120.94199 -283.312089)
			(xy 120.963212 -283.36035) (xy 120.977587 -283.411074) (xy 120.984839 -283.463293) (xy 120.98528 -283.489654)
			(xy 120.984672 -283.519776) (xy 120.975198 -283.57927) (xy 120.956496 -283.636537) (xy 120.929029 -283.690155)
			(xy 120.893479 -283.738791) (xy 120.872504 -283.760418) (xy 120.865664 -283.767818) (xy 120.857944 -283.786417)
			(xy 120.857518 -283.796486) (xy 120.857518 -283.868622) (xy 120.857927 -283.878693) (xy 120.865659 -283.897291)
			(xy 120.872504 -283.90469) (xy 120.893505 -283.926295) (xy 120.929071 -283.97493) (xy 120.956547 -284.028551)
			(xy 120.970926 -284.072584) (xy 125.872494 -284.072584) (xy 125.872952 -284.045214) (xy 125.880772 -283.991034)
			(xy 125.896263 -283.938531) (xy 125.919107 -283.888784) (xy 125.948832 -283.842818) (xy 125.966474 -283.821886)
			(xy 125.966728 -283.821632) (xy 125.97231 -283.814543) (xy 125.978559 -283.797628) (xy 125.97892 -283.788612)
			(xy 125.97892 -283.721556) (xy 125.978532 -283.712542) (xy 125.972306 -283.695625) (xy 125.966728 -283.688536)
			(xy 125.966474 -283.688536) (xy 125.966474 -283.688282) (xy 125.948856 -283.667333) (xy 125.919142 -283.621365)
			(xy 125.896302 -283.571621) (xy 125.880806 -283.519124) (xy 125.872972 -283.464952) (xy 125.872494 -283.437584)
			(xy 125.87298 -283.410333) (xy 125.880736 -283.356385) (xy 125.896091 -283.30409) (xy 125.918733 -283.254513)
			(xy 125.948199 -283.208663) (xy 125.98389 -283.167472) (xy 126.025081 -283.131781) (xy 126.070931 -283.102315)
			(xy 126.120508 -283.079673) (xy 126.172803 -283.064318) (xy 126.226751 -283.056562) (xy 126.281253 -283.056562)
			(xy 126.335201 -283.064318) (xy 126.387496 -283.079673) (xy 126.437073 -283.102315) (xy 126.482923 -283.131781)
			(xy 126.524114 -283.167472) (xy 126.559805 -283.208663) (xy 126.589271 -283.254513) (xy 126.611913 -283.30409)
			(xy 126.627268 -283.356385) (xy 126.635024 -283.410333) (xy 126.63551 -283.437584) (xy 126.635032 -283.464954)
			(xy 126.627217 -283.519132) (xy 126.61173 -283.571635) (xy 126.588891 -283.621382) (xy 126.55917 -283.66735)
			(xy 126.54153 -283.688282) (xy 126.541276 -283.688536) (xy 126.535707 -283.695635) (xy 126.529451 -283.712542)
			(xy 126.529084 -283.721556) (xy 126.529084 -283.788612) (xy 126.529439 -283.797629) (xy 126.535688 -283.814546)
			(xy 126.541276 -283.821632) (xy 126.54153 -283.821632) (xy 126.54153 -283.821886) (xy 126.559181 -283.842809)
			(xy 126.58889 -283.888785) (xy 126.611723 -283.938534) (xy 126.627211 -283.991037) (xy 126.635037 -284.045214)
			(xy 126.63551 -284.072584) (xy 126.635024 -284.099835) (xy 126.627268 -284.153783) (xy 126.611913 -284.206078)
			(xy 126.589271 -284.255655) (xy 126.559805 -284.301505) (xy 126.524114 -284.342696) (xy 126.482923 -284.378387)
			(xy 126.437073 -284.407853) (xy 126.387496 -284.430495) (xy 126.335201 -284.44585) (xy 126.281253 -284.453606)
			(xy 126.226751 -284.453606) (xy 126.172803 -284.44585) (xy 126.120508 -284.430495) (xy 126.070931 -284.407853)
			(xy 126.025081 -284.378387) (xy 125.98389 -284.342696) (xy 125.948199 -284.301505) (xy 125.918733 -284.255655)
			(xy 125.896091 -284.206078) (xy 125.880736 -284.153783) (xy 125.87298 -284.099835) (xy 125.872494 -284.072584)
			(xy 120.970926 -284.072584) (xy 120.97525 -284.085825) (xy 120.984715 -284.145328) (xy 120.98528 -284.175454)
			(xy 120.984794 -284.202705) (xy 120.977038 -284.256653) (xy 120.961683 -284.308948) (xy 120.939041 -284.358525)
			(xy 120.909575 -284.404375) (xy 120.873884 -284.445566) (xy 120.832693 -284.481257) (xy 120.786843 -284.510723)
			(xy 120.737266 -284.533365) (xy 120.684971 -284.54872) (xy 120.631023 -284.556476) (xy 120.576521 -284.556476)
			(xy 120.522573 -284.54872) (xy 120.470278 -284.533365) (xy 120.420701 -284.510723) (xy 120.374851 -284.481257)
			(xy 120.33366 -284.445566) (xy 120.297969 -284.404375) (xy 120.268503 -284.358525) (xy 120.245861 -284.308948)
			(xy 120.230506 -284.256653) (xy 120.22275 -284.202705) (xy 120.222264 -284.175454) (xy 120.222865 -284.145332)
			(xy 120.232338 -284.085837) (xy 120.251042 -284.028569) (xy 120.278511 -283.974951) (xy 120.314064 -283.926316)
			(xy 120.33504 -283.90469) (xy 120.341883 -283.897292) (xy 120.3496 -283.878691) (xy 120.350026 -283.868622)
			(xy 120.350026 -283.796486) (xy 120.349627 -283.786413) (xy 120.34189 -283.767815) (xy 120.33504 -283.760418)
			(xy 120.31405 -283.738802) (xy 120.278482 -283.690171) (xy 120.251003 -283.636553) (xy 120.232297 -283.57928)
			(xy 120.22283 -283.519779) (xy 120.222264 -283.489654) (xy 120.222837 -283.459815) (xy 120.232154 -283.400869)
			(xy 120.240806 -283.372306) (xy 120.244108 -283.361892) (xy 120.241822 -283.340302) (xy 120.19153 -283.25572)
			(xy 120.174258 -283.243274) (xy 120.163336 -283.241242) (xy 120.135485 -283.2354) (xy 120.081821 -283.216461)
			(xy 120.031564 -283.189765) (xy 119.985828 -283.155903) (xy 119.945626 -283.115625) (xy 119.91185 -283.069825)
			(xy 119.885249 -283.019517) (xy 119.866412 -282.965818) (xy 119.860568 -282.937966) (xy 119.858028 -282.92552)
			(xy 119.842788 -282.906216) (xy 119.741696 -282.862528) (xy 119.717058 -282.864306) (xy 119.70639 -282.871164)
			(xy 119.683423 -282.885207) (xy 119.634348 -282.907337) (xy 119.582645 -282.922332) (xy 119.529345 -282.929892)
			(xy 119.502428 -282.930346) (xy 119.484408 -282.93013) (xy 119.448534 -282.926693) (xy 119.4308 -282.923488)
			(xy 119.421148 -282.92171) (xy 119.402098 -282.925266) (xy 119.327168 -282.973272) (xy 119.315738 -282.98902)
			(xy 119.313452 -282.998418) (xy 119.306065 -283.025466) (xy 119.284437 -283.077194) (xy 119.255473 -283.125202)
			(xy 119.219797 -283.168455) (xy 119.178176 -283.206023) (xy 119.131506 -283.237097) (xy 119.080793 -283.261008)
			(xy 119.027126 -283.277242) (xy 118.971662 -283.285449) (xy 118.943628 -283.285946) (xy 118.916379 -283.285396)
			(xy 118.862436 -283.277644) (xy 118.810145 -283.262294) (xy 118.76057 -283.239659) (xy 118.714721 -283.2102)
			(xy 118.673532 -283.174515) (xy 118.63784 -283.133331) (xy 118.608372 -283.087488) (xy 118.585729 -283.037917)
			(xy 118.57037 -282.985629) (xy 118.562609 -282.931687) (xy 118.56212 -282.904438) (xy 113.843292 -282.904438)
			(xy 113.837059 -282.947793) (xy 113.821706 -283.000084) (xy 113.799067 -283.049658) (xy 113.769605 -283.095506)
			(xy 113.733917 -283.136695) (xy 113.692732 -283.172385) (xy 113.646886 -283.201852) (xy 113.597314 -283.224494)
			(xy 113.545024 -283.239852) (xy 113.491081 -283.247612) (xy 113.463832 -283.2481) (xy 113.436462 -283.247615)
			(xy 113.382284 -283.239802) (xy 113.329781 -283.224317) (xy 113.280034 -283.20148) (xy 113.234066 -283.171759)
			(xy 113.213134 -283.15412) (xy 113.21288 -283.153866) (xy 113.205806 -283.148261) (xy 113.188879 -283.142027)
			(xy 113.17986 -283.141674) (xy 113.112804 -283.141674) (xy 113.103788 -283.142039) (xy 113.086871 -283.148282)
			(xy 113.079784 -283.153866) (xy 113.079784 -283.15412) (xy 113.07953 -283.15412) (xy 113.0586 -283.171762)
			(xy 113.012626 -283.201472) (xy 112.962878 -283.224308) (xy 112.910377 -283.239798) (xy 112.856201 -283.247626)
			(xy 112.828832 -283.2481) (xy 112.801577 -283.247655) (xy 112.747622 -283.239901) (xy 112.695319 -283.224548)
			(xy 112.645734 -283.201907) (xy 112.599876 -283.172439) (xy 112.558678 -283.136745) (xy 112.52298 -283.09555)
			(xy 112.493509 -283.049695) (xy 112.470863 -283.000111) (xy 112.455505 -282.94781) (xy 112.447747 -282.893855)
			(xy 112.117605 -282.893855) (xy 112.117554 -282.89643) (xy 112.108246 -282.955376) (xy 112.099598 -282.98394)
			(xy 112.096296 -282.994354) (xy 112.098582 -283.015944) (xy 112.148874 -283.100526) (xy 112.166146 -283.112972)
			(xy 112.177068 -283.115004) (xy 112.202885 -283.120343) (xy 112.252801 -283.137311) (xy 112.299905 -283.160992)
			(xy 112.3433 -283.190933) (xy 112.382158 -283.226565) (xy 112.41574 -283.267207) (xy 112.443405 -283.312087)
			(xy 112.464627 -283.360349) (xy 112.479001 -283.411073) (xy 112.486253 -283.463293) (xy 112.486694 -283.489654)
			(xy 112.48611 -283.519777) (xy 112.476635 -283.579274) (xy 112.457928 -283.636542) (xy 112.430454 -283.690159)
			(xy 112.394897 -283.738793) (xy 112.373918 -283.760418) (xy 112.36708 -283.76782) (xy 112.359358 -283.786418)
			(xy 112.358932 -283.796486) (xy 112.358932 -283.868622) (xy 112.359338 -283.878694) (xy 112.367071 -283.897292)
			(xy 112.373918 -283.90469) (xy 112.394922 -283.926293) (xy 112.430486 -283.974928) (xy 112.457962 -284.02855)
			(xy 112.47234 -284.072584) (xy 117.373908 -284.072584) (xy 117.374363 -284.045213) (xy 117.382183 -283.991034)
			(xy 117.397675 -283.93853) (xy 117.420519 -283.888784) (xy 117.450246 -283.842817) (xy 117.467888 -283.821886)
			(xy 117.468142 -283.821632) (xy 117.473726 -283.814544) (xy 117.479973 -283.797628) (xy 117.480334 -283.788612)
			(xy 117.480334 -283.721556) (xy 117.479943 -283.712543) (xy 117.473718 -283.695626) (xy 117.468142 -283.688536)
			(xy 117.467888 -283.688536) (xy 117.467888 -283.688282) (xy 117.450272 -283.667331) (xy 117.420557 -283.621363)
			(xy 117.397717 -283.571621) (xy 117.38222 -283.519124) (xy 117.374386 -283.464952) (xy 117.373908 -283.437584)
			(xy 117.374394 -283.410333) (xy 117.38215 -283.356385) (xy 117.397505 -283.30409) (xy 117.420147 -283.254513)
			(xy 117.449613 -283.208663) (xy 117.485304 -283.167472) (xy 117.526495 -283.131781) (xy 117.572345 -283.102315)
			(xy 117.621922 -283.079673) (xy 117.674217 -283.064318) (xy 117.728165 -283.056562) (xy 117.782667 -283.056562)
			(xy 117.836615 -283.064318) (xy 117.88891 -283.079673) (xy 117.938487 -283.102315) (xy 117.984337 -283.131781)
			(xy 118.025528 -283.167472) (xy 118.061219 -283.208663) (xy 118.090685 -283.254513) (xy 118.113327 -283.30409)
			(xy 118.128682 -283.356385) (xy 118.136438 -283.410333) (xy 118.136924 -283.437584) (xy 118.136467 -283.464955)
			(xy 118.12865 -283.519135) (xy 118.11316 -283.571639) (xy 118.090315 -283.621386) (xy 118.060587 -283.667351)
			(xy 118.042944 -283.688282) (xy 118.04269 -283.688536) (xy 118.037123 -283.695636) (xy 118.030865 -283.712542)
			(xy 118.030498 -283.721556) (xy 118.030498 -283.788612) (xy 118.03085 -283.797629) (xy 118.037101 -283.814546)
			(xy 118.04269 -283.821632) (xy 118.042944 -283.821632) (xy 118.042944 -283.821886) (xy 118.060597 -283.842807)
			(xy 118.090306 -283.888783) (xy 118.113138 -283.938534) (xy 118.128626 -283.991037) (xy 118.136452 -284.045214)
			(xy 118.136924 -284.072584) (xy 118.136438 -284.099835) (xy 118.128682 -284.153783) (xy 118.113327 -284.206078)
			(xy 118.090685 -284.255655) (xy 118.061219 -284.301505) (xy 118.025528 -284.342696) (xy 117.984337 -284.378387)
			(xy 117.938487 -284.407853) (xy 117.88891 -284.430495) (xy 117.836615 -284.44585) (xy 117.782667 -284.453606)
			(xy 117.728165 -284.453606) (xy 117.674217 -284.44585) (xy 117.621922 -284.430495) (xy 117.572345 -284.407853)
			(xy 117.526495 -284.378387) (xy 117.485304 -284.342696) (xy 117.449613 -284.301505) (xy 117.420147 -284.255655)
			(xy 117.397505 -284.206078) (xy 117.38215 -284.153783) (xy 117.374394 -284.099835) (xy 117.373908 -284.072584)
			(xy 112.47234 -284.072584) (xy 112.476664 -284.085825) (xy 112.486129 -284.145328) (xy 112.486694 -284.175454)
			(xy 112.486208 -284.202705) (xy 112.478452 -284.256653) (xy 112.463097 -284.308948) (xy 112.440455 -284.358525)
			(xy 112.410989 -284.404375) (xy 112.375298 -284.445566) (xy 112.334107 -284.481257) (xy 112.288257 -284.510723)
			(xy 112.23868 -284.533365) (xy 112.186385 -284.54872) (xy 112.132437 -284.556476) (xy 112.077935 -284.556476)
			(xy 112.023987 -284.54872) (xy 111.971692 -284.533365) (xy 111.922115 -284.510723) (xy 111.876265 -284.481257)
			(xy 111.835074 -284.445566) (xy 111.799383 -284.404375) (xy 111.769917 -284.358525) (xy 111.747275 -284.308948)
			(xy 111.73192 -284.256653) (xy 111.724164 -284.202705) (xy 111.723678 -284.175454) (xy 111.724275 -284.145332)
			(xy 111.733748 -284.085836) (xy 111.752453 -284.028568) (xy 111.779923 -283.974951) (xy 111.815477 -283.926316)
			(xy 111.836454 -283.90469) (xy 111.843285 -283.897282) (xy 111.851011 -283.878689) (xy 111.85144 -283.868622)
			(xy 111.85144 -283.796486) (xy 111.851038 -283.786414) (xy 111.843303 -283.767815) (xy 111.836454 -283.760418)
			(xy 111.815467 -283.738799) (xy 111.779897 -283.69017) (xy 111.752417 -283.636552) (xy 111.733711 -283.57928)
			(xy 111.724244 -283.519779) (xy 111.723678 -283.489654) (xy 111.72425 -283.459815) (xy 111.733568 -283.400869)
			(xy 111.74222 -283.372306) (xy 111.745522 -283.361892) (xy 111.743236 -283.340302) (xy 111.692944 -283.25572)
			(xy 111.675672 -283.243274) (xy 111.66475 -283.241242) (xy 111.636901 -283.23539) (xy 111.583237 -283.216453)
			(xy 111.53298 -283.189759) (xy 111.487243 -283.155898) (xy 111.447041 -283.115622) (xy 111.413265 -283.069823)
			(xy 111.386664 -283.019516) (xy 111.367826 -282.965818) (xy 111.361982 -282.937966) (xy 111.359442 -282.92552)
			(xy 111.344202 -282.906216) (xy 111.24311 -282.862528) (xy 111.218472 -282.864306) (xy 111.207804 -282.871164)
			(xy 111.184833 -282.885201) (xy 111.13576 -282.907332) (xy 111.084058 -282.922329) (xy 111.030759 -282.929892)
			(xy 111.003842 -282.930346) (xy 110.985823 -282.930129) (xy 110.949948 -282.926692) (xy 110.932214 -282.923488)
			(xy 110.922562 -282.92171) (xy 110.903512 -282.925266) (xy 110.828582 -282.973272) (xy 110.817152 -282.98902)
			(xy 110.814866 -282.998418) (xy 110.807467 -283.025462) (xy 110.785839 -283.07719) (xy 110.756877 -283.125197)
			(xy 110.721202 -283.168449) (xy 110.679583 -283.206017) (xy 110.632915 -283.237092) (xy 110.582203 -283.261004)
			(xy 110.528538 -283.277239) (xy 110.473075 -283.285448) (xy 110.445042 -283.285946) (xy 110.417792 -283.285406)
			(xy 110.363846 -283.277655) (xy 110.311552 -283.262307) (xy 110.261974 -283.239672) (xy 110.216123 -283.210212)
			(xy 110.17493 -283.174526) (xy 110.139236 -283.133341) (xy 110.109767 -283.087496) (xy 110.087121 -283.037923)
			(xy 110.071762 -282.985633) (xy 110.064 -282.931688) (xy 110.063534 -282.904438) (xy 105.682792 -282.904438)
			(xy 105.676558 -282.947795) (xy 105.661205 -283.000087) (xy 105.638565 -283.049662) (xy 105.609102 -283.09551)
			(xy 105.573413 -283.136699) (xy 105.532226 -283.17239) (xy 105.486379 -283.201856) (xy 105.436805 -283.224498)
			(xy 105.384514 -283.239854) (xy 105.33057 -283.247613) (xy 105.30332 -283.2481) (xy 105.27595 -283.247622)
			(xy 105.221772 -283.239807) (xy 105.169269 -283.224321) (xy 105.119522 -283.201482) (xy 105.073554 -283.17176)
			(xy 105.052622 -283.15412) (xy 105.052368 -283.153866) (xy 105.045269 -283.148298) (xy 105.028362 -283.142041)
			(xy 105.019348 -283.141674) (xy 104.952292 -283.141674) (xy 104.943275 -283.142033) (xy 104.926359 -283.14828)
			(xy 104.919272 -283.153866) (xy 104.919272 -283.15412) (xy 104.919018 -283.15412) (xy 104.898093 -283.171767)
			(xy 104.852118 -283.201477) (xy 104.802368 -283.224311) (xy 104.749866 -283.2398) (xy 104.69569 -283.247627)
			(xy 104.66832 -283.2481) (xy 104.641066 -283.247654) (xy 104.587111 -283.239899) (xy 104.53481 -283.224545)
			(xy 104.485226 -283.201903) (xy 104.43937 -283.172435) (xy 104.398174 -283.13674) (xy 104.362477 -283.095546)
			(xy 104.333007 -283.049691) (xy 104.310362 -283.000109) (xy 104.295005 -282.947808) (xy 104.287247 -282.893854)
			(xy 103.957113 -282.893854) (xy 103.94936 -282.947788) (xy 103.934007 -283.000081) (xy 103.911368 -283.049657)
			(xy 103.881904 -283.095506) (xy 103.846216 -283.136696) (xy 103.805029 -283.172388) (xy 103.759181 -283.201855)
			(xy 103.709607 -283.224497) (xy 103.657315 -283.239854) (xy 103.60337 -283.247613) (xy 103.57612 -283.2481)
			(xy 103.549739 -283.247582) (xy 103.497478 -283.240334) (xy 103.446716 -283.225947) (xy 103.398425 -283.204695)
			(xy 103.353526 -283.176985) (xy 103.312879 -283.143347) (xy 103.27726 -283.104423) (xy 103.247351 -283.060959)
			(xy 103.223723 -283.013784) (xy 103.206829 -282.9638) (xy 103.20147 -282.937966) (xy 103.19893 -282.92552)
			(xy 103.18369 -282.906216) (xy 103.082598 -282.862528) (xy 103.05796 -282.864306) (xy 103.047292 -282.871164)
			(xy 103.024324 -282.885206) (xy 102.97525 -282.907336) (xy 102.923547 -282.922331) (xy 102.870247 -282.929892)
			(xy 102.84333 -282.930346) (xy 102.825311 -282.93013) (xy 102.789436 -282.926693) (xy 102.771702 -282.923488)
			(xy 102.76205 -282.92171) (xy 102.743 -282.925266) (xy 102.66807 -282.973272) (xy 102.65664 -282.98902)
			(xy 102.654354 -282.998418) (xy 102.646966 -283.025465) (xy 102.625337 -283.077194) (xy 102.596373 -283.125201)
			(xy 102.560697 -283.168454) (xy 102.519077 -283.206022) (xy 102.472407 -283.237096) (xy 102.421694 -283.261007)
			(xy 102.368028 -283.277242) (xy 102.312564 -283.285449) (xy 102.28453 -283.285946) (xy 102.257281 -283.285394)
			(xy 102.203338 -283.277643) (xy 102.151047 -283.262293) (xy 102.101472 -283.239658) (xy 102.055624 -283.210199)
			(xy 102.014434 -283.174514) (xy 101.978742 -283.133331) (xy 101.949274 -283.087487) (xy 101.926631 -283.037917)
			(xy 101.911272 -282.985629) (xy 101.903511 -282.931687) (xy 101.903022 -282.904438) (xy 100.33 -282.904438)
			(xy 100.33 -284.175454) (xy 103.562656 -284.175454) (xy 103.566727 -284.119832) (xy 103.578853 -284.065395)
			(xy 103.598776 -284.013304) (xy 103.626072 -283.964669) (xy 103.660158 -283.920526) (xy 103.700307 -283.881817)
			(xy 103.745665 -283.849366) (xy 103.795265 -283.823865) (xy 103.848049 -283.805858) (xy 103.902892 -283.795728)
			(xy 103.958626 -283.793691) (xy 104.014063 -283.799791) (xy 104.06802 -283.813897) (xy 104.119349 -283.835709)
			(xy 104.166955 -283.864763) (xy 104.209823 -283.900438) (xy 104.24704 -283.941975) (xy 104.277813 -283.988488)
			(xy 104.301485 -284.038985) (xy 104.311594 -284.072584) (xy 109.213396 -284.072584) (xy 109.213854 -284.045213)
			(xy 109.221674 -283.991034) (xy 109.237165 -283.938531) (xy 109.260008 -283.888784) (xy 109.289734 -283.842818)
			(xy 109.307376 -283.821886) (xy 109.30763 -283.821632) (xy 109.313213 -283.814543) (xy 109.319461 -283.797628)
			(xy 109.319822 -283.788612) (xy 109.319822 -283.721556) (xy 109.319434 -283.712542) (xy 109.313207 -283.695625)
			(xy 109.30763 -283.688536) (xy 109.307376 -283.688536) (xy 109.307376 -283.688282) (xy 109.289758 -283.667333)
			(xy 109.260044 -283.621364) (xy 109.237204 -283.571621) (xy 109.221708 -283.519124) (xy 109.213874 -283.464952)
			(xy 109.213396 -283.437584) (xy 109.213882 -283.410333) (xy 109.221638 -283.356385) (xy 109.236993 -283.30409)
			(xy 109.259635 -283.254513) (xy 109.289101 -283.208663) (xy 109.324792 -283.167472) (xy 109.365983 -283.131781)
			(xy 109.411833 -283.102315) (xy 109.46141 -283.079673) (xy 109.513705 -283.064318) (xy 109.567653 -283.056562)
			(xy 109.622155 -283.056562) (xy 109.676103 -283.064318) (xy 109.728398 -283.079673) (xy 109.777975 -283.102315)
			(xy 109.823825 -283.131781) (xy 109.865016 -283.167472) (xy 109.900707 -283.208663) (xy 109.930173 -283.254513)
			(xy 109.952815 -283.30409) (xy 109.96817 -283.356385) (xy 109.975926 -283.410333) (xy 109.976412 -283.437584)
			(xy 109.975934 -283.464954) (xy 109.968118 -283.519132) (xy 109.952632 -283.571635) (xy 109.929793 -283.621382)
			(xy 109.900072 -283.66735) (xy 109.882432 -283.688282) (xy 109.882178 -283.688536) (xy 109.87661 -283.695635)
			(xy 109.870353 -283.712542) (xy 109.869986 -283.721556) (xy 109.869986 -283.788612) (xy 109.87034 -283.797629)
			(xy 109.87659 -283.814546) (xy 109.882178 -283.821632) (xy 109.882432 -283.821632) (xy 109.882432 -283.821886)
			(xy 109.900083 -283.842808) (xy 109.929792 -283.888784) (xy 109.952625 -283.938534) (xy 109.968113 -283.991037)
			(xy 109.975939 -284.045214) (xy 109.976412 -284.072584) (xy 109.975926 -284.099835) (xy 109.96817 -284.153783)
			(xy 109.952815 -284.206078) (xy 109.930173 -284.255655) (xy 109.900707 -284.301505) (xy 109.865016 -284.342696)
			(xy 109.823825 -284.378387) (xy 109.777975 -284.407853) (xy 109.728398 -284.430495) (xy 109.676103 -284.44585)
			(xy 109.622155 -284.453606) (xy 109.567653 -284.453606) (xy 109.513705 -284.44585) (xy 109.46141 -284.430495)
			(xy 109.411833 -284.407853) (xy 109.365983 -284.378387) (xy 109.324792 -284.342696) (xy 109.289101 -284.301505)
			(xy 109.259635 -284.255655) (xy 109.236993 -284.206078) (xy 109.221638 -284.153783) (xy 109.213882 -284.099835)
			(xy 109.213396 -284.072584) (xy 104.311594 -284.072584) (xy 104.317553 -284.092392) (xy 104.325673 -284.147568)
			(xy 104.326182 -284.175454) (xy 104.325673 -284.20334) (xy 104.317553 -284.258516) (xy 104.301485 -284.311923)
			(xy 104.277813 -284.36242) (xy 104.24704 -284.408933) (xy 104.209823 -284.45047) (xy 104.166955 -284.486145)
			(xy 104.119349 -284.515199) (xy 104.06802 -284.537011) (xy 104.014063 -284.551117) (xy 103.958626 -284.557217)
			(xy 103.902892 -284.55518) (xy 103.848049 -284.54505) (xy 103.795265 -284.527043) (xy 103.745665 -284.501542)
			(xy 103.700307 -284.469091) (xy 103.660158 -284.430382) (xy 103.626072 -284.386239) (xy 103.598776 -284.337604)
			(xy 103.578853 -284.285513) (xy 103.566727 -284.231076) (xy 103.562656 -284.175454) (xy 100.33 -284.175454)
			(xy 100.33 -286.60344) (xy 100.330264 -286.611083) (xy 100.334796 -286.625682) (xy 100.33889 -286.632142)
			(xy 100.362512 -286.666432) (xy 100.370386 -286.66948) (xy 100.37699 -286.67202) (xy 100.453851 -286.702519)
			(xy 100.604814 -286.770047) (xy 100.642892 -286.789368) (xy 108.672374 -286.789368) (xy 108.676445 -286.733746)
			(xy 108.688571 -286.679309) (xy 108.708494 -286.627218) (xy 108.73579 -286.578583) (xy 108.769876 -286.53444)
			(xy 108.810025 -286.495731) (xy 108.855383 -286.46328) (xy 108.904983 -286.437779) (xy 108.957767 -286.419772)
			(xy 109.01261 -286.409642) (xy 109.068344 -286.407605) (xy 109.123781 -286.413705) (xy 109.177738 -286.427811)
			(xy 109.229067 -286.449623) (xy 109.276673 -286.478677) (xy 109.319541 -286.514352) (xy 109.356758 -286.555889)
			(xy 109.387531 -286.602402) (xy 109.411203 -286.652899) (xy 109.427271 -286.706306) (xy 109.429365 -286.720534)
			(xy 109.558834 -286.720534) (xy 109.562905 -286.664912) (xy 109.575031 -286.610475) (xy 109.594954 -286.558384)
			(xy 109.62225 -286.509749) (xy 109.656336 -286.465606) (xy 109.696485 -286.426897) (xy 109.741843 -286.394446)
			(xy 109.791443 -286.368945) (xy 109.844227 -286.350938) (xy 109.89907 -286.340808) (xy 109.954804 -286.338771)
			(xy 110.010241 -286.344871) (xy 110.064198 -286.358977) (xy 110.115527 -286.380789) (xy 110.163133 -286.409843)
			(xy 110.206001 -286.445518) (xy 110.243218 -286.487055) (xy 110.273991 -286.533568) (xy 110.297663 -286.584065)
			(xy 110.313731 -286.637472) (xy 110.321851 -286.692648) (xy 110.32236 -286.720534) (xy 110.321851 -286.74842)
			(xy 110.31575 -286.789876) (xy 125.407926 -286.789876) (xy 125.411997 -286.734254) (xy 125.424123 -286.679817)
			(xy 125.444046 -286.627726) (xy 125.471342 -286.579091) (xy 125.505428 -286.534948) (xy 125.545577 -286.496239)
			(xy 125.590935 -286.463788) (xy 125.640535 -286.438287) (xy 125.693319 -286.42028) (xy 125.748162 -286.41015)
			(xy 125.803896 -286.408113) (xy 125.859333 -286.414213) (xy 125.91329 -286.428319) (xy 125.964619 -286.450131)
			(xy 126.012225 -286.479185) (xy 126.055093 -286.51486) (xy 126.09231 -286.556397) (xy 126.123083 -286.60291)
			(xy 126.146755 -286.653407) (xy 126.162213 -286.704786) (xy 126.29464 -286.704786) (xy 126.298711 -286.649164)
			(xy 126.310837 -286.594727) (xy 126.33076 -286.542636) (xy 126.358056 -286.494001) (xy 126.392142 -286.449858)
			(xy 126.432291 -286.411149) (xy 126.477649 -286.378698) (xy 126.527249 -286.353197) (xy 126.580033 -286.33519)
			(xy 126.634876 -286.32506) (xy 126.69061 -286.323023) (xy 126.746047 -286.329123) (xy 126.800004 -286.343229)
			(xy 126.851333 -286.365041) (xy 126.898939 -286.394095) (xy 126.941807 -286.42977) (xy 126.979024 -286.471307)
			(xy 127.009797 -286.51782) (xy 127.033469 -286.568317) (xy 127.049537 -286.621724) (xy 127.057657 -286.6769)
			(xy 127.058166 -286.704786) (xy 127.057657 -286.732672) (xy 127.049537 -286.787848) (xy 127.033469 -286.841255)
			(xy 127.009797 -286.891752) (xy 126.979024 -286.938265) (xy 126.941807 -286.979802) (xy 126.898939 -287.015477)
			(xy 126.851333 -287.044531) (xy 126.800004 -287.066343) (xy 126.746047 -287.080449) (xy 126.69061 -287.086549)
			(xy 126.634876 -287.084512) (xy 126.580033 -287.074382) (xy 126.527249 -287.056375) (xy 126.477649 -287.030874)
			(xy 126.432291 -286.998423) (xy 126.392142 -286.959714) (xy 126.358056 -286.915571) (xy 126.33076 -286.866936)
			(xy 126.310837 -286.814845) (xy 126.298711 -286.760408) (xy 126.29464 -286.704786) (xy 126.162213 -286.704786)
			(xy 126.162823 -286.706814) (xy 126.170943 -286.76199) (xy 126.171452 -286.789876) (xy 126.170943 -286.817762)
			(xy 126.162823 -286.872938) (xy 126.146755 -286.926345) (xy 126.123083 -286.976842) (xy 126.09231 -287.023355)
			(xy 126.055093 -287.064892) (xy 126.012225 -287.100567) (xy 125.964619 -287.129621) (xy 125.91329 -287.151433)
			(xy 125.859333 -287.165539) (xy 125.803896 -287.171639) (xy 125.748162 -287.169602) (xy 125.693319 -287.159472)
			(xy 125.640535 -287.141465) (xy 125.590935 -287.115964) (xy 125.545577 -287.083513) (xy 125.505428 -287.044804)
			(xy 125.471342 -287.000661) (xy 125.444046 -286.952026) (xy 125.424123 -286.899935) (xy 125.411997 -286.845498)
			(xy 125.407926 -286.789876) (xy 110.31575 -286.789876) (xy 110.313731 -286.803596) (xy 110.297663 -286.857003)
			(xy 110.273991 -286.9075) (xy 110.243218 -286.954013) (xy 110.206001 -286.99555) (xy 110.163133 -287.031225)
			(xy 110.115527 -287.060279) (xy 110.064198 -287.082091) (xy 110.010241 -287.096197) (xy 109.954804 -287.102297)
			(xy 109.89907 -287.10026) (xy 109.844227 -287.09013) (xy 109.791443 -287.072123) (xy 109.741843 -287.046622)
			(xy 109.696485 -287.014171) (xy 109.656336 -286.975462) (xy 109.62225 -286.931319) (xy 109.594954 -286.882684)
			(xy 109.575031 -286.830593) (xy 109.562905 -286.776156) (xy 109.558834 -286.720534) (xy 109.429365 -286.720534)
			(xy 109.435391 -286.761482) (xy 109.4359 -286.789368) (xy 109.435391 -286.817254) (xy 109.427271 -286.87243)
			(xy 109.411203 -286.925837) (xy 109.387531 -286.976334) (xy 109.356758 -287.022847) (xy 109.319541 -287.064384)
			(xy 109.276673 -287.100059) (xy 109.229067 -287.129113) (xy 109.177738 -287.150925) (xy 109.123781 -287.165031)
			(xy 109.068344 -287.171131) (xy 109.01261 -287.169094) (xy 108.957767 -287.158964) (xy 108.904983 -287.140957)
			(xy 108.855383 -287.115456) (xy 108.810025 -287.083005) (xy 108.769876 -287.044296) (xy 108.73579 -287.000153)
			(xy 108.708494 -286.951518) (xy 108.688571 -286.899427) (xy 108.676445 -286.84499) (xy 108.672374 -286.789368)
			(xy 100.642892 -286.789368) (xy 100.752294 -286.84488) (xy 100.895935 -286.926839) (xy 101.035395 -287.015727)
			(xy 101.170339 -287.111332) (xy 101.300443 -287.213424) (xy 101.425398 -287.321759) (xy 101.544902 -287.436078)
			(xy 101.658671 -287.556106) (xy 101.766431 -287.681557) (xy 101.867924 -287.81213) (xy 101.962907 -287.947512)
			(xy 102.051154 -288.087378) (xy 102.132451 -288.231395) (xy 102.206606 -288.379216) (xy 102.27344 -288.530489)
			(xy 102.332792 -288.68485) (xy 102.384522 -288.84193) (xy 102.428505 -289.001352) (xy 102.464635 -289.162736)
			(xy 102.492827 -289.325694) (xy 102.513012 -289.489836) (xy 102.525143 -289.654769) (xy 102.529189 -289.820099)
			(xy 102.525143 -289.985428) (xy 102.513012 -290.150361) (xy 102.492827 -290.314503) (xy 102.464636 -290.477461)
			(xy 102.428506 -290.638845) (xy 102.384523 -290.798268) (xy 102.332793 -290.955348) (xy 102.273441 -291.109709)
			(xy 102.206607 -291.260981) (xy 102.132453 -291.408803) (xy 102.051155 -291.552819) (xy 101.962909 -291.692686)
			(xy 101.867925 -291.828068) (xy 101.766432 -291.958641) (xy 101.658673 -292.084091) (xy 101.544904 -292.20412)
			(xy 101.4254 -292.318439) (xy 101.300446 -292.426774) (xy 101.170341 -292.528866) (xy 101.035397 -292.624471)
			(xy 100.895938 -292.713359) (xy 100.752296 -292.795318) (xy 100.604817 -292.870151) (xy 100.453853 -292.93768)
			(xy 100.37699 -292.968172) (xy 100.370386 -292.970712) (xy 100.362512 -292.97376) (xy 100.33889 -293.00805)
			(xy 100.334777 -293.014501) (xy 100.330242 -293.029106) (xy 100.33 -293.036752) (xy 100.33 -294.199564)
			(xy 110.64951 -294.199564) (xy 110.653581 -294.143942) (xy 110.665707 -294.089505) (xy 110.68563 -294.037414)
			(xy 110.712926 -293.988779) (xy 110.747012 -293.944636) (xy 110.787161 -293.905927) (xy 110.832519 -293.873476)
			(xy 110.882119 -293.847975) (xy 110.934903 -293.829968) (xy 110.989746 -293.819838) (xy 111.04548 -293.817801)
			(xy 111.100917 -293.823901) (xy 111.154874 -293.838007) (xy 111.206203 -293.859819) (xy 111.253809 -293.888873)
			(xy 111.296677 -293.924548) (xy 111.333894 -293.966085) (xy 111.364667 -294.012598) (xy 111.388339 -294.063095)
			(xy 111.404407 -294.116502) (xy 111.412527 -294.171678) (xy 111.413036 -294.199564) (xy 111.412527 -294.22745)
			(xy 111.404407 -294.282626) (xy 111.388339 -294.336033) (xy 111.364667 -294.38653) (xy 111.333894 -294.433043)
			(xy 111.296677 -294.47458) (xy 111.253809 -294.510255) (xy 111.206203 -294.539309) (xy 111.154874 -294.561121)
			(xy 111.100917 -294.575227) (xy 111.04548 -294.581327) (xy 110.989746 -294.57929) (xy 110.934903 -294.56916)
			(xy 110.882119 -294.551153) (xy 110.832519 -294.525652) (xy 110.787161 -294.493201) (xy 110.747012 -294.454492)
			(xy 110.712926 -294.410349) (xy 110.68563 -294.361714) (xy 110.665707 -294.309623) (xy 110.653581 -294.255186)
			(xy 110.64951 -294.199564) (xy 100.33 -294.199564) (xy 100.33 -294.851836) (xy 102.046784 -294.851836)
			(xy 102.050855 -294.796214) (xy 102.062981 -294.741777) (xy 102.082904 -294.689686) (xy 102.1102 -294.641051)
			(xy 102.144286 -294.596908) (xy 102.184435 -294.558199) (xy 102.229793 -294.525748) (xy 102.279393 -294.500247)
			(xy 102.332177 -294.48224) (xy 102.38702 -294.47211) (xy 102.442754 -294.470073) (xy 102.498191 -294.476173)
			(xy 102.552148 -294.490279) (xy 102.603477 -294.512091) (xy 102.651083 -294.541145) (xy 102.693951 -294.57682)
			(xy 102.731168 -294.618357) (xy 102.761941 -294.66487) (xy 102.785613 -294.715367) (xy 102.801681 -294.768774)
			(xy 102.809801 -294.82395) (xy 102.81031 -294.851836) (xy 117.14048 -294.851836) (xy 117.144551 -294.796214)
			(xy 117.156677 -294.741777) (xy 117.1766 -294.689686) (xy 117.203896 -294.641051) (xy 117.237982 -294.596908)
			(xy 117.278131 -294.558199) (xy 117.323489 -294.525748) (xy 117.373089 -294.500247) (xy 117.425873 -294.48224)
			(xy 117.480716 -294.47211) (xy 117.53645 -294.470073) (xy 117.591887 -294.476173) (xy 117.645844 -294.490279)
			(xy 117.697173 -294.512091) (xy 117.744779 -294.541145) (xy 117.787647 -294.57682) (xy 117.824864 -294.618357)
			(xy 117.855637 -294.66487) (xy 117.879309 -294.715367) (xy 117.895377 -294.768774) (xy 117.903497 -294.82395)
			(xy 117.904006 -294.851836) (xy 117.903497 -294.879722) (xy 117.895377 -294.934898) (xy 117.879309 -294.988305)
			(xy 117.855637 -295.038802) (xy 117.824864 -295.085315) (xy 117.787647 -295.126852) (xy 117.744779 -295.162527)
			(xy 117.697173 -295.191581) (xy 117.645844 -295.213393) (xy 117.591887 -295.227499) (xy 117.53645 -295.233599)
			(xy 117.480716 -295.231562) (xy 117.425873 -295.221432) (xy 117.373089 -295.203425) (xy 117.323489 -295.177924)
			(xy 117.278131 -295.145473) (xy 117.237982 -295.106764) (xy 117.203896 -295.062621) (xy 117.1766 -295.013986)
			(xy 117.156677 -294.961895) (xy 117.144551 -294.907458) (xy 117.14048 -294.851836) (xy 102.81031 -294.851836)
			(xy 102.809801 -294.879722) (xy 102.801681 -294.934898) (xy 102.785613 -294.988305) (xy 102.761941 -295.038802)
			(xy 102.731168 -295.085315) (xy 102.693951 -295.126852) (xy 102.651083 -295.162527) (xy 102.603477 -295.191581)
			(xy 102.552148 -295.213393) (xy 102.498191 -295.227499) (xy 102.442754 -295.233599) (xy 102.38702 -295.231562)
			(xy 102.332177 -295.221432) (xy 102.279393 -295.203425) (xy 102.229793 -295.177924) (xy 102.184435 -295.145473)
			(xy 102.144286 -295.106764) (xy 102.1102 -295.062621) (xy 102.082904 -295.013986) (xy 102.062981 -294.961895)
			(xy 102.050855 -294.907458) (xy 102.046784 -294.851836) (xy 100.33 -294.851836) (xy 100.33 -298.420536)
			(xy 103.494586 -298.420536) (xy 103.495077 -298.393167) (xy 103.502889 -298.338989) (xy 103.518373 -298.286486)
			(xy 103.541209 -298.236739) (xy 103.570928 -298.190771) (xy 103.588566 -298.169838) (xy 103.58882 -298.169584)
			(xy 103.594422 -298.162508) (xy 103.600659 -298.145583) (xy 103.601012 -298.136564) (xy 103.601012 -298.069508)
			(xy 103.600649 -298.060492) (xy 103.594405 -298.043575) (xy 103.58882 -298.036488) (xy 103.588566 -298.036488)
			(xy 103.588566 -298.036234) (xy 103.570959 -298.015273) (xy 103.54123 -297.969311) (xy 103.51838 -297.91957)
			(xy 103.502879 -297.867072) (xy 103.495046 -297.812896) (xy 103.495042 -297.758158) (xy 103.502868 -297.703981)
			(xy 103.518361 -297.651481) (xy 103.541204 -297.601736) (xy 103.570926 -297.55577) (xy 103.588566 -297.534838)
			(xy 103.58882 -297.534584) (xy 103.594422 -297.527508) (xy 103.600659 -297.510583) (xy 103.601012 -297.501564)
			(xy 103.601012 -297.434508) (xy 103.600649 -297.425492) (xy 103.594405 -297.408575) (xy 103.58882 -297.401488)
			(xy 103.588566 -297.401488) (xy 103.588566 -297.401234) (xy 103.570959 -297.380273) (xy 103.54123 -297.334311)
			(xy 103.51838 -297.28457) (xy 103.502879 -297.232072) (xy 103.495046 -297.177896) (xy 103.495042 -297.123158)
			(xy 103.502868 -297.068981) (xy 103.518361 -297.016481) (xy 103.541204 -296.966736) (xy 103.570926 -296.92077)
			(xy 103.588566 -296.899838) (xy 103.58882 -296.899584) (xy 103.594422 -296.892508) (xy 103.600659 -296.875583)
			(xy 103.601012 -296.866564) (xy 103.601012 -296.799508) (xy 103.600649 -296.790492) (xy 103.594405 -296.773575)
			(xy 103.58882 -296.766488) (xy 103.588566 -296.766488) (xy 103.588566 -296.766234) (xy 103.570959 -296.745273)
			(xy 103.54123 -296.699311) (xy 103.51838 -296.64957) (xy 103.502879 -296.597072) (xy 103.495046 -296.542896)
			(xy 103.495042 -296.488158) (xy 103.502868 -296.433981) (xy 103.518361 -296.381481) (xy 103.541204 -296.331736)
			(xy 103.570926 -296.28577) (xy 103.588566 -296.264838) (xy 103.58882 -296.264584) (xy 103.594422 -296.257508)
			(xy 103.600659 -296.240583) (xy 103.601012 -296.231564) (xy 103.601012 -296.164508) (xy 103.600649 -296.155492)
			(xy 103.594405 -296.138575) (xy 103.58882 -296.131488) (xy 103.588566 -296.131488) (xy 103.588566 -296.131234)
			(xy 103.570959 -296.110273) (xy 103.54123 -296.064311) (xy 103.51838 -296.01457) (xy 103.502879 -295.962072)
			(xy 103.495046 -295.907896) (xy 103.495042 -295.853158) (xy 103.502868 -295.798981) (xy 103.518361 -295.746481)
			(xy 103.541204 -295.696736) (xy 103.570926 -295.65077) (xy 103.588566 -295.629838) (xy 103.58882 -295.629584)
			(xy 103.594422 -295.622508) (xy 103.600659 -295.605583) (xy 103.601012 -295.596564) (xy 103.601012 -295.529508)
			(xy 103.600649 -295.520492) (xy 103.594405 -295.503575) (xy 103.58882 -295.496488) (xy 103.588566 -295.496488)
			(xy 103.588566 -295.496234) (xy 103.570924 -295.475304) (xy 103.541214 -295.42933) (xy 103.518379 -295.379582)
			(xy 103.502888 -295.327081) (xy 103.49506 -295.272905) (xy 103.494586 -295.245536) (xy 103.495089 -295.218284)
			(xy 103.502841 -295.164335) (xy 103.518192 -295.112038) (xy 103.54083 -295.062459) (xy 103.570293 -295.016606)
			(xy 103.605983 -294.975413) (xy 103.647172 -294.939719) (xy 103.693022 -294.91025) (xy 103.742599 -294.887607)
			(xy 103.794894 -294.87225) (xy 103.848842 -294.864492) (xy 103.876094 -294.864028) (xy 103.903464 -294.864491)
			(xy 103.957644 -294.872308) (xy 104.010147 -294.887798) (xy 104.059894 -294.91064) (xy 104.105861 -294.940366)
			(xy 104.126792 -294.958008) (xy 104.127046 -294.958262) (xy 104.134139 -294.963839) (xy 104.151051 -294.97009)
			(xy 104.160066 -294.970454) (xy 104.227122 -294.970454) (xy 104.236141 -294.970118) (xy 104.253059 -294.963857)
			(xy 104.260142 -294.958262) (xy 104.260142 -294.958008) (xy 104.260396 -294.958008) (xy 104.28132 -294.940359)
			(xy 104.327295 -294.910648) (xy 104.377044 -294.887814) (xy 104.429547 -294.872325) (xy 104.483724 -294.8645)
			(xy 104.511094 -294.864028) (xy 104.538348 -294.864461) (xy 104.592302 -294.872218) (xy 104.644603 -294.887575)
			(xy 104.694185 -294.91022) (xy 104.74004 -294.93969) (xy 104.781234 -294.975387) (xy 104.816928 -295.016584)
			(xy 104.846395 -295.062441) (xy 104.869035 -295.112025) (xy 104.884388 -295.164327) (xy 104.892141 -295.218282)
			(xy 104.892602 -295.245536) (xy 104.892157 -295.272907) (xy 104.884334 -295.327087) (xy 104.86884 -295.37959)
			(xy 104.845993 -295.429337) (xy 104.816265 -295.475303) (xy 104.798622 -295.496234) (xy 104.798368 -295.496488)
			(xy 104.792777 -295.503571) (xy 104.786534 -295.520491) (xy 104.786176 -295.529508) (xy 104.786176 -295.596564)
			(xy 104.786555 -295.605578) (xy 104.792788 -295.622495) (xy 104.798368 -295.629584) (xy 104.798622 -295.629584)
			(xy 104.798622 -295.629838) (xy 104.816296 -295.650743) (xy 104.846016 -295.696717) (xy 104.868856 -295.746468)
			(xy 104.884347 -295.798974) (xy 104.892171 -295.853155) (xy 104.892167 -295.907899) (xy 104.884336 -295.962079)
			(xy 104.868837 -296.014583) (xy 104.845989 -296.064331) (xy 104.816263 -296.1103) (xy 104.798622 -296.131234)
			(xy 104.798368 -296.131488) (xy 104.792777 -296.138571) (xy 104.786534 -296.155491) (xy 104.786176 -296.164508)
			(xy 104.786176 -296.231564) (xy 104.786555 -296.240578) (xy 104.792788 -296.257495) (xy 104.798368 -296.264584)
			(xy 104.798622 -296.264584) (xy 104.798622 -296.264838) (xy 104.816296 -296.285743) (xy 104.846016 -296.331717)
			(xy 104.868856 -296.381468) (xy 104.884347 -296.433974) (xy 104.892171 -296.488155) (xy 104.892167 -296.542899)
			(xy 104.884336 -296.597079) (xy 104.868837 -296.649583) (xy 104.845989 -296.699331) (xy 104.816263 -296.7453)
			(xy 104.798622 -296.766234) (xy 104.798368 -296.766488) (xy 104.792777 -296.773571) (xy 104.786534 -296.790491)
			(xy 104.786176 -296.799508) (xy 104.786176 -296.866564) (xy 104.786555 -296.875578) (xy 104.792788 -296.892495)
			(xy 104.798368 -296.899584) (xy 104.798622 -296.899584) (xy 104.798622 -296.899838) (xy 104.816296 -296.920743)
			(xy 104.846016 -296.966717) (xy 104.868856 -297.016468) (xy 104.884347 -297.068974) (xy 104.892171 -297.123155)
			(xy 104.892167 -297.177899) (xy 104.884336 -297.232079) (xy 104.868837 -297.284583) (xy 104.845989 -297.334331)
			(xy 104.816263 -297.3803) (xy 104.798622 -297.401234) (xy 104.798368 -297.401488) (xy 104.792777 -297.408571)
			(xy 104.786534 -297.425491) (xy 104.786176 -297.434508) (xy 104.786176 -297.501564) (xy 104.786555 -297.510578)
			(xy 104.792788 -297.527495) (xy 104.798368 -297.534584) (xy 104.798622 -297.534584) (xy 104.798622 -297.534838)
			(xy 104.816296 -297.555743) (xy 104.846016 -297.601717) (xy 104.868856 -297.651468) (xy 104.884347 -297.703974)
			(xy 104.892171 -297.758155) (xy 104.892167 -297.812899) (xy 104.884336 -297.867079) (xy 104.868837 -297.919583)
			(xy 104.845989 -297.969331) (xy 104.816263 -298.0153) (xy 104.798622 -298.036234) (xy 104.798368 -298.036488)
			(xy 104.792777 -298.043571) (xy 104.786534 -298.060491) (xy 104.786176 -298.069508) (xy 104.786176 -298.136564)
			(xy 104.786555 -298.145578) (xy 104.792788 -298.162495) (xy 104.798368 -298.169584) (xy 104.798622 -298.169584)
			(xy 104.798622 -298.169838) (xy 104.816249 -298.19078) (xy 104.845962 -298.23675) (xy 104.8688 -298.286495)
			(xy 104.884294 -298.338994) (xy 104.892126 -298.393168) (xy 104.892602 -298.420536) (xy 108.135166 -298.420536)
			(xy 108.135637 -298.393166) (xy 108.143451 -298.338986) (xy 108.158938 -298.286483) (xy 108.181779 -298.236736)
			(xy 108.211504 -298.190769) (xy 108.229146 -298.169838) (xy 108.2294 -298.169584) (xy 108.234999 -298.162506)
			(xy 108.241238 -298.145583) (xy 108.241592 -298.136564) (xy 108.241592 -298.069508) (xy 108.241233 -298.060491)
			(xy 108.234987 -298.043574) (xy 108.2294 -298.036488) (xy 108.229146 -298.036488) (xy 108.229146 -298.036234)
			(xy 108.21154 -298.015273) (xy 108.181812 -297.969311) (xy 108.158963 -297.919569) (xy 108.143464 -297.867071)
			(xy 108.135631 -297.812896) (xy 108.135627 -297.758158) (xy 108.143452 -297.703982) (xy 108.158944 -297.651482)
			(xy 108.181786 -297.601737) (xy 108.211507 -297.55577) (xy 108.229146 -297.534838) (xy 108.2294 -297.534584)
			(xy 108.234999 -297.527506) (xy 108.241238 -297.510583) (xy 108.241592 -297.501564) (xy 108.241592 -297.434508)
			(xy 108.241233 -297.425491) (xy 108.234987 -297.408574) (xy 108.2294 -297.401488) (xy 108.229146 -297.401488)
			(xy 108.229146 -297.401234) (xy 108.21154 -297.380273) (xy 108.181812 -297.334311) (xy 108.158963 -297.284569)
			(xy 108.143464 -297.232071) (xy 108.135631 -297.177896) (xy 108.135627 -297.123158) (xy 108.143452 -297.068982)
			(xy 108.158944 -297.016482) (xy 108.181786 -296.966737) (xy 108.211507 -296.92077) (xy 108.229146 -296.899838)
			(xy 108.2294 -296.899584) (xy 108.234999 -296.892506) (xy 108.241238 -296.875583) (xy 108.241592 -296.866564)
			(xy 108.241592 -296.799508) (xy 108.241233 -296.790491) (xy 108.234987 -296.773574) (xy 108.2294 -296.766488)
			(xy 108.229146 -296.766488) (xy 108.229146 -296.766234) (xy 108.21154 -296.745273) (xy 108.181812 -296.699311)
			(xy 108.158963 -296.649569) (xy 108.143464 -296.597071) (xy 108.135631 -296.542896) (xy 108.135627 -296.488158)
			(xy 108.143452 -296.433982) (xy 108.158944 -296.381482) (xy 108.181786 -296.331737) (xy 108.211507 -296.28577)
			(xy 108.229146 -296.264838) (xy 108.2294 -296.264584) (xy 108.234999 -296.257506) (xy 108.241238 -296.240583)
			(xy 108.241592 -296.231564) (xy 108.241592 -296.164508) (xy 108.241233 -296.155491) (xy 108.234987 -296.138574)
			(xy 108.2294 -296.131488) (xy 108.229146 -296.131488) (xy 108.229146 -296.131234) (xy 108.21154 -296.110273)
			(xy 108.181812 -296.064311) (xy 108.158963 -296.014569) (xy 108.143464 -295.962071) (xy 108.135631 -295.907896)
			(xy 108.135627 -295.853158) (xy 108.143452 -295.798982) (xy 108.158944 -295.746482) (xy 108.181786 -295.696737)
			(xy 108.211507 -295.65077) (xy 108.229146 -295.629838) (xy 108.2294 -295.629584) (xy 108.234999 -295.622506)
			(xy 108.241238 -295.605583) (xy 108.241592 -295.596564) (xy 108.241592 -295.529508) (xy 108.241233 -295.520491)
			(xy 108.234987 -295.503574) (xy 108.2294 -295.496488) (xy 108.229146 -295.496488) (xy 108.229146 -295.496234)
			(xy 108.211517 -295.475294) (xy 108.181802 -295.429324) (xy 108.158963 -295.379579) (xy 108.14347 -295.327079)
			(xy 108.13564 -295.272905) (xy 108.135166 -295.245536) (xy 108.135689 -295.218285) (xy 108.14344 -295.164338)
			(xy 108.15879 -295.112043) (xy 108.181427 -295.062464) (xy 108.210889 -295.016612) (xy 108.246576 -294.97542)
			(xy 108.287763 -294.939726) (xy 108.33361 -294.910256) (xy 108.383184 -294.887612) (xy 108.435477 -294.872253)
			(xy 108.489423 -294.864493) (xy 108.516674 -294.864028) (xy 108.544044 -294.864502) (xy 108.598223 -294.872317)
			(xy 108.650726 -294.887804) (xy 108.700473 -294.910644) (xy 108.74644 -294.940367) (xy 108.767372 -294.958008)
			(xy 108.767626 -294.958262) (xy 108.774724 -294.963831) (xy 108.791632 -294.970087) (xy 108.800646 -294.970454)
			(xy 108.867702 -294.970454) (xy 108.87672 -294.970108) (xy 108.893637 -294.963854) (xy 108.900722 -294.958262)
			(xy 108.900722 -294.958008) (xy 108.900976 -294.958008) (xy 108.921907 -294.940368) (xy 108.96788 -294.910656)
			(xy 109.017628 -294.88782) (xy 109.070129 -294.872329) (xy 109.124305 -294.864502) (xy 109.151674 -294.864028)
			(xy 109.178928 -294.86448) (xy 109.232881 -294.872234) (xy 109.285181 -294.887589) (xy 109.334764 -294.910231)
			(xy 109.380619 -294.939699) (xy 109.421813 -294.975394) (xy 109.457507 -295.016589) (xy 109.486974 -295.062445)
			(xy 109.509615 -295.112028) (xy 109.524968 -295.164329) (xy 109.532721 -295.218282) (xy 109.533182 -295.245536)
			(xy 109.532741 -295.272907) (xy 109.524918 -295.327088) (xy 109.509423 -295.379591) (xy 109.486576 -295.429338)
			(xy 109.456846 -295.475303) (xy 109.439202 -295.496234) (xy 109.438948 -295.496488) (xy 109.433354 -295.503569)
			(xy 109.427113 -295.52049) (xy 109.426756 -295.529508) (xy 109.426756 -295.596564) (xy 109.427118 -295.605581)
			(xy 109.433361 -295.622498) (xy 109.438948 -295.629584) (xy 109.439202 -295.629584) (xy 109.439202 -295.629838)
			(xy 109.456877 -295.650743) (xy 109.486598 -295.696716) (xy 109.509439 -295.746467) (xy 109.524932 -295.798973)
			(xy 109.532756 -295.853155) (xy 109.532752 -295.907899) (xy 109.52492 -295.96208) (xy 109.50942 -296.014584)
			(xy 109.486572 -296.064331) (xy 109.456844 -296.110301) (xy 109.439202 -296.131234) (xy 109.438948 -296.131488)
			(xy 109.433354 -296.138569) (xy 109.427113 -296.15549) (xy 109.426756 -296.164508) (xy 109.426756 -296.231564)
			(xy 109.427118 -296.240581) (xy 109.433361 -296.257498) (xy 109.438948 -296.264584) (xy 109.439202 -296.264584)
			(xy 109.439202 -296.264838) (xy 109.456877 -296.285743) (xy 109.486598 -296.331716) (xy 109.509439 -296.381467)
			(xy 109.524932 -296.433973) (xy 109.532756 -296.488155) (xy 109.532752 -296.542899) (xy 109.52492 -296.59708)
			(xy 109.50942 -296.649584) (xy 109.486572 -296.699331) (xy 109.456844 -296.745301) (xy 109.439202 -296.766234)
			(xy 109.438948 -296.766488) (xy 109.433354 -296.773569) (xy 109.427113 -296.79049) (xy 109.426756 -296.799508)
			(xy 109.426756 -296.866564) (xy 109.427118 -296.875581) (xy 109.433361 -296.892498) (xy 109.438948 -296.899584)
			(xy 109.439202 -296.899584) (xy 109.439202 -296.899838) (xy 109.456877 -296.920743) (xy 109.486598 -296.966716)
			(xy 109.509439 -297.016467) (xy 109.524932 -297.068973) (xy 109.532756 -297.123155) (xy 109.532752 -297.177899)
			(xy 109.52492 -297.23208) (xy 109.50942 -297.284584) (xy 109.486572 -297.334331) (xy 109.456844 -297.380301)
			(xy 109.439202 -297.401234) (xy 109.438948 -297.401488) (xy 109.433354 -297.408569) (xy 109.427113 -297.42549)
			(xy 109.426756 -297.434508) (xy 109.426756 -297.501564) (xy 109.427118 -297.510581) (xy 109.433361 -297.527498)
			(xy 109.438948 -297.534584) (xy 109.439202 -297.534584) (xy 109.439202 -297.534838) (xy 109.456877 -297.555743)
			(xy 109.486598 -297.601716) (xy 109.509439 -297.651467) (xy 109.524932 -297.703973) (xy 109.532756 -297.758155)
			(xy 109.532752 -297.812899) (xy 109.52492 -297.86708) (xy 109.50942 -297.919584) (xy 109.486572 -297.969331)
			(xy 109.456844 -298.015301) (xy 109.439202 -298.036234) (xy 109.438948 -298.036488) (xy 109.433354 -298.043569)
			(xy 109.427113 -298.06049) (xy 109.426756 -298.069508) (xy 109.426756 -298.136564) (xy 109.427118 -298.145581)
			(xy 109.433361 -298.162498) (xy 109.438948 -298.169584) (xy 109.439202 -298.169584) (xy 109.439202 -298.169838)
			(xy 109.456826 -298.190782) (xy 109.48654 -298.236752) (xy 109.509379 -298.286496) (xy 109.524873 -298.338994)
			(xy 109.532706 -298.393168) (xy 109.533182 -298.420536) (xy 110.562898 -298.420536) (xy 110.563386 -298.393167)
			(xy 110.571198 -298.338988) (xy 110.586682 -298.286486) (xy 110.609519 -298.236738) (xy 110.639239 -298.19077)
			(xy 110.656878 -298.169838) (xy 110.657132 -298.169584) (xy 110.662735 -298.162509) (xy 110.668971 -298.145583)
			(xy 110.669324 -298.136564) (xy 110.669324 -298.069508) (xy 110.668958 -298.060492) (xy 110.662716 -298.043575)
			(xy 110.657132 -298.036488) (xy 110.656878 -298.036488) (xy 110.656878 -298.036234) (xy 110.639275 -298.015272)
			(xy 110.609552 -297.969308) (xy 110.586708 -297.919566) (xy 110.571211 -297.867069) (xy 110.56338 -297.812895)
			(xy 110.563376 -297.758159) (xy 110.571199 -297.703984) (xy 110.586689 -297.651485) (xy 110.609526 -297.60174)
			(xy 110.639242 -297.555772) (xy 110.656878 -297.534838) (xy 110.657132 -297.534584) (xy 110.662735 -297.527509)
			(xy 110.668971 -297.510583) (xy 110.669324 -297.501564) (xy 110.669324 -297.434508) (xy 110.668958 -297.425492)
			(xy 110.662716 -297.408575) (xy 110.657132 -297.401488) (xy 110.656878 -297.401488) (xy 110.656878 -297.401234)
			(xy 110.639275 -297.380272) (xy 110.609552 -297.334308) (xy 110.586708 -297.284566) (xy 110.571211 -297.232069)
			(xy 110.56338 -297.177895) (xy 110.563376 -297.123159) (xy 110.571199 -297.068984) (xy 110.586689 -297.016485)
			(xy 110.609526 -296.96674) (xy 110.639242 -296.920772) (xy 110.656878 -296.899838) (xy 110.657132 -296.899584)
			(xy 110.662735 -296.892509) (xy 110.668971 -296.875583) (xy 110.669324 -296.866564) (xy 110.669324 -296.799508)
			(xy 110.668958 -296.790492) (xy 110.662716 -296.773575) (xy 110.657132 -296.766488) (xy 110.656878 -296.766488)
			(xy 110.656878 -296.766234) (xy 110.639275 -296.745272) (xy 110.609552 -296.699308) (xy 110.586708 -296.649566)
			(xy 110.571211 -296.597069) (xy 110.56338 -296.542895) (xy 110.563376 -296.488159) (xy 110.571199 -296.433984)
			(xy 110.586689 -296.381485) (xy 110.609526 -296.33174) (xy 110.639242 -296.285772) (xy 110.656878 -296.264838)
			(xy 110.657132 -296.264584) (xy 110.662735 -296.257509) (xy 110.668971 -296.240583) (xy 110.669324 -296.231564)
			(xy 110.669324 -296.164508) (xy 110.668958 -296.155492) (xy 110.662716 -296.138575) (xy 110.657132 -296.131488)
			(xy 110.656878 -296.131488) (xy 110.656878 -296.131234) (xy 110.639275 -296.110272) (xy 110.609552 -296.064308)
			(xy 110.586708 -296.014566) (xy 110.571211 -295.962069) (xy 110.56338 -295.907895) (xy 110.563376 -295.853159)
			(xy 110.571199 -295.798984) (xy 110.586689 -295.746485) (xy 110.609526 -295.69674) (xy 110.639242 -295.650772)
			(xy 110.656878 -295.629838) (xy 110.657132 -295.629584) (xy 110.662735 -295.622509) (xy 110.668971 -295.605583)
			(xy 110.669324 -295.596564) (xy 110.669324 -295.529508) (xy 110.668958 -295.520492) (xy 110.662716 -295.503575)
			(xy 110.657132 -295.496488) (xy 110.656878 -295.496488) (xy 110.656878 -295.496234) (xy 110.639238 -295.475303)
			(xy 110.609527 -295.429329) (xy 110.586692 -295.379582) (xy 110.571201 -295.327081) (xy 110.563372 -295.272905)
			(xy 110.562898 -295.245536) (xy 110.563389 -295.218284) (xy 110.571141 -295.164334) (xy 110.586493 -295.112036)
			(xy 110.609132 -295.062455) (xy 110.638596 -295.016602) (xy 110.674287 -294.975409) (xy 110.715478 -294.939714)
			(xy 110.761329 -294.910246) (xy 110.810908 -294.887603) (xy 110.863204 -294.872247) (xy 110.917154 -294.864491)
			(xy 110.944406 -294.864028) (xy 110.971777 -294.864484) (xy 111.025956 -294.872303) (xy 111.07846 -294.887794)
			(xy 111.128207 -294.910638) (xy 111.174173 -294.940365) (xy 111.195104 -294.958008) (xy 111.195358 -294.958262)
			(xy 111.202447 -294.963844) (xy 111.219362 -294.970092) (xy 111.228378 -294.970454) (xy 111.295434 -294.970454)
			(xy 111.304454 -294.970123) (xy 111.321371 -294.963859) (xy 111.328454 -294.958262) (xy 111.328454 -294.958008)
			(xy 111.328708 -294.958008) (xy 111.349627 -294.940353) (xy 111.395603 -294.910643) (xy 111.445354 -294.88781)
			(xy 111.497858 -294.872323) (xy 111.552036 -294.864499) (xy 111.579406 -294.864028) (xy 111.606661 -294.86445)
			(xy 111.660615 -294.872209) (xy 111.712916 -294.887567) (xy 111.762498 -294.910213) (xy 111.808353 -294.939685)
			(xy 111.849547 -294.975383) (xy 111.88524 -295.016581) (xy 111.914707 -295.062439) (xy 111.937347 -295.112024)
			(xy 111.9527 -295.164326) (xy 111.960453 -295.218281) (xy 111.960914 -295.245536) (xy 111.960466 -295.272907)
			(xy 111.952643 -295.327087) (xy 111.93715 -295.37959) (xy 111.914304 -295.429336) (xy 111.884576 -295.475303)
			(xy 111.866934 -295.496234) (xy 111.86668 -295.496488) (xy 111.86109 -295.503572) (xy 111.854846 -295.520491)
			(xy 111.854488 -295.529508) (xy 111.854488 -295.596564) (xy 111.854865 -295.605579) (xy 111.861099 -295.622496)
			(xy 111.86668 -295.629584) (xy 111.866934 -295.629584) (xy 111.866934 -295.629838) (xy 111.884612 -295.650741)
			(xy 111.914338 -295.696713) (xy 111.937184 -295.746464) (xy 111.952679 -295.798971) (xy 111.960505 -295.853154)
			(xy 111.960501 -295.9079) (xy 111.952667 -295.962082) (xy 111.937164 -296.014587) (xy 111.914312 -296.064334)
			(xy 111.884579 -296.110302) (xy 111.866934 -296.131234) (xy 111.86668 -296.131488) (xy 111.86109 -296.138572)
			(xy 111.854846 -296.155491) (xy 111.854488 -296.164508) (xy 111.854488 -296.231564) (xy 111.854865 -296.240579)
			(xy 111.861099 -296.257496) (xy 111.86668 -296.264584) (xy 111.866934 -296.264584) (xy 111.866934 -296.264838)
			(xy 111.884612 -296.285741) (xy 111.914338 -296.331713) (xy 111.937184 -296.381464) (xy 111.952679 -296.433971)
			(xy 111.960505 -296.488154) (xy 111.960501 -296.5429) (xy 111.952667 -296.597082) (xy 111.937164 -296.649587)
			(xy 111.914312 -296.699334) (xy 111.884579 -296.745302) (xy 111.866934 -296.766234) (xy 111.86668 -296.766488)
			(xy 111.86109 -296.773572) (xy 111.854846 -296.790491) (xy 111.854488 -296.799508) (xy 111.854488 -296.866564)
			(xy 111.854865 -296.875579) (xy 111.861099 -296.892496) (xy 111.86668 -296.899584) (xy 111.866934 -296.899584)
			(xy 111.866934 -296.899838) (xy 111.884612 -296.920741) (xy 111.914338 -296.966713) (xy 111.937184 -297.016464)
			(xy 111.952679 -297.068971) (xy 111.960505 -297.123154) (xy 111.960501 -297.1779) (xy 111.952667 -297.232082)
			(xy 111.937164 -297.284587) (xy 111.914312 -297.334334) (xy 111.884579 -297.380302) (xy 111.866934 -297.401234)
			(xy 111.86668 -297.401488) (xy 111.86109 -297.408572) (xy 111.854846 -297.425491) (xy 111.854488 -297.434508)
			(xy 111.854488 -297.501564) (xy 111.854865 -297.510579) (xy 111.861099 -297.527496) (xy 111.86668 -297.534584)
			(xy 111.866934 -297.534584) (xy 111.866934 -297.534838) (xy 111.884612 -297.555741) (xy 111.914338 -297.601713)
			(xy 111.937184 -297.651464) (xy 111.952679 -297.703971) (xy 111.960505 -297.758154) (xy 111.960501 -297.8129)
			(xy 111.952667 -297.867082) (xy 111.937164 -297.919587) (xy 111.914312 -297.969334) (xy 111.884579 -298.015302)
			(xy 111.866934 -298.036234) (xy 111.86668 -298.036488) (xy 111.86109 -298.043572) (xy 111.854846 -298.060491)
			(xy 111.854488 -298.069508) (xy 111.854488 -298.136564) (xy 111.854865 -298.145579) (xy 111.861099 -298.162496)
			(xy 111.86668 -298.169584) (xy 111.866934 -298.169584) (xy 111.866934 -298.169838) (xy 111.884563 -298.190778)
			(xy 111.914275 -298.236749) (xy 111.937112 -298.286495) (xy 111.952606 -298.338993) (xy 111.960438 -298.393167)
			(xy 111.960914 -298.420536) (xy 115.203478 -298.420536) (xy 115.203946 -298.393166) (xy 115.211761 -298.338986)
			(xy 115.227248 -298.286482) (xy 115.25009 -298.236735) (xy 115.279816 -298.190769) (xy 115.297458 -298.169838)
			(xy 115.297712 -298.169584) (xy 115.303313 -298.162507) (xy 115.309551 -298.145583) (xy 115.309904 -298.136564)
			(xy 115.309904 -298.069508) (xy 115.309542 -298.060492) (xy 115.303298 -298.043575) (xy 115.297712 -298.036488)
			(xy 115.297458 -298.036488) (xy 115.297458 -298.036234) (xy 115.279851 -298.015273) (xy 115.250123 -297.969311)
			(xy 115.227273 -297.91957) (xy 115.211773 -297.867072) (xy 115.20394 -297.812896) (xy 115.203936 -297.758158)
			(xy 115.211761 -297.703981) (xy 115.227254 -297.651481) (xy 115.250097 -297.601736) (xy 115.279819 -297.55577)
			(xy 115.297458 -297.534838) (xy 115.297712 -297.534584) (xy 115.303313 -297.527507) (xy 115.309551 -297.510583)
			(xy 115.309904 -297.501564) (xy 115.309904 -297.434508) (xy 115.309542 -297.425492) (xy 115.303298 -297.408575)
			(xy 115.297712 -297.401488) (xy 115.297458 -297.401488) (xy 115.297458 -297.401234) (xy 115.279851 -297.380273)
			(xy 115.250123 -297.334311) (xy 115.227273 -297.28457) (xy 115.211773 -297.232072) (xy 115.20394 -297.177896)
			(xy 115.203936 -297.123158) (xy 115.211761 -297.068981) (xy 115.227254 -297.016481) (xy 115.250097 -296.966736)
			(xy 115.279819 -296.92077) (xy 115.297458 -296.899838) (xy 115.297712 -296.899584) (xy 115.303313 -296.892507)
			(xy 115.309551 -296.875583) (xy 115.309904 -296.866564) (xy 115.309904 -296.799508) (xy 115.309542 -296.790492)
			(xy 115.303298 -296.773575) (xy 115.297712 -296.766488) (xy 115.297458 -296.766488) (xy 115.297458 -296.766234)
			(xy 115.279851 -296.745273) (xy 115.250123 -296.699311) (xy 115.227273 -296.64957) (xy 115.211773 -296.597072)
			(xy 115.20394 -296.542896) (xy 115.203936 -296.488158) (xy 115.211761 -296.433981) (xy 115.227254 -296.381481)
			(xy 115.250097 -296.331736) (xy 115.279819 -296.28577) (xy 115.297458 -296.264838) (xy 115.297712 -296.264584)
			(xy 115.303313 -296.257507) (xy 115.309551 -296.240583) (xy 115.309904 -296.231564) (xy 115.309904 -296.164508)
			(xy 115.309542 -296.155492) (xy 115.303298 -296.138575) (xy 115.297712 -296.131488) (xy 115.297458 -296.131488)
			(xy 115.297458 -296.131234) (xy 115.279851 -296.110273) (xy 115.250123 -296.064311) (xy 115.227273 -296.01457)
			(xy 115.211773 -295.962072) (xy 115.20394 -295.907896) (xy 115.203936 -295.853158) (xy 115.211761 -295.798981)
			(xy 115.227254 -295.746481) (xy 115.250097 -295.696736) (xy 115.279819 -295.65077) (xy 115.297458 -295.629838)
			(xy 115.297712 -295.629584) (xy 115.303313 -295.622507) (xy 115.309551 -295.605583) (xy 115.309904 -295.596564)
			(xy 115.309904 -295.529508) (xy 115.309542 -295.520492) (xy 115.303298 -295.503575) (xy 115.297712 -295.496488)
			(xy 115.297458 -295.496488) (xy 115.297458 -295.496234) (xy 115.279814 -295.475306) (xy 115.250105 -295.429331)
			(xy 115.22727 -295.379583) (xy 115.21178 -295.327081) (xy 115.203952 -295.272905) (xy 115.203478 -295.245536)
			(xy 115.203989 -295.218285) (xy 115.21174 -295.164336) (xy 115.227091 -295.11204) (xy 115.249729 -295.062461)
			(xy 115.279191 -295.016608) (xy 115.31488 -294.975416) (xy 115.356068 -294.939721) (xy 115.401917 -294.910253)
			(xy 115.451493 -294.887609) (xy 115.503787 -294.872251) (xy 115.557735 -294.864492) (xy 115.584986 -294.864028)
			(xy 115.612356 -294.864495) (xy 115.666536 -294.872312) (xy 115.719039 -294.8878) (xy 115.768786 -294.910642)
			(xy 115.814752 -294.940367) (xy 115.835684 -294.958008) (xy 115.835938 -294.958262) (xy 115.843033 -294.963836)
			(xy 115.859944 -294.970089) (xy 115.868958 -294.970454) (xy 115.936014 -294.970454) (xy 115.945033 -294.970114)
			(xy 115.96195 -294.963856) (xy 115.969034 -294.958262) (xy 115.969034 -294.958008) (xy 115.969288 -294.958008)
			(xy 115.990215 -294.940362) (xy 116.036189 -294.910651) (xy 116.085938 -294.887816) (xy 116.13844 -294.872327)
			(xy 116.192616 -294.864501) (xy 116.219986 -294.864028) (xy 116.24724 -294.864468) (xy 116.301194 -294.872224)
			(xy 116.353494 -294.887581) (xy 116.403077 -294.910224) (xy 116.448932 -294.939694) (xy 116.490125 -294.97539)
			(xy 116.525819 -295.016586) (xy 116.555287 -295.062443) (xy 116.577927 -295.112026) (xy 116.59328 -295.164328)
			(xy 116.601033 -295.218282) (xy 116.601494 -295.245536) (xy 116.60105 -295.272907) (xy 116.593227 -295.327087)
			(xy 116.577733 -295.379591) (xy 116.554886 -295.429337) (xy 116.525157 -295.475303) (xy 116.507514 -295.496234)
			(xy 116.50726 -295.496488) (xy 116.501667 -295.50357) (xy 116.495425 -295.52049) (xy 116.495068 -295.529508)
			(xy 116.495068 -295.596564) (xy 116.495449 -295.605578) (xy 116.501681 -295.622495) (xy 116.50726 -295.629584)
			(xy 116.507514 -295.629584) (xy 116.507514 -295.629838) (xy 116.525188 -295.650743) (xy 116.554908 -295.696717)
			(xy 116.577749 -295.746468) (xy 116.593241 -295.798974) (xy 116.601065 -295.853155) (xy 116.601061 -295.907899)
			(xy 116.593229 -295.962079) (xy 116.57773 -296.014583) (xy 116.554882 -296.064331) (xy 116.525156 -296.1103)
			(xy 116.507514 -296.131234) (xy 116.50726 -296.131488) (xy 116.501667 -296.13857) (xy 116.495425 -296.15549)
			(xy 116.495068 -296.164508) (xy 116.495068 -296.231564) (xy 116.495449 -296.240578) (xy 116.501681 -296.257495)
			(xy 116.50726 -296.264584) (xy 116.507514 -296.264584) (xy 116.507514 -296.264838) (xy 116.525188 -296.285743)
			(xy 116.554908 -296.331717) (xy 116.577749 -296.381468) (xy 116.593241 -296.433974) (xy 116.601065 -296.488155)
			(xy 116.601061 -296.542899) (xy 116.593229 -296.597079) (xy 116.57773 -296.649583) (xy 116.554882 -296.699331)
			(xy 116.525156 -296.7453) (xy 116.507514 -296.766234) (xy 116.50726 -296.766488) (xy 116.501667 -296.77357)
			(xy 116.495425 -296.79049) (xy 116.495068 -296.799508) (xy 116.495068 -296.866564) (xy 116.495449 -296.875578)
			(xy 116.501681 -296.892495) (xy 116.50726 -296.899584) (xy 116.507514 -296.899584) (xy 116.507514 -296.899838)
			(xy 116.525188 -296.920743) (xy 116.554908 -296.966717) (xy 116.577749 -297.016468) (xy 116.593241 -297.068974)
			(xy 116.601065 -297.123155) (xy 116.601061 -297.177899) (xy 116.593229 -297.232079) (xy 116.57773 -297.284583)
			(xy 116.554882 -297.334331) (xy 116.525156 -297.3803) (xy 116.507514 -297.401234) (xy 116.50726 -297.401488)
			(xy 116.501667 -297.40857) (xy 116.495425 -297.42549) (xy 116.495068 -297.434508) (xy 116.495068 -297.501564)
			(xy 116.495449 -297.510578) (xy 116.501681 -297.527495) (xy 116.50726 -297.534584) (xy 116.507514 -297.534584)
			(xy 116.507514 -297.534838) (xy 116.525188 -297.555743) (xy 116.554908 -297.601717) (xy 116.577749 -297.651468)
			(xy 116.593241 -297.703974) (xy 116.601065 -297.758155) (xy 116.601061 -297.812899) (xy 116.593229 -297.867079)
			(xy 116.57773 -297.919583) (xy 116.554882 -297.969331) (xy 116.525156 -298.0153) (xy 116.507514 -298.036234)
			(xy 116.50726 -298.036488) (xy 116.501667 -298.04357) (xy 116.495425 -298.06049) (xy 116.495068 -298.069508)
			(xy 116.495068 -298.136564) (xy 116.495449 -298.145578) (xy 116.501681 -298.162495) (xy 116.50726 -298.169584)
			(xy 116.507514 -298.169584) (xy 116.507514 -298.169838) (xy 116.52514 -298.190781) (xy 116.554853 -298.236751)
			(xy 116.577691 -298.286496) (xy 116.593186 -298.338994) (xy 116.601018 -298.393168) (xy 116.601494 -298.420536)
			(xy 116.601056 -298.447789) (xy 116.593294 -298.501739) (xy 116.577933 -298.554035) (xy 116.555287 -298.603614)
			(xy 116.525816 -298.649465) (xy 116.490119 -298.690655) (xy 116.448925 -298.726346) (xy 116.40307 -298.755811)
			(xy 116.353488 -298.778451) (xy 116.30119 -298.793805) (xy 116.247239 -298.801559) (xy 116.219986 -298.802044)
			(xy 116.192615 -298.8016) (xy 116.138434 -298.793779) (xy 116.08593 -298.778285) (xy 116.036184 -298.755438)
			(xy 115.990218 -298.725708) (xy 115.969288 -298.708064) (xy 115.969034 -298.70781) (xy 115.961941 -298.702233)
			(xy 115.945029 -298.69598) (xy 115.936014 -298.695618) (xy 115.868958 -298.695618) (xy 115.859943 -298.695999)
			(xy 115.843026 -298.70223) (xy 115.835938 -298.70781) (xy 115.835938 -298.708064) (xy 115.835684 -298.708064)
			(xy 115.814726 -298.725672) (xy 115.768761 -298.755389) (xy 115.71902 -298.778232) (xy 115.666525 -298.79373)
			(xy 115.612354 -298.801566) (xy 115.584986 -298.802044) (xy 115.557736 -298.801535) (xy 115.503791 -298.793778)
			(xy 115.451499 -298.778423) (xy 115.401924 -298.755783) (xy 115.356075 -298.726318) (xy 115.314886 -298.690629)
			(xy 115.279195 -298.649442) (xy 115.249728 -298.603595) (xy 115.227085 -298.554022) (xy 115.211727 -298.501731)
			(xy 115.203966 -298.447786) (xy 115.203478 -298.420536) (xy 111.960914 -298.420536) (xy 111.960456 -298.447788)
			(xy 111.952694 -298.501736) (xy 111.937335 -298.554031) (xy 111.91469 -298.603608) (xy 111.885221 -298.649458)
			(xy 111.849526 -298.690648) (xy 111.808334 -298.726339) (xy 111.762482 -298.755805) (xy 111.712903 -298.778446)
			(xy 111.660607 -298.793801) (xy 111.606658 -298.801558) (xy 111.579406 -298.802044) (xy 111.552035 -298.801588)
			(xy 111.497855 -298.79377) (xy 111.445351 -298.778279) (xy 111.395605 -298.755435) (xy 111.349639 -298.725707)
			(xy 111.328708 -298.708064) (xy 111.328454 -298.70781) (xy 111.321355 -298.702241) (xy 111.304448 -298.695983)
			(xy 111.295434 -298.695618) (xy 111.228378 -298.695618) (xy 111.21936 -298.695961) (xy 111.202443 -298.702218)
			(xy 111.195358 -298.70781) (xy 111.195358 -298.708064) (xy 111.195104 -298.708064) (xy 111.174177 -298.725709)
			(xy 111.128203 -298.755421) (xy 111.078454 -298.778257) (xy 111.025953 -298.793746) (xy 110.971776 -298.801572)
			(xy 110.944406 -298.802044) (xy 110.917157 -298.801517) (xy 110.863212 -298.793762) (xy 110.81092 -298.778409)
			(xy 110.761346 -298.755772) (xy 110.715497 -298.726309) (xy 110.674308 -298.690622) (xy 110.638616 -298.649437)
			(xy 110.609149 -298.603591) (xy 110.586505 -298.554019) (xy 110.571147 -298.501729) (xy 110.563386 -298.447785)
			(xy 110.562898 -298.420536) (xy 109.533182 -298.420536) (xy 109.532756 -298.447789) (xy 109.524994 -298.501741)
			(xy 109.509633 -298.554038) (xy 109.486985 -298.603617) (xy 109.457513 -298.649469) (xy 109.421815 -298.690659)
			(xy 109.380619 -298.72635) (xy 109.334763 -298.755815) (xy 109.28518 -298.778454) (xy 109.23288 -298.793807)
			(xy 109.178927 -298.80156) (xy 109.151674 -298.802044) (xy 109.124303 -298.801607) (xy 109.070122 -298.793784)
			(xy 109.017618 -298.778289) (xy 108.967871 -298.755441) (xy 108.921906 -298.725709) (xy 108.900976 -298.708064)
			(xy 108.900722 -298.70781) (xy 108.893632 -298.702228) (xy 108.876718 -298.695978) (xy 108.867702 -298.695618)
			(xy 108.800646 -298.695618) (xy 108.791631 -298.695993) (xy 108.774714 -298.702228) (xy 108.767626 -298.70781)
			(xy 108.767626 -298.708064) (xy 108.767372 -298.708064) (xy 108.746419 -298.725677) (xy 108.700452 -298.755394)
			(xy 108.65071 -298.778236) (xy 108.598214 -298.793733) (xy 108.544042 -298.801567) (xy 108.516674 -298.802044)
			(xy 108.489424 -298.801546) (xy 108.435478 -298.793787) (xy 108.383186 -298.778431) (xy 108.333611 -298.755789)
			(xy 108.287763 -298.726324) (xy 108.246574 -298.690634) (xy 108.210882 -298.649445) (xy 108.181416 -298.603598)
			(xy 108.158773 -298.554023) (xy 108.143415 -298.501731) (xy 108.135654 -298.447786) (xy 108.135166 -298.420536)
			(xy 104.892602 -298.420536) (xy 104.892156 -298.447788) (xy 104.884394 -298.501738) (xy 104.869034 -298.554034)
			(xy 104.846388 -298.603611) (xy 104.816918 -298.649462) (xy 104.781222 -298.690652) (xy 104.740028 -298.726343)
			(xy 104.694175 -298.755808) (xy 104.644594 -298.778449) (xy 104.592297 -298.793803) (xy 104.538346 -298.801559)
			(xy 104.511094 -298.802044) (xy 104.483723 -298.801595) (xy 104.429543 -298.793775) (xy 104.377039 -298.778283)
			(xy 104.327292 -298.755437) (xy 104.281327 -298.725708) (xy 104.260396 -298.708064) (xy 104.260142 -298.70781)
			(xy 104.253047 -298.702236) (xy 104.236137 -298.695981) (xy 104.227122 -298.695618) (xy 104.160066 -298.695618)
			(xy 104.151047 -298.695955) (xy 104.13413 -298.702216) (xy 104.127046 -298.70781) (xy 104.127046 -298.708064)
			(xy 104.126792 -298.708064) (xy 104.105869 -298.725715) (xy 104.059894 -298.755426) (xy 104.010145 -298.77826)
			(xy 103.957642 -298.793749) (xy 103.903464 -298.801573) (xy 103.876094 -298.802044) (xy 103.848844 -298.801528)
			(xy 103.794899 -298.793772) (xy 103.742607 -298.778417) (xy 103.693033 -298.755778) (xy 103.647184 -298.726315)
			(xy 103.605995 -298.690626) (xy 103.570303 -298.64944) (xy 103.540836 -298.603594) (xy 103.518193 -298.554021)
			(xy 103.502835 -298.50173) (xy 103.495074 -298.447786) (xy 103.494586 -298.420536) (xy 100.33 -298.420536)
			(xy 100.33 -301.424086) (xy 102.823518 -301.424086) (xy 102.823971 -301.396715) (xy 102.831792 -301.342535)
			(xy 102.847283 -301.290032) (xy 102.870128 -301.240285) (xy 102.899855 -301.194319) (xy 102.917498 -301.173388)
			(xy 102.917752 -301.173134) (xy 102.923337 -301.166046) (xy 102.929583 -301.14913) (xy 102.929944 -301.140114)
			(xy 102.929944 -301.073058) (xy 102.929572 -301.064042) (xy 102.923336 -301.047125) (xy 102.917752 -301.040038)
			(xy 102.917498 -301.040038) (xy 102.917498 -301.039784) (xy 102.899845 -301.018862) (xy 102.870123 -300.972891)
			(xy 102.84728 -300.923143) (xy 102.831786 -300.87064) (xy 102.823959 -300.81646) (xy 102.823961 -300.761719)
			(xy 102.831791 -300.707539) (xy 102.847287 -300.655037) (xy 102.870133 -300.60529) (xy 102.899858 -300.559321)
			(xy 102.917498 -300.538388) (xy 102.917752 -300.538134) (xy 102.923337 -300.531046) (xy 102.929583 -300.51413)
			(xy 102.929944 -300.505114) (xy 102.929944 -300.438058) (xy 102.929572 -300.429042) (xy 102.923336 -300.412125)
			(xy 102.917752 -300.405038) (xy 102.917498 -300.405038) (xy 102.917498 -300.404784) (xy 102.899845 -300.383862)
			(xy 102.870123 -300.337891) (xy 102.84728 -300.288143) (xy 102.831786 -300.23564) (xy 102.823959 -300.18146)
			(xy 102.823961 -300.126719) (xy 102.831791 -300.072539) (xy 102.847287 -300.020037) (xy 102.870133 -299.97029)
			(xy 102.899858 -299.924321) (xy 102.917498 -299.903388) (xy 102.917752 -299.903134) (xy 102.923337 -299.896046)
			(xy 102.929583 -299.87913) (xy 102.929944 -299.870114) (xy 102.929944 -299.803058) (xy 102.929572 -299.794042)
			(xy 102.923336 -299.777125) (xy 102.917752 -299.770038) (xy 102.917498 -299.770038) (xy 102.917498 -299.769784)
			(xy 102.899885 -299.748831) (xy 102.870169 -299.702864) (xy 102.847328 -299.653122) (xy 102.831831 -299.600626)
			(xy 102.823996 -299.546454) (xy 102.823518 -299.519086) (xy 102.824004 -299.491835) (xy 102.83176 -299.437887)
			(xy 102.847115 -299.385592) (xy 102.869757 -299.336015) (xy 102.899223 -299.290165) (xy 102.934914 -299.248974)
			(xy 102.976105 -299.213283) (xy 103.021955 -299.183817) (xy 103.071532 -299.161175) (xy 103.123827 -299.14582)
			(xy 103.177775 -299.138064) (xy 103.232277 -299.138064) (xy 103.286225 -299.14582) (xy 103.33852 -299.161175)
			(xy 103.388097 -299.183817) (xy 103.433947 -299.213283) (xy 103.475138 -299.248974) (xy 103.510829 -299.290165)
			(xy 103.540295 -299.336015) (xy 103.562937 -299.385592) (xy 103.578292 -299.437887) (xy 103.586048 -299.491835)
			(xy 103.586534 -299.519086) (xy 103.586076 -299.546457) (xy 103.578259 -299.600637) (xy 103.562769 -299.653141)
			(xy 103.539925 -299.702887) (xy 103.510197 -299.748853) (xy 103.492554 -299.769784) (xy 103.4923 -299.770038)
			(xy 103.486733 -299.777138) (xy 103.480475 -299.794045) (xy 103.480108 -299.803058) (xy 103.480108 -299.870114)
			(xy 103.480457 -299.879132) (xy 103.48671 -299.896049) (xy 103.4923 -299.903134) (xy 103.492554 -299.903134)
			(xy 103.492554 -299.903388) (xy 103.510182 -299.924331) (xy 103.539909 -299.970297) (xy 103.562756 -300.020041)
			(xy 103.578254 -300.072542) (xy 103.586084 -300.126719) (xy 103.586086 -300.18146) (xy 103.578259 -300.235637)
			(xy 103.562763 -300.288139) (xy 103.539919 -300.337885) (xy 103.510194 -300.383852) (xy 103.492554 -300.404784)
			(xy 103.4923 -300.405038) (xy 103.486733 -300.412138) (xy 103.480475 -300.429045) (xy 103.480108 -300.438058)
			(xy 103.480108 -300.505114) (xy 103.480457 -300.514132) (xy 103.48671 -300.531049) (xy 103.4923 -300.538134)
			(xy 103.492554 -300.538134) (xy 103.492554 -300.538388) (xy 103.510182 -300.559331) (xy 103.539909 -300.605297)
			(xy 103.562756 -300.655041) (xy 103.578254 -300.707542) (xy 103.586084 -300.761719) (xy 103.586086 -300.81646)
			(xy 103.578259 -300.870637) (xy 103.562763 -300.923139) (xy 103.539919 -300.972885) (xy 103.510194 -301.018852)
			(xy 103.492554 -301.039784) (xy 103.4923 -301.040038) (xy 103.486733 -301.047138) (xy 103.480475 -301.064045)
			(xy 103.480108 -301.073058) (xy 103.480108 -301.140114) (xy 103.480457 -301.149132) (xy 103.48671 -301.166049)
			(xy 103.4923 -301.173134) (xy 103.492554 -301.173134) (xy 103.492554 -301.173388) (xy 103.510194 -301.19432)
			(xy 103.539907 -301.240292) (xy 103.562744 -301.290039) (xy 103.578234 -301.34254) (xy 103.586061 -301.396717)
			(xy 103.586534 -301.424086) (xy 103.586048 -301.451337) (xy 103.582224 -301.477934) (xy 106.455718 -301.477934)
			(xy 106.4562 -301.450564) (xy 106.464013 -301.396386) (xy 106.479498 -301.343883) (xy 106.502337 -301.294135)
			(xy 106.532058 -301.248168) (xy 106.549698 -301.227236) (xy 106.549952 -301.226982) (xy 106.555558 -301.219909)
			(xy 106.561792 -301.202982) (xy 106.562144 -301.193962) (xy 106.562144 -301.126906) (xy 106.561796 -301.117888)
			(xy 106.555543 -301.10097) (xy 106.549952 -301.093886) (xy 106.549698 -301.093886) (xy 106.549698 -301.093632)
			(xy 106.532092 -301.072672) (xy 106.502368 -301.026708) (xy 106.479522 -300.976966) (xy 106.464025 -300.924469)
			(xy 106.456193 -300.870294) (xy 106.45619 -300.815557) (xy 106.464014 -300.761382) (xy 106.479504 -300.708882)
			(xy 106.502343 -300.659137) (xy 106.532061 -300.613169) (xy 106.549698 -300.592236) (xy 106.549952 -300.591982)
			(xy 106.555558 -300.584909) (xy 106.561792 -300.567982) (xy 106.562144 -300.558962) (xy 106.562144 -300.491906)
			(xy 106.561796 -300.482888) (xy 106.555543 -300.46597) (xy 106.549952 -300.458886) (xy 106.549698 -300.458886)
			(xy 106.549698 -300.458632) (xy 106.532092 -300.437672) (xy 106.502368 -300.391708) (xy 106.479522 -300.341966)
			(xy 106.464025 -300.289469) (xy 106.456193 -300.235294) (xy 106.45619 -300.180557) (xy 106.464014 -300.126382)
			(xy 106.479504 -300.073882) (xy 106.502343 -300.024137) (xy 106.532061 -299.978169) (xy 106.549698 -299.957236)
			(xy 106.549952 -299.956982) (xy 106.555558 -299.949909) (xy 106.561792 -299.932982) (xy 106.562144 -299.923962)
			(xy 106.562144 -299.856906) (xy 106.561796 -299.847888) (xy 106.555543 -299.83097) (xy 106.549952 -299.823886)
			(xy 106.549698 -299.823886) (xy 106.549698 -299.823632) (xy 106.53206 -299.802699) (xy 106.502348 -299.756726)
			(xy 106.479512 -299.706979) (xy 106.464021 -299.654479) (xy 106.456192 -299.600303) (xy 106.455718 -299.572934)
			(xy 106.456204 -299.545683) (xy 106.46396 -299.491735) (xy 106.479315 -299.43944) (xy 106.501957 -299.389863)
			(xy 106.531423 -299.344013) (xy 106.567114 -299.302822) (xy 106.608305 -299.267131) (xy 106.654155 -299.237665)
			(xy 106.703732 -299.215023) (xy 106.756027 -299.199668) (xy 106.809975 -299.191912) (xy 106.864477 -299.191912)
			(xy 106.918425 -299.199668) (xy 106.97072 -299.215023) (xy 107.020297 -299.237665) (xy 107.066147 -299.267131)
			(xy 107.107338 -299.302822) (xy 107.143029 -299.344013) (xy 107.172495 -299.389863) (xy 107.195137 -299.43944)
			(xy 107.210492 -299.491735) (xy 107.218248 -299.545683) (xy 107.218734 -299.572934) (xy 107.218304 -299.600306)
			(xy 107.21048 -299.654487) (xy 107.194983 -299.706991) (xy 107.172133 -299.756737) (xy 107.1424 -299.802702)
			(xy 107.124754 -299.823632) (xy 107.1245 -299.823886) (xy 107.118913 -299.830972) (xy 107.112667 -299.847889)
			(xy 107.112308 -299.856906) (xy 107.112308 -299.923962) (xy 107.112682 -299.932977) (xy 107.118918 -299.949894)
			(xy 107.1245 -299.956982) (xy 107.124754 -299.956982) (xy 107.124754 -299.957236) (xy 107.142429 -299.978141)
			(xy 107.172154 -300.024113) (xy 107.194998 -300.073864) (xy 107.210493 -300.126371) (xy 107.218318 -300.180553)
			(xy 107.218315 -300.235298) (xy 107.210482 -300.28948) (xy 107.19498 -300.341984) (xy 107.172129 -300.391732)
			(xy 107.142398 -300.4377) (xy 107.124754 -300.458632) (xy 107.1245 -300.458886) (xy 107.118913 -300.465972)
			(xy 107.112667 -300.482889) (xy 107.112308 -300.491906) (xy 107.112308 -300.558962) (xy 107.112682 -300.567977)
			(xy 107.118918 -300.584894) (xy 107.1245 -300.591982) (xy 107.124754 -300.591982) (xy 107.124754 -300.592236)
			(xy 107.142429 -300.613141) (xy 107.172154 -300.659113) (xy 107.194998 -300.708864) (xy 107.210493 -300.761371)
			(xy 107.218318 -300.815553) (xy 107.218315 -300.870298) (xy 107.210482 -300.92448) (xy 107.19498 -300.976984)
			(xy 107.172129 -301.026732) (xy 107.142398 -301.0727) (xy 107.124754 -301.093632) (xy 107.1245 -301.093886)
			(xy 107.118913 -301.100972) (xy 107.112667 -301.117889) (xy 107.112308 -301.126906) (xy 107.112308 -301.193962)
			(xy 107.112682 -301.202977) (xy 107.118918 -301.219894) (xy 107.1245 -301.226982) (xy 107.124754 -301.226982)
			(xy 107.124754 -301.227236) (xy 107.142369 -301.248187) (xy 107.172086 -301.294154) (xy 107.194928 -301.343897)
			(xy 107.210424 -301.396393) (xy 107.214428 -301.424086) (xy 109.663738 -301.424086) (xy 109.664187 -301.396715)
			(xy 109.672007 -301.342535) (xy 109.6875 -301.290031) (xy 109.710346 -301.240285) (xy 109.740075 -301.194319)
			(xy 109.757718 -301.173388) (xy 109.757972 -301.173134) (xy 109.763559 -301.166048) (xy 109.769803 -301.149131)
			(xy 109.770164 -301.140114) (xy 109.770164 -301.073058) (xy 109.769787 -301.064043) (xy 109.763554 -301.047125)
			(xy 109.757972 -301.040038) (xy 109.757718 -301.040038) (xy 109.757718 -301.039784) (xy 109.740064 -301.018862)
			(xy 109.71034 -300.972892) (xy 109.687496 -300.923144) (xy 109.672002 -300.870641) (xy 109.664175 -300.816461)
			(xy 109.664176 -300.761718) (xy 109.672006 -300.707539) (xy 109.687504 -300.655036) (xy 109.710351 -300.605289)
			(xy 109.740077 -300.559321) (xy 109.757718 -300.538388) (xy 109.757972 -300.538134) (xy 109.763559 -300.531048)
			(xy 109.769803 -300.514131) (xy 109.770164 -300.505114) (xy 109.770164 -300.438058) (xy 109.769787 -300.429043)
			(xy 109.763554 -300.412125) (xy 109.757972 -300.405038) (xy 109.757718 -300.405038) (xy 109.757718 -300.404784)
			(xy 109.740064 -300.383862) (xy 109.71034 -300.337892) (xy 109.687496 -300.288144) (xy 109.672002 -300.235641)
			(xy 109.664175 -300.181461) (xy 109.664176 -300.126718) (xy 109.672006 -300.072539) (xy 109.687504 -300.020036)
			(xy 109.710351 -299.970289) (xy 109.740077 -299.924321) (xy 109.757718 -299.903388) (xy 109.757972 -299.903134)
			(xy 109.763559 -299.896048) (xy 109.769803 -299.879131) (xy 109.770164 -299.870114) (xy 109.770164 -299.803058)
			(xy 109.769787 -299.794043) (xy 109.763554 -299.777125) (xy 109.757972 -299.770038) (xy 109.757718 -299.770038)
			(xy 109.757718 -299.769784) (xy 109.740108 -299.748829) (xy 109.710391 -299.702863) (xy 109.687549 -299.653121)
			(xy 109.672051 -299.600625) (xy 109.664216 -299.546454) (xy 109.663738 -299.519086) (xy 109.664224 -299.491835)
			(xy 109.67198 -299.437887) (xy 109.687335 -299.385592) (xy 109.709977 -299.336015) (xy 109.739443 -299.290165)
			(xy 109.775134 -299.248974) (xy 109.816325 -299.213283) (xy 109.862175 -299.183817) (xy 109.911752 -299.161175)
			(xy 109.964047 -299.14582) (xy 110.017995 -299.138064) (xy 110.072497 -299.138064) (xy 110.126445 -299.14582)
			(xy 110.17874 -299.161175) (xy 110.228317 -299.183817) (xy 110.274167 -299.213283) (xy 110.315358 -299.248974)
			(xy 110.351049 -299.290165) (xy 110.380515 -299.336015) (xy 110.403157 -299.385592) (xy 110.418512 -299.437887)
			(xy 110.426268 -299.491835) (xy 110.426754 -299.519086) (xy 110.426291 -299.546456) (xy 110.418474 -299.600636)
			(xy 110.402985 -299.65314) (xy 110.380142 -299.702887) (xy 110.350416 -299.748853) (xy 110.332774 -299.769784)
			(xy 110.33252 -299.770038) (xy 110.326944 -299.777131) (xy 110.320693 -299.794043) (xy 110.320328 -299.803058)
			(xy 110.320328 -299.870114) (xy 110.320672 -299.879132) (xy 110.326928 -299.89605) (xy 110.33252 -299.903134)
			(xy 110.332774 -299.903134) (xy 110.332774 -299.903388) (xy 110.350401 -299.924332) (xy 110.380126 -299.970298)
			(xy 110.402972 -300.020042) (xy 110.41847 -300.072543) (xy 110.4263 -300.12672) (xy 110.426301 -300.181459)
			(xy 110.418474 -300.235637) (xy 110.40298 -300.288138) (xy 110.380136 -300.337884) (xy 110.350414 -300.383851)
			(xy 110.332774 -300.404784) (xy 110.33252 -300.405038) (xy 110.326944 -300.412131) (xy 110.320693 -300.429043)
			(xy 110.320328 -300.438058) (xy 110.320328 -300.505114) (xy 110.320672 -300.514132) (xy 110.326928 -300.53105)
			(xy 110.33252 -300.538134) (xy 110.332774 -300.538134) (xy 110.332774 -300.538388) (xy 110.350401 -300.559332)
			(xy 110.380126 -300.605298) (xy 110.402972 -300.655042) (xy 110.41847 -300.707543) (xy 110.4263 -300.76172)
			(xy 110.426301 -300.816459) (xy 110.418474 -300.870637) (xy 110.40298 -300.923138) (xy 110.380136 -300.972884)
			(xy 110.350414 -301.018851) (xy 110.332774 -301.039784) (xy 110.33252 -301.040038) (xy 110.326944 -301.047131)
			(xy 110.320693 -301.064043) (xy 110.320328 -301.073058) (xy 110.320328 -301.140114) (xy 110.320672 -301.149132)
			(xy 110.326928 -301.16605) (xy 110.33252 -301.173134) (xy 110.332774 -301.173134) (xy 110.332774 -301.173388)
			(xy 110.350417 -301.194317) (xy 110.380129 -301.24029) (xy 110.402965 -301.290039) (xy 110.418455 -301.34254)
			(xy 110.426281 -301.396717) (xy 110.426754 -301.424086) (xy 110.426268 -301.451337) (xy 110.422444 -301.477934)
			(xy 113.295938 -301.477934) (xy 113.296415 -301.450564) (xy 113.304229 -301.396385) (xy 113.319715 -301.343882)
			(xy 113.342554 -301.294135) (xy 113.372277 -301.248168) (xy 113.389918 -301.227236) (xy 113.390172 -301.226982)
			(xy 113.395781 -301.219911) (xy 113.402012 -301.202982) (xy 113.402364 -301.193962) (xy 113.402364 -301.126906)
			(xy 113.402012 -301.117889) (xy 113.395762 -301.100971) (xy 113.390172 -301.093886) (xy 113.389918 -301.093886)
			(xy 113.389918 -301.093632) (xy 113.372311 -301.072672) (xy 113.342586 -301.026709) (xy 113.319739 -300.976967)
			(xy 113.30424 -300.924469) (xy 113.296409 -300.870294) (xy 113.296405 -300.815557) (xy 113.304229 -300.761381)
			(xy 113.319721 -300.708881) (xy 113.342561 -300.659136) (xy 113.37228 -300.613169) (xy 113.389918 -300.592236)
			(xy 113.390172 -300.591982) (xy 113.395781 -300.584911) (xy 113.402012 -300.567982) (xy 113.402364 -300.558962)
			(xy 113.402364 -300.491906) (xy 113.402012 -300.482889) (xy 113.395762 -300.465971) (xy 113.390172 -300.458886)
			(xy 113.389918 -300.458886) (xy 113.389918 -300.458632) (xy 113.372311 -300.437672) (xy 113.342586 -300.391709)
			(xy 113.319739 -300.341967) (xy 113.30424 -300.289469) (xy 113.296409 -300.235294) (xy 113.296405 -300.180557)
			(xy 113.304229 -300.126381) (xy 113.319721 -300.073881) (xy 113.342561 -300.024136) (xy 113.37228 -299.978169)
			(xy 113.389918 -299.957236) (xy 113.390172 -299.956982) (xy 113.395781 -299.949911) (xy 113.402012 -299.932982)
			(xy 113.402364 -299.923962) (xy 113.402364 -299.856906) (xy 113.402012 -299.847889) (xy 113.395762 -299.830971)
			(xy 113.390172 -299.823886) (xy 113.389918 -299.823886) (xy 113.389918 -299.823632) (xy 113.372283 -299.802696)
			(xy 113.34257 -299.756725) (xy 113.319733 -299.706978) (xy 113.304241 -299.654478) (xy 113.296412 -299.600303)
			(xy 113.295938 -299.572934) (xy 113.296424 -299.545683) (xy 113.30418 -299.491735) (xy 113.319535 -299.43944)
			(xy 113.342177 -299.389863) (xy 113.371643 -299.344013) (xy 113.407334 -299.302822) (xy 113.448525 -299.267131)
			(xy 113.494375 -299.237665) (xy 113.543952 -299.215023) (xy 113.596247 -299.199668) (xy 113.650195 -299.191912)
			(xy 113.704697 -299.191912) (xy 113.758645 -299.199668) (xy 113.81094 -299.215023) (xy 113.860517 -299.237665)
			(xy 113.906367 -299.267131) (xy 113.947558 -299.302822) (xy 113.983249 -299.344013) (xy 114.012715 -299.389863)
			(xy 114.035357 -299.43944) (xy 114.050712 -299.491735) (xy 114.058468 -299.545683) (xy 114.058954 -299.572934)
			(xy 114.058519 -299.600305) (xy 114.050695 -299.654486) (xy 114.0352 -299.70699) (xy 114.012351 -299.756737)
			(xy 113.982619 -299.802702) (xy 113.964974 -299.823632) (xy 113.96472 -299.823886) (xy 113.959124 -299.830966)
			(xy 113.952885 -299.847888) (xy 113.952528 -299.856906) (xy 113.952528 -299.923962) (xy 113.952897 -299.932978)
			(xy 113.959136 -299.949895) (xy 113.96472 -299.956982) (xy 113.964974 -299.956982) (xy 113.964974 -299.957236)
			(xy 113.982648 -299.978142) (xy 114.012371 -300.024114) (xy 114.035215 -300.073865) (xy 114.050708 -300.126371)
			(xy 114.058534 -300.180553) (xy 114.05853 -300.235298) (xy 114.050697 -300.289479) (xy 114.035197 -300.341983)
			(xy 114.012347 -300.391731) (xy 113.982617 -300.437699) (xy 113.964974 -300.458632) (xy 113.96472 -300.458886)
			(xy 113.959124 -300.465966) (xy 113.952885 -300.482888) (xy 113.952528 -300.491906) (xy 113.952528 -300.558962)
			(xy 113.952897 -300.567978) (xy 113.959136 -300.584895) (xy 113.96472 -300.591982) (xy 113.964974 -300.591982)
			(xy 113.964974 -300.592236) (xy 113.982648 -300.613142) (xy 114.012371 -300.659114) (xy 114.035215 -300.708865)
			(xy 114.050708 -300.761371) (xy 114.058534 -300.815553) (xy 114.05853 -300.870298) (xy 114.050697 -300.924479)
			(xy 114.035197 -300.976983) (xy 114.012347 -301.026731) (xy 113.982617 -301.072699) (xy 113.964974 -301.093632)
			(xy 113.96472 -301.093886) (xy 113.959124 -301.100966) (xy 113.952885 -301.117888) (xy 113.952528 -301.126906)
			(xy 113.952528 -301.193962) (xy 113.952897 -301.202978) (xy 113.959136 -301.219895) (xy 113.96472 -301.226982)
			(xy 113.964974 -301.226982) (xy 113.964974 -301.227236) (xy 113.982593 -301.248185) (xy 114.012308 -301.294153)
			(xy 114.035149 -301.343896) (xy 114.050644 -301.396393) (xy 114.058478 -301.450566) (xy 114.058954 -301.477934)
			(xy 114.058468 -301.505185) (xy 114.050712 -301.559133) (xy 114.035357 -301.611428) (xy 114.012715 -301.661005)
			(xy 113.983249 -301.706855) (xy 113.947558 -301.748046) (xy 113.906367 -301.783737) (xy 113.860517 -301.813203)
			(xy 113.81094 -301.835845) (xy 113.758645 -301.8512) (xy 113.704697 -301.858956) (xy 113.650195 -301.858956)
			(xy 113.596247 -301.8512) (xy 113.543952 -301.835845) (xy 113.494375 -301.813203) (xy 113.448525 -301.783737)
			(xy 113.407334 -301.748046) (xy 113.371643 -301.706855) (xy 113.342177 -301.661005) (xy 113.319535 -301.611428)
			(xy 113.30418 -301.559133) (xy 113.296424 -301.505185) (xy 113.295938 -301.477934) (xy 110.422444 -301.477934)
			(xy 110.418512 -301.505285) (xy 110.403157 -301.55758) (xy 110.380515 -301.607157) (xy 110.351049 -301.653007)
			(xy 110.315358 -301.694198) (xy 110.274167 -301.729889) (xy 110.228317 -301.759355) (xy 110.17874 -301.781997)
			(xy 110.126445 -301.797352) (xy 110.072497 -301.805108) (xy 110.017995 -301.805108) (xy 109.964047 -301.797352)
			(xy 109.911752 -301.781997) (xy 109.862175 -301.759355) (xy 109.816325 -301.729889) (xy 109.775134 -301.694198)
			(xy 109.739443 -301.653007) (xy 109.709977 -301.607157) (xy 109.687335 -301.55758) (xy 109.67198 -301.505285)
			(xy 109.664224 -301.451337) (xy 109.663738 -301.424086) (xy 107.214428 -301.424086) (xy 107.218257 -301.450566)
			(xy 107.218734 -301.477934) (xy 107.218248 -301.505185) (xy 107.210492 -301.559133) (xy 107.195137 -301.611428)
			(xy 107.172495 -301.661005) (xy 107.143029 -301.706855) (xy 107.107338 -301.748046) (xy 107.066147 -301.783737)
			(xy 107.020297 -301.813203) (xy 106.97072 -301.835845) (xy 106.918425 -301.8512) (xy 106.864477 -301.858956)
			(xy 106.809975 -301.858956) (xy 106.756027 -301.8512) (xy 106.703732 -301.835845) (xy 106.654155 -301.813203)
			(xy 106.608305 -301.783737) (xy 106.567114 -301.748046) (xy 106.531423 -301.706855) (xy 106.501957 -301.661005)
			(xy 106.479315 -301.611428) (xy 106.46396 -301.559133) (xy 106.456204 -301.505185) (xy 106.455718 -301.477934)
			(xy 103.582224 -301.477934) (xy 103.578292 -301.505285) (xy 103.562937 -301.55758) (xy 103.540295 -301.607157)
			(xy 103.510829 -301.653007) (xy 103.475138 -301.694198) (xy 103.433947 -301.729889) (xy 103.388097 -301.759355)
			(xy 103.33852 -301.781997) (xy 103.286225 -301.797352) (xy 103.232277 -301.805108) (xy 103.177775 -301.805108)
			(xy 103.123827 -301.797352) (xy 103.071532 -301.781997) (xy 103.021955 -301.759355) (xy 102.976105 -301.729889)
			(xy 102.934914 -301.694198) (xy 102.899223 -301.653007) (xy 102.869757 -301.607157) (xy 102.847115 -301.55758)
			(xy 102.83176 -301.505285) (xy 102.824004 -301.451337) (xy 102.823518 -301.424086) (xy 100.33 -301.424086)
			(xy 100.33 -302.925734) (xy 102.235508 -302.925734) (xy 102.235992 -302.898364) (xy 102.243805 -302.844186)
			(xy 102.25929 -302.791683) (xy 102.282128 -302.741936) (xy 102.311849 -302.695968) (xy 102.329488 -302.675036)
			(xy 102.329742 -302.674782) (xy 102.335347 -302.667708) (xy 102.341582 -302.650782) (xy 102.341934 -302.641762)
			(xy 102.341934 -302.574706) (xy 102.341567 -302.56569) (xy 102.335325 -302.548774) (xy 102.329742 -302.541686)
			(xy 102.329488 -302.541686) (xy 102.329488 -302.541432) (xy 102.311849 -302.5205) (xy 102.282137 -302.474527)
			(xy 102.259302 -302.42478) (xy 102.24381 -302.372279) (xy 102.235982 -302.318103) (xy 102.235508 -302.290734)
			(xy 102.235994 -302.263483) (xy 102.24375 -302.209535) (xy 102.259105 -302.15724) (xy 102.281747 -302.107663)
			(xy 102.311213 -302.061813) (xy 102.346904 -302.020622) (xy 102.388095 -301.984931) (xy 102.433945 -301.955465)
			(xy 102.483522 -301.932823) (xy 102.535817 -301.917468) (xy 102.589765 -301.909712) (xy 102.644267 -301.909712)
			(xy 102.698215 -301.917468) (xy 102.75051 -301.932823) (xy 102.800087 -301.955465) (xy 102.845937 -301.984931)
			(xy 102.887128 -302.020622) (xy 102.922819 -302.061813) (xy 102.952285 -302.107663) (xy 102.974927 -302.15724)
			(xy 102.990282 -302.209535) (xy 102.998038 -302.263483) (xy 102.998524 -302.290734) (xy 102.998096 -302.318106)
			(xy 102.990272 -302.372287) (xy 102.974775 -302.424792) (xy 102.951924 -302.474538) (xy 102.92219 -302.520502)
			(xy 102.904544 -302.541432) (xy 102.90429 -302.541686) (xy 102.898702 -302.548772) (xy 102.892456 -302.565689)
			(xy 102.892098 -302.574706) (xy 102.892098 -302.641762) (xy 102.892473 -302.650777) (xy 102.898708 -302.667694)
			(xy 102.90429 -302.674782) (xy 102.904544 -302.674782) (xy 102.904544 -302.675036) (xy 102.922174 -302.695975)
			(xy 102.951886 -302.741947) (xy 102.974723 -302.791693) (xy 102.990216 -302.844191) (xy 102.998048 -302.898365)
			(xy 102.998524 -302.925734) (xy 105.655618 -302.925734) (xy 105.6561 -302.898364) (xy 105.663913 -302.844186)
			(xy 105.679398 -302.791683) (xy 105.702237 -302.741935) (xy 105.731958 -302.695968) (xy 105.749598 -302.675036)
			(xy 105.749852 -302.674782) (xy 105.755458 -302.667709) (xy 105.761692 -302.650782) (xy 105.762044 -302.641762)
			(xy 105.762044 -302.574706) (xy 105.761696 -302.565688) (xy 105.755443 -302.54877) (xy 105.749852 -302.541686)
			(xy 105.749598 -302.541686) (xy 105.749598 -302.541432) (xy 105.73196 -302.520499) (xy 105.702248 -302.474526)
			(xy 105.679412 -302.424779) (xy 105.663921 -302.372279) (xy 105.656092 -302.318103) (xy 105.655618 -302.290734)
			(xy 105.656104 -302.263483) (xy 105.66386 -302.209535) (xy 105.679215 -302.15724) (xy 105.701857 -302.107663)
			(xy 105.731323 -302.061813) (xy 105.767014 -302.020622) (xy 105.808205 -301.984931) (xy 105.854055 -301.955465)
			(xy 105.903632 -301.932823) (xy 105.955927 -301.917468) (xy 106.009875 -301.909712) (xy 106.064377 -301.909712)
			(xy 106.118325 -301.917468) (xy 106.17062 -301.932823) (xy 106.220197 -301.955465) (xy 106.266047 -301.984931)
			(xy 106.307238 -302.020622) (xy 106.342929 -302.061813) (xy 106.372395 -302.107663) (xy 106.395037 -302.15724)
			(xy 106.410392 -302.209535) (xy 106.418148 -302.263483) (xy 106.418634 -302.290734) (xy 106.418204 -302.318106)
			(xy 106.41038 -302.372287) (xy 106.394883 -302.424791) (xy 106.372033 -302.474537) (xy 106.3423 -302.520502)
			(xy 106.324654 -302.541432) (xy 106.3244 -302.541686) (xy 106.318813 -302.548772) (xy 106.312567 -302.565689)
			(xy 106.312208 -302.574706) (xy 106.312208 -302.641762) (xy 106.312582 -302.650777) (xy 106.318818 -302.667694)
			(xy 106.3244 -302.674782) (xy 106.324654 -302.674782) (xy 106.324654 -302.675036) (xy 106.342269 -302.695987)
			(xy 106.371986 -302.741954) (xy 106.394828 -302.791697) (xy 106.410324 -302.844193) (xy 106.418157 -302.898366)
			(xy 106.418634 -302.925734) (xy 107.043728 -302.925734) (xy 107.044207 -302.898364) (xy 107.052021 -302.844185)
			(xy 107.067506 -302.791682) (xy 107.090345 -302.741935) (xy 107.120068 -302.695968) (xy 107.137708 -302.675036)
			(xy 107.137962 -302.674782) (xy 107.14357 -302.66771) (xy 107.149802 -302.650782) (xy 107.150154 -302.641762)
			(xy 107.150154 -302.574706) (xy 107.149804 -302.565688) (xy 107.143553 -302.548771) (xy 107.137962 -302.541686)
			(xy 107.137708 -302.541686) (xy 107.137708 -302.541432) (xy 107.120072 -302.520498) (xy 107.090359 -302.474526)
			(xy 107.067523 -302.424779) (xy 107.052031 -302.372278) (xy 107.044202 -302.318103) (xy 107.043728 -302.290734)
			(xy 107.044214 -302.263483) (xy 107.05197 -302.209535) (xy 107.067325 -302.15724) (xy 107.089967 -302.107663)
			(xy 107.119433 -302.061813) (xy 107.155124 -302.020622) (xy 107.196315 -301.984931) (xy 107.242165 -301.955465)
			(xy 107.291742 -301.932823) (xy 107.344037 -301.917468) (xy 107.397985 -301.909712) (xy 107.452487 -301.909712)
			(xy 107.506435 -301.917468) (xy 107.55873 -301.932823) (xy 107.608307 -301.955465) (xy 107.654157 -301.984931)
			(xy 107.695348 -302.020622) (xy 107.731039 -302.061813) (xy 107.760505 -302.107663) (xy 107.783147 -302.15724)
			(xy 107.798502 -302.209535) (xy 107.806258 -302.263483) (xy 107.806744 -302.290734) (xy 107.806312 -302.318106)
			(xy 107.798488 -302.372287) (xy 107.782992 -302.424791) (xy 107.760142 -302.474537) (xy 107.730409 -302.520502)
			(xy 107.712764 -302.541432) (xy 107.71251 -302.541686) (xy 107.706924 -302.548773) (xy 107.700677 -302.565689)
			(xy 107.700318 -302.574706) (xy 107.700318 -302.641762) (xy 107.700689 -302.650777) (xy 107.706927 -302.667695)
			(xy 107.71251 -302.674782) (xy 107.712764 -302.674782) (xy 107.712764 -302.675036) (xy 107.730381 -302.695986)
			(xy 107.760097 -302.741953) (xy 107.782938 -302.791696) (xy 107.798434 -302.844193) (xy 107.806267 -302.898366)
			(xy 107.806744 -302.925734) (xy 109.075728 -302.925734) (xy 109.076207 -302.898364) (xy 109.084021 -302.844185)
			(xy 109.099506 -302.791682) (xy 109.122345 -302.741935) (xy 109.152068 -302.695968) (xy 109.169708 -302.675036)
			(xy 109.169962 -302.674782) (xy 109.17557 -302.66771) (xy 109.181802 -302.650782) (xy 109.182154 -302.641762)
			(xy 109.182154 -302.574706) (xy 109.181804 -302.565688) (xy 109.175553 -302.548771) (xy 109.169962 -302.541686)
			(xy 109.169708 -302.541686) (xy 109.169708 -302.541432) (xy 109.152072 -302.520498) (xy 109.122359 -302.474526)
			(xy 109.099523 -302.424779) (xy 109.084031 -302.372278) (xy 109.076202 -302.318103) (xy 109.075728 -302.290734)
			(xy 109.076214 -302.263483) (xy 109.08397 -302.209535) (xy 109.099325 -302.15724) (xy 109.121967 -302.107663)
			(xy 109.151433 -302.061813) (xy 109.187124 -302.020622) (xy 109.228315 -301.984931) (xy 109.274165 -301.955465)
			(xy 109.323742 -301.932823) (xy 109.376037 -301.917468) (xy 109.429985 -301.909712) (xy 109.484487 -301.909712)
			(xy 109.538435 -301.917468) (xy 109.59073 -301.932823) (xy 109.640307 -301.955465) (xy 109.686157 -301.984931)
			(xy 109.727348 -302.020622) (xy 109.763039 -302.061813) (xy 109.792505 -302.107663) (xy 109.815147 -302.15724)
			(xy 109.830502 -302.209535) (xy 109.838258 -302.263483) (xy 109.838744 -302.290734) (xy 109.838312 -302.318106)
			(xy 109.830488 -302.372287) (xy 109.814992 -302.424791) (xy 109.792142 -302.474537) (xy 109.762409 -302.520502)
			(xy 109.744764 -302.541432) (xy 109.74451 -302.541686) (xy 109.738924 -302.548773) (xy 109.732677 -302.565689)
			(xy 109.732318 -302.574706) (xy 109.732318 -302.641762) (xy 109.732689 -302.650777) (xy 109.738927 -302.667695)
			(xy 109.74451 -302.674782) (xy 109.744764 -302.674782) (xy 109.744764 -302.675036) (xy 109.762381 -302.695986)
			(xy 109.792097 -302.741953) (xy 109.814938 -302.791696) (xy 109.830434 -302.844193) (xy 109.838267 -302.898366)
			(xy 109.838744 -302.925734) (xy 113.883948 -302.925734) (xy 113.884422 -302.898364) (xy 113.892236 -302.844185)
			(xy 113.907723 -302.791681) (xy 113.930563 -302.741934) (xy 113.960287 -302.695967) (xy 113.977928 -302.675036)
			(xy 113.978182 -302.674782) (xy 113.98378 -302.667703) (xy 113.99002 -302.65078) (xy 113.990374 -302.641762)
			(xy 113.990374 -302.574706) (xy 113.99002 -302.565689) (xy 113.983771 -302.548771) (xy 113.978182 -302.541686)
			(xy 113.977928 -302.541686) (xy 113.977928 -302.541432) (xy 113.960295 -302.520495) (xy 113.930581 -302.474524)
			(xy 113.907744 -302.424778) (xy 113.892251 -302.372278) (xy 113.884422 -302.318103) (xy 113.883948 -302.290734)
			(xy 113.884434 -302.263483) (xy 113.89219 -302.209535) (xy 113.907545 -302.15724) (xy 113.930187 -302.107663)
			(xy 113.959653 -302.061813) (xy 113.995344 -302.020622) (xy 114.036535 -301.984931) (xy 114.082385 -301.955465)
			(xy 114.131962 -301.932823) (xy 114.184257 -301.917468) (xy 114.238205 -301.909712) (xy 114.292707 -301.909712)
			(xy 114.346655 -301.917468) (xy 114.39895 -301.932823) (xy 114.448527 -301.955465) (xy 114.494377 -301.984931)
			(xy 114.535568 -302.020622) (xy 114.571259 -302.061813) (xy 114.600725 -302.107663) (xy 114.623367 -302.15724)
			(xy 114.638722 -302.209535) (xy 114.646478 -302.263483) (xy 114.646964 -302.290734) (xy 114.646527 -302.318105)
			(xy 114.638703 -302.372286) (xy 114.623208 -302.42479) (xy 114.60036 -302.474536) (xy 114.570628 -302.520502)
			(xy 114.552984 -302.541432) (xy 114.55273 -302.541686) (xy 114.547135 -302.548766) (xy 114.540895 -302.565688)
			(xy 114.540538 -302.574706) (xy 114.540538 -302.641762) (xy 114.540905 -302.650778) (xy 114.547145 -302.667695)
			(xy 114.55273 -302.674782) (xy 114.552984 -302.674782) (xy 114.552984 -302.675036) (xy 114.570604 -302.695983)
			(xy 114.600319 -302.741952) (xy 114.623159 -302.791695) (xy 114.638655 -302.844193) (xy 114.646488 -302.898366)
			(xy 114.646964 -302.925734) (xy 114.646478 -302.952985) (xy 114.638722 -303.006933) (xy 114.623367 -303.059228)
			(xy 114.600725 -303.108805) (xy 114.579627 -303.141634) (xy 116.784372 -303.141634) (xy 116.788443 -303.086012)
			(xy 116.800569 -303.031575) (xy 116.820492 -302.979484) (xy 116.847788 -302.930849) (xy 116.881874 -302.886706)
			(xy 116.922023 -302.847997) (xy 116.967381 -302.815546) (xy 117.016981 -302.790045) (xy 117.069765 -302.772038)
			(xy 117.124608 -302.761908) (xy 117.180342 -302.759871) (xy 117.235779 -302.765971) (xy 117.289736 -302.780077)
			(xy 117.341065 -302.801889) (xy 117.388671 -302.830943) (xy 117.431539 -302.866618) (xy 117.468756 -302.908155)
			(xy 117.499529 -302.954668) (xy 117.523201 -303.005165) (xy 117.539269 -303.058572) (xy 117.547389 -303.113748)
			(xy 117.547898 -303.141634) (xy 117.547389 -303.16952) (xy 117.539269 -303.224696) (xy 117.523201 -303.278103)
			(xy 117.499529 -303.3286) (xy 117.468756 -303.375113) (xy 117.431539 -303.41665) (xy 117.388671 -303.452325)
			(xy 117.341065 -303.481379) (xy 117.289736 -303.503191) (xy 117.235779 -303.517297) (xy 117.180342 -303.523397)
			(xy 117.124608 -303.52136) (xy 117.069765 -303.51123) (xy 117.016981 -303.493223) (xy 116.967381 -303.467722)
			(xy 116.922023 -303.435271) (xy 116.881874 -303.396562) (xy 116.847788 -303.352419) (xy 116.820492 -303.303784)
			(xy 116.800569 -303.251693) (xy 116.788443 -303.197256) (xy 116.784372 -303.141634) (xy 114.579627 -303.141634)
			(xy 114.571259 -303.154655) (xy 114.535568 -303.195846) (xy 114.494377 -303.231537) (xy 114.448527 -303.261003)
			(xy 114.39895 -303.283645) (xy 114.346655 -303.299) (xy 114.292707 -303.306756) (xy 114.238205 -303.306756)
			(xy 114.184257 -303.299) (xy 114.131962 -303.283645) (xy 114.082385 -303.261003) (xy 114.036535 -303.231537)
			(xy 113.995344 -303.195846) (xy 113.959653 -303.154655) (xy 113.930187 -303.108805) (xy 113.907545 -303.059228)
			(xy 113.89219 -303.006933) (xy 113.884434 -302.952985) (xy 113.883948 -302.925734) (xy 109.838744 -302.925734)
			(xy 109.838258 -302.952985) (xy 109.830502 -303.006933) (xy 109.815147 -303.059228) (xy 109.792505 -303.108805)
			(xy 109.763039 -303.154655) (xy 109.727348 -303.195846) (xy 109.686157 -303.231537) (xy 109.640307 -303.261003)
			(xy 109.59073 -303.283645) (xy 109.538435 -303.299) (xy 109.484487 -303.306756) (xy 109.429985 -303.306756)
			(xy 109.376037 -303.299) (xy 109.323742 -303.283645) (xy 109.274165 -303.261003) (xy 109.228315 -303.231537)
			(xy 109.187124 -303.195846) (xy 109.151433 -303.154655) (xy 109.121967 -303.108805) (xy 109.099325 -303.059228)
			(xy 109.08397 -303.006933) (xy 109.076214 -302.952985) (xy 109.075728 -302.925734) (xy 107.806744 -302.925734)
			(xy 107.806258 -302.952985) (xy 107.798502 -303.006933) (xy 107.783147 -303.059228) (xy 107.760505 -303.108805)
			(xy 107.731039 -303.154655) (xy 107.695348 -303.195846) (xy 107.654157 -303.231537) (xy 107.608307 -303.261003)
			(xy 107.55873 -303.283645) (xy 107.506435 -303.299) (xy 107.452487 -303.306756) (xy 107.397985 -303.306756)
			(xy 107.344037 -303.299) (xy 107.291742 -303.283645) (xy 107.242165 -303.261003) (xy 107.196315 -303.231537)
			(xy 107.155124 -303.195846) (xy 107.119433 -303.154655) (xy 107.089967 -303.108805) (xy 107.067325 -303.059228)
			(xy 107.05197 -303.006933) (xy 107.044214 -302.952985) (xy 107.043728 -302.925734) (xy 106.418634 -302.925734)
			(xy 106.418148 -302.952985) (xy 106.410392 -303.006933) (xy 106.395037 -303.059228) (xy 106.372395 -303.108805)
			(xy 106.342929 -303.154655) (xy 106.307238 -303.195846) (xy 106.266047 -303.231537) (xy 106.220197 -303.261003)
			(xy 106.17062 -303.283645) (xy 106.118325 -303.299) (xy 106.064377 -303.306756) (xy 106.009875 -303.306756)
			(xy 105.955927 -303.299) (xy 105.903632 -303.283645) (xy 105.854055 -303.261003) (xy 105.808205 -303.231537)
			(xy 105.767014 -303.195846) (xy 105.731323 -303.154655) (xy 105.701857 -303.108805) (xy 105.679215 -303.059228)
			(xy 105.66386 -303.006933) (xy 105.656104 -302.952985) (xy 105.655618 -302.925734) (xy 102.998524 -302.925734)
			(xy 102.998038 -302.952985) (xy 102.990282 -303.006933) (xy 102.974927 -303.059228) (xy 102.952285 -303.108805)
			(xy 102.922819 -303.154655) (xy 102.887128 -303.195846) (xy 102.845937 -303.231537) (xy 102.800087 -303.261003)
			(xy 102.75051 -303.283645) (xy 102.698215 -303.299) (xy 102.644267 -303.306756) (xy 102.589765 -303.306756)
			(xy 102.535817 -303.299) (xy 102.483522 -303.283645) (xy 102.433945 -303.261003) (xy 102.388095 -303.231537)
			(xy 102.346904 -303.195846) (xy 102.311213 -303.154655) (xy 102.281747 -303.108805) (xy 102.259105 -303.059228)
			(xy 102.24375 -303.006933) (xy 102.235994 -302.952985) (xy 102.235508 -302.925734) (xy 100.33 -302.925734)
			(xy 100.33 -304.157634) (xy 116.784372 -304.157634) (xy 116.788443 -304.102012) (xy 116.800569 -304.047575)
			(xy 116.820492 -303.995484) (xy 116.847788 -303.946849) (xy 116.881874 -303.902706) (xy 116.922023 -303.863997)
			(xy 116.967381 -303.831546) (xy 117.016981 -303.806045) (xy 117.069765 -303.788038) (xy 117.124608 -303.777908)
			(xy 117.180342 -303.775871) (xy 117.235779 -303.781971) (xy 117.289736 -303.796077) (xy 117.341065 -303.817889)
			(xy 117.388671 -303.846943) (xy 117.431539 -303.882618) (xy 117.468756 -303.924155) (xy 117.499529 -303.970668)
			(xy 117.523201 -304.021165) (xy 117.539269 -304.074572) (xy 117.547389 -304.129748) (xy 117.547898 -304.157634)
			(xy 117.547389 -304.18552) (xy 117.539269 -304.240696) (xy 117.523201 -304.294103) (xy 117.499529 -304.3446)
			(xy 117.468756 -304.391113) (xy 117.431539 -304.43265) (xy 117.388671 -304.468325) (xy 117.341065 -304.497379)
			(xy 117.289736 -304.519191) (xy 117.235779 -304.533297) (xy 117.180342 -304.539397) (xy 117.124608 -304.53736)
			(xy 117.069765 -304.52723) (xy 117.016981 -304.509223) (xy 116.967381 -304.483722) (xy 116.922023 -304.451271)
			(xy 116.881874 -304.412562) (xy 116.847788 -304.368419) (xy 116.820492 -304.319784) (xy 116.800569 -304.267693)
			(xy 116.788443 -304.213256) (xy 116.784372 -304.157634) (xy 100.33 -304.157634) (xy 100.33 -310.242712)
			(xy 100.471984 -310.242712) (xy 100.476055 -310.18709) (xy 100.488181 -310.132653) (xy 100.508104 -310.080562)
			(xy 100.5354 -310.031927) (xy 100.569486 -309.987784) (xy 100.609635 -309.949075) (xy 100.654993 -309.916624)
			(xy 100.704593 -309.891123) (xy 100.757377 -309.873116) (xy 100.81222 -309.862986) (xy 100.867954 -309.860949)
			(xy 100.923391 -309.867049) (xy 100.977348 -309.881155) (xy 101.028677 -309.902967) (xy 101.076283 -309.932021)
			(xy 101.119151 -309.967696) (xy 101.156368 -310.009233) (xy 101.187141 -310.055746) (xy 101.210813 -310.106243)
			(xy 101.226881 -310.15965) (xy 101.235001 -310.214826) (xy 101.23551 -310.242712) (xy 101.487984 -310.242712)
			(xy 101.492055 -310.18709) (xy 101.504181 -310.132653) (xy 101.524104 -310.080562) (xy 101.5514 -310.031927)
			(xy 101.585486 -309.987784) (xy 101.625635 -309.949075) (xy 101.670993 -309.916624) (xy 101.720593 -309.891123)
			(xy 101.773377 -309.873116) (xy 101.82822 -309.862986) (xy 101.883954 -309.860949) (xy 101.939391 -309.867049)
			(xy 101.993348 -309.881155) (xy 102.044677 -309.902967) (xy 102.092283 -309.932021) (xy 102.135151 -309.967696)
			(xy 102.172368 -310.009233) (xy 102.203141 -310.055746) (xy 102.226813 -310.106243) (xy 102.242881 -310.15965)
			(xy 102.251001 -310.214826) (xy 102.25151 -310.242712) (xy 102.503984 -310.242712) (xy 102.508055 -310.18709)
			(xy 102.520181 -310.132653) (xy 102.540104 -310.080562) (xy 102.5674 -310.031927) (xy 102.601486 -309.987784)
			(xy 102.641635 -309.949075) (xy 102.686993 -309.916624) (xy 102.736593 -309.891123) (xy 102.789377 -309.873116)
			(xy 102.84422 -309.862986) (xy 102.899954 -309.860949) (xy 102.955391 -309.867049) (xy 103.009348 -309.881155)
			(xy 103.060677 -309.902967) (xy 103.108283 -309.932021) (xy 103.151151 -309.967696) (xy 103.188368 -310.009233)
			(xy 103.219141 -310.055746) (xy 103.242813 -310.106243) (xy 103.258881 -310.15965) (xy 103.267001 -310.214826)
			(xy 103.26751 -310.242712) (xy 103.519984 -310.242712) (xy 103.524055 -310.18709) (xy 103.536181 -310.132653)
			(xy 103.556104 -310.080562) (xy 103.5834 -310.031927) (xy 103.617486 -309.987784) (xy 103.657635 -309.949075)
			(xy 103.702993 -309.916624) (xy 103.752593 -309.891123) (xy 103.805377 -309.873116) (xy 103.86022 -309.862986)
			(xy 103.915954 -309.860949) (xy 103.971391 -309.867049) (xy 104.025348 -309.881155) (xy 104.076677 -309.902967)
			(xy 104.124283 -309.932021) (xy 104.167151 -309.967696) (xy 104.204368 -310.009233) (xy 104.235141 -310.055746)
			(xy 104.258813 -310.106243) (xy 104.274881 -310.15965) (xy 104.283001 -310.214826) (xy 104.28351 -310.242712)
			(xy 104.535984 -310.242712) (xy 104.540055 -310.18709) (xy 104.552181 -310.132653) (xy 104.572104 -310.080562)
			(xy 104.5994 -310.031927) (xy 104.633486 -309.987784) (xy 104.673635 -309.949075) (xy 104.718993 -309.916624)
			(xy 104.768593 -309.891123) (xy 104.821377 -309.873116) (xy 104.87622 -309.862986) (xy 104.931954 -309.860949)
			(xy 104.987391 -309.867049) (xy 105.041348 -309.881155) (xy 105.092677 -309.902967) (xy 105.140283 -309.932021)
			(xy 105.183151 -309.967696) (xy 105.220368 -310.009233) (xy 105.251141 -310.055746) (xy 105.274813 -310.106243)
			(xy 105.290881 -310.15965) (xy 105.299001 -310.214826) (xy 105.29951 -310.242712) (xy 105.551984 -310.242712)
			(xy 105.556055 -310.18709) (xy 105.568181 -310.132653) (xy 105.588104 -310.080562) (xy 105.6154 -310.031927)
			(xy 105.649486 -309.987784) (xy 105.689635 -309.949075) (xy 105.734993 -309.916624) (xy 105.784593 -309.891123)
			(xy 105.837377 -309.873116) (xy 105.89222 -309.862986) (xy 105.947954 -309.860949) (xy 106.003391 -309.867049)
			(xy 106.057348 -309.881155) (xy 106.108677 -309.902967) (xy 106.156283 -309.932021) (xy 106.199151 -309.967696)
			(xy 106.236368 -310.009233) (xy 106.267141 -310.055746) (xy 106.290813 -310.106243) (xy 106.306881 -310.15965)
			(xy 106.315001 -310.214826) (xy 106.31551 -310.242712) (xy 106.567984 -310.242712) (xy 106.572055 -310.18709)
			(xy 106.584181 -310.132653) (xy 106.604104 -310.080562) (xy 106.6314 -310.031927) (xy 106.665486 -309.987784)
			(xy 106.705635 -309.949075) (xy 106.750993 -309.916624) (xy 106.800593 -309.891123) (xy 106.853377 -309.873116)
			(xy 106.90822 -309.862986) (xy 106.963954 -309.860949) (xy 107.019391 -309.867049) (xy 107.073348 -309.881155)
			(xy 107.124677 -309.902967) (xy 107.172283 -309.932021) (xy 107.215151 -309.967696) (xy 107.252368 -310.009233)
			(xy 107.283141 -310.055746) (xy 107.306813 -310.106243) (xy 107.322881 -310.15965) (xy 107.331001 -310.214826)
			(xy 107.33151 -310.242712) (xy 107.583984 -310.242712) (xy 107.588055 -310.18709) (xy 107.600181 -310.132653)
			(xy 107.620104 -310.080562) (xy 107.6474 -310.031927) (xy 107.681486 -309.987784) (xy 107.721635 -309.949075)
			(xy 107.766993 -309.916624) (xy 107.816593 -309.891123) (xy 107.869377 -309.873116) (xy 107.92422 -309.862986)
			(xy 107.979954 -309.860949) (xy 108.035391 -309.867049) (xy 108.089348 -309.881155) (xy 108.140677 -309.902967)
			(xy 108.188283 -309.932021) (xy 108.231151 -309.967696) (xy 108.268368 -310.009233) (xy 108.299141 -310.055746)
			(xy 108.322813 -310.106243) (xy 108.338881 -310.15965) (xy 108.347001 -310.214826) (xy 108.34751 -310.242712)
			(xy 108.599984 -310.242712) (xy 108.604055 -310.18709) (xy 108.616181 -310.132653) (xy 108.636104 -310.080562)
			(xy 108.6634 -310.031927) (xy 108.697486 -309.987784) (xy 108.737635 -309.949075) (xy 108.782993 -309.916624)
			(xy 108.832593 -309.891123) (xy 108.885377 -309.873116) (xy 108.94022 -309.862986) (xy 108.995954 -309.860949)
			(xy 109.051391 -309.867049) (xy 109.105348 -309.881155) (xy 109.156677 -309.902967) (xy 109.204283 -309.932021)
			(xy 109.247151 -309.967696) (xy 109.284368 -310.009233) (xy 109.315141 -310.055746) (xy 109.338813 -310.106243)
			(xy 109.354881 -310.15965) (xy 109.363001 -310.214826) (xy 109.36351 -310.242712) (xy 109.615984 -310.242712)
			(xy 109.620055 -310.18709) (xy 109.632181 -310.132653) (xy 109.652104 -310.080562) (xy 109.6794 -310.031927)
			(xy 109.713486 -309.987784) (xy 109.753635 -309.949075) (xy 109.798993 -309.916624) (xy 109.848593 -309.891123)
			(xy 109.901377 -309.873116) (xy 109.95622 -309.862986) (xy 110.011954 -309.860949) (xy 110.067391 -309.867049)
			(xy 110.121348 -309.881155) (xy 110.172677 -309.902967) (xy 110.220283 -309.932021) (xy 110.263151 -309.967696)
			(xy 110.300368 -310.009233) (xy 110.331141 -310.055746) (xy 110.354813 -310.106243) (xy 110.370881 -310.15965)
			(xy 110.379001 -310.214826) (xy 110.37951 -310.242712) (xy 110.379001 -310.270598) (xy 110.370881 -310.325774)
			(xy 110.354813 -310.379181) (xy 110.331141 -310.429678) (xy 110.300368 -310.476191) (xy 110.263151 -310.517728)
			(xy 110.220283 -310.553403) (xy 110.172677 -310.582457) (xy 110.121348 -310.604269) (xy 110.067391 -310.618375)
			(xy 110.011954 -310.624475) (xy 109.95622 -310.622438) (xy 109.901377 -310.612308) (xy 109.848593 -310.594301)
			(xy 109.798993 -310.5688) (xy 109.753635 -310.536349) (xy 109.713486 -310.49764) (xy 109.6794 -310.453497)
			(xy 109.652104 -310.404862) (xy 109.632181 -310.352771) (xy 109.620055 -310.298334) (xy 109.615984 -310.242712)
			(xy 109.36351 -310.242712) (xy 109.363001 -310.270598) (xy 109.354881 -310.325774) (xy 109.338813 -310.379181)
			(xy 109.315141 -310.429678) (xy 109.284368 -310.476191) (xy 109.247151 -310.517728) (xy 109.204283 -310.553403)
			(xy 109.156677 -310.582457) (xy 109.105348 -310.604269) (xy 109.051391 -310.618375) (xy 108.995954 -310.624475)
			(xy 108.94022 -310.622438) (xy 108.885377 -310.612308) (xy 108.832593 -310.594301) (xy 108.782993 -310.5688)
			(xy 108.737635 -310.536349) (xy 108.697486 -310.49764) (xy 108.6634 -310.453497) (xy 108.636104 -310.404862)
			(xy 108.616181 -310.352771) (xy 108.604055 -310.298334) (xy 108.599984 -310.242712) (xy 108.34751 -310.242712)
			(xy 108.347001 -310.270598) (xy 108.338881 -310.325774) (xy 108.322813 -310.379181) (xy 108.299141 -310.429678)
			(xy 108.268368 -310.476191) (xy 108.231151 -310.517728) (xy 108.188283 -310.553403) (xy 108.140677 -310.582457)
			(xy 108.089348 -310.604269) (xy 108.035391 -310.618375) (xy 107.979954 -310.624475) (xy 107.92422 -310.622438)
			(xy 107.869377 -310.612308) (xy 107.816593 -310.594301) (xy 107.766993 -310.5688) (xy 107.721635 -310.536349)
			(xy 107.681486 -310.49764) (xy 107.6474 -310.453497) (xy 107.620104 -310.404862) (xy 107.600181 -310.352771)
			(xy 107.588055 -310.298334) (xy 107.583984 -310.242712) (xy 107.33151 -310.242712) (xy 107.331001 -310.270598)
			(xy 107.322881 -310.325774) (xy 107.306813 -310.379181) (xy 107.283141 -310.429678) (xy 107.252368 -310.476191)
			(xy 107.215151 -310.517728) (xy 107.172283 -310.553403) (xy 107.124677 -310.582457) (xy 107.073348 -310.604269)
			(xy 107.019391 -310.618375) (xy 106.963954 -310.624475) (xy 106.90822 -310.622438) (xy 106.853377 -310.612308)
			(xy 106.800593 -310.594301) (xy 106.750993 -310.5688) (xy 106.705635 -310.536349) (xy 106.665486 -310.49764)
			(xy 106.6314 -310.453497) (xy 106.604104 -310.404862) (xy 106.584181 -310.352771) (xy 106.572055 -310.298334)
			(xy 106.567984 -310.242712) (xy 106.31551 -310.242712) (xy 106.315001 -310.270598) (xy 106.306881 -310.325774)
			(xy 106.290813 -310.379181) (xy 106.267141 -310.429678) (xy 106.236368 -310.476191) (xy 106.199151 -310.517728)
			(xy 106.156283 -310.553403) (xy 106.108677 -310.582457) (xy 106.057348 -310.604269) (xy 106.003391 -310.618375)
			(xy 105.947954 -310.624475) (xy 105.89222 -310.622438) (xy 105.837377 -310.612308) (xy 105.784593 -310.594301)
			(xy 105.734993 -310.5688) (xy 105.689635 -310.536349) (xy 105.649486 -310.49764) (xy 105.6154 -310.453497)
			(xy 105.588104 -310.404862) (xy 105.568181 -310.352771) (xy 105.556055 -310.298334) (xy 105.551984 -310.242712)
			(xy 105.29951 -310.242712) (xy 105.299001 -310.270598) (xy 105.290881 -310.325774) (xy 105.274813 -310.379181)
			(xy 105.251141 -310.429678) (xy 105.220368 -310.476191) (xy 105.183151 -310.517728) (xy 105.140283 -310.553403)
			(xy 105.092677 -310.582457) (xy 105.041348 -310.604269) (xy 104.987391 -310.618375) (xy 104.931954 -310.624475)
			(xy 104.87622 -310.622438) (xy 104.821377 -310.612308) (xy 104.768593 -310.594301) (xy 104.718993 -310.5688)
			(xy 104.673635 -310.536349) (xy 104.633486 -310.49764) (xy 104.5994 -310.453497) (xy 104.572104 -310.404862)
			(xy 104.552181 -310.352771) (xy 104.540055 -310.298334) (xy 104.535984 -310.242712) (xy 104.28351 -310.242712)
			(xy 104.283001 -310.270598) (xy 104.274881 -310.325774) (xy 104.258813 -310.379181) (xy 104.235141 -310.429678)
			(xy 104.204368 -310.476191) (xy 104.167151 -310.517728) (xy 104.124283 -310.553403) (xy 104.076677 -310.582457)
			(xy 104.025348 -310.604269) (xy 103.971391 -310.618375) (xy 103.915954 -310.624475) (xy 103.86022 -310.622438)
			(xy 103.805377 -310.612308) (xy 103.752593 -310.594301) (xy 103.702993 -310.5688) (xy 103.657635 -310.536349)
			(xy 103.617486 -310.49764) (xy 103.5834 -310.453497) (xy 103.556104 -310.404862) (xy 103.536181 -310.352771)
			(xy 103.524055 -310.298334) (xy 103.519984 -310.242712) (xy 103.26751 -310.242712) (xy 103.267001 -310.270598)
			(xy 103.258881 -310.325774) (xy 103.242813 -310.379181) (xy 103.219141 -310.429678) (xy 103.188368 -310.476191)
			(xy 103.151151 -310.517728) (xy 103.108283 -310.553403) (xy 103.060677 -310.582457) (xy 103.009348 -310.604269)
			(xy 102.955391 -310.618375) (xy 102.899954 -310.624475) (xy 102.84422 -310.622438) (xy 102.789377 -310.612308)
			(xy 102.736593 -310.594301) (xy 102.686993 -310.5688) (xy 102.641635 -310.536349) (xy 102.601486 -310.49764)
			(xy 102.5674 -310.453497) (xy 102.540104 -310.404862) (xy 102.520181 -310.352771) (xy 102.508055 -310.298334)
			(xy 102.503984 -310.242712) (xy 102.25151 -310.242712) (xy 102.251001 -310.270598) (xy 102.242881 -310.325774)
			(xy 102.226813 -310.379181) (xy 102.203141 -310.429678) (xy 102.172368 -310.476191) (xy 102.135151 -310.517728)
			(xy 102.092283 -310.553403) (xy 102.044677 -310.582457) (xy 101.993348 -310.604269) (xy 101.939391 -310.618375)
			(xy 101.883954 -310.624475) (xy 101.82822 -310.622438) (xy 101.773377 -310.612308) (xy 101.720593 -310.594301)
			(xy 101.670993 -310.5688) (xy 101.625635 -310.536349) (xy 101.585486 -310.49764) (xy 101.5514 -310.453497)
			(xy 101.524104 -310.404862) (xy 101.504181 -310.352771) (xy 101.492055 -310.298334) (xy 101.487984 -310.242712)
			(xy 101.23551 -310.242712) (xy 101.235001 -310.270598) (xy 101.226881 -310.325774) (xy 101.210813 -310.379181)
			(xy 101.187141 -310.429678) (xy 101.156368 -310.476191) (xy 101.119151 -310.517728) (xy 101.076283 -310.553403)
			(xy 101.028677 -310.582457) (xy 100.977348 -310.604269) (xy 100.923391 -310.618375) (xy 100.867954 -310.624475)
			(xy 100.81222 -310.622438) (xy 100.757377 -310.612308) (xy 100.704593 -310.594301) (xy 100.654993 -310.5688)
			(xy 100.609635 -310.536349) (xy 100.569486 -310.49764) (xy 100.5354 -310.453497) (xy 100.508104 -310.404862)
			(xy 100.488181 -310.352771) (xy 100.476055 -310.298334) (xy 100.471984 -310.242712) (xy 100.33 -310.242712)
			(xy 100.33 -311.258712) (xy 100.471984 -311.258712) (xy 100.476055 -311.20309) (xy 100.488181 -311.148653)
			(xy 100.508104 -311.096562) (xy 100.5354 -311.047927) (xy 100.569486 -311.003784) (xy 100.609635 -310.965075)
			(xy 100.654993 -310.932624) (xy 100.704593 -310.907123) (xy 100.757377 -310.889116) (xy 100.81222 -310.878986)
			(xy 100.867954 -310.876949) (xy 100.923391 -310.883049) (xy 100.977348 -310.897155) (xy 101.028677 -310.918967)
			(xy 101.076283 -310.948021) (xy 101.119151 -310.983696) (xy 101.156368 -311.025233) (xy 101.187141 -311.071746)
			(xy 101.210813 -311.122243) (xy 101.226881 -311.17565) (xy 101.235001 -311.230826) (xy 101.23551 -311.258712)
			(xy 101.487984 -311.258712) (xy 101.492055 -311.20309) (xy 101.504181 -311.148653) (xy 101.524104 -311.096562)
			(xy 101.5514 -311.047927) (xy 101.585486 -311.003784) (xy 101.625635 -310.965075) (xy 101.670993 -310.932624)
			(xy 101.720593 -310.907123) (xy 101.773377 -310.889116) (xy 101.82822 -310.878986) (xy 101.883954 -310.876949)
			(xy 101.939391 -310.883049) (xy 101.993348 -310.897155) (xy 102.044677 -310.918967) (xy 102.092283 -310.948021)
			(xy 102.135151 -310.983696) (xy 102.172368 -311.025233) (xy 102.203141 -311.071746) (xy 102.226813 -311.122243)
			(xy 102.242881 -311.17565) (xy 102.251001 -311.230826) (xy 102.25151 -311.258712) (xy 102.503984 -311.258712)
			(xy 102.508055 -311.20309) (xy 102.520181 -311.148653) (xy 102.540104 -311.096562) (xy 102.5674 -311.047927)
			(xy 102.601486 -311.003784) (xy 102.641635 -310.965075) (xy 102.686993 -310.932624) (xy 102.736593 -310.907123)
			(xy 102.789377 -310.889116) (xy 102.84422 -310.878986) (xy 102.899954 -310.876949) (xy 102.955391 -310.883049)
			(xy 103.009348 -310.897155) (xy 103.060677 -310.918967) (xy 103.108283 -310.948021) (xy 103.151151 -310.983696)
			(xy 103.188368 -311.025233) (xy 103.219141 -311.071746) (xy 103.242813 -311.122243) (xy 103.258881 -311.17565)
			(xy 103.267001 -311.230826) (xy 103.26751 -311.258712) (xy 103.519984 -311.258712) (xy 103.524055 -311.20309)
			(xy 103.536181 -311.148653) (xy 103.556104 -311.096562) (xy 103.5834 -311.047927) (xy 103.617486 -311.003784)
			(xy 103.657635 -310.965075) (xy 103.702993 -310.932624) (xy 103.752593 -310.907123) (xy 103.805377 -310.889116)
			(xy 103.86022 -310.878986) (xy 103.915954 -310.876949) (xy 103.971391 -310.883049) (xy 104.025348 -310.897155)
			(xy 104.076677 -310.918967) (xy 104.124283 -310.948021) (xy 104.167151 -310.983696) (xy 104.204368 -311.025233)
			(xy 104.235141 -311.071746) (xy 104.258813 -311.122243) (xy 104.274881 -311.17565) (xy 104.283001 -311.230826)
			(xy 104.28351 -311.258712) (xy 104.535984 -311.258712) (xy 104.540055 -311.20309) (xy 104.552181 -311.148653)
			(xy 104.572104 -311.096562) (xy 104.5994 -311.047927) (xy 104.633486 -311.003784) (xy 104.673635 -310.965075)
			(xy 104.718993 -310.932624) (xy 104.768593 -310.907123) (xy 104.821377 -310.889116) (xy 104.87622 -310.878986)
			(xy 104.931954 -310.876949) (xy 104.987391 -310.883049) (xy 105.041348 -310.897155) (xy 105.092677 -310.918967)
			(xy 105.140283 -310.948021) (xy 105.183151 -310.983696) (xy 105.220368 -311.025233) (xy 105.251141 -311.071746)
			(xy 105.274813 -311.122243) (xy 105.290881 -311.17565) (xy 105.299001 -311.230826) (xy 105.29951 -311.258712)
			(xy 105.551984 -311.258712) (xy 105.556055 -311.20309) (xy 105.568181 -311.148653) (xy 105.588104 -311.096562)
			(xy 105.6154 -311.047927) (xy 105.649486 -311.003784) (xy 105.689635 -310.965075) (xy 105.734993 -310.932624)
			(xy 105.784593 -310.907123) (xy 105.837377 -310.889116) (xy 105.89222 -310.878986) (xy 105.947954 -310.876949)
			(xy 106.003391 -310.883049) (xy 106.057348 -310.897155) (xy 106.108677 -310.918967) (xy 106.156283 -310.948021)
			(xy 106.199151 -310.983696) (xy 106.236368 -311.025233) (xy 106.267141 -311.071746) (xy 106.290813 -311.122243)
			(xy 106.306881 -311.17565) (xy 106.315001 -311.230826) (xy 106.31551 -311.258712) (xy 106.567984 -311.258712)
			(xy 106.572055 -311.20309) (xy 106.584181 -311.148653) (xy 106.604104 -311.096562) (xy 106.6314 -311.047927)
			(xy 106.665486 -311.003784) (xy 106.705635 -310.965075) (xy 106.750993 -310.932624) (xy 106.800593 -310.907123)
			(xy 106.853377 -310.889116) (xy 106.90822 -310.878986) (xy 106.963954 -310.876949) (xy 107.019391 -310.883049)
			(xy 107.073348 -310.897155) (xy 107.124677 -310.918967) (xy 107.172283 -310.948021) (xy 107.215151 -310.983696)
			(xy 107.252368 -311.025233) (xy 107.283141 -311.071746) (xy 107.306813 -311.122243) (xy 107.322881 -311.17565)
			(xy 107.331001 -311.230826) (xy 107.33151 -311.258712) (xy 107.583984 -311.258712) (xy 107.588055 -311.20309)
			(xy 107.600181 -311.148653) (xy 107.620104 -311.096562) (xy 107.6474 -311.047927) (xy 107.681486 -311.003784)
			(xy 107.721635 -310.965075) (xy 107.766993 -310.932624) (xy 107.816593 -310.907123) (xy 107.869377 -310.889116)
			(xy 107.92422 -310.878986) (xy 107.979954 -310.876949) (xy 108.035391 -310.883049) (xy 108.089348 -310.897155)
			(xy 108.140677 -310.918967) (xy 108.188283 -310.948021) (xy 108.231151 -310.983696) (xy 108.268368 -311.025233)
			(xy 108.299141 -311.071746) (xy 108.322813 -311.122243) (xy 108.338881 -311.17565) (xy 108.347001 -311.230826)
			(xy 108.34751 -311.258712) (xy 108.599984 -311.258712) (xy 108.604055 -311.20309) (xy 108.616181 -311.148653)
			(xy 108.636104 -311.096562) (xy 108.6634 -311.047927) (xy 108.697486 -311.003784) (xy 108.737635 -310.965075)
			(xy 108.782993 -310.932624) (xy 108.832593 -310.907123) (xy 108.885377 -310.889116) (xy 108.94022 -310.878986)
			(xy 108.995954 -310.876949) (xy 109.051391 -310.883049) (xy 109.105348 -310.897155) (xy 109.156677 -310.918967)
			(xy 109.204283 -310.948021) (xy 109.247151 -310.983696) (xy 109.284368 -311.025233) (xy 109.315141 -311.071746)
			(xy 109.338813 -311.122243) (xy 109.354881 -311.17565) (xy 109.363001 -311.230826) (xy 109.36351 -311.258712)
			(xy 109.615984 -311.258712) (xy 109.620055 -311.20309) (xy 109.632181 -311.148653) (xy 109.652104 -311.096562)
			(xy 109.6794 -311.047927) (xy 109.713486 -311.003784) (xy 109.753635 -310.965075) (xy 109.798993 -310.932624)
			(xy 109.848593 -310.907123) (xy 109.901377 -310.889116) (xy 109.95622 -310.878986) (xy 110.011954 -310.876949)
			(xy 110.067391 -310.883049) (xy 110.121348 -310.897155) (xy 110.172677 -310.918967) (xy 110.220283 -310.948021)
			(xy 110.263151 -310.983696) (xy 110.300368 -311.025233) (xy 110.331141 -311.071746) (xy 110.354813 -311.122243)
			(xy 110.370881 -311.17565) (xy 110.379001 -311.230826) (xy 110.37951 -311.258712) (xy 110.379001 -311.286598)
			(xy 110.370881 -311.341774) (xy 110.354813 -311.395181) (xy 110.331141 -311.445678) (xy 110.300368 -311.492191)
			(xy 110.263151 -311.533728) (xy 110.220283 -311.569403) (xy 110.172677 -311.598457) (xy 110.121348 -311.620269)
			(xy 110.067391 -311.634375) (xy 110.011954 -311.640475) (xy 109.95622 -311.638438) (xy 109.901377 -311.628308)
			(xy 109.848593 -311.610301) (xy 109.798993 -311.5848) (xy 109.753635 -311.552349) (xy 109.713486 -311.51364)
			(xy 109.6794 -311.469497) (xy 109.652104 -311.420862) (xy 109.632181 -311.368771) (xy 109.620055 -311.314334)
			(xy 109.615984 -311.258712) (xy 109.36351 -311.258712) (xy 109.363001 -311.286598) (xy 109.354881 -311.341774)
			(xy 109.338813 -311.395181) (xy 109.315141 -311.445678) (xy 109.284368 -311.492191) (xy 109.247151 -311.533728)
			(xy 109.204283 -311.569403) (xy 109.156677 -311.598457) (xy 109.105348 -311.620269) (xy 109.051391 -311.634375)
			(xy 108.995954 -311.640475) (xy 108.94022 -311.638438) (xy 108.885377 -311.628308) (xy 108.832593 -311.610301)
			(xy 108.782993 -311.5848) (xy 108.737635 -311.552349) (xy 108.697486 -311.51364) (xy 108.6634 -311.469497)
			(xy 108.636104 -311.420862) (xy 108.616181 -311.368771) (xy 108.604055 -311.314334) (xy 108.599984 -311.258712)
			(xy 108.34751 -311.258712) (xy 108.347001 -311.286598) (xy 108.338881 -311.341774) (xy 108.322813 -311.395181)
			(xy 108.299141 -311.445678) (xy 108.268368 -311.492191) (xy 108.231151 -311.533728) (xy 108.188283 -311.569403)
			(xy 108.140677 -311.598457) (xy 108.089348 -311.620269) (xy 108.035391 -311.634375) (xy 107.979954 -311.640475)
			(xy 107.92422 -311.638438) (xy 107.869377 -311.628308) (xy 107.816593 -311.610301) (xy 107.766993 -311.5848)
			(xy 107.721635 -311.552349) (xy 107.681486 -311.51364) (xy 107.6474 -311.469497) (xy 107.620104 -311.420862)
			(xy 107.600181 -311.368771) (xy 107.588055 -311.314334) (xy 107.583984 -311.258712) (xy 107.33151 -311.258712)
			(xy 107.331001 -311.286598) (xy 107.322881 -311.341774) (xy 107.306813 -311.395181) (xy 107.283141 -311.445678)
			(xy 107.252368 -311.492191) (xy 107.215151 -311.533728) (xy 107.172283 -311.569403) (xy 107.124677 -311.598457)
			(xy 107.073348 -311.620269) (xy 107.019391 -311.634375) (xy 106.963954 -311.640475) (xy 106.90822 -311.638438)
			(xy 106.853377 -311.628308) (xy 106.800593 -311.610301) (xy 106.750993 -311.5848) (xy 106.705635 -311.552349)
			(xy 106.665486 -311.51364) (xy 106.6314 -311.469497) (xy 106.604104 -311.420862) (xy 106.584181 -311.368771)
			(xy 106.572055 -311.314334) (xy 106.567984 -311.258712) (xy 106.31551 -311.258712) (xy 106.315001 -311.286598)
			(xy 106.306881 -311.341774) (xy 106.290813 -311.395181) (xy 106.267141 -311.445678) (xy 106.236368 -311.492191)
			(xy 106.199151 -311.533728) (xy 106.156283 -311.569403) (xy 106.108677 -311.598457) (xy 106.057348 -311.620269)
			(xy 106.003391 -311.634375) (xy 105.947954 -311.640475) (xy 105.89222 -311.638438) (xy 105.837377 -311.628308)
			(xy 105.784593 -311.610301) (xy 105.734993 -311.5848) (xy 105.689635 -311.552349) (xy 105.649486 -311.51364)
			(xy 105.6154 -311.469497) (xy 105.588104 -311.420862) (xy 105.568181 -311.368771) (xy 105.556055 -311.314334)
			(xy 105.551984 -311.258712) (xy 105.29951 -311.258712) (xy 105.299001 -311.286598) (xy 105.290881 -311.341774)
			(xy 105.274813 -311.395181) (xy 105.251141 -311.445678) (xy 105.220368 -311.492191) (xy 105.183151 -311.533728)
			(xy 105.140283 -311.569403) (xy 105.092677 -311.598457) (xy 105.041348 -311.620269) (xy 104.987391 -311.634375)
			(xy 104.931954 -311.640475) (xy 104.87622 -311.638438) (xy 104.821377 -311.628308) (xy 104.768593 -311.610301)
			(xy 104.718993 -311.5848) (xy 104.673635 -311.552349) (xy 104.633486 -311.51364) (xy 104.5994 -311.469497)
			(xy 104.572104 -311.420862) (xy 104.552181 -311.368771) (xy 104.540055 -311.314334) (xy 104.535984 -311.258712)
			(xy 104.28351 -311.258712) (xy 104.283001 -311.286598) (xy 104.274881 -311.341774) (xy 104.258813 -311.395181)
			(xy 104.235141 -311.445678) (xy 104.204368 -311.492191) (xy 104.167151 -311.533728) (xy 104.124283 -311.569403)
			(xy 104.076677 -311.598457) (xy 104.025348 -311.620269) (xy 103.971391 -311.634375) (xy 103.915954 -311.640475)
			(xy 103.86022 -311.638438) (xy 103.805377 -311.628308) (xy 103.752593 -311.610301) (xy 103.702993 -311.5848)
			(xy 103.657635 -311.552349) (xy 103.617486 -311.51364) (xy 103.5834 -311.469497) (xy 103.556104 -311.420862)
			(xy 103.536181 -311.368771) (xy 103.524055 -311.314334) (xy 103.519984 -311.258712) (xy 103.26751 -311.258712)
			(xy 103.267001 -311.286598) (xy 103.258881 -311.341774) (xy 103.242813 -311.395181) (xy 103.219141 -311.445678)
			(xy 103.188368 -311.492191) (xy 103.151151 -311.533728) (xy 103.108283 -311.569403) (xy 103.060677 -311.598457)
			(xy 103.009348 -311.620269) (xy 102.955391 -311.634375) (xy 102.899954 -311.640475) (xy 102.84422 -311.638438)
			(xy 102.789377 -311.628308) (xy 102.736593 -311.610301) (xy 102.686993 -311.5848) (xy 102.641635 -311.552349)
			(xy 102.601486 -311.51364) (xy 102.5674 -311.469497) (xy 102.540104 -311.420862) (xy 102.520181 -311.368771)
			(xy 102.508055 -311.314334) (xy 102.503984 -311.258712) (xy 102.25151 -311.258712) (xy 102.251001 -311.286598)
			(xy 102.242881 -311.341774) (xy 102.226813 -311.395181) (xy 102.203141 -311.445678) (xy 102.172368 -311.492191)
			(xy 102.135151 -311.533728) (xy 102.092283 -311.569403) (xy 102.044677 -311.598457) (xy 101.993348 -311.620269)
			(xy 101.939391 -311.634375) (xy 101.883954 -311.640475) (xy 101.82822 -311.638438) (xy 101.773377 -311.628308)
			(xy 101.720593 -311.610301) (xy 101.670993 -311.5848) (xy 101.625635 -311.552349) (xy 101.585486 -311.51364)
			(xy 101.5514 -311.469497) (xy 101.524104 -311.420862) (xy 101.504181 -311.368771) (xy 101.492055 -311.314334)
			(xy 101.487984 -311.258712) (xy 101.23551 -311.258712) (xy 101.235001 -311.286598) (xy 101.226881 -311.341774)
			(xy 101.210813 -311.395181) (xy 101.187141 -311.445678) (xy 101.156368 -311.492191) (xy 101.119151 -311.533728)
			(xy 101.076283 -311.569403) (xy 101.028677 -311.598457) (xy 100.977348 -311.620269) (xy 100.923391 -311.634375)
			(xy 100.867954 -311.640475) (xy 100.81222 -311.638438) (xy 100.757377 -311.628308) (xy 100.704593 -311.610301)
			(xy 100.654993 -311.5848) (xy 100.609635 -311.552349) (xy 100.569486 -311.51364) (xy 100.5354 -311.469497)
			(xy 100.508104 -311.420862) (xy 100.488181 -311.368771) (xy 100.476055 -311.314334) (xy 100.471984 -311.258712)
			(xy 100.33 -311.258712) (xy 100.33 -312.274712) (xy 100.471984 -312.274712) (xy 100.476055 -312.21909)
			(xy 100.488181 -312.164653) (xy 100.508104 -312.112562) (xy 100.5354 -312.063927) (xy 100.569486 -312.019784)
			(xy 100.609635 -311.981075) (xy 100.654993 -311.948624) (xy 100.704593 -311.923123) (xy 100.757377 -311.905116)
			(xy 100.81222 -311.894986) (xy 100.867954 -311.892949) (xy 100.923391 -311.899049) (xy 100.977348 -311.913155)
			(xy 101.028677 -311.934967) (xy 101.076283 -311.964021) (xy 101.119151 -311.999696) (xy 101.156368 -312.041233)
			(xy 101.187141 -312.087746) (xy 101.210813 -312.138243) (xy 101.226881 -312.19165) (xy 101.235001 -312.246826)
			(xy 101.23551 -312.274712) (xy 101.487984 -312.274712) (xy 101.492055 -312.21909) (xy 101.504181 -312.164653)
			(xy 101.524104 -312.112562) (xy 101.5514 -312.063927) (xy 101.585486 -312.019784) (xy 101.625635 -311.981075)
			(xy 101.670993 -311.948624) (xy 101.720593 -311.923123) (xy 101.773377 -311.905116) (xy 101.82822 -311.894986)
			(xy 101.883954 -311.892949) (xy 101.939391 -311.899049) (xy 101.993348 -311.913155) (xy 102.044677 -311.934967)
			(xy 102.092283 -311.964021) (xy 102.135151 -311.999696) (xy 102.172368 -312.041233) (xy 102.203141 -312.087746)
			(xy 102.226813 -312.138243) (xy 102.242881 -312.19165) (xy 102.251001 -312.246826) (xy 102.25151 -312.274712)
			(xy 102.503984 -312.274712) (xy 102.508055 -312.21909) (xy 102.520181 -312.164653) (xy 102.540104 -312.112562)
			(xy 102.5674 -312.063927) (xy 102.601486 -312.019784) (xy 102.641635 -311.981075) (xy 102.686993 -311.948624)
			(xy 102.736593 -311.923123) (xy 102.789377 -311.905116) (xy 102.84422 -311.894986) (xy 102.899954 -311.892949)
			(xy 102.955391 -311.899049) (xy 103.009348 -311.913155) (xy 103.060677 -311.934967) (xy 103.108283 -311.964021)
			(xy 103.151151 -311.999696) (xy 103.188368 -312.041233) (xy 103.219141 -312.087746) (xy 103.242813 -312.138243)
			(xy 103.258881 -312.19165) (xy 103.267001 -312.246826) (xy 103.26751 -312.274712) (xy 103.519984 -312.274712)
			(xy 103.524055 -312.21909) (xy 103.536181 -312.164653) (xy 103.556104 -312.112562) (xy 103.5834 -312.063927)
			(xy 103.617486 -312.019784) (xy 103.657635 -311.981075) (xy 103.702993 -311.948624) (xy 103.752593 -311.923123)
			(xy 103.805377 -311.905116) (xy 103.86022 -311.894986) (xy 103.915954 -311.892949) (xy 103.971391 -311.899049)
			(xy 104.025348 -311.913155) (xy 104.076677 -311.934967) (xy 104.124283 -311.964021) (xy 104.167151 -311.999696)
			(xy 104.204368 -312.041233) (xy 104.235141 -312.087746) (xy 104.258813 -312.138243) (xy 104.274881 -312.19165)
			(xy 104.283001 -312.246826) (xy 104.28351 -312.274712) (xy 104.535984 -312.274712) (xy 104.540055 -312.21909)
			(xy 104.552181 -312.164653) (xy 104.572104 -312.112562) (xy 104.5994 -312.063927) (xy 104.633486 -312.019784)
			(xy 104.673635 -311.981075) (xy 104.718993 -311.948624) (xy 104.768593 -311.923123) (xy 104.821377 -311.905116)
			(xy 104.87622 -311.894986) (xy 104.931954 -311.892949) (xy 104.987391 -311.899049) (xy 105.041348 -311.913155)
			(xy 105.092677 -311.934967) (xy 105.140283 -311.964021) (xy 105.183151 -311.999696) (xy 105.220368 -312.041233)
			(xy 105.251141 -312.087746) (xy 105.274813 -312.138243) (xy 105.290881 -312.19165) (xy 105.299001 -312.246826)
			(xy 105.29951 -312.274712) (xy 105.551984 -312.274712) (xy 105.556055 -312.21909) (xy 105.568181 -312.164653)
			(xy 105.588104 -312.112562) (xy 105.6154 -312.063927) (xy 105.649486 -312.019784) (xy 105.689635 -311.981075)
			(xy 105.734993 -311.948624) (xy 105.784593 -311.923123) (xy 105.837377 -311.905116) (xy 105.89222 -311.894986)
			(xy 105.947954 -311.892949) (xy 106.003391 -311.899049) (xy 106.057348 -311.913155) (xy 106.108677 -311.934967)
			(xy 106.156283 -311.964021) (xy 106.199151 -311.999696) (xy 106.236368 -312.041233) (xy 106.267141 -312.087746)
			(xy 106.290813 -312.138243) (xy 106.306881 -312.19165) (xy 106.315001 -312.246826) (xy 106.31551 -312.274712)
			(xy 106.567984 -312.274712) (xy 106.572055 -312.21909) (xy 106.584181 -312.164653) (xy 106.604104 -312.112562)
			(xy 106.6314 -312.063927) (xy 106.665486 -312.019784) (xy 106.705635 -311.981075) (xy 106.750993 -311.948624)
			(xy 106.800593 -311.923123) (xy 106.853377 -311.905116) (xy 106.90822 -311.894986) (xy 106.963954 -311.892949)
			(xy 107.019391 -311.899049) (xy 107.073348 -311.913155) (xy 107.124677 -311.934967) (xy 107.172283 -311.964021)
			(xy 107.215151 -311.999696) (xy 107.252368 -312.041233) (xy 107.283141 -312.087746) (xy 107.306813 -312.138243)
			(xy 107.322881 -312.19165) (xy 107.331001 -312.246826) (xy 107.33151 -312.274712) (xy 107.583984 -312.274712)
			(xy 107.588055 -312.21909) (xy 107.600181 -312.164653) (xy 107.620104 -312.112562) (xy 107.6474 -312.063927)
			(xy 107.681486 -312.019784) (xy 107.721635 -311.981075) (xy 107.766993 -311.948624) (xy 107.816593 -311.923123)
			(xy 107.869377 -311.905116) (xy 107.92422 -311.894986) (xy 107.979954 -311.892949) (xy 108.035391 -311.899049)
			(xy 108.089348 -311.913155) (xy 108.140677 -311.934967) (xy 108.188283 -311.964021) (xy 108.231151 -311.999696)
			(xy 108.268368 -312.041233) (xy 108.299141 -312.087746) (xy 108.322813 -312.138243) (xy 108.338881 -312.19165)
			(xy 108.347001 -312.246826) (xy 108.34751 -312.274712) (xy 108.599984 -312.274712) (xy 108.604055 -312.21909)
			(xy 108.616181 -312.164653) (xy 108.636104 -312.112562) (xy 108.6634 -312.063927) (xy 108.697486 -312.019784)
			(xy 108.737635 -311.981075) (xy 108.782993 -311.948624) (xy 108.832593 -311.923123) (xy 108.885377 -311.905116)
			(xy 108.94022 -311.894986) (xy 108.995954 -311.892949) (xy 109.051391 -311.899049) (xy 109.105348 -311.913155)
			(xy 109.156677 -311.934967) (xy 109.204283 -311.964021) (xy 109.247151 -311.999696) (xy 109.284368 -312.041233)
			(xy 109.315141 -312.087746) (xy 109.338813 -312.138243) (xy 109.354881 -312.19165) (xy 109.363001 -312.246826)
			(xy 109.36351 -312.274712) (xy 109.615984 -312.274712) (xy 109.620055 -312.21909) (xy 109.632181 -312.164653)
			(xy 109.652104 -312.112562) (xy 109.6794 -312.063927) (xy 109.713486 -312.019784) (xy 109.753635 -311.981075)
			(xy 109.798993 -311.948624) (xy 109.848593 -311.923123) (xy 109.901377 -311.905116) (xy 109.95622 -311.894986)
			(xy 110.011954 -311.892949) (xy 110.067391 -311.899049) (xy 110.121348 -311.913155) (xy 110.172677 -311.934967)
			(xy 110.220283 -311.964021) (xy 110.263151 -311.999696) (xy 110.300368 -312.041233) (xy 110.331141 -312.087746)
			(xy 110.354813 -312.138243) (xy 110.370881 -312.19165) (xy 110.379001 -312.246826) (xy 110.37951 -312.274712)
			(xy 110.379001 -312.302598) (xy 110.370881 -312.357774) (xy 110.354813 -312.411181) (xy 110.331141 -312.461678)
			(xy 110.300368 -312.508191) (xy 110.263151 -312.549728) (xy 110.220283 -312.585403) (xy 110.172677 -312.614457)
			(xy 110.121348 -312.636269) (xy 110.067391 -312.650375) (xy 110.011954 -312.656475) (xy 109.95622 -312.654438)
			(xy 109.901377 -312.644308) (xy 109.848593 -312.626301) (xy 109.798993 -312.6008) (xy 109.753635 -312.568349)
			(xy 109.713486 -312.52964) (xy 109.6794 -312.485497) (xy 109.652104 -312.436862) (xy 109.632181 -312.384771)
			(xy 109.620055 -312.330334) (xy 109.615984 -312.274712) (xy 109.36351 -312.274712) (xy 109.363001 -312.302598)
			(xy 109.354881 -312.357774) (xy 109.338813 -312.411181) (xy 109.315141 -312.461678) (xy 109.284368 -312.508191)
			(xy 109.247151 -312.549728) (xy 109.204283 -312.585403) (xy 109.156677 -312.614457) (xy 109.105348 -312.636269)
			(xy 109.051391 -312.650375) (xy 108.995954 -312.656475) (xy 108.94022 -312.654438) (xy 108.885377 -312.644308)
			(xy 108.832593 -312.626301) (xy 108.782993 -312.6008) (xy 108.737635 -312.568349) (xy 108.697486 -312.52964)
			(xy 108.6634 -312.485497) (xy 108.636104 -312.436862) (xy 108.616181 -312.384771) (xy 108.604055 -312.330334)
			(xy 108.599984 -312.274712) (xy 108.34751 -312.274712) (xy 108.347001 -312.302598) (xy 108.338881 -312.357774)
			(xy 108.322813 -312.411181) (xy 108.299141 -312.461678) (xy 108.268368 -312.508191) (xy 108.231151 -312.549728)
			(xy 108.188283 -312.585403) (xy 108.140677 -312.614457) (xy 108.089348 -312.636269) (xy 108.035391 -312.650375)
			(xy 107.979954 -312.656475) (xy 107.92422 -312.654438) (xy 107.869377 -312.644308) (xy 107.816593 -312.626301)
			(xy 107.766993 -312.6008) (xy 107.721635 -312.568349) (xy 107.681486 -312.52964) (xy 107.6474 -312.485497)
			(xy 107.620104 -312.436862) (xy 107.600181 -312.384771) (xy 107.588055 -312.330334) (xy 107.583984 -312.274712)
			(xy 107.33151 -312.274712) (xy 107.331001 -312.302598) (xy 107.322881 -312.357774) (xy 107.306813 -312.411181)
			(xy 107.283141 -312.461678) (xy 107.252368 -312.508191) (xy 107.215151 -312.549728) (xy 107.172283 -312.585403)
			(xy 107.124677 -312.614457) (xy 107.073348 -312.636269) (xy 107.019391 -312.650375) (xy 106.963954 -312.656475)
			(xy 106.90822 -312.654438) (xy 106.853377 -312.644308) (xy 106.800593 -312.626301) (xy 106.750993 -312.6008)
			(xy 106.705635 -312.568349) (xy 106.665486 -312.52964) (xy 106.6314 -312.485497) (xy 106.604104 -312.436862)
			(xy 106.584181 -312.384771) (xy 106.572055 -312.330334) (xy 106.567984 -312.274712) (xy 106.31551 -312.274712)
			(xy 106.315001 -312.302598) (xy 106.306881 -312.357774) (xy 106.290813 -312.411181) (xy 106.267141 -312.461678)
			(xy 106.236368 -312.508191) (xy 106.199151 -312.549728) (xy 106.156283 -312.585403) (xy 106.108677 -312.614457)
			(xy 106.057348 -312.636269) (xy 106.003391 -312.650375) (xy 105.947954 -312.656475) (xy 105.89222 -312.654438)
			(xy 105.837377 -312.644308) (xy 105.784593 -312.626301) (xy 105.734993 -312.6008) (xy 105.689635 -312.568349)
			(xy 105.649486 -312.52964) (xy 105.6154 -312.485497) (xy 105.588104 -312.436862) (xy 105.568181 -312.384771)
			(xy 105.556055 -312.330334) (xy 105.551984 -312.274712) (xy 105.29951 -312.274712) (xy 105.299001 -312.302598)
			(xy 105.290881 -312.357774) (xy 105.274813 -312.411181) (xy 105.251141 -312.461678) (xy 105.220368 -312.508191)
			(xy 105.183151 -312.549728) (xy 105.140283 -312.585403) (xy 105.092677 -312.614457) (xy 105.041348 -312.636269)
			(xy 104.987391 -312.650375) (xy 104.931954 -312.656475) (xy 104.87622 -312.654438) (xy 104.821377 -312.644308)
			(xy 104.768593 -312.626301) (xy 104.718993 -312.6008) (xy 104.673635 -312.568349) (xy 104.633486 -312.52964)
			(xy 104.5994 -312.485497) (xy 104.572104 -312.436862) (xy 104.552181 -312.384771) (xy 104.540055 -312.330334)
			(xy 104.535984 -312.274712) (xy 104.28351 -312.274712) (xy 104.283001 -312.302598) (xy 104.274881 -312.357774)
			(xy 104.258813 -312.411181) (xy 104.235141 -312.461678) (xy 104.204368 -312.508191) (xy 104.167151 -312.549728)
			(xy 104.124283 -312.585403) (xy 104.076677 -312.614457) (xy 104.025348 -312.636269) (xy 103.971391 -312.650375)
			(xy 103.915954 -312.656475) (xy 103.86022 -312.654438) (xy 103.805377 -312.644308) (xy 103.752593 -312.626301)
			(xy 103.702993 -312.6008) (xy 103.657635 -312.568349) (xy 103.617486 -312.52964) (xy 103.5834 -312.485497)
			(xy 103.556104 -312.436862) (xy 103.536181 -312.384771) (xy 103.524055 -312.330334) (xy 103.519984 -312.274712)
			(xy 103.26751 -312.274712) (xy 103.267001 -312.302598) (xy 103.258881 -312.357774) (xy 103.242813 -312.411181)
			(xy 103.219141 -312.461678) (xy 103.188368 -312.508191) (xy 103.151151 -312.549728) (xy 103.108283 -312.585403)
			(xy 103.060677 -312.614457) (xy 103.009348 -312.636269) (xy 102.955391 -312.650375) (xy 102.899954 -312.656475)
			(xy 102.84422 -312.654438) (xy 102.789377 -312.644308) (xy 102.736593 -312.626301) (xy 102.686993 -312.6008)
			(xy 102.641635 -312.568349) (xy 102.601486 -312.52964) (xy 102.5674 -312.485497) (xy 102.540104 -312.436862)
			(xy 102.520181 -312.384771) (xy 102.508055 -312.330334) (xy 102.503984 -312.274712) (xy 102.25151 -312.274712)
			(xy 102.251001 -312.302598) (xy 102.242881 -312.357774) (xy 102.226813 -312.411181) (xy 102.203141 -312.461678)
			(xy 102.172368 -312.508191) (xy 102.135151 -312.549728) (xy 102.092283 -312.585403) (xy 102.044677 -312.614457)
			(xy 101.993348 -312.636269) (xy 101.939391 -312.650375) (xy 101.883954 -312.656475) (xy 101.82822 -312.654438)
			(xy 101.773377 -312.644308) (xy 101.720593 -312.626301) (xy 101.670993 -312.6008) (xy 101.625635 -312.568349)
			(xy 101.585486 -312.52964) (xy 101.5514 -312.485497) (xy 101.524104 -312.436862) (xy 101.504181 -312.384771)
			(xy 101.492055 -312.330334) (xy 101.487984 -312.274712) (xy 101.23551 -312.274712) (xy 101.235001 -312.302598)
			(xy 101.226881 -312.357774) (xy 101.210813 -312.411181) (xy 101.187141 -312.461678) (xy 101.156368 -312.508191)
			(xy 101.119151 -312.549728) (xy 101.076283 -312.585403) (xy 101.028677 -312.614457) (xy 100.977348 -312.636269)
			(xy 100.923391 -312.650375) (xy 100.867954 -312.656475) (xy 100.81222 -312.654438) (xy 100.757377 -312.644308)
			(xy 100.704593 -312.626301) (xy 100.654993 -312.6008) (xy 100.609635 -312.568349) (xy 100.569486 -312.52964)
			(xy 100.5354 -312.485497) (xy 100.508104 -312.436862) (xy 100.488181 -312.384771) (xy 100.476055 -312.330334)
			(xy 100.471984 -312.274712) (xy 100.33 -312.274712) (xy 100.33 -313.290712) (xy 100.471984 -313.290712)
			(xy 100.476055 -313.23509) (xy 100.488181 -313.180653) (xy 100.508104 -313.128562) (xy 100.5354 -313.079927)
			(xy 100.569486 -313.035784) (xy 100.609635 -312.997075) (xy 100.654993 -312.964624) (xy 100.704593 -312.939123)
			(xy 100.757377 -312.921116) (xy 100.81222 -312.910986) (xy 100.867954 -312.908949) (xy 100.923391 -312.915049)
			(xy 100.977348 -312.929155) (xy 101.028677 -312.950967) (xy 101.076283 -312.980021) (xy 101.119151 -313.015696)
			(xy 101.156368 -313.057233) (xy 101.187141 -313.103746) (xy 101.210813 -313.154243) (xy 101.226881 -313.20765)
			(xy 101.235001 -313.262826) (xy 101.23551 -313.290712) (xy 101.487984 -313.290712) (xy 101.492055 -313.23509)
			(xy 101.504181 -313.180653) (xy 101.524104 -313.128562) (xy 101.5514 -313.079927) (xy 101.585486 -313.035784)
			(xy 101.625635 -312.997075) (xy 101.670993 -312.964624) (xy 101.720593 -312.939123) (xy 101.773377 -312.921116)
			(xy 101.82822 -312.910986) (xy 101.883954 -312.908949) (xy 101.939391 -312.915049) (xy 101.993348 -312.929155)
			(xy 102.044677 -312.950967) (xy 102.092283 -312.980021) (xy 102.135151 -313.015696) (xy 102.172368 -313.057233)
			(xy 102.203141 -313.103746) (xy 102.226813 -313.154243) (xy 102.242881 -313.20765) (xy 102.251001 -313.262826)
			(xy 102.25151 -313.290712) (xy 102.503984 -313.290712) (xy 102.508055 -313.23509) (xy 102.520181 -313.180653)
			(xy 102.540104 -313.128562) (xy 102.5674 -313.079927) (xy 102.601486 -313.035784) (xy 102.641635 -312.997075)
			(xy 102.686993 -312.964624) (xy 102.736593 -312.939123) (xy 102.789377 -312.921116) (xy 102.84422 -312.910986)
			(xy 102.899954 -312.908949) (xy 102.955391 -312.915049) (xy 103.009348 -312.929155) (xy 103.060677 -312.950967)
			(xy 103.108283 -312.980021) (xy 103.151151 -313.015696) (xy 103.188368 -313.057233) (xy 103.219141 -313.103746)
			(xy 103.242813 -313.154243) (xy 103.258881 -313.20765) (xy 103.267001 -313.262826) (xy 103.26751 -313.290712)
			(xy 103.519984 -313.290712) (xy 103.524055 -313.23509) (xy 103.536181 -313.180653) (xy 103.556104 -313.128562)
			(xy 103.5834 -313.079927) (xy 103.617486 -313.035784) (xy 103.657635 -312.997075) (xy 103.702993 -312.964624)
			(xy 103.752593 -312.939123) (xy 103.805377 -312.921116) (xy 103.86022 -312.910986) (xy 103.915954 -312.908949)
			(xy 103.971391 -312.915049) (xy 104.025348 -312.929155) (xy 104.076677 -312.950967) (xy 104.124283 -312.980021)
			(xy 104.167151 -313.015696) (xy 104.204368 -313.057233) (xy 104.235141 -313.103746) (xy 104.258813 -313.154243)
			(xy 104.274881 -313.20765) (xy 104.283001 -313.262826) (xy 104.28351 -313.290712) (xy 104.535984 -313.290712)
			(xy 104.540055 -313.23509) (xy 104.552181 -313.180653) (xy 104.572104 -313.128562) (xy 104.5994 -313.079927)
			(xy 104.633486 -313.035784) (xy 104.673635 -312.997075) (xy 104.718993 -312.964624) (xy 104.768593 -312.939123)
			(xy 104.821377 -312.921116) (xy 104.87622 -312.910986) (xy 104.931954 -312.908949) (xy 104.987391 -312.915049)
			(xy 105.041348 -312.929155) (xy 105.092677 -312.950967) (xy 105.140283 -312.980021) (xy 105.183151 -313.015696)
			(xy 105.220368 -313.057233) (xy 105.251141 -313.103746) (xy 105.274813 -313.154243) (xy 105.290881 -313.20765)
			(xy 105.299001 -313.262826) (xy 105.29951 -313.290712) (xy 105.551984 -313.290712) (xy 105.556055 -313.23509)
			(xy 105.568181 -313.180653) (xy 105.588104 -313.128562) (xy 105.6154 -313.079927) (xy 105.649486 -313.035784)
			(xy 105.689635 -312.997075) (xy 105.734993 -312.964624) (xy 105.784593 -312.939123) (xy 105.837377 -312.921116)
			(xy 105.89222 -312.910986) (xy 105.947954 -312.908949) (xy 106.003391 -312.915049) (xy 106.057348 -312.929155)
			(xy 106.108677 -312.950967) (xy 106.156283 -312.980021) (xy 106.199151 -313.015696) (xy 106.236368 -313.057233)
			(xy 106.267141 -313.103746) (xy 106.290813 -313.154243) (xy 106.306881 -313.20765) (xy 106.315001 -313.262826)
			(xy 106.31551 -313.290712) (xy 106.567984 -313.290712) (xy 106.572055 -313.23509) (xy 106.584181 -313.180653)
			(xy 106.604104 -313.128562) (xy 106.6314 -313.079927) (xy 106.665486 -313.035784) (xy 106.705635 -312.997075)
			(xy 106.750993 -312.964624) (xy 106.800593 -312.939123) (xy 106.853377 -312.921116) (xy 106.90822 -312.910986)
			(xy 106.963954 -312.908949) (xy 107.019391 -312.915049) (xy 107.073348 -312.929155) (xy 107.124677 -312.950967)
			(xy 107.172283 -312.980021) (xy 107.215151 -313.015696) (xy 107.252368 -313.057233) (xy 107.283141 -313.103746)
			(xy 107.306813 -313.154243) (xy 107.322881 -313.20765) (xy 107.331001 -313.262826) (xy 107.33151 -313.290712)
			(xy 107.583984 -313.290712) (xy 107.588055 -313.23509) (xy 107.600181 -313.180653) (xy 107.620104 -313.128562)
			(xy 107.6474 -313.079927) (xy 107.681486 -313.035784) (xy 107.721635 -312.997075) (xy 107.766993 -312.964624)
			(xy 107.816593 -312.939123) (xy 107.869377 -312.921116) (xy 107.92422 -312.910986) (xy 107.979954 -312.908949)
			(xy 108.035391 -312.915049) (xy 108.089348 -312.929155) (xy 108.140677 -312.950967) (xy 108.188283 -312.980021)
			(xy 108.231151 -313.015696) (xy 108.268368 -313.057233) (xy 108.299141 -313.103746) (xy 108.322813 -313.154243)
			(xy 108.338881 -313.20765) (xy 108.347001 -313.262826) (xy 108.34751 -313.290712) (xy 108.599984 -313.290712)
			(xy 108.604055 -313.23509) (xy 108.616181 -313.180653) (xy 108.636104 -313.128562) (xy 108.6634 -313.079927)
			(xy 108.697486 -313.035784) (xy 108.737635 -312.997075) (xy 108.782993 -312.964624) (xy 108.832593 -312.939123)
			(xy 108.885377 -312.921116) (xy 108.94022 -312.910986) (xy 108.995954 -312.908949) (xy 109.051391 -312.915049)
			(xy 109.105348 -312.929155) (xy 109.156677 -312.950967) (xy 109.204283 -312.980021) (xy 109.247151 -313.015696)
			(xy 109.284368 -313.057233) (xy 109.315141 -313.103746) (xy 109.338813 -313.154243) (xy 109.354881 -313.20765)
			(xy 109.363001 -313.262826) (xy 109.36351 -313.290712) (xy 109.615984 -313.290712) (xy 109.620055 -313.23509)
			(xy 109.632181 -313.180653) (xy 109.652104 -313.128562) (xy 109.6794 -313.079927) (xy 109.713486 -313.035784)
			(xy 109.753635 -312.997075) (xy 109.798993 -312.964624) (xy 109.848593 -312.939123) (xy 109.901377 -312.921116)
			(xy 109.95622 -312.910986) (xy 110.011954 -312.908949) (xy 110.067391 -312.915049) (xy 110.121348 -312.929155)
			(xy 110.172677 -312.950967) (xy 110.220283 -312.980021) (xy 110.263151 -313.015696) (xy 110.300368 -313.057233)
			(xy 110.331141 -313.103746) (xy 110.354813 -313.154243) (xy 110.370881 -313.20765) (xy 110.379001 -313.262826)
			(xy 110.37951 -313.290712) (xy 110.379001 -313.318598) (xy 110.370881 -313.373774) (xy 110.354813 -313.427181)
			(xy 110.331141 -313.477678) (xy 110.300368 -313.524191) (xy 110.263151 -313.565728) (xy 110.220283 -313.601403)
			(xy 110.172677 -313.630457) (xy 110.121348 -313.652269) (xy 110.067391 -313.666375) (xy 110.011954 -313.672475)
			(xy 109.95622 -313.670438) (xy 109.901377 -313.660308) (xy 109.848593 -313.642301) (xy 109.798993 -313.6168)
			(xy 109.753635 -313.584349) (xy 109.713486 -313.54564) (xy 109.6794 -313.501497) (xy 109.652104 -313.452862)
			(xy 109.632181 -313.400771) (xy 109.620055 -313.346334) (xy 109.615984 -313.290712) (xy 109.36351 -313.290712)
			(xy 109.363001 -313.318598) (xy 109.354881 -313.373774) (xy 109.338813 -313.427181) (xy 109.315141 -313.477678)
			(xy 109.284368 -313.524191) (xy 109.247151 -313.565728) (xy 109.204283 -313.601403) (xy 109.156677 -313.630457)
			(xy 109.105348 -313.652269) (xy 109.051391 -313.666375) (xy 108.995954 -313.672475) (xy 108.94022 -313.670438)
			(xy 108.885377 -313.660308) (xy 108.832593 -313.642301) (xy 108.782993 -313.6168) (xy 108.737635 -313.584349)
			(xy 108.697486 -313.54564) (xy 108.6634 -313.501497) (xy 108.636104 -313.452862) (xy 108.616181 -313.400771)
			(xy 108.604055 -313.346334) (xy 108.599984 -313.290712) (xy 108.34751 -313.290712) (xy 108.347001 -313.318598)
			(xy 108.338881 -313.373774) (xy 108.322813 -313.427181) (xy 108.299141 -313.477678) (xy 108.268368 -313.524191)
			(xy 108.231151 -313.565728) (xy 108.188283 -313.601403) (xy 108.140677 -313.630457) (xy 108.089348 -313.652269)
			(xy 108.035391 -313.666375) (xy 107.979954 -313.672475) (xy 107.92422 -313.670438) (xy 107.869377 -313.660308)
			(xy 107.816593 -313.642301) (xy 107.766993 -313.6168) (xy 107.721635 -313.584349) (xy 107.681486 -313.54564)
			(xy 107.6474 -313.501497) (xy 107.620104 -313.452862) (xy 107.600181 -313.400771) (xy 107.588055 -313.346334)
			(xy 107.583984 -313.290712) (xy 107.33151 -313.290712) (xy 107.331001 -313.318598) (xy 107.322881 -313.373774)
			(xy 107.306813 -313.427181) (xy 107.283141 -313.477678) (xy 107.252368 -313.524191) (xy 107.215151 -313.565728)
			(xy 107.172283 -313.601403) (xy 107.124677 -313.630457) (xy 107.073348 -313.652269) (xy 107.019391 -313.666375)
			(xy 106.963954 -313.672475) (xy 106.90822 -313.670438) (xy 106.853377 -313.660308) (xy 106.800593 -313.642301)
			(xy 106.750993 -313.6168) (xy 106.705635 -313.584349) (xy 106.665486 -313.54564) (xy 106.6314 -313.501497)
			(xy 106.604104 -313.452862) (xy 106.584181 -313.400771) (xy 106.572055 -313.346334) (xy 106.567984 -313.290712)
			(xy 106.31551 -313.290712) (xy 106.315001 -313.318598) (xy 106.306881 -313.373774) (xy 106.290813 -313.427181)
			(xy 106.267141 -313.477678) (xy 106.236368 -313.524191) (xy 106.199151 -313.565728) (xy 106.156283 -313.601403)
			(xy 106.108677 -313.630457) (xy 106.057348 -313.652269) (xy 106.003391 -313.666375) (xy 105.947954 -313.672475)
			(xy 105.89222 -313.670438) (xy 105.837377 -313.660308) (xy 105.784593 -313.642301) (xy 105.734993 -313.6168)
			(xy 105.689635 -313.584349) (xy 105.649486 -313.54564) (xy 105.6154 -313.501497) (xy 105.588104 -313.452862)
			(xy 105.568181 -313.400771) (xy 105.556055 -313.346334) (xy 105.551984 -313.290712) (xy 105.29951 -313.290712)
			(xy 105.299001 -313.318598) (xy 105.290881 -313.373774) (xy 105.274813 -313.427181) (xy 105.251141 -313.477678)
			(xy 105.220368 -313.524191) (xy 105.183151 -313.565728) (xy 105.140283 -313.601403) (xy 105.092677 -313.630457)
			(xy 105.041348 -313.652269) (xy 104.987391 -313.666375) (xy 104.931954 -313.672475) (xy 104.87622 -313.670438)
			(xy 104.821377 -313.660308) (xy 104.768593 -313.642301) (xy 104.718993 -313.6168) (xy 104.673635 -313.584349)
			(xy 104.633486 -313.54564) (xy 104.5994 -313.501497) (xy 104.572104 -313.452862) (xy 104.552181 -313.400771)
			(xy 104.540055 -313.346334) (xy 104.535984 -313.290712) (xy 104.28351 -313.290712) (xy 104.283001 -313.318598)
			(xy 104.274881 -313.373774) (xy 104.258813 -313.427181) (xy 104.235141 -313.477678) (xy 104.204368 -313.524191)
			(xy 104.167151 -313.565728) (xy 104.124283 -313.601403) (xy 104.076677 -313.630457) (xy 104.025348 -313.652269)
			(xy 103.971391 -313.666375) (xy 103.915954 -313.672475) (xy 103.86022 -313.670438) (xy 103.805377 -313.660308)
			(xy 103.752593 -313.642301) (xy 103.702993 -313.6168) (xy 103.657635 -313.584349) (xy 103.617486 -313.54564)
			(xy 103.5834 -313.501497) (xy 103.556104 -313.452862) (xy 103.536181 -313.400771) (xy 103.524055 -313.346334)
			(xy 103.519984 -313.290712) (xy 103.26751 -313.290712) (xy 103.267001 -313.318598) (xy 103.258881 -313.373774)
			(xy 103.242813 -313.427181) (xy 103.219141 -313.477678) (xy 103.188368 -313.524191) (xy 103.151151 -313.565728)
			(xy 103.108283 -313.601403) (xy 103.060677 -313.630457) (xy 103.009348 -313.652269) (xy 102.955391 -313.666375)
			(xy 102.899954 -313.672475) (xy 102.84422 -313.670438) (xy 102.789377 -313.660308) (xy 102.736593 -313.642301)
			(xy 102.686993 -313.6168) (xy 102.641635 -313.584349) (xy 102.601486 -313.54564) (xy 102.5674 -313.501497)
			(xy 102.540104 -313.452862) (xy 102.520181 -313.400771) (xy 102.508055 -313.346334) (xy 102.503984 -313.290712)
			(xy 102.25151 -313.290712) (xy 102.251001 -313.318598) (xy 102.242881 -313.373774) (xy 102.226813 -313.427181)
			(xy 102.203141 -313.477678) (xy 102.172368 -313.524191) (xy 102.135151 -313.565728) (xy 102.092283 -313.601403)
			(xy 102.044677 -313.630457) (xy 101.993348 -313.652269) (xy 101.939391 -313.666375) (xy 101.883954 -313.672475)
			(xy 101.82822 -313.670438) (xy 101.773377 -313.660308) (xy 101.720593 -313.642301) (xy 101.670993 -313.6168)
			(xy 101.625635 -313.584349) (xy 101.585486 -313.54564) (xy 101.5514 -313.501497) (xy 101.524104 -313.452862)
			(xy 101.504181 -313.400771) (xy 101.492055 -313.346334) (xy 101.487984 -313.290712) (xy 101.23551 -313.290712)
			(xy 101.235001 -313.318598) (xy 101.226881 -313.373774) (xy 101.210813 -313.427181) (xy 101.187141 -313.477678)
			(xy 101.156368 -313.524191) (xy 101.119151 -313.565728) (xy 101.076283 -313.601403) (xy 101.028677 -313.630457)
			(xy 100.977348 -313.652269) (xy 100.923391 -313.666375) (xy 100.867954 -313.672475) (xy 100.81222 -313.670438)
			(xy 100.757377 -313.660308) (xy 100.704593 -313.642301) (xy 100.654993 -313.6168) (xy 100.609635 -313.584349)
			(xy 100.569486 -313.54564) (xy 100.5354 -313.501497) (xy 100.508104 -313.452862) (xy 100.488181 -313.400771)
			(xy 100.476055 -313.346334) (xy 100.471984 -313.290712) (xy 100.33 -313.290712) (xy 100.33 -314.306712)
			(xy 101.487984 -314.306712) (xy 101.492055 -314.25109) (xy 101.504181 -314.196653) (xy 101.524104 -314.144562)
			(xy 101.5514 -314.095927) (xy 101.585486 -314.051784) (xy 101.625635 -314.013075) (xy 101.670993 -313.980624)
			(xy 101.720593 -313.955123) (xy 101.773377 -313.937116) (xy 101.82822 -313.926986) (xy 101.883954 -313.924949)
			(xy 101.939391 -313.931049) (xy 101.993348 -313.945155) (xy 102.044677 -313.966967) (xy 102.092283 -313.996021)
			(xy 102.135151 -314.031696) (xy 102.172368 -314.073233) (xy 102.203141 -314.119746) (xy 102.226813 -314.170243)
			(xy 102.242881 -314.22365) (xy 102.251001 -314.278826) (xy 102.25151 -314.306712) (xy 102.503984 -314.306712)
			(xy 102.508055 -314.25109) (xy 102.520181 -314.196653) (xy 102.540104 -314.144562) (xy 102.5674 -314.095927)
			(xy 102.601486 -314.051784) (xy 102.641635 -314.013075) (xy 102.686993 -313.980624) (xy 102.736593 -313.955123)
			(xy 102.789377 -313.937116) (xy 102.84422 -313.926986) (xy 102.899954 -313.924949) (xy 102.955391 -313.931049)
			(xy 103.009348 -313.945155) (xy 103.060677 -313.966967) (xy 103.108283 -313.996021) (xy 103.151151 -314.031696)
			(xy 103.188368 -314.073233) (xy 103.219141 -314.119746) (xy 103.242813 -314.170243) (xy 103.258881 -314.22365)
			(xy 103.267001 -314.278826) (xy 103.26751 -314.306712) (xy 103.519984 -314.306712) (xy 103.524055 -314.25109)
			(xy 103.536181 -314.196653) (xy 103.556104 -314.144562) (xy 103.5834 -314.095927) (xy 103.617486 -314.051784)
			(xy 103.657635 -314.013075) (xy 103.702993 -313.980624) (xy 103.752593 -313.955123) (xy 103.805377 -313.937116)
			(xy 103.86022 -313.926986) (xy 103.915954 -313.924949) (xy 103.971391 -313.931049) (xy 104.025348 -313.945155)
			(xy 104.076677 -313.966967) (xy 104.124283 -313.996021) (xy 104.167151 -314.031696) (xy 104.204368 -314.073233)
			(xy 104.235141 -314.119746) (xy 104.258813 -314.170243) (xy 104.274881 -314.22365) (xy 104.283001 -314.278826)
			(xy 104.28351 -314.306712) (xy 104.535984 -314.306712) (xy 104.540055 -314.25109) (xy 104.552181 -314.196653)
			(xy 104.572104 -314.144562) (xy 104.5994 -314.095927) (xy 104.633486 -314.051784) (xy 104.673635 -314.013075)
			(xy 104.718993 -313.980624) (xy 104.768593 -313.955123) (xy 104.821377 -313.937116) (xy 104.87622 -313.926986)
			(xy 104.931954 -313.924949) (xy 104.987391 -313.931049) (xy 105.041348 -313.945155) (xy 105.092677 -313.966967)
			(xy 105.140283 -313.996021) (xy 105.183151 -314.031696) (xy 105.220368 -314.073233) (xy 105.251141 -314.119746)
			(xy 105.274813 -314.170243) (xy 105.290881 -314.22365) (xy 105.299001 -314.278826) (xy 105.29951 -314.306712)
			(xy 105.551984 -314.306712) (xy 105.556055 -314.25109) (xy 105.568181 -314.196653) (xy 105.588104 -314.144562)
			(xy 105.6154 -314.095927) (xy 105.649486 -314.051784) (xy 105.689635 -314.013075) (xy 105.734993 -313.980624)
			(xy 105.784593 -313.955123) (xy 105.837377 -313.937116) (xy 105.89222 -313.926986) (xy 105.947954 -313.924949)
			(xy 106.003391 -313.931049) (xy 106.057348 -313.945155) (xy 106.108677 -313.966967) (xy 106.156283 -313.996021)
			(xy 106.199151 -314.031696) (xy 106.236368 -314.073233) (xy 106.267141 -314.119746) (xy 106.290813 -314.170243)
			(xy 106.306881 -314.22365) (xy 106.315001 -314.278826) (xy 106.31551 -314.306712) (xy 106.567984 -314.306712)
			(xy 106.572055 -314.25109) (xy 106.584181 -314.196653) (xy 106.604104 -314.144562) (xy 106.6314 -314.095927)
			(xy 106.665486 -314.051784) (xy 106.705635 -314.013075) (xy 106.750993 -313.980624) (xy 106.800593 -313.955123)
			(xy 106.853377 -313.937116) (xy 106.90822 -313.926986) (xy 106.963954 -313.924949) (xy 107.019391 -313.931049)
			(xy 107.073348 -313.945155) (xy 107.124677 -313.966967) (xy 107.172283 -313.996021) (xy 107.215151 -314.031696)
			(xy 107.252368 -314.073233) (xy 107.283141 -314.119746) (xy 107.306813 -314.170243) (xy 107.322881 -314.22365)
			(xy 107.331001 -314.278826) (xy 107.33151 -314.306712) (xy 107.583984 -314.306712) (xy 107.588055 -314.25109)
			(xy 107.600181 -314.196653) (xy 107.620104 -314.144562) (xy 107.6474 -314.095927) (xy 107.681486 -314.051784)
			(xy 107.721635 -314.013075) (xy 107.766993 -313.980624) (xy 107.816593 -313.955123) (xy 107.869377 -313.937116)
			(xy 107.92422 -313.926986) (xy 107.979954 -313.924949) (xy 108.035391 -313.931049) (xy 108.089348 -313.945155)
			(xy 108.140677 -313.966967) (xy 108.188283 -313.996021) (xy 108.231151 -314.031696) (xy 108.268368 -314.073233)
			(xy 108.299141 -314.119746) (xy 108.322813 -314.170243) (xy 108.338881 -314.22365) (xy 108.347001 -314.278826)
			(xy 108.34751 -314.306712) (xy 108.599984 -314.306712) (xy 108.604055 -314.25109) (xy 108.616181 -314.196653)
			(xy 108.636104 -314.144562) (xy 108.6634 -314.095927) (xy 108.697486 -314.051784) (xy 108.737635 -314.013075)
			(xy 108.782993 -313.980624) (xy 108.832593 -313.955123) (xy 108.885377 -313.937116) (xy 108.94022 -313.926986)
			(xy 108.995954 -313.924949) (xy 109.051391 -313.931049) (xy 109.105348 -313.945155) (xy 109.156677 -313.966967)
			(xy 109.204283 -313.996021) (xy 109.247151 -314.031696) (xy 109.284368 -314.073233) (xy 109.315141 -314.119746)
			(xy 109.338813 -314.170243) (xy 109.354881 -314.22365) (xy 109.363001 -314.278826) (xy 109.36351 -314.306712)
			(xy 109.615984 -314.306712) (xy 109.620055 -314.25109) (xy 109.632181 -314.196653) (xy 109.652104 -314.144562)
			(xy 109.6794 -314.095927) (xy 109.713486 -314.051784) (xy 109.753635 -314.013075) (xy 109.798993 -313.980624)
			(xy 109.848593 -313.955123) (xy 109.901377 -313.937116) (xy 109.95622 -313.926986) (xy 110.011954 -313.924949)
			(xy 110.067391 -313.931049) (xy 110.121348 -313.945155) (xy 110.172677 -313.966967) (xy 110.220283 -313.996021)
			(xy 110.263151 -314.031696) (xy 110.300368 -314.073233) (xy 110.331141 -314.119746) (xy 110.354813 -314.170243)
			(xy 110.370881 -314.22365) (xy 110.379001 -314.278826) (xy 110.37951 -314.306712) (xy 110.379001 -314.334598)
			(xy 110.370881 -314.389774) (xy 110.354813 -314.443181) (xy 110.331141 -314.493678) (xy 110.300368 -314.540191)
			(xy 110.263151 -314.581728) (xy 110.220283 -314.617403) (xy 110.172677 -314.646457) (xy 110.121348 -314.668269)
			(xy 110.067391 -314.682375) (xy 110.011954 -314.688475) (xy 109.95622 -314.686438) (xy 109.901377 -314.676308)
			(xy 109.848593 -314.658301) (xy 109.798993 -314.6328) (xy 109.753635 -314.600349) (xy 109.713486 -314.56164)
			(xy 109.6794 -314.517497) (xy 109.652104 -314.468862) (xy 109.632181 -314.416771) (xy 109.620055 -314.362334)
			(xy 109.615984 -314.306712) (xy 109.36351 -314.306712) (xy 109.363001 -314.334598) (xy 109.354881 -314.389774)
			(xy 109.338813 -314.443181) (xy 109.315141 -314.493678) (xy 109.284368 -314.540191) (xy 109.247151 -314.581728)
			(xy 109.204283 -314.617403) (xy 109.156677 -314.646457) (xy 109.105348 -314.668269) (xy 109.051391 -314.682375)
			(xy 108.995954 -314.688475) (xy 108.94022 -314.686438) (xy 108.885377 -314.676308) (xy 108.832593 -314.658301)
			(xy 108.782993 -314.6328) (xy 108.737635 -314.600349) (xy 108.697486 -314.56164) (xy 108.6634 -314.517497)
			(xy 108.636104 -314.468862) (xy 108.616181 -314.416771) (xy 108.604055 -314.362334) (xy 108.599984 -314.306712)
			(xy 108.34751 -314.306712) (xy 108.347001 -314.334598) (xy 108.338881 -314.389774) (xy 108.322813 -314.443181)
			(xy 108.299141 -314.493678) (xy 108.268368 -314.540191) (xy 108.231151 -314.581728) (xy 108.188283 -314.617403)
			(xy 108.140677 -314.646457) (xy 108.089348 -314.668269) (xy 108.035391 -314.682375) (xy 107.979954 -314.688475)
			(xy 107.92422 -314.686438) (xy 107.869377 -314.676308) (xy 107.816593 -314.658301) (xy 107.766993 -314.6328)
			(xy 107.721635 -314.600349) (xy 107.681486 -314.56164) (xy 107.6474 -314.517497) (xy 107.620104 -314.468862)
			(xy 107.600181 -314.416771) (xy 107.588055 -314.362334) (xy 107.583984 -314.306712) (xy 107.33151 -314.306712)
			(xy 107.331001 -314.334598) (xy 107.322881 -314.389774) (xy 107.306813 -314.443181) (xy 107.283141 -314.493678)
			(xy 107.252368 -314.540191) (xy 107.215151 -314.581728) (xy 107.172283 -314.617403) (xy 107.124677 -314.646457)
			(xy 107.073348 -314.668269) (xy 107.019391 -314.682375) (xy 106.963954 -314.688475) (xy 106.90822 -314.686438)
			(xy 106.853377 -314.676308) (xy 106.800593 -314.658301) (xy 106.750993 -314.6328) (xy 106.705635 -314.600349)
			(xy 106.665486 -314.56164) (xy 106.6314 -314.517497) (xy 106.604104 -314.468862) (xy 106.584181 -314.416771)
			(xy 106.572055 -314.362334) (xy 106.567984 -314.306712) (xy 106.31551 -314.306712) (xy 106.315001 -314.334598)
			(xy 106.306881 -314.389774) (xy 106.290813 -314.443181) (xy 106.267141 -314.493678) (xy 106.236368 -314.540191)
			(xy 106.199151 -314.581728) (xy 106.156283 -314.617403) (xy 106.108677 -314.646457) (xy 106.057348 -314.668269)
			(xy 106.003391 -314.682375) (xy 105.947954 -314.688475) (xy 105.89222 -314.686438) (xy 105.837377 -314.676308)
			(xy 105.784593 -314.658301) (xy 105.734993 -314.6328) (xy 105.689635 -314.600349) (xy 105.649486 -314.56164)
			(xy 105.6154 -314.517497) (xy 105.588104 -314.468862) (xy 105.568181 -314.416771) (xy 105.556055 -314.362334)
			(xy 105.551984 -314.306712) (xy 105.29951 -314.306712) (xy 105.299001 -314.334598) (xy 105.290881 -314.389774)
			(xy 105.274813 -314.443181) (xy 105.251141 -314.493678) (xy 105.220368 -314.540191) (xy 105.183151 -314.581728)
			(xy 105.140283 -314.617403) (xy 105.092677 -314.646457) (xy 105.041348 -314.668269) (xy 104.987391 -314.682375)
			(xy 104.931954 -314.688475) (xy 104.87622 -314.686438) (xy 104.821377 -314.676308) (xy 104.768593 -314.658301)
			(xy 104.718993 -314.6328) (xy 104.673635 -314.600349) (xy 104.633486 -314.56164) (xy 104.5994 -314.517497)
			(xy 104.572104 -314.468862) (xy 104.552181 -314.416771) (xy 104.540055 -314.362334) (xy 104.535984 -314.306712)
			(xy 104.28351 -314.306712) (xy 104.283001 -314.334598) (xy 104.274881 -314.389774) (xy 104.258813 -314.443181)
			(xy 104.235141 -314.493678) (xy 104.204368 -314.540191) (xy 104.167151 -314.581728) (xy 104.124283 -314.617403)
			(xy 104.076677 -314.646457) (xy 104.025348 -314.668269) (xy 103.971391 -314.682375) (xy 103.915954 -314.688475)
			(xy 103.86022 -314.686438) (xy 103.805377 -314.676308) (xy 103.752593 -314.658301) (xy 103.702993 -314.6328)
			(xy 103.657635 -314.600349) (xy 103.617486 -314.56164) (xy 103.5834 -314.517497) (xy 103.556104 -314.468862)
			(xy 103.536181 -314.416771) (xy 103.524055 -314.362334) (xy 103.519984 -314.306712) (xy 103.26751 -314.306712)
			(xy 103.267001 -314.334598) (xy 103.258881 -314.389774) (xy 103.242813 -314.443181) (xy 103.219141 -314.493678)
			(xy 103.188368 -314.540191) (xy 103.151151 -314.581728) (xy 103.108283 -314.617403) (xy 103.060677 -314.646457)
			(xy 103.009348 -314.668269) (xy 102.955391 -314.682375) (xy 102.899954 -314.688475) (xy 102.84422 -314.686438)
			(xy 102.789377 -314.676308) (xy 102.736593 -314.658301) (xy 102.686993 -314.6328) (xy 102.641635 -314.600349)
			(xy 102.601486 -314.56164) (xy 102.5674 -314.517497) (xy 102.540104 -314.468862) (xy 102.520181 -314.416771)
			(xy 102.508055 -314.362334) (xy 102.503984 -314.306712) (xy 102.25151 -314.306712) (xy 102.251001 -314.334598)
			(xy 102.242881 -314.389774) (xy 102.226813 -314.443181) (xy 102.203141 -314.493678) (xy 102.172368 -314.540191)
			(xy 102.135151 -314.581728) (xy 102.092283 -314.617403) (xy 102.044677 -314.646457) (xy 101.993348 -314.668269)
			(xy 101.939391 -314.682375) (xy 101.883954 -314.688475) (xy 101.82822 -314.686438) (xy 101.773377 -314.676308)
			(xy 101.720593 -314.658301) (xy 101.670993 -314.6328) (xy 101.625635 -314.600349) (xy 101.585486 -314.56164)
			(xy 101.5514 -314.517497) (xy 101.524104 -314.468862) (xy 101.504181 -314.416771) (xy 101.492055 -314.362334)
			(xy 101.487984 -314.306712) (xy 100.33 -314.306712) (xy 100.33 -315.322712) (xy 101.487984 -315.322712)
			(xy 101.492055 -315.26709) (xy 101.504181 -315.212653) (xy 101.524104 -315.160562) (xy 101.5514 -315.111927)
			(xy 101.585486 -315.067784) (xy 101.625635 -315.029075) (xy 101.670993 -314.996624) (xy 101.720593 -314.971123)
			(xy 101.773377 -314.953116) (xy 101.82822 -314.942986) (xy 101.883954 -314.940949) (xy 101.939391 -314.947049)
			(xy 101.993348 -314.961155) (xy 102.044677 -314.982967) (xy 102.092283 -315.012021) (xy 102.135151 -315.047696)
			(xy 102.172368 -315.089233) (xy 102.203141 -315.135746) (xy 102.226813 -315.186243) (xy 102.242881 -315.23965)
			(xy 102.251001 -315.294826) (xy 102.25151 -315.322712) (xy 102.503984 -315.322712) (xy 102.508055 -315.26709)
			(xy 102.520181 -315.212653) (xy 102.540104 -315.160562) (xy 102.5674 -315.111927) (xy 102.601486 -315.067784)
			(xy 102.641635 -315.029075) (xy 102.686993 -314.996624) (xy 102.736593 -314.971123) (xy 102.789377 -314.953116)
			(xy 102.84422 -314.942986) (xy 102.899954 -314.940949) (xy 102.955391 -314.947049) (xy 103.009348 -314.961155)
			(xy 103.060677 -314.982967) (xy 103.108283 -315.012021) (xy 103.151151 -315.047696) (xy 103.188368 -315.089233)
			(xy 103.219141 -315.135746) (xy 103.242813 -315.186243) (xy 103.258881 -315.23965) (xy 103.267001 -315.294826)
			(xy 103.26751 -315.322712) (xy 103.519984 -315.322712) (xy 103.524055 -315.26709) (xy 103.536181 -315.212653)
			(xy 103.556104 -315.160562) (xy 103.5834 -315.111927) (xy 103.617486 -315.067784) (xy 103.657635 -315.029075)
			(xy 103.702993 -314.996624) (xy 103.752593 -314.971123) (xy 103.805377 -314.953116) (xy 103.86022 -314.942986)
			(xy 103.915954 -314.940949) (xy 103.971391 -314.947049) (xy 104.025348 -314.961155) (xy 104.076677 -314.982967)
			(xy 104.124283 -315.012021) (xy 104.167151 -315.047696) (xy 104.204368 -315.089233) (xy 104.235141 -315.135746)
			(xy 104.258813 -315.186243) (xy 104.274881 -315.23965) (xy 104.283001 -315.294826) (xy 104.28351 -315.322712)
			(xy 104.535984 -315.322712) (xy 104.540055 -315.26709) (xy 104.552181 -315.212653) (xy 104.572104 -315.160562)
			(xy 104.5994 -315.111927) (xy 104.633486 -315.067784) (xy 104.673635 -315.029075) (xy 104.718993 -314.996624)
			(xy 104.768593 -314.971123) (xy 104.821377 -314.953116) (xy 104.87622 -314.942986) (xy 104.931954 -314.940949)
			(xy 104.987391 -314.947049) (xy 105.041348 -314.961155) (xy 105.092677 -314.982967) (xy 105.140283 -315.012021)
			(xy 105.183151 -315.047696) (xy 105.220368 -315.089233) (xy 105.251141 -315.135746) (xy 105.274813 -315.186243)
			(xy 105.290881 -315.23965) (xy 105.299001 -315.294826) (xy 105.29951 -315.322712) (xy 105.551984 -315.322712)
			(xy 105.556055 -315.26709) (xy 105.568181 -315.212653) (xy 105.588104 -315.160562) (xy 105.6154 -315.111927)
			(xy 105.649486 -315.067784) (xy 105.689635 -315.029075) (xy 105.734993 -314.996624) (xy 105.784593 -314.971123)
			(xy 105.837377 -314.953116) (xy 105.89222 -314.942986) (xy 105.947954 -314.940949) (xy 106.003391 -314.947049)
			(xy 106.057348 -314.961155) (xy 106.108677 -314.982967) (xy 106.156283 -315.012021) (xy 106.199151 -315.047696)
			(xy 106.236368 -315.089233) (xy 106.267141 -315.135746) (xy 106.290813 -315.186243) (xy 106.306881 -315.23965)
			(xy 106.315001 -315.294826) (xy 106.31551 -315.322712) (xy 106.567984 -315.322712) (xy 106.572055 -315.26709)
			(xy 106.584181 -315.212653) (xy 106.604104 -315.160562) (xy 106.6314 -315.111927) (xy 106.665486 -315.067784)
			(xy 106.705635 -315.029075) (xy 106.750993 -314.996624) (xy 106.800593 -314.971123) (xy 106.853377 -314.953116)
			(xy 106.90822 -314.942986) (xy 106.963954 -314.940949) (xy 107.019391 -314.947049) (xy 107.073348 -314.961155)
			(xy 107.124677 -314.982967) (xy 107.172283 -315.012021) (xy 107.215151 -315.047696) (xy 107.252368 -315.089233)
			(xy 107.283141 -315.135746) (xy 107.306813 -315.186243) (xy 107.322881 -315.23965) (xy 107.331001 -315.294826)
			(xy 107.33151 -315.322712) (xy 107.583984 -315.322712) (xy 107.588055 -315.26709) (xy 107.600181 -315.212653)
			(xy 107.620104 -315.160562) (xy 107.6474 -315.111927) (xy 107.681486 -315.067784) (xy 107.721635 -315.029075)
			(xy 107.766993 -314.996624) (xy 107.816593 -314.971123) (xy 107.869377 -314.953116) (xy 107.92422 -314.942986)
			(xy 107.979954 -314.940949) (xy 108.035391 -314.947049) (xy 108.089348 -314.961155) (xy 108.140677 -314.982967)
			(xy 108.188283 -315.012021) (xy 108.231151 -315.047696) (xy 108.268368 -315.089233) (xy 108.299141 -315.135746)
			(xy 108.322813 -315.186243) (xy 108.338881 -315.23965) (xy 108.347001 -315.294826) (xy 108.34751 -315.322712)
			(xy 108.599984 -315.322712) (xy 108.604055 -315.26709) (xy 108.616181 -315.212653) (xy 108.636104 -315.160562)
			(xy 108.6634 -315.111927) (xy 108.697486 -315.067784) (xy 108.737635 -315.029075) (xy 108.782993 -314.996624)
			(xy 108.832593 -314.971123) (xy 108.885377 -314.953116) (xy 108.94022 -314.942986) (xy 108.995954 -314.940949)
			(xy 109.051391 -314.947049) (xy 109.105348 -314.961155) (xy 109.156677 -314.982967) (xy 109.204283 -315.012021)
			(xy 109.247151 -315.047696) (xy 109.284368 -315.089233) (xy 109.315141 -315.135746) (xy 109.338813 -315.186243)
			(xy 109.354881 -315.23965) (xy 109.363001 -315.294826) (xy 109.36351 -315.322712) (xy 109.615984 -315.322712)
			(xy 109.620055 -315.26709) (xy 109.632181 -315.212653) (xy 109.652104 -315.160562) (xy 109.6794 -315.111927)
			(xy 109.713486 -315.067784) (xy 109.753635 -315.029075) (xy 109.798993 -314.996624) (xy 109.848593 -314.971123)
			(xy 109.901377 -314.953116) (xy 109.95622 -314.942986) (xy 110.011954 -314.940949) (xy 110.067391 -314.947049)
			(xy 110.121348 -314.961155) (xy 110.172677 -314.982967) (xy 110.220283 -315.012021) (xy 110.263151 -315.047696)
			(xy 110.300368 -315.089233) (xy 110.331141 -315.135746) (xy 110.354813 -315.186243) (xy 110.370881 -315.23965)
			(xy 110.379001 -315.294826) (xy 110.37951 -315.322712) (xy 110.379001 -315.350598) (xy 110.370881 -315.405774)
			(xy 110.354813 -315.459181) (xy 110.331141 -315.509678) (xy 110.300368 -315.556191) (xy 110.263151 -315.597728)
			(xy 110.220283 -315.633403) (xy 110.172677 -315.662457) (xy 110.121348 -315.684269) (xy 110.067391 -315.698375)
			(xy 110.011954 -315.704475) (xy 109.95622 -315.702438) (xy 109.901377 -315.692308) (xy 109.848593 -315.674301)
			(xy 109.798993 -315.6488) (xy 109.753635 -315.616349) (xy 109.713486 -315.57764) (xy 109.6794 -315.533497)
			(xy 109.652104 -315.484862) (xy 109.632181 -315.432771) (xy 109.620055 -315.378334) (xy 109.615984 -315.322712)
			(xy 109.36351 -315.322712) (xy 109.363001 -315.350598) (xy 109.354881 -315.405774) (xy 109.338813 -315.459181)
			(xy 109.315141 -315.509678) (xy 109.284368 -315.556191) (xy 109.247151 -315.597728) (xy 109.204283 -315.633403)
			(xy 109.156677 -315.662457) (xy 109.105348 -315.684269) (xy 109.051391 -315.698375) (xy 108.995954 -315.704475)
			(xy 108.94022 -315.702438) (xy 108.885377 -315.692308) (xy 108.832593 -315.674301) (xy 108.782993 -315.6488)
			(xy 108.737635 -315.616349) (xy 108.697486 -315.57764) (xy 108.6634 -315.533497) (xy 108.636104 -315.484862)
			(xy 108.616181 -315.432771) (xy 108.604055 -315.378334) (xy 108.599984 -315.322712) (xy 108.34751 -315.322712)
			(xy 108.347001 -315.350598) (xy 108.338881 -315.405774) (xy 108.322813 -315.459181) (xy 108.299141 -315.509678)
			(xy 108.268368 -315.556191) (xy 108.231151 -315.597728) (xy 108.188283 -315.633403) (xy 108.140677 -315.662457)
			(xy 108.089348 -315.684269) (xy 108.035391 -315.698375) (xy 107.979954 -315.704475) (xy 107.92422 -315.702438)
			(xy 107.869377 -315.692308) (xy 107.816593 -315.674301) (xy 107.766993 -315.6488) (xy 107.721635 -315.616349)
			(xy 107.681486 -315.57764) (xy 107.6474 -315.533497) (xy 107.620104 -315.484862) (xy 107.600181 -315.432771)
			(xy 107.588055 -315.378334) (xy 107.583984 -315.322712) (xy 107.33151 -315.322712) (xy 107.331001 -315.350598)
			(xy 107.322881 -315.405774) (xy 107.306813 -315.459181) (xy 107.283141 -315.509678) (xy 107.252368 -315.556191)
			(xy 107.215151 -315.597728) (xy 107.172283 -315.633403) (xy 107.124677 -315.662457) (xy 107.073348 -315.684269)
			(xy 107.019391 -315.698375) (xy 106.963954 -315.704475) (xy 106.90822 -315.702438) (xy 106.853377 -315.692308)
			(xy 106.800593 -315.674301) (xy 106.750993 -315.6488) (xy 106.705635 -315.616349) (xy 106.665486 -315.57764)
			(xy 106.6314 -315.533497) (xy 106.604104 -315.484862) (xy 106.584181 -315.432771) (xy 106.572055 -315.378334)
			(xy 106.567984 -315.322712) (xy 106.31551 -315.322712) (xy 106.315001 -315.350598) (xy 106.306881 -315.405774)
			(xy 106.290813 -315.459181) (xy 106.267141 -315.509678) (xy 106.236368 -315.556191) (xy 106.199151 -315.597728)
			(xy 106.156283 -315.633403) (xy 106.108677 -315.662457) (xy 106.057348 -315.684269) (xy 106.003391 -315.698375)
			(xy 105.947954 -315.704475) (xy 105.89222 -315.702438) (xy 105.837377 -315.692308) (xy 105.784593 -315.674301)
			(xy 105.734993 -315.6488) (xy 105.689635 -315.616349) (xy 105.649486 -315.57764) (xy 105.6154 -315.533497)
			(xy 105.588104 -315.484862) (xy 105.568181 -315.432771) (xy 105.556055 -315.378334) (xy 105.551984 -315.322712)
			(xy 105.29951 -315.322712) (xy 105.299001 -315.350598) (xy 105.290881 -315.405774) (xy 105.274813 -315.459181)
			(xy 105.251141 -315.509678) (xy 105.220368 -315.556191) (xy 105.183151 -315.597728) (xy 105.140283 -315.633403)
			(xy 105.092677 -315.662457) (xy 105.041348 -315.684269) (xy 104.987391 -315.698375) (xy 104.931954 -315.704475)
			(xy 104.87622 -315.702438) (xy 104.821377 -315.692308) (xy 104.768593 -315.674301) (xy 104.718993 -315.6488)
			(xy 104.673635 -315.616349) (xy 104.633486 -315.57764) (xy 104.5994 -315.533497) (xy 104.572104 -315.484862)
			(xy 104.552181 -315.432771) (xy 104.540055 -315.378334) (xy 104.535984 -315.322712) (xy 104.28351 -315.322712)
			(xy 104.283001 -315.350598) (xy 104.274881 -315.405774) (xy 104.258813 -315.459181) (xy 104.235141 -315.509678)
			(xy 104.204368 -315.556191) (xy 104.167151 -315.597728) (xy 104.124283 -315.633403) (xy 104.076677 -315.662457)
			(xy 104.025348 -315.684269) (xy 103.971391 -315.698375) (xy 103.915954 -315.704475) (xy 103.86022 -315.702438)
			(xy 103.805377 -315.692308) (xy 103.752593 -315.674301) (xy 103.702993 -315.6488) (xy 103.657635 -315.616349)
			(xy 103.617486 -315.57764) (xy 103.5834 -315.533497) (xy 103.556104 -315.484862) (xy 103.536181 -315.432771)
			(xy 103.524055 -315.378334) (xy 103.519984 -315.322712) (xy 103.26751 -315.322712) (xy 103.267001 -315.350598)
			(xy 103.258881 -315.405774) (xy 103.242813 -315.459181) (xy 103.219141 -315.509678) (xy 103.188368 -315.556191)
			(xy 103.151151 -315.597728) (xy 103.108283 -315.633403) (xy 103.060677 -315.662457) (xy 103.009348 -315.684269)
			(xy 102.955391 -315.698375) (xy 102.899954 -315.704475) (xy 102.84422 -315.702438) (xy 102.789377 -315.692308)
			(xy 102.736593 -315.674301) (xy 102.686993 -315.6488) (xy 102.641635 -315.616349) (xy 102.601486 -315.57764)
			(xy 102.5674 -315.533497) (xy 102.540104 -315.484862) (xy 102.520181 -315.432771) (xy 102.508055 -315.378334)
			(xy 102.503984 -315.322712) (xy 102.25151 -315.322712) (xy 102.251001 -315.350598) (xy 102.242881 -315.405774)
			(xy 102.226813 -315.459181) (xy 102.203141 -315.509678) (xy 102.172368 -315.556191) (xy 102.135151 -315.597728)
			(xy 102.092283 -315.633403) (xy 102.044677 -315.662457) (xy 101.993348 -315.684269) (xy 101.939391 -315.698375)
			(xy 101.883954 -315.704475) (xy 101.82822 -315.702438) (xy 101.773377 -315.692308) (xy 101.720593 -315.674301)
			(xy 101.670993 -315.6488) (xy 101.625635 -315.616349) (xy 101.585486 -315.57764) (xy 101.5514 -315.533497)
			(xy 101.524104 -315.484862) (xy 101.504181 -315.432771) (xy 101.492055 -315.378334) (xy 101.487984 -315.322712)
			(xy 100.33 -315.322712) (xy 100.33 -316.338712) (xy 102.503984 -316.338712) (xy 102.508055 -316.28309)
			(xy 102.520181 -316.228653) (xy 102.540104 -316.176562) (xy 102.5674 -316.127927) (xy 102.601486 -316.083784)
			(xy 102.641635 -316.045075) (xy 102.686993 -316.012624) (xy 102.736593 -315.987123) (xy 102.789377 -315.969116)
			(xy 102.84422 -315.958986) (xy 102.899954 -315.956949) (xy 102.955391 -315.963049) (xy 103.009348 -315.977155)
			(xy 103.060677 -315.998967) (xy 103.108283 -316.028021) (xy 103.151151 -316.063696) (xy 103.188368 -316.105233)
			(xy 103.219141 -316.151746) (xy 103.242813 -316.202243) (xy 103.258881 -316.25565) (xy 103.267001 -316.310826)
			(xy 103.26751 -316.338712) (xy 103.519984 -316.338712) (xy 103.524055 -316.28309) (xy 103.536181 -316.228653)
			(xy 103.556104 -316.176562) (xy 103.5834 -316.127927) (xy 103.617486 -316.083784) (xy 103.657635 -316.045075)
			(xy 103.702993 -316.012624) (xy 103.752593 -315.987123) (xy 103.805377 -315.969116) (xy 103.86022 -315.958986)
			(xy 103.915954 -315.956949) (xy 103.971391 -315.963049) (xy 104.025348 -315.977155) (xy 104.076677 -315.998967)
			(xy 104.124283 -316.028021) (xy 104.167151 -316.063696) (xy 104.204368 -316.105233) (xy 104.235141 -316.151746)
			(xy 104.258813 -316.202243) (xy 104.274881 -316.25565) (xy 104.283001 -316.310826) (xy 104.28351 -316.338712)
			(xy 104.535984 -316.338712) (xy 104.540055 -316.28309) (xy 104.552181 -316.228653) (xy 104.572104 -316.176562)
			(xy 104.5994 -316.127927) (xy 104.633486 -316.083784) (xy 104.673635 -316.045075) (xy 104.718993 -316.012624)
			(xy 104.768593 -315.987123) (xy 104.821377 -315.969116) (xy 104.87622 -315.958986) (xy 104.931954 -315.956949)
			(xy 104.987391 -315.963049) (xy 105.041348 -315.977155) (xy 105.092677 -315.998967) (xy 105.140283 -316.028021)
			(xy 105.183151 -316.063696) (xy 105.220368 -316.105233) (xy 105.251141 -316.151746) (xy 105.274813 -316.202243)
			(xy 105.290881 -316.25565) (xy 105.299001 -316.310826) (xy 105.29951 -316.338712) (xy 105.551984 -316.338712)
			(xy 105.556055 -316.28309) (xy 105.568181 -316.228653) (xy 105.588104 -316.176562) (xy 105.6154 -316.127927)
			(xy 105.649486 -316.083784) (xy 105.689635 -316.045075) (xy 105.734993 -316.012624) (xy 105.784593 -315.987123)
			(xy 105.837377 -315.969116) (xy 105.89222 -315.958986) (xy 105.947954 -315.956949) (xy 106.003391 -315.963049)
			(xy 106.057348 -315.977155) (xy 106.108677 -315.998967) (xy 106.156283 -316.028021) (xy 106.199151 -316.063696)
			(xy 106.236368 -316.105233) (xy 106.267141 -316.151746) (xy 106.290813 -316.202243) (xy 106.306881 -316.25565)
			(xy 106.315001 -316.310826) (xy 106.31551 -316.338712) (xy 106.567984 -316.338712) (xy 106.572055 -316.28309)
			(xy 106.584181 -316.228653) (xy 106.604104 -316.176562) (xy 106.6314 -316.127927) (xy 106.665486 -316.083784)
			(xy 106.705635 -316.045075) (xy 106.750993 -316.012624) (xy 106.800593 -315.987123) (xy 106.853377 -315.969116)
			(xy 106.90822 -315.958986) (xy 106.963954 -315.956949) (xy 107.019391 -315.963049) (xy 107.073348 -315.977155)
			(xy 107.124677 -315.998967) (xy 107.172283 -316.028021) (xy 107.215151 -316.063696) (xy 107.252368 -316.105233)
			(xy 107.283141 -316.151746) (xy 107.306813 -316.202243) (xy 107.322881 -316.25565) (xy 107.331001 -316.310826)
			(xy 107.33151 -316.338712) (xy 107.583984 -316.338712) (xy 107.588055 -316.28309) (xy 107.600181 -316.228653)
			(xy 107.620104 -316.176562) (xy 107.6474 -316.127927) (xy 107.681486 -316.083784) (xy 107.721635 -316.045075)
			(xy 107.766993 -316.012624) (xy 107.816593 -315.987123) (xy 107.869377 -315.969116) (xy 107.92422 -315.958986)
			(xy 107.979954 -315.956949) (xy 108.035391 -315.963049) (xy 108.089348 -315.977155) (xy 108.140677 -315.998967)
			(xy 108.188283 -316.028021) (xy 108.231151 -316.063696) (xy 108.268368 -316.105233) (xy 108.299141 -316.151746)
			(xy 108.322813 -316.202243) (xy 108.338881 -316.25565) (xy 108.347001 -316.310826) (xy 108.34751 -316.338712)
			(xy 108.599984 -316.338712) (xy 108.604055 -316.28309) (xy 108.616181 -316.228653) (xy 108.636104 -316.176562)
			(xy 108.6634 -316.127927) (xy 108.697486 -316.083784) (xy 108.737635 -316.045075) (xy 108.782993 -316.012624)
			(xy 108.832593 -315.987123) (xy 108.885377 -315.969116) (xy 108.94022 -315.958986) (xy 108.995954 -315.956949)
			(xy 109.051391 -315.963049) (xy 109.105348 -315.977155) (xy 109.156677 -315.998967) (xy 109.204283 -316.028021)
			(xy 109.247151 -316.063696) (xy 109.284368 -316.105233) (xy 109.315141 -316.151746) (xy 109.338813 -316.202243)
			(xy 109.354881 -316.25565) (xy 109.363001 -316.310826) (xy 109.36351 -316.338712) (xy 109.615984 -316.338712)
			(xy 109.620055 -316.28309) (xy 109.632181 -316.228653) (xy 109.652104 -316.176562) (xy 109.6794 -316.127927)
			(xy 109.713486 -316.083784) (xy 109.753635 -316.045075) (xy 109.798993 -316.012624) (xy 109.848593 -315.987123)
			(xy 109.901377 -315.969116) (xy 109.95622 -315.958986) (xy 110.011954 -315.956949) (xy 110.067391 -315.963049)
			(xy 110.121348 -315.977155) (xy 110.172677 -315.998967) (xy 110.220283 -316.028021) (xy 110.263151 -316.063696)
			(xy 110.300368 -316.105233) (xy 110.331141 -316.151746) (xy 110.354813 -316.202243) (xy 110.370881 -316.25565)
			(xy 110.379001 -316.310826) (xy 110.37951 -316.338712) (xy 110.379001 -316.366598) (xy 110.370881 -316.421774)
			(xy 110.354813 -316.475181) (xy 110.331141 -316.525678) (xy 110.300368 -316.572191) (xy 110.263151 -316.613728)
			(xy 110.220283 -316.649403) (xy 110.172677 -316.678457) (xy 110.121348 -316.700269) (xy 110.067391 -316.714375)
			(xy 110.011954 -316.720475) (xy 109.95622 -316.718438) (xy 109.901377 -316.708308) (xy 109.848593 -316.690301)
			(xy 109.798993 -316.6648) (xy 109.753635 -316.632349) (xy 109.713486 -316.59364) (xy 109.6794 -316.549497)
			(xy 109.652104 -316.500862) (xy 109.632181 -316.448771) (xy 109.620055 -316.394334) (xy 109.615984 -316.338712)
			(xy 109.36351 -316.338712) (xy 109.363001 -316.366598) (xy 109.354881 -316.421774) (xy 109.338813 -316.475181)
			(xy 109.315141 -316.525678) (xy 109.284368 -316.572191) (xy 109.247151 -316.613728) (xy 109.204283 -316.649403)
			(xy 109.156677 -316.678457) (xy 109.105348 -316.700269) (xy 109.051391 -316.714375) (xy 108.995954 -316.720475)
			(xy 108.94022 -316.718438) (xy 108.885377 -316.708308) (xy 108.832593 -316.690301) (xy 108.782993 -316.6648)
			(xy 108.737635 -316.632349) (xy 108.697486 -316.59364) (xy 108.6634 -316.549497) (xy 108.636104 -316.500862)
			(xy 108.616181 -316.448771) (xy 108.604055 -316.394334) (xy 108.599984 -316.338712) (xy 108.34751 -316.338712)
			(xy 108.347001 -316.366598) (xy 108.338881 -316.421774) (xy 108.322813 -316.475181) (xy 108.299141 -316.525678)
			(xy 108.268368 -316.572191) (xy 108.231151 -316.613728) (xy 108.188283 -316.649403) (xy 108.140677 -316.678457)
			(xy 108.089348 -316.700269) (xy 108.035391 -316.714375) (xy 107.979954 -316.720475) (xy 107.92422 -316.718438)
			(xy 107.869377 -316.708308) (xy 107.816593 -316.690301) (xy 107.766993 -316.6648) (xy 107.721635 -316.632349)
			(xy 107.681486 -316.59364) (xy 107.6474 -316.549497) (xy 107.620104 -316.500862) (xy 107.600181 -316.448771)
			(xy 107.588055 -316.394334) (xy 107.583984 -316.338712) (xy 107.33151 -316.338712) (xy 107.331001 -316.366598)
			(xy 107.322881 -316.421774) (xy 107.306813 -316.475181) (xy 107.283141 -316.525678) (xy 107.252368 -316.572191)
			(xy 107.215151 -316.613728) (xy 107.172283 -316.649403) (xy 107.124677 -316.678457) (xy 107.073348 -316.700269)
			(xy 107.019391 -316.714375) (xy 106.963954 -316.720475) (xy 106.90822 -316.718438) (xy 106.853377 -316.708308)
			(xy 106.800593 -316.690301) (xy 106.750993 -316.6648) (xy 106.705635 -316.632349) (xy 106.665486 -316.59364)
			(xy 106.6314 -316.549497) (xy 106.604104 -316.500862) (xy 106.584181 -316.448771) (xy 106.572055 -316.394334)
			(xy 106.567984 -316.338712) (xy 106.31551 -316.338712) (xy 106.315001 -316.366598) (xy 106.306881 -316.421774)
			(xy 106.290813 -316.475181) (xy 106.267141 -316.525678) (xy 106.236368 -316.572191) (xy 106.199151 -316.613728)
			(xy 106.156283 -316.649403) (xy 106.108677 -316.678457) (xy 106.057348 -316.700269) (xy 106.003391 -316.714375)
			(xy 105.947954 -316.720475) (xy 105.89222 -316.718438) (xy 105.837377 -316.708308) (xy 105.784593 -316.690301)
			(xy 105.734993 -316.6648) (xy 105.689635 -316.632349) (xy 105.649486 -316.59364) (xy 105.6154 -316.549497)
			(xy 105.588104 -316.500862) (xy 105.568181 -316.448771) (xy 105.556055 -316.394334) (xy 105.551984 -316.338712)
			(xy 105.29951 -316.338712) (xy 105.299001 -316.366598) (xy 105.290881 -316.421774) (xy 105.274813 -316.475181)
			(xy 105.251141 -316.525678) (xy 105.220368 -316.572191) (xy 105.183151 -316.613728) (xy 105.140283 -316.649403)
			(xy 105.092677 -316.678457) (xy 105.041348 -316.700269) (xy 104.987391 -316.714375) (xy 104.931954 -316.720475)
			(xy 104.87622 -316.718438) (xy 104.821377 -316.708308) (xy 104.768593 -316.690301) (xy 104.718993 -316.6648)
			(xy 104.673635 -316.632349) (xy 104.633486 -316.59364) (xy 104.5994 -316.549497) (xy 104.572104 -316.500862)
			(xy 104.552181 -316.448771) (xy 104.540055 -316.394334) (xy 104.535984 -316.338712) (xy 104.28351 -316.338712)
			(xy 104.283001 -316.366598) (xy 104.274881 -316.421774) (xy 104.258813 -316.475181) (xy 104.235141 -316.525678)
			(xy 104.204368 -316.572191) (xy 104.167151 -316.613728) (xy 104.124283 -316.649403) (xy 104.076677 -316.678457)
			(xy 104.025348 -316.700269) (xy 103.971391 -316.714375) (xy 103.915954 -316.720475) (xy 103.86022 -316.718438)
			(xy 103.805377 -316.708308) (xy 103.752593 -316.690301) (xy 103.702993 -316.6648) (xy 103.657635 -316.632349)
			(xy 103.617486 -316.59364) (xy 103.5834 -316.549497) (xy 103.556104 -316.500862) (xy 103.536181 -316.448771)
			(xy 103.524055 -316.394334) (xy 103.519984 -316.338712) (xy 103.26751 -316.338712) (xy 103.267001 -316.366598)
			(xy 103.258881 -316.421774) (xy 103.242813 -316.475181) (xy 103.219141 -316.525678) (xy 103.188368 -316.572191)
			(xy 103.151151 -316.613728) (xy 103.108283 -316.649403) (xy 103.060677 -316.678457) (xy 103.009348 -316.700269)
			(xy 102.955391 -316.714375) (xy 102.899954 -316.720475) (xy 102.84422 -316.718438) (xy 102.789377 -316.708308)
			(xy 102.736593 -316.690301) (xy 102.686993 -316.6648) (xy 102.641635 -316.632349) (xy 102.601486 -316.59364)
			(xy 102.5674 -316.549497) (xy 102.540104 -316.500862) (xy 102.520181 -316.448771) (xy 102.508055 -316.394334)
			(xy 102.503984 -316.338712) (xy 100.33 -316.338712) (xy 100.33 -320.08064) (xy 106.2228 -320.08064)
			(xy 106.223347 -320.051724) (xy 106.23207 -319.994554) (xy 106.249322 -319.939356) (xy 106.274709 -319.887394)
			(xy 106.307647 -319.83986) (xy 106.347383 -319.797841) (xy 106.369866 -319.77965) (xy 106.378652 -319.772023)
			(xy 106.388844 -319.751137) (xy 106.389424 -319.739518) (xy 106.389424 -319.659762) (xy 106.388919 -319.648125)
			(xy 106.378709 -319.627214) (xy 106.369866 -319.61963) (xy 106.34739 -319.601431) (xy 106.307656 -319.559412)
			(xy 106.274717 -319.511878) (xy 106.249328 -319.459919) (xy 106.232069 -319.404723) (xy 106.223337 -319.347555)
			(xy 106.2228 -319.31864) (xy 106.223293 -319.291388) (xy 106.231044 -319.237437) (xy 106.246396 -319.18514)
			(xy 106.269034 -319.135559) (xy 106.298499 -319.089705) (xy 106.334189 -319.048512) (xy 106.37538 -319.012818)
			(xy 106.421231 -318.983349) (xy 106.47081 -318.960707) (xy 106.523106 -318.945351) (xy 106.577056 -318.937595)
			(xy 106.604308 -318.937132) (xy 106.633223 -318.937704) (xy 106.690392 -318.946421) (xy 106.74559 -318.963667)
			(xy 106.797553 -318.989048) (xy 106.845088 -319.021983) (xy 106.887106 -319.061716) (xy 106.905298 -319.084198)
			(xy 106.912916 -319.092994) (xy 106.933808 -319.103184) (xy 106.94543 -319.103756) (xy 107.025186 -319.103756)
			(xy 107.036817 -319.10321) (xy 107.057728 -319.093028) (xy 107.065318 -319.084198) (xy 107.082071 -319.063415)
			(xy 107.120425 -319.026285) (xy 107.163579 -318.994863) (xy 107.210693 -318.969764) (xy 107.260845 -318.951478)
			(xy 107.313056 -318.940361) (xy 107.366308 -318.936631) (xy 107.41956 -318.940361) (xy 107.471771 -318.951478)
			(xy 107.521923 -318.969764) (xy 107.569037 -318.994863) (xy 107.612191 -319.026285) (xy 107.650545 -319.063415)
			(xy 107.667298 -319.084198) (xy 107.674916 -319.092994) (xy 107.695808 -319.103184) (xy 107.70743 -319.103756)
			(xy 107.787186 -319.103756) (xy 107.798817 -319.10321) (xy 107.819728 -319.093028) (xy 107.827318 -319.084198)
			(xy 107.844071 -319.063415) (xy 107.882425 -319.026285) (xy 107.925579 -318.994863) (xy 107.972693 -318.969764)
			(xy 108.022845 -318.951478) (xy 108.075056 -318.940361) (xy 108.128308 -318.936631) (xy 108.18156 -318.940361)
			(xy 108.233771 -318.951478) (xy 108.283923 -318.969764) (xy 108.331037 -318.994863) (xy 108.374191 -319.026285)
			(xy 108.412545 -319.063415) (xy 108.429298 -319.084198) (xy 108.436916 -319.092994) (xy 108.457808 -319.103184)
			(xy 108.46943 -319.103756) (xy 108.549186 -319.103756) (xy 108.560817 -319.10321) (xy 108.581728 -319.093028)
			(xy 108.589318 -319.084198) (xy 108.606071 -319.063415) (xy 108.644425 -319.026285) (xy 108.687579 -318.994863)
			(xy 108.734693 -318.969764) (xy 108.784845 -318.951478) (xy 108.837056 -318.940361) (xy 108.890308 -318.936631)
			(xy 108.94356 -318.940361) (xy 108.995771 -318.951478) (xy 109.045923 -318.969764) (xy 109.093037 -318.994863)
			(xy 109.136191 -319.026285) (xy 109.174545 -319.063415) (xy 109.191298 -319.084198) (xy 109.198916 -319.092994)
			(xy 109.219808 -319.103184) (xy 109.23143 -319.103756) (xy 109.311186 -319.103756) (xy 109.322817 -319.10321)
			(xy 109.343728 -319.093028) (xy 109.351318 -319.084198) (xy 109.368071 -319.063415) (xy 109.406425 -319.026285)
			(xy 109.449579 -318.994863) (xy 109.496693 -318.969764) (xy 109.546845 -318.951478) (xy 109.599056 -318.940361)
			(xy 109.652308 -318.936631) (xy 109.70556 -318.940361) (xy 109.757771 -318.951478) (xy 109.807923 -318.969764)
			(xy 109.855037 -318.994863) (xy 109.898191 -319.026285) (xy 109.936545 -319.063415) (xy 109.953298 -319.084198)
			(xy 109.960916 -319.092994) (xy 109.981808 -319.103184) (xy 109.99343 -319.103756) (xy 110.073186 -319.103756)
			(xy 110.084817 -319.10321) (xy 110.105728 -319.093028) (xy 110.113318 -319.084198) (xy 110.130071 -319.063415)
			(xy 110.168425 -319.026285) (xy 110.211579 -318.994863) (xy 110.258693 -318.969764) (xy 110.308845 -318.951478)
			(xy 110.361056 -318.940361) (xy 110.414308 -318.936631) (xy 110.46756 -318.940361) (xy 110.519771 -318.951478)
			(xy 110.569923 -318.969764) (xy 110.617037 -318.994863) (xy 110.660191 -319.026285) (xy 110.698545 -319.063415)
			(xy 110.715298 -319.084198) (xy 110.722916 -319.092994) (xy 110.743808 -319.103184) (xy 110.75543 -319.103756)
			(xy 110.835186 -319.103756) (xy 110.846817 -319.10321) (xy 110.867728 -319.093028) (xy 110.875318 -319.084198)
			(xy 110.892071 -319.063415) (xy 110.930425 -319.026285) (xy 110.973579 -318.994863) (xy 111.020693 -318.969764)
			(xy 111.070845 -318.951478) (xy 111.123056 -318.940361) (xy 111.176308 -318.936631) (xy 111.22956 -318.940361)
			(xy 111.281771 -318.951478) (xy 111.331923 -318.969764) (xy 111.379037 -318.994863) (xy 111.422191 -319.026285)
			(xy 111.460545 -319.063415) (xy 111.477298 -319.084198) (xy 111.484916 -319.092994) (xy 111.505808 -319.103184)
			(xy 111.51743 -319.103756) (xy 111.597186 -319.103756) (xy 111.608817 -319.10321) (xy 111.629728 -319.093028)
			(xy 111.637318 -319.084198) (xy 111.654071 -319.063415) (xy 111.692425 -319.026285) (xy 111.735579 -318.994863)
			(xy 111.782693 -318.969764) (xy 111.832845 -318.951478) (xy 111.885056 -318.940361) (xy 111.938308 -318.936631)
			(xy 111.99156 -318.940361) (xy 112.043771 -318.951478) (xy 112.093923 -318.969764) (xy 112.141037 -318.994863)
			(xy 112.184191 -319.026285) (xy 112.222545 -319.063415) (xy 112.239298 -319.084198) (xy 112.246916 -319.092994)
			(xy 112.267808 -319.103184) (xy 112.27943 -319.103756) (xy 112.359186 -319.103756) (xy 112.370817 -319.10321)
			(xy 112.391728 -319.093028) (xy 112.399318 -319.084198) (xy 112.416071 -319.063415) (xy 112.454425 -319.026285)
			(xy 112.497579 -318.994863) (xy 112.544693 -318.969764) (xy 112.594845 -318.951478) (xy 112.647056 -318.940361)
			(xy 112.700308 -318.936631) (xy 112.75356 -318.940361) (xy 112.805771 -318.951478) (xy 112.855923 -318.969764)
			(xy 112.903037 -318.994863) (xy 112.946191 -319.026285) (xy 112.984545 -319.063415) (xy 113.001298 -319.084198)
			(xy 113.008916 -319.092994) (xy 113.029808 -319.103184) (xy 113.04143 -319.103756) (xy 113.121186 -319.103756)
			(xy 113.132817 -319.10321) (xy 113.153728 -319.093028) (xy 113.161318 -319.084198) (xy 113.178071 -319.063415)
			(xy 113.216425 -319.026285) (xy 113.259579 -318.994863) (xy 113.306693 -318.969764) (xy 113.356845 -318.951478)
			(xy 113.409056 -318.940361) (xy 113.462308 -318.936631) (xy 113.51556 -318.940361) (xy 113.567771 -318.951478)
			(xy 113.617923 -318.969764) (xy 113.665037 -318.994863) (xy 113.708191 -319.026285) (xy 113.746545 -319.063415)
			(xy 113.763298 -319.084198) (xy 113.770916 -319.092994) (xy 113.791808 -319.103184) (xy 113.80343 -319.103756)
			(xy 113.883186 -319.103756) (xy 113.894817 -319.10321) (xy 113.915728 -319.093028) (xy 113.923318 -319.084198)
			(xy 113.941498 -319.061705) (xy 113.98352 -319.021971) (xy 114.031058 -318.989033) (xy 114.083021 -318.963646)
			(xy 114.13822 -318.946392) (xy 114.195391 -318.937666) (xy 114.224308 -318.937132) (xy 114.251563 -318.937548)
			(xy 114.305518 -318.945307) (xy 114.357819 -318.960666) (xy 114.407402 -318.983313) (xy 114.453257 -319.012785)
			(xy 114.49445 -319.048484) (xy 114.530144 -319.089682) (xy 114.559611 -319.135541) (xy 114.582251 -319.185126)
			(xy 114.597603 -319.237429) (xy 114.605355 -319.291385) (xy 114.605816 -319.31864) (xy 114.605286 -319.347557)
			(xy 114.596564 -319.404729) (xy 114.57931 -319.459929) (xy 114.553921 -319.511891) (xy 114.520978 -319.559425)
			(xy 114.481236 -319.601441) (xy 114.45875 -319.61963) (xy 114.449931 -319.627225) (xy 114.439756 -319.648135)
			(xy 114.439192 -319.659762) (xy 114.439192 -319.739518) (xy 114.439738 -319.751149) (xy 114.449922 -319.772058)
			(xy 114.45875 -319.77965) (xy 114.48122 -319.797857) (xy 114.520954 -319.839875) (xy 114.553893 -319.887407)
			(xy 114.579283 -319.939365) (xy 114.596543 -319.994559) (xy 114.605278 -320.051725) (xy 114.605816 -320.08064)
			(xy 119.41683 -320.08064) (xy 119.417366 -320.051724) (xy 119.426089 -319.994553) (xy 119.443343 -319.939354)
			(xy 119.468732 -319.887392) (xy 119.501673 -319.839857) (xy 119.541411 -319.79784) (xy 119.563896 -319.77965)
			(xy 119.57267 -319.772011) (xy 119.582872 -319.751134) (xy 119.583454 -319.739518) (xy 119.583454 -319.659762)
			(xy 119.582939 -319.648127) (xy 119.572735 -319.627216) (xy 119.563896 -319.61963) (xy 119.541426 -319.601423)
			(xy 119.50169 -319.559407) (xy 119.46875 -319.511875) (xy 119.443359 -319.459917) (xy 119.4261 -319.404722)
			(xy 119.417367 -319.347555) (xy 119.41683 -319.31864) (xy 119.417293 -319.291386) (xy 119.425045 -319.237433)
			(xy 119.440398 -319.185133) (xy 119.463039 -319.135551) (xy 119.492506 -319.089696) (xy 119.5282 -319.048501)
			(xy 119.569394 -319.012807) (xy 119.615249 -318.98334) (xy 119.664831 -318.960699) (xy 119.717132 -318.945346)
			(xy 119.771084 -318.937593) (xy 119.798338 -318.937132) (xy 119.827254 -318.937683) (xy 119.884424 -318.946403)
			(xy 119.939623 -318.963654) (xy 119.991585 -318.989039) (xy 120.03912 -319.021978) (xy 120.081137 -319.061714)
			(xy 120.099328 -319.084198) (xy 120.106933 -319.093008) (xy 120.127835 -319.10319) (xy 120.13946 -319.103756)
			(xy 120.219216 -319.103756) (xy 120.23085 -319.103227) (xy 120.25176 -319.093033) (xy 120.259348 -319.084198)
			(xy 120.276101 -319.063415) (xy 120.314455 -319.026285) (xy 120.357609 -318.994863) (xy 120.404723 -318.969764)
			(xy 120.454875 -318.951478) (xy 120.507086 -318.940361) (xy 120.560338 -318.936631) (xy 120.61359 -318.940361)
			(xy 120.665801 -318.951478) (xy 120.715953 -318.969764) (xy 120.763067 -318.994863) (xy 120.806221 -319.026285)
			(xy 120.844575 -319.063415) (xy 120.861328 -319.084198) (xy 120.868933 -319.093008) (xy 120.889835 -319.10319)
			(xy 120.90146 -319.103756) (xy 120.981216 -319.103756) (xy 120.99285 -319.103227) (xy 121.01376 -319.093033)
			(xy 121.021348 -319.084198) (xy 121.038101 -319.063415) (xy 121.076455 -319.026285) (xy 121.119609 -318.994863)
			(xy 121.166723 -318.969764) (xy 121.216875 -318.951478) (xy 121.269086 -318.940361) (xy 121.322338 -318.936631)
			(xy 121.37559 -318.940361) (xy 121.427801 -318.951478) (xy 121.477953 -318.969764) (xy 121.525067 -318.994863)
			(xy 121.568221 -319.026285) (xy 121.606575 -319.063415) (xy 121.623328 -319.084198) (xy 121.630933 -319.093008)
			(xy 121.651835 -319.10319) (xy 121.66346 -319.103756) (xy 121.743216 -319.103756) (xy 121.75485 -319.103227)
			(xy 121.77576 -319.093033) (xy 121.783348 -319.084198) (xy 121.800101 -319.063415) (xy 121.838455 -319.026285)
			(xy 121.881609 -318.994863) (xy 121.928723 -318.969764) (xy 121.978875 -318.951478) (xy 122.031086 -318.940361)
			(xy 122.084338 -318.936631) (xy 122.13759 -318.940361) (xy 122.189801 -318.951478) (xy 122.239953 -318.969764)
			(xy 122.287067 -318.994863) (xy 122.330221 -319.026285) (xy 122.368575 -319.063415) (xy 122.385328 -319.084198)
			(xy 122.392933 -319.093008) (xy 122.413835 -319.10319) (xy 122.42546 -319.103756) (xy 122.505216 -319.103756)
			(xy 122.51685 -319.103227) (xy 122.53776 -319.093033) (xy 122.545348 -319.084198) (xy 122.562101 -319.063415)
			(xy 122.600455 -319.026285) (xy 122.643609 -318.994863) (xy 122.690723 -318.969764) (xy 122.740875 -318.951478)
			(xy 122.793086 -318.940361) (xy 122.846338 -318.936631) (xy 122.89959 -318.940361) (xy 122.951801 -318.951478)
			(xy 123.001953 -318.969764) (xy 123.049067 -318.994863) (xy 123.092221 -319.026285) (xy 123.130575 -319.063415)
			(xy 123.147328 -319.084198) (xy 123.154933 -319.093008) (xy 123.175835 -319.10319) (xy 123.18746 -319.103756)
			(xy 123.267216 -319.103756) (xy 123.27885 -319.103227) (xy 123.29976 -319.093033) (xy 123.307348 -319.084198)
			(xy 123.324101 -319.063415) (xy 123.362455 -319.026285) (xy 123.405609 -318.994863) (xy 123.452723 -318.969764)
			(xy 123.502875 -318.951478) (xy 123.555086 -318.940361) (xy 123.608338 -318.936631) (xy 123.66159 -318.940361)
			(xy 123.713801 -318.951478) (xy 123.763953 -318.969764) (xy 123.811067 -318.994863) (xy 123.854221 -319.026285)
			(xy 123.892575 -319.063415) (xy 123.909328 -319.084198) (xy 123.916933 -319.093008) (xy 123.937835 -319.10319)
			(xy 123.94946 -319.103756) (xy 124.029216 -319.103756) (xy 124.04085 -319.103227) (xy 124.06176 -319.093033)
			(xy 124.069348 -319.084198) (xy 124.086101 -319.063415) (xy 124.124455 -319.026285) (xy 124.167609 -318.994863)
			(xy 124.214723 -318.969764) (xy 124.264875 -318.951478) (xy 124.317086 -318.940361) (xy 124.370338 -318.936631)
			(xy 124.42359 -318.940361) (xy 124.475801 -318.951478) (xy 124.525953 -318.969764) (xy 124.573067 -318.994863)
			(xy 124.616221 -319.026285) (xy 124.654575 -319.063415) (xy 124.671328 -319.084198) (xy 124.678933 -319.093008)
			(xy 124.699835 -319.10319) (xy 124.71146 -319.103756) (xy 124.791216 -319.103756) (xy 124.80285 -319.103227)
			(xy 124.82376 -319.093033) (xy 124.831348 -319.084198) (xy 124.848101 -319.063415) (xy 124.886455 -319.026285)
			(xy 124.929609 -318.994863) (xy 124.976723 -318.969764) (xy 125.026875 -318.951478) (xy 125.079086 -318.940361)
			(xy 125.132338 -318.936631) (xy 125.18559 -318.940361) (xy 125.237801 -318.951478) (xy 125.287953 -318.969764)
			(xy 125.335067 -318.994863) (xy 125.378221 -319.026285) (xy 125.416575 -319.063415) (xy 125.433328 -319.084198)
			(xy 125.440933 -319.093008) (xy 125.461835 -319.10319) (xy 125.47346 -319.103756) (xy 125.553216 -319.103756)
			(xy 125.56485 -319.103227) (xy 125.58576 -319.093033) (xy 125.593348 -319.084198) (xy 125.610101 -319.063415)
			(xy 125.648455 -319.026285) (xy 125.691609 -318.994863) (xy 125.738723 -318.969764) (xy 125.788875 -318.951478)
			(xy 125.841086 -318.940361) (xy 125.894338 -318.936631) (xy 125.94759 -318.940361) (xy 125.999801 -318.951478)
			(xy 126.049953 -318.969764) (xy 126.097067 -318.994863) (xy 126.140221 -319.026285) (xy 126.178575 -319.063415)
			(xy 126.195328 -319.084198) (xy 126.202933 -319.093008) (xy 126.223835 -319.10319) (xy 126.23546 -319.103756)
			(xy 126.315216 -319.103756) (xy 126.32685 -319.103227) (xy 126.34776 -319.093033) (xy 126.355348 -319.084198)
			(xy 126.372101 -319.063415) (xy 126.410455 -319.026285) (xy 126.453609 -318.994863) (xy 126.500723 -318.969764)
			(xy 126.550875 -318.951478) (xy 126.603086 -318.940361) (xy 126.656338 -318.936631) (xy 126.70959 -318.940361)
			(xy 126.761801 -318.951478) (xy 126.811953 -318.969764) (xy 126.859067 -318.994863) (xy 126.902221 -319.026285)
			(xy 126.940575 -319.063415) (xy 126.957328 -319.084198) (xy 126.964933 -319.093008) (xy 126.985835 -319.10319)
			(xy 126.99746 -319.103756) (xy 127.077216 -319.103756) (xy 127.08885 -319.103227) (xy 127.10976 -319.093033)
			(xy 127.117348 -319.084198) (xy 127.134101 -319.063415) (xy 127.172455 -319.026285) (xy 127.215609 -318.994863)
			(xy 127.262723 -318.969764) (xy 127.312875 -318.951478) (xy 127.365086 -318.940361) (xy 127.418338 -318.936631)
			(xy 127.47159 -318.940361) (xy 127.523801 -318.951478) (xy 127.573953 -318.969764) (xy 127.621067 -318.994863)
			(xy 127.664221 -319.026285) (xy 127.702575 -319.063415) (xy 127.719328 -319.084198) (xy 127.726933 -319.093008)
			(xy 127.747835 -319.10319) (xy 127.75946 -319.103756) (xy 127.839216 -319.103756) (xy 127.85085 -319.103227)
			(xy 127.87176 -319.093033) (xy 127.879348 -319.084198) (xy 127.897568 -319.061739) (xy 127.939582 -319.022002)
			(xy 127.987111 -318.989061) (xy 128.039066 -318.963668) (xy 128.094259 -318.946406) (xy 128.151424 -318.937671)
			(xy 128.180338 -318.937132) (xy 128.21046 -318.937747) (xy 128.269954 -318.947218) (xy 128.327221 -318.965919)
			(xy 128.380839 -318.993385) (xy 128.429475 -319.028934) (xy 128.451102 -319.049908) (xy 128.458506 -319.056742)
			(xy 128.477102 -319.064465) (xy 128.48717 -319.064894) (xy 128.559306 -319.064894) (xy 128.569376 -319.064473)
			(xy 128.587974 -319.056749) (xy 128.595374 -319.049908) (xy 128.616988 -319.028916) (xy 128.66562 -318.993349)
			(xy 128.719239 -318.965871) (xy 128.776512 -318.947166) (xy 128.836013 -318.937698) (xy 128.866138 -318.937132)
			(xy 128.893394 -318.93752) (xy 128.947349 -318.945283) (xy 128.999651 -318.960646) (xy 129.049234 -318.983296)
			(xy 129.095089 -319.012771) (xy 129.136282 -319.048473) (xy 129.171975 -319.089673) (xy 129.201442 -319.135534)
			(xy 129.224082 -319.185122) (xy 129.239434 -319.237427) (xy 129.247186 -319.291384) (xy 129.247646 -319.31864)
			(xy 129.247105 -319.347556) (xy 129.238383 -319.404727) (xy 129.221131 -319.459927) (xy 129.195744 -319.511889)
			(xy 129.162803 -319.559423) (xy 129.123064 -319.60144) (xy 129.10058 -319.61963) (xy 129.091766 -319.62723)
			(xy 129.081587 -319.648136) (xy 129.081022 -319.659762) (xy 129.081022 -319.739518) (xy 129.081557 -319.751151)
			(xy 129.091748 -319.772061) (xy 129.10058 -319.77965) (xy 129.123035 -319.797874) (xy 129.162773 -319.839887)
			(xy 129.195716 -319.887414) (xy 129.221109 -319.939369) (xy 129.238372 -319.994561) (xy 129.247107 -320.051726)
			(xy 129.247646 -320.08064) (xy 129.24716 -320.107891) (xy 129.239399 -320.161836) (xy 129.22404 -320.214129)
			(xy 129.201397 -320.263703) (xy 129.17193 -320.309552) (xy 129.136239 -320.350741) (xy 129.09505 -320.386432)
			(xy 129.049202 -320.415898) (xy 128.999627 -320.438541) (xy 128.947334 -320.453899) (xy 128.893389 -320.46166)
			(xy 128.866138 -320.462148) (xy 128.836016 -320.461554) (xy 128.77652 -320.452079) (xy 128.719252 -320.433373)
			(xy 128.665635 -320.405903) (xy 128.617 -320.370349) (xy 128.595374 -320.349372) (xy 128.58798 -320.342524)
			(xy 128.569376 -320.33481) (xy 128.559306 -320.334386) (xy 128.48717 -320.334386) (xy 128.477096 -320.334773)
			(xy 128.458497 -320.342518) (xy 128.451102 -320.349372) (xy 128.429495 -320.370372) (xy 128.380862 -320.405938)
			(xy 128.327241 -320.433415) (xy 128.269967 -320.452119) (xy 128.210464 -320.461584) (xy 128.180338 -320.462148)
			(xy 128.151421 -320.461622) (xy 128.094249 -320.452898) (xy 128.03905 -320.435642) (xy 127.987088 -320.410252)
			(xy 127.939554 -320.377309) (xy 127.897537 -320.337568) (xy 127.879348 -320.315082) (xy 127.871713 -320.306303)
			(xy 127.850833 -320.296105) (xy 127.839216 -320.295524) (xy 127.75946 -320.295524) (xy 127.747826 -320.296046)
			(xy 127.726916 -320.306246) (xy 127.719328 -320.315082) (xy 127.702575 -320.335865) (xy 127.664221 -320.372995)
			(xy 127.621067 -320.404417) (xy 127.573953 -320.429516) (xy 127.523801 -320.447802) (xy 127.47159 -320.458919)
			(xy 127.418338 -320.462649) (xy 127.365086 -320.458919) (xy 127.312875 -320.447802) (xy 127.262723 -320.429516)
			(xy 127.215609 -320.404417) (xy 127.172455 -320.372995) (xy 127.134101 -320.335865) (xy 127.117348 -320.315082)
			(xy 127.109713 -320.306303) (xy 127.088833 -320.296105) (xy 127.077216 -320.295524) (xy 126.99746 -320.295524)
			(xy 126.985826 -320.296046) (xy 126.964916 -320.306246) (xy 126.957328 -320.315082) (xy 126.940575 -320.335865)
			(xy 126.902221 -320.372995) (xy 126.859067 -320.404417) (xy 126.811953 -320.429516) (xy 126.761801 -320.447802)
			(xy 126.70959 -320.458919) (xy 126.656338 -320.462649) (xy 126.603086 -320.458919) (xy 126.550875 -320.447802)
			(xy 126.500723 -320.429516) (xy 126.453609 -320.404417) (xy 126.410455 -320.372995) (xy 126.372101 -320.335865)
			(xy 126.355348 -320.315082) (xy 126.347713 -320.306303) (xy 126.326833 -320.296105) (xy 126.315216 -320.295524)
			(xy 126.23546 -320.295524) (xy 126.223826 -320.296046) (xy 126.202916 -320.306246) (xy 126.195328 -320.315082)
			(xy 126.178575 -320.335865) (xy 126.140221 -320.372995) (xy 126.097067 -320.404417) (xy 126.049953 -320.429516)
			(xy 125.999801 -320.447802) (xy 125.94759 -320.458919) (xy 125.894338 -320.462649) (xy 125.841086 -320.458919)
			(xy 125.788875 -320.447802) (xy 125.738723 -320.429516) (xy 125.691609 -320.404417) (xy 125.648455 -320.372995)
			(xy 125.610101 -320.335865) (xy 125.593348 -320.315082) (xy 125.585713 -320.306303) (xy 125.564833 -320.296105)
			(xy 125.553216 -320.295524) (xy 125.47346 -320.295524) (xy 125.461826 -320.296046) (xy 125.440916 -320.306246)
			(xy 125.433328 -320.315082) (xy 125.416575 -320.335865) (xy 125.378221 -320.372995) (xy 125.335067 -320.404417)
			(xy 125.287953 -320.429516) (xy 125.237801 -320.447802) (xy 125.18559 -320.458919) (xy 125.132338 -320.462649)
			(xy 125.079086 -320.458919) (xy 125.026875 -320.447802) (xy 124.976723 -320.429516) (xy 124.929609 -320.404417)
			(xy 124.886455 -320.372995) (xy 124.848101 -320.335865) (xy 124.831348 -320.315082) (xy 124.823713 -320.306303)
			(xy 124.802833 -320.296105) (xy 124.791216 -320.295524) (xy 124.71146 -320.295524) (xy 124.699826 -320.296046)
			(xy 124.678916 -320.306246) (xy 124.671328 -320.315082) (xy 124.654575 -320.335865) (xy 124.616221 -320.372995)
			(xy 124.573067 -320.404417) (xy 124.525953 -320.429516) (xy 124.475801 -320.447802) (xy 124.42359 -320.458919)
			(xy 124.370338 -320.462649) (xy 124.317086 -320.458919) (xy 124.264875 -320.447802) (xy 124.214723 -320.429516)
			(xy 124.167609 -320.404417) (xy 124.124455 -320.372995) (xy 124.086101 -320.335865) (xy 124.069348 -320.315082)
			(xy 124.061713 -320.306303) (xy 124.040833 -320.296105) (xy 124.029216 -320.295524) (xy 123.94946 -320.295524)
			(xy 123.937826 -320.296046) (xy 123.916916 -320.306246) (xy 123.909328 -320.315082) (xy 123.892575 -320.335865)
			(xy 123.854221 -320.372995) (xy 123.811067 -320.404417) (xy 123.763953 -320.429516) (xy 123.713801 -320.447802)
			(xy 123.66159 -320.458919) (xy 123.608338 -320.462649) (xy 123.555086 -320.458919) (xy 123.502875 -320.447802)
			(xy 123.452723 -320.429516) (xy 123.405609 -320.404417) (xy 123.362455 -320.372995) (xy 123.324101 -320.335865)
			(xy 123.307348 -320.315082) (xy 123.299713 -320.306303) (xy 123.278833 -320.296105) (xy 123.267216 -320.295524)
			(xy 123.18746 -320.295524) (xy 123.175826 -320.296046) (xy 123.154916 -320.306246) (xy 123.147328 -320.315082)
			(xy 123.130575 -320.335865) (xy 123.092221 -320.372995) (xy 123.049067 -320.404417) (xy 123.001953 -320.429516)
			(xy 122.951801 -320.447802) (xy 122.89959 -320.458919) (xy 122.846338 -320.462649) (xy 122.793086 -320.458919)
			(xy 122.740875 -320.447802) (xy 122.690723 -320.429516) (xy 122.643609 -320.404417) (xy 122.600455 -320.372995)
			(xy 122.562101 -320.335865) (xy 122.545348 -320.315082) (xy 122.537713 -320.306303) (xy 122.516833 -320.296105)
			(xy 122.505216 -320.295524) (xy 122.42546 -320.295524) (xy 122.413826 -320.296046) (xy 122.392916 -320.306246)
			(xy 122.385328 -320.315082) (xy 122.368575 -320.335865) (xy 122.330221 -320.372995) (xy 122.287067 -320.404417)
			(xy 122.239953 -320.429516) (xy 122.189801 -320.447802) (xy 122.13759 -320.458919) (xy 122.084338 -320.462649)
			(xy 122.031086 -320.458919) (xy 121.978875 -320.447802) (xy 121.928723 -320.429516) (xy 121.881609 -320.404417)
			(xy 121.838455 -320.372995) (xy 121.800101 -320.335865) (xy 121.783348 -320.315082) (xy 121.775713 -320.306303)
			(xy 121.754833 -320.296105) (xy 121.743216 -320.295524) (xy 121.66346 -320.295524) (xy 121.651826 -320.296046)
			(xy 121.630916 -320.306246) (xy 121.623328 -320.315082) (xy 121.606575 -320.335865) (xy 121.568221 -320.372995)
			(xy 121.525067 -320.404417) (xy 121.477953 -320.429516) (xy 121.427801 -320.447802) (xy 121.37559 -320.458919)
			(xy 121.322338 -320.462649) (xy 121.269086 -320.458919) (xy 121.216875 -320.447802) (xy 121.166723 -320.429516)
			(xy 121.119609 -320.404417) (xy 121.076455 -320.372995) (xy 121.038101 -320.335865) (xy 121.021348 -320.315082)
			(xy 121.013713 -320.306303) (xy 120.992833 -320.296105) (xy 120.981216 -320.295524) (xy 120.90146 -320.295524)
			(xy 120.889826 -320.296046) (xy 120.868916 -320.306246) (xy 120.861328 -320.315082) (xy 120.844575 -320.335865)
			(xy 120.806221 -320.372995) (xy 120.763067 -320.404417) (xy 120.715953 -320.429516) (xy 120.665801 -320.447802)
			(xy 120.61359 -320.458919) (xy 120.560338 -320.462649) (xy 120.507086 -320.458919) (xy 120.454875 -320.447802)
			(xy 120.404723 -320.429516) (xy 120.357609 -320.404417) (xy 120.314455 -320.372995) (xy 120.276101 -320.335865)
			(xy 120.259348 -320.315082) (xy 120.251713 -320.306303) (xy 120.230833 -320.296105) (xy 120.219216 -320.295524)
			(xy 120.13946 -320.295524) (xy 120.127826 -320.296046) (xy 120.106916 -320.306246) (xy 120.099328 -320.315082)
			(xy 120.081117 -320.337548) (xy 120.039102 -320.377285) (xy 119.991571 -320.410227) (xy 119.939614 -320.435618)
			(xy 119.88442 -320.452878) (xy 119.827253 -320.461611) (xy 119.798338 -320.462148) (xy 119.77109 -320.461587)
			(xy 119.717147 -320.453836) (xy 119.664856 -320.438488) (xy 119.615281 -320.415854) (xy 119.569433 -320.386396)
			(xy 119.528243 -320.350712) (xy 119.492551 -320.30953) (xy 119.463083 -320.263687) (xy 119.440439 -320.214117)
			(xy 119.42508 -320.16183) (xy 119.417319 -320.107888) (xy 119.41683 -320.08064) (xy 114.605816 -320.08064)
			(xy 114.605359 -320.107892) (xy 114.597598 -320.16184) (xy 114.582238 -320.214135) (xy 114.559593 -320.263712)
			(xy 114.530123 -320.309562) (xy 114.494429 -320.350751) (xy 114.453236 -320.386442) (xy 114.407384 -320.415908)
			(xy 114.357805 -320.438549) (xy 114.305509 -320.453904) (xy 114.25156 -320.461662) (xy 114.224308 -320.462148)
			(xy 114.19539 -320.461644) (xy 114.138218 -320.452914) (xy 114.083018 -320.435655) (xy 114.031056 -320.410261)
			(xy 113.983522 -320.377314) (xy 113.941507 -320.337569) (xy 113.923318 -320.315082) (xy 113.915696 -320.30629)
			(xy 113.894807 -320.296099) (xy 113.883186 -320.295524) (xy 113.80343 -320.295524) (xy 113.791801 -320.296086)
			(xy 113.77089 -320.306258) (xy 113.763298 -320.315082) (xy 113.746545 -320.335865) (xy 113.708191 -320.372995)
			(xy 113.665037 -320.404417) (xy 113.617923 -320.429516) (xy 113.567771 -320.447802) (xy 113.51556 -320.458919)
			(xy 113.462308 -320.462649) (xy 113.409056 -320.458919) (xy 113.356845 -320.447802) (xy 113.306693 -320.429516)
			(xy 113.259579 -320.404417) (xy 113.216425 -320.372995) (xy 113.178071 -320.335865) (xy 113.161318 -320.315082)
			(xy 113.153696 -320.30629) (xy 113.132807 -320.296099) (xy 113.121186 -320.295524) (xy 113.04143 -320.295524)
			(xy 113.029801 -320.296086) (xy 113.00889 -320.306258) (xy 113.001298 -320.315082) (xy 112.984545 -320.335865)
			(xy 112.946191 -320.372995) (xy 112.903037 -320.404417) (xy 112.855923 -320.429516) (xy 112.805771 -320.447802)
			(xy 112.75356 -320.458919) (xy 112.700308 -320.462649) (xy 112.647056 -320.458919) (xy 112.594845 -320.447802)
			(xy 112.544693 -320.429516) (xy 112.497579 -320.404417) (xy 112.454425 -320.372995) (xy 112.416071 -320.335865)
			(xy 112.399318 -320.315082) (xy 112.391696 -320.30629) (xy 112.370807 -320.296099) (xy 112.359186 -320.295524)
			(xy 112.27943 -320.295524) (xy 112.267801 -320.296086) (xy 112.24689 -320.306258) (xy 112.239298 -320.315082)
			(xy 112.222545 -320.335865) (xy 112.184191 -320.372995) (xy 112.141037 -320.404417) (xy 112.093923 -320.429516)
			(xy 112.043771 -320.447802) (xy 111.99156 -320.458919) (xy 111.938308 -320.462649) (xy 111.885056 -320.458919)
			(xy 111.832845 -320.447802) (xy 111.782693 -320.429516) (xy 111.735579 -320.404417) (xy 111.692425 -320.372995)
			(xy 111.654071 -320.335865) (xy 111.637318 -320.315082) (xy 111.629696 -320.30629) (xy 111.608807 -320.296099)
			(xy 111.597186 -320.295524) (xy 111.51743 -320.295524) (xy 111.505801 -320.296086) (xy 111.48489 -320.306258)
			(xy 111.477298 -320.315082) (xy 111.460545 -320.335865) (xy 111.422191 -320.372995) (xy 111.379037 -320.404417)
			(xy 111.331923 -320.429516) (xy 111.281771 -320.447802) (xy 111.22956 -320.458919) (xy 111.176308 -320.462649)
			(xy 111.123056 -320.458919) (xy 111.070845 -320.447802) (xy 111.020693 -320.429516) (xy 110.973579 -320.404417)
			(xy 110.930425 -320.372995) (xy 110.892071 -320.335865) (xy 110.875318 -320.315082) (xy 110.867696 -320.30629)
			(xy 110.846807 -320.296099) (xy 110.835186 -320.295524) (xy 110.75543 -320.295524) (xy 110.743801 -320.296086)
			(xy 110.72289 -320.306258) (xy 110.715298 -320.315082) (xy 110.698545 -320.335865) (xy 110.660191 -320.372995)
			(xy 110.617037 -320.404417) (xy 110.569923 -320.429516) (xy 110.519771 -320.447802) (xy 110.46756 -320.458919)
			(xy 110.414308 -320.462649) (xy 110.361056 -320.458919) (xy 110.308845 -320.447802) (xy 110.258693 -320.429516)
			(xy 110.211579 -320.404417) (xy 110.168425 -320.372995) (xy 110.130071 -320.335865) (xy 110.113318 -320.315082)
			(xy 110.105696 -320.30629) (xy 110.084807 -320.296099) (xy 110.073186 -320.295524) (xy 109.99343 -320.295524)
			(xy 109.981801 -320.296086) (xy 109.96089 -320.306258) (xy 109.953298 -320.315082) (xy 109.936545 -320.335865)
			(xy 109.898191 -320.372995) (xy 109.855037 -320.404417) (xy 109.807923 -320.429516) (xy 109.757771 -320.447802)
			(xy 109.70556 -320.458919) (xy 109.652308 -320.462649) (xy 109.599056 -320.458919) (xy 109.546845 -320.447802)
			(xy 109.496693 -320.429516) (xy 109.449579 -320.404417) (xy 109.406425 -320.372995) (xy 109.368071 -320.335865)
			(xy 109.351318 -320.315082) (xy 109.343696 -320.30629) (xy 109.322807 -320.296099) (xy 109.311186 -320.295524)
			(xy 109.23143 -320.295524) (xy 109.219801 -320.296086) (xy 109.19889 -320.306258) (xy 109.191298 -320.315082)
			(xy 109.174545 -320.335865) (xy 109.136191 -320.372995) (xy 109.093037 -320.404417) (xy 109.045923 -320.429516)
			(xy 108.995771 -320.447802) (xy 108.94356 -320.458919) (xy 108.890308 -320.462649) (xy 108.837056 -320.458919)
			(xy 108.784845 -320.447802) (xy 108.734693 -320.429516) (xy 108.687579 -320.404417) (xy 108.644425 -320.372995)
			(xy 108.606071 -320.335865) (xy 108.589318 -320.315082) (xy 108.581696 -320.30629) (xy 108.560807 -320.296099)
			(xy 108.549186 -320.295524) (xy 108.46943 -320.295524) (xy 108.457801 -320.296086) (xy 108.43689 -320.306258)
			(xy 108.429298 -320.315082) (xy 108.412545 -320.335865) (xy 108.374191 -320.372995) (xy 108.331037 -320.404417)
			(xy 108.283923 -320.429516) (xy 108.233771 -320.447802) (xy 108.18156 -320.458919) (xy 108.128308 -320.462649)
			(xy 108.075056 -320.458919) (xy 108.022845 -320.447802) (xy 107.972693 -320.429516) (xy 107.925579 -320.404417)
			(xy 107.882425 -320.372995) (xy 107.844071 -320.335865) (xy 107.827318 -320.315082) (xy 107.819696 -320.30629)
			(xy 107.798807 -320.296099) (xy 107.787186 -320.295524) (xy 107.70743 -320.295524) (xy 107.695801 -320.296086)
			(xy 107.67489 -320.306258) (xy 107.667298 -320.315082) (xy 107.650545 -320.335865) (xy 107.612191 -320.372995)
			(xy 107.569037 -320.404417) (xy 107.521923 -320.429516) (xy 107.471771 -320.447802) (xy 107.41956 -320.458919)
			(xy 107.366308 -320.462649) (xy 107.313056 -320.458919) (xy 107.260845 -320.447802) (xy 107.210693 -320.429516)
			(xy 107.163579 -320.404417) (xy 107.120425 -320.372995) (xy 107.082071 -320.335865) (xy 107.065318 -320.315082)
			(xy 107.057696 -320.30629) (xy 107.036807 -320.296099) (xy 107.025186 -320.295524) (xy 106.94543 -320.295524)
			(xy 106.933801 -320.296086) (xy 106.91289 -320.306258) (xy 106.905298 -320.315082) (xy 106.887104 -320.337563)
			(xy 106.845085 -320.377299) (xy 106.797551 -320.410239) (xy 106.74559 -320.435628) (xy 106.690393 -320.452884)
			(xy 106.633224 -320.461613) (xy 106.604308 -320.462148) (xy 106.577059 -320.461615) (xy 106.523115 -320.453861)
			(xy 106.470823 -320.438508) (xy 106.421249 -320.415871) (xy 106.3754 -320.386409) (xy 106.334211 -320.350723)
			(xy 106.298519 -320.309538) (xy 106.269052 -320.263693) (xy 106.246408 -320.214122) (xy 106.23105 -320.161832)
			(xy 106.223289 -320.107889) (xy 106.2228 -320.08064) (xy 100.33 -320.08064) (xy 100.33 -323.059806)
			(xy 102.316278 -323.059806) (xy 102.320349 -323.004184) (xy 102.332475 -322.949747) (xy 102.352398 -322.897656)
			(xy 102.379694 -322.849021) (xy 102.41378 -322.804878) (xy 102.453929 -322.766169) (xy 102.499287 -322.733718)
			(xy 102.548887 -322.708217) (xy 102.601671 -322.69021) (xy 102.656514 -322.68008) (xy 102.712248 -322.678043)
			(xy 102.767685 -322.684143) (xy 102.821642 -322.698249) (xy 102.872971 -322.720061) (xy 102.920577 -322.749115)
			(xy 102.963445 -322.78479) (xy 103.000662 -322.826327) (xy 103.031435 -322.87284) (xy 103.055107 -322.923337)
			(xy 103.071175 -322.976744) (xy 103.079295 -323.03192) (xy 103.079804 -323.059806) (xy 103.079295 -323.087692)
			(xy 103.071175 -323.142868) (xy 103.055107 -323.196275) (xy 103.031435 -323.246772) (xy 103.000662 -323.293285)
			(xy 102.963445 -323.334822) (xy 102.920577 -323.370497) (xy 102.872971 -323.399551) (xy 102.821642 -323.421363)
			(xy 102.767685 -323.435469) (xy 102.712248 -323.441569) (xy 102.656514 -323.439532) (xy 102.601671 -323.429402)
			(xy 102.548887 -323.411395) (xy 102.499287 -323.385894) (xy 102.453929 -323.353443) (xy 102.41378 -323.314734)
			(xy 102.379694 -323.270591) (xy 102.352398 -323.221956) (xy 102.332475 -323.169865) (xy 102.320349 -323.115428)
			(xy 102.316278 -323.059806) (xy 100.33 -323.059806) (xy 100.33 -324.075806) (xy 102.316278 -324.075806)
			(xy 102.320349 -324.020184) (xy 102.332475 -323.965747) (xy 102.352398 -323.913656) (xy 102.379694 -323.865021)
			(xy 102.41378 -323.820878) (xy 102.453929 -323.782169) (xy 102.499287 -323.749718) (xy 102.548887 -323.724217)
			(xy 102.601671 -323.70621) (xy 102.656514 -323.69608) (xy 102.712248 -323.694043) (xy 102.767685 -323.700143)
			(xy 102.821642 -323.714249) (xy 102.872971 -323.736061) (xy 102.920577 -323.765115) (xy 102.963445 -323.80079)
			(xy 103.000662 -323.842327) (xy 103.031435 -323.88884) (xy 103.055107 -323.939337) (xy 103.071175 -323.992744)
			(xy 103.079295 -324.04792) (xy 103.079804 -324.075806) (xy 103.079295 -324.103692) (xy 103.071175 -324.158868)
			(xy 103.055107 -324.212275) (xy 103.031435 -324.262772) (xy 103.000662 -324.309285) (xy 102.963445 -324.350822)
			(xy 102.920577 -324.386497) (xy 102.872971 -324.415551) (xy 102.821642 -324.437363) (xy 102.767685 -324.451469)
			(xy 102.712248 -324.457569) (xy 102.656514 -324.455532) (xy 102.601671 -324.445402) (xy 102.548887 -324.427395)
			(xy 102.499287 -324.401894) (xy 102.453929 -324.369443) (xy 102.41378 -324.330734) (xy 102.379694 -324.286591)
			(xy 102.352398 -324.237956) (xy 102.332475 -324.185865) (xy 102.320349 -324.131428) (xy 102.316278 -324.075806)
			(xy 100.33 -324.075806) (xy 100.33 -325.88454) (xy 100.331016 -325.894192) (xy 100.332648 -325.901434)
			(xy 100.339495 -325.914597) (xy 100.344478 -325.9201) (xy 100.953316 -326.528938) (xy 100.974144 -326.536558)
			(xy 100.985066 -326.535542) (xy 101.01453 -326.534526) (xy 101.041781 -326.534991) (xy 101.095726 -326.542752)
			(xy 101.148019 -326.558111) (xy 101.197593 -326.580756) (xy 101.24344 -326.610225) (xy 101.284626 -326.645919)
			(xy 101.320313 -326.687111) (xy 101.337331 -326.713596) (xy 109.961678 -326.713596) (xy 109.965749 -326.657974)
			(xy 109.977875 -326.603537) (xy 109.997798 -326.551446) (xy 110.025094 -326.502811) (xy 110.05918 -326.458668)
			(xy 110.099329 -326.419959) (xy 110.144687 -326.387508) (xy 110.194287 -326.362007) (xy 110.247071 -326.344)
			(xy 110.301914 -326.33387) (xy 110.357648 -326.331833) (xy 110.413085 -326.337933) (xy 110.467042 -326.352039)
			(xy 110.518371 -326.373851) (xy 110.565977 -326.402905) (xy 110.608845 -326.43858) (xy 110.646062 -326.480117)
			(xy 110.676835 -326.52663) (xy 110.700507 -326.577127) (xy 110.716575 -326.630534) (xy 110.724695 -326.68571)
			(xy 110.725204 -326.713596) (xy 110.724695 -326.741482) (xy 110.716575 -326.796658) (xy 110.700507 -326.850065)
			(xy 110.676835 -326.900562) (xy 110.646062 -326.947075) (xy 110.608845 -326.988612) (xy 110.565977 -327.024287)
			(xy 110.518371 -327.053341) (xy 110.467042 -327.075153) (xy 110.413085 -327.089259) (xy 110.357648 -327.095359)
			(xy 110.301914 -327.093322) (xy 110.247071 -327.083192) (xy 110.194287 -327.065185) (xy 110.144687 -327.039684)
			(xy 110.099329 -327.007233) (xy 110.05918 -326.968524) (xy 110.025094 -326.924381) (xy 109.997798 -326.875746)
			(xy 109.977875 -326.823655) (xy 109.965749 -326.769218) (xy 109.961678 -326.713596) (xy 101.337331 -326.713596)
			(xy 101.349775 -326.732963) (xy 101.372411 -326.782541) (xy 101.387762 -326.834836) (xy 101.395513 -326.888783)
			(xy 101.396038 -326.916034) (xy 101.395022 -326.945498) (xy 101.394006 -326.95642) (xy 101.401626 -326.977248)
			(xy 102.143306 -327.718928) (xy 102.148805 -327.723916) (xy 102.161971 -327.730761) (xy 102.169214 -327.73239)
			(xy 102.178866 -327.733406)
		)
		(stroke
			(width 0)
			(type solid)
		)
		(fill yes)
		(layer "In15.Cu")
		(net "GND")
	)
	(gr_poly
		(pts
			(xy 185.54954 -363.506512) (xy 185.559607 -363.506082) (xy 185.578202 -363.498359) (xy 185.585608 -363.491526)
			(xy 189.583822 -359.493312) (xy 189.597734 -359.479847) (xy 189.628167 -359.455912) (xy 189.644528 -359.44556)
			(xy 189.649608 -359.442258) (xy 189.670436 -359.42143) (xy 189.677782 -359.414622) (xy 189.696245 -359.406898)
			(xy 189.70625 -359.406444) (xy 189.736222 -359.406444) (xy 189.742064 -359.405174) (xy 189.760841 -359.401027)
			(xy 189.799037 -359.396572) (xy 189.818264 -359.396284) (xy 196.494146 -359.396284) (xy 196.504212 -359.395852)
			(xy 196.522803 -359.388124) (xy 196.530214 -359.381298) (xy 197.282562 -358.628696) (xy 197.296472 -358.615229)
			(xy 197.326904 -358.591291) (xy 197.343268 -358.580944) (xy 197.348348 -358.577642) (xy 197.369176 -358.556814)
			(xy 197.376525 -358.550014) (xy 197.394988 -358.542307) (xy 197.40499 -358.541828) (xy 197.434962 -358.541828)
			(xy 197.440804 -358.540558) (xy 197.459581 -358.536414) (xy 197.497777 -358.531963) (xy 197.517004 -358.531668)
			(xy 197.965568 -358.531668) (xy 197.977506 -358.52862) (xy 197.983094 -358.525572) (xy 198.010665 -358.511733)
			(xy 198.069165 -358.492158) (xy 198.13005 -358.48224) (xy 198.160894 -358.48163) (xy 198.161148 -358.48163)
			(xy 198.188416 -358.48212) (xy 198.242395 -358.489887) (xy 198.29472 -358.505257) (xy 198.344325 -358.527916)
			(xy 198.390201 -358.557404) (xy 198.431414 -358.59312) (xy 198.467125 -358.634337) (xy 198.496607 -358.680217)
			(xy 198.51926 -358.729825) (xy 198.534623 -358.782152) (xy 198.542384 -358.836132) (xy 198.542384 -358.890668)
			(xy 198.534623 -358.944648) (xy 198.51926 -358.996975) (xy 198.496607 -359.046583) (xy 198.467125 -359.092463)
			(xy 198.431414 -359.13368) (xy 198.390201 -359.169396) (xy 198.344325 -359.198884) (xy 198.29472 -359.221543)
			(xy 198.242395 -359.236913) (xy 198.188416 -359.24468) (xy 198.161148 -359.245154) (xy 198.160894 -359.245154)
			(xy 198.13005 -359.244561) (xy 198.069165 -359.234636) (xy 198.010669 -359.215045) (xy 197.983094 -359.201212)
			(xy 197.977506 -359.198164) (xy 197.965568 -359.195116) (xy 197.675754 -359.195116) (xy 197.665688 -359.195548)
			(xy 197.647097 -359.203276) (xy 197.639686 -359.210102) (xy 197.546468 -359.303574) (xy 197.54553 -359.313214)
			(xy 197.550095 -359.33202) (xy 197.555358 -359.34015) (xy 197.565518 -359.353104) (xy 197.567804 -359.355898)
			(xy 197.576748 -359.364633) (xy 197.60032 -359.372879) (xy 197.612762 -359.371646) (xy 197.626224 -359.367582)
			(xy 197.651392 -359.356526) (xy 197.704104 -359.34093) (xy 197.758505 -359.333037) (xy 197.78599 -359.33253)
			(xy 197.812509 -359.332985) (xy 197.865037 -359.340327) (xy 197.916042 -359.354871) (xy 197.964542 -359.376338)
			(xy 198.009602 -359.404313) (xy 198.050355 -359.438258) (xy 198.086016 -359.477518) (xy 198.115897 -359.521338)
			(xy 198.139423 -359.568873) (xy 198.156141 -359.619208) (xy 198.161402 -359.645204) (xy 198.162926 -359.652316)
			(xy 198.165452 -359.660283) (xy 198.174923 -359.674042) (xy 198.181468 -359.67924) (xy 198.789544 -359.67924)
			(xy 198.799609 -359.678807) (xy 198.818196 -359.671075) (xy 198.825612 -359.664254) (xy 199.565768 -358.924098)
			(xy 199.589332 -358.9012) (xy 199.640714 -358.860245) (xy 199.696357 -358.825296) (xy 199.75556 -358.796793)
			(xy 199.817581 -358.775093) (xy 199.881641 -358.760469) (xy 199.946934 -358.753104) (xy 199.979788 -358.752648)
			(xy 201.383392 -358.752648) (xy 201.418746 -358.753185) (xy 201.488938 -358.761706) (xy 201.557595 -358.778615)
			(xy 201.623717 -358.803663) (xy 201.686343 -358.836489) (xy 201.744563 -358.876614) (xy 201.797531 -358.923454)
			(xy 201.844475 -358.976329) (xy 201.884714 -359.034471) (xy 201.917663 -359.097032) (xy 201.942842 -359.163105)
			(xy 201.959885 -359.231728) (xy 201.964798 -359.266744) (xy 201.966193 -359.275545) (xy 201.974254 -359.291423)
			(xy 201.980546 -359.297732) (xy 202.00239 -359.318052) (xy 202.009195 -359.323881) (xy 202.025718 -359.330785)
			(xy 202.034648 -359.331514) (xy 202.068846 -359.33374) (xy 202.136418 -359.34518) (xy 202.202194 -359.364426)
			(xy 202.265276 -359.391213) (xy 202.324802 -359.425177) (xy 202.379959 -359.465854) (xy 202.429995 -359.512687)
			(xy 202.474225 -359.565038) (xy 202.512045 -359.622191) (xy 202.54294 -359.683366) (xy 202.566487 -359.747728)
			(xy 202.582365 -359.814397) (xy 202.590357 -359.882463) (xy 202.590908 -359.91673) (xy 202.590372 -359.952133)
			(xy 202.581837 -360.022421) (xy 202.564894 -360.091169) (xy 202.539791 -360.157375) (xy 202.506894 -360.220074)
			(xy 202.466681 -360.278351) (xy 202.419739 -360.331359) (xy 202.366752 -360.378324) (xy 202.308491 -360.418562)
			(xy 202.245807 -360.451487) (xy 202.179612 -360.476619) (xy 202.110871 -360.493591) (xy 202.040586 -360.502157)
			(xy 202.005184 -360.502708) (xy 200.711816 -360.502708) (xy 200.703689 -360.503053) (xy 200.688281 -360.508241)
			(xy 200.68159 -360.512868) (xy 200.67019 -360.521925) (xy 200.652681 -360.545173) (xy 200.642448 -360.57242)
			(xy 200.640325 -360.601446) (xy 200.646484 -360.629892) (xy 200.660423 -360.655441) (xy 200.670414 -360.66603)
			(xy 201.241406 -361.237022) (xy 201.246905 -361.24201) (xy 201.260071 -361.248856) (xy 201.267314 -361.250484)
			(xy 201.276966 -361.2515) (xy 236.010196 -361.2515) (xy 236.018324 -361.250738) (xy 236.018832 -361.250738)
			(xy 236.026351 -361.249139) (xy 236.040043 -361.242166) (xy 236.045756 -361.237022) (xy 236.97057 -360.312208)
			(xy 236.977972 -360.305372) (xy 236.99657 -360.297662) (xy 237.006638 -360.297222) (xy 245.207536 -360.297222)
			(xy 245.215664 -360.29646) (xy 245.216172 -360.29646) (xy 245.223687 -360.294853) (xy 245.237364 -360.287865)
			(xy 245.243096 -360.282744) (xy 246.449596 -359.076244) (xy 246.456992 -359.069392) (xy 246.475591 -359.061649)
			(xy 246.485664 -359.061258) (xy 248.233692 -359.061258) (xy 248.242036 -359.060966) (xy 248.25785 -359.055648)
			(xy 248.26468 -359.050844) (xy 248.271284 -359.04551) (xy 248.280682 -359.03154) (xy 248.282714 -359.023412)
			(xy 248.29046 -358.995987) (xy 248.312964 -358.943634) (xy 248.343004 -358.89521) (xy 248.379912 -358.851791)
			(xy 248.422865 -358.814344) (xy 248.47091 -358.783701) (xy 248.522978 -358.760543) (xy 248.57791 -358.745386)
			(xy 248.634486 -358.738566) (xy 248.691447 -358.740236) (xy 248.747526 -358.750358) (xy 248.801476 -358.768707)
			(xy 248.852097 -358.794875) (xy 248.87555 -358.811068) (xy 248.888345 -358.819673) (xy 248.917554 -358.829507)
			(xy 248.948366 -358.830219) (xy 248.977998 -358.821743) (xy 249.003774 -358.804846) (xy 249.01398 -358.793288)
			(xy 249.035039 -358.768296) (xy 249.082437 -358.723298) (xy 249.135136 -358.684643) (xy 249.192293 -358.652949)
			(xy 249.252993 -358.628723) (xy 249.316265 -358.612353) (xy 249.381098 -358.604101) (xy 249.413776 -358.60355)
			(xy 249.44611 -358.604055) (xy 249.510272 -358.612132) (xy 249.572926 -358.628151) (xy 249.633091 -358.65186)
			(xy 249.689829 -358.68289) (xy 249.742253 -358.720756) (xy 249.789543 -358.764865) (xy 249.83096 -358.81453)
			(xy 249.865859 -358.868974) (xy 249.893692 -358.927346) (xy 249.914027 -358.988735) (xy 249.92076 -359.020364)
			(xy 249.92283 -359.028981) (xy 249.931937 -359.044169) (xy 249.93854 -359.050082) (xy 249.945144 -359.055416)
			(xy 249.9614 -359.061258) (xy 251.440188 -359.061258) (xy 251.448316 -359.060496) (xy 251.448824 -359.060496)
			(xy 251.456343 -359.058896) (xy 251.470032 -359.051921) (xy 251.475748 -359.04678) (xy 252.1712 -358.351328)
			(xy 252.176183 -358.345827) (xy 252.183015 -358.332658) (xy 252.184662 -358.32542) (xy 252.185678 -358.315768)
			(xy 252.185678 -356.865174) (xy 252.186105 -356.855105) (xy 252.193824 -356.836506) (xy 252.200664 -356.829106)
			(xy 253.16688 -355.86289) (xy 253.174278 -355.856046) (xy 253.192878 -355.848327) (xy 253.202948 -355.847904)
			(xy 266.000992 -355.847904) (xy 266.00912 -355.847142) (xy 266.009628 -355.847142) (xy 266.017148 -355.845543)
			(xy 266.030841 -355.838572) (xy 266.036552 -355.833426) (xy 266.629642 -355.240336) (xy 266.634622 -355.234833)
			(xy 266.641451 -355.221664) (xy 266.643104 -355.214428) (xy 266.64412 -355.204776) (xy 266.64412 -343.558114)
			(xy 266.643599 -343.548732) (xy 266.636703 -343.53127) (xy 266.630658 -343.524078) (xy 266.582652 -343.473278)
			(xy 266.578334 -343.468706) (xy 266.561316 -343.457784) (xy 266.548108 -343.457022) (xy 266.519377 -343.454745)
			(xy 266.463033 -343.442629) (xy 266.409152 -343.422177) (xy 266.35896 -343.393854) (xy 266.313599 -343.358303)
			(xy 266.274101 -343.316335) (xy 266.241365 -343.268903) (xy 266.216134 -343.217088) (xy 266.198984 -343.162067)
			(xy 266.190305 -343.105092) (xy 266.189714 -343.076276) (xy 266.19023 -343.047974) (xy 266.198593 -342.991991)
			(xy 266.215132 -342.937858) (xy 266.239485 -342.88676) (xy 266.271117 -342.83982) (xy 266.309334 -342.798065)
			(xy 266.353299 -342.762413) (xy 266.37742 -342.7476) (xy 266.383008 -342.744298) (xy 266.388342 -342.738964)
			(xy 266.392914 -342.734646) (xy 266.415012 -342.69807) (xy 266.415774 -342.68537) (xy 266.420092 -342.611456)
			(xy 266.41961 -342.601492) (xy 266.412027 -342.583063) (xy 266.40536 -342.575642) (xy 266.398502 -342.568784)
			(xy 266.394946 -342.566244) (xy 266.374056 -342.550822) (xy 266.336242 -342.515237) (xy 266.303598 -342.474857)
			(xy 266.276725 -342.430427) (xy 266.256119 -342.382767) (xy 266.24216 -342.332753) (xy 266.235106 -342.28131)
			(xy 266.234672 -342.255348) (xy 266.235174 -342.227599) (xy 266.243221 -342.172686) (xy 266.259136 -342.119518)
			(xy 266.282585 -342.069216) (xy 266.313073 -342.022842) (xy 266.349957 -341.981372) (xy 266.392459 -341.945683)
			(xy 266.439682 -341.916526) (xy 266.49063 -341.894517) (xy 266.544229 -341.880119) (xy 266.57173 -341.87638)
			(xy 266.578588 -341.875618) (xy 266.595098 -341.86876) (xy 266.605766 -341.864442) (xy 266.630404 -341.838026)
			(xy 266.636653 -341.830789) (xy 266.643709 -341.813034) (xy 266.64412 -341.803482) (xy 266.64412 -341.113364)
			(xy 266.64455 -341.103297) (xy 266.652276 -341.084704) (xy 266.659106 -341.077296) (xy 274.95246 -332.783942)
			(xy 274.95986 -332.7771) (xy 274.978458 -332.769381) (xy 274.988528 -332.768956) (xy 276.533102 -332.768956)
			(xy 276.544278 -332.767686) (xy 276.553676 -332.764892) (xy 276.555708 -332.763876) (xy 276.559772 -332.761336)
			(xy 276.565826 -332.7579) (xy 276.579229 -332.754159) (xy 276.586188 -332.75397) (xy 285.002478 -332.75397)
			(xy 285.010606 -332.753208) (xy 285.011114 -332.753208) (xy 285.018634 -332.75161) (xy 285.032326 -332.744638)
			(xy 285.038038 -332.739492) (xy 295.758362 -322.019168) (xy 295.763344 -322.013666) (xy 295.770178 -322.000498)
			(xy 295.771824 -321.99326) (xy 295.77284 -321.983608) (xy 295.77284 -320.413888) (xy 295.77235 -320.403879)
			(xy 295.76469 -320.385384) (xy 295.750539 -320.371226) (xy 295.732049 -320.363555) (xy 295.72204 -320.363088)
			(xy 266.68222 -320.363088) (xy 266.671685 -320.363675) (xy 266.652408 -320.372202) (xy 266.644882 -320.379598)
			(xy 266.594336 -320.43497) (xy 266.591232 -320.438475) (xy 266.586253 -320.446405) (xy 266.58443 -320.450718)
			(xy 266.581128 -320.459354) (xy 266.581128 -320.472562) (xy 266.581382 -320.474848) (xy 266.585113 -320.517786)
			(xy 266.591209 -320.603771) (xy 266.593574 -320.646806) (xy 266.596769 -320.710067) (xy 266.600199 -320.836703)
			(xy 266.600432 -320.900044) (xy 266.599938 -320.996959) (xy 266.592032 -321.190627) (xy 266.576233 -321.383811)
			(xy 266.552568 -321.57619) (xy 266.521075 -321.767444) (xy 266.481808 -321.957254) (xy 266.434831 -322.145304)
			(xy 266.380223 -322.331282) (xy 266.318074 -322.514877) (xy 266.248489 -322.695785) (xy 266.171583 -322.873704)
			(xy 266.087484 -323.048338) (xy 265.996331 -323.219397) (xy 265.898277 -323.386595) (xy 265.793485 -323.549654)
			(xy 265.68213 -323.708304) (xy 265.564396 -323.862279) (xy 265.440479 -324.011324) (xy 265.310586 -324.155191)
			(xy 265.174933 -324.29364) (xy 265.033746 -324.42644) (xy 264.88726 -324.553371) (xy 264.735718 -324.674222)
			(xy 264.579373 -324.788791) (xy 264.418485 -324.896887) (xy 264.253322 -324.998331) (xy 264.084158 -325.092954)
			(xy 263.911276 -325.180598) (xy 263.734963 -325.261118) (xy 263.555512 -325.334379) (xy 263.373222 -325.400259)
			(xy 263.188397 -325.458649) (xy 263.001344 -325.509452) (xy 262.812375 -325.552583) (xy 262.621803 -325.587971)
			(xy 262.429947 -325.615555) (xy 262.237125 -325.635292) (xy 262.043659 -325.647147) (xy 261.84987 -325.651101)
			(xy 261.656081 -325.647147) (xy 261.462615 -325.635292) (xy 261.269793 -325.615555) (xy 261.077937 -325.587971)
			(xy 260.887365 -325.552583) (xy 260.698396 -325.509452) (xy 260.511343 -325.458649) (xy 260.326518 -325.400259)
			(xy 260.144228 -325.334379) (xy 259.964777 -325.261118) (xy 259.788464 -325.180598) (xy 259.615582 -325.092954)
			(xy 259.446418 -324.998331) (xy 259.281255 -324.896887) (xy 259.120367 -324.788791) (xy 258.964022 -324.674222)
			(xy 258.81248 -324.553371) (xy 258.665994 -324.42644) (xy 258.524807 -324.29364) (xy 258.389154 -324.155191)
			(xy 258.259261 -324.011324) (xy 258.135344 -323.862279) (xy 258.01761 -323.708304) (xy 257.906255 -323.549654)
			(xy 257.801463 -323.386595) (xy 257.703409 -323.219397) (xy 257.612256 -323.048338) (xy 257.528157 -322.873704)
			(xy 257.451251 -322.695785) (xy 257.381666 -322.514877) (xy 257.319517 -322.331282) (xy 257.264909 -322.145304)
			(xy 257.217932 -321.957254) (xy 257.178665 -321.767444) (xy 257.147172 -321.57619) (xy 257.123507 -321.383811)
			(xy 257.107708 -321.190627) (xy 257.099802 -320.996959) (xy 257.099308 -320.900044) (xy 257.099546 -320.836703)
			(xy 257.102976 -320.710067) (xy 257.106166 -320.646806) (xy 257.108706 -320.604388) (xy 257.118358 -320.475864)
			(xy 257.118612 -320.473578) (xy 257.118612 -320.46926) (xy 257.118329 -320.461707) (xy 257.113931 -320.447254)
			(xy 257.109976 -320.440812) (xy 257.109468 -320.440304) (xy 257.105912 -320.435478) (xy 257.086354 -320.414142)
			(xy 257.054858 -320.379598) (xy 257.047361 -320.372163) (xy 257.028066 -320.363651) (xy 257.01752 -320.363088)
			(xy 251.847858 -320.363088) (xy 251.841848 -320.363254) (xy 251.830165 -320.366076) (xy 251.824744 -320.368676)
			(xy 251.821271 -320.370517) (xy 251.814894 -320.375112) (xy 251.812044 -320.37782) (xy 249.217942 -322.971922)
			(xy 249.210544 -322.978768) (xy 249.191945 -322.986494) (xy 249.181874 -322.986908) (xy 219.05087 -322.986908)
			(xy 219.040802 -322.98648) (xy 219.022205 -322.978759) (xy 219.014802 -322.971922) (xy 217.45448 -321.4116)
			(xy 217.447625 -321.404205) (xy 217.439878 -321.385606) (xy 217.439494 -321.375532) (xy 217.439494 -314.826904)
			(xy 217.439321 -314.820896) (xy 217.436488 -314.809219) (xy 217.433906 -314.80379) (xy 217.432067 -314.800315)
			(xy 217.427475 -314.793935) (xy 217.424762 -314.79109) (xy 217.42273 -314.789058) (xy 217.367358 -314.73902)
			(xy 217.360246 -314.73267) (xy 217.34272 -314.725812) (xy 217.32875 -314.725812) (xy 217.32621 -314.726066)
			(xy 217.242714 -314.733451) (xy 217.075258 -314.74133) (xy 216.991438 -314.741814) (xy 216.989914 -314.741814)
			(xy 216.905139 -314.741317) (xy 216.73578 -314.733251) (xy 216.566997 -314.717134) (xy 216.399172 -314.693005)
			(xy 216.232685 -314.660918) (xy 216.067913 -314.620946) (xy 215.905231 -314.573178) (xy 215.745005 -314.517724)
			(xy 215.587599 -314.454709) (xy 215.43337 -314.384275) (xy 215.282667 -314.306583) (xy 215.135832 -314.221808)
			(xy 214.993196 -314.130143) (xy 214.855084 -314.031794) (xy 214.721808 -313.926985) (xy 214.59367 -313.815953)
			(xy 214.47096 -313.69895) (xy 214.353956 -313.57624) (xy 214.242924 -313.448103) (xy 214.138115 -313.314827)
			(xy 214.039765 -313.176715) (xy 213.948099 -313.03408) (xy 213.863323 -312.887245) (xy 213.785631 -312.736542)
			(xy 213.715197 -312.582314) (xy 213.652181 -312.424908) (xy 213.596726 -312.264683) (xy 213.548958 -312.102)
			(xy 213.508985 -311.937229) (xy 213.476897 -311.770742) (xy 213.452767 -311.602917) (xy 213.43665 -311.434134)
			(xy 213.428583 -311.264775) (xy 213.428583 -311.095225) (xy 213.43665 -310.925866) (xy 213.452767 -310.757083)
			(xy 213.476897 -310.589258) (xy 213.508985 -310.422771) (xy 213.548958 -310.258) (xy 213.596726 -310.095317)
			(xy 213.652181 -309.935092) (xy 213.715197 -309.777686) (xy 213.785631 -309.623458) (xy 213.863323 -309.472755)
			(xy 213.948099 -309.32592) (xy 214.039765 -309.183285) (xy 214.138115 -309.045173) (xy 214.242924 -308.911897)
			(xy 214.353956 -308.78376) (xy 214.47096 -308.66105) (xy 214.59367 -308.544047) (xy 214.721808 -308.433015)
			(xy 214.855084 -308.328206) (xy 214.993196 -308.229857) (xy 215.135832 -308.138192) (xy 215.282667 -308.053417)
			(xy 215.43337 -307.975725) (xy 215.587599 -307.905291) (xy 215.745005 -307.842276) (xy 215.905231 -307.786822)
			(xy 216.067913 -307.739054) (xy 216.232685 -307.699082) (xy 216.399172 -307.666995) (xy 216.566997 -307.642866)
			(xy 216.73578 -307.626749) (xy 216.905139 -307.618683) (xy 216.989914 -307.61813) (xy 216.99093 -307.61813)
			(xy 217.075325 -307.618632) (xy 217.243925 -307.626637) (xy 217.327988 -307.634132) (xy 217.33891 -307.635148)
			(xy 217.349324 -307.631592) (xy 217.359992 -307.628036) (xy 217.380058 -307.609494) (xy 217.380566 -307.608986)
			(xy 217.422984 -307.570632) (xy 217.424 -307.569616) (xy 217.431366 -307.562504) (xy 217.43543 -307.553106)
			(xy 217.436823 -307.549683) (xy 217.438735 -307.542543) (xy 217.43924 -307.538882) (xy 217.439494 -307.533294)
			(xy 217.439494 -290.051744) (xy 217.439326 -290.045735) (xy 217.436501 -290.034053) (xy 217.433906 -290.02863)
			(xy 217.432069 -290.025154) (xy 217.427481 -290.01877) (xy 217.424762 -290.01593) (xy 215.864186 -288.455354)
			(xy 215.860454 -288.451834) (xy 215.851879 -288.446208) (xy 215.847168 -288.444178) (xy 215.838532 -288.440622)
			(xy 213.00821 -288.440622) (xy 213.002202 -288.440794) (xy 212.990524 -288.443627) (xy 212.985096 -288.44621)
			(xy 212.981622 -288.448049) (xy 212.975242 -288.452642) (xy 212.972396 -288.455354) (xy 210.140042 -291.287708)
			(xy 210.136687 -291.29135) (xy 210.131309 -291.299661) (xy 210.129374 -291.304218) (xy 210.120484 -291.328348)
			(xy 210.12023 -291.33673) (xy 210.118707 -291.363846) (xy 210.108936 -291.41727) (xy 210.091679 -291.468764)
			(xy 210.067284 -291.517287) (xy 210.036247 -291.561854) (xy 209.999195 -291.601562) (xy 209.956881 -291.635606)
			(xy 209.933794 -291.649912) (xy 209.933286 -291.65042) (xy 209.929984 -291.652198) (xy 209.922741 -291.656888)
			(xy 209.91167 -291.670109) (xy 209.905616 -291.686257) (xy 209.905092 -291.69487) (xy 209.905092 -291.74821)
			(xy 209.905419 -291.757105) (xy 209.911494 -291.773826) (xy 209.922938 -291.787446) (xy 209.930492 -291.792152)
			(xy 209.954865 -291.806908) (xy 209.99934 -291.842518) (xy 210.038025 -291.884345) (xy 210.070059 -291.931461)
			(xy 210.09473 -291.982817) (xy 210.111488 -292.03727) (xy 210.119962 -292.093611) (xy 210.120484 -292.122098)
			(xy 210.119999 -292.149337) (xy 210.112249 -292.203261) (xy 210.096906 -292.255535) (xy 210.074284 -292.305094)
			(xy 210.044841 -292.35093) (xy 210.009176 -292.392112) (xy 209.968016 -292.427801) (xy 209.922198 -292.457272)
			(xy 209.872652 -292.479925) (xy 209.820388 -292.495299) (xy 209.766469 -292.503082) (xy 209.73923 -292.503606)
			(xy 209.738976 -292.503606) (xy 209.724244 -292.503352) (xy 209.723228 -292.503352) (xy 209.71383 -292.503606)
			(xy 209.713322 -292.503606) (xy 209.686289 -292.503088) (xy 209.632777 -292.495359) (xy 209.580892 -292.480153)
			(xy 209.531673 -292.457773) (xy 209.486108 -292.428669) (xy 209.445107 -292.393423) (xy 209.409494 -292.352742)
			(xy 209.379981 -292.307439) (xy 209.368136 -292.283134) (xy 209.367374 -292.281356) (xy 209.363564 -292.273736)
			(xy 209.357976 -292.264338) (xy 209.355944 -292.260528) (xy 209.34426 -292.246304) (xy 209.33537 -292.241478)
			(xy 209.326226 -292.236398) (xy 209.247994 -292.22065) (xy 209.242914 -292.219634) (xy 209.229198 -292.219634)
			(xy 209.219231 -292.22011) (xy 209.200794 -292.227685) (xy 209.193384 -292.234366) (xy 207.935576 -293.492174)
			(xy 207.927735 -293.500843) (xy 207.920187 -293.522939) (xy 207.921098 -293.534592) (xy 207.927702 -293.585138)
			(xy 207.927702 -293.585646) (xy 207.930496 -293.606728) (xy 207.933798 -293.618158) (xy 207.949038 -293.641272)
			(xy 207.952848 -293.644828) (xy 207.96504 -293.65702) (xy 207.969612 -293.660068) (xy 207.992226 -293.675204)
			(xy 208.033323 -293.710871) (xy 208.068929 -293.75202) (xy 208.09832 -293.797815) (xy 208.120899 -293.847325)
			(xy 208.136205 -293.899544) (xy 208.143929 -293.953408) (xy 208.144364 -293.980616) (xy 208.143858 -294.008351)
			(xy 208.135812 -294.063234) (xy 208.119905 -294.116374) (xy 208.096474 -294.166652) (xy 208.066011 -294.213008)
			(xy 208.029158 -294.254466) (xy 207.986692 -294.290153) (xy 207.939507 -294.319316) (xy 207.888598 -294.341342)
			(xy 207.835037 -294.355766) (xy 207.80756 -294.359584) (xy 207.793082 -294.361108) (xy 207.762856 -294.362378)
			(xy 207.734851 -294.361872) (xy 207.679435 -294.353732) (xy 207.625793 -294.337617) (xy 207.575066 -294.31387)
			(xy 207.528333 -294.282996) (xy 207.486589 -294.245652) (xy 207.450722 -294.202633) (xy 207.435704 -294.17899)
			(xy 207.433164 -294.174672) (xy 207.43037 -294.169592) (xy 207.422242 -294.160956) (xy 207.41767 -294.157654)
			(xy 207.412737 -294.154552) (xy 207.401833 -294.150452) (xy 207.39608 -294.149526) (xy 207.316832 -294.138858)
			(xy 207.303878 -294.138858) (xy 207.295951 -294.140135) (xy 207.281452 -294.147009) (xy 207.27543 -294.15232)
			(xy 204.981302 -296.446448) (xy 204.977868 -296.450065) (xy 204.972365 -296.458382) (xy 204.97038 -296.462958)
			(xy 204.96657 -296.472102) (xy 204.96657 -296.482262) (xy 204.966155 -296.509583) (xy 204.958463 -296.563679)
			(xy 204.944024 -296.613072) (xy 205.362554 -296.613072) (xy 205.366625 -296.55745) (xy 205.378751 -296.503013)
			(xy 205.398674 -296.450922) (xy 205.42597 -296.402287) (xy 205.460056 -296.358144) (xy 205.500205 -296.319435)
			(xy 205.545563 -296.286984) (xy 205.595163 -296.261483) (xy 205.647947 -296.243476) (xy 205.70279 -296.233346)
			(xy 205.758524 -296.231309) (xy 205.813961 -296.237409) (xy 205.867918 -296.251515) (xy 205.919247 -296.273327)
			(xy 205.966853 -296.302381) (xy 206.009721 -296.338056) (xy 206.046938 -296.379593) (xy 206.077711 -296.426106)
			(xy 206.101383 -296.476603) (xy 206.117451 -296.53001) (xy 206.125571 -296.585186) (xy 206.12608 -296.613072)
			(xy 206.63738 -296.613072) (xy 206.641451 -296.55745) (xy 206.653577 -296.503013) (xy 206.6735 -296.450922)
			(xy 206.700796 -296.402287) (xy 206.734882 -296.358144) (xy 206.775031 -296.319435) (xy 206.820389 -296.286984)
			(xy 206.869989 -296.261483) (xy 206.922773 -296.243476) (xy 206.977616 -296.233346) (xy 207.03335 -296.231309)
			(xy 207.088787 -296.237409) (xy 207.142744 -296.251515) (xy 207.194073 -296.273327) (xy 207.241679 -296.302381)
			(xy 207.284547 -296.338056) (xy 207.321764 -296.379593) (xy 207.352537 -296.426106) (xy 207.376209 -296.476603)
			(xy 207.392277 -296.53001) (xy 207.400397 -296.585186) (xy 207.400906 -296.613072) (xy 207.400397 -296.640958)
			(xy 207.392277 -296.696134) (xy 207.376209 -296.749541) (xy 207.352537 -296.800038) (xy 207.321764 -296.846551)
			(xy 207.284547 -296.888088) (xy 207.241679 -296.923763) (xy 207.194073 -296.952817) (xy 207.142744 -296.974629)
			(xy 207.088787 -296.988735) (xy 207.03335 -296.994835) (xy 206.977616 -296.992798) (xy 206.922773 -296.982668)
			(xy 206.869989 -296.964661) (xy 206.820389 -296.93916) (xy 206.775031 -296.906709) (xy 206.734882 -296.868)
			(xy 206.700796 -296.823857) (xy 206.6735 -296.775222) (xy 206.653577 -296.723131) (xy 206.641451 -296.668694)
			(xy 206.63738 -296.613072) (xy 206.12608 -296.613072) (xy 206.125571 -296.640958) (xy 206.117451 -296.696134)
			(xy 206.101383 -296.749541) (xy 206.077711 -296.800038) (xy 206.046938 -296.846551) (xy 206.009721 -296.888088)
			(xy 205.966853 -296.923763) (xy 205.919247 -296.952817) (xy 205.867918 -296.974629) (xy 205.813961 -296.988735)
			(xy 205.758524 -296.994835) (xy 205.70279 -296.992798) (xy 205.647947 -296.982668) (xy 205.595163 -296.964661)
			(xy 205.545563 -296.93916) (xy 205.500205 -296.906709) (xy 205.460056 -296.868) (xy 205.42597 -296.823857)
			(xy 205.398674 -296.775222) (xy 205.378751 -296.723131) (xy 205.366625 -296.668694) (xy 205.362554 -296.613072)
			(xy 204.944024 -296.613072) (xy 204.943132 -296.616124) (xy 204.920476 -296.665845) (xy 204.890957 -296.711825)
			(xy 204.855179 -296.753123) (xy 204.813876 -296.788894) (xy 204.767891 -296.818405) (xy 204.718166 -296.841054)
			(xy 204.665718 -296.856376) (xy 204.611621 -296.864059) (xy 204.5843 -296.864532) (xy 204.57414 -296.864532)
			(xy 204.564996 -296.868342) (xy 204.56043 -296.870346) (xy 204.55211 -296.87584) (xy 204.548486 -296.879264)
			(xy 204.494638 -296.933112) (xy 204.48724 -296.939958) (xy 204.468641 -296.947684) (xy 204.45857 -296.948098)
			(xy 203.988924 -296.948098) (xy 203.976746 -296.948874) (xy 203.955151 -296.96016) (xy 203.947522 -296.969688)
			(xy 203.947268 -296.969942) (xy 203.937362 -296.984166) (xy 203.935076 -296.991532) (xy 203.925911 -297.018309)
			(xy 203.900796 -297.069027) (xy 203.868471 -297.115483) (xy 203.829643 -297.156659) (xy 203.785163 -297.191654)
			(xy 203.736005 -297.2197) (xy 203.683247 -297.240183) (xy 203.628042 -297.252656) (xy 203.571602 -297.256844)
			(xy 203.515162 -297.252656) (xy 203.459957 -297.240183) (xy 203.407199 -297.2197) (xy 203.358041 -297.191654)
			(xy 203.313561 -297.156659) (xy 203.274733 -297.115483) (xy 203.242408 -297.069027) (xy 203.217293 -297.018309)
			(xy 203.208128 -296.991532) (xy 203.205842 -296.984166) (xy 203.196444 -296.970704) (xy 203.194158 -296.968164)
			(xy 203.190856 -296.963592) (xy 203.18222 -296.95648) (xy 203.176886 -296.953686) (xy 203.17146 -296.9511)
			(xy 203.15978 -296.948271) (xy 203.153772 -296.948098) (xy 196.469508 -296.948098) (xy 196.458555 -296.948623)
			(xy 196.438632 -296.957732) (xy 196.424304 -296.974304) (xy 196.42074 -296.984674) (xy 196.41185 -297.015154)
			(xy 196.409056 -297.022012) (xy 196.408294 -297.023536) (xy 196.405754 -297.029632) (xy 196.391022 -297.063414)
			(xy 196.387694 -297.071799) (xy 196.386548 -297.089791) (xy 196.391711 -297.107065) (xy 196.396864 -297.114468)
			(xy 196.40169 -297.12031) (xy 196.40296 -297.121834) (xy 196.403468 -297.122342) (xy 196.404484 -297.123358)
			(xy 196.40931 -297.1292) (xy 196.409818 -297.129454) (xy 196.426328 -297.150199) (xy 196.452681 -297.1962)
			(xy 196.470708 -297.246056) (xy 196.479869 -297.298273) (xy 196.48043 -297.32478) (xy 196.480176 -297.331892)
			(xy 196.479922 -297.33875) (xy 196.478312 -297.363226) (xy 196.468266 -297.411235) (xy 196.450674 -297.45702)
			(xy 196.425991 -297.499405) (xy 196.39485 -297.5373) (xy 196.358052 -297.56973) (xy 196.316544 -297.59586)
			(xy 196.271392 -297.615021) (xy 196.223759 -297.626718) (xy 196.174868 -297.63065) (xy 196.125977 -297.626718)
			(xy 196.078344 -297.615021) (xy 196.033192 -297.59586) (xy 195.991684 -297.56973) (xy 195.954886 -297.5373)
			(xy 195.923745 -297.499405) (xy 195.899062 -297.45702) (xy 195.88147 -297.411235) (xy 195.871424 -297.363226)
			(xy 195.869814 -297.33875) (xy 195.86956 -297.331892) (xy 195.86956 -297.324526) (xy 195.869966 -297.301938)
			(xy 195.876623 -297.257255) (xy 195.889795 -297.214042) (xy 195.909194 -297.173244) (xy 195.934397 -297.135751)
			(xy 195.949316 -297.118786) (xy 195.955412 -297.112182) (xy 195.957698 -297.106594) (xy 195.962524 -297.094148)
			(xy 195.962524 -297.08221) (xy 195.962371 -297.076975) (xy 195.960202 -297.066731) (xy 195.958206 -297.06189)
			(xy 195.940426 -297.021758) (xy 195.940426 -297.02125) (xy 195.925694 -296.987976) (xy 195.921122 -296.978832)
			(xy 195.918328 -296.972228) (xy 195.908676 -296.960544) (xy 195.90258 -296.95648) (xy 195.89625 -296.952616)
			(xy 195.882052 -296.948358) (xy 195.87464 -296.948098) (xy 195.519548 -296.948098) (xy 195.508589 -296.948615)
			(xy 195.488653 -296.957717) (xy 195.474312 -296.97429) (xy 195.47078 -296.984674) (xy 195.46189 -297.015154)
			(xy 195.459096 -297.022012) (xy 195.458334 -297.023536) (xy 195.455794 -297.029632) (xy 195.441062 -297.063414)
			(xy 195.437733 -297.071799) (xy 195.436585 -297.089791) (xy 195.441752 -297.107064) (xy 195.446904 -297.114468)
			(xy 195.45173 -297.12031) (xy 195.453 -297.121834) (xy 195.453508 -297.122342) (xy 195.454524 -297.123358)
			(xy 195.45935 -297.1292) (xy 195.459858 -297.129454) (xy 195.476366 -297.1502) (xy 195.502716 -297.196202)
			(xy 195.52074 -297.246057) (xy 195.5299 -297.298273) (xy 195.53047 -297.32478) (xy 195.530216 -297.331892)
			(xy 195.529962 -297.33875) (xy 195.528352 -297.363226) (xy 195.518306 -297.411235) (xy 195.500714 -297.45702)
			(xy 195.476031 -297.499405) (xy 195.44489 -297.5373) (xy 195.408092 -297.56973) (xy 195.366584 -297.59586)
			(xy 195.321432 -297.615021) (xy 195.273799 -297.626718) (xy 195.224908 -297.63065) (xy 195.176017 -297.626718)
			(xy 195.128384 -297.615021) (xy 195.083232 -297.59586) (xy 195.041724 -297.56973) (xy 195.004926 -297.5373)
			(xy 194.973785 -297.499405) (xy 194.949102 -297.45702) (xy 194.93151 -297.411235) (xy 194.921464 -297.363226)
			(xy 194.919854 -297.33875) (xy 194.9196 -297.331892) (xy 194.9196 -297.324526) (xy 194.920006 -297.301938)
			(xy 194.926662 -297.257254) (xy 194.939832 -297.214039) (xy 194.959228 -297.173238) (xy 194.984427 -297.135743)
			(xy 194.999356 -297.118786) (xy 195.005452 -297.112182) (xy 195.007738 -297.106594) (xy 195.012564 -297.094148)
			(xy 195.012564 -297.08221) (xy 195.012411 -297.076975) (xy 195.010244 -297.066731) (xy 195.008246 -297.06189)
			(xy 194.990466 -297.021758) (xy 194.990466 -297.02125) (xy 194.975734 -296.987976) (xy 194.971162 -296.978832)
			(xy 194.968368 -296.972228) (xy 194.958716 -296.960544) (xy 194.95262 -296.95648) (xy 194.946291 -296.952611)
			(xy 194.932093 -296.948341) (xy 194.92468 -296.948098) (xy 191.719708 -296.948098) (xy 191.708755 -296.948623)
			(xy 191.688832 -296.957732) (xy 191.674504 -296.974304) (xy 191.67094 -296.984674) (xy 191.66205 -297.015154)
			(xy 191.659256 -297.022012) (xy 191.658494 -297.023536) (xy 191.655954 -297.029632) (xy 191.641222 -297.063414)
			(xy 191.637894 -297.071799) (xy 191.636748 -297.089791) (xy 191.641911 -297.107065) (xy 191.647064 -297.114468)
			(xy 191.65189 -297.12031) (xy 191.65316 -297.121834) (xy 191.653668 -297.122342) (xy 191.654684 -297.123358)
			(xy 191.65951 -297.1292) (xy 191.660018 -297.129454) (xy 191.676528 -297.150199) (xy 191.702881 -297.1962)
			(xy 191.720908 -297.246056) (xy 191.730069 -297.298273) (xy 191.73063 -297.32478) (xy 191.730376 -297.331892)
			(xy 191.730122 -297.33875) (xy 191.728512 -297.363226) (xy 191.718466 -297.411235) (xy 191.700874 -297.45702)
			(xy 191.676191 -297.499405) (xy 191.64505 -297.5373) (xy 191.608252 -297.56973) (xy 191.566744 -297.59586)
			(xy 191.521592 -297.615021) (xy 191.473959 -297.626718) (xy 191.425068 -297.63065) (xy 191.376177 -297.626718)
			(xy 191.328544 -297.615021) (xy 191.283392 -297.59586) (xy 191.241884 -297.56973) (xy 191.205086 -297.5373)
			(xy 191.173945 -297.499405) (xy 191.149262 -297.45702) (xy 191.13167 -297.411235) (xy 191.121624 -297.363226)
			(xy 191.120014 -297.33875) (xy 191.11976 -297.331892) (xy 191.11976 -297.324526) (xy 191.120166 -297.301938)
			(xy 191.126823 -297.257255) (xy 191.139995 -297.214042) (xy 191.159394 -297.173244) (xy 191.184597 -297.135751)
			(xy 191.199516 -297.118786) (xy 191.205612 -297.112182) (xy 191.207898 -297.106594) (xy 191.212724 -297.094148)
			(xy 191.212724 -297.08221) (xy 191.212571 -297.076975) (xy 191.210402 -297.066731) (xy 191.208406 -297.06189)
			(xy 191.190626 -297.021758) (xy 191.190626 -297.02125) (xy 191.175894 -296.987976) (xy 191.171322 -296.978832)
			(xy 191.168528 -296.972228) (xy 191.158876 -296.960544) (xy 191.15278 -296.95648) (xy 191.14645 -296.952616)
			(xy 191.132252 -296.948358) (xy 191.12484 -296.948098) (xy 190.769748 -296.948098) (xy 190.758789 -296.948615)
			(xy 190.738853 -296.957717) (xy 190.724512 -296.97429) (xy 190.72098 -296.984674) (xy 190.71209 -297.015154)
			(xy 190.709296 -297.022012) (xy 190.708534 -297.023536) (xy 190.705994 -297.029632) (xy 190.691262 -297.063414)
			(xy 190.687933 -297.071799) (xy 190.686785 -297.089791) (xy 190.691952 -297.107064) (xy 190.697104 -297.114468)
			(xy 190.70193 -297.12031) (xy 190.7032 -297.121834) (xy 190.703708 -297.122342) (xy 190.704724 -297.123358)
			(xy 190.70955 -297.1292) (xy 190.710058 -297.129454) (xy 190.726566 -297.1502) (xy 190.752916 -297.196202)
			(xy 190.77094 -297.246057) (xy 190.7801 -297.298273) (xy 190.78067 -297.32478) (xy 190.780416 -297.331892)
			(xy 190.780162 -297.33875) (xy 190.778552 -297.363226) (xy 190.768506 -297.411235) (xy 190.750914 -297.45702)
			(xy 190.726231 -297.499405) (xy 190.69509 -297.5373) (xy 190.658292 -297.56973) (xy 190.616784 -297.59586)
			(xy 190.571632 -297.615021) (xy 190.523999 -297.626718) (xy 190.475108 -297.63065) (xy 190.426217 -297.626718)
			(xy 190.378584 -297.615021) (xy 190.333432 -297.59586) (xy 190.291924 -297.56973) (xy 190.255126 -297.5373)
			(xy 190.223985 -297.499405) (xy 190.199302 -297.45702) (xy 190.18171 -297.411235) (xy 190.171664 -297.363226)
			(xy 190.170054 -297.33875) (xy 190.1698 -297.331892) (xy 190.1698 -297.324526) (xy 190.170206 -297.301938)
			(xy 190.176862 -297.257254) (xy 190.190032 -297.214039) (xy 190.209428 -297.173238) (xy 190.234627 -297.135743)
			(xy 190.249556 -297.118786) (xy 190.255652 -297.112182) (xy 190.257938 -297.106594) (xy 190.262764 -297.094148)
			(xy 190.262764 -297.08221) (xy 190.262611 -297.076975) (xy 190.260444 -297.066731) (xy 190.258446 -297.06189)
			(xy 190.240666 -297.021758) (xy 190.240666 -297.02125) (xy 190.225934 -296.987976) (xy 190.221362 -296.978832)
			(xy 190.218568 -296.972228) (xy 190.208916 -296.960544) (xy 190.20282 -296.95648) (xy 190.196491 -296.952611)
			(xy 190.182293 -296.948341) (xy 190.17488 -296.948098) (xy 188.869574 -296.948098) (xy 188.858625 -296.948629)
			(xy 188.838714 -296.957746) (xy 188.824398 -296.974316) (xy 188.820806 -296.984674) (xy 188.811916 -297.015154)
			(xy 188.809122 -297.022012) (xy 188.80836 -297.023536) (xy 188.80582 -297.029632) (xy 188.791088 -297.063414)
			(xy 188.787762 -297.0718) (xy 188.786616 -297.089792) (xy 188.791776 -297.107065) (xy 188.79693 -297.114468)
			(xy 188.801756 -297.12031) (xy 188.803026 -297.121834) (xy 188.803534 -297.122342) (xy 188.80455 -297.123358)
			(xy 188.809376 -297.1292) (xy 188.809884 -297.129454) (xy 188.826396 -297.150199) (xy 188.852752 -297.196199)
			(xy 188.870781 -297.246055) (xy 188.879943 -297.298272) (xy 188.880496 -297.32478) (xy 188.880242 -297.331892)
			(xy 188.879988 -297.33875) (xy 188.878378 -297.363226) (xy 188.868332 -297.411235) (xy 188.85074 -297.45702)
			(xy 188.826057 -297.499405) (xy 188.794916 -297.5373) (xy 188.758118 -297.56973) (xy 188.71661 -297.59586)
			(xy 188.671458 -297.615021) (xy 188.623825 -297.626718) (xy 188.574934 -297.63065) (xy 188.526043 -297.626718)
			(xy 188.47841 -297.615021) (xy 188.433258 -297.59586) (xy 188.39175 -297.56973) (xy 188.354952 -297.5373)
			(xy 188.323811 -297.499405) (xy 188.299128 -297.45702) (xy 188.281536 -297.411235) (xy 188.27149 -297.363226)
			(xy 188.26988 -297.33875) (xy 188.269626 -297.331892) (xy 188.269626 -297.324526) (xy 188.270032 -297.301938)
			(xy 188.276688 -297.257254) (xy 188.289859 -297.214041) (xy 188.309257 -297.173241) (xy 188.334457 -297.135746)
			(xy 188.349382 -297.118786) (xy 188.355478 -297.112182) (xy 188.357764 -297.106594) (xy 188.36259 -297.094148)
			(xy 188.36259 -297.08221) (xy 188.362436 -297.076975) (xy 188.360266 -297.066732) (xy 188.358272 -297.06189)
			(xy 188.340492 -297.021758) (xy 188.340492 -297.02125) (xy 188.32576 -296.987976) (xy 188.321188 -296.978832)
			(xy 188.318394 -296.972228) (xy 188.308742 -296.960544) (xy 188.302646 -296.95648) (xy 188.296315 -296.95262)
			(xy 188.282116 -296.948371) (xy 188.274706 -296.948098) (xy 186.889644 -296.948098) (xy 186.883635 -296.948266)
			(xy 186.871953 -296.951091) (xy 186.86653 -296.953686) (xy 186.863054 -296.955522) (xy 186.856669 -296.960111)
			(xy 186.85383 -296.96283) (xy 186.828938 -296.987722) (xy 186.826233 -296.990574) (xy 186.821642 -296.996953)
			(xy 186.819794 -297.000422) (xy 186.815425 -297.010166) (xy 186.814245 -297.031463) (xy 186.821802 -297.051408)
			(xy 186.828938 -297.05935) (xy 186.833002 -297.063414) (xy 186.837828 -297.066462) (xy 186.859269 -297.080597)
			(xy 186.897519 -297.114857) (xy 186.929498 -297.155035) (xy 186.954302 -297.199997) (xy 186.971232 -297.248476)
			(xy 186.979812 -297.299105) (xy 186.980322 -297.32478) (xy 186.979851 -297.349015) (xy 186.972183 -297.396875)
			(xy 186.957052 -297.442924) (xy 186.934837 -297.486004) (xy 186.906097 -297.525035) (xy 186.871553 -297.559037)
			(xy 186.832073 -297.587156) (xy 186.788646 -297.608686) (xy 186.742364 -297.623087) (xy 186.718448 -297.62704)
			(xy 186.706256 -297.628818) (xy 186.675014 -297.630342) (xy 186.649253 -297.629811) (xy 186.59846 -297.621181)
			(xy 186.549831 -297.604162) (xy 186.504741 -297.579235) (xy 186.464465 -297.547105) (xy 186.446922 -297.528234)
			(xy 186.445906 -297.526964) (xy 186.441588 -297.522646) (xy 186.434981 -297.516619) (xy 186.418722 -297.509193)
			(xy 186.409838 -297.508168) (xy 186.3344 -297.505374) (xy 186.333384 -297.505374) (xy 186.323146 -297.505634)
			(xy 186.304149 -297.513235) (xy 186.296554 -297.520106) (xy 185.938414 -297.878246) (xy 185.931531 -297.885833)
			(xy 185.923931 -297.904835) (xy 185.923682 -297.915076) (xy 185.923682 -297.915838) (xy 185.926476 -297.990006)
			(xy 185.930794 -297.999404) (xy 185.94324 -298.026074) (xy 185.950352 -298.032678) (xy 185.969864 -298.051597)
			(xy 186.00305 -298.094634) (xy 186.028755 -298.142515) (xy 186.046289 -298.193954) (xy 186.055181 -298.247567)
			(xy 186.055762 -298.27474) (xy 186.36921 -298.27474) (xy 186.37317 -298.225686) (xy 186.384947 -298.177902)
			(xy 186.404238 -298.132626) (xy 186.430541 -298.09103) (xy 186.463176 -298.054193) (xy 186.501297 -298.023068)
			(xy 186.543918 -297.998461) (xy 186.589934 -297.981009) (xy 186.638153 -297.971165) (xy 186.687328 -297.969184)
			(xy 186.736183 -297.975116) (xy 186.783454 -297.988808) (xy 186.827916 -298.009906) (xy 186.868419 -298.037862)
			(xy 186.903912 -298.071954) (xy 186.933477 -298.111298) (xy 186.956348 -298.154875) (xy 186.971932 -298.201556)
			(xy 186.979827 -298.250133) (xy 186.980322 -298.27474) (xy 188.26913 -298.27474) (xy 188.27309 -298.225686)
			(xy 188.284867 -298.177902) (xy 188.304158 -298.132626) (xy 188.330461 -298.09103) (xy 188.363096 -298.054193)
			(xy 188.401217 -298.023068) (xy 188.443838 -297.998461) (xy 188.489854 -297.981009) (xy 188.538073 -297.971165)
			(xy 188.587248 -297.969184) (xy 188.636103 -297.975116) (xy 188.683374 -297.988808) (xy 188.727836 -298.009906)
			(xy 188.768339 -298.037862) (xy 188.803832 -298.071954) (xy 188.833397 -298.111298) (xy 188.856268 -298.154875)
			(xy 188.871852 -298.201556) (xy 188.879747 -298.250133) (xy 188.880242 -298.27474) (xy 193.019184 -298.27474)
			(xy 193.023144 -298.225686) (xy 193.034921 -298.177902) (xy 193.054212 -298.132626) (xy 193.080515 -298.09103)
			(xy 193.11315 -298.054193) (xy 193.151271 -298.023068) (xy 193.193892 -297.998461) (xy 193.239908 -297.981009)
			(xy 193.288127 -297.971165) (xy 193.337302 -297.969184) (xy 193.386157 -297.975116) (xy 193.433428 -297.988808)
			(xy 193.47789 -298.009906) (xy 193.518393 -298.037862) (xy 193.553886 -298.071954) (xy 193.583451 -298.111298)
			(xy 193.606322 -298.154875) (xy 193.621906 -298.201556) (xy 193.629801 -298.250133) (xy 193.630296 -298.27474)
			(xy 193.969144 -298.27474) (xy 193.973104 -298.225686) (xy 193.984881 -298.177902) (xy 194.004172 -298.132626)
			(xy 194.030475 -298.09103) (xy 194.06311 -298.054193) (xy 194.101231 -298.023068) (xy 194.143852 -297.998461)
			(xy 194.189868 -297.981009) (xy 194.238087 -297.971165) (xy 194.287262 -297.969184) (xy 194.336117 -297.975116)
			(xy 194.383388 -297.988808) (xy 194.42785 -298.009906) (xy 194.468353 -298.037862) (xy 194.503846 -298.071954)
			(xy 194.533411 -298.111298) (xy 194.556282 -298.154875) (xy 194.571866 -298.201556) (xy 194.579761 -298.250133)
			(xy 194.580256 -298.27474) (xy 197.769238 -298.27474) (xy 197.773198 -298.225686) (xy 197.784975 -298.177902)
			(xy 197.804266 -298.132626) (xy 197.830569 -298.09103) (xy 197.863204 -298.054193) (xy 197.901325 -298.023068)
			(xy 197.943946 -297.998461) (xy 197.989962 -297.981009) (xy 198.038181 -297.971165) (xy 198.087356 -297.969184)
			(xy 198.136211 -297.975116) (xy 198.183482 -297.988808) (xy 198.227944 -298.009906) (xy 198.268447 -298.037862)
			(xy 198.30394 -298.071954) (xy 198.333505 -298.111298) (xy 198.356376 -298.154875) (xy 198.37196 -298.201556)
			(xy 198.379855 -298.250133) (xy 198.38035 -298.27474) (xy 198.719198 -298.27474) (xy 198.723158 -298.225686)
			(xy 198.734935 -298.177902) (xy 198.754226 -298.132626) (xy 198.780529 -298.09103) (xy 198.813164 -298.054193)
			(xy 198.851285 -298.023068) (xy 198.893906 -297.998461) (xy 198.939922 -297.981009) (xy 198.988141 -297.971165)
			(xy 199.037316 -297.969184) (xy 199.086171 -297.975116) (xy 199.133442 -297.988808) (xy 199.177904 -298.009906)
			(xy 199.218407 -298.037862) (xy 199.2539 -298.071954) (xy 199.283465 -298.111298) (xy 199.306336 -298.154875)
			(xy 199.32192 -298.201556) (xy 199.329815 -298.250133) (xy 199.33031 -298.27474) (xy 199.329815 -298.299347)
			(xy 199.32192 -298.347924) (xy 199.321344 -298.349649) (xy 199.767688 -298.349649) (xy 199.767688 -298.296351)
			(xy 199.775631 -298.243647) (xy 199.791341 -298.192717) (xy 199.814467 -298.144696) (xy 199.844491 -298.100659)
			(xy 199.880743 -298.061588) (xy 199.922414 -298.028357) (xy 199.968572 -298.001708) (xy 200.018186 -297.982236)
			(xy 200.070148 -297.970376) (xy 200.123298 -297.966393) (xy 200.176448 -297.970376) (xy 200.22841 -297.982236)
			(xy 200.235858 -297.985159) (xy 200.882748 -297.985159) (xy 200.882748 -297.931861) (xy 200.890691 -297.879157)
			(xy 200.906401 -297.828227) (xy 200.929527 -297.780206) (xy 200.959551 -297.736169) (xy 200.995803 -297.697098)
			(xy 201.037474 -297.663867) (xy 201.083632 -297.637218) (xy 201.133246 -297.617746) (xy 201.185208 -297.605886)
			(xy 201.238358 -297.601903) (xy 201.291508 -297.605886) (xy 201.34347 -297.617746) (xy 201.393084 -297.637218)
			(xy 201.439242 -297.663867) (xy 201.473008 -297.690794) (xy 202.399644 -297.690794) (xy 202.403715 -297.635172)
			(xy 202.415841 -297.580735) (xy 202.435764 -297.528644) (xy 202.46306 -297.480009) (xy 202.497146 -297.435866)
			(xy 202.537295 -297.397157) (xy 202.582653 -297.364706) (xy 202.632253 -297.339205) (xy 202.685037 -297.321198)
			(xy 202.73988 -297.311068) (xy 202.795614 -297.309031) (xy 202.851051 -297.315131) (xy 202.905008 -297.329237)
			(xy 202.956337 -297.351049) (xy 202.995283 -297.374818) (xy 208.715862 -297.374818) (xy 208.719933 -297.319196)
			(xy 208.732059 -297.264759) (xy 208.751982 -297.212668) (xy 208.779278 -297.164033) (xy 208.813364 -297.11989)
			(xy 208.853513 -297.081181) (xy 208.898871 -297.04873) (xy 208.948471 -297.023229) (xy 209.001255 -297.005222)
			(xy 209.056098 -296.995092) (xy 209.111832 -296.993055) (xy 209.167269 -296.999155) (xy 209.221226 -297.013261)
			(xy 209.272555 -297.035073) (xy 209.320161 -297.064127) (xy 209.363029 -297.099802) (xy 209.400246 -297.141339)
			(xy 209.431019 -297.187852) (xy 209.454691 -297.238349) (xy 209.470759 -297.291756) (xy 209.478879 -297.346932)
			(xy 209.479388 -297.374818) (xy 209.478879 -297.402704) (xy 209.470759 -297.45788) (xy 209.454691 -297.511287)
			(xy 209.431019 -297.561784) (xy 209.400246 -297.608297) (xy 209.363029 -297.649834) (xy 209.320161 -297.685509)
			(xy 209.272555 -297.714563) (xy 209.221226 -297.736375) (xy 209.167269 -297.750481) (xy 209.111832 -297.756581)
			(xy 209.056098 -297.754544) (xy 209.001255 -297.744414) (xy 208.948471 -297.726407) (xy 208.898871 -297.700906)
			(xy 208.853513 -297.668455) (xy 208.813364 -297.629746) (xy 208.779278 -297.585603) (xy 208.751982 -297.536968)
			(xy 208.732059 -297.484877) (xy 208.719933 -297.43044) (xy 208.715862 -297.374818) (xy 202.995283 -297.374818)
			(xy 203.003943 -297.380103) (xy 203.046811 -297.415778) (xy 203.084028 -297.457315) (xy 203.114801 -297.503828)
			(xy 203.138473 -297.554325) (xy 203.154541 -297.607732) (xy 203.162661 -297.662908) (xy 203.16317 -297.690794)
			(xy 203.162661 -297.71868) (xy 203.154541 -297.773856) (xy 203.138473 -297.827263) (xy 203.114801 -297.87776)
			(xy 203.084028 -297.924273) (xy 203.046811 -297.96581) (xy 203.003943 -298.001485) (xy 202.956337 -298.030539)
			(xy 202.905008 -298.052351) (xy 202.851051 -298.066457) (xy 202.795614 -298.072557) (xy 202.73988 -298.07052)
			(xy 202.685037 -298.06039) (xy 202.632253 -298.042383) (xy 202.582653 -298.016882) (xy 202.537295 -297.984431)
			(xy 202.497146 -297.945722) (xy 202.46306 -297.901579) (xy 202.435764 -297.852944) (xy 202.415841 -297.800853)
			(xy 202.403715 -297.746416) (xy 202.399644 -297.690794) (xy 201.473008 -297.690794) (xy 201.480913 -297.697098)
			(xy 201.517165 -297.736169) (xy 201.547189 -297.780206) (xy 201.570315 -297.828227) (xy 201.586025 -297.879157)
			(xy 201.593968 -297.931861) (xy 201.594466 -297.95851) (xy 201.593968 -297.985159) (xy 201.586025 -298.037863)
			(xy 201.570315 -298.088793) (xy 201.547189 -298.136814) (xy 201.517165 -298.180851) (xy 201.480913 -298.219922)
			(xy 201.439242 -298.253153) (xy 201.393084 -298.279802) (xy 201.34347 -298.299274) (xy 201.291508 -298.311134)
			(xy 201.238358 -298.315118) (xy 201.185208 -298.311134) (xy 201.133246 -298.299274) (xy 201.083632 -298.279802)
			(xy 201.037474 -298.253153) (xy 200.995803 -298.219922) (xy 200.959551 -298.180851) (xy 200.929527 -298.136814)
			(xy 200.906401 -298.088793) (xy 200.890691 -298.037863) (xy 200.882748 -297.985159) (xy 200.235858 -297.985159)
			(xy 200.278024 -298.001708) (xy 200.324182 -298.028357) (xy 200.365853 -298.061588) (xy 200.402105 -298.100659)
			(xy 200.432129 -298.144696) (xy 200.455255 -298.192717) (xy 200.470965 -298.243647) (xy 200.478908 -298.296351)
			(xy 200.479406 -298.323) (xy 200.478908 -298.349649) (xy 200.470965 -298.402353) (xy 200.455255 -298.453283)
			(xy 200.432129 -298.501304) (xy 200.402105 -298.545341) (xy 200.365853 -298.584412) (xy 200.324182 -298.617643)
			(xy 200.278024 -298.644292) (xy 200.22841 -298.663764) (xy 200.176448 -298.675624) (xy 200.123298 -298.679608)
			(xy 200.070148 -298.675624) (xy 200.018186 -298.663764) (xy 199.968572 -298.644292) (xy 199.922414 -298.617643)
			(xy 199.880743 -298.584412) (xy 199.844491 -298.545341) (xy 199.814467 -298.501304) (xy 199.791341 -298.453283)
			(xy 199.775631 -298.402353) (xy 199.767688 -298.349649) (xy 199.321344 -298.349649) (xy 199.306336 -298.394605)
			(xy 199.283465 -298.438182) (xy 199.2539 -298.477526) (xy 199.218407 -298.511618) (xy 199.177904 -298.539574)
			(xy 199.133442 -298.560672) (xy 199.086171 -298.574364) (xy 199.037316 -298.580296) (xy 198.988141 -298.578315)
			(xy 198.939922 -298.568471) (xy 198.893906 -298.551019) (xy 198.851285 -298.526412) (xy 198.813164 -298.495287)
			(xy 198.780529 -298.45845) (xy 198.754226 -298.416854) (xy 198.734935 -298.371578) (xy 198.723158 -298.323794)
			(xy 198.719198 -298.27474) (xy 198.38035 -298.27474) (xy 198.379855 -298.299347) (xy 198.37196 -298.347924)
			(xy 198.356376 -298.394605) (xy 198.333505 -298.438182) (xy 198.30394 -298.477526) (xy 198.268447 -298.511618)
			(xy 198.227944 -298.539574) (xy 198.183482 -298.560672) (xy 198.136211 -298.574364) (xy 198.087356 -298.580296)
			(xy 198.038181 -298.578315) (xy 197.989962 -298.568471) (xy 197.943946 -298.551019) (xy 197.901325 -298.526412)
			(xy 197.863204 -298.495287) (xy 197.830569 -298.45845) (xy 197.804266 -298.416854) (xy 197.784975 -298.371578)
			(xy 197.773198 -298.323794) (xy 197.769238 -298.27474) (xy 194.580256 -298.27474) (xy 194.579761 -298.299347)
			(xy 194.571866 -298.347924) (xy 194.556282 -298.394605) (xy 194.533411 -298.438182) (xy 194.503846 -298.477526)
			(xy 194.468353 -298.511618) (xy 194.42785 -298.539574) (xy 194.383388 -298.560672) (xy 194.336117 -298.574364)
			(xy 194.287262 -298.580296) (xy 194.238087 -298.578315) (xy 194.189868 -298.568471) (xy 194.143852 -298.551019)
			(xy 194.101231 -298.526412) (xy 194.06311 -298.495287) (xy 194.030475 -298.45845) (xy 194.004172 -298.416854)
			(xy 193.984881 -298.371578) (xy 193.973104 -298.323794) (xy 193.969144 -298.27474) (xy 193.630296 -298.27474)
			(xy 193.629801 -298.299347) (xy 193.621906 -298.347924) (xy 193.606322 -298.394605) (xy 193.583451 -298.438182)
			(xy 193.553886 -298.477526) (xy 193.518393 -298.511618) (xy 193.47789 -298.539574) (xy 193.433428 -298.560672)
			(xy 193.386157 -298.574364) (xy 193.337302 -298.580296) (xy 193.288127 -298.578315) (xy 193.239908 -298.568471)
			(xy 193.193892 -298.551019) (xy 193.151271 -298.526412) (xy 193.11315 -298.495287) (xy 193.080515 -298.45845)
			(xy 193.054212 -298.416854) (xy 193.034921 -298.371578) (xy 193.023144 -298.323794) (xy 193.019184 -298.27474)
			(xy 188.880242 -298.27474) (xy 188.879747 -298.299347) (xy 188.871852 -298.347924) (xy 188.856268 -298.394605)
			(xy 188.833397 -298.438182) (xy 188.803832 -298.477526) (xy 188.768339 -298.511618) (xy 188.727836 -298.539574)
			(xy 188.683374 -298.560672) (xy 188.636103 -298.574364) (xy 188.587248 -298.580296) (xy 188.538073 -298.578315)
			(xy 188.489854 -298.568471) (xy 188.443838 -298.551019) (xy 188.401217 -298.526412) (xy 188.363096 -298.495287)
			(xy 188.330461 -298.45845) (xy 188.304158 -298.416854) (xy 188.284867 -298.371578) (xy 188.27309 -298.323794)
			(xy 188.26913 -298.27474) (xy 186.980322 -298.27474) (xy 186.979827 -298.299347) (xy 186.971932 -298.347924)
			(xy 186.956348 -298.394605) (xy 186.933477 -298.438182) (xy 186.903912 -298.477526) (xy 186.868419 -298.511618)
			(xy 186.827916 -298.539574) (xy 186.783454 -298.560672) (xy 186.736183 -298.574364) (xy 186.687328 -298.580296)
			(xy 186.638153 -298.578315) (xy 186.589934 -298.568471) (xy 186.543918 -298.551019) (xy 186.501297 -298.526412)
			(xy 186.463176 -298.495287) (xy 186.430541 -298.45845) (xy 186.404238 -298.416854) (xy 186.384947 -298.371578)
			(xy 186.37317 -298.323794) (xy 186.36921 -298.27474) (xy 186.055762 -298.27474) (xy 186.055264 -298.300552)
			(xy 186.04724 -298.351547) (xy 186.031393 -298.400678) (xy 186.008108 -298.446752) (xy 185.977949 -298.48865)
			(xy 185.941649 -298.525355) (xy 185.900089 -298.555978) (xy 185.854278 -298.579773) (xy 185.829956 -298.58843)
			(xy 185.829702 -298.58843) (xy 185.822197 -298.591237) (xy 185.809365 -298.600818) (xy 185.804556 -298.607226)
			(xy 185.800238 -298.613576) (xy 185.795412 -298.628308) (xy 185.795412 -298.69765) (xy 202.569062 -298.69765)
			(xy 202.573133 -298.642028) (xy 202.585259 -298.587591) (xy 202.605182 -298.5355) (xy 202.632478 -298.486865)
			(xy 202.666564 -298.442722) (xy 202.706713 -298.404013) (xy 202.752071 -298.371562) (xy 202.801671 -298.346061)
			(xy 202.854455 -298.328054) (xy 202.909298 -298.317924) (xy 202.965032 -298.315887) (xy 203.020469 -298.321987)
			(xy 203.074426 -298.336093) (xy 203.125755 -298.357905) (xy 203.173361 -298.386959) (xy 203.216229 -298.422634)
			(xy 203.253446 -298.464171) (xy 203.284219 -298.510684) (xy 203.307891 -298.561181) (xy 203.323959 -298.614588)
			(xy 203.332079 -298.669764) (xy 203.332588 -298.69765) (xy 203.332079 -298.725536) (xy 203.323959 -298.780712)
			(xy 203.307891 -298.834119) (xy 203.284219 -298.884616) (xy 203.253446 -298.931129) (xy 203.216229 -298.972666)
			(xy 203.173361 -299.008341) (xy 203.125755 -299.037395) (xy 203.074426 -299.059207) (xy 203.020469 -299.073313)
			(xy 202.965032 -299.079413) (xy 202.909298 -299.077376) (xy 202.854455 -299.067246) (xy 202.801671 -299.049239)
			(xy 202.752071 -299.023738) (xy 202.706713 -298.991287) (xy 202.666564 -298.952578) (xy 202.632478 -298.908435)
			(xy 202.605182 -298.8598) (xy 202.585259 -298.807709) (xy 202.573133 -298.753272) (xy 202.569062 -298.69765)
			(xy 185.795412 -298.69765) (xy 185.795412 -298.841668) (xy 185.79551 -298.846545) (xy 185.797304 -298.856132)
			(xy 185.798968 -298.860718) (xy 185.802524 -298.869354) (xy 185.809636 -298.87672) (xy 185.81497 -298.882308)
			(xy 185.820201 -298.888108) (xy 185.827174 -298.902076) (xy 185.828686 -298.90974) (xy 185.828686 -298.909994)
			(xy 185.83021 -298.919138) (xy 185.834274 -298.926758) (xy 185.836605 -298.930762) (xy 185.842477 -298.937926)
			(xy 185.845958 -298.940982) (xy 185.854594 -298.948348) (xy 185.860436 -298.951396) (xy 185.881968 -298.962553)
			(xy 185.921499 -298.990637) (xy 185.956088 -299.024624) (xy 185.984861 -299.063657) (xy 186.007095 -299.106752)
			(xy 186.022227 -299.152823) (xy 186.029878 -299.200708) (xy 186.030362 -299.224954) (xy 188.26913 -299.224954)
			(xy 188.27309 -299.1759) (xy 188.284867 -299.128116) (xy 188.304158 -299.08284) (xy 188.330461 -299.041244)
			(xy 188.363096 -299.004407) (xy 188.401217 -298.973282) (xy 188.443838 -298.948675) (xy 188.489854 -298.931223)
			(xy 188.538073 -298.921379) (xy 188.587248 -298.919398) (xy 188.636103 -298.92533) (xy 188.683374 -298.939022)
			(xy 188.727836 -298.96012) (xy 188.768339 -298.988076) (xy 188.803832 -299.022168) (xy 188.833397 -299.061512)
			(xy 188.856268 -299.105089) (xy 188.871852 -299.15177) (xy 188.879747 -299.200347) (xy 188.880242 -299.224954)
			(xy 194.919104 -299.224954) (xy 194.923064 -299.1759) (xy 194.934841 -299.128116) (xy 194.954132 -299.08284)
			(xy 194.980435 -299.041244) (xy 195.01307 -299.004407) (xy 195.051191 -298.973282) (xy 195.093812 -298.948675)
			(xy 195.139828 -298.931223) (xy 195.188047 -298.921379) (xy 195.237222 -298.919398) (xy 195.286077 -298.92533)
			(xy 195.333348 -298.939022) (xy 195.37781 -298.96012) (xy 195.418313 -298.988076) (xy 195.453806 -299.022168)
			(xy 195.483371 -299.061512) (xy 195.506242 -299.105089) (xy 195.521826 -299.15177) (xy 195.529721 -299.200347)
			(xy 195.530216 -299.224954) (xy 195.869064 -299.224954) (xy 195.873024 -299.1759) (xy 195.884801 -299.128116)
			(xy 195.904092 -299.08284) (xy 195.930395 -299.041244) (xy 195.96303 -299.004407) (xy 196.001151 -298.973282)
			(xy 196.043772 -298.948675) (xy 196.089788 -298.931223) (xy 196.138007 -298.921379) (xy 196.187182 -298.919398)
			(xy 196.236037 -298.92533) (xy 196.283308 -298.939022) (xy 196.32777 -298.96012) (xy 196.368273 -298.988076)
			(xy 196.403766 -299.022168) (xy 196.433331 -299.061512) (xy 196.456202 -299.105089) (xy 196.471786 -299.15177)
			(xy 196.479681 -299.200347) (xy 196.480176 -299.224954) (xy 196.479681 -299.249561) (xy 196.475878 -299.27296)
			(xy 206.414622 -299.27296) (xy 206.418693 -299.217338) (xy 206.430819 -299.162901) (xy 206.450742 -299.11081)
			(xy 206.478038 -299.062175) (xy 206.512124 -299.018032) (xy 206.552273 -298.979323) (xy 206.597631 -298.946872)
			(xy 206.647231 -298.921371) (xy 206.700015 -298.903364) (xy 206.754858 -298.893234) (xy 206.810592 -298.891197)
			(xy 206.866029 -298.897297) (xy 206.919986 -298.911403) (xy 206.971315 -298.933215) (xy 207.018921 -298.962269)
			(xy 207.061789 -298.997944) (xy 207.099006 -299.039481) (xy 207.129779 -299.085994) (xy 207.153451 -299.136491)
			(xy 207.169519 -299.189898) (xy 207.177639 -299.245074) (xy 207.178148 -299.27296) (xy 207.177639 -299.300846)
			(xy 207.169519 -299.356022) (xy 207.153451 -299.409429) (xy 207.129779 -299.459926) (xy 207.099006 -299.506439)
			(xy 207.061789 -299.547976) (xy 207.018921 -299.583651) (xy 206.971315 -299.612705) (xy 206.919986 -299.634517)
			(xy 206.866029 -299.648623) (xy 206.810592 -299.654723) (xy 206.754858 -299.652686) (xy 206.700015 -299.642556)
			(xy 206.647231 -299.624549) (xy 206.597631 -299.599048) (xy 206.552273 -299.566597) (xy 206.512124 -299.527888)
			(xy 206.478038 -299.483745) (xy 206.450742 -299.43511) (xy 206.430819 -299.383019) (xy 206.418693 -299.328582)
			(xy 206.414622 -299.27296) (xy 196.475878 -299.27296) (xy 196.471786 -299.298138) (xy 196.456202 -299.344819)
			(xy 196.433331 -299.388396) (xy 196.403766 -299.42774) (xy 196.368273 -299.461832) (xy 196.32777 -299.489788)
			(xy 196.283308 -299.510886) (xy 196.236037 -299.524578) (xy 196.187182 -299.53051) (xy 196.138007 -299.528529)
			(xy 196.089788 -299.518685) (xy 196.043772 -299.501233) (xy 196.001151 -299.476626) (xy 195.96303 -299.445501)
			(xy 195.930395 -299.408664) (xy 195.904092 -299.367068) (xy 195.884801 -299.321792) (xy 195.873024 -299.274008)
			(xy 195.869064 -299.224954) (xy 195.530216 -299.224954) (xy 195.529721 -299.249561) (xy 195.521826 -299.298138)
			(xy 195.506242 -299.344819) (xy 195.483371 -299.388396) (xy 195.453806 -299.42774) (xy 195.418313 -299.461832)
			(xy 195.37781 -299.489788) (xy 195.333348 -299.510886) (xy 195.286077 -299.524578) (xy 195.237222 -299.53051)
			(xy 195.188047 -299.528529) (xy 195.139828 -299.518685) (xy 195.093812 -299.501233) (xy 195.051191 -299.476626)
			(xy 195.01307 -299.445501) (xy 194.980435 -299.408664) (xy 194.954132 -299.367068) (xy 194.934841 -299.321792)
			(xy 194.923064 -299.274008) (xy 194.919104 -299.224954) (xy 188.880242 -299.224954) (xy 188.879747 -299.249561)
			(xy 188.871852 -299.298138) (xy 188.856268 -299.344819) (xy 188.833397 -299.388396) (xy 188.803832 -299.42774)
			(xy 188.768339 -299.461832) (xy 188.727836 -299.489788) (xy 188.683374 -299.510886) (xy 188.636103 -299.524578)
			(xy 188.587248 -299.53051) (xy 188.538073 -299.528529) (xy 188.489854 -299.518685) (xy 188.443838 -299.501233)
			(xy 188.401217 -299.476626) (xy 188.363096 -299.445501) (xy 188.330461 -299.408664) (xy 188.304158 -299.367068)
			(xy 188.284867 -299.321792) (xy 188.27309 -299.274008) (xy 188.26913 -299.224954) (xy 186.030362 -299.224954)
			(xy 186.029921 -299.248312) (xy 186.022808 -299.294483) (xy 186.008741 -299.33903) (xy 185.988049 -299.380913)
			(xy 185.961215 -299.419152) (xy 185.928866 -299.452856) (xy 185.891759 -299.481235) (xy 185.85076 -299.503627)
			(xy 185.82894 -299.511974) (xy 185.826146 -299.51299) (xy 185.817507 -299.517138) (xy 185.803904 -299.530616)
			(xy 185.796187 -299.548142) (xy 185.795412 -299.557694) (xy 185.795412 -299.76445) (xy 204.14183 -299.76445)
			(xy 204.145901 -299.708828) (xy 204.158027 -299.654391) (xy 204.17795 -299.6023) (xy 204.205246 -299.553665)
			(xy 204.239332 -299.509522) (xy 204.279481 -299.470813) (xy 204.324839 -299.438362) (xy 204.374439 -299.412861)
			(xy 204.427223 -299.394854) (xy 204.482066 -299.384724) (xy 204.5378 -299.382687) (xy 204.593237 -299.388787)
			(xy 204.647194 -299.402893) (xy 204.698523 -299.424705) (xy 204.746129 -299.453759) (xy 204.788997 -299.489434)
			(xy 204.826214 -299.530971) (xy 204.856987 -299.577484) (xy 204.880659 -299.627981) (xy 204.896727 -299.681388)
			(xy 204.904847 -299.736564) (xy 204.905356 -299.76445) (xy 204.905078 -299.77969) (xy 208.738468 -299.77969)
			(xy 208.742539 -299.724068) (xy 208.754665 -299.669631) (xy 208.774588 -299.61754) (xy 208.801884 -299.568905)
			(xy 208.83597 -299.524762) (xy 208.876119 -299.486053) (xy 208.921477 -299.453602) (xy 208.971077 -299.428101)
			(xy 209.023861 -299.410094) (xy 209.078704 -299.399964) (xy 209.134438 -299.397927) (xy 209.189875 -299.404027)
			(xy 209.243832 -299.418133) (xy 209.295161 -299.439945) (xy 209.342767 -299.468999) (xy 209.385635 -299.504674)
			(xy 209.422852 -299.546211) (xy 209.453625 -299.592724) (xy 209.477297 -299.643221) (xy 209.493365 -299.696628)
			(xy 209.501485 -299.751804) (xy 209.501994 -299.77969) (xy 209.501485 -299.807576) (xy 209.493365 -299.862752)
			(xy 209.477297 -299.916159) (xy 209.453625 -299.966656) (xy 209.422852 -300.013169) (xy 209.385635 -300.054706)
			(xy 209.342767 -300.090381) (xy 209.295161 -300.119435) (xy 209.243832 -300.141247) (xy 209.189875 -300.155353)
			(xy 209.134438 -300.161453) (xy 209.078704 -300.159416) (xy 209.023861 -300.149286) (xy 208.971077 -300.131279)
			(xy 208.921477 -300.105778) (xy 208.876119 -300.073327) (xy 208.83597 -300.034618) (xy 208.801884 -299.990475)
			(xy 208.774588 -299.94184) (xy 208.754665 -299.889749) (xy 208.742539 -299.835312) (xy 208.738468 -299.77969)
			(xy 204.905078 -299.77969) (xy 204.904847 -299.792336) (xy 204.896727 -299.847512) (xy 204.880659 -299.900919)
			(xy 204.856987 -299.951416) (xy 204.826214 -299.997929) (xy 204.788997 -300.039466) (xy 204.746129 -300.075141)
			(xy 204.698523 -300.104195) (xy 204.647194 -300.126007) (xy 204.593237 -300.140113) (xy 204.5378 -300.146213)
			(xy 204.482066 -300.144176) (xy 204.427223 -300.134046) (xy 204.374439 -300.116039) (xy 204.324839 -300.090538)
			(xy 204.279481 -300.058087) (xy 204.239332 -300.019378) (xy 204.205246 -299.975235) (xy 204.17795 -299.9266)
			(xy 204.158027 -299.874509) (xy 204.145901 -299.820072) (xy 204.14183 -299.76445) (xy 185.795412 -299.76445)
			(xy 185.795412 -299.813218) (xy 185.795705 -299.821092) (xy 185.800486 -299.836096) (xy 185.80481 -299.842682)
			(xy 185.809382 -299.849032) (xy 185.822082 -299.858684) (xy 185.829956 -299.861224) (xy 185.854283 -299.869879)
			(xy 185.900112 -299.893658) (xy 185.941689 -299.92427) (xy 185.978004 -299.960971) (xy 186.008175 -300.00287)
			(xy 186.031469 -300.048947) (xy 186.04732 -300.098085) (xy 186.055342 -300.149089) (xy 186.055341 -300.174914)
			(xy 187.31917 -300.174914) (xy 187.32313 -300.12586) (xy 187.334907 -300.078076) (xy 187.354198 -300.0328)
			(xy 187.380501 -299.991204) (xy 187.413136 -299.954367) (xy 187.451257 -299.923242) (xy 187.493878 -299.898635)
			(xy 187.539894 -299.881183) (xy 187.588113 -299.871339) (xy 187.637288 -299.869358) (xy 187.686143 -299.87529)
			(xy 187.733414 -299.888982) (xy 187.777876 -299.91008) (xy 187.818379 -299.938036) (xy 187.853872 -299.972128)
			(xy 187.883437 -300.011472) (xy 187.906308 -300.055049) (xy 187.921892 -300.10173) (xy 187.929787 -300.150307)
			(xy 187.930282 -300.174914) (xy 189.21909 -300.174914) (xy 189.22305 -300.12586) (xy 189.234827 -300.078076)
			(xy 189.254118 -300.0328) (xy 189.280421 -299.991204) (xy 189.313056 -299.954367) (xy 189.351177 -299.923242)
			(xy 189.393798 -299.898635) (xy 189.439814 -299.881183) (xy 189.488033 -299.871339) (xy 189.537208 -299.869358)
			(xy 189.586063 -299.87529) (xy 189.633334 -299.888982) (xy 189.677796 -299.91008) (xy 189.718299 -299.938036)
			(xy 189.753792 -299.972128) (xy 189.783357 -300.011472) (xy 189.806228 -300.055049) (xy 189.821812 -300.10173)
			(xy 189.829707 -300.150307) (xy 189.830202 -300.174914) (xy 193.019184 -300.174914) (xy 193.023144 -300.12586)
			(xy 193.034921 -300.078076) (xy 193.054212 -300.0328) (xy 193.080515 -299.991204) (xy 193.11315 -299.954367)
			(xy 193.151271 -299.923242) (xy 193.193892 -299.898635) (xy 193.239908 -299.881183) (xy 193.288127 -299.871339)
			(xy 193.337302 -299.869358) (xy 193.386157 -299.87529) (xy 193.433428 -299.888982) (xy 193.47789 -299.91008)
			(xy 193.518393 -299.938036) (xy 193.553886 -299.972128) (xy 193.583451 -300.011472) (xy 193.606322 -300.055049)
			(xy 193.621906 -300.10173) (xy 193.629801 -300.150307) (xy 193.630296 -300.174914) (xy 193.969144 -300.174914)
			(xy 193.973104 -300.12586) (xy 193.984881 -300.078076) (xy 194.004172 -300.0328) (xy 194.030475 -299.991204)
			(xy 194.06311 -299.954367) (xy 194.101231 -299.923242) (xy 194.143852 -299.898635) (xy 194.189868 -299.881183)
			(xy 194.238087 -299.871339) (xy 194.287262 -299.869358) (xy 194.336117 -299.87529) (xy 194.383388 -299.888982)
			(xy 194.42785 -299.91008) (xy 194.468353 -299.938036) (xy 194.503846 -299.972128) (xy 194.533411 -300.011472)
			(xy 194.556282 -300.055049) (xy 194.571866 -300.10173) (xy 194.579761 -300.150307) (xy 194.580256 -300.174914)
			(xy 197.769238 -300.174914) (xy 197.773198 -300.12586) (xy 197.784975 -300.078076) (xy 197.804266 -300.0328)
			(xy 197.830569 -299.991204) (xy 197.863204 -299.954367) (xy 197.901325 -299.923242) (xy 197.943946 -299.898635)
			(xy 197.989962 -299.881183) (xy 198.038181 -299.871339) (xy 198.087356 -299.869358) (xy 198.136211 -299.87529)
			(xy 198.183482 -299.888982) (xy 198.227944 -299.91008) (xy 198.268447 -299.938036) (xy 198.30394 -299.972128)
			(xy 198.333505 -300.011472) (xy 198.356376 -300.055049) (xy 198.37196 -300.10173) (xy 198.379855 -300.150307)
			(xy 198.38035 -300.174914) (xy 198.719198 -300.174914) (xy 198.723158 -300.12586) (xy 198.734935 -300.078076)
			(xy 198.754226 -300.0328) (xy 198.780529 -299.991204) (xy 198.813164 -299.954367) (xy 198.851285 -299.923242)
			(xy 198.893906 -299.898635) (xy 198.939922 -299.881183) (xy 198.988141 -299.871339) (xy 199.037316 -299.869358)
			(xy 199.086171 -299.87529) (xy 199.133442 -299.888982) (xy 199.177904 -299.91008) (xy 199.218407 -299.938036)
			(xy 199.2539 -299.972128) (xy 199.283465 -300.011472) (xy 199.306336 -300.055049) (xy 199.32192 -300.10173)
			(xy 199.329815 -300.150307) (xy 199.33031 -300.174914) (xy 199.329815 -300.199521) (xy 199.32192 -300.248098)
			(xy 199.306336 -300.294779) (xy 199.283465 -300.338356) (xy 199.2539 -300.3777) (xy 199.218407 -300.411792)
			(xy 199.177904 -300.439748) (xy 199.133442 -300.460846) (xy 199.086171 -300.474538) (xy 199.037316 -300.48047)
			(xy 198.988141 -300.478489) (xy 198.939922 -300.468645) (xy 198.893906 -300.451193) (xy 198.851285 -300.426586)
			(xy 198.813164 -300.395461) (xy 198.780529 -300.358624) (xy 198.754226 -300.317028) (xy 198.734935 -300.271752)
			(xy 198.723158 -300.223968) (xy 198.719198 -300.174914) (xy 198.38035 -300.174914) (xy 198.379855 -300.199521)
			(xy 198.37196 -300.248098) (xy 198.356376 -300.294779) (xy 198.333505 -300.338356) (xy 198.30394 -300.3777)
			(xy 198.268447 -300.411792) (xy 198.227944 -300.439748) (xy 198.183482 -300.460846) (xy 198.136211 -300.474538)
			(xy 198.087356 -300.48047) (xy 198.038181 -300.478489) (xy 197.989962 -300.468645) (xy 197.943946 -300.451193)
			(xy 197.901325 -300.426586) (xy 197.863204 -300.395461) (xy 197.830569 -300.358624) (xy 197.804266 -300.317028)
			(xy 197.784975 -300.271752) (xy 197.773198 -300.223968) (xy 197.769238 -300.174914) (xy 194.580256 -300.174914)
			(xy 194.579761 -300.199521) (xy 194.571866 -300.248098) (xy 194.556282 -300.294779) (xy 194.533411 -300.338356)
			(xy 194.503846 -300.3777) (xy 194.468353 -300.411792) (xy 194.42785 -300.439748) (xy 194.383388 -300.460846)
			(xy 194.336117 -300.474538) (xy 194.287262 -300.48047) (xy 194.238087 -300.478489) (xy 194.189868 -300.468645)
			(xy 194.143852 -300.451193) (xy 194.101231 -300.426586) (xy 194.06311 -300.395461) (xy 194.030475 -300.358624)
			(xy 194.004172 -300.317028) (xy 193.984881 -300.271752) (xy 193.973104 -300.223968) (xy 193.969144 -300.174914)
			(xy 193.630296 -300.174914) (xy 193.629801 -300.199521) (xy 193.621906 -300.248098) (xy 193.606322 -300.294779)
			(xy 193.583451 -300.338356) (xy 193.553886 -300.3777) (xy 193.518393 -300.411792) (xy 193.47789 -300.439748)
			(xy 193.433428 -300.460846) (xy 193.386157 -300.474538) (xy 193.337302 -300.48047) (xy 193.288127 -300.478489)
			(xy 193.239908 -300.468645) (xy 193.193892 -300.451193) (xy 193.151271 -300.426586) (xy 193.11315 -300.395461)
			(xy 193.080515 -300.358624) (xy 193.054212 -300.317028) (xy 193.034921 -300.271752) (xy 193.023144 -300.223968)
			(xy 193.019184 -300.174914) (xy 189.830202 -300.174914) (xy 189.829707 -300.199521) (xy 189.821812 -300.248098)
			(xy 189.806228 -300.294779) (xy 189.783357 -300.338356) (xy 189.753792 -300.3777) (xy 189.718299 -300.411792)
			(xy 189.677796 -300.439748) (xy 189.633334 -300.460846) (xy 189.586063 -300.474538) (xy 189.537208 -300.48047)
			(xy 189.488033 -300.478489) (xy 189.439814 -300.468645) (xy 189.393798 -300.451193) (xy 189.351177 -300.426586)
			(xy 189.313056 -300.395461) (xy 189.280421 -300.358624) (xy 189.254118 -300.317028) (xy 189.234827 -300.271752)
			(xy 189.22305 -300.223968) (xy 189.21909 -300.174914) (xy 187.930282 -300.174914) (xy 187.929787 -300.199521)
			(xy 187.921892 -300.248098) (xy 187.906308 -300.294779) (xy 187.883437 -300.338356) (xy 187.853872 -300.3777)
			(xy 187.818379 -300.411792) (xy 187.777876 -300.439748) (xy 187.733414 -300.460846) (xy 187.686143 -300.474538)
			(xy 187.637288 -300.48047) (xy 187.588113 -300.478489) (xy 187.539894 -300.468645) (xy 187.493878 -300.451193)
			(xy 187.451257 -300.426586) (xy 187.413136 -300.395461) (xy 187.380501 -300.358624) (xy 187.354198 -300.317028)
			(xy 187.334907 -300.271752) (xy 187.32313 -300.223968) (xy 187.31917 -300.174914) (xy 186.055341 -300.174914)
			(xy 186.055341 -300.20072) (xy 186.047318 -300.251724) (xy 186.031466 -300.300861) (xy 186.008171 -300.346938)
			(xy 185.977998 -300.388836) (xy 185.941682 -300.425536) (xy 185.900104 -300.456147) (xy 185.854274 -300.479925)
			(xy 185.829956 -300.488604) (xy 185.829702 -300.488604) (xy 185.822196 -300.49141) (xy 185.80936 -300.500987)
			(xy 185.804556 -300.5074) (xy 185.800238 -300.51375) (xy 185.795412 -300.528482) (xy 185.795412 -300.741588)
			(xy 185.795512 -300.746465) (xy 185.797309 -300.756051) (xy 185.798968 -300.760638) (xy 185.802524 -300.769274)
			(xy 185.809636 -300.77664) (xy 185.81497 -300.782228) (xy 185.820199 -300.788029) (xy 185.827166 -300.801998)
			(xy 185.828686 -300.80966) (xy 185.828686 -300.809914) (xy 185.83021 -300.819058) (xy 185.834274 -300.826678)
			(xy 185.836606 -300.830681) (xy 185.84248 -300.837843) (xy 185.845958 -300.840902) (xy 185.854594 -300.848268)
			(xy 185.860436 -300.851316) (xy 185.881967 -300.862473) (xy 185.921497 -300.890558) (xy 185.956083 -300.924546)
			(xy 185.984854 -300.963579) (xy 186.007084 -301.006674) (xy 186.022214 -301.052744) (xy 186.029862 -301.100628)
			(xy 186.030362 -301.124874) (xy 194.919104 -301.124874) (xy 194.923064 -301.07582) (xy 194.934841 -301.028036)
			(xy 194.954132 -300.98276) (xy 194.980435 -300.941164) (xy 195.01307 -300.904327) (xy 195.051191 -300.873202)
			(xy 195.093812 -300.848595) (xy 195.139828 -300.831143) (xy 195.188047 -300.821299) (xy 195.237222 -300.819318)
			(xy 195.286077 -300.82525) (xy 195.333348 -300.838942) (xy 195.37781 -300.86004) (xy 195.418313 -300.887996)
			(xy 195.453806 -300.922088) (xy 195.483371 -300.961432) (xy 195.506242 -301.005009) (xy 195.521826 -301.05169)
			(xy 195.529721 -301.100267) (xy 195.530216 -301.124874) (xy 195.869064 -301.124874) (xy 195.873024 -301.07582)
			(xy 195.884801 -301.028036) (xy 195.904092 -300.98276) (xy 195.930395 -300.941164) (xy 195.96303 -300.904327)
			(xy 196.001151 -300.873202) (xy 196.043772 -300.848595) (xy 196.089788 -300.831143) (xy 196.138007 -300.821299)
			(xy 196.187182 -300.819318) (xy 196.236037 -300.82525) (xy 196.283308 -300.838942) (xy 196.32777 -300.86004)
			(xy 196.368273 -300.887996) (xy 196.403766 -300.922088) (xy 196.433331 -300.961432) (xy 196.456202 -301.005009)
			(xy 196.468574 -301.04207) (xy 206.417162 -301.04207) (xy 206.421233 -300.986448) (xy 206.433359 -300.932011)
			(xy 206.453282 -300.87992) (xy 206.480578 -300.831285) (xy 206.514664 -300.787142) (xy 206.554813 -300.748433)
			(xy 206.600171 -300.715982) (xy 206.649771 -300.690481) (xy 206.702555 -300.672474) (xy 206.757398 -300.662344)
			(xy 206.813132 -300.660307) (xy 206.868569 -300.666407) (xy 206.922526 -300.680513) (xy 206.973855 -300.702325)
			(xy 207.021461 -300.731379) (xy 207.064329 -300.767054) (xy 207.101546 -300.808591) (xy 207.132319 -300.855104)
			(xy 207.155991 -300.905601) (xy 207.172059 -300.959008) (xy 207.180179 -301.014184) (xy 207.180688 -301.04207)
			(xy 207.180535 -301.050452) (xy 208.791046 -301.050452) (xy 208.795117 -300.99483) (xy 208.807243 -300.940393)
			(xy 208.827166 -300.888302) (xy 208.854462 -300.839667) (xy 208.888548 -300.795524) (xy 208.928697 -300.756815)
			(xy 208.974055 -300.724364) (xy 209.023655 -300.698863) (xy 209.076439 -300.680856) (xy 209.131282 -300.670726)
			(xy 209.187016 -300.668689) (xy 209.242453 -300.674789) (xy 209.29641 -300.688895) (xy 209.347739 -300.710707)
			(xy 209.395345 -300.739761) (xy 209.438213 -300.775436) (xy 209.47543 -300.816973) (xy 209.506203 -300.863486)
			(xy 209.529875 -300.913983) (xy 209.545943 -300.96739) (xy 209.554063 -301.022566) (xy 209.554572 -301.050452)
			(xy 209.554063 -301.078338) (xy 209.545943 -301.133514) (xy 209.529875 -301.186921) (xy 209.506203 -301.237418)
			(xy 209.47543 -301.283931) (xy 209.438213 -301.325468) (xy 209.395345 -301.361143) (xy 209.347739 -301.390197)
			(xy 209.29641 -301.412009) (xy 209.242453 -301.426115) (xy 209.187016 -301.432215) (xy 209.131282 -301.430178)
			(xy 209.076439 -301.420048) (xy 209.023655 -301.402041) (xy 208.974055 -301.37654) (xy 208.928697 -301.344089)
			(xy 208.888548 -301.30538) (xy 208.854462 -301.261237) (xy 208.827166 -301.212602) (xy 208.807243 -301.160511)
			(xy 208.795117 -301.106074) (xy 208.791046 -301.050452) (xy 207.180535 -301.050452) (xy 207.180179 -301.069956)
			(xy 207.172059 -301.125132) (xy 207.155991 -301.178539) (xy 207.132319 -301.229036) (xy 207.101546 -301.275549)
			(xy 207.064329 -301.317086) (xy 207.021461 -301.352761) (xy 206.973855 -301.381815) (xy 206.922526 -301.403627)
			(xy 206.868569 -301.417733) (xy 206.813132 -301.423833) (xy 206.757398 -301.421796) (xy 206.702555 -301.411666)
			(xy 206.649771 -301.393659) (xy 206.600171 -301.368158) (xy 206.554813 -301.335707) (xy 206.514664 -301.296998)
			(xy 206.480578 -301.252855) (xy 206.453282 -301.20422) (xy 206.433359 -301.152129) (xy 206.421233 -301.097692)
			(xy 206.417162 -301.04207) (xy 196.468574 -301.04207) (xy 196.471786 -301.05169) (xy 196.479681 -301.100267)
			(xy 196.480176 -301.124874) (xy 196.479681 -301.149481) (xy 196.471786 -301.198058) (xy 196.456202 -301.244739)
			(xy 196.433331 -301.288316) (xy 196.403766 -301.32766) (xy 196.368273 -301.361752) (xy 196.32777 -301.389708)
			(xy 196.283308 -301.410806) (xy 196.236037 -301.424498) (xy 196.187182 -301.43043) (xy 196.138007 -301.428449)
			(xy 196.089788 -301.418605) (xy 196.043772 -301.401153) (xy 196.001151 -301.376546) (xy 195.96303 -301.345421)
			(xy 195.930395 -301.308584) (xy 195.904092 -301.266988) (xy 195.884801 -301.221712) (xy 195.873024 -301.173928)
			(xy 195.869064 -301.124874) (xy 195.530216 -301.124874) (xy 195.529721 -301.149481) (xy 195.521826 -301.198058)
			(xy 195.506242 -301.244739) (xy 195.483371 -301.288316) (xy 195.453806 -301.32766) (xy 195.418313 -301.361752)
			(xy 195.37781 -301.389708) (xy 195.333348 -301.410806) (xy 195.286077 -301.424498) (xy 195.237222 -301.43043)
			(xy 195.188047 -301.428449) (xy 195.139828 -301.418605) (xy 195.093812 -301.401153) (xy 195.051191 -301.376546)
			(xy 195.01307 -301.345421) (xy 194.980435 -301.308584) (xy 194.954132 -301.266988) (xy 194.934841 -301.221712)
			(xy 194.923064 -301.173928) (xy 194.919104 -301.124874) (xy 186.030362 -301.124874) (xy 186.029919 -301.148231)
			(xy 186.022804 -301.1944) (xy 186.008735 -301.238945) (xy 185.988041 -301.280825) (xy 185.961207 -301.319062)
			(xy 185.928858 -301.352763) (xy 185.891751 -301.38114) (xy 185.850753 -301.40353) (xy 185.82894 -301.411894)
			(xy 185.826146 -301.41291) (xy 185.817509 -301.417058) (xy 185.803911 -301.430538) (xy 185.796201 -301.448064)
			(xy 185.795412 -301.457614) (xy 185.795412 -301.691548) (xy 185.795508 -301.696425) (xy 185.797298 -301.706014)
			(xy 185.798968 -301.710598) (xy 185.802524 -301.719234) (xy 185.809636 -301.7266) (xy 185.81497 -301.732188)
			(xy 185.820204 -301.737987) (xy 185.827182 -301.751954) (xy 185.828686 -301.75962) (xy 185.828686 -301.759874)
			(xy 185.83021 -301.769018) (xy 185.834274 -301.776638) (xy 185.83661 -301.780638) (xy 185.842489 -301.787793)
			(xy 185.845958 -301.790862) (xy 185.854594 -301.798228) (xy 185.860436 -301.801276) (xy 185.881969 -301.812432)
			(xy 185.921502 -301.840516) (xy 185.956093 -301.874503) (xy 185.984869 -301.913536) (xy 186.007105 -301.956631)
			(xy 186.022241 -302.002701) (xy 186.029894 -302.050587) (xy 186.030362 -302.074834) (xy 188.26913 -302.074834)
			(xy 188.27309 -302.02578) (xy 188.284867 -301.977996) (xy 188.304158 -301.93272) (xy 188.330461 -301.891124)
			(xy 188.363096 -301.854287) (xy 188.401217 -301.823162) (xy 188.443838 -301.798555) (xy 188.489854 -301.781103)
			(xy 188.538073 -301.771259) (xy 188.587248 -301.769278) (xy 188.636103 -301.77521) (xy 188.683374 -301.788902)
			(xy 188.727836 -301.81) (xy 188.768339 -301.837956) (xy 188.803832 -301.872048) (xy 188.833397 -301.911392)
			(xy 188.856268 -301.954969) (xy 188.871852 -302.00165) (xy 188.879747 -302.050227) (xy 188.880242 -302.074834)
			(xy 189.21909 -302.074834) (xy 189.22305 -302.02578) (xy 189.234827 -301.977996) (xy 189.254118 -301.93272)
			(xy 189.280421 -301.891124) (xy 189.313056 -301.854287) (xy 189.351177 -301.823162) (xy 189.393798 -301.798555)
			(xy 189.439814 -301.781103) (xy 189.488033 -301.771259) (xy 189.537208 -301.769278) (xy 189.586063 -301.77521)
			(xy 189.633334 -301.788902) (xy 189.677796 -301.81) (xy 189.718299 -301.837956) (xy 189.753792 -301.872048)
			(xy 189.783357 -301.911392) (xy 189.806228 -301.954969) (xy 189.821812 -302.00165) (xy 189.829707 -302.050227)
			(xy 189.830202 -302.074834) (xy 197.769238 -302.074834) (xy 197.773198 -302.02578) (xy 197.784975 -301.977996)
			(xy 197.804266 -301.93272) (xy 197.830569 -301.891124) (xy 197.863204 -301.854287) (xy 197.901325 -301.823162)
			(xy 197.943946 -301.798555) (xy 197.989962 -301.781103) (xy 198.038181 -301.771259) (xy 198.087356 -301.769278)
			(xy 198.136211 -301.77521) (xy 198.183482 -301.788902) (xy 198.227944 -301.81) (xy 198.268447 -301.837956)
			(xy 198.30394 -301.872048) (xy 198.333505 -301.911392) (xy 198.356376 -301.954969) (xy 198.37196 -302.00165)
			(xy 198.379855 -302.050227) (xy 198.38035 -302.074834) (xy 198.719198 -302.074834) (xy 198.723158 -302.02578)
			(xy 198.734935 -301.977996) (xy 198.754226 -301.93272) (xy 198.780529 -301.891124) (xy 198.813164 -301.854287)
			(xy 198.851285 -301.823162) (xy 198.893906 -301.798555) (xy 198.939922 -301.781103) (xy 198.988141 -301.771259)
			(xy 199.037316 -301.769278) (xy 199.086171 -301.77521) (xy 199.133442 -301.788902) (xy 199.177904 -301.81)
			(xy 199.218407 -301.837956) (xy 199.22015 -301.83963) (xy 202.44765 -301.83963) (xy 202.451721 -301.784008)
			(xy 202.463847 -301.729571) (xy 202.48377 -301.67748) (xy 202.511066 -301.628845) (xy 202.545152 -301.584702)
			(xy 202.585301 -301.545993) (xy 202.630659 -301.513542) (xy 202.680259 -301.488041) (xy 202.733043 -301.470034)
			(xy 202.787886 -301.459904) (xy 202.84362 -301.457867) (xy 202.899057 -301.463967) (xy 202.953014 -301.478073)
			(xy 203.004343 -301.499885) (xy 203.051949 -301.528939) (xy 203.080393 -301.55261) (xy 204.219808 -301.55261)
			(xy 204.223879 -301.496988) (xy 204.236005 -301.442551) (xy 204.255928 -301.39046) (xy 204.283224 -301.341825)
			(xy 204.31731 -301.297682) (xy 204.357459 -301.258973) (xy 204.402817 -301.226522) (xy 204.452417 -301.201021)
			(xy 204.505201 -301.183014) (xy 204.560044 -301.172884) (xy 204.615778 -301.170847) (xy 204.671215 -301.176947)
			(xy 204.725172 -301.191053) (xy 204.776501 -301.212865) (xy 204.824107 -301.241919) (xy 204.866975 -301.277594)
			(xy 204.904192 -301.319131) (xy 204.934965 -301.365644) (xy 204.958637 -301.416141) (xy 204.974705 -301.469548)
			(xy 204.982825 -301.524724) (xy 204.983334 -301.55261) (xy 204.982894 -301.57674) (xy 207.613248 -301.57674)
			(xy 207.617319 -301.521118) (xy 207.629445 -301.466681) (xy 207.649368 -301.41459) (xy 207.676664 -301.365955)
			(xy 207.71075 -301.321812) (xy 207.750899 -301.283103) (xy 207.796257 -301.250652) (xy 207.845857 -301.225151)
			(xy 207.898641 -301.207144) (xy 207.953484 -301.197014) (xy 208.009218 -301.194977) (xy 208.064655 -301.201077)
			(xy 208.118612 -301.215183) (xy 208.169941 -301.236995) (xy 208.217547 -301.266049) (xy 208.260415 -301.301724)
			(xy 208.297632 -301.343261) (xy 208.328405 -301.389774) (xy 208.352077 -301.440271) (xy 208.368145 -301.493678)
			(xy 208.376265 -301.548854) (xy 208.376774 -301.57674) (xy 208.376265 -301.604626) (xy 208.368145 -301.659802)
			(xy 208.352077 -301.713209) (xy 208.328405 -301.763706) (xy 208.297632 -301.810219) (xy 208.260415 -301.851756)
			(xy 208.217547 -301.887431) (xy 208.169941 -301.916485) (xy 208.118612 -301.938297) (xy 208.064655 -301.952403)
			(xy 208.009218 -301.958503) (xy 207.953484 -301.956466) (xy 207.898641 -301.946336) (xy 207.845857 -301.928329)
			(xy 207.796257 -301.902828) (xy 207.750899 -301.870377) (xy 207.71075 -301.831668) (xy 207.676664 -301.787525)
			(xy 207.649368 -301.73889) (xy 207.629445 -301.686799) (xy 207.617319 -301.632362) (xy 207.613248 -301.57674)
			(xy 204.982894 -301.57674) (xy 204.982825 -301.580496) (xy 204.974705 -301.635672) (xy 204.958637 -301.689079)
			(xy 204.934965 -301.739576) (xy 204.904192 -301.786089) (xy 204.866975 -301.827626) (xy 204.824107 -301.863301)
			(xy 204.776501 -301.892355) (xy 204.725172 -301.914167) (xy 204.671215 -301.928273) (xy 204.615778 -301.934373)
			(xy 204.560044 -301.932336) (xy 204.505201 -301.922206) (xy 204.452417 -301.904199) (xy 204.402817 -301.878698)
			(xy 204.357459 -301.846247) (xy 204.31731 -301.807538) (xy 204.283224 -301.763395) (xy 204.255928 -301.71476)
			(xy 204.236005 -301.662669) (xy 204.223879 -301.608232) (xy 204.219808 -301.55261) (xy 203.080393 -301.55261)
			(xy 203.094817 -301.564614) (xy 203.132034 -301.606151) (xy 203.162807 -301.652664) (xy 203.186479 -301.703161)
			(xy 203.202547 -301.756568) (xy 203.210667 -301.811744) (xy 203.211176 -301.83963) (xy 203.210667 -301.867516)
			(xy 203.202547 -301.922692) (xy 203.186479 -301.976099) (xy 203.162807 -302.026596) (xy 203.132034 -302.073109)
			(xy 203.094817 -302.114646) (xy 203.051949 -302.150321) (xy 203.004343 -302.179375) (xy 202.953014 -302.201187)
			(xy 202.899057 -302.215293) (xy 202.84362 -302.221393) (xy 202.787886 -302.219356) (xy 202.733043 -302.209226)
			(xy 202.680259 -302.191219) (xy 202.630659 -302.165718) (xy 202.585301 -302.133267) (xy 202.545152 -302.094558)
			(xy 202.511066 -302.050415) (xy 202.48377 -302.00178) (xy 202.463847 -301.949689) (xy 202.451721 -301.895252)
			(xy 202.44765 -301.83963) (xy 199.22015 -301.83963) (xy 199.2539 -301.872048) (xy 199.283465 -301.911392)
			(xy 199.306336 -301.954969) (xy 199.32192 -302.00165) (xy 199.329815 -302.050227) (xy 199.33031 -302.074834)
			(xy 199.329815 -302.099441) (xy 199.32192 -302.148018) (xy 199.306336 -302.194699) (xy 199.283465 -302.238276)
			(xy 199.2539 -302.27762) (xy 199.218407 -302.311712) (xy 199.177904 -302.339668) (xy 199.133442 -302.360766)
			(xy 199.086171 -302.374458) (xy 199.037316 -302.38039) (xy 198.988141 -302.378409) (xy 198.939922 -302.368565)
			(xy 198.893906 -302.351113) (xy 198.851285 -302.326506) (xy 198.813164 -302.295381) (xy 198.780529 -302.258544)
			(xy 198.754226 -302.216948) (xy 198.734935 -302.171672) (xy 198.723158 -302.123888) (xy 198.719198 -302.074834)
			(xy 198.38035 -302.074834) (xy 198.379855 -302.099441) (xy 198.37196 -302.148018) (xy 198.356376 -302.194699)
			(xy 198.333505 -302.238276) (xy 198.30394 -302.27762) (xy 198.268447 -302.311712) (xy 198.227944 -302.339668)
			(xy 198.183482 -302.360766) (xy 198.136211 -302.374458) (xy 198.087356 -302.38039) (xy 198.038181 -302.378409)
			(xy 197.989962 -302.368565) (xy 197.943946 -302.351113) (xy 197.901325 -302.326506) (xy 197.863204 -302.295381)
			(xy 197.830569 -302.258544) (xy 197.804266 -302.216948) (xy 197.784975 -302.171672) (xy 197.773198 -302.123888)
			(xy 197.769238 -302.074834) (xy 189.830202 -302.074834) (xy 189.829707 -302.099441) (xy 189.821812 -302.148018)
			(xy 189.806228 -302.194699) (xy 189.783357 -302.238276) (xy 189.753792 -302.27762) (xy 189.718299 -302.311712)
			(xy 189.677796 -302.339668) (xy 189.633334 -302.360766) (xy 189.586063 -302.374458) (xy 189.537208 -302.38039)
			(xy 189.488033 -302.378409) (xy 189.439814 -302.368565) (xy 189.393798 -302.351113) (xy 189.351177 -302.326506)
			(xy 189.313056 -302.295381) (xy 189.280421 -302.258544) (xy 189.254118 -302.216948) (xy 189.234827 -302.171672)
			(xy 189.22305 -302.123888) (xy 189.21909 -302.074834) (xy 188.880242 -302.074834) (xy 188.879747 -302.099441)
			(xy 188.871852 -302.148018) (xy 188.856268 -302.194699) (xy 188.833397 -302.238276) (xy 188.803832 -302.27762)
			(xy 188.768339 -302.311712) (xy 188.727836 -302.339668) (xy 188.683374 -302.360766) (xy 188.636103 -302.374458)
			(xy 188.587248 -302.38039) (xy 188.538073 -302.378409) (xy 188.489854 -302.368565) (xy 188.443838 -302.351113)
			(xy 188.401217 -302.326506) (xy 188.363096 -302.295381) (xy 188.330461 -302.258544) (xy 188.304158 -302.216948)
			(xy 188.284867 -302.171672) (xy 188.27309 -302.123888) (xy 188.26913 -302.074834) (xy 186.030362 -302.074834)
			(xy 186.029922 -302.098193) (xy 186.022812 -302.144365) (xy 186.008747 -302.188915) (xy 185.988056 -302.2308)
			(xy 185.961223 -302.269043) (xy 185.928874 -302.302748) (xy 185.891767 -302.33113) (xy 185.850767 -302.353524)
			(xy 185.82894 -302.361854) (xy 185.826146 -302.36287) (xy 185.817505 -302.367017) (xy 185.803896 -302.380494)
			(xy 185.796173 -302.39802) (xy 185.795412 -302.407574) (xy 185.795412 -302.641508) (xy 185.795505 -302.646386)
			(xy 185.797288 -302.655978) (xy 185.798968 -302.660558) (xy 185.802524 -302.669194) (xy 185.809636 -302.67656)
			(xy 185.81497 -302.682148) (xy 185.820208 -302.687945) (xy 185.827197 -302.70191) (xy 185.828633 -302.709305)
			(xy 200.909418 -302.709305) (xy 200.909418 -302.656007) (xy 200.917361 -302.603303) (xy 200.933071 -302.552373)
			(xy 200.956197 -302.504352) (xy 200.986221 -302.460315) (xy 201.022473 -302.421244) (xy 201.064144 -302.388013)
			(xy 201.110302 -302.361364) (xy 201.159916 -302.341892) (xy 201.211878 -302.330032) (xy 201.265028 -302.326049)
			(xy 201.318178 -302.330032) (xy 201.37014 -302.341892) (xy 201.419754 -302.361364) (xy 201.465912 -302.388013)
			(xy 201.507583 -302.421244) (xy 201.543835 -302.460315) (xy 201.573859 -302.504352) (xy 201.596985 -302.552373)
			(xy 201.612695 -302.603303) (xy 201.620638 -302.656007) (xy 201.621136 -302.682656) (xy 201.620638 -302.709305)
			(xy 201.612695 -302.762009) (xy 201.596985 -302.812939) (xy 201.573859 -302.86096) (xy 201.543835 -302.904997)
			(xy 201.507583 -302.944068) (xy 201.465912 -302.977299) (xy 201.419754 -303.003948) (xy 201.37014 -303.02342)
			(xy 201.318178 -303.03528) (xy 201.265028 -303.039264) (xy 201.211878 -303.03528) (xy 201.159916 -303.02342)
			(xy 201.110302 -303.003948) (xy 201.064144 -302.977299) (xy 201.022473 -302.944068) (xy 200.986221 -302.904997)
			(xy 200.956197 -302.86096) (xy 200.933071 -302.812939) (xy 200.917361 -302.762009) (xy 200.909418 -302.709305)
			(xy 185.828633 -302.709305) (xy 185.828686 -302.70958) (xy 185.828686 -302.709834) (xy 185.83021 -302.718978)
			(xy 185.834274 -302.726598) (xy 185.836607 -302.7306) (xy 185.842483 -302.737759) (xy 185.845958 -302.740822)
			(xy 185.854594 -302.748188) (xy 185.860436 -302.751236) (xy 185.881966 -302.762393) (xy 185.921494 -302.790479)
			(xy 185.956078 -302.824467) (xy 185.984846 -302.863501) (xy 186.007074 -302.906596) (xy 186.022201 -302.952666)
			(xy 186.029845 -303.000549) (xy 186.030362 -303.024794) (xy 194.919104 -303.024794) (xy 194.923064 -302.97574)
			(xy 194.934841 -302.927956) (xy 194.954132 -302.88268) (xy 194.980435 -302.841084) (xy 195.01307 -302.804247)
			(xy 195.051191 -302.773122) (xy 195.093812 -302.748515) (xy 195.139828 -302.731063) (xy 195.188047 -302.721219)
			(xy 195.237222 -302.719238) (xy 195.286077 -302.72517) (xy 195.333348 -302.738862) (xy 195.37781 -302.75996)
			(xy 195.418313 -302.787916) (xy 195.453806 -302.822008) (xy 195.483371 -302.861352) (xy 195.506242 -302.904929)
			(xy 195.521826 -302.95161) (xy 195.529721 -303.000187) (xy 195.530216 -303.024794) (xy 195.869064 -303.024794)
			(xy 195.873024 -302.97574) (xy 195.884801 -302.927956) (xy 195.904092 -302.88268) (xy 195.930395 -302.841084)
			(xy 195.96303 -302.804247) (xy 196.001151 -302.773122) (xy 196.043772 -302.748515) (xy 196.089788 -302.731063)
			(xy 196.138007 -302.721219) (xy 196.187182 -302.719238) (xy 196.236037 -302.72517) (xy 196.283308 -302.738862)
			(xy 196.32777 -302.75996) (xy 196.368273 -302.787916) (xy 196.403766 -302.822008) (xy 196.433331 -302.861352)
			(xy 196.456202 -302.904929) (xy 196.471786 -302.95161) (xy 196.479681 -303.000187) (xy 196.480176 -303.024794)
			(xy 196.479681 -303.049401) (xy 196.479511 -303.050448) (xy 203.950314 -303.050448) (xy 203.954385 -302.994826)
			(xy 203.966511 -302.940389) (xy 203.986434 -302.888298) (xy 204.01373 -302.839663) (xy 204.047816 -302.79552)
			(xy 204.087965 -302.756811) (xy 204.133323 -302.72436) (xy 204.182923 -302.698859) (xy 204.235707 -302.680852)
			(xy 204.29055 -302.670722) (xy 204.346284 -302.668685) (xy 204.401721 -302.674785) (xy 204.455678 -302.688891)
			(xy 204.507007 -302.710703) (xy 204.554613 -302.739757) (xy 204.597481 -302.775432) (xy 204.634698 -302.816969)
			(xy 204.665471 -302.863482) (xy 204.689143 -302.913979) (xy 204.705211 -302.967386) (xy 204.713331 -303.022562)
			(xy 204.71384 -303.050448) (xy 204.713331 -303.078334) (xy 204.705211 -303.13351) (xy 204.689143 -303.186917)
			(xy 204.665471 -303.237414) (xy 204.634698 -303.283927) (xy 204.597481 -303.325464) (xy 204.554613 -303.361139)
			(xy 204.507007 -303.390193) (xy 204.455678 -303.412005) (xy 204.401721 -303.426111) (xy 204.346284 -303.432211)
			(xy 204.29055 -303.430174) (xy 204.235707 -303.420044) (xy 204.182923 -303.402037) (xy 204.133323 -303.376536)
			(xy 204.087965 -303.344085) (xy 204.047816 -303.305376) (xy 204.01373 -303.261233) (xy 203.986434 -303.212598)
			(xy 203.966511 -303.160507) (xy 203.954385 -303.10607) (xy 203.950314 -303.050448) (xy 196.479511 -303.050448)
			(xy 196.471786 -303.097978) (xy 196.456202 -303.144659) (xy 196.433331 -303.188236) (xy 196.403766 -303.22758)
			(xy 196.368273 -303.261672) (xy 196.32777 -303.289628) (xy 196.283308 -303.310726) (xy 196.236037 -303.324418)
			(xy 196.187182 -303.33035) (xy 196.138007 -303.328369) (xy 196.089788 -303.318525) (xy 196.043772 -303.301073)
			(xy 196.001151 -303.276466) (xy 195.96303 -303.245341) (xy 195.930395 -303.208504) (xy 195.904092 -303.166908)
			(xy 195.884801 -303.121632) (xy 195.873024 -303.073848) (xy 195.869064 -303.024794) (xy 195.530216 -303.024794)
			(xy 195.529721 -303.049401) (xy 195.521826 -303.097978) (xy 195.506242 -303.144659) (xy 195.483371 -303.188236)
			(xy 195.453806 -303.22758) (xy 195.418313 -303.261672) (xy 195.37781 -303.289628) (xy 195.333348 -303.310726)
			(xy 195.286077 -303.324418) (xy 195.237222 -303.33035) (xy 195.188047 -303.328369) (xy 195.139828 -303.318525)
			(xy 195.093812 -303.301073) (xy 195.051191 -303.276466) (xy 195.01307 -303.245341) (xy 194.980435 -303.208504)
			(xy 194.954132 -303.166908) (xy 194.934841 -303.121632) (xy 194.923064 -303.073848) (xy 194.919104 -303.024794)
			(xy 186.030362 -303.024794) (xy 186.029925 -303.048154) (xy 186.02282 -303.094331) (xy 186.008758 -303.138886)
			(xy 185.98807 -303.180776) (xy 185.961239 -303.219023) (xy 185.928891 -303.252734) (xy 185.891782 -303.28112)
			(xy 185.85078 -303.303517) (xy 185.82894 -303.311814) (xy 185.826146 -303.31283) (xy 185.817511 -303.31698)
			(xy 185.803918 -303.33046) (xy 185.796215 -303.347986) (xy 185.795412 -303.357534) (xy 185.795412 -303.613058)
			(xy 185.79571 -303.62093) (xy 185.800502 -303.635927) (xy 185.80481 -303.642522) (xy 185.809382 -303.648872)
			(xy 185.822082 -303.658524) (xy 185.829956 -303.661064) (xy 185.854287 -303.669719) (xy 185.900125 -303.6935)
			(xy 185.941712 -303.724115) (xy 185.978035 -303.76082) (xy 186.008214 -303.802724) (xy 186.031514 -303.848808)
			(xy 186.047371 -303.897953) (xy 186.055397 -303.948965) (xy 186.055398 -303.974754) (xy 186.36921 -303.974754)
			(xy 186.37317 -303.9257) (xy 186.384947 -303.877916) (xy 186.404238 -303.83264) (xy 186.430541 -303.791044)
			(xy 186.463176 -303.754207) (xy 186.501297 -303.723082) (xy 186.543918 -303.698475) (xy 186.589934 -303.681023)
			(xy 186.638153 -303.671179) (xy 186.687328 -303.669198) (xy 186.736183 -303.67513) (xy 186.783454 -303.688822)
			(xy 186.827916 -303.70992) (xy 186.868419 -303.737876) (xy 186.903912 -303.771968) (xy 186.933477 -303.811312)
			(xy 186.956348 -303.854889) (xy 186.971932 -303.90157) (xy 186.979827 -303.950147) (xy 186.980322 -303.974754)
			(xy 188.26913 -303.974754) (xy 188.27309 -303.9257) (xy 188.284867 -303.877916) (xy 188.304158 -303.83264)
			(xy 188.330461 -303.791044) (xy 188.363096 -303.754207) (xy 188.401217 -303.723082) (xy 188.443838 -303.698475)
			(xy 188.489854 -303.681023) (xy 188.538073 -303.671179) (xy 188.587248 -303.669198) (xy 188.636103 -303.67513)
			(xy 188.683374 -303.688822) (xy 188.727836 -303.70992) (xy 188.749052 -303.724564) (xy 201.429364 -303.724564)
			(xy 201.433435 -303.668942) (xy 201.445561 -303.614505) (xy 201.465484 -303.562414) (xy 201.49278 -303.513779)
			(xy 201.526866 -303.469636) (xy 201.567015 -303.430927) (xy 201.612373 -303.398476) (xy 201.661973 -303.372975)
			(xy 201.714757 -303.354968) (xy 201.7696 -303.344838) (xy 201.825334 -303.342801) (xy 201.880771 -303.348901)
			(xy 201.934728 -303.363007) (xy 201.986057 -303.384819) (xy 202.033663 -303.413873) (xy 202.076531 -303.449548)
			(xy 202.113748 -303.491085) (xy 202.144521 -303.537598) (xy 202.168193 -303.588095) (xy 202.184261 -303.641502)
			(xy 202.192381 -303.696678) (xy 202.19289 -303.724564) (xy 202.192381 -303.75245) (xy 202.184261 -303.807626)
			(xy 202.168193 -303.861033) (xy 202.144521 -303.91153) (xy 202.113748 -303.958043) (xy 202.076531 -303.99958)
			(xy 202.033663 -304.035255) (xy 201.986057 -304.064309) (xy 201.934728 -304.086121) (xy 201.880771 -304.100227)
			(xy 201.825334 -304.106327) (xy 201.7696 -304.10429) (xy 201.714757 -304.09416) (xy 201.661973 -304.076153)
			(xy 201.612373 -304.050652) (xy 201.567015 -304.018201) (xy 201.526866 -303.979492) (xy 201.49278 -303.935349)
			(xy 201.465484 -303.886714) (xy 201.445561 -303.834623) (xy 201.433435 -303.780186) (xy 201.429364 -303.724564)
			(xy 188.749052 -303.724564) (xy 188.768339 -303.737876) (xy 188.803832 -303.771968) (xy 188.833397 -303.811312)
			(xy 188.856268 -303.854889) (xy 188.871852 -303.90157) (xy 188.879747 -303.950147) (xy 188.880242 -303.974754)
			(xy 188.879747 -303.999361) (xy 188.871852 -304.047938) (xy 188.856268 -304.094619) (xy 188.833397 -304.138196)
			(xy 188.803832 -304.17754) (xy 188.768339 -304.211632) (xy 188.727836 -304.239588) (xy 188.683374 -304.260686)
			(xy 188.636103 -304.274378) (xy 188.587248 -304.28031) (xy 188.538073 -304.278329) (xy 188.489854 -304.268485)
			(xy 188.443838 -304.251033) (xy 188.401217 -304.226426) (xy 188.363096 -304.195301) (xy 188.330461 -304.158464)
			(xy 188.304158 -304.116868) (xy 188.284867 -304.071592) (xy 188.27309 -304.023808) (xy 188.26913 -303.974754)
			(xy 186.980322 -303.974754) (xy 186.979827 -303.999361) (xy 186.971932 -304.047938) (xy 186.956348 -304.094619)
			(xy 186.933477 -304.138196) (xy 186.903912 -304.17754) (xy 186.868419 -304.211632) (xy 186.827916 -304.239588)
			(xy 186.783454 -304.260686) (xy 186.736183 -304.274378) (xy 186.687328 -304.28031) (xy 186.638153 -304.278329)
			(xy 186.589934 -304.268485) (xy 186.543918 -304.251033) (xy 186.501297 -304.226426) (xy 186.463176 -304.195301)
			(xy 186.430541 -304.158464) (xy 186.404238 -304.116868) (xy 186.384947 -304.071592) (xy 186.37317 -304.023808)
			(xy 186.36921 -303.974754) (xy 186.055398 -303.974754) (xy 186.0554 -304.000605) (xy 186.047377 -304.051618)
			(xy 186.031525 -304.100765) (xy 186.008229 -304.146851) (xy 185.978054 -304.188758) (xy 185.941734 -304.225466)
			(xy 185.90015 -304.256085) (xy 185.854314 -304.27987) (xy 185.829956 -304.288444) (xy 185.829702 -304.288444)
			(xy 185.822198 -304.291252) (xy 185.809368 -304.300834) (xy 185.804556 -304.30724) (xy 185.800238 -304.31359)
			(xy 185.795412 -304.328322) (xy 185.795412 -304.475442) (xy 190.62344 -304.475442) (xy 190.62344 -304.424026)
			(xy 190.631483 -304.373244) (xy 190.647371 -304.324345) (xy 190.670714 -304.278533) (xy 190.700935 -304.236937)
			(xy 190.737291 -304.200581) (xy 190.778887 -304.17036) (xy 190.824699 -304.147017) (xy 190.873598 -304.131129)
			(xy 190.92438 -304.123086) (xy 190.975796 -304.123086) (xy 191.026578 -304.131129) (xy 191.075477 -304.147017)
			(xy 191.121289 -304.17036) (xy 191.162885 -304.200581) (xy 191.199241 -304.236937) (xy 191.229462 -304.278533)
			(xy 191.252805 -304.324345) (xy 191.268693 -304.373244) (xy 191.276736 -304.424026) (xy 191.27724 -304.449734)
			(xy 191.276736 -304.475442) (xy 191.5734 -304.475442) (xy 191.5734 -304.424026) (xy 191.581443 -304.373244)
			(xy 191.597331 -304.324345) (xy 191.620674 -304.278533) (xy 191.650895 -304.236937) (xy 191.687251 -304.200581)
			(xy 191.728847 -304.17036) (xy 191.774659 -304.147017) (xy 191.823558 -304.131129) (xy 191.87434 -304.123086)
			(xy 191.925756 -304.123086) (xy 191.976538 -304.131129) (xy 192.025437 -304.147017) (xy 192.071249 -304.17036)
			(xy 192.112845 -304.200581) (xy 192.149201 -304.236937) (xy 192.179422 -304.278533) (xy 192.202765 -304.324345)
			(xy 192.218653 -304.373244) (xy 192.226696 -304.424026) (xy 192.2272 -304.449734) (xy 192.226696 -304.475442)
			(xy 197.273414 -304.475442) (xy 197.273414 -304.424026) (xy 197.281457 -304.373244) (xy 197.297345 -304.324345)
			(xy 197.320688 -304.278533) (xy 197.350909 -304.236937) (xy 197.387265 -304.200581) (xy 197.428861 -304.17036)
			(xy 197.474673 -304.147017) (xy 197.523572 -304.131129) (xy 197.574354 -304.123086) (xy 197.62577 -304.123086)
			(xy 197.676552 -304.131129) (xy 197.725451 -304.147017) (xy 197.771263 -304.17036) (xy 197.812859 -304.200581)
			(xy 197.849215 -304.236937) (xy 197.879436 -304.278533) (xy 197.902779 -304.324345) (xy 197.918667 -304.373244)
			(xy 197.92671 -304.424026) (xy 197.927214 -304.449734) (xy 197.92671 -304.475442) (xy 198.223374 -304.475442)
			(xy 198.223374 -304.424026) (xy 198.231417 -304.373244) (xy 198.247305 -304.324345) (xy 198.270648 -304.278533)
			(xy 198.300869 -304.236937) (xy 198.337225 -304.200581) (xy 198.378821 -304.17036) (xy 198.424633 -304.147017)
			(xy 198.473532 -304.131129) (xy 198.524314 -304.123086) (xy 198.57573 -304.123086) (xy 198.626512 -304.131129)
			(xy 198.675411 -304.147017) (xy 198.721223 -304.17036) (xy 198.762819 -304.200581) (xy 198.799175 -304.236937)
			(xy 198.829396 -304.278533) (xy 198.852739 -304.324345) (xy 198.868627 -304.373244) (xy 198.87667 -304.424026)
			(xy 198.877174 -304.449734) (xy 198.87667 -304.475442) (xy 198.868627 -304.526224) (xy 198.852739 -304.575123)
			(xy 198.829396 -304.620935) (xy 198.799175 -304.662531) (xy 198.762819 -304.698887) (xy 198.721223 -304.729108)
			(xy 198.675411 -304.752451) (xy 198.626512 -304.768339) (xy 198.57573 -304.776382) (xy 198.524314 -304.776382)
			(xy 198.473532 -304.768339) (xy 198.424633 -304.752451) (xy 198.378821 -304.729108) (xy 198.337225 -304.698887)
			(xy 198.300869 -304.662531) (xy 198.270648 -304.620935) (xy 198.247305 -304.575123) (xy 198.231417 -304.526224)
			(xy 198.223374 -304.475442) (xy 197.92671 -304.475442) (xy 197.918667 -304.526224) (xy 197.902779 -304.575123)
			(xy 197.879436 -304.620935) (xy 197.849215 -304.662531) (xy 197.812859 -304.698887) (xy 197.771263 -304.729108)
			(xy 197.725451 -304.752451) (xy 197.676552 -304.768339) (xy 197.62577 -304.776382) (xy 197.574354 -304.776382)
			(xy 197.523572 -304.768339) (xy 197.474673 -304.752451) (xy 197.428861 -304.729108) (xy 197.387265 -304.698887)
			(xy 197.350909 -304.662531) (xy 197.320688 -304.620935) (xy 197.297345 -304.575123) (xy 197.281457 -304.526224)
			(xy 197.273414 -304.475442) (xy 192.226696 -304.475442) (xy 192.218653 -304.526224) (xy 192.202765 -304.575123)
			(xy 192.179422 -304.620935) (xy 192.149201 -304.662531) (xy 192.112845 -304.698887) (xy 192.071249 -304.729108)
			(xy 192.025437 -304.752451) (xy 191.976538 -304.768339) (xy 191.925756 -304.776382) (xy 191.87434 -304.776382)
			(xy 191.823558 -304.768339) (xy 191.774659 -304.752451) (xy 191.728847 -304.729108) (xy 191.687251 -304.698887)
			(xy 191.650895 -304.662531) (xy 191.620674 -304.620935) (xy 191.597331 -304.575123) (xy 191.581443 -304.526224)
			(xy 191.5734 -304.475442) (xy 191.276736 -304.475442) (xy 191.268693 -304.526224) (xy 191.252805 -304.575123)
			(xy 191.229462 -304.620935) (xy 191.199241 -304.662531) (xy 191.162885 -304.698887) (xy 191.121289 -304.729108)
			(xy 191.075477 -304.752451) (xy 191.026578 -304.768339) (xy 190.975796 -304.776382) (xy 190.92438 -304.776382)
			(xy 190.873598 -304.768339) (xy 190.824699 -304.752451) (xy 190.778887 -304.729108) (xy 190.737291 -304.698887)
			(xy 190.700935 -304.662531) (xy 190.670714 -304.620935) (xy 190.647371 -304.575123) (xy 190.631483 -304.526224)
			(xy 190.62344 -304.475442) (xy 185.795412 -304.475442) (xy 185.795412 -304.541428) (xy 185.795507 -304.546306)
			(xy 185.797293 -304.555896) (xy 185.798968 -304.560478) (xy 185.802524 -304.569114) (xy 185.809636 -304.57648)
			(xy 185.81497 -304.582068) (xy 185.820206 -304.587866) (xy 185.827189 -304.601832) (xy 185.828686 -304.6095)
			(xy 185.828686 -304.609754) (xy 185.83021 -304.618898) (xy 185.834274 -304.626518) (xy 185.836608 -304.630519)
			(xy 185.842486 -304.637676) (xy 185.845958 -304.640742) (xy 185.854594 -304.648108) (xy 185.860436 -304.651156)
			(xy 185.88197 -304.662312) (xy 185.921505 -304.690395) (xy 185.956098 -304.724381) (xy 185.984877 -304.763414)
			(xy 186.007115 -304.806509) (xy 186.022254 -304.85258) (xy 186.029911 -304.900466) (xy 186.030362 -304.924714)
			(xy 186.36921 -304.924714) (xy 186.37317 -304.87566) (xy 186.384947 -304.827876) (xy 186.404238 -304.7826)
			(xy 186.430541 -304.741004) (xy 186.463176 -304.704167) (xy 186.501297 -304.673042) (xy 186.543918 -304.648435)
			(xy 186.589934 -304.630983) (xy 186.638153 -304.621139) (xy 186.687328 -304.619158) (xy 186.736183 -304.62509)
			(xy 186.783454 -304.638782) (xy 186.827916 -304.65988) (xy 186.868419 -304.687836) (xy 186.903912 -304.721928)
			(xy 186.933477 -304.761272) (xy 186.956348 -304.804849) (xy 186.971932 -304.85153) (xy 186.979827 -304.900107)
			(xy 186.980322 -304.924714) (xy 187.31917 -304.924714) (xy 187.32313 -304.87566) (xy 187.334907 -304.827876)
			(xy 187.354198 -304.7826) (xy 187.380501 -304.741004) (xy 187.413136 -304.704167) (xy 187.451257 -304.673042)
			(xy 187.493878 -304.648435) (xy 187.539894 -304.630983) (xy 187.588113 -304.621139) (xy 187.637288 -304.619158)
			(xy 187.686143 -304.62509) (xy 187.733414 -304.638782) (xy 187.777876 -304.65988) (xy 187.818379 -304.687836)
			(xy 187.853872 -304.721928) (xy 187.883437 -304.761272) (xy 187.906308 -304.804849) (xy 187.921892 -304.85153)
			(xy 187.929787 -304.900107) (xy 187.930282 -304.924714) (xy 188.26913 -304.924714) (xy 188.27309 -304.87566)
			(xy 188.284867 -304.827876) (xy 188.304158 -304.7826) (xy 188.330461 -304.741004) (xy 188.363096 -304.704167)
			(xy 188.401217 -304.673042) (xy 188.443838 -304.648435) (xy 188.489854 -304.630983) (xy 188.538073 -304.621139)
			(xy 188.587248 -304.619158) (xy 188.636103 -304.62509) (xy 188.683374 -304.638782) (xy 188.727836 -304.65988)
			(xy 188.768339 -304.687836) (xy 188.803832 -304.721928) (xy 188.833397 -304.761272) (xy 188.843256 -304.780056)
			(xy 203.949711 -304.780056) (xy 203.949711 -304.725544) (xy 203.957469 -304.671586) (xy 203.972827 -304.619281)
			(xy 203.995473 -304.569695) (xy 204.024945 -304.523836) (xy 204.060644 -304.482638) (xy 204.101842 -304.44694)
			(xy 204.147702 -304.417469) (xy 204.197289 -304.394824) (xy 204.249594 -304.379467) (xy 204.303552 -304.37171)
			(xy 204.330808 -304.371248) (xy 204.357952 -304.371727) (xy 204.411695 -304.379403) (xy 204.463805 -304.394627)
			(xy 204.513227 -304.417092) (xy 204.558962 -304.446341) (xy 204.600084 -304.481785) (xy 204.63576 -304.522705)
			(xy 204.665269 -304.568273) (xy 204.688013 -304.617567) (xy 204.703533 -304.669589) (xy 204.707998 -304.696368)
			(xy 204.710733 -304.711218) (xy 204.723778 -304.738439) (xy 204.744199 -304.760668) (xy 204.770219 -304.775969)
			(xy 204.799571 -304.783011) (xy 204.829701 -304.78118) (xy 204.857985 -304.770637) (xy 204.870304 -304.7619)
			(xy 204.89035 -304.747071) (xy 204.933571 -304.722205) (xy 204.979661 -304.703176) (xy 205.027835 -304.690307)
			(xy 205.077274 -304.683818) (xy 205.102206 -304.683414) (xy 205.129459 -304.683856) (xy 205.183409 -304.691614)
			(xy 205.235706 -304.70697) (xy 205.285285 -304.729613) (xy 205.331137 -304.759081) (xy 205.372329 -304.794775)
			(xy 205.408022 -304.835967) (xy 205.43749 -304.88182) (xy 205.460132 -304.9314) (xy 205.475487 -304.983697)
			(xy 205.483244 -305.037647) (xy 205.483244 -305.064922) (xy 205.735172 -305.064922) (xy 205.739243 -305.0093)
			(xy 205.751369 -304.954863) (xy 205.771292 -304.902772) (xy 205.798588 -304.854137) (xy 205.832674 -304.809994)
			(xy 205.872823 -304.771285) (xy 205.918181 -304.738834) (xy 205.967781 -304.713333) (xy 206.020565 -304.695326)
			(xy 206.075408 -304.685196) (xy 206.131142 -304.683159) (xy 206.186579 -304.689259) (xy 206.240536 -304.703365)
			(xy 206.291865 -304.725177) (xy 206.339471 -304.754231) (xy 206.382339 -304.789906) (xy 206.419556 -304.831443)
			(xy 206.450329 -304.877956) (xy 206.474001 -304.928453) (xy 206.490069 -304.98186) (xy 206.498189 -305.037036)
			(xy 206.498698 -305.064922) (xy 206.743552 -305.064922) (xy 206.747623 -305.0093) (xy 206.759749 -304.954863)
			(xy 206.779672 -304.902772) (xy 206.806968 -304.854137) (xy 206.841054 -304.809994) (xy 206.881203 -304.771285)
			(xy 206.926561 -304.738834) (xy 206.976161 -304.713333) (xy 207.028945 -304.695326) (xy 207.083788 -304.685196)
			(xy 207.139522 -304.683159) (xy 207.194959 -304.689259) (xy 207.248916 -304.703365) (xy 207.300245 -304.725177)
			(xy 207.347851 -304.754231) (xy 207.390719 -304.789906) (xy 207.427936 -304.831443) (xy 207.458709 -304.877956)
			(xy 207.482381 -304.928453) (xy 207.498449 -304.98186) (xy 207.506569 -305.037036) (xy 207.507059 -305.063906)
			(xy 207.768188 -305.063906) (xy 207.772259 -305.008284) (xy 207.784385 -304.953847) (xy 207.804308 -304.901756)
			(xy 207.831604 -304.853121) (xy 207.86569 -304.808978) (xy 207.905839 -304.770269) (xy 207.951197 -304.737818)
			(xy 208.000797 -304.712317) (xy 208.053581 -304.69431) (xy 208.108424 -304.68418) (xy 208.164158 -304.682143)
			(xy 208.219595 -304.688243) (xy 208.273552 -304.702349) (xy 208.324881 -304.724161) (xy 208.372487 -304.753215)
			(xy 208.415355 -304.78889) (xy 208.452572 -304.830427) (xy 208.483345 -304.87694) (xy 208.507017 -304.927437)
			(xy 208.523085 -304.980844) (xy 208.531205 -305.03602) (xy 208.531389 -305.046126) (xy 208.784188 -305.046126)
			(xy 208.788259 -304.990504) (xy 208.800385 -304.936067) (xy 208.820308 -304.883976) (xy 208.847604 -304.835341)
			(xy 208.88169 -304.791198) (xy 208.921839 -304.752489) (xy 208.967197 -304.720038) (xy 209.016797 -304.694537)
			(xy 209.069581 -304.67653) (xy 209.124424 -304.6664) (xy 209.180158 -304.664363) (xy 209.235595 -304.670463)
			(xy 209.289552 -304.684569) (xy 209.340881 -304.706381) (xy 209.388487 -304.735435) (xy 209.431355 -304.77111)
			(xy 209.468572 -304.812647) (xy 209.499345 -304.85916) (xy 209.523017 -304.909657) (xy 209.539085 -304.963064)
			(xy 209.547205 -305.01824) (xy 209.547714 -305.046126) (xy 209.547205 -305.074012) (xy 209.539085 -305.129188)
			(xy 209.523017 -305.182595) (xy 209.499345 -305.233092) (xy 209.468572 -305.279605) (xy 209.431355 -305.321142)
			(xy 209.388487 -305.356817) (xy 209.340881 -305.385871) (xy 209.289552 -305.407683) (xy 209.235595 -305.421789)
			(xy 209.180158 -305.427889) (xy 209.124424 -305.425852) (xy 209.069581 -305.415722) (xy 209.016797 -305.397715)
			(xy 208.967197 -305.372214) (xy 208.921839 -305.339763) (xy 208.88169 -305.301054) (xy 208.847604 -305.256911)
			(xy 208.820308 -305.208276) (xy 208.800385 -305.156185) (xy 208.788259 -305.101748) (xy 208.784188 -305.046126)
			(xy 208.531389 -305.046126) (xy 208.531714 -305.063906) (xy 208.531205 -305.091792) (xy 208.523085 -305.146968)
			(xy 208.507017 -305.200375) (xy 208.483345 -305.250872) (xy 208.452572 -305.297385) (xy 208.415355 -305.338922)
			(xy 208.372487 -305.374597) (xy 208.324881 -305.403651) (xy 208.273552 -305.425463) (xy 208.219595 -305.439569)
			(xy 208.164158 -305.445669) (xy 208.108424 -305.443632) (xy 208.053581 -305.433502) (xy 208.000797 -305.415495)
			(xy 207.951197 -305.389994) (xy 207.905839 -305.357543) (xy 207.86569 -305.318834) (xy 207.831604 -305.274691)
			(xy 207.804308 -305.226056) (xy 207.784385 -305.173965) (xy 207.772259 -305.119528) (xy 207.768188 -305.063906)
			(xy 207.507059 -305.063906) (xy 207.507078 -305.064922) (xy 207.506569 -305.092808) (xy 207.498449 -305.147984)
			(xy 207.482381 -305.201391) (xy 207.458709 -305.251888) (xy 207.427936 -305.298401) (xy 207.390719 -305.339938)
			(xy 207.347851 -305.375613) (xy 207.300245 -305.404667) (xy 207.248916 -305.426479) (xy 207.194959 -305.440585)
			(xy 207.139522 -305.446685) (xy 207.083788 -305.444648) (xy 207.028945 -305.434518) (xy 206.976161 -305.416511)
			(xy 206.926561 -305.39101) (xy 206.881203 -305.358559) (xy 206.841054 -305.31985) (xy 206.806968 -305.275707)
			(xy 206.779672 -305.227072) (xy 206.759749 -305.174981) (xy 206.747623 -305.120544) (xy 206.743552 -305.064922)
			(xy 206.498698 -305.064922) (xy 206.498189 -305.092808) (xy 206.490069 -305.147984) (xy 206.474001 -305.201391)
			(xy 206.450329 -305.251888) (xy 206.419556 -305.298401) (xy 206.382339 -305.339938) (xy 206.339471 -305.375613)
			(xy 206.291865 -305.404667) (xy 206.240536 -305.426479) (xy 206.186579 -305.440585) (xy 206.131142 -305.446685)
			(xy 206.075408 -305.444648) (xy 206.020565 -305.434518) (xy 205.967781 -305.416511) (xy 205.918181 -305.39101)
			(xy 205.872823 -305.358559) (xy 205.832674 -305.31985) (xy 205.798588 -305.275707) (xy 205.771292 -305.227072)
			(xy 205.751369 -305.174981) (xy 205.739243 -305.120544) (xy 205.735172 -305.064922) (xy 205.483244 -305.064922)
			(xy 205.483244 -305.092153) (xy 205.475487 -305.146103) (xy 205.460132 -305.1984) (xy 205.43749 -305.24798)
			(xy 205.408022 -305.293833) (xy 205.372329 -305.335025) (xy 205.331137 -305.370719) (xy 205.285285 -305.400187)
			(xy 205.235706 -305.42283) (xy 205.183409 -305.438186) (xy 205.129459 -305.445944) (xy 205.102206 -305.44643)
			(xy 205.075061 -305.445957) (xy 205.021317 -305.438282) (xy 204.969206 -305.423059) (xy 204.919783 -305.400594)
			(xy 204.874047 -305.371344) (xy 204.832925 -305.3359) (xy 204.797249 -305.294979) (xy 204.767741 -305.249409)
			(xy 204.744997 -305.200114) (xy 204.72948 -305.148089) (xy 204.725016 -305.12131) (xy 204.722271 -305.106463)
			(xy 204.709224 -305.079247) (xy 204.688803 -305.057023) (xy 204.662787 -305.041723) (xy 204.633438 -305.034681)
			(xy 204.603312 -305.036508) (xy 204.575029 -305.047045) (xy 204.56271 -305.055778) (xy 204.542667 -305.070611)
			(xy 204.499445 -305.095475) (xy 204.453354 -305.114502) (xy 204.405179 -305.12737) (xy 204.35574 -305.13386)
			(xy 204.330808 -305.134264) (xy 204.303552 -305.13389) (xy 204.249594 -305.126133) (xy 204.197289 -305.110776)
			(xy 204.147702 -305.088131) (xy 204.101842 -305.05866) (xy 204.060644 -305.022962) (xy 204.024945 -304.981764)
			(xy 203.995473 -304.935905) (xy 203.972827 -304.886319) (xy 203.957469 -304.834014) (xy 203.949711 -304.780056)
			(xy 188.843256 -304.780056) (xy 188.856268 -304.804849) (xy 188.871852 -304.85153) (xy 188.879747 -304.900107)
			(xy 188.880242 -304.924714) (xy 188.879747 -304.949321) (xy 188.871852 -304.997898) (xy 188.856268 -305.044579)
			(xy 188.833397 -305.088156) (xy 188.803832 -305.1275) (xy 188.768339 -305.161592) (xy 188.727836 -305.189548)
			(xy 188.683374 -305.210646) (xy 188.636103 -305.224338) (xy 188.587248 -305.23027) (xy 188.538073 -305.228289)
			(xy 188.489854 -305.218445) (xy 188.443838 -305.200993) (xy 188.401217 -305.176386) (xy 188.363096 -305.145261)
			(xy 188.330461 -305.108424) (xy 188.304158 -305.066828) (xy 188.284867 -305.021552) (xy 188.27309 -304.973768)
			(xy 188.26913 -304.924714) (xy 187.930282 -304.924714) (xy 187.929787 -304.949321) (xy 187.921892 -304.997898)
			(xy 187.906308 -305.044579) (xy 187.883437 -305.088156) (xy 187.853872 -305.1275) (xy 187.818379 -305.161592)
			(xy 187.777876 -305.189548) (xy 187.733414 -305.210646) (xy 187.686143 -305.224338) (xy 187.637288 -305.23027)
			(xy 187.588113 -305.228289) (xy 187.539894 -305.218445) (xy 187.493878 -305.200993) (xy 187.451257 -305.176386)
			(xy 187.413136 -305.145261) (xy 187.380501 -305.108424) (xy 187.354198 -305.066828) (xy 187.334907 -305.021552)
			(xy 187.32313 -304.973768) (xy 187.31917 -304.924714) (xy 186.980322 -304.924714) (xy 186.979827 -304.949321)
			(xy 186.971932 -304.997898) (xy 186.956348 -305.044579) (xy 186.933477 -305.088156) (xy 186.903912 -305.1275)
			(xy 186.868419 -305.161592) (xy 186.827916 -305.189548) (xy 186.783454 -305.210646) (xy 186.736183 -305.224338)
			(xy 186.687328 -305.23027) (xy 186.638153 -305.228289) (xy 186.589934 -305.218445) (xy 186.543918 -305.200993)
			(xy 186.501297 -305.176386) (xy 186.463176 -305.145261) (xy 186.430541 -305.108424) (xy 186.404238 -305.066828)
			(xy 186.384947 -305.021552) (xy 186.37317 -304.973768) (xy 186.36921 -304.924714) (xy 186.030362 -304.924714)
			(xy 186.029924 -304.948074) (xy 186.022816 -304.994248) (xy 186.008753 -305.0388) (xy 185.988063 -305.080688)
			(xy 185.961231 -305.118933) (xy 185.928882 -305.152641) (xy 185.891774 -305.181025) (xy 185.850774 -305.203421)
			(xy 185.82894 -305.211734) (xy 185.826146 -305.21275) (xy 185.817513 -305.216901) (xy 185.803926 -305.230382)
			(xy 185.796229 -305.247908) (xy 185.795412 -305.257454) (xy 185.795412 -305.425656) (xy 192.52336 -305.425656)
			(xy 192.52336 -305.37424) (xy 192.531403 -305.323458) (xy 192.547291 -305.274559) (xy 192.570634 -305.228747)
			(xy 192.600855 -305.187151) (xy 192.637211 -305.150795) (xy 192.678807 -305.120574) (xy 192.724619 -305.097231)
			(xy 192.773518 -305.081343) (xy 192.8243 -305.0733) (xy 192.875716 -305.0733) (xy 192.926498 -305.081343)
			(xy 192.975397 -305.097231) (xy 193.021209 -305.120574) (xy 193.062805 -305.150795) (xy 193.099161 -305.187151)
			(xy 193.129382 -305.228747) (xy 193.152725 -305.274559) (xy 193.168613 -305.323458) (xy 193.176656 -305.37424)
			(xy 193.17716 -305.399948) (xy 193.176656 -305.425656) (xy 193.47332 -305.425656) (xy 193.47332 -305.37424)
			(xy 193.481363 -305.323458) (xy 193.497251 -305.274559) (xy 193.520594 -305.228747) (xy 193.550815 -305.187151)
			(xy 193.587171 -305.150795) (xy 193.628767 -305.120574) (xy 193.674579 -305.097231) (xy 193.723478 -305.081343)
			(xy 193.77426 -305.0733) (xy 193.825676 -305.0733) (xy 193.876458 -305.081343) (xy 193.925357 -305.097231)
			(xy 193.971169 -305.120574) (xy 194.012765 -305.150795) (xy 194.049121 -305.187151) (xy 194.079342 -305.228747)
			(xy 194.102685 -305.274559) (xy 194.118573 -305.323458) (xy 194.126616 -305.37424) (xy 194.12712 -305.399948)
			(xy 194.126616 -305.425656) (xy 195.37324 -305.425656) (xy 195.37324 -305.37424) (xy 195.381283 -305.323458)
			(xy 195.397171 -305.274559) (xy 195.420514 -305.228747) (xy 195.450735 -305.187151) (xy 195.487091 -305.150795)
			(xy 195.528687 -305.120574) (xy 195.574499 -305.097231) (xy 195.623398 -305.081343) (xy 195.67418 -305.0733)
			(xy 195.725596 -305.0733) (xy 195.776378 -305.081343) (xy 195.825277 -305.097231) (xy 195.871089 -305.120574)
			(xy 195.912685 -305.150795) (xy 195.949041 -305.187151) (xy 195.979262 -305.228747) (xy 196.002605 -305.274559)
			(xy 196.018493 -305.323458) (xy 196.026536 -305.37424) (xy 196.02704 -305.399948) (xy 196.026536 -305.425656)
			(xy 196.3232 -305.425656) (xy 196.3232 -305.37424) (xy 196.331243 -305.323458) (xy 196.347131 -305.274559)
			(xy 196.370474 -305.228747) (xy 196.400695 -305.187151) (xy 196.437051 -305.150795) (xy 196.478647 -305.120574)
			(xy 196.524459 -305.097231) (xy 196.573358 -305.081343) (xy 196.62414 -305.0733) (xy 196.675556 -305.0733)
			(xy 196.726338 -305.081343) (xy 196.775237 -305.097231) (xy 196.821049 -305.120574) (xy 196.862645 -305.150795)
			(xy 196.899001 -305.187151) (xy 196.929222 -305.228747) (xy 196.952565 -305.274559) (xy 196.968453 -305.323458)
			(xy 196.976496 -305.37424) (xy 196.977 -305.399948) (xy 196.976496 -305.425656) (xy 196.968453 -305.476438)
			(xy 196.952565 -305.525337) (xy 196.929222 -305.571149) (xy 196.899001 -305.612745) (xy 196.862645 -305.649101)
			(xy 196.821049 -305.679322) (xy 196.775237 -305.702665) (xy 196.726338 -305.718553) (xy 196.675556 -305.726596)
			(xy 196.62414 -305.726596) (xy 196.573358 -305.718553) (xy 196.524459 -305.702665) (xy 196.478647 -305.679322)
			(xy 196.437051 -305.649101) (xy 196.400695 -305.612745) (xy 196.370474 -305.571149) (xy 196.347131 -305.525337)
			(xy 196.331243 -305.476438) (xy 196.3232 -305.425656) (xy 196.026536 -305.425656) (xy 196.018493 -305.476438)
			(xy 196.002605 -305.525337) (xy 195.979262 -305.571149) (xy 195.949041 -305.612745) (xy 195.912685 -305.649101)
			(xy 195.871089 -305.679322) (xy 195.825277 -305.702665) (xy 195.776378 -305.718553) (xy 195.725596 -305.726596)
			(xy 195.67418 -305.726596) (xy 195.623398 -305.718553) (xy 195.574499 -305.702665) (xy 195.528687 -305.679322)
			(xy 195.487091 -305.649101) (xy 195.450735 -305.612745) (xy 195.420514 -305.571149) (xy 195.397171 -305.525337)
			(xy 195.381283 -305.476438) (xy 195.37324 -305.425656) (xy 194.126616 -305.425656) (xy 194.118573 -305.476438)
			(xy 194.102685 -305.525337) (xy 194.079342 -305.571149) (xy 194.049121 -305.612745) (xy 194.012765 -305.649101)
			(xy 193.971169 -305.679322) (xy 193.925357 -305.702665) (xy 193.876458 -305.718553) (xy 193.825676 -305.726596)
			(xy 193.77426 -305.726596) (xy 193.723478 -305.718553) (xy 193.674579 -305.702665) (xy 193.628767 -305.679322)
			(xy 193.587171 -305.649101) (xy 193.550815 -305.612745) (xy 193.520594 -305.571149) (xy 193.497251 -305.525337)
			(xy 193.481363 -305.476438) (xy 193.47332 -305.425656) (xy 193.176656 -305.425656) (xy 193.168613 -305.476438)
			(xy 193.152725 -305.525337) (xy 193.129382 -305.571149) (xy 193.099161 -305.612745) (xy 193.062805 -305.649101)
			(xy 193.021209 -305.679322) (xy 192.975397 -305.702665) (xy 192.926498 -305.718553) (xy 192.875716 -305.726596)
			(xy 192.8243 -305.726596) (xy 192.773518 -305.718553) (xy 192.724619 -305.702665) (xy 192.678807 -305.679322)
			(xy 192.637211 -305.649101) (xy 192.600855 -305.612745) (xy 192.570634 -305.571149) (xy 192.547291 -305.525337)
			(xy 192.531403 -305.476438) (xy 192.52336 -305.425656) (xy 185.795412 -305.425656) (xy 185.795412 -305.513232)
			(xy 185.795707 -305.521105) (xy 185.800491 -305.536107) (xy 185.80481 -305.542696) (xy 185.809382 -305.549046)
			(xy 185.822082 -305.558698) (xy 185.829956 -305.561238) (xy 185.854281 -305.569893) (xy 185.900108 -305.593672)
			(xy 185.941684 -305.624283) (xy 185.977997 -305.660983) (xy 186.008166 -305.70288) (xy 186.031458 -305.748956)
			(xy 186.047308 -305.798092) (xy 186.055329 -305.849094) (xy 186.055328 -305.874928) (xy 186.36921 -305.874928)
			(xy 186.37317 -305.825874) (xy 186.384947 -305.77809) (xy 186.404238 -305.732814) (xy 186.430541 -305.691218)
			(xy 186.463176 -305.654381) (xy 186.501297 -305.623256) (xy 186.543918 -305.598649) (xy 186.589934 -305.581197)
			(xy 186.638153 -305.571353) (xy 186.687328 -305.569372) (xy 186.736183 -305.575304) (xy 186.783454 -305.588996)
			(xy 186.827916 -305.610094) (xy 186.868419 -305.63805) (xy 186.903912 -305.672142) (xy 186.933477 -305.711486)
			(xy 186.956348 -305.755063) (xy 186.971932 -305.801744) (xy 186.979827 -305.850321) (xy 186.980322 -305.874928)
			(xy 188.26913 -305.874928) (xy 188.27309 -305.825874) (xy 188.284867 -305.77809) (xy 188.304158 -305.732814)
			(xy 188.330461 -305.691218) (xy 188.363096 -305.654381) (xy 188.401217 -305.623256) (xy 188.443838 -305.598649)
			(xy 188.489854 -305.581197) (xy 188.538073 -305.571353) (xy 188.587248 -305.569372) (xy 188.636103 -305.575304)
			(xy 188.683374 -305.588996) (xy 188.727836 -305.610094) (xy 188.768339 -305.63805) (xy 188.803832 -305.672142)
			(xy 188.833397 -305.711486) (xy 188.856268 -305.755063) (xy 188.871852 -305.801744) (xy 188.879747 -305.850321)
			(xy 188.880242 -305.874928) (xy 188.879747 -305.899535) (xy 188.871852 -305.948112) (xy 188.856268 -305.994793)
			(xy 188.833397 -306.03837) (xy 188.803832 -306.077714) (xy 188.768339 -306.111806) (xy 188.727836 -306.139762)
			(xy 188.683374 -306.16086) (xy 188.636103 -306.174552) (xy 188.587248 -306.180484) (xy 188.538073 -306.178503)
			(xy 188.489854 -306.168659) (xy 188.443838 -306.151207) (xy 188.401217 -306.1266) (xy 188.363096 -306.095475)
			(xy 188.330461 -306.058638) (xy 188.304158 -306.017042) (xy 188.284867 -305.971766) (xy 188.27309 -305.923982)
			(xy 188.26913 -305.874928) (xy 186.980322 -305.874928) (xy 186.979827 -305.899535) (xy 186.971932 -305.948112)
			(xy 186.956348 -305.994793) (xy 186.933477 -306.03837) (xy 186.903912 -306.077714) (xy 186.868419 -306.111806)
			(xy 186.827916 -306.139762) (xy 186.783454 -306.16086) (xy 186.736183 -306.174552) (xy 186.687328 -306.180484)
			(xy 186.638153 -306.178503) (xy 186.589934 -306.168659) (xy 186.543918 -306.151207) (xy 186.501297 -306.1266)
			(xy 186.463176 -306.095475) (xy 186.430541 -306.058638) (xy 186.404238 -306.017042) (xy 186.384947 -305.971766)
			(xy 186.37317 -305.923982) (xy 186.36921 -305.874928) (xy 186.055328 -305.874928) (xy 186.055328 -305.900723)
			(xy 186.047304 -305.951725) (xy 186.031452 -306.00086) (xy 186.008157 -306.046935) (xy 185.977985 -306.08883)
			(xy 185.94167 -306.125528) (xy 185.900093 -306.156138) (xy 185.854265 -306.179914) (xy 185.829956 -306.188618)
			(xy 185.829702 -306.188618) (xy 185.822197 -306.191425) (xy 185.809362 -306.201004) (xy 185.804556 -306.207414)
			(xy 185.800238 -306.213764) (xy 185.795412 -306.228496) (xy 185.795412 -306.375616) (xy 190.62344 -306.375616)
			(xy 190.62344 -306.3242) (xy 190.631483 -306.273418) (xy 190.647371 -306.224519) (xy 190.670714 -306.178707)
			(xy 190.700935 -306.137111) (xy 190.737291 -306.100755) (xy 190.778887 -306.070534) (xy 190.824699 -306.047191)
			(xy 190.873598 -306.031303) (xy 190.92438 -306.02326) (xy 190.975796 -306.02326) (xy 191.026578 -306.031303)
			(xy 191.075477 -306.047191) (xy 191.121289 -306.070534) (xy 191.162885 -306.100755) (xy 191.199241 -306.137111)
			(xy 191.229462 -306.178707) (xy 191.252805 -306.224519) (xy 191.268693 -306.273418) (xy 191.276736 -306.3242)
			(xy 191.27724 -306.349908) (xy 191.276736 -306.375616) (xy 191.5734 -306.375616) (xy 191.5734 -306.3242)
			(xy 191.581443 -306.273418) (xy 191.597331 -306.224519) (xy 191.620674 -306.178707) (xy 191.650895 -306.137111)
			(xy 191.687251 -306.100755) (xy 191.728847 -306.070534) (xy 191.774659 -306.047191) (xy 191.823558 -306.031303)
			(xy 191.87434 -306.02326) (xy 191.925756 -306.02326) (xy 191.976538 -306.031303) (xy 192.025437 -306.047191)
			(xy 192.071249 -306.070534) (xy 192.112845 -306.100755) (xy 192.149201 -306.137111) (xy 192.179422 -306.178707)
			(xy 192.202765 -306.224519) (xy 192.218653 -306.273418) (xy 192.226696 -306.3242) (xy 192.2272 -306.349908)
			(xy 192.226696 -306.375616) (xy 197.273414 -306.375616) (xy 197.273414 -306.3242) (xy 197.281457 -306.273418)
			(xy 197.297345 -306.224519) (xy 197.320688 -306.178707) (xy 197.350909 -306.137111) (xy 197.387265 -306.100755)
			(xy 197.428861 -306.070534) (xy 197.474673 -306.047191) (xy 197.523572 -306.031303) (xy 197.574354 -306.02326)
			(xy 197.62577 -306.02326) (xy 197.676552 -306.031303) (xy 197.725451 -306.047191) (xy 197.771263 -306.070534)
			(xy 197.812859 -306.100755) (xy 197.849215 -306.137111) (xy 197.879436 -306.178707) (xy 197.902779 -306.224519)
			(xy 197.918667 -306.273418) (xy 197.92671 -306.3242) (xy 197.927214 -306.349908) (xy 197.92671 -306.375616)
			(xy 198.223374 -306.375616) (xy 198.223374 -306.3242) (xy 198.231417 -306.273418) (xy 198.247305 -306.224519)
			(xy 198.270648 -306.178707) (xy 198.300869 -306.137111) (xy 198.337225 -306.100755) (xy 198.378821 -306.070534)
			(xy 198.424633 -306.047191) (xy 198.473532 -306.031303) (xy 198.524314 -306.02326) (xy 198.57573 -306.02326)
			(xy 198.626512 -306.031303) (xy 198.675411 -306.047191) (xy 198.721223 -306.070534) (xy 198.762819 -306.100755)
			(xy 198.799175 -306.137111) (xy 198.829396 -306.178707) (xy 198.852739 -306.224519) (xy 198.868627 -306.273418)
			(xy 198.87667 -306.3242) (xy 198.877174 -306.349908) (xy 198.87667 -306.375616) (xy 198.868627 -306.426398)
			(xy 198.852739 -306.475297) (xy 198.829396 -306.521109) (xy 198.799175 -306.562705) (xy 198.762819 -306.599061)
			(xy 198.721223 -306.629282) (xy 198.675411 -306.652625) (xy 198.626512 -306.668513) (xy 198.57573 -306.676556)
			(xy 198.524314 -306.676556) (xy 198.473532 -306.668513) (xy 198.424633 -306.652625) (xy 198.378821 -306.629282)
			(xy 198.337225 -306.599061) (xy 198.300869 -306.562705) (xy 198.270648 -306.521109) (xy 198.247305 -306.475297)
			(xy 198.231417 -306.426398) (xy 198.223374 -306.375616) (xy 197.92671 -306.375616) (xy 197.918667 -306.426398)
			(xy 197.902779 -306.475297) (xy 197.879436 -306.521109) (xy 197.849215 -306.562705) (xy 197.812859 -306.599061)
			(xy 197.771263 -306.629282) (xy 197.725451 -306.652625) (xy 197.676552 -306.668513) (xy 197.62577 -306.676556)
			(xy 197.574354 -306.676556) (xy 197.523572 -306.668513) (xy 197.474673 -306.652625) (xy 197.428861 -306.629282)
			(xy 197.387265 -306.599061) (xy 197.350909 -306.562705) (xy 197.320688 -306.521109) (xy 197.297345 -306.475297)
			(xy 197.281457 -306.426398) (xy 197.273414 -306.375616) (xy 192.226696 -306.375616) (xy 192.218653 -306.426398)
			(xy 192.202765 -306.475297) (xy 192.179422 -306.521109) (xy 192.149201 -306.562705) (xy 192.112845 -306.599061)
			(xy 192.071249 -306.629282) (xy 192.025437 -306.652625) (xy 191.976538 -306.668513) (xy 191.925756 -306.676556)
			(xy 191.87434 -306.676556) (xy 191.823558 -306.668513) (xy 191.774659 -306.652625) (xy 191.728847 -306.629282)
			(xy 191.687251 -306.599061) (xy 191.650895 -306.562705) (xy 191.620674 -306.521109) (xy 191.597331 -306.475297)
			(xy 191.581443 -306.426398) (xy 191.5734 -306.375616) (xy 191.276736 -306.375616) (xy 191.268693 -306.426398)
			(xy 191.252805 -306.475297) (xy 191.229462 -306.521109) (xy 191.199241 -306.562705) (xy 191.162885 -306.599061)
			(xy 191.121289 -306.629282) (xy 191.075477 -306.652625) (xy 191.026578 -306.668513) (xy 190.975796 -306.676556)
			(xy 190.92438 -306.676556) (xy 190.873598 -306.668513) (xy 190.824699 -306.652625) (xy 190.778887 -306.629282)
			(xy 190.737291 -306.599061) (xy 190.700935 -306.562705) (xy 190.670714 -306.521109) (xy 190.647371 -306.475297)
			(xy 190.631483 -306.426398) (xy 190.62344 -306.375616) (xy 185.795412 -306.375616) (xy 185.795412 -306.463192)
			(xy 185.795701 -306.471067) (xy 185.800476 -306.486076) (xy 185.80481 -306.492656) (xy 185.809382 -306.499006)
			(xy 185.822082 -306.508658) (xy 185.829956 -306.511198) (xy 185.854285 -306.519853) (xy 185.900118 -306.543633)
			(xy 185.941699 -306.574246) (xy 185.978018 -306.610949) (xy 186.008192 -306.65285) (xy 186.031489 -306.69893)
			(xy 186.047342 -306.748071) (xy 186.055366 -306.799079) (xy 186.055366 -306.824888) (xy 186.36921 -306.824888)
			(xy 186.37317 -306.775834) (xy 186.384947 -306.72805) (xy 186.404238 -306.682774) (xy 186.430541 -306.641178)
			(xy 186.463176 -306.604341) (xy 186.501297 -306.573216) (xy 186.543918 -306.548609) (xy 186.589934 -306.531157)
			(xy 186.638153 -306.521313) (xy 186.687328 -306.519332) (xy 186.736183 -306.525264) (xy 186.783454 -306.538956)
			(xy 186.827916 -306.560054) (xy 186.868419 -306.58801) (xy 186.903912 -306.622102) (xy 186.933477 -306.661446)
			(xy 186.956348 -306.705023) (xy 186.971932 -306.751704) (xy 186.979827 -306.800281) (xy 186.980322 -306.824888)
			(xy 187.31917 -306.824888) (xy 187.32313 -306.775834) (xy 187.334907 -306.72805) (xy 187.354198 -306.682774)
			(xy 187.380501 -306.641178) (xy 187.413136 -306.604341) (xy 187.451257 -306.573216) (xy 187.493878 -306.548609)
			(xy 187.539894 -306.531157) (xy 187.588113 -306.521313) (xy 187.637288 -306.519332) (xy 187.686143 -306.525264)
			(xy 187.733414 -306.538956) (xy 187.777876 -306.560054) (xy 187.818379 -306.58801) (xy 187.853872 -306.622102)
			(xy 187.883437 -306.661446) (xy 187.906308 -306.705023) (xy 187.921892 -306.751704) (xy 187.929787 -306.800281)
			(xy 187.930282 -306.824888) (xy 188.26913 -306.824888) (xy 188.27309 -306.775834) (xy 188.284867 -306.72805)
			(xy 188.304158 -306.682774) (xy 188.330461 -306.641178) (xy 188.363096 -306.604341) (xy 188.401217 -306.573216)
			(xy 188.443838 -306.548609) (xy 188.489854 -306.531157) (xy 188.538073 -306.521313) (xy 188.587248 -306.519332)
			(xy 188.636103 -306.525264) (xy 188.683374 -306.538956) (xy 188.727836 -306.560054) (xy 188.768339 -306.58801)
			(xy 188.803832 -306.622102) (xy 188.833397 -306.661446) (xy 188.856268 -306.705023) (xy 188.871852 -306.751704)
			(xy 188.879747 -306.800281) (xy 188.880242 -306.824888) (xy 188.879747 -306.849495) (xy 188.871852 -306.898072)
			(xy 188.856268 -306.944753) (xy 188.833397 -306.98833) (xy 188.803832 -307.027674) (xy 188.768339 -307.061766)
			(xy 188.727836 -307.089722) (xy 188.683374 -307.11082) (xy 188.636103 -307.124512) (xy 188.587248 -307.130444)
			(xy 188.538073 -307.128463) (xy 188.489854 -307.118619) (xy 188.443838 -307.101167) (xy 188.401217 -307.07656)
			(xy 188.363096 -307.045435) (xy 188.330461 -307.008598) (xy 188.304158 -306.967002) (xy 188.284867 -306.921726)
			(xy 188.27309 -306.873942) (xy 188.26913 -306.824888) (xy 187.930282 -306.824888) (xy 187.929787 -306.849495)
			(xy 187.921892 -306.898072) (xy 187.906308 -306.944753) (xy 187.883437 -306.98833) (xy 187.853872 -307.027674)
			(xy 187.818379 -307.061766) (xy 187.777876 -307.089722) (xy 187.733414 -307.11082) (xy 187.686143 -307.124512)
			(xy 187.637288 -307.130444) (xy 187.588113 -307.128463) (xy 187.539894 -307.118619) (xy 187.493878 -307.101167)
			(xy 187.451257 -307.07656) (xy 187.413136 -307.045435) (xy 187.380501 -307.008598) (xy 187.354198 -306.967002)
			(xy 187.334907 -306.921726) (xy 187.32313 -306.873942) (xy 187.31917 -306.824888) (xy 186.980322 -306.824888)
			(xy 186.979827 -306.849495) (xy 186.971932 -306.898072) (xy 186.956348 -306.944753) (xy 186.933477 -306.98833)
			(xy 186.903912 -307.027674) (xy 186.868419 -307.061766) (xy 186.827916 -307.089722) (xy 186.783454 -307.11082)
			(xy 186.736183 -307.124512) (xy 186.687328 -307.130444) (xy 186.638153 -307.128463) (xy 186.589934 -307.118619)
			(xy 186.543918 -307.101167) (xy 186.501297 -307.07656) (xy 186.463176 -307.045435) (xy 186.430541 -307.008598)
			(xy 186.404238 -306.967002) (xy 186.384947 -306.921726) (xy 186.37317 -306.873942) (xy 186.36921 -306.824888)
			(xy 186.055366 -306.824888) (xy 186.055367 -306.850714) (xy 186.047343 -306.901721) (xy 186.031492 -306.950863)
			(xy 186.008196 -306.996944) (xy 185.978023 -307.038845) (xy 185.941704 -307.075549) (xy 185.900124 -307.106163)
			(xy 185.854292 -307.129944) (xy 185.829956 -307.138578) (xy 185.829702 -307.138578) (xy 185.822195 -307.141383)
			(xy 185.809355 -307.150957) (xy 185.804556 -307.157374) (xy 185.800238 -307.163724) (xy 185.795412 -307.178456)
			(xy 185.795412 -307.325576) (xy 192.52336 -307.325576) (xy 192.52336 -307.27416) (xy 192.531403 -307.223378)
			(xy 192.547291 -307.174479) (xy 192.570634 -307.128667) (xy 192.600855 -307.087071) (xy 192.637211 -307.050715)
			(xy 192.678807 -307.020494) (xy 192.724619 -306.997151) (xy 192.773518 -306.981263) (xy 192.8243 -306.97322)
			(xy 192.875716 -306.97322) (xy 192.926498 -306.981263) (xy 192.975397 -306.997151) (xy 193.021209 -307.020494)
			(xy 193.062805 -307.050715) (xy 193.099161 -307.087071) (xy 193.129382 -307.128667) (xy 193.152725 -307.174479)
			(xy 193.168613 -307.223378) (xy 193.176656 -307.27416) (xy 193.17716 -307.299868) (xy 193.176656 -307.325576)
			(xy 193.47332 -307.325576) (xy 193.47332 -307.27416) (xy 193.481363 -307.223378) (xy 193.497251 -307.174479)
			(xy 193.520594 -307.128667) (xy 193.550815 -307.087071) (xy 193.587171 -307.050715) (xy 193.628767 -307.020494)
			(xy 193.674579 -306.997151) (xy 193.723478 -306.981263) (xy 193.77426 -306.97322) (xy 193.825676 -306.97322)
			(xy 193.876458 -306.981263) (xy 193.925357 -306.997151) (xy 193.971169 -307.020494) (xy 194.012765 -307.050715)
			(xy 194.049121 -307.087071) (xy 194.079342 -307.128667) (xy 194.102685 -307.174479) (xy 194.118573 -307.223378)
			(xy 194.126616 -307.27416) (xy 194.12712 -307.299868) (xy 194.126616 -307.325576) (xy 195.37324 -307.325576)
			(xy 195.37324 -307.27416) (xy 195.381283 -307.223378) (xy 195.397171 -307.174479) (xy 195.420514 -307.128667)
			(xy 195.450735 -307.087071) (xy 195.487091 -307.050715) (xy 195.528687 -307.020494) (xy 195.574499 -306.997151)
			(xy 195.623398 -306.981263) (xy 195.67418 -306.97322) (xy 195.725596 -306.97322) (xy 195.776378 -306.981263)
			(xy 195.825277 -306.997151) (xy 195.871089 -307.020494) (xy 195.912685 -307.050715) (xy 195.949041 -307.087071)
			(xy 195.979262 -307.128667) (xy 196.002605 -307.174479) (xy 196.018493 -307.223378) (xy 196.026536 -307.27416)
			(xy 196.02704 -307.299868) (xy 196.026536 -307.325576) (xy 196.3232 -307.325576) (xy 196.3232 -307.27416)
			(xy 196.331243 -307.223378) (xy 196.347131 -307.174479) (xy 196.370474 -307.128667) (xy 196.400695 -307.087071)
			(xy 196.437051 -307.050715) (xy 196.478647 -307.020494) (xy 196.524459 -306.997151) (xy 196.573358 -306.981263)
			(xy 196.62414 -306.97322) (xy 196.675556 -306.97322) (xy 196.726338 -306.981263) (xy 196.775237 -306.997151)
			(xy 196.821049 -307.020494) (xy 196.862645 -307.050715) (xy 196.896152 -307.084222) (xy 208.814414 -307.084222)
			(xy 208.818485 -307.0286) (xy 208.830611 -306.974163) (xy 208.850534 -306.922072) (xy 208.87783 -306.873437)
			(xy 208.911916 -306.829294) (xy 208.952065 -306.790585) (xy 208.997423 -306.758134) (xy 209.047023 -306.732633)
			(xy 209.099807 -306.714626) (xy 209.15465 -306.704496) (xy 209.210384 -306.702459) (xy 209.265821 -306.708559)
			(xy 209.319778 -306.722665) (xy 209.371107 -306.744477) (xy 209.418713 -306.773531) (xy 209.461581 -306.809206)
			(xy 209.498798 -306.850743) (xy 209.529571 -306.897256) (xy 209.553243 -306.947753) (xy 209.569311 -307.00116)
			(xy 209.577431 -307.056336) (xy 209.57794 -307.084222) (xy 209.577431 -307.112108) (xy 209.569311 -307.167284)
			(xy 209.553243 -307.220691) (xy 209.529571 -307.271188) (xy 209.498798 -307.317701) (xy 209.461581 -307.359238)
			(xy 209.418713 -307.394913) (xy 209.371107 -307.423967) (xy 209.319778 -307.445779) (xy 209.265821 -307.459885)
			(xy 209.210384 -307.465985) (xy 209.15465 -307.463948) (xy 209.099807 -307.453818) (xy 209.047023 -307.435811)
			(xy 208.997423 -307.41031) (xy 208.952065 -307.377859) (xy 208.911916 -307.33915) (xy 208.87783 -307.295007)
			(xy 208.850534 -307.246372) (xy 208.830611 -307.194281) (xy 208.818485 -307.139844) (xy 208.814414 -307.084222)
			(xy 196.896152 -307.084222) (xy 196.899001 -307.087071) (xy 196.929222 -307.128667) (xy 196.952565 -307.174479)
			(xy 196.968453 -307.223378) (xy 196.976496 -307.27416) (xy 196.977 -307.299868) (xy 196.976496 -307.325576)
			(xy 196.968453 -307.376358) (xy 196.952565 -307.425257) (xy 196.929222 -307.471069) (xy 196.899001 -307.512665)
			(xy 196.862645 -307.549021) (xy 196.821049 -307.579242) (xy 196.775237 -307.602585) (xy 196.726338 -307.618473)
			(xy 196.675556 -307.626516) (xy 196.62414 -307.626516) (xy 196.573358 -307.618473) (xy 196.524459 -307.602585)
			(xy 196.478647 -307.579242) (xy 196.437051 -307.549021) (xy 196.400695 -307.512665) (xy 196.370474 -307.471069)
			(xy 196.347131 -307.425257) (xy 196.331243 -307.376358) (xy 196.3232 -307.325576) (xy 196.026536 -307.325576)
			(xy 196.018493 -307.376358) (xy 196.002605 -307.425257) (xy 195.979262 -307.471069) (xy 195.949041 -307.512665)
			(xy 195.912685 -307.549021) (xy 195.871089 -307.579242) (xy 195.825277 -307.602585) (xy 195.776378 -307.618473)
			(xy 195.725596 -307.626516) (xy 195.67418 -307.626516) (xy 195.623398 -307.618473) (xy 195.574499 -307.602585)
			(xy 195.528687 -307.579242) (xy 195.487091 -307.549021) (xy 195.450735 -307.512665) (xy 195.420514 -307.471069)
			(xy 195.397171 -307.425257) (xy 195.381283 -307.376358) (xy 195.37324 -307.325576) (xy 194.126616 -307.325576)
			(xy 194.118573 -307.376358) (xy 194.102685 -307.425257) (xy 194.079342 -307.471069) (xy 194.049121 -307.512665)
			(xy 194.012765 -307.549021) (xy 193.971169 -307.579242) (xy 193.925357 -307.602585) (xy 193.876458 -307.618473)
			(xy 193.825676 -307.626516) (xy 193.77426 -307.626516) (xy 193.723478 -307.618473) (xy 193.674579 -307.602585)
			(xy 193.628767 -307.579242) (xy 193.587171 -307.549021) (xy 193.550815 -307.512665) (xy 193.520594 -307.471069)
			(xy 193.497251 -307.425257) (xy 193.481363 -307.376358) (xy 193.47332 -307.325576) (xy 193.176656 -307.325576)
			(xy 193.168613 -307.376358) (xy 193.152725 -307.425257) (xy 193.129382 -307.471069) (xy 193.099161 -307.512665)
			(xy 193.062805 -307.549021) (xy 193.021209 -307.579242) (xy 192.975397 -307.602585) (xy 192.926498 -307.618473)
			(xy 192.875716 -307.626516) (xy 192.8243 -307.626516) (xy 192.773518 -307.618473) (xy 192.724619 -307.602585)
			(xy 192.678807 -307.579242) (xy 192.637211 -307.549021) (xy 192.600855 -307.512665) (xy 192.570634 -307.471069)
			(xy 192.547291 -307.425257) (xy 192.531403 -307.376358) (xy 192.52336 -307.325576) (xy 185.795412 -307.325576)
			(xy 185.795412 -307.391562) (xy 185.79551 -307.396439) (xy 185.797302 -307.406027) (xy 185.798968 -307.410612)
			(xy 185.802524 -307.419248) (xy 185.809636 -307.426614) (xy 185.81497 -307.432202) (xy 185.820202 -307.438002)
			(xy 185.827176 -307.451969) (xy 185.828686 -307.459634) (xy 185.828686 -307.459888) (xy 185.83021 -307.469032)
			(xy 185.834274 -307.476652) (xy 185.836604 -307.480656) (xy 185.842476 -307.487821) (xy 185.845958 -307.490876)
			(xy 185.854594 -307.498242) (xy 185.860436 -307.50129) (xy 185.881968 -307.512446) (xy 185.9215 -307.540531)
			(xy 185.956089 -307.574518) (xy 185.984864 -307.613551) (xy 186.007098 -307.656646) (xy 186.022231 -307.702716)
			(xy 186.029883 -307.750601) (xy 186.030362 -307.774848) (xy 187.31917 -307.774848) (xy 187.32313 -307.725794)
			(xy 187.334907 -307.67801) (xy 187.354198 -307.632734) (xy 187.380501 -307.591138) (xy 187.413136 -307.554301)
			(xy 187.451257 -307.523176) (xy 187.493878 -307.498569) (xy 187.539894 -307.481117) (xy 187.588113 -307.471273)
			(xy 187.637288 -307.469292) (xy 187.686143 -307.475224) (xy 187.733414 -307.488916) (xy 187.777876 -307.510014)
			(xy 187.818379 -307.53797) (xy 187.853872 -307.572062) (xy 187.883437 -307.611406) (xy 187.906308 -307.654983)
			(xy 187.921892 -307.701664) (xy 187.929787 -307.750241) (xy 187.930282 -307.774848) (xy 188.26913 -307.774848)
			(xy 188.27309 -307.725794) (xy 188.284867 -307.67801) (xy 188.304158 -307.632734) (xy 188.330461 -307.591138)
			(xy 188.363096 -307.554301) (xy 188.401217 -307.523176) (xy 188.443838 -307.498569) (xy 188.489854 -307.481117)
			(xy 188.538073 -307.471273) (xy 188.587248 -307.469292) (xy 188.636103 -307.475224) (xy 188.683374 -307.488916)
			(xy 188.727836 -307.510014) (xy 188.768339 -307.53797) (xy 188.803832 -307.572062) (xy 188.833397 -307.611406)
			(xy 188.856268 -307.654983) (xy 188.871852 -307.701664) (xy 188.879747 -307.750241) (xy 188.880242 -307.774848)
			(xy 188.879747 -307.799455) (xy 188.871852 -307.848032) (xy 188.856268 -307.894713) (xy 188.833397 -307.93829)
			(xy 188.803832 -307.977634) (xy 188.768339 -308.011726) (xy 188.727836 -308.039682) (xy 188.683374 -308.06078)
			(xy 188.636103 -308.074472) (xy 188.587248 -308.080404) (xy 188.538073 -308.078423) (xy 188.489854 -308.068579)
			(xy 188.443838 -308.051127) (xy 188.401217 -308.02652) (xy 188.363096 -307.995395) (xy 188.330461 -307.958558)
			(xy 188.304158 -307.916962) (xy 188.284867 -307.871686) (xy 188.27309 -307.823902) (xy 188.26913 -307.774848)
			(xy 187.930282 -307.774848) (xy 187.929787 -307.799455) (xy 187.921892 -307.848032) (xy 187.906308 -307.894713)
			(xy 187.883437 -307.93829) (xy 187.853872 -307.977634) (xy 187.818379 -308.011726) (xy 187.777876 -308.039682)
			(xy 187.733414 -308.06078) (xy 187.686143 -308.074472) (xy 187.637288 -308.080404) (xy 187.588113 -308.078423)
			(xy 187.539894 -308.068579) (xy 187.493878 -308.051127) (xy 187.451257 -308.02652) (xy 187.413136 -307.995395)
			(xy 187.380501 -307.958558) (xy 187.354198 -307.916962) (xy 187.334907 -307.871686) (xy 187.32313 -307.823902)
			(xy 187.31917 -307.774848) (xy 186.030362 -307.774848) (xy 186.029921 -307.798206) (xy 186.022809 -307.844377)
			(xy 186.008742 -307.888925) (xy 185.988051 -307.930809) (xy 185.961217 -307.969049) (xy 185.928869 -308.002753)
			(xy 185.891761 -308.031133) (xy 185.850762 -308.053526) (xy 185.82894 -308.061868) (xy 185.826146 -308.062884)
			(xy 185.817506 -308.067031) (xy 185.803901 -308.080509) (xy 185.796183 -308.098036) (xy 185.795412 -308.107588)
			(xy 185.795412 -308.275536) (xy 190.62344 -308.275536) (xy 190.62344 -308.22412) (xy 190.631483 -308.173338)
			(xy 190.647371 -308.124439) (xy 190.670714 -308.078627) (xy 190.700935 -308.037031) (xy 190.737291 -308.000675)
			(xy 190.778887 -307.970454) (xy 190.824699 -307.947111) (xy 190.873598 -307.931223) (xy 190.92438 -307.92318)
			(xy 190.975796 -307.92318) (xy 191.026578 -307.931223) (xy 191.075477 -307.947111) (xy 191.121289 -307.970454)
			(xy 191.162885 -308.000675) (xy 191.199241 -308.037031) (xy 191.229462 -308.078627) (xy 191.252805 -308.124439)
			(xy 191.268693 -308.173338) (xy 191.276736 -308.22412) (xy 191.27724 -308.249828) (xy 191.276736 -308.275536)
			(xy 191.5734 -308.275536) (xy 191.5734 -308.22412) (xy 191.581443 -308.173338) (xy 191.597331 -308.124439)
			(xy 191.620674 -308.078627) (xy 191.650895 -308.037031) (xy 191.687251 -308.000675) (xy 191.728847 -307.970454)
			(xy 191.774659 -307.947111) (xy 191.823558 -307.931223) (xy 191.87434 -307.92318) (xy 191.925756 -307.92318)
			(xy 191.976538 -307.931223) (xy 192.025437 -307.947111) (xy 192.071249 -307.970454) (xy 192.112845 -308.000675)
			(xy 192.149201 -308.037031) (xy 192.179422 -308.078627) (xy 192.202765 -308.124439) (xy 192.218653 -308.173338)
			(xy 192.226696 -308.22412) (xy 192.2272 -308.249828) (xy 192.226696 -308.275536) (xy 197.273414 -308.275536)
			(xy 197.273414 -308.22412) (xy 197.281457 -308.173338) (xy 197.297345 -308.124439) (xy 197.320688 -308.078627)
			(xy 197.350909 -308.037031) (xy 197.387265 -308.000675) (xy 197.428861 -307.970454) (xy 197.474673 -307.947111)
			(xy 197.523572 -307.931223) (xy 197.574354 -307.92318) (xy 197.62577 -307.92318) (xy 197.676552 -307.931223)
			(xy 197.725451 -307.947111) (xy 197.771263 -307.970454) (xy 197.812859 -308.000675) (xy 197.849215 -308.037031)
			(xy 197.879436 -308.078627) (xy 197.902779 -308.124439) (xy 197.918667 -308.173338) (xy 197.92671 -308.22412)
			(xy 197.927214 -308.249828) (xy 197.92671 -308.275536) (xy 198.223374 -308.275536) (xy 198.223374 -308.22412)
			(xy 198.231417 -308.173338) (xy 198.247305 -308.124439) (xy 198.270648 -308.078627) (xy 198.300869 -308.037031)
			(xy 198.337225 -308.000675) (xy 198.378821 -307.970454) (xy 198.424633 -307.947111) (xy 198.473532 -307.931223)
			(xy 198.524314 -307.92318) (xy 198.57573 -307.92318) (xy 198.626512 -307.931223) (xy 198.675411 -307.947111)
			(xy 198.721223 -307.970454) (xy 198.762819 -308.000675) (xy 198.799175 -308.037031) (xy 198.829396 -308.078627)
			(xy 198.852739 -308.124439) (xy 198.868627 -308.173338) (xy 198.87667 -308.22412) (xy 198.877174 -308.249828)
			(xy 198.87667 -308.275536) (xy 198.868627 -308.326318) (xy 198.852739 -308.375217) (xy 198.829396 -308.421029)
			(xy 198.799175 -308.462625) (xy 198.762819 -308.498981) (xy 198.721223 -308.529202) (xy 198.675411 -308.552545)
			(xy 198.626512 -308.568433) (xy 198.57573 -308.576476) (xy 198.524314 -308.576476) (xy 198.473532 -308.568433)
			(xy 198.424633 -308.552545) (xy 198.378821 -308.529202) (xy 198.337225 -308.498981) (xy 198.300869 -308.462625)
			(xy 198.270648 -308.421029) (xy 198.247305 -308.375217) (xy 198.231417 -308.326318) (xy 198.223374 -308.275536)
			(xy 197.92671 -308.275536) (xy 197.918667 -308.326318) (xy 197.902779 -308.375217) (xy 197.879436 -308.421029)
			(xy 197.849215 -308.462625) (xy 197.812859 -308.498981) (xy 197.771263 -308.529202) (xy 197.725451 -308.552545)
			(xy 197.676552 -308.568433) (xy 197.62577 -308.576476) (xy 197.574354 -308.576476) (xy 197.523572 -308.568433)
			(xy 197.474673 -308.552545) (xy 197.428861 -308.529202) (xy 197.387265 -308.498981) (xy 197.350909 -308.462625)
			(xy 197.320688 -308.421029) (xy 197.297345 -308.375217) (xy 197.281457 -308.326318) (xy 197.273414 -308.275536)
			(xy 192.226696 -308.275536) (xy 192.218653 -308.326318) (xy 192.202765 -308.375217) (xy 192.179422 -308.421029)
			(xy 192.149201 -308.462625) (xy 192.112845 -308.498981) (xy 192.071249 -308.529202) (xy 192.025437 -308.552545)
			(xy 191.976538 -308.568433) (xy 191.925756 -308.576476) (xy 191.87434 -308.576476) (xy 191.823558 -308.568433)
			(xy 191.774659 -308.552545) (xy 191.728847 -308.529202) (xy 191.687251 -308.498981) (xy 191.650895 -308.462625)
			(xy 191.620674 -308.421029) (xy 191.597331 -308.375217) (xy 191.581443 -308.326318) (xy 191.5734 -308.275536)
			(xy 191.276736 -308.275536) (xy 191.268693 -308.326318) (xy 191.252805 -308.375217) (xy 191.229462 -308.421029)
			(xy 191.199241 -308.462625) (xy 191.162885 -308.498981) (xy 191.121289 -308.529202) (xy 191.075477 -308.552545)
			(xy 191.026578 -308.568433) (xy 190.975796 -308.576476) (xy 190.92438 -308.576476) (xy 190.873598 -308.568433)
			(xy 190.824699 -308.552545) (xy 190.778887 -308.529202) (xy 190.737291 -308.498981) (xy 190.700935 -308.462625)
			(xy 190.670714 -308.421029) (xy 190.647371 -308.375217) (xy 190.631483 -308.326318) (xy 190.62344 -308.275536)
			(xy 185.795412 -308.275536) (xy 185.795412 -308.341522) (xy 185.795506 -308.3464) (xy 185.797292 -308.35599)
			(xy 185.798968 -308.360572) (xy 185.802524 -308.369208) (xy 185.809636 -308.376574) (xy 185.81497 -308.382162)
			(xy 185.820206 -308.38796) (xy 185.827192 -308.401926) (xy 185.828686 -308.409594) (xy 185.828686 -308.409848)
			(xy 185.83021 -308.418992) (xy 185.834274 -308.426612) (xy 185.836608 -308.430613) (xy 185.842485 -308.437771)
			(xy 185.845958 -308.440836) (xy 185.854594 -308.448202) (xy 185.860436 -308.45125) (xy 185.88197 -308.462406)
			(xy 185.921506 -308.490489) (xy 185.9561 -308.524475) (xy 185.984879 -308.563507) (xy 186.007119 -308.606602)
			(xy 186.022258 -308.652674) (xy 186.029915 -308.70056) (xy 186.030362 -308.724808) (xy 186.36921 -308.724808)
			(xy 186.37317 -308.675754) (xy 186.384947 -308.62797) (xy 186.404238 -308.582694) (xy 186.430541 -308.541098)
			(xy 186.463176 -308.504261) (xy 186.501297 -308.473136) (xy 186.543918 -308.448529) (xy 186.589934 -308.431077)
			(xy 186.638153 -308.421233) (xy 186.687328 -308.419252) (xy 186.736183 -308.425184) (xy 186.783454 -308.438876)
			(xy 186.827916 -308.459974) (xy 186.868419 -308.48793) (xy 186.903912 -308.522022) (xy 186.933477 -308.561366)
			(xy 186.956348 -308.604943) (xy 186.971932 -308.651624) (xy 186.979827 -308.700201) (xy 186.980322 -308.724808)
			(xy 187.31917 -308.724808) (xy 187.32313 -308.675754) (xy 187.334907 -308.62797) (xy 187.354198 -308.582694)
			(xy 187.380501 -308.541098) (xy 187.413136 -308.504261) (xy 187.451257 -308.473136) (xy 187.493878 -308.448529)
			(xy 187.539894 -308.431077) (xy 187.588113 -308.421233) (xy 187.637288 -308.419252) (xy 187.686143 -308.425184)
			(xy 187.733414 -308.438876) (xy 187.777876 -308.459974) (xy 187.818379 -308.48793) (xy 187.853872 -308.522022)
			(xy 187.883437 -308.561366) (xy 187.906308 -308.604943) (xy 187.921892 -308.651624) (xy 187.929787 -308.700201)
			(xy 187.930282 -308.724808) (xy 188.26913 -308.724808) (xy 188.27309 -308.675754) (xy 188.284867 -308.62797)
			(xy 188.304158 -308.582694) (xy 188.330461 -308.541098) (xy 188.363096 -308.504261) (xy 188.401217 -308.473136)
			(xy 188.443838 -308.448529) (xy 188.489854 -308.431077) (xy 188.538073 -308.421233) (xy 188.587248 -308.419252)
			(xy 188.636103 -308.425184) (xy 188.683374 -308.438876) (xy 188.727836 -308.459974) (xy 188.768339 -308.48793)
			(xy 188.803832 -308.522022) (xy 188.833397 -308.561366) (xy 188.856268 -308.604943) (xy 188.871852 -308.651624)
			(xy 188.879747 -308.700201) (xy 188.880242 -308.724808) (xy 188.879747 -308.749415) (xy 188.871852 -308.797992)
			(xy 188.856268 -308.844673) (xy 188.833397 -308.88825) (xy 188.803832 -308.927594) (xy 188.768339 -308.961686)
			(xy 188.727836 -308.989642) (xy 188.683374 -309.01074) (xy 188.636103 -309.024432) (xy 188.587248 -309.030364)
			(xy 188.538073 -309.028383) (xy 188.489854 -309.018539) (xy 188.443838 -309.001087) (xy 188.401217 -308.97648)
			(xy 188.363096 -308.945355) (xy 188.330461 -308.908518) (xy 188.304158 -308.866922) (xy 188.284867 -308.821646)
			(xy 188.27309 -308.773862) (xy 188.26913 -308.724808) (xy 187.930282 -308.724808) (xy 187.929787 -308.749415)
			(xy 187.921892 -308.797992) (xy 187.906308 -308.844673) (xy 187.883437 -308.88825) (xy 187.853872 -308.927594)
			(xy 187.818379 -308.961686) (xy 187.777876 -308.989642) (xy 187.733414 -309.01074) (xy 187.686143 -309.024432)
			(xy 187.637288 -309.030364) (xy 187.588113 -309.028383) (xy 187.539894 -309.018539) (xy 187.493878 -309.001087)
			(xy 187.451257 -308.97648) (xy 187.413136 -308.945355) (xy 187.380501 -308.908518) (xy 187.354198 -308.866922)
			(xy 187.334907 -308.821646) (xy 187.32313 -308.773862) (xy 187.31917 -308.724808) (xy 186.980322 -308.724808)
			(xy 186.979827 -308.749415) (xy 186.971932 -308.797992) (xy 186.956348 -308.844673) (xy 186.933477 -308.88825)
			(xy 186.903912 -308.927594) (xy 186.868419 -308.961686) (xy 186.827916 -308.989642) (xy 186.783454 -309.01074)
			(xy 186.736183 -309.024432) (xy 186.687328 -309.030364) (xy 186.638153 -309.028383) (xy 186.589934 -309.018539)
			(xy 186.543918 -309.001087) (xy 186.501297 -308.97648) (xy 186.463176 -308.945355) (xy 186.430541 -308.908518)
			(xy 186.404238 -308.866922) (xy 186.384947 -308.821646) (xy 186.37317 -308.773862) (xy 186.36921 -308.724808)
			(xy 186.030362 -308.724808) (xy 186.029924 -308.748168) (xy 186.022817 -308.794343) (xy 186.008754 -308.838896)
			(xy 185.988065 -308.880784) (xy 185.961233 -308.91903) (xy 185.928885 -308.952739) (xy 185.891777 -308.981123)
			(xy 185.850776 -309.00352) (xy 185.82894 -309.011828) (xy 185.826146 -309.012844) (xy 185.817512 -309.016994)
			(xy 185.803923 -309.030476) (xy 185.796225 -309.048001) (xy 185.795412 -309.057548) (xy 185.795412 -309.225496)
			(xy 192.52336 -309.225496) (xy 192.52336 -309.17408) (xy 192.531403 -309.123298) (xy 192.547291 -309.074399)
			(xy 192.570634 -309.028587) (xy 192.600855 -308.986991) (xy 192.637211 -308.950635) (xy 192.678807 -308.920414)
			(xy 192.724619 -308.897071) (xy 192.773518 -308.881183) (xy 192.8243 -308.87314) (xy 192.875716 -308.87314)
			(xy 192.926498 -308.881183) (xy 192.975397 -308.897071) (xy 193.021209 -308.920414) (xy 193.062805 -308.950635)
			(xy 193.099161 -308.986991) (xy 193.129382 -309.028587) (xy 193.152725 -309.074399) (xy 193.168613 -309.123298)
			(xy 193.176656 -309.17408) (xy 193.17716 -309.199788) (xy 193.176656 -309.225496) (xy 193.47332 -309.225496)
			(xy 193.47332 -309.17408) (xy 193.481363 -309.123298) (xy 193.497251 -309.074399) (xy 193.520594 -309.028587)
			(xy 193.550815 -308.986991) (xy 193.587171 -308.950635) (xy 193.628767 -308.920414) (xy 193.674579 -308.897071)
			(xy 193.723478 -308.881183) (xy 193.77426 -308.87314) (xy 193.825676 -308.87314) (xy 193.876458 -308.881183)
			(xy 193.925357 -308.897071) (xy 193.971169 -308.920414) (xy 194.012765 -308.950635) (xy 194.049121 -308.986991)
			(xy 194.079342 -309.028587) (xy 194.102685 -309.074399) (xy 194.118573 -309.123298) (xy 194.126616 -309.17408)
			(xy 194.12712 -309.199788) (xy 194.126616 -309.225496) (xy 195.37324 -309.225496) (xy 195.37324 -309.17408)
			(xy 195.381283 -309.123298) (xy 195.397171 -309.074399) (xy 195.420514 -309.028587) (xy 195.450735 -308.986991)
			(xy 195.487091 -308.950635) (xy 195.528687 -308.920414) (xy 195.574499 -308.897071) (xy 195.623398 -308.881183)
			(xy 195.67418 -308.87314) (xy 195.725596 -308.87314) (xy 195.776378 -308.881183) (xy 195.825277 -308.897071)
			(xy 195.871089 -308.920414) (xy 195.912685 -308.950635) (xy 195.949041 -308.986991) (xy 195.979262 -309.028587)
			(xy 196.002605 -309.074399) (xy 196.018493 -309.123298) (xy 196.026536 -309.17408) (xy 196.02704 -309.199788)
			(xy 196.026536 -309.225496) (xy 196.3232 -309.225496) (xy 196.3232 -309.17408) (xy 196.331243 -309.123298)
			(xy 196.347131 -309.074399) (xy 196.370474 -309.028587) (xy 196.400695 -308.986991) (xy 196.437051 -308.950635)
			(xy 196.478647 -308.920414) (xy 196.524459 -308.897071) (xy 196.573358 -308.881183) (xy 196.62414 -308.87314)
			(xy 196.675556 -308.87314) (xy 196.726338 -308.881183) (xy 196.775237 -308.897071) (xy 196.821049 -308.920414)
			(xy 196.862645 -308.950635) (xy 196.899001 -308.986991) (xy 196.929222 -309.028587) (xy 196.952565 -309.074399)
			(xy 196.968453 -309.123298) (xy 196.976496 -309.17408) (xy 196.977 -309.199788) (xy 196.976496 -309.225496)
			(xy 196.968453 -309.276278) (xy 196.952565 -309.325177) (xy 196.929222 -309.370989) (xy 196.927154 -309.373836)
			(xy 204.602097 -309.373836) (xy 204.602099 -309.319337) (xy 204.609857 -309.265393) (xy 204.625213 -309.213102)
			(xy 204.647854 -309.163529) (xy 204.67732 -309.117682) (xy 204.71301 -309.076496) (xy 204.754198 -309.040808)
			(xy 204.800047 -309.011344) (xy 204.849621 -308.988706) (xy 204.901913 -308.973353) (xy 204.955857 -308.965598)
			(xy 205.010356 -308.965599) (xy 205.0643 -308.973356) (xy 205.116591 -308.98871) (xy 205.166165 -309.011351)
			(xy 205.212012 -309.040816) (xy 205.253199 -309.076505) (xy 205.288888 -309.117693) (xy 205.318352 -309.163541)
			(xy 205.340992 -309.213115) (xy 205.356346 -309.265406) (xy 205.364102 -309.319351) (xy 205.364588 -309.3466)
			(xy 205.36408 -309.365904) (xy 205.36408 -309.366158) (xy 205.364157 -309.376749) (xy 205.371924 -309.396433)
			(xy 205.379066 -309.404258) (xy 205.43266 -309.457598) (xy 205.440553 -309.464839) (xy 205.460556 -309.472459)
			(xy 205.471268 -309.47233) (xy 205.492858 -309.471822) (xy 205.520114 -309.47221) (xy 205.574072 -309.479962)
			(xy 205.626378 -309.495314) (xy 205.675966 -309.517954) (xy 205.721828 -309.547421) (xy 205.763029 -309.583114)
			(xy 205.798731 -309.624308) (xy 205.828208 -309.670163) (xy 205.850858 -309.719747) (xy 205.866221 -309.772049)
			(xy 205.873984 -309.826006) (xy 205.87399 -309.880518) (xy 205.866237 -309.934476) (xy 205.850884 -309.986782)
			(xy 205.828244 -310.03637) (xy 205.798777 -310.082231) (xy 205.763083 -310.123432) (xy 205.721889 -310.159134)
			(xy 205.676033 -310.18861) (xy 205.626449 -310.211259) (xy 205.574147 -310.226622) (xy 205.52019 -310.234385)
			(xy 205.465678 -310.234389) (xy 205.41172 -310.226636) (xy 205.359415 -310.211283) (xy 205.309827 -310.188642)
			(xy 205.263966 -310.159175) (xy 205.222765 -310.12348) (xy 205.187064 -310.082286) (xy 205.157589 -310.03643)
			(xy 205.134939 -309.986845) (xy 205.119577 -309.934543) (xy 205.111815 -309.880586) (xy 205.11135 -309.85333)
			(xy 205.111858 -309.834026) (xy 205.111858 -309.833772) (xy 205.111754 -309.823183) (xy 205.104004 -309.8035)
			(xy 205.096872 -309.795672) (xy 205.043278 -309.742332) (xy 205.035367 -309.735113) (xy 205.015378 -309.72748)
			(xy 205.00467 -309.7276) (xy 204.98308 -309.728108) (xy 204.955831 -309.7276) (xy 204.901887 -309.719842)
			(xy 204.849596 -309.704485) (xy 204.800023 -309.681843) (xy 204.754177 -309.652376) (xy 204.712991 -309.616685)
			(xy 204.677304 -309.575496) (xy 204.647841 -309.529648) (xy 204.625203 -309.480073) (xy 204.609851 -309.427781)
			(xy 204.602097 -309.373836) (xy 196.927154 -309.373836) (xy 196.899001 -309.412585) (xy 196.862645 -309.448941)
			(xy 196.821049 -309.479162) (xy 196.775237 -309.502505) (xy 196.726338 -309.518393) (xy 196.675556 -309.526436)
			(xy 196.62414 -309.526436) (xy 196.573358 -309.518393) (xy 196.524459 -309.502505) (xy 196.478647 -309.479162)
			(xy 196.437051 -309.448941) (xy 196.400695 -309.412585) (xy 196.370474 -309.370989) (xy 196.347131 -309.325177)
			(xy 196.331243 -309.276278) (xy 196.3232 -309.225496) (xy 196.026536 -309.225496) (xy 196.018493 -309.276278)
			(xy 196.002605 -309.325177) (xy 195.979262 -309.370989) (xy 195.949041 -309.412585) (xy 195.912685 -309.448941)
			(xy 195.871089 -309.479162) (xy 195.825277 -309.502505) (xy 195.776378 -309.518393) (xy 195.725596 -309.526436)
			(xy 195.67418 -309.526436) (xy 195.623398 -309.518393) (xy 195.574499 -309.502505) (xy 195.528687 -309.479162)
			(xy 195.487091 -309.448941) (xy 195.450735 -309.412585) (xy 195.420514 -309.370989) (xy 195.397171 -309.325177)
			(xy 195.381283 -309.276278) (xy 195.37324 -309.225496) (xy 194.126616 -309.225496) (xy 194.118573 -309.276278)
			(xy 194.102685 -309.325177) (xy 194.079342 -309.370989) (xy 194.049121 -309.412585) (xy 194.012765 -309.448941)
			(xy 193.971169 -309.479162) (xy 193.925357 -309.502505) (xy 193.876458 -309.518393) (xy 193.825676 -309.526436)
			(xy 193.77426 -309.526436) (xy 193.723478 -309.518393) (xy 193.674579 -309.502505) (xy 193.628767 -309.479162)
			(xy 193.587171 -309.448941) (xy 193.550815 -309.412585) (xy 193.520594 -309.370989) (xy 193.497251 -309.325177)
			(xy 193.481363 -309.276278) (xy 193.47332 -309.225496) (xy 193.176656 -309.225496) (xy 193.168613 -309.276278)
			(xy 193.152725 -309.325177) (xy 193.129382 -309.370989) (xy 193.099161 -309.412585) (xy 193.062805 -309.448941)
			(xy 193.021209 -309.479162) (xy 192.975397 -309.502505) (xy 192.926498 -309.518393) (xy 192.875716 -309.526436)
			(xy 192.8243 -309.526436) (xy 192.773518 -309.518393) (xy 192.724619 -309.502505) (xy 192.678807 -309.479162)
			(xy 192.637211 -309.448941) (xy 192.600855 -309.412585) (xy 192.570634 -309.370989) (xy 192.547291 -309.325177)
			(xy 192.531403 -309.276278) (xy 192.52336 -309.225496) (xy 185.795412 -309.225496) (xy 185.795412 -309.313072)
			(xy 185.795713 -309.320943) (xy 185.800507 -309.335938) (xy 185.80481 -309.342536) (xy 185.809382 -309.348886)
			(xy 185.822082 -309.358538) (xy 185.829956 -309.361078) (xy 185.854286 -309.369733) (xy 185.900122 -309.393513)
			(xy 185.941706 -309.424128) (xy 185.978028 -309.460832) (xy 186.008205 -309.502734) (xy 186.031504 -309.548817)
			(xy 186.047359 -309.597961) (xy 186.055384 -309.648971) (xy 186.055386 -309.700609) (xy 186.047363 -309.75162)
			(xy 186.031511 -309.800764) (xy 186.008215 -309.846848) (xy 185.978041 -309.888753) (xy 185.941722 -309.925459)
			(xy 185.90014 -309.956076) (xy 185.854305 -309.979859) (xy 185.829956 -309.988458) (xy 185.829702 -309.988458)
			(xy 185.822199 -309.991267) (xy 185.809371 -310.000851) (xy 185.804556 -310.007254) (xy 185.800238 -310.013604)
			(xy 185.795412 -310.028336) (xy 185.795412 -310.175456) (xy 197.273414 -310.175456) (xy 197.273414 -310.12404)
			(xy 197.281457 -310.073258) (xy 197.297345 -310.024359) (xy 197.320688 -309.978547) (xy 197.350909 -309.936951)
			(xy 197.387265 -309.900595) (xy 197.428861 -309.870374) (xy 197.474673 -309.847031) (xy 197.523572 -309.831143)
			(xy 197.574354 -309.8231) (xy 197.62577 -309.8231) (xy 197.676552 -309.831143) (xy 197.725451 -309.847031)
			(xy 197.771263 -309.870374) (xy 197.812859 -309.900595) (xy 197.849215 -309.936951) (xy 197.879436 -309.978547)
			(xy 197.902779 -310.024359) (xy 197.918667 -310.073258) (xy 197.92671 -310.12404) (xy 197.927214 -310.149748)
			(xy 197.92671 -310.175456) (xy 198.223374 -310.175456) (xy 198.223374 -310.12404) (xy 198.231417 -310.073258)
			(xy 198.247305 -310.024359) (xy 198.270648 -309.978547) (xy 198.300869 -309.936951) (xy 198.337225 -309.900595)
			(xy 198.378821 -309.870374) (xy 198.424633 -309.847031) (xy 198.473532 -309.831143) (xy 198.524314 -309.8231)
			(xy 198.57573 -309.8231) (xy 198.626512 -309.831143) (xy 198.675411 -309.847031) (xy 198.721223 -309.870374)
			(xy 198.762819 -309.900595) (xy 198.799175 -309.936951) (xy 198.829396 -309.978547) (xy 198.852739 -310.024359)
			(xy 198.868627 -310.073258) (xy 198.87667 -310.12404) (xy 198.877174 -310.149748) (xy 198.87667 -310.175456)
			(xy 198.868627 -310.226238) (xy 198.852739 -310.275137) (xy 198.829396 -310.320949) (xy 198.799175 -310.362545)
			(xy 198.762819 -310.398901) (xy 198.721223 -310.429122) (xy 198.675411 -310.452465) (xy 198.626512 -310.468353)
			(xy 198.57573 -310.476396) (xy 198.524314 -310.476396) (xy 198.473532 -310.468353) (xy 198.424633 -310.452465)
			(xy 198.378821 -310.429122) (xy 198.337225 -310.398901) (xy 198.300869 -310.362545) (xy 198.270648 -310.320949)
			(xy 198.247305 -310.275137) (xy 198.231417 -310.226238) (xy 198.223374 -310.175456) (xy 197.92671 -310.175456)
			(xy 197.918667 -310.226238) (xy 197.902779 -310.275137) (xy 197.879436 -310.320949) (xy 197.849215 -310.362545)
			(xy 197.812859 -310.398901) (xy 197.771263 -310.429122) (xy 197.725451 -310.452465) (xy 197.676552 -310.468353)
			(xy 197.62577 -310.476396) (xy 197.574354 -310.476396) (xy 197.523572 -310.468353) (xy 197.474673 -310.452465)
			(xy 197.428861 -310.429122) (xy 197.387265 -310.398901) (xy 197.350909 -310.362545) (xy 197.320688 -310.320949)
			(xy 197.297345 -310.275137) (xy 197.281457 -310.226238) (xy 197.273414 -310.175456) (xy 185.795412 -310.175456)
			(xy 185.795412 -310.263032) (xy 185.795707 -310.270905) (xy 185.800491 -310.285907) (xy 185.80481 -310.292496)
			(xy 185.809382 -310.298846) (xy 185.822082 -310.308498) (xy 185.829956 -310.311038) (xy 185.853557 -310.319418)
			(xy 185.898115 -310.342282) (xy 185.938717 -310.371601) (xy 185.974437 -310.406704) (xy 186.004458 -310.446789)
			(xy 186.028095 -310.490941) (xy 186.044808 -310.538152) (xy 186.054214 -310.587342) (xy 186.056099 -310.637387)
			(xy 186.05373 -310.66232) (xy 186.05246 -310.67375) (xy 186.056314 -310.68518) (xy 205.94269 -310.68518)
			(xy 205.946761 -310.629558) (xy 205.958887 -310.575121) (xy 205.97881 -310.52303) (xy 206.006106 -310.474395)
			(xy 206.040192 -310.430252) (xy 206.080341 -310.391543) (xy 206.125699 -310.359092) (xy 206.175299 -310.333591)
			(xy 206.228083 -310.315584) (xy 206.282926 -310.305454) (xy 206.33866 -310.303417) (xy 206.394097 -310.309517)
			(xy 206.448054 -310.323623) (xy 206.499383 -310.345435) (xy 206.546989 -310.374489) (xy 206.589857 -310.410164)
			(xy 206.627074 -310.451701) (xy 206.657847 -310.498214) (xy 206.681519 -310.548711) (xy 206.697587 -310.602118)
			(xy 206.705707 -310.657294) (xy 206.706216 -310.68518) (xy 206.705707 -310.713066) (xy 206.697587 -310.768242)
			(xy 206.681519 -310.821649) (xy 206.657847 -310.872146) (xy 206.627074 -310.918659) (xy 206.589857 -310.960196)
			(xy 206.546989 -310.995871) (xy 206.499383 -311.024925) (xy 206.448054 -311.046737) (xy 206.394097 -311.060843)
			(xy 206.33866 -311.066943) (xy 206.282926 -311.064906) (xy 206.228083 -311.054776) (xy 206.175299 -311.036769)
			(xy 206.125699 -311.011268) (xy 206.080341 -310.978817) (xy 206.040192 -310.940108) (xy 206.006106 -310.895965)
			(xy 205.97881 -310.84733) (xy 205.958887 -310.795239) (xy 205.946761 -310.740802) (xy 205.94269 -310.68518)
			(xy 186.056314 -310.68518) (xy 186.059826 -310.695594) (xy 186.132216 -310.768238) (xy 186.153806 -310.776112)
			(xy 186.165236 -310.774842) (xy 186.200034 -310.773064) (xy 186.225723 -310.77357) (xy 186.276468 -310.781612)
			(xy 186.32533 -310.797493) (xy 186.371107 -310.820822) (xy 186.41267 -310.851024) (xy 186.448998 -310.887355)
			(xy 186.479196 -310.928922) (xy 186.50252 -310.974701) (xy 186.518395 -311.023565) (xy 186.526432 -311.074311)
			(xy 186.526432 -311.12567) (xy 187.773306 -311.12567) (xy 187.773306 -311.074254) (xy 187.781349 -311.023472)
			(xy 187.797237 -310.974573) (xy 187.82058 -310.928761) (xy 187.850801 -310.887165) (xy 187.887157 -310.850809)
			(xy 187.928753 -310.820588) (xy 187.974565 -310.797245) (xy 188.023464 -310.781357) (xy 188.074246 -310.773314)
			(xy 188.125662 -310.773314) (xy 188.176444 -310.781357) (xy 188.225343 -310.797245) (xy 188.271155 -310.820588)
			(xy 188.312751 -310.850809) (xy 188.349107 -310.887165) (xy 188.379328 -310.928761) (xy 188.402671 -310.974573)
			(xy 188.418559 -311.023472) (xy 188.426602 -311.074254) (xy 188.427106 -311.099962) (xy 188.426602 -311.12567)
			(xy 189.673226 -311.12567) (xy 189.673226 -311.074254) (xy 189.681269 -311.023472) (xy 189.697157 -310.974573)
			(xy 189.7205 -310.928761) (xy 189.750721 -310.887165) (xy 189.787077 -310.850809) (xy 189.828673 -310.820588)
			(xy 189.874485 -310.797245) (xy 189.923384 -310.781357) (xy 189.974166 -310.773314) (xy 190.025582 -310.773314)
			(xy 190.076364 -310.781357) (xy 190.125263 -310.797245) (xy 190.171075 -310.820588) (xy 190.212671 -310.850809)
			(xy 190.249027 -310.887165) (xy 190.279248 -310.928761) (xy 190.302591 -310.974573) (xy 190.318479 -311.023472)
			(xy 190.326522 -311.074254) (xy 190.327026 -311.099962) (xy 190.326522 -311.12567) (xy 191.5734 -311.12567)
			(xy 191.5734 -311.074254) (xy 191.581443 -311.023472) (xy 191.597331 -310.974573) (xy 191.620674 -310.928761)
			(xy 191.650895 -310.887165) (xy 191.687251 -310.850809) (xy 191.728847 -310.820588) (xy 191.774659 -310.797245)
			(xy 191.823558 -310.781357) (xy 191.87434 -310.773314) (xy 191.925756 -310.773314) (xy 191.976538 -310.781357)
			(xy 192.025437 -310.797245) (xy 192.071249 -310.820588) (xy 192.112845 -310.850809) (xy 192.149201 -310.887165)
			(xy 192.179422 -310.928761) (xy 192.202765 -310.974573) (xy 192.218653 -311.023472) (xy 192.226696 -311.074254)
			(xy 192.2272 -311.099962) (xy 192.226696 -311.12567) (xy 193.47332 -311.12567) (xy 193.47332 -311.074254)
			(xy 193.481363 -311.023472) (xy 193.497251 -310.974573) (xy 193.520594 -310.928761) (xy 193.550815 -310.887165)
			(xy 193.587171 -310.850809) (xy 193.628767 -310.820588) (xy 193.674579 -310.797245) (xy 193.723478 -310.781357)
			(xy 193.77426 -310.773314) (xy 193.825676 -310.773314) (xy 193.876458 -310.781357) (xy 193.925357 -310.797245)
			(xy 193.971169 -310.820588) (xy 194.012765 -310.850809) (xy 194.049121 -310.887165) (xy 194.079342 -310.928761)
			(xy 194.102685 -310.974573) (xy 194.118573 -311.023472) (xy 194.126616 -311.074254) (xy 194.12712 -311.099962)
			(xy 194.126616 -311.12567) (xy 195.37324 -311.12567) (xy 195.37324 -311.074254) (xy 195.381283 -311.023472)
			(xy 195.397171 -310.974573) (xy 195.420514 -310.928761) (xy 195.450735 -310.887165) (xy 195.487091 -310.850809)
			(xy 195.528687 -310.820588) (xy 195.574499 -310.797245) (xy 195.623398 -310.781357) (xy 195.67418 -310.773314)
			(xy 195.725596 -310.773314) (xy 195.776378 -310.781357) (xy 195.825277 -310.797245) (xy 195.871089 -310.820588)
			(xy 195.912685 -310.850809) (xy 195.949041 -310.887165) (xy 195.979262 -310.928761) (xy 196.002605 -310.974573)
			(xy 196.018493 -311.023472) (xy 196.026536 -311.074254) (xy 196.02704 -311.099962) (xy 196.026536 -311.12567)
			(xy 196.018493 -311.176452) (xy 196.002605 -311.225351) (xy 195.979262 -311.271163) (xy 195.949041 -311.312759)
			(xy 195.912685 -311.349115) (xy 195.871089 -311.379336) (xy 195.868047 -311.380886) (xy 206.666706 -311.380886)
			(xy 206.674458 -311.326928) (xy 206.68981 -311.274621) (xy 206.71245 -311.225033) (xy 206.741917 -311.17917)
			(xy 206.777611 -311.137969) (xy 206.818805 -311.102266) (xy 206.86466 -311.072789) (xy 206.914245 -311.050139)
			(xy 206.966547 -311.034775) (xy 207.020504 -311.027012) (xy 207.075017 -311.027006) (xy 207.128976 -311.034759)
			(xy 207.181282 -311.050111) (xy 207.23087 -311.072752) (xy 207.276732 -311.102219) (xy 207.317934 -311.137913)
			(xy 207.353636 -311.179107) (xy 207.383112 -311.224963) (xy 207.405762 -311.274548) (xy 207.421125 -311.326851)
			(xy 207.428888 -311.380808) (xy 207.429354 -311.408064) (xy 207.429157 -311.425112) (xy 207.426103 -311.459072)
			(xy 207.423258 -311.475882) (xy 207.420972 -311.488328) (xy 207.428338 -311.51195) (xy 207.5053 -311.588912)
			(xy 207.528922 -311.596278) (xy 207.541368 -311.593992) (xy 207.558177 -311.591134) (xy 207.592137 -311.588079)
			(xy 207.609186 -311.587896) (xy 207.60944 -311.587896) (xy 207.636692 -311.588341) (xy 207.690642 -311.596103)
			(xy 207.742938 -311.611463) (xy 207.792515 -311.634109) (xy 207.838366 -311.66358) (xy 207.879555 -311.699276)
			(xy 207.915246 -311.74047) (xy 207.944712 -311.786323) (xy 207.967352 -311.835904) (xy 207.982707 -311.888201)
			(xy 207.990463 -311.942152) (xy 207.990948 -311.969404) (xy 207.989932 -311.99836) (xy 207.98917 -312.009536)
			(xy 207.99679 -312.030364) (xy 208.06791 -312.100468) (xy 208.088738 -312.108088) (xy 208.099914 -312.107072)
			(xy 208.132426 -312.105802) (xy 208.159675 -312.106306) (xy 208.213617 -312.114065) (xy 208.265906 -312.129422)
			(xy 208.315478 -312.152064) (xy 208.361322 -312.181531) (xy 208.402507 -312.217221) (xy 208.438193 -312.25841)
			(xy 208.467655 -312.304257) (xy 208.490292 -312.353831) (xy 208.505643 -312.406122) (xy 208.513397 -312.460065)
			(xy 208.513395 -312.514563) (xy 208.505637 -312.568505) (xy 208.490282 -312.620795) (xy 208.467641 -312.670367)
			(xy 208.438176 -312.716213) (xy 208.402487 -312.757399) (xy 208.3613 -312.793086) (xy 208.315453 -312.822549)
			(xy 208.26588 -312.845187) (xy 208.21359 -312.860541) (xy 208.159647 -312.868296) (xy 208.105149 -312.868296)
			(xy 208.051206 -312.86054) (xy 207.998916 -312.845186) (xy 207.949343 -312.822547) (xy 207.903497 -312.793084)
			(xy 207.86231 -312.757396) (xy 207.826621 -312.71621) (xy 207.797157 -312.670364) (xy 207.774517 -312.620791)
			(xy 207.759162 -312.568502) (xy 207.751405 -312.514559) (xy 207.750918 -312.48731) (xy 207.751934 -312.458354)
			(xy 207.752696 -312.447178) (xy 207.745076 -312.42635) (xy 207.673956 -312.356246) (xy 207.653128 -312.348626)
			(xy 207.641952 -312.349642) (xy 207.60944 -312.350912) (xy 207.582188 -312.350408) (xy 207.528239 -312.342656)
			(xy 207.475942 -312.327305) (xy 207.426363 -312.304668) (xy 207.380509 -312.275204) (xy 207.339316 -312.239515)
			(xy 207.303622 -312.198326) (xy 207.274153 -312.152476) (xy 207.25151 -312.102899) (xy 207.236153 -312.050604)
			(xy 207.228396 -311.996656) (xy 207.227932 -311.969404) (xy 207.228138 -311.952356) (xy 207.231186 -311.918397)
			(xy 207.234028 -311.901586) (xy 207.236314 -311.88914) (xy 207.228948 -311.865518) (xy 207.151986 -311.788556)
			(xy 207.128364 -311.78119) (xy 207.115918 -311.783476) (xy 207.09911 -311.786335) (xy 207.065149 -311.78939)
			(xy 207.0481 -311.789572) (xy 207.047846 -311.789572) (xy 207.02059 -311.789194) (xy 206.966631 -311.781443)
			(xy 206.914325 -311.766091) (xy 206.864735 -311.743452) (xy 206.818873 -311.713985) (xy 206.777671 -311.678292)
			(xy 206.741968 -311.637098) (xy 206.712491 -311.591242) (xy 206.68984 -311.541659) (xy 206.674476 -311.489356)
			(xy 206.666712 -311.435399) (xy 206.666706 -311.380886) (xy 195.868047 -311.380886) (xy 195.825277 -311.402679)
			(xy 195.776378 -311.418567) (xy 195.725596 -311.42661) (xy 195.67418 -311.42661) (xy 195.623398 -311.418567)
			(xy 195.574499 -311.402679) (xy 195.528687 -311.379336) (xy 195.487091 -311.349115) (xy 195.450735 -311.312759)
			(xy 195.420514 -311.271163) (xy 195.397171 -311.225351) (xy 195.381283 -311.176452) (xy 195.37324 -311.12567)
			(xy 194.126616 -311.12567) (xy 194.118573 -311.176452) (xy 194.102685 -311.225351) (xy 194.079342 -311.271163)
			(xy 194.049121 -311.312759) (xy 194.012765 -311.349115) (xy 193.971169 -311.379336) (xy 193.925357 -311.402679)
			(xy 193.876458 -311.418567) (xy 193.825676 -311.42661) (xy 193.77426 -311.42661) (xy 193.723478 -311.418567)
			(xy 193.674579 -311.402679) (xy 193.628767 -311.379336) (xy 193.587171 -311.349115) (xy 193.550815 -311.312759)
			(xy 193.520594 -311.271163) (xy 193.497251 -311.225351) (xy 193.481363 -311.176452) (xy 193.47332 -311.12567)
			(xy 192.226696 -311.12567) (xy 192.218653 -311.176452) (xy 192.202765 -311.225351) (xy 192.179422 -311.271163)
			(xy 192.149201 -311.312759) (xy 192.112845 -311.349115) (xy 192.071249 -311.379336) (xy 192.025437 -311.402679)
			(xy 191.976538 -311.418567) (xy 191.925756 -311.42661) (xy 191.87434 -311.42661) (xy 191.823558 -311.418567)
			(xy 191.774659 -311.402679) (xy 191.728847 -311.379336) (xy 191.687251 -311.349115) (xy 191.650895 -311.312759)
			(xy 191.620674 -311.271163) (xy 191.597331 -311.225351) (xy 191.581443 -311.176452) (xy 191.5734 -311.12567)
			(xy 190.326522 -311.12567) (xy 190.318479 -311.176452) (xy 190.302591 -311.225351) (xy 190.279248 -311.271163)
			(xy 190.249027 -311.312759) (xy 190.212671 -311.349115) (xy 190.171075 -311.379336) (xy 190.125263 -311.402679)
			(xy 190.076364 -311.418567) (xy 190.025582 -311.42661) (xy 189.974166 -311.42661) (xy 189.923384 -311.418567)
			(xy 189.874485 -311.402679) (xy 189.828673 -311.379336) (xy 189.787077 -311.349115) (xy 189.750721 -311.312759)
			(xy 189.7205 -311.271163) (xy 189.697157 -311.225351) (xy 189.681269 -311.176452) (xy 189.673226 -311.12567)
			(xy 188.426602 -311.12567) (xy 188.418559 -311.176452) (xy 188.402671 -311.225351) (xy 188.379328 -311.271163)
			(xy 188.349107 -311.312759) (xy 188.312751 -311.349115) (xy 188.271155 -311.379336) (xy 188.225343 -311.402679)
			(xy 188.176444 -311.418567) (xy 188.125662 -311.42661) (xy 188.074246 -311.42661) (xy 188.023464 -311.418567)
			(xy 187.974565 -311.402679) (xy 187.928753 -311.379336) (xy 187.887157 -311.349115) (xy 187.850801 -311.312759)
			(xy 187.82058 -311.271163) (xy 187.797237 -311.225351) (xy 187.781349 -311.176452) (xy 187.773306 -311.12567)
			(xy 186.526432 -311.12567) (xy 186.526432 -311.125689) (xy 186.518395 -311.176435) (xy 186.50252 -311.225299)
			(xy 186.479196 -311.271078) (xy 186.448998 -311.312645) (xy 186.41267 -311.348976) (xy 186.371107 -311.379178)
			(xy 186.32533 -311.402507) (xy 186.276468 -311.418388) (xy 186.225723 -311.42643) (xy 186.200034 -311.42686)
			(xy 186.16549 -311.425082) (xy 186.165236 -311.425082) (xy 186.153889 -311.424564) (xy 186.132533 -311.432217)
			(xy 186.124088 -311.439814) (xy 186.059826 -311.50433) (xy 186.05246 -311.526174) (xy 186.05373 -311.537604)
			(xy 186.055583 -311.556228) (xy 186.055578 -311.593656) (xy 186.05373 -311.61228) (xy 186.05246 -311.62371)
			(xy 186.059826 -311.645554) (xy 186.124088 -311.71007) (xy 186.132515 -311.717699) (xy 186.153884 -311.725362)
			(xy 186.165236 -311.724802) (xy 186.16549 -311.724802) (xy 186.200034 -311.723024) (xy 186.225718 -311.72353)
			(xy 186.276454 -311.731571) (xy 186.325307 -311.747449) (xy 186.371075 -311.770773) (xy 186.412632 -311.800969)
			(xy 186.448953 -311.837294) (xy 186.479145 -311.878854) (xy 186.502464 -311.924624) (xy 186.518337 -311.973479)
			(xy 186.526372 -312.024216) (xy 186.526372 -312.075584) (xy 186.526365 -312.07563) (xy 187.773306 -312.07563)
			(xy 187.773306 -312.024214) (xy 187.781349 -311.973432) (xy 187.797237 -311.924533) (xy 187.82058 -311.878721)
			(xy 187.850801 -311.837125) (xy 187.887157 -311.800769) (xy 187.928753 -311.770548) (xy 187.974565 -311.747205)
			(xy 188.023464 -311.731317) (xy 188.074246 -311.723274) (xy 188.125662 -311.723274) (xy 188.176444 -311.731317)
			(xy 188.225343 -311.747205) (xy 188.271155 -311.770548) (xy 188.312751 -311.800769) (xy 188.349107 -311.837125)
			(xy 188.379328 -311.878721) (xy 188.402671 -311.924533) (xy 188.418559 -311.973432) (xy 188.426602 -312.024214)
			(xy 188.427106 -312.049922) (xy 188.426602 -312.07563) (xy 189.673226 -312.07563) (xy 189.673226 -312.024214)
			(xy 189.681269 -311.973432) (xy 189.697157 -311.924533) (xy 189.7205 -311.878721) (xy 189.750721 -311.837125)
			(xy 189.787077 -311.800769) (xy 189.828673 -311.770548) (xy 189.874485 -311.747205) (xy 189.923384 -311.731317)
			(xy 189.974166 -311.723274) (xy 190.025582 -311.723274) (xy 190.076364 -311.731317) (xy 190.125263 -311.747205)
			(xy 190.171075 -311.770548) (xy 190.212671 -311.800769) (xy 190.249027 -311.837125) (xy 190.279248 -311.878721)
			(xy 190.302591 -311.924533) (xy 190.318479 -311.973432) (xy 190.326522 -312.024214) (xy 190.327026 -312.049922)
			(xy 190.326522 -312.07563) (xy 191.5734 -312.07563) (xy 191.5734 -312.024214) (xy 191.581443 -311.973432)
			(xy 191.597331 -311.924533) (xy 191.620674 -311.878721) (xy 191.650895 -311.837125) (xy 191.687251 -311.800769)
			(xy 191.728847 -311.770548) (xy 191.774659 -311.747205) (xy 191.823558 -311.731317) (xy 191.87434 -311.723274)
			(xy 191.925756 -311.723274) (xy 191.976538 -311.731317) (xy 192.025437 -311.747205) (xy 192.071249 -311.770548)
			(xy 192.112845 -311.800769) (xy 192.149201 -311.837125) (xy 192.179422 -311.878721) (xy 192.202765 -311.924533)
			(xy 192.218653 -311.973432) (xy 192.226696 -312.024214) (xy 192.2272 -312.049922) (xy 192.226696 -312.07563)
			(xy 193.47332 -312.07563) (xy 193.47332 -312.024214) (xy 193.481363 -311.973432) (xy 193.497251 -311.924533)
			(xy 193.520594 -311.878721) (xy 193.550815 -311.837125) (xy 193.587171 -311.800769) (xy 193.628767 -311.770548)
			(xy 193.674579 -311.747205) (xy 193.723478 -311.731317) (xy 193.77426 -311.723274) (xy 193.825676 -311.723274)
			(xy 193.876458 -311.731317) (xy 193.925357 -311.747205) (xy 193.971169 -311.770548) (xy 194.012765 -311.800769)
			(xy 194.049121 -311.837125) (xy 194.079342 -311.878721) (xy 194.102685 -311.924533) (xy 194.118573 -311.973432)
			(xy 194.126616 -312.024214) (xy 194.12712 -312.049922) (xy 194.126616 -312.07563) (xy 195.37324 -312.07563)
			(xy 195.37324 -312.024214) (xy 195.381283 -311.973432) (xy 195.397171 -311.924533) (xy 195.420514 -311.878721)
			(xy 195.450735 -311.837125) (xy 195.487091 -311.800769) (xy 195.528687 -311.770548) (xy 195.574499 -311.747205)
			(xy 195.623398 -311.731317) (xy 195.67418 -311.723274) (xy 195.725596 -311.723274) (xy 195.776378 -311.731317)
			(xy 195.825277 -311.747205) (xy 195.871089 -311.770548) (xy 195.912685 -311.800769) (xy 195.949041 -311.837125)
			(xy 195.979262 -311.878721) (xy 196.002605 -311.924533) (xy 196.018493 -311.973432) (xy 196.026536 -312.024214)
			(xy 196.02704 -312.049922) (xy 196.026536 -312.07563) (xy 197.273414 -312.07563) (xy 197.273414 -312.024214)
			(xy 197.281457 -311.973432) (xy 197.297345 -311.924533) (xy 197.320688 -311.878721) (xy 197.350909 -311.837125)
			(xy 197.387265 -311.800769) (xy 197.428861 -311.770548) (xy 197.474673 -311.747205) (xy 197.523572 -311.731317)
			(xy 197.574354 -311.723274) (xy 197.62577 -311.723274) (xy 197.676552 -311.731317) (xy 197.725451 -311.747205)
			(xy 197.771263 -311.770548) (xy 197.812859 -311.800769) (xy 197.849215 -311.837125) (xy 197.879436 -311.878721)
			(xy 197.902779 -311.924533) (xy 197.918667 -311.973432) (xy 197.92671 -312.024214) (xy 197.927214 -312.049922)
			(xy 197.92671 -312.07563) (xy 198.223374 -312.07563) (xy 198.223374 -312.024214) (xy 198.231417 -311.973432)
			(xy 198.247305 -311.924533) (xy 198.270648 -311.878721) (xy 198.300869 -311.837125) (xy 198.337225 -311.800769)
			(xy 198.378821 -311.770548) (xy 198.424633 -311.747205) (xy 198.473532 -311.731317) (xy 198.524314 -311.723274)
			(xy 198.57573 -311.723274) (xy 198.626512 -311.731317) (xy 198.675411 -311.747205) (xy 198.721223 -311.770548)
			(xy 198.762819 -311.800769) (xy 198.799175 -311.837125) (xy 198.829396 -311.878721) (xy 198.852739 -311.924533)
			(xy 198.868627 -311.973432) (xy 198.87667 -312.024214) (xy 198.877174 -312.049922) (xy 198.87667 -312.07563)
			(xy 198.868627 -312.126412) (xy 198.852739 -312.175311) (xy 198.829396 -312.221123) (xy 198.799175 -312.262719)
			(xy 198.762819 -312.299075) (xy 198.721223 -312.329296) (xy 198.675411 -312.352639) (xy 198.626512 -312.368527)
			(xy 198.57573 -312.37657) (xy 198.524314 -312.37657) (xy 198.473532 -312.368527) (xy 198.424633 -312.352639)
			(xy 198.378821 -312.329296) (xy 198.337225 -312.299075) (xy 198.300869 -312.262719) (xy 198.270648 -312.221123)
			(xy 198.247305 -312.175311) (xy 198.231417 -312.126412) (xy 198.223374 -312.07563) (xy 197.92671 -312.07563)
			(xy 197.918667 -312.126412) (xy 197.902779 -312.175311) (xy 197.879436 -312.221123) (xy 197.849215 -312.262719)
			(xy 197.812859 -312.299075) (xy 197.771263 -312.329296) (xy 197.725451 -312.352639) (xy 197.676552 -312.368527)
			(xy 197.62577 -312.37657) (xy 197.574354 -312.37657) (xy 197.523572 -312.368527) (xy 197.474673 -312.352639)
			(xy 197.428861 -312.329296) (xy 197.387265 -312.299075) (xy 197.350909 -312.262719) (xy 197.320688 -312.221123)
			(xy 197.297345 -312.175311) (xy 197.281457 -312.126412) (xy 197.273414 -312.07563) (xy 196.026536 -312.07563)
			(xy 196.018493 -312.126412) (xy 196.002605 -312.175311) (xy 195.979262 -312.221123) (xy 195.949041 -312.262719)
			(xy 195.912685 -312.299075) (xy 195.871089 -312.329296) (xy 195.825277 -312.352639) (xy 195.776378 -312.368527)
			(xy 195.725596 -312.37657) (xy 195.67418 -312.37657) (xy 195.623398 -312.368527) (xy 195.574499 -312.352639)
			(xy 195.528687 -312.329296) (xy 195.487091 -312.299075) (xy 195.450735 -312.262719) (xy 195.420514 -312.221123)
			(xy 195.397171 -312.175311) (xy 195.381283 -312.126412) (xy 195.37324 -312.07563) (xy 194.126616 -312.07563)
			(xy 194.118573 -312.126412) (xy 194.102685 -312.175311) (xy 194.079342 -312.221123) (xy 194.049121 -312.262719)
			(xy 194.012765 -312.299075) (xy 193.971169 -312.329296) (xy 193.925357 -312.352639) (xy 193.876458 -312.368527)
			(xy 193.825676 -312.37657) (xy 193.77426 -312.37657) (xy 193.723478 -312.368527) (xy 193.674579 -312.352639)
			(xy 193.628767 -312.329296) (xy 193.587171 -312.299075) (xy 193.550815 -312.262719) (xy 193.520594 -312.221123)
			(xy 193.497251 -312.175311) (xy 193.481363 -312.126412) (xy 193.47332 -312.07563) (xy 192.226696 -312.07563)
			(xy 192.218653 -312.126412) (xy 192.202765 -312.175311) (xy 192.179422 -312.221123) (xy 192.149201 -312.262719)
			(xy 192.112845 -312.299075) (xy 192.071249 -312.329296) (xy 192.025437 -312.352639) (xy 191.976538 -312.368527)
			(xy 191.925756 -312.37657) (xy 191.87434 -312.37657) (xy 191.823558 -312.368527) (xy 191.774659 -312.352639)
			(xy 191.728847 -312.329296) (xy 191.687251 -312.299075) (xy 191.650895 -312.262719) (xy 191.620674 -312.221123)
			(xy 191.597331 -312.175311) (xy 191.581443 -312.126412) (xy 191.5734 -312.07563) (xy 190.326522 -312.07563)
			(xy 190.318479 -312.126412) (xy 190.302591 -312.175311) (xy 190.279248 -312.221123) (xy 190.249027 -312.262719)
			(xy 190.212671 -312.299075) (xy 190.171075 -312.329296) (xy 190.125263 -312.352639) (xy 190.076364 -312.368527)
			(xy 190.025582 -312.37657) (xy 189.974166 -312.37657) (xy 189.923384 -312.368527) (xy 189.874485 -312.352639)
			(xy 189.828673 -312.329296) (xy 189.787077 -312.299075) (xy 189.750721 -312.262719) (xy 189.7205 -312.221123)
			(xy 189.697157 -312.175311) (xy 189.681269 -312.126412) (xy 189.673226 -312.07563) (xy 188.426602 -312.07563)
			(xy 188.418559 -312.126412) (xy 188.402671 -312.175311) (xy 188.379328 -312.221123) (xy 188.349107 -312.262719)
			(xy 188.312751 -312.299075) (xy 188.271155 -312.329296) (xy 188.225343 -312.352639) (xy 188.176444 -312.368527)
			(xy 188.125662 -312.37657) (xy 188.074246 -312.37657) (xy 188.023464 -312.368527) (xy 187.974565 -312.352639)
			(xy 187.928753 -312.329296) (xy 187.887157 -312.299075) (xy 187.850801 -312.262719) (xy 187.82058 -312.221123)
			(xy 187.797237 -312.175311) (xy 187.781349 -312.126412) (xy 187.773306 -312.07563) (xy 186.526365 -312.07563)
			(xy 186.518337 -312.126321) (xy 186.502464 -312.175176) (xy 186.479145 -312.220946) (xy 186.448953 -312.262506)
			(xy 186.412632 -312.298831) (xy 186.371075 -312.329027) (xy 186.325307 -312.352351) (xy 186.276454 -312.368229)
			(xy 186.225718 -312.37627) (xy 186.200034 -312.37682) (xy 186.16549 -312.375042) (xy 186.165236 -312.375042)
			(xy 186.15389 -312.374525) (xy 186.13254 -312.382185) (xy 186.124088 -312.389774) (xy 186.059826 -312.45429)
			(xy 186.05246 -312.476134) (xy 186.05373 -312.487564) (xy 186.056098 -312.512483) (xy 186.05419 -312.562501)
			(xy 186.044766 -312.61166) (xy 186.028043 -312.658837) (xy 186.004402 -312.702956) (xy 185.974383 -312.74301)
			(xy 185.938671 -312.778082) (xy 185.898082 -312.807373) (xy 185.853543 -312.830213) (xy 185.829956 -312.838592)
			(xy 185.829702 -312.838592) (xy 185.822195 -312.841397) (xy 185.809357 -312.850973) (xy 185.804556 -312.857388)
			(xy 185.800238 -312.863738) (xy 185.795412 -312.87847) (xy 185.795412 -313.02559) (xy 186.823346 -313.02559)
			(xy 186.823346 -312.974174) (xy 186.831389 -312.923392) (xy 186.847277 -312.874493) (xy 186.87062 -312.828681)
			(xy 186.900841 -312.787085) (xy 186.937197 -312.750729) (xy 186.978793 -312.720508) (xy 187.024605 -312.697165)
			(xy 187.073504 -312.681277) (xy 187.124286 -312.673234) (xy 187.175702 -312.673234) (xy 187.226484 -312.681277)
			(xy 187.275383 -312.697165) (xy 187.321195 -312.720508) (xy 187.362791 -312.750729) (xy 187.399147 -312.787085)
			(xy 187.429368 -312.828681) (xy 187.452711 -312.874493) (xy 187.468599 -312.923392) (xy 187.476642 -312.974174)
			(xy 187.477146 -312.999882) (xy 187.476642 -313.02559) (xy 188.723266 -313.02559) (xy 188.723266 -312.974174)
			(xy 188.731309 -312.923392) (xy 188.747197 -312.874493) (xy 188.77054 -312.828681) (xy 188.800761 -312.787085)
			(xy 188.837117 -312.750729) (xy 188.878713 -312.720508) (xy 188.924525 -312.697165) (xy 188.973424 -312.681277)
			(xy 189.024206 -312.673234) (xy 189.075622 -312.673234) (xy 189.126404 -312.681277) (xy 189.175303 -312.697165)
			(xy 189.221115 -312.720508) (xy 189.262711 -312.750729) (xy 189.299067 -312.787085) (xy 189.329288 -312.828681)
			(xy 189.352631 -312.874493) (xy 189.368519 -312.923392) (xy 189.376562 -312.974174) (xy 189.377066 -312.999882)
			(xy 189.376562 -313.02559) (xy 190.62344 -313.02559) (xy 190.62344 -312.974174) (xy 190.631483 -312.923392)
			(xy 190.647371 -312.874493) (xy 190.670714 -312.828681) (xy 190.700935 -312.787085) (xy 190.737291 -312.750729)
			(xy 190.778887 -312.720508) (xy 190.824699 -312.697165) (xy 190.873598 -312.681277) (xy 190.92438 -312.673234)
			(xy 190.975796 -312.673234) (xy 191.026578 -312.681277) (xy 191.075477 -312.697165) (xy 191.121289 -312.720508)
			(xy 191.162885 -312.750729) (xy 191.199241 -312.787085) (xy 191.229462 -312.828681) (xy 191.252805 -312.874493)
			(xy 191.268693 -312.923392) (xy 191.276736 -312.974174) (xy 191.27724 -312.999882) (xy 191.276736 -313.02559)
			(xy 192.52336 -313.02559) (xy 192.52336 -312.974174) (xy 192.531403 -312.923392) (xy 192.547291 -312.874493)
			(xy 192.570634 -312.828681) (xy 192.600855 -312.787085) (xy 192.637211 -312.750729) (xy 192.678807 -312.720508)
			(xy 192.724619 -312.697165) (xy 192.773518 -312.681277) (xy 192.8243 -312.673234) (xy 192.875716 -312.673234)
			(xy 192.926498 -312.681277) (xy 192.975397 -312.697165) (xy 193.021209 -312.720508) (xy 193.062805 -312.750729)
			(xy 193.099161 -312.787085) (xy 193.129382 -312.828681) (xy 193.152725 -312.874493) (xy 193.168613 -312.923392)
			(xy 193.176656 -312.974174) (xy 193.17716 -312.999882) (xy 193.176656 -313.02559) (xy 194.42328 -313.02559)
			(xy 194.42328 -312.974174) (xy 194.431323 -312.923392) (xy 194.447211 -312.874493) (xy 194.470554 -312.828681)
			(xy 194.500775 -312.787085) (xy 194.537131 -312.750729) (xy 194.578727 -312.720508) (xy 194.624539 -312.697165)
			(xy 194.673438 -312.681277) (xy 194.72422 -312.673234) (xy 194.775636 -312.673234) (xy 194.826418 -312.681277)
			(xy 194.875317 -312.697165) (xy 194.921129 -312.720508) (xy 194.962725 -312.750729) (xy 194.999081 -312.787085)
			(xy 195.029302 -312.828681) (xy 195.052645 -312.874493) (xy 195.068533 -312.923392) (xy 195.076576 -312.974174)
			(xy 195.07708 -312.999882) (xy 195.076576 -313.02559) (xy 196.3232 -313.02559) (xy 196.3232 -312.974174)
			(xy 196.331243 -312.923392) (xy 196.347131 -312.874493) (xy 196.370474 -312.828681) (xy 196.400695 -312.787085)
			(xy 196.437051 -312.750729) (xy 196.478647 -312.720508) (xy 196.524459 -312.697165) (xy 196.573358 -312.681277)
			(xy 196.62414 -312.673234) (xy 196.675556 -312.673234) (xy 196.726338 -312.681277) (xy 196.775237 -312.697165)
			(xy 196.821049 -312.720508) (xy 196.862645 -312.750729) (xy 196.899001 -312.787085) (xy 196.929222 -312.828681)
			(xy 196.952565 -312.874493) (xy 196.968453 -312.923392) (xy 196.976496 -312.974174) (xy 196.977 -312.999882)
			(xy 196.976496 -313.02559) (xy 196.968453 -313.076372) (xy 196.952565 -313.125271) (xy 196.929222 -313.171083)
			(xy 196.899001 -313.212679) (xy 196.862645 -313.249035) (xy 196.821049 -313.279256) (xy 196.775237 -313.302599)
			(xy 196.726338 -313.318487) (xy 196.675556 -313.32653) (xy 196.62414 -313.32653) (xy 196.573358 -313.318487)
			(xy 196.524459 -313.302599) (xy 196.478647 -313.279256) (xy 196.437051 -313.249035) (xy 196.400695 -313.212679)
			(xy 196.370474 -313.171083) (xy 196.347131 -313.125271) (xy 196.331243 -313.076372) (xy 196.3232 -313.02559)
			(xy 195.076576 -313.02559) (xy 195.068533 -313.076372) (xy 195.052645 -313.125271) (xy 195.029302 -313.171083)
			(xy 194.999081 -313.212679) (xy 194.962725 -313.249035) (xy 194.921129 -313.279256) (xy 194.875317 -313.302599)
			(xy 194.826418 -313.318487) (xy 194.775636 -313.32653) (xy 194.72422 -313.32653) (xy 194.673438 -313.318487)
			(xy 194.624539 -313.302599) (xy 194.578727 -313.279256) (xy 194.537131 -313.249035) (xy 194.500775 -313.212679)
			(xy 194.470554 -313.171083) (xy 194.447211 -313.125271) (xy 194.431323 -313.076372) (xy 194.42328 -313.02559)
			(xy 193.176656 -313.02559) (xy 193.168613 -313.076372) (xy 193.152725 -313.125271) (xy 193.129382 -313.171083)
			(xy 193.099161 -313.212679) (xy 193.062805 -313.249035) (xy 193.021209 -313.279256) (xy 192.975397 -313.302599)
			(xy 192.926498 -313.318487) (xy 192.875716 -313.32653) (xy 192.8243 -313.32653) (xy 192.773518 -313.318487)
			(xy 192.724619 -313.302599) (xy 192.678807 -313.279256) (xy 192.637211 -313.249035) (xy 192.600855 -313.212679)
			(xy 192.570634 -313.171083) (xy 192.547291 -313.125271) (xy 192.531403 -313.076372) (xy 192.52336 -313.02559)
			(xy 191.276736 -313.02559) (xy 191.268693 -313.076372) (xy 191.252805 -313.125271) (xy 191.229462 -313.171083)
			(xy 191.199241 -313.212679) (xy 191.162885 -313.249035) (xy 191.121289 -313.279256) (xy 191.075477 -313.302599)
			(xy 191.026578 -313.318487) (xy 190.975796 -313.32653) (xy 190.92438 -313.32653) (xy 190.873598 -313.318487)
			(xy 190.824699 -313.302599) (xy 190.778887 -313.279256) (xy 190.737291 -313.249035) (xy 190.700935 -313.212679)
			(xy 190.670714 -313.171083) (xy 190.647371 -313.125271) (xy 190.631483 -313.076372) (xy 190.62344 -313.02559)
			(xy 189.376562 -313.02559) (xy 189.368519 -313.076372) (xy 189.352631 -313.125271) (xy 189.329288 -313.171083)
			(xy 189.299067 -313.212679) (xy 189.262711 -313.249035) (xy 189.221115 -313.279256) (xy 189.175303 -313.302599)
			(xy 189.126404 -313.318487) (xy 189.075622 -313.32653) (xy 189.024206 -313.32653) (xy 188.973424 -313.318487)
			(xy 188.924525 -313.302599) (xy 188.878713 -313.279256) (xy 188.837117 -313.249035) (xy 188.800761 -313.212679)
			(xy 188.77054 -313.171083) (xy 188.747197 -313.125271) (xy 188.731309 -313.076372) (xy 188.723266 -313.02559)
			(xy 187.476642 -313.02559) (xy 187.468599 -313.076372) (xy 187.452711 -313.125271) (xy 187.429368 -313.171083)
			(xy 187.399147 -313.212679) (xy 187.362791 -313.249035) (xy 187.321195 -313.279256) (xy 187.275383 -313.302599)
			(xy 187.226484 -313.318487) (xy 187.175702 -313.32653) (xy 187.124286 -313.32653) (xy 187.073504 -313.318487)
			(xy 187.024605 -313.302599) (xy 186.978793 -313.279256) (xy 186.937197 -313.249035) (xy 186.900841 -313.212679)
			(xy 186.87062 -313.171083) (xy 186.847277 -313.125271) (xy 186.831389 -313.076372) (xy 186.823346 -313.02559)
			(xy 185.795412 -313.02559) (xy 185.795412 -313.112404) (xy 185.795666 -313.116468) (xy 185.79732 -313.129056)
			(xy 185.811069 -313.150361) (xy 185.821828 -313.157108) (xy 185.822082 -313.157108) (xy 185.825638 -313.159394)
			(xy 185.831734 -313.16168) (xy 185.832496 -313.161934) (xy 185.856618 -313.170707) (xy 185.902024 -313.194639)
			(xy 185.943186 -313.225302) (xy 185.979114 -313.261957) (xy 186.008945 -313.303725) (xy 186.031963 -313.349601)
			(xy 186.047613 -313.398484) (xy 186.055521 -313.449198) (xy 186.056016 -313.474862) (xy 186.056016 -313.97555)
			(xy 186.823346 -313.97555) (xy 186.823346 -313.924134) (xy 186.831389 -313.873352) (xy 186.847277 -313.824453)
			(xy 186.87062 -313.778641) (xy 186.900841 -313.737045) (xy 186.937197 -313.700689) (xy 186.978793 -313.670468)
			(xy 187.024605 -313.647125) (xy 187.073504 -313.631237) (xy 187.124286 -313.623194) (xy 187.175702 -313.623194)
			(xy 187.226484 -313.631237) (xy 187.275383 -313.647125) (xy 187.321195 -313.670468) (xy 187.362791 -313.700689)
			(xy 187.399147 -313.737045) (xy 187.429368 -313.778641) (xy 187.452711 -313.824453) (xy 187.468599 -313.873352)
			(xy 187.476642 -313.924134) (xy 187.477146 -313.949842) (xy 187.476642 -313.97555) (xy 188.723266 -313.97555)
			(xy 188.723266 -313.924134) (xy 188.731309 -313.873352) (xy 188.747197 -313.824453) (xy 188.77054 -313.778641)
			(xy 188.800761 -313.737045) (xy 188.837117 -313.700689) (xy 188.878713 -313.670468) (xy 188.924525 -313.647125)
			(xy 188.973424 -313.631237) (xy 189.024206 -313.623194) (xy 189.075622 -313.623194) (xy 189.126404 -313.631237)
			(xy 189.175303 -313.647125) (xy 189.221115 -313.670468) (xy 189.262711 -313.700689) (xy 189.299067 -313.737045)
			(xy 189.329288 -313.778641) (xy 189.352631 -313.824453) (xy 189.368519 -313.873352) (xy 189.376562 -313.924134)
			(xy 189.377066 -313.949842) (xy 189.376562 -313.97555) (xy 190.62344 -313.97555) (xy 190.62344 -313.924134)
			(xy 190.631483 -313.873352) (xy 190.647371 -313.824453) (xy 190.670714 -313.778641) (xy 190.700935 -313.737045)
			(xy 190.737291 -313.700689) (xy 190.778887 -313.670468) (xy 190.824699 -313.647125) (xy 190.873598 -313.631237)
			(xy 190.92438 -313.623194) (xy 190.975796 -313.623194) (xy 191.026578 -313.631237) (xy 191.075477 -313.647125)
			(xy 191.121289 -313.670468) (xy 191.162885 -313.700689) (xy 191.199241 -313.737045) (xy 191.229462 -313.778641)
			(xy 191.252805 -313.824453) (xy 191.268693 -313.873352) (xy 191.276736 -313.924134) (xy 191.27724 -313.949842)
			(xy 191.276736 -313.97555) (xy 192.52336 -313.97555) (xy 192.52336 -313.924134) (xy 192.531403 -313.873352)
			(xy 192.547291 -313.824453) (xy 192.570634 -313.778641) (xy 192.600855 -313.737045) (xy 192.637211 -313.700689)
			(xy 192.678807 -313.670468) (xy 192.724619 -313.647125) (xy 192.773518 -313.631237) (xy 192.8243 -313.623194)
			(xy 192.875716 -313.623194) (xy 192.926498 -313.631237) (xy 192.975397 -313.647125) (xy 193.021209 -313.670468)
			(xy 193.062805 -313.700689) (xy 193.099161 -313.737045) (xy 193.129382 -313.778641) (xy 193.152725 -313.824453)
			(xy 193.168613 -313.873352) (xy 193.176656 -313.924134) (xy 193.17716 -313.949842) (xy 193.176656 -313.97555)
			(xy 194.42328 -313.97555) (xy 194.42328 -313.924134) (xy 194.431323 -313.873352) (xy 194.447211 -313.824453)
			(xy 194.470554 -313.778641) (xy 194.500775 -313.737045) (xy 194.537131 -313.700689) (xy 194.578727 -313.670468)
			(xy 194.624539 -313.647125) (xy 194.673438 -313.631237) (xy 194.72422 -313.623194) (xy 194.775636 -313.623194)
			(xy 194.826418 -313.631237) (xy 194.875317 -313.647125) (xy 194.921129 -313.670468) (xy 194.962725 -313.700689)
			(xy 194.999081 -313.737045) (xy 195.029302 -313.778641) (xy 195.052645 -313.824453) (xy 195.068533 -313.873352)
			(xy 195.076576 -313.924134) (xy 195.07708 -313.949842) (xy 195.076576 -313.97555) (xy 196.3232 -313.97555)
			(xy 196.3232 -313.924134) (xy 196.331243 -313.873352) (xy 196.347131 -313.824453) (xy 196.370474 -313.778641)
			(xy 196.400695 -313.737045) (xy 196.437051 -313.700689) (xy 196.478647 -313.670468) (xy 196.524459 -313.647125)
			(xy 196.573358 -313.631237) (xy 196.62414 -313.623194) (xy 196.675556 -313.623194) (xy 196.726338 -313.631237)
			(xy 196.775237 -313.647125) (xy 196.821049 -313.670468) (xy 196.862645 -313.700689) (xy 196.899001 -313.737045)
			(xy 196.929222 -313.778641) (xy 196.952565 -313.824453) (xy 196.968453 -313.873352) (xy 196.976496 -313.924134)
			(xy 196.977 -313.949842) (xy 196.976496 -313.97555) (xy 196.968453 -314.026332) (xy 196.952565 -314.075231)
			(xy 196.929222 -314.121043) (xy 196.899001 -314.162639) (xy 196.862645 -314.198995) (xy 196.821049 -314.229216)
			(xy 196.775237 -314.252559) (xy 196.726338 -314.268447) (xy 196.675556 -314.27649) (xy 196.62414 -314.27649)
			(xy 196.573358 -314.268447) (xy 196.524459 -314.252559) (xy 196.478647 -314.229216) (xy 196.437051 -314.198995)
			(xy 196.400695 -314.162639) (xy 196.370474 -314.121043) (xy 196.347131 -314.075231) (xy 196.331243 -314.026332)
			(xy 196.3232 -313.97555) (xy 195.076576 -313.97555) (xy 195.068533 -314.026332) (xy 195.052645 -314.075231)
			(xy 195.029302 -314.121043) (xy 194.999081 -314.162639) (xy 194.962725 -314.198995) (xy 194.921129 -314.229216)
			(xy 194.875317 -314.252559) (xy 194.826418 -314.268447) (xy 194.775636 -314.27649) (xy 194.72422 -314.27649)
			(xy 194.673438 -314.268447) (xy 194.624539 -314.252559) (xy 194.578727 -314.229216) (xy 194.537131 -314.198995)
			(xy 194.500775 -314.162639) (xy 194.470554 -314.121043) (xy 194.447211 -314.075231) (xy 194.431323 -314.026332)
			(xy 194.42328 -313.97555) (xy 193.176656 -313.97555) (xy 193.168613 -314.026332) (xy 193.152725 -314.075231)
			(xy 193.129382 -314.121043) (xy 193.099161 -314.162639) (xy 193.062805 -314.198995) (xy 193.021209 -314.229216)
			(xy 192.975397 -314.252559) (xy 192.926498 -314.268447) (xy 192.875716 -314.27649) (xy 192.8243 -314.27649)
			(xy 192.773518 -314.268447) (xy 192.724619 -314.252559) (xy 192.678807 -314.229216) (xy 192.637211 -314.198995)
			(xy 192.600855 -314.162639) (xy 192.570634 -314.121043) (xy 192.547291 -314.075231) (xy 192.531403 -314.026332)
			(xy 192.52336 -313.97555) (xy 191.276736 -313.97555) (xy 191.268693 -314.026332) (xy 191.252805 -314.075231)
			(xy 191.229462 -314.121043) (xy 191.199241 -314.162639) (xy 191.162885 -314.198995) (xy 191.121289 -314.229216)
			(xy 191.075477 -314.252559) (xy 191.026578 -314.268447) (xy 190.975796 -314.27649) (xy 190.92438 -314.27649)
			(xy 190.873598 -314.268447) (xy 190.824699 -314.252559) (xy 190.778887 -314.229216) (xy 190.737291 -314.198995)
			(xy 190.700935 -314.162639) (xy 190.670714 -314.121043) (xy 190.647371 -314.075231) (xy 190.631483 -314.026332)
			(xy 190.62344 -313.97555) (xy 189.376562 -313.97555) (xy 189.368519 -314.026332) (xy 189.352631 -314.075231)
			(xy 189.329288 -314.121043) (xy 189.299067 -314.162639) (xy 189.262711 -314.198995) (xy 189.221115 -314.229216)
			(xy 189.175303 -314.252559) (xy 189.126404 -314.268447) (xy 189.075622 -314.27649) (xy 189.024206 -314.27649)
			(xy 188.973424 -314.268447) (xy 188.924525 -314.252559) (xy 188.878713 -314.229216) (xy 188.837117 -314.198995)
			(xy 188.800761 -314.162639) (xy 188.77054 -314.121043) (xy 188.747197 -314.075231) (xy 188.731309 -314.026332)
			(xy 188.723266 -313.97555) (xy 187.476642 -313.97555) (xy 187.468599 -314.026332) (xy 187.452711 -314.075231)
			(xy 187.429368 -314.121043) (xy 187.399147 -314.162639) (xy 187.362791 -314.198995) (xy 187.321195 -314.229216)
			(xy 187.275383 -314.252559) (xy 187.226484 -314.268447) (xy 187.175702 -314.27649) (xy 187.124286 -314.27649)
			(xy 187.073504 -314.268447) (xy 187.024605 -314.252559) (xy 186.978793 -314.229216) (xy 186.937197 -314.198995)
			(xy 186.900841 -314.162639) (xy 186.87062 -314.121043) (xy 186.847277 -314.075231) (xy 186.831389 -314.026332)
			(xy 186.823346 -313.97555) (xy 186.056016 -313.97555) (xy 186.056016 -314.424822) (xy 186.055518 -314.450659)
			(xy 186.047487 -314.501706) (xy 186.031624 -314.550885) (xy 186.008313 -314.597003) (xy 185.978121 -314.63894)
			(xy 185.941781 -314.675678) (xy 185.900175 -314.706324) (xy 185.854313 -314.730135) (xy 185.829956 -314.738766)
			(xy 185.829702 -314.738766) (xy 185.822194 -314.74157) (xy 185.809352 -314.751143) (xy 185.804556 -314.757562)
			(xy 185.800238 -314.763912) (xy 185.795412 -314.778644) (xy 185.795412 -314.845446) (xy 185.799476 -314.848494)
			(xy 185.807806 -314.854047) (xy 185.82721 -314.858888) (xy 185.846992 -314.85595) (xy 185.864151 -314.845677)
			(xy 185.876084 -314.829628) (xy 185.878978 -314.820046) (xy 185.885306 -314.79648) (xy 185.90394 -314.751385)
			(xy 185.928991 -314.709514) (xy 185.959916 -314.671772) (xy 185.996046 -314.638978) (xy 186.036597 -314.611843)
			(xy 186.080693 -314.590953) (xy 186.127376 -314.576762) (xy 186.175638 -314.569576) (xy 186.200034 -314.569094)
			(xy 186.226019 -314.569606) (xy 186.27735 -314.577741) (xy 186.326776 -314.593805) (xy 186.37308 -314.617403)
			(xy 186.415123 -314.647953) (xy 186.45187 -314.684704) (xy 186.482416 -314.726751) (xy 186.506009 -314.773058)
			(xy 186.522068 -314.822485) (xy 186.530197 -314.873817) (xy 186.530742 -314.899802) (xy 186.530742 -314.900818)
			(xy 186.531165 -314.910901) (xy 186.538932 -314.929509) (xy 186.55329 -314.943666) (xy 186.562492 -314.947808)
			(xy 186.612441 -314.968694) (xy 186.707787 -315.019995) (xy 186.752738 -315.05017) (xy 186.756163 -315.052392)
			(xy 186.763566 -315.055834) (xy 186.76747 -315.057028) (xy 186.793928 -315.065313) (xy 186.843834 -315.089456)
			(xy 186.889019 -315.121577) (xy 186.92822 -315.160777) (xy 186.960342 -315.205962) (xy 186.984485 -315.255867)
			(xy 186.992768 -315.282326) (xy 186.99395 -315.286234) (xy 186.997402 -315.293634) (xy 186.999626 -315.297058)
			(xy 187.025686 -315.33578) (xy 187.071099 -315.417331) (xy 187.090304 -315.459872) (xy 187.091066 -315.460126)
			(xy 187.093098 -315.461142) (xy 187.1345 -315.482478) (xy 187.143573 -315.486807) (xy 187.16355 -315.488847)
			(xy 187.182792 -315.483103) (xy 187.190888 -315.477144) (xy 187.198508 -315.471048) (xy 187.203135 -315.467171)
			(xy 187.210574 -315.457668) (xy 187.21324 -315.452252) (xy 187.232783 -315.409926) (xy 187.278843 -315.328864)
			(xy 187.332459 -315.25259) (xy 187.393139 -315.181806) (xy 187.460323 -315.117162) (xy 187.533393 -315.059255)
			(xy 187.611676 -315.008617) (xy 187.694452 -314.965714) (xy 187.737496 -314.947808) (xy 187.746666 -314.943621)
			(xy 187.760991 -314.929459) (xy 187.768793 -314.910888) (xy 187.769246 -314.900818) (xy 187.769246 -314.899802)
			(xy 187.769756 -314.873815) (xy 187.777886 -314.82248) (xy 187.793947 -314.77305) (xy 187.817543 -314.72674)
			(xy 187.848093 -314.684692) (xy 187.884844 -314.647941) (xy 187.926892 -314.617391) (xy 187.973202 -314.593795)
			(xy 188.022632 -314.577734) (xy 188.073967 -314.569604) (xy 188.125941 -314.569604) (xy 188.177276 -314.577734)
			(xy 188.226706 -314.593795) (xy 188.273016 -314.617391) (xy 188.315064 -314.647941) (xy 188.351815 -314.684692)
			(xy 188.382365 -314.72674) (xy 188.405961 -314.77305) (xy 188.422022 -314.82248) (xy 188.430152 -314.873815)
			(xy 188.430662 -314.899802) (xy 188.430662 -314.900818) (xy 188.431085 -314.9109) (xy 188.437185 -314.92551)
			(xy 197.273414 -314.92551) (xy 197.273414 -314.874094) (xy 197.281457 -314.823312) (xy 197.297345 -314.774413)
			(xy 197.320688 -314.728601) (xy 197.350909 -314.687005) (xy 197.387265 -314.650649) (xy 197.428861 -314.620428)
			(xy 197.474673 -314.597085) (xy 197.523572 -314.581197) (xy 197.574354 -314.573154) (xy 197.62577 -314.573154)
			(xy 197.676552 -314.581197) (xy 197.725451 -314.597085) (xy 197.771263 -314.620428) (xy 197.812859 -314.650649)
			(xy 197.849215 -314.687005) (xy 197.879436 -314.728601) (xy 197.902779 -314.774413) (xy 197.918667 -314.823312)
			(xy 197.92671 -314.874094) (xy 197.927214 -314.899802) (xy 197.92671 -314.92551) (xy 198.223374 -314.92551)
			(xy 198.223374 -314.874094) (xy 198.231417 -314.823312) (xy 198.247305 -314.774413) (xy 198.270648 -314.728601)
			(xy 198.300869 -314.687005) (xy 198.337225 -314.650649) (xy 198.378821 -314.620428) (xy 198.424633 -314.597085)
			(xy 198.473532 -314.581197) (xy 198.524314 -314.573154) (xy 198.57573 -314.573154) (xy 198.626512 -314.581197)
			(xy 198.675411 -314.597085) (xy 198.721223 -314.620428) (xy 198.762819 -314.650649) (xy 198.799175 -314.687005)
			(xy 198.829396 -314.728601) (xy 198.852739 -314.774413) (xy 198.868627 -314.823312) (xy 198.87667 -314.874094)
			(xy 198.877174 -314.899802) (xy 198.87667 -314.92551) (xy 198.868627 -314.976292) (xy 198.852739 -315.025191)
			(xy 198.829396 -315.071003) (xy 198.799175 -315.112599) (xy 198.762819 -315.148955) (xy 198.721223 -315.179176)
			(xy 198.675411 -315.202519) (xy 198.626512 -315.218407) (xy 198.57573 -315.22645) (xy 198.524314 -315.22645)
			(xy 198.473532 -315.218407) (xy 198.424633 -315.202519) (xy 198.378821 -315.179176) (xy 198.337225 -315.148955)
			(xy 198.300869 -315.112599) (xy 198.270648 -315.071003) (xy 198.247305 -315.025191) (xy 198.231417 -314.976292)
			(xy 198.223374 -314.92551) (xy 197.92671 -314.92551) (xy 197.918667 -314.976292) (xy 197.902779 -315.025191)
			(xy 197.879436 -315.071003) (xy 197.849215 -315.112599) (xy 197.812859 -315.148955) (xy 197.771263 -315.179176)
			(xy 197.725451 -315.202519) (xy 197.676552 -315.218407) (xy 197.62577 -315.22645) (xy 197.574354 -315.22645)
			(xy 197.523572 -315.218407) (xy 197.474673 -315.202519) (xy 197.428861 -315.179176) (xy 197.387265 -315.148955)
			(xy 197.350909 -315.112599) (xy 197.320688 -315.071003) (xy 197.297345 -315.025191) (xy 197.281457 -314.976292)
			(xy 197.273414 -314.92551) (xy 188.437185 -314.92551) (xy 188.438854 -314.929506) (xy 188.453214 -314.943658)
			(xy 188.462412 -314.947808) (xy 188.512361 -314.968695) (xy 188.607705 -315.019997) (xy 188.652658 -315.05017)
			(xy 188.656083 -315.052391) (xy 188.663487 -315.05583) (xy 188.66739 -315.057028) (xy 188.693847 -315.065314)
			(xy 188.74375 -315.089459) (xy 188.788933 -315.121581) (xy 188.828132 -315.160782) (xy 188.860251 -315.205967)
			(xy 188.884393 -315.255871) (xy 188.892688 -315.282326) (xy 188.893868 -315.286235) (xy 188.897315 -315.293638)
			(xy 188.899546 -315.297058) (xy 188.923057 -315.33194) (xy 188.964647 -315.405067) (xy 188.982604 -315.443108)
			(xy 188.986497 -315.450769) (xy 188.998435 -315.463113) (xy 189.005972 -315.467238) (xy 189.028712 -315.478832)
			(xy 189.073059 -315.504118) (xy 189.094618 -315.517784) (xy 189.098728 -315.520351) (xy 189.107677 -315.524058)
			(xy 189.112398 -315.52515) (xy 189.136492 -315.530246) (xy 189.182934 -315.546622) (xy 189.226432 -315.569709)
			(xy 189.266021 -315.598996) (xy 189.300825 -315.633835) (xy 189.330072 -315.673455) (xy 189.353114 -315.716976)
			(xy 189.369442 -315.763436) (xy 189.374526 -315.787532) (xy 189.3756 -315.792258) (xy 189.379308 -315.801212)
			(xy 189.381892 -315.805312) (xy 189.405421 -315.842908) (xy 189.446254 -315.921646) (xy 189.463426 -315.962538)
			(xy 189.463426 -315.962792) (xy 189.466513 -315.969609) (xy 189.475931 -315.98123) (xy 189.481968 -315.985652)
			(xy 189.488064 -315.98997) (xy 189.502542 -315.994288) (xy 189.521846 -315.994288) (xy 189.523878 -315.994034)
			(xy 189.525148 -315.994034) (xy 189.534439 -315.994083) (xy 189.552992 -315.9951) (xy 189.562232 -315.996066)
			(xy 189.573662 -315.997336) (xy 189.595506 -315.98997) (xy 189.660022 -315.925708) (xy 189.667644 -315.917278)
			(xy 189.675296 -315.895911) (xy 189.674754 -315.88456) (xy 189.674754 -315.884306) (xy 189.672976 -315.849762)
			(xy 189.67348 -315.824074) (xy 189.681517 -315.773331) (xy 189.697393 -315.72447) (xy 189.720717 -315.678694)
			(xy 189.750914 -315.63713) (xy 189.787242 -315.600802) (xy 189.828806 -315.570605) (xy 189.874582 -315.547281)
			(xy 189.923443 -315.531405) (xy 189.974186 -315.523368) (xy 190.025562 -315.523368) (xy 190.076305 -315.531405)
			(xy 190.125166 -315.547281) (xy 190.170942 -315.570605) (xy 190.212506 -315.600802) (xy 190.248834 -315.63713)
			(xy 190.279031 -315.678694) (xy 190.302355 -315.72447) (xy 190.318231 -315.773331) (xy 190.326268 -315.824074)
			(xy 190.326772 -315.849762) (xy 190.325458 -315.87547) (xy 191.5734 -315.87547) (xy 191.5734 -315.824054)
			(xy 191.581443 -315.773272) (xy 191.597331 -315.724373) (xy 191.620674 -315.678561) (xy 191.650895 -315.636965)
			(xy 191.687251 -315.600609) (xy 191.728847 -315.570388) (xy 191.774659 -315.547045) (xy 191.823558 -315.531157)
			(xy 191.87434 -315.523114) (xy 191.925756 -315.523114) (xy 191.976538 -315.531157) (xy 192.025437 -315.547045)
			(xy 192.071249 -315.570388) (xy 192.112845 -315.600609) (xy 192.149201 -315.636965) (xy 192.179422 -315.678561)
			(xy 192.202765 -315.724373) (xy 192.218653 -315.773272) (xy 192.226696 -315.824054) (xy 192.2272 -315.849762)
			(xy 192.226696 -315.87547) (xy 193.47332 -315.87547) (xy 193.47332 -315.824054) (xy 193.481363 -315.773272)
			(xy 193.497251 -315.724373) (xy 193.520594 -315.678561) (xy 193.550815 -315.636965) (xy 193.587171 -315.600609)
			(xy 193.628767 -315.570388) (xy 193.674579 -315.547045) (xy 193.723478 -315.531157) (xy 193.77426 -315.523114)
			(xy 193.825676 -315.523114) (xy 193.876458 -315.531157) (xy 193.925357 -315.547045) (xy 193.971169 -315.570388)
			(xy 194.012765 -315.600609) (xy 194.049121 -315.636965) (xy 194.079342 -315.678561) (xy 194.102685 -315.724373)
			(xy 194.118573 -315.773272) (xy 194.126616 -315.824054) (xy 194.12712 -315.849762) (xy 194.126616 -315.87547)
			(xy 195.37324 -315.87547) (xy 195.37324 -315.824054) (xy 195.381283 -315.773272) (xy 195.397171 -315.724373)
			(xy 195.420514 -315.678561) (xy 195.450735 -315.636965) (xy 195.487091 -315.600609) (xy 195.528687 -315.570388)
			(xy 195.574499 -315.547045) (xy 195.623398 -315.531157) (xy 195.67418 -315.523114) (xy 195.725596 -315.523114)
			(xy 195.776378 -315.531157) (xy 195.825277 -315.547045) (xy 195.871089 -315.570388) (xy 195.912685 -315.600609)
			(xy 195.949041 -315.636965) (xy 195.979262 -315.678561) (xy 196.002605 -315.724373) (xy 196.018493 -315.773272)
			(xy 196.026536 -315.824054) (xy 196.02704 -315.849762) (xy 196.026536 -315.87547) (xy 196.018493 -315.926252)
			(xy 196.002605 -315.975151) (xy 195.979262 -316.020963) (xy 195.949041 -316.062559) (xy 195.912685 -316.098915)
			(xy 195.871089 -316.129136) (xy 195.825277 -316.152479) (xy 195.776378 -316.168367) (xy 195.725596 -316.17641)
			(xy 195.67418 -316.17641) (xy 195.623398 -316.168367) (xy 195.574499 -316.152479) (xy 195.528687 -316.129136)
			(xy 195.487091 -316.098915) (xy 195.450735 -316.062559) (xy 195.420514 -316.020963) (xy 195.397171 -315.975151)
			(xy 195.381283 -315.926252) (xy 195.37324 -315.87547) (xy 194.126616 -315.87547) (xy 194.118573 -315.926252)
			(xy 194.102685 -315.975151) (xy 194.079342 -316.020963) (xy 194.049121 -316.062559) (xy 194.012765 -316.098915)
			(xy 193.971169 -316.129136) (xy 193.925357 -316.152479) (xy 193.876458 -316.168367) (xy 193.825676 -316.17641)
			(xy 193.77426 -316.17641) (xy 193.723478 -316.168367) (xy 193.674579 -316.152479) (xy 193.628767 -316.129136)
			(xy 193.587171 -316.098915) (xy 193.550815 -316.062559) (xy 193.520594 -316.020963) (xy 193.497251 -315.975151)
			(xy 193.481363 -315.926252) (xy 193.47332 -315.87547) (xy 192.226696 -315.87547) (xy 192.218653 -315.926252)
			(xy 192.202765 -315.975151) (xy 192.179422 -316.020963) (xy 192.149201 -316.062559) (xy 192.112845 -316.098915)
			(xy 192.071249 -316.129136) (xy 192.025437 -316.152479) (xy 191.976538 -316.168367) (xy 191.925756 -316.17641)
			(xy 191.87434 -316.17641) (xy 191.823558 -316.168367) (xy 191.774659 -316.152479) (xy 191.728847 -316.129136)
			(xy 191.687251 -316.098915) (xy 191.650895 -316.062559) (xy 191.620674 -316.020963) (xy 191.597331 -315.975151)
			(xy 191.581443 -315.926252) (xy 191.5734 -315.87547) (xy 190.325458 -315.87547) (xy 190.324994 -315.88456)
			(xy 190.323724 -315.89599) (xy 190.331598 -315.91758) (xy 190.404242 -315.98997) (xy 190.426086 -315.997336)
			(xy 190.437516 -315.996066) (xy 190.446883 -315.995091) (xy 190.46569 -315.994075) (xy 190.475108 -315.994034)
			(xy 190.501096 -315.994518) (xy 190.552431 -316.00265) (xy 190.601862 -316.018714) (xy 190.648171 -316.042313)
			(xy 190.690218 -316.072866) (xy 190.726967 -316.109621) (xy 190.757514 -316.151672) (xy 190.781105 -316.197985)
			(xy 190.797161 -316.247418) (xy 190.805286 -316.298754) (xy 190.805816 -316.324742) (xy 190.805816 -316.82543)
			(xy 191.5734 -316.82543) (xy 191.5734 -316.774014) (xy 191.581443 -316.723232) (xy 191.597331 -316.674333)
			(xy 191.620674 -316.628521) (xy 191.650895 -316.586925) (xy 191.687251 -316.550569) (xy 191.728847 -316.520348)
			(xy 191.774659 -316.497005) (xy 191.823558 -316.481117) (xy 191.87434 -316.473074) (xy 191.925756 -316.473074)
			(xy 191.976538 -316.481117) (xy 192.025437 -316.497005) (xy 192.071249 -316.520348) (xy 192.112845 -316.550569)
			(xy 192.149201 -316.586925) (xy 192.179422 -316.628521) (xy 192.202765 -316.674333) (xy 192.218653 -316.723232)
			(xy 192.226696 -316.774014) (xy 192.2272 -316.799722) (xy 192.226696 -316.82543) (xy 193.47332 -316.82543)
			(xy 193.47332 -316.774014) (xy 193.481363 -316.723232) (xy 193.497251 -316.674333) (xy 193.520594 -316.628521)
			(xy 193.550815 -316.586925) (xy 193.587171 -316.550569) (xy 193.628767 -316.520348) (xy 193.674579 -316.497005)
			(xy 193.723478 -316.481117) (xy 193.77426 -316.473074) (xy 193.825676 -316.473074) (xy 193.876458 -316.481117)
			(xy 193.925357 -316.497005) (xy 193.971169 -316.520348) (xy 194.012765 -316.550569) (xy 194.049121 -316.586925)
			(xy 194.079342 -316.628521) (xy 194.102685 -316.674333) (xy 194.118573 -316.723232) (xy 194.126616 -316.774014)
			(xy 194.12712 -316.799722) (xy 194.126616 -316.82543) (xy 195.37324 -316.82543) (xy 195.37324 -316.774014)
			(xy 195.381283 -316.723232) (xy 195.397171 -316.674333) (xy 195.420514 -316.628521) (xy 195.450735 -316.586925)
			(xy 195.487091 -316.550569) (xy 195.528687 -316.520348) (xy 195.574499 -316.497005) (xy 195.623398 -316.481117)
			(xy 195.67418 -316.473074) (xy 195.725596 -316.473074) (xy 195.776378 -316.481117) (xy 195.825277 -316.497005)
			(xy 195.871089 -316.520348) (xy 195.912685 -316.550569) (xy 195.949041 -316.586925) (xy 195.979262 -316.628521)
			(xy 196.002605 -316.674333) (xy 196.018493 -316.723232) (xy 196.026536 -316.774014) (xy 196.02704 -316.799722)
			(xy 196.026536 -316.82543) (xy 197.273414 -316.82543) (xy 197.273414 -316.774014) (xy 197.281457 -316.723232)
			(xy 197.297345 -316.674333) (xy 197.320688 -316.628521) (xy 197.350909 -316.586925) (xy 197.387265 -316.550569)
			(xy 197.428861 -316.520348) (xy 197.474673 -316.497005) (xy 197.523572 -316.481117) (xy 197.574354 -316.473074)
			(xy 197.62577 -316.473074) (xy 197.676552 -316.481117) (xy 197.725451 -316.497005) (xy 197.771263 -316.520348)
			(xy 197.812859 -316.550569) (xy 197.849215 -316.586925) (xy 197.879436 -316.628521) (xy 197.902779 -316.674333)
			(xy 197.918667 -316.723232) (xy 197.92671 -316.774014) (xy 197.927214 -316.799722) (xy 197.92671 -316.82543)
			(xy 198.223374 -316.82543) (xy 198.223374 -316.774014) (xy 198.231417 -316.723232) (xy 198.247305 -316.674333)
			(xy 198.270648 -316.628521) (xy 198.300869 -316.586925) (xy 198.337225 -316.550569) (xy 198.378821 -316.520348)
			(xy 198.424633 -316.497005) (xy 198.473532 -316.481117) (xy 198.524314 -316.473074) (xy 198.57573 -316.473074)
			(xy 198.626512 -316.481117) (xy 198.675411 -316.497005) (xy 198.721223 -316.520348) (xy 198.762819 -316.550569)
			(xy 198.799175 -316.586925) (xy 198.829396 -316.628521) (xy 198.852739 -316.674333) (xy 198.868627 -316.723232)
			(xy 198.87667 -316.774014) (xy 198.877174 -316.799722) (xy 198.87667 -316.82543) (xy 198.868627 -316.876212)
			(xy 198.852739 -316.925111) (xy 198.829396 -316.970923) (xy 198.799175 -317.012519) (xy 198.762819 -317.048875)
			(xy 198.721223 -317.079096) (xy 198.675411 -317.102439) (xy 198.626512 -317.118327) (xy 198.57573 -317.12637)
			(xy 198.524314 -317.12637) (xy 198.473532 -317.118327) (xy 198.424633 -317.102439) (xy 198.378821 -317.079096)
			(xy 198.337225 -317.048875) (xy 198.300869 -317.012519) (xy 198.270648 -316.970923) (xy 198.247305 -316.925111)
			(xy 198.231417 -316.876212) (xy 198.223374 -316.82543) (xy 197.92671 -316.82543) (xy 197.918667 -316.876212)
			(xy 197.902779 -316.925111) (xy 197.879436 -316.970923) (xy 197.849215 -317.012519) (xy 197.812859 -317.048875)
			(xy 197.771263 -317.079096) (xy 197.725451 -317.102439) (xy 197.676552 -317.118327) (xy 197.62577 -317.12637)
			(xy 197.574354 -317.12637) (xy 197.523572 -317.118327) (xy 197.474673 -317.102439) (xy 197.428861 -317.079096)
			(xy 197.387265 -317.048875) (xy 197.350909 -317.012519) (xy 197.320688 -316.970923) (xy 197.297345 -316.925111)
			(xy 197.281457 -316.876212) (xy 197.273414 -316.82543) (xy 196.026536 -316.82543) (xy 196.018493 -316.876212)
			(xy 196.002605 -316.925111) (xy 195.979262 -316.970923) (xy 195.949041 -317.012519) (xy 195.912685 -317.048875)
			(xy 195.871089 -317.079096) (xy 195.825277 -317.102439) (xy 195.776378 -317.118327) (xy 195.725596 -317.12637)
			(xy 195.67418 -317.12637) (xy 195.623398 -317.118327) (xy 195.574499 -317.102439) (xy 195.528687 -317.079096)
			(xy 195.487091 -317.048875) (xy 195.450735 -317.012519) (xy 195.420514 -316.970923) (xy 195.397171 -316.925111)
			(xy 195.381283 -316.876212) (xy 195.37324 -316.82543) (xy 194.126616 -316.82543) (xy 194.118573 -316.876212)
			(xy 194.102685 -316.925111) (xy 194.079342 -316.970923) (xy 194.049121 -317.012519) (xy 194.012765 -317.048875)
			(xy 193.971169 -317.079096) (xy 193.925357 -317.102439) (xy 193.876458 -317.118327) (xy 193.825676 -317.12637)
			(xy 193.77426 -317.12637) (xy 193.723478 -317.118327) (xy 193.674579 -317.102439) (xy 193.628767 -317.079096)
			(xy 193.587171 -317.048875) (xy 193.550815 -317.012519) (xy 193.520594 -316.970923) (xy 193.497251 -316.925111)
			(xy 193.481363 -316.876212) (xy 193.47332 -316.82543) (xy 192.226696 -316.82543) (xy 192.218653 -316.876212)
			(xy 192.202765 -316.925111) (xy 192.179422 -316.970923) (xy 192.149201 -317.012519) (xy 192.112845 -317.048875)
			(xy 192.071249 -317.079096) (xy 192.025437 -317.102439) (xy 191.976538 -317.118327) (xy 191.925756 -317.12637)
			(xy 191.87434 -317.12637) (xy 191.823558 -317.118327) (xy 191.774659 -317.102439) (xy 191.728847 -317.079096)
			(xy 191.687251 -317.048875) (xy 191.650895 -317.012519) (xy 191.620674 -316.970923) (xy 191.597331 -316.925111)
			(xy 191.581443 -316.876212) (xy 191.5734 -316.82543) (xy 190.805816 -316.82543) (xy 190.805816 -317.036704)
			(xy 190.80607 -317.036958) (xy 190.80607 -317.274702) (xy 190.806035 -317.28412) (xy 190.805021 -317.302928)
			(xy 190.804038 -317.312294) (xy 190.802768 -317.323724) (xy 190.810134 -317.345568) (xy 190.882524 -317.418212)
			(xy 190.904114 -317.426086) (xy 190.915544 -317.424816) (xy 190.949834 -317.422784) (xy 190.950342 -317.422784)
			(xy 190.976034 -317.423306) (xy 191.026782 -317.431378) (xy 191.075643 -317.447286) (xy 191.121416 -317.470639)
			(xy 191.162975 -317.500861) (xy 191.199297 -317.537209) (xy 191.229488 -317.57879) (xy 191.252807 -317.62458)
			(xy 191.268678 -317.673454) (xy 191.276713 -317.724207) (xy 191.276713 -317.775593) (xy 191.276705 -317.775644)
			(xy 192.52336 -317.775644) (xy 192.52336 -317.724228) (xy 192.531403 -317.673446) (xy 192.547291 -317.624547)
			(xy 192.570634 -317.578735) (xy 192.600855 -317.537139) (xy 192.637211 -317.500783) (xy 192.678807 -317.470562)
			(xy 192.724619 -317.447219) (xy 192.773518 -317.431331) (xy 192.8243 -317.423288) (xy 192.875716 -317.423288)
			(xy 192.926498 -317.431331) (xy 192.975397 -317.447219) (xy 193.021209 -317.470562) (xy 193.062805 -317.500783)
			(xy 193.099161 -317.537139) (xy 193.129382 -317.578735) (xy 193.152725 -317.624547) (xy 193.168613 -317.673446)
			(xy 193.176656 -317.724228) (xy 193.17716 -317.749936) (xy 193.176656 -317.775644) (xy 194.42328 -317.775644)
			(xy 194.42328 -317.724228) (xy 194.431323 -317.673446) (xy 194.447211 -317.624547) (xy 194.470554 -317.578735)
			(xy 194.500775 -317.537139) (xy 194.537131 -317.500783) (xy 194.578727 -317.470562) (xy 194.624539 -317.447219)
			(xy 194.673438 -317.431331) (xy 194.72422 -317.423288) (xy 194.775636 -317.423288) (xy 194.826418 -317.431331)
			(xy 194.875317 -317.447219) (xy 194.921129 -317.470562) (xy 194.962725 -317.500783) (xy 194.999081 -317.537139)
			(xy 195.029302 -317.578735) (xy 195.052645 -317.624547) (xy 195.068533 -317.673446) (xy 195.076576 -317.724228)
			(xy 195.07708 -317.749936) (xy 195.076576 -317.775644) (xy 196.3232 -317.775644) (xy 196.3232 -317.724228)
			(xy 196.331243 -317.673446) (xy 196.347131 -317.624547) (xy 196.370474 -317.578735) (xy 196.400695 -317.537139)
			(xy 196.437051 -317.500783) (xy 196.478647 -317.470562) (xy 196.524459 -317.447219) (xy 196.573358 -317.431331)
			(xy 196.62414 -317.423288) (xy 196.675556 -317.423288) (xy 196.726338 -317.431331) (xy 196.775237 -317.447219)
			(xy 196.821049 -317.470562) (xy 196.862645 -317.500783) (xy 196.899001 -317.537139) (xy 196.929222 -317.578735)
			(xy 196.952565 -317.624547) (xy 196.968453 -317.673446) (xy 196.976496 -317.724228) (xy 196.977 -317.749936)
			(xy 196.976496 -317.775644) (xy 196.968453 -317.826426) (xy 196.952565 -317.875325) (xy 196.929222 -317.921137)
			(xy 196.899001 -317.962733) (xy 196.862645 -317.999089) (xy 196.821049 -318.02931) (xy 196.775237 -318.052653)
			(xy 196.726338 -318.068541) (xy 196.675556 -318.076584) (xy 196.62414 -318.076584) (xy 196.573358 -318.068541)
			(xy 196.524459 -318.052653) (xy 196.478647 -318.02931) (xy 196.437051 -317.999089) (xy 196.400695 -317.962733)
			(xy 196.370474 -317.921137) (xy 196.347131 -317.875325) (xy 196.331243 -317.826426) (xy 196.3232 -317.775644)
			(xy 195.076576 -317.775644) (xy 195.068533 -317.826426) (xy 195.052645 -317.875325) (xy 195.029302 -317.921137)
			(xy 194.999081 -317.962733) (xy 194.962725 -317.999089) (xy 194.921129 -318.02931) (xy 194.875317 -318.052653)
			(xy 194.826418 -318.068541) (xy 194.775636 -318.076584) (xy 194.72422 -318.076584) (xy 194.673438 -318.068541)
			(xy 194.624539 -318.052653) (xy 194.578727 -318.02931) (xy 194.537131 -317.999089) (xy 194.500775 -317.962733)
			(xy 194.470554 -317.921137) (xy 194.447211 -317.875325) (xy 194.431323 -317.826426) (xy 194.42328 -317.775644)
			(xy 193.176656 -317.775644) (xy 193.168613 -317.826426) (xy 193.152725 -317.875325) (xy 193.129382 -317.921137)
			(xy 193.099161 -317.962733) (xy 193.062805 -317.999089) (xy 193.021209 -318.02931) (xy 192.975397 -318.052653)
			(xy 192.926498 -318.068541) (xy 192.875716 -318.076584) (xy 192.8243 -318.076584) (xy 192.773518 -318.068541)
			(xy 192.724619 -318.052653) (xy 192.678807 -318.02931) (xy 192.637211 -317.999089) (xy 192.600855 -317.962733)
			(xy 192.570634 -317.921137) (xy 192.547291 -317.875325) (xy 192.531403 -317.826426) (xy 192.52336 -317.775644)
			(xy 191.276705 -317.775644) (xy 191.268678 -317.826347) (xy 191.252807 -317.87522) (xy 191.229488 -317.92101)
			(xy 191.199297 -317.962591) (xy 191.162975 -317.998939) (xy 191.121416 -318.029161) (xy 191.075643 -318.052514)
			(xy 191.026782 -318.068422) (xy 190.976034 -318.076494) (xy 190.950342 -318.077088) (xy 190.949834 -318.077088)
			(xy 190.915544 -318.075056) (xy 190.915036 -318.075056) (xy 190.903606 -318.073786) (xy 190.882016 -318.08166)
			(xy 190.809626 -318.154304) (xy 190.80226 -318.176148) (xy 190.80353 -318.187578) (xy 190.8045 -318.196882)
			(xy 190.805518 -318.215562) (xy 190.805562 -318.224916) (xy 190.805518 -318.23427) (xy 190.8045 -318.25295)
			(xy 190.80353 -318.262254) (xy 190.80226 -318.273684) (xy 190.809626 -318.295528) (xy 190.873888 -318.360044)
			(xy 190.882314 -318.367676) (xy 190.903683 -318.375343) (xy 190.915036 -318.374776) (xy 190.91529 -318.374776)
			(xy 190.949834 -318.372744) (xy 190.950342 -318.372744) (xy 190.976038 -318.373266) (xy 191.026792 -318.381339)
			(xy 191.075659 -318.397249) (xy 191.121437 -318.420604) (xy 191.163001 -318.45083) (xy 191.199327 -318.487183)
			(xy 191.229522 -318.528769) (xy 191.252843 -318.574565) (xy 191.268717 -318.623444) (xy 191.276753 -318.674204)
			(xy 191.276753 -318.725596) (xy 191.276752 -318.725604) (xy 192.52336 -318.725604) (xy 192.52336 -318.674188)
			(xy 192.531403 -318.623406) (xy 192.547291 -318.574507) (xy 192.570634 -318.528695) (xy 192.600855 -318.487099)
			(xy 192.637211 -318.450743) (xy 192.678807 -318.420522) (xy 192.724619 -318.397179) (xy 192.773518 -318.381291)
			(xy 192.8243 -318.373248) (xy 192.875716 -318.373248) (xy 192.926498 -318.381291) (xy 192.975397 -318.397179)
			(xy 193.021209 -318.420522) (xy 193.062805 -318.450743) (xy 193.099161 -318.487099) (xy 193.129382 -318.528695)
			(xy 193.152725 -318.574507) (xy 193.168613 -318.623406) (xy 193.176656 -318.674188) (xy 193.17716 -318.699896)
			(xy 193.176656 -318.725604) (xy 194.42328 -318.725604) (xy 194.42328 -318.674188) (xy 194.431323 -318.623406)
			(xy 194.447211 -318.574507) (xy 194.470554 -318.528695) (xy 194.500775 -318.487099) (xy 194.537131 -318.450743)
			(xy 194.578727 -318.420522) (xy 194.624539 -318.397179) (xy 194.673438 -318.381291) (xy 194.72422 -318.373248)
			(xy 194.775636 -318.373248) (xy 194.826418 -318.381291) (xy 194.875317 -318.397179) (xy 194.921129 -318.420522)
			(xy 194.962725 -318.450743) (xy 194.999081 -318.487099) (xy 195.029302 -318.528695) (xy 195.052645 -318.574507)
			(xy 195.068533 -318.623406) (xy 195.076576 -318.674188) (xy 195.07708 -318.699896) (xy 195.076576 -318.725604)
			(xy 196.3232 -318.725604) (xy 196.3232 -318.674188) (xy 196.331243 -318.623406) (xy 196.347131 -318.574507)
			(xy 196.370474 -318.528695) (xy 196.400695 -318.487099) (xy 196.437051 -318.450743) (xy 196.478647 -318.420522)
			(xy 196.524459 -318.397179) (xy 196.573358 -318.381291) (xy 196.62414 -318.373248) (xy 196.675556 -318.373248)
			(xy 196.726338 -318.381291) (xy 196.775237 -318.397179) (xy 196.821049 -318.420522) (xy 196.862645 -318.450743)
			(xy 196.899001 -318.487099) (xy 196.929222 -318.528695) (xy 196.952565 -318.574507) (xy 196.968453 -318.623406)
			(xy 196.976496 -318.674188) (xy 196.977 -318.699896) (xy 196.976496 -318.725604) (xy 196.968453 -318.776386)
			(xy 196.952565 -318.825285) (xy 196.929222 -318.871097) (xy 196.899001 -318.912693) (xy 196.862645 -318.949049)
			(xy 196.821049 -318.97927) (xy 196.775237 -319.002613) (xy 196.726338 -319.018501) (xy 196.675556 -319.026544)
			(xy 196.62414 -319.026544) (xy 196.573358 -319.018501) (xy 196.524459 -319.002613) (xy 196.478647 -318.97927)
			(xy 196.437051 -318.949049) (xy 196.400695 -318.912693) (xy 196.370474 -318.871097) (xy 196.347131 -318.825285)
			(xy 196.331243 -318.776386) (xy 196.3232 -318.725604) (xy 195.076576 -318.725604) (xy 195.068533 -318.776386)
			(xy 195.052645 -318.825285) (xy 195.029302 -318.871097) (xy 194.999081 -318.912693) (xy 194.962725 -318.949049)
			(xy 194.921129 -318.97927) (xy 194.875317 -319.002613) (xy 194.826418 -319.018501) (xy 194.775636 -319.026544)
			(xy 194.72422 -319.026544) (xy 194.673438 -319.018501) (xy 194.624539 -319.002613) (xy 194.578727 -318.97927)
			(xy 194.537131 -318.949049) (xy 194.500775 -318.912693) (xy 194.470554 -318.871097) (xy 194.447211 -318.825285)
			(xy 194.431323 -318.776386) (xy 194.42328 -318.725604) (xy 193.176656 -318.725604) (xy 193.168613 -318.776386)
			(xy 193.152725 -318.825285) (xy 193.129382 -318.871097) (xy 193.099161 -318.912693) (xy 193.062805 -318.949049)
			(xy 193.021209 -318.97927) (xy 192.975397 -319.002613) (xy 192.926498 -319.018501) (xy 192.875716 -319.026544)
			(xy 192.8243 -319.026544) (xy 192.773518 -319.018501) (xy 192.724619 -319.002613) (xy 192.678807 -318.97927)
			(xy 192.637211 -318.949049) (xy 192.600855 -318.912693) (xy 192.570634 -318.871097) (xy 192.547291 -318.825285)
			(xy 192.531403 -318.776386) (xy 192.52336 -318.725604) (xy 191.276752 -318.725604) (xy 191.268717 -318.776356)
			(xy 191.252843 -318.825235) (xy 191.229522 -318.871031) (xy 191.199327 -318.912617) (xy 191.163001 -318.94897)
			(xy 191.121437 -318.979196) (xy 191.075659 -319.002551) (xy 191.026792 -319.018461) (xy 190.976038 -319.026534)
			(xy 190.950342 -319.027048) (xy 190.949834 -319.027048) (xy 190.915544 -319.025016) (xy 190.915036 -319.025016)
			(xy 190.903606 -319.023746) (xy 190.882016 -319.03162) (xy 190.809626 -319.104264) (xy 190.80226 -319.126108)
			(xy 190.80353 -319.137538) (xy 190.804498 -319.146842) (xy 190.805513 -319.165522) (xy 190.805562 -319.174876)
			(xy 190.805048 -319.200845) (xy 190.796921 -319.252143) (xy 190.780878 -319.301541) (xy 190.757314 -319.347825)
			(xy 190.726807 -319.38986) (xy 190.690106 -319.42661) (xy 190.648114 -319.457175) (xy 190.601862 -319.480803)
			(xy 190.552486 -319.496914) (xy 190.526924 -319.50152) (xy 190.526162 -319.50152) (xy 190.517567 -319.503342)
			(xy 190.502249 -319.51192) (xy 190.49619 -319.518284) (xy 190.490348 -319.524888) (xy 190.483998 -319.541906)
			(xy 190.483998 -319.551304) (xy 190.48346 -319.561291) (xy 190.475745 -319.579722) (xy 190.469012 -319.587118)
			(xy 190.219584 -319.836546) (xy 190.217044 -319.839086) (xy 190.216282 -319.840102) (xy 190.197994 -319.858644)
			(xy 190.190882 -319.865502) (xy 190.179452 -319.89268) (xy 190.177578 -319.897419) (xy 190.175527 -319.907398)
			(xy 190.175388 -319.912492) (xy 190.175388 -320.900044) (xy 202.982331 -320.900044) (xy 202.98632 -320.751504)
			(xy 202.998277 -320.603391) (xy 203.018167 -320.456134) (xy 203.045932 -320.310158) (xy 203.081493 -320.165881)
			(xy 203.124747 -320.023722) (xy 203.175569 -319.884089) (xy 203.233813 -319.747386) (xy 203.299311 -319.614006)
			(xy 203.371874 -319.484334) (xy 203.451292 -319.358744) (xy 203.537337 -319.237597) (xy 203.629761 -319.121244)
			(xy 203.728297 -319.01002) (xy 203.832661 -318.904245) (xy 203.942553 -318.804225) (xy 204.057654 -318.710247)
			(xy 204.177634 -318.622583) (xy 204.302147 -318.541486) (xy 204.430833 -318.467189) (xy 204.563322 -318.399907)
			(xy 204.699231 -318.339833) (xy 204.838169 -318.287141) (xy 204.979735 -318.241982) (xy 205.123521 -318.204487)
			(xy 205.269112 -318.174765) (xy 205.416088 -318.1529) (xy 205.564027 -318.138956) (xy 205.7125 -318.132972)
			(xy 205.861081 -318.134967) (xy 206.00934 -318.144935) (xy 206.156851 -318.162846) (xy 206.303187 -318.188649)
			(xy 206.447928 -318.222269) (xy 206.590655 -318.263611) (xy 206.730958 -318.312554) (xy 206.868431 -318.368957)
			(xy 207.002678 -318.432658) (xy 207.133313 -318.503474) (xy 207.259958 -318.581199) (xy 207.382248 -318.66561)
			(xy 207.499831 -318.756463) (xy 207.612368 -318.853497) (xy 207.719535 -318.956432) (xy 207.821022 -319.064971)
			(xy 207.916536 -319.1788) (xy 208.005803 -319.297593) (xy 208.088564 -319.421005) (xy 208.164582 -319.548683)
			(xy 208.233637 -319.680256) (xy 208.29553 -319.815347) (xy 208.350083 -319.953564) (xy 208.397138 -320.094511)
			(xy 208.43656 -320.237781) (xy 208.468234 -320.38296) (xy 208.49207 -320.529629) (xy 208.507999 -320.677367)
			(xy 208.515975 -320.825747) (xy 208.516474 -320.900044) (xy 208.515975 -320.974341) (xy 208.507999 -321.122721)
			(xy 208.49207 -321.270459) (xy 208.468234 -321.417128) (xy 208.43656 -321.562307) (xy 208.397138 -321.705577)
			(xy 208.350083 -321.846524) (xy 208.29553 -321.984741) (xy 208.233637 -322.119832) (xy 208.164582 -322.251405)
			(xy 208.088564 -322.379083) (xy 208.005803 -322.502495) (xy 207.916536 -322.621288) (xy 207.821022 -322.735117)
			(xy 207.719535 -322.843656) (xy 207.612368 -322.946591) (xy 207.499831 -323.043625) (xy 207.382248 -323.134478)
			(xy 207.259958 -323.218889) (xy 207.133313 -323.296614) (xy 207.002678 -323.36743) (xy 206.868431 -323.431131)
			(xy 206.730958 -323.487534) (xy 206.590655 -323.536477) (xy 206.447928 -323.577819) (xy 206.303187 -323.611439)
			(xy 206.156851 -323.637242) (xy 206.00934 -323.655153) (xy 205.861081 -323.665121) (xy 205.7125 -323.667116)
			(xy 205.564027 -323.661132) (xy 205.416088 -323.647188) (xy 205.269112 -323.625323) (xy 205.123521 -323.595601)
			(xy 204.979735 -323.558106) (xy 204.838169 -323.512947) (xy 204.699231 -323.460255) (xy 204.563322 -323.400181)
			(xy 204.430833 -323.332899) (xy 204.302147 -323.258602) (xy 204.177634 -323.177505) (xy 204.057654 -323.089841)
			(xy 203.942553 -322.995863) (xy 203.832661 -322.895843) (xy 203.728297 -322.790068) (xy 203.629761 -322.678844)
			(xy 203.537337 -322.562491) (xy 203.451292 -322.441344) (xy 203.371874 -322.315754) (xy 203.299311 -322.186082)
			(xy 203.233813 -322.052702) (xy 203.175569 -321.915999) (xy 203.124747 -321.776366) (xy 203.081493 -321.634207)
			(xy 203.045932 -321.48993) (xy 203.018167 -321.343954) (xy 202.998277 -321.196697) (xy 202.98632 -321.048584)
			(xy 202.982331 -320.900044) (xy 190.175388 -320.900044) (xy 190.175388 -321.897248) (xy 190.175284 -321.901859)
			(xy 190.173618 -321.910931) (xy 190.172086 -321.915282) (xy 190.114682 -322.063872) (xy 190.114428 -322.06438)
			(xy 190.109348 -322.078096) (xy 189.586616 -323.432932) (xy 189.584628 -323.439612) (xy 189.583984 -323.453529)
			(xy 189.585346 -323.460364) (xy 189.589664 -323.474588) (xy 189.590172 -323.477128) (xy 189.591741 -323.485691)
			(xy 189.589663 -323.502963) (xy 189.586108 -323.51091) (xy 189.5221 -323.638926) (xy 189.519638 -323.644251)
			(xy 189.516941 -323.655668) (xy 189.516766 -323.661532) (xy 189.516766 -323.804788) (xy 189.516344 -323.814858)
			(xy 189.508629 -323.833463) (xy 189.50178 -323.840856) (xy 189.314582 -324.028054) (xy 189.307216 -324.037452)
			(xy 189.157864 -324.281292) (xy 189.15634 -324.2818) (xy 188.509656 -325.331582) (xy 188.504322 -325.340218)
			(xy 188.504068 -325.340472) (xy 188.451998 -325.425054) (xy 188.444632 -325.434452) (xy 188.374274 -325.50481)
			(xy 188.366908 -325.512176) (xy 187.775662 -326.103488) (xy 228.141528 -326.103488) (xy 228.145599 -326.047866)
			(xy 228.157725 -325.993429) (xy 228.177648 -325.941338) (xy 228.204944 -325.892703) (xy 228.23903 -325.84856)
			(xy 228.279179 -325.809851) (xy 228.324537 -325.7774) (xy 228.374137 -325.751899) (xy 228.426921 -325.733892)
			(xy 228.481764 -325.723762) (xy 228.537498 -325.721725) (xy 228.592935 -325.727825) (xy 228.646892 -325.741931)
			(xy 228.698221 -325.763743) (xy 228.745827 -325.792797) (xy 228.788695 -325.828472) (xy 228.825912 -325.870009)
			(xy 228.856685 -325.916522) (xy 228.880357 -325.967019) (xy 228.896425 -326.020426) (xy 228.904545 -326.075602)
			(xy 228.905054 -326.103488) (xy 228.904545 -326.131374) (xy 228.896425 -326.18655) (xy 228.880357 -326.239957)
			(xy 228.856685 -326.290454) (xy 228.825912 -326.336967) (xy 228.788695 -326.378504) (xy 228.745827 -326.414179)
			(xy 228.698221 -326.443233) (xy 228.646892 -326.465045) (xy 228.592935 -326.479151) (xy 228.537498 -326.485251)
			(xy 228.481764 -326.483214) (xy 228.426921 -326.473084) (xy 228.374137 -326.455077) (xy 228.324537 -326.429576)
			(xy 228.279179 -326.397125) (xy 228.23903 -326.358416) (xy 228.204944 -326.314273) (xy 228.177648 -326.265638)
			(xy 228.157725 -326.213547) (xy 228.145599 -326.15911) (xy 228.141528 -326.103488) (xy 187.775662 -326.103488)
			(xy 186.492344 -327.38695) (xy 248.284236 -327.38695) (xy 248.288307 -327.331328) (xy 248.300433 -327.276891)
			(xy 248.320356 -327.2248) (xy 248.347652 -327.176165) (xy 248.381738 -327.132022) (xy 248.421887 -327.093313)
			(xy 248.467245 -327.060862) (xy 248.516845 -327.035361) (xy 248.569629 -327.017354) (xy 248.624472 -327.007224)
			(xy 248.680206 -327.005187) (xy 248.735643 -327.011287) (xy 248.7896 -327.025393) (xy 248.840929 -327.047205)
			(xy 248.888535 -327.076259) (xy 248.931403 -327.111934) (xy 248.96862 -327.153471) (xy 248.999393 -327.199984)
			(xy 249.023065 -327.250481) (xy 249.039133 -327.303888) (xy 249.047253 -327.359064) (xy 249.047762 -327.38695)
			(xy 249.047253 -327.414836) (xy 249.039133 -327.470012) (xy 249.023065 -327.523419) (xy 248.999393 -327.573916)
			(xy 248.96862 -327.620429) (xy 248.931403 -327.661966) (xy 248.888535 -327.697641) (xy 248.840929 -327.726695)
			(xy 248.7896 -327.748507) (xy 248.735643 -327.762613) (xy 248.680206 -327.768713) (xy 248.624472 -327.766676)
			(xy 248.569629 -327.756546) (xy 248.516845 -327.738539) (xy 248.467245 -327.713038) (xy 248.421887 -327.680587)
			(xy 248.381738 -327.641878) (xy 248.347652 -327.597735) (xy 248.320356 -327.5491) (xy 248.300433 -327.497009)
			(xy 248.288307 -327.442572) (xy 248.284236 -327.38695) (xy 186.492344 -327.38695) (xy 186.096402 -327.782936)
			(xy 186.060715 -327.817721) (xy 185.983478 -327.880707) (xy 185.953093 -327.9013) (xy 247.264172 -327.9013)
			(xy 247.268243 -327.845678) (xy 247.280369 -327.791241) (xy 247.300292 -327.73915) (xy 247.327588 -327.690515)
			(xy 247.361674 -327.646372) (xy 247.401823 -327.607663) (xy 247.447181 -327.575212) (xy 247.496781 -327.549711)
			(xy 247.549565 -327.531704) (xy 247.604408 -327.521574) (xy 247.660142 -327.519537) (xy 247.715579 -327.525637)
			(xy 247.769536 -327.539743) (xy 247.820865 -327.561555) (xy 247.868471 -327.590609) (xy 247.911339 -327.626284)
			(xy 247.948556 -327.667821) (xy 247.979329 -327.714334) (xy 248.003001 -327.764831) (xy 248.019069 -327.818238)
			(xy 248.027189 -327.873414) (xy 248.027698 -327.9013) (xy 248.027189 -327.929186) (xy 248.019069 -327.984362)
			(xy 248.003001 -328.037769) (xy 247.979329 -328.088266) (xy 247.948556 -328.134779) (xy 247.911339 -328.176316)
			(xy 247.868471 -328.211991) (xy 247.820865 -328.241045) (xy 247.769536 -328.262857) (xy 247.715579 -328.276963)
			(xy 247.660142 -328.283063) (xy 247.604408 -328.281026) (xy 247.549565 -328.270896) (xy 247.496781 -328.252889)
			(xy 247.447181 -328.227388) (xy 247.401823 -328.194937) (xy 247.361674 -328.156228) (xy 247.327588 -328.112085)
			(xy 247.300292 -328.06345) (xy 247.280369 -328.011359) (xy 247.268243 -327.956922) (xy 247.264172 -327.9013)
			(xy 185.953093 -327.9013) (xy 185.942224 -327.908666) (xy 184.197506 -329.061064) (xy 225.609148 -329.061064)
			(xy 225.613219 -329.005442) (xy 225.625345 -328.951005) (xy 225.645268 -328.898914) (xy 225.672564 -328.850279)
			(xy 225.70665 -328.806136) (xy 225.746799 -328.767427) (xy 225.792157 -328.734976) (xy 225.841757 -328.709475)
			(xy 225.894541 -328.691468) (xy 225.949384 -328.681338) (xy 226.005118 -328.679301) (xy 226.060555 -328.685401)
			(xy 226.114512 -328.699507) (xy 226.165841 -328.721319) (xy 226.213447 -328.750373) (xy 226.256315 -328.786048)
			(xy 226.293532 -328.827585) (xy 226.324305 -328.874098) (xy 226.347977 -328.924595) (xy 226.364045 -328.978002)
			(xy 226.372165 -329.033178) (xy 226.372674 -329.061064) (xy 226.372165 -329.08895) (xy 226.364045 -329.144126)
			(xy 226.354723 -329.17511) (xy 240.475768 -329.17511) (xy 240.479839 -329.119488) (xy 240.491965 -329.065051)
			(xy 240.511888 -329.01296) (xy 240.539184 -328.964325) (xy 240.57327 -328.920182) (xy 240.613419 -328.881473)
			(xy 240.658777 -328.849022) (xy 240.708377 -328.823521) (xy 240.761161 -328.805514) (xy 240.816004 -328.795384)
			(xy 240.871738 -328.793347) (xy 240.927175 -328.799447) (xy 240.981132 -328.813553) (xy 241.032461 -328.835365)
			(xy 241.080067 -328.864419) (xy 241.122935 -328.900094) (xy 241.160152 -328.941631) (xy 241.190925 -328.988144)
			(xy 241.214597 -329.038641) (xy 241.230665 -329.092048) (xy 241.238785 -329.147224) (xy 241.239294 -329.17511)
			(xy 241.238785 -329.202996) (xy 241.230665 -329.258172) (xy 241.214597 -329.311579) (xy 241.190925 -329.362076)
			(xy 241.160152 -329.408589) (xy 241.122935 -329.450126) (xy 241.080067 -329.485801) (xy 241.032461 -329.514855)
			(xy 240.981132 -329.536667) (xy 240.927175 -329.550773) (xy 240.871738 -329.556873) (xy 240.816004 -329.554836)
			(xy 240.761161 -329.544706) (xy 240.708377 -329.526699) (xy 240.658777 -329.501198) (xy 240.613419 -329.468747)
			(xy 240.57327 -329.430038) (xy 240.539184 -329.385895) (xy 240.511888 -329.33726) (xy 240.491965 -329.285169)
			(xy 240.479839 -329.230732) (xy 240.475768 -329.17511) (xy 226.354723 -329.17511) (xy 226.347977 -329.197533)
			(xy 226.324305 -329.24803) (xy 226.293532 -329.294543) (xy 226.256315 -329.33608) (xy 226.213447 -329.371755)
			(xy 226.165841 -329.400809) (xy 226.114512 -329.422621) (xy 226.060555 -329.436727) (xy 226.005118 -329.442827)
			(xy 225.949384 -329.44079) (xy 225.894541 -329.43066) (xy 225.841757 -329.412653) (xy 225.792157 -329.387152)
			(xy 225.746799 -329.354701) (xy 225.70665 -329.315992) (xy 225.672564 -329.271849) (xy 225.645268 -329.223214)
			(xy 225.625345 -329.171123) (xy 225.613219 -329.116686) (xy 225.609148 -329.061064) (xy 184.197506 -329.061064)
			(xy 182.533544 -330.160122) (xy 182.4916 -330.187083) (xy 182.403294 -330.233399) (xy 182.357268 -330.252578)
			(xy 182.22214 -330.306934) (xy 182.216806 -330.308966) (xy 182.061462 -330.411582) (xy 221.258892 -330.411582)
			(xy 221.259349 -330.384211) (xy 221.26717 -330.330032) (xy 221.282661 -330.277529) (xy 221.305504 -330.227782)
			(xy 221.33523 -330.181816) (xy 221.352872 -330.160884) (xy 221.353126 -330.16063) (xy 221.358709 -330.153541)
			(xy 221.364957 -330.136626) (xy 221.365318 -330.12761) (xy 221.365318 -330.060554) (xy 221.364931 -330.05154)
			(xy 221.358704 -330.034623) (xy 221.353126 -330.027534) (xy 221.352872 -330.027534) (xy 221.352872 -330.02728)
			(xy 221.335253 -330.006332) (xy 221.305539 -329.960363) (xy 221.282699 -329.91062) (xy 221.267204 -329.858123)
			(xy 221.259369 -329.80395) (xy 221.258892 -329.776582) (xy 221.259378 -329.749331) (xy 221.267134 -329.695383)
			(xy 221.282489 -329.643088) (xy 221.305131 -329.593511) (xy 221.334597 -329.547661) (xy 221.370288 -329.50647)
			(xy 221.411479 -329.470779) (xy 221.457329 -329.441313) (xy 221.506906 -329.418671) (xy 221.559201 -329.403316)
			(xy 221.613149 -329.39556) (xy 221.667651 -329.39556) (xy 221.721599 -329.403316) (xy 221.773894 -329.418671)
			(xy 221.823471 -329.441313) (xy 221.869321 -329.470779) (xy 221.910512 -329.50647) (xy 221.946203 -329.547661)
			(xy 221.975669 -329.593511) (xy 221.998311 -329.643088) (xy 222.013666 -329.695383) (xy 222.021422 -329.749331)
			(xy 222.021908 -329.776582) (xy 222.021429 -329.803952) (xy 222.013614 -329.85813) (xy 222.009273 -329.872848)
			(xy 224.897186 -329.872848) (xy 224.901257 -329.817226) (xy 224.913383 -329.762789) (xy 224.933306 -329.710698)
			(xy 224.960602 -329.662063) (xy 224.994688 -329.61792) (xy 225.034837 -329.579211) (xy 225.080195 -329.54676)
			(xy 225.129795 -329.521259) (xy 225.182579 -329.503252) (xy 225.237422 -329.493122) (xy 225.293156 -329.491085)
			(xy 225.348593 -329.497185) (xy 225.40255 -329.511291) (xy 225.453879 -329.533103) (xy 225.501485 -329.562157)
			(xy 225.544353 -329.597832) (xy 225.58157 -329.639369) (xy 225.612343 -329.685882) (xy 225.636015 -329.736379)
			(xy 225.652083 -329.789786) (xy 225.660203 -329.844962) (xy 225.660712 -329.872848) (xy 225.660203 -329.900734)
			(xy 225.652083 -329.95591) (xy 225.636015 -330.009317) (xy 225.612343 -330.059814) (xy 225.58157 -330.106327)
			(xy 225.544353 -330.147864) (xy 225.534202 -330.156312) (xy 228.956614 -330.156312) (xy 228.960685 -330.10069)
			(xy 228.972811 -330.046253) (xy 228.992734 -329.994162) (xy 229.02003 -329.945527) (xy 229.054116 -329.901384)
			(xy 229.094265 -329.862675) (xy 229.139623 -329.830224) (xy 229.189223 -329.804723) (xy 229.242007 -329.786716)
			(xy 229.29685 -329.776586) (xy 229.352584 -329.774549) (xy 229.408021 -329.780649) (xy 229.461978 -329.794755)
			(xy 229.513307 -329.816567) (xy 229.560913 -329.845621) (xy 229.603781 -329.881296) (xy 229.640998 -329.922833)
			(xy 229.671771 -329.969346) (xy 229.683212 -329.993752) (xy 229.870506 -329.993752) (xy 229.874577 -329.93813)
			(xy 229.886703 -329.883693) (xy 229.906626 -329.831602) (xy 229.933922 -329.782967) (xy 229.968008 -329.738824)
			(xy 230.008157 -329.700115) (xy 230.053515 -329.667664) (xy 230.103115 -329.642163) (xy 230.155899 -329.624156)
			(xy 230.210742 -329.614026) (xy 230.266476 -329.611989) (xy 230.321913 -329.618089) (xy 230.37587 -329.632195)
			(xy 230.427199 -329.654007) (xy 230.474805 -329.683061) (xy 230.517673 -329.718736) (xy 230.55489 -329.760273)
			(xy 230.585663 -329.806786) (xy 230.609335 -329.857283) (xy 230.625403 -329.91069) (xy 230.633523 -329.965866)
			(xy 230.634032 -329.993752) (xy 230.633523 -330.021638) (xy 230.627609 -330.061824) (xy 230.958134 -330.061824)
			(xy 230.962205 -330.006202) (xy 230.974331 -329.951765) (xy 230.994254 -329.899674) (xy 231.02155 -329.851039)
			(xy 231.055636 -329.806896) (xy 231.095785 -329.768187) (xy 231.141143 -329.735736) (xy 231.190743 -329.710235)
			(xy 231.243527 -329.692228) (xy 231.29837 -329.682098) (xy 231.354104 -329.680061) (xy 231.409541 -329.686161)
			(xy 231.463498 -329.700267) (xy 231.514827 -329.722079) (xy 231.562433 -329.751133) (xy 231.605301 -329.786808)
			(xy 231.642518 -329.828345) (xy 231.673291 -329.874858) (xy 231.696963 -329.925355) (xy 231.713031 -329.978762)
			(xy 231.721151 -330.033938) (xy 231.72166 -330.061824) (xy 231.721151 -330.08971) (xy 231.713031 -330.144886)
			(xy 231.696963 -330.198293) (xy 231.673291 -330.24879) (xy 231.642518 -330.295303) (xy 231.605301 -330.33684)
			(xy 231.562433 -330.372515) (xy 231.514827 -330.401569) (xy 231.463498 -330.423381) (xy 231.409541 -330.437487)
			(xy 231.354104 -330.443587) (xy 231.29837 -330.44155) (xy 231.243527 -330.43142) (xy 231.190743 -330.413413)
			(xy 231.141143 -330.387912) (xy 231.095785 -330.355461) (xy 231.055636 -330.316752) (xy 231.02155 -330.272609)
			(xy 230.994254 -330.223974) (xy 230.974331 -330.171883) (xy 230.962205 -330.117446) (xy 230.958134 -330.061824)
			(xy 230.627609 -330.061824) (xy 230.625403 -330.076814) (xy 230.609335 -330.130221) (xy 230.585663 -330.180718)
			(xy 230.55489 -330.227231) (xy 230.517673 -330.268768) (xy 230.474805 -330.304443) (xy 230.427199 -330.333497)
			(xy 230.37587 -330.355309) (xy 230.321913 -330.369415) (xy 230.266476 -330.375515) (xy 230.210742 -330.373478)
			(xy 230.155899 -330.363348) (xy 230.103115 -330.345341) (xy 230.053515 -330.31984) (xy 230.008157 -330.287389)
			(xy 229.968008 -330.24868) (xy 229.933922 -330.204537) (xy 229.906626 -330.155902) (xy 229.886703 -330.103811)
			(xy 229.874577 -330.049374) (xy 229.870506 -329.993752) (xy 229.683212 -329.993752) (xy 229.695443 -330.019843)
			(xy 229.711511 -330.07325) (xy 229.719631 -330.128426) (xy 229.72014 -330.156312) (xy 229.719631 -330.184198)
			(xy 229.711511 -330.239374) (xy 229.695443 -330.292781) (xy 229.671771 -330.343278) (xy 229.640998 -330.389791)
			(xy 229.603781 -330.431328) (xy 229.560913 -330.467003) (xy 229.513307 -330.496057) (xy 229.461978 -330.517869)
			(xy 229.408021 -330.531975) (xy 229.352584 -330.538075) (xy 229.29685 -330.536038) (xy 229.242007 -330.525908)
			(xy 229.189223 -330.507901) (xy 229.139623 -330.4824) (xy 229.094265 -330.449949) (xy 229.054116 -330.41124)
			(xy 229.02003 -330.367097) (xy 228.992734 -330.318462) (xy 228.972811 -330.266371) (xy 228.960685 -330.211934)
			(xy 228.956614 -330.156312) (xy 225.534202 -330.156312) (xy 225.501485 -330.183539) (xy 225.453879 -330.212593)
			(xy 225.40255 -330.234405) (xy 225.348593 -330.248511) (xy 225.293156 -330.254611) (xy 225.237422 -330.252574)
			(xy 225.182579 -330.242444) (xy 225.129795 -330.224437) (xy 225.080195 -330.198936) (xy 225.034837 -330.166485)
			(xy 224.994688 -330.127776) (xy 224.960602 -330.083633) (xy 224.933306 -330.034998) (xy 224.913383 -329.982907)
			(xy 224.901257 -329.92847) (xy 224.897186 -329.872848) (xy 222.009273 -329.872848) (xy 221.998128 -329.910633)
			(xy 221.975289 -329.96038) (xy 221.945568 -330.006348) (xy 221.927928 -330.02728) (xy 221.927674 -330.027534)
			(xy 221.922106 -330.034633) (xy 221.915849 -330.05154) (xy 221.915482 -330.060554) (xy 221.915482 -330.12761)
			(xy 221.915838 -330.136627) (xy 221.922087 -330.153544) (xy 221.927674 -330.16063) (xy 221.927928 -330.16063)
			(xy 221.927928 -330.160884) (xy 221.945577 -330.181808) (xy 221.975287 -330.227783) (xy 221.99812 -330.277533)
			(xy 222.013609 -330.330035) (xy 222.021435 -330.384212) (xy 222.021908 -330.411582) (xy 222.021422 -330.438833)
			(xy 222.013666 -330.492781) (xy 221.998311 -330.545076) (xy 221.975669 -330.594653) (xy 221.946203 -330.640503)
			(xy 221.910512 -330.681694) (xy 221.869321 -330.717385) (xy 221.823471 -330.746851) (xy 221.773894 -330.769493)
			(xy 221.721599 -330.784848) (xy 221.667651 -330.792604) (xy 221.613149 -330.792604) (xy 221.559201 -330.784848)
			(xy 221.506906 -330.769493) (xy 221.457329 -330.746851) (xy 221.411479 -330.717385) (xy 221.370288 -330.681694)
			(xy 221.334597 -330.640503) (xy 221.305131 -330.594653) (xy 221.282489 -330.545076) (xy 221.267134 -330.492781)
			(xy 221.259378 -330.438833) (xy 221.258892 -330.411582) (xy 182.061462 -330.411582) (xy 181.114019 -331.037438)
			(xy 249.7615 -331.037438) (xy 249.765571 -330.981816) (xy 249.777697 -330.927379) (xy 249.79762 -330.875288)
			(xy 249.824916 -330.826653) (xy 249.859002 -330.78251) (xy 249.899151 -330.743801) (xy 249.944509 -330.71135)
			(xy 249.994109 -330.685849) (xy 250.046893 -330.667842) (xy 250.101736 -330.657712) (xy 250.15747 -330.655675)
			(xy 250.212907 -330.661775) (xy 250.266864 -330.675881) (xy 250.318193 -330.697693) (xy 250.365799 -330.726747)
			(xy 250.408667 -330.762422) (xy 250.445884 -330.803959) (xy 250.476657 -330.850472) (xy 250.500329 -330.900969)
			(xy 250.516397 -330.954376) (xy 250.524517 -331.009552) (xy 250.525026 -331.037438) (xy 250.524517 -331.065324)
			(xy 250.516397 -331.1205) (xy 250.500329 -331.173907) (xy 250.476657 -331.224404) (xy 250.445884 -331.270917)
			(xy 250.408667 -331.312454) (xy 250.365799 -331.348129) (xy 250.318193 -331.377183) (xy 250.266864 -331.398995)
			(xy 250.212907 -331.413101) (xy 250.15747 -331.419201) (xy 250.101736 -331.417164) (xy 250.046893 -331.407034)
			(xy 249.994109 -331.389027) (xy 249.944509 -331.363526) (xy 249.899151 -331.331075) (xy 249.859002 -331.292366)
			(xy 249.824916 -331.248223) (xy 249.79762 -331.199588) (xy 249.777697 -331.147497) (xy 249.765571 -331.09306)
			(xy 249.7615 -331.037438) (xy 181.114019 -331.037438) (xy 179.840892 -331.878432) (xy 239.366296 -331.878432)
			(xy 239.370367 -331.82281) (xy 239.382493 -331.768373) (xy 239.402416 -331.716282) (xy 239.429712 -331.667647)
			(xy 239.463798 -331.623504) (xy 239.503947 -331.584795) (xy 239.549305 -331.552344) (xy 239.598905 -331.526843)
			(xy 239.651689 -331.508836) (xy 239.706532 -331.498706) (xy 239.762266 -331.496669) (xy 239.817703 -331.502769)
			(xy 239.87166 -331.516875) (xy 239.922989 -331.538687) (xy 239.970595 -331.567741) (xy 240.013463 -331.603416)
			(xy 240.05068 -331.644953) (xy 240.081453 -331.691466) (xy 240.105125 -331.741963) (xy 240.121193 -331.79537)
			(xy 240.129313 -331.850546) (xy 240.129822 -331.878432) (xy 240.129313 -331.906318) (xy 240.121193 -331.961494)
			(xy 240.105125 -332.014901) (xy 240.081453 -332.065398) (xy 240.05068 -332.111911) (xy 240.013463 -332.153448)
			(xy 239.970595 -332.189123) (xy 239.922989 -332.218177) (xy 239.87166 -332.239989) (xy 239.817703 -332.254095)
			(xy 239.762266 -332.260195) (xy 239.706532 -332.258158) (xy 239.651689 -332.248028) (xy 239.598905 -332.230021)
			(xy 239.549305 -332.20452) (xy 239.503947 -332.172069) (xy 239.463798 -332.13336) (xy 239.429712 -332.089217)
			(xy 239.402416 -332.040582) (xy 239.382493 -331.988491) (xy 239.370367 -331.934054) (xy 239.366296 -331.878432)
			(xy 179.840892 -331.878432) (xy 178.76407 -332.589752) (xy 228.949232 -332.589752) (xy 228.949232 -332.535248)
			(xy 228.956988 -332.481298) (xy 228.972342 -332.429001) (xy 228.994983 -332.379421) (xy 229.024448 -332.333567)
			(xy 229.060138 -332.292374) (xy 229.101327 -332.256678) (xy 229.147177 -332.227207) (xy 229.196754 -332.20456)
			(xy 229.249049 -332.189199) (xy 229.302998 -332.181435) (xy 229.33025 -332.180946) (xy 229.356964 -332.181383)
			(xy 229.409865 -332.188873) (xy 229.461204 -332.203671) (xy 229.509975 -332.225488) (xy 229.555226 -332.253897)
			(xy 229.596069 -332.288342) (xy 229.614222 -332.307946) (xy 229.614222 -332.3082) (xy 229.621904 -332.315821)
			(xy 229.641761 -332.324372) (xy 229.652576 -332.32471) (xy 229.74046 -332.323694) (xy 229.760272 -332.314296)
			(xy 229.767384 -332.305914) (xy 229.785598 -332.285247) (xy 229.826945 -332.248848) (xy 229.873099 -332.218775)
			(xy 229.923098 -332.195653) (xy 229.975904 -332.179965) (xy 230.030417 -332.172035) (xy 230.05796 -332.171548)
			(xy 230.085212 -332.172096) (xy 230.139161 -332.179848) (xy 230.191457 -332.195199) (xy 230.241037 -332.217836)
			(xy 230.28689 -332.2473) (xy 230.328082 -332.282989) (xy 230.363776 -332.324178) (xy 230.393244 -332.370028)
			(xy 230.415887 -332.419605) (xy 230.431244 -332.4719) (xy 230.439001 -332.525848) (xy 230.439001 -332.580352)
			(xy 230.431244 -332.6343) (xy 230.415887 -332.686595) (xy 230.393244 -332.736172) (xy 230.363776 -332.782022)
			(xy 230.328082 -332.823211) (xy 230.28689 -332.8589) (xy 230.248986 -332.883256) (xy 236.029498 -332.883256)
			(xy 236.033569 -332.827634) (xy 236.045695 -332.773197) (xy 236.065618 -332.721106) (xy 236.092914 -332.672471)
			(xy 236.127 -332.628328) (xy 236.167149 -332.589619) (xy 236.212507 -332.557168) (xy 236.262107 -332.531667)
			(xy 236.314891 -332.51366) (xy 236.369734 -332.50353) (xy 236.425468 -332.501493) (xy 236.480905 -332.507593)
			(xy 236.534862 -332.521699) (xy 236.586191 -332.543511) (xy 236.633797 -332.572565) (xy 236.676665 -332.60824)
			(xy 236.713882 -332.649777) (xy 236.744655 -332.69629) (xy 236.768327 -332.746787) (xy 236.784395 -332.800194)
			(xy 236.792515 -332.85537) (xy 236.793024 -332.883256) (xy 236.792515 -332.911142) (xy 236.784395 -332.966318)
			(xy 236.768327 -333.019725) (xy 236.744655 -333.070222) (xy 236.713882 -333.116735) (xy 236.676665 -333.158272)
			(xy 236.633797 -333.193947) (xy 236.586191 -333.223001) (xy 236.534862 -333.244813) (xy 236.480905 -333.258919)
			(xy 236.425468 -333.265019) (xy 236.369734 -333.262982) (xy 236.314891 -333.252852) (xy 236.262107 -333.234845)
			(xy 236.212507 -333.209344) (xy 236.167149 -333.176893) (xy 236.127 -333.138184) (xy 236.092914 -333.094041)
			(xy 236.065618 -333.045406) (xy 236.045695 -332.993315) (xy 236.033569 -332.938878) (xy 236.029498 -332.883256)
			(xy 230.248986 -332.883256) (xy 230.241037 -332.888364) (xy 230.191457 -332.911001) (xy 230.139161 -332.926352)
			(xy 230.085212 -332.934104) (xy 230.05796 -332.934564) (xy 230.031246 -332.934117) (xy 229.978346 -332.926628)
			(xy 229.927007 -332.911832) (xy 229.878236 -332.890017) (xy 229.832985 -332.86161) (xy 229.792141 -332.827167)
			(xy 229.773988 -332.807564) (xy 229.773988 -332.80731) (xy 229.766301 -332.799695) (xy 229.746448 -332.79114)
			(xy 229.735634 -332.7908) (xy 229.64775 -332.791816) (xy 229.627938 -332.801214) (xy 229.620826 -332.809596)
			(xy 229.602609 -332.830261) (xy 229.561262 -332.866659) (xy 229.515109 -332.896732) (xy 229.46511 -332.919854)
			(xy 229.412305 -332.935543) (xy 229.357793 -332.943474) (xy 229.33025 -332.943962) (xy 229.302998 -332.943565)
			(xy 229.249049 -332.935801) (xy 229.196754 -332.92044) (xy 229.147177 -332.897793) (xy 229.101327 -332.868322)
			(xy 229.060138 -332.832626) (xy 229.024448 -332.791433) (xy 228.994983 -332.745579) (xy 228.972342 -332.695999)
			(xy 228.956988 -332.643702) (xy 228.949232 -332.589752) (xy 178.76407 -332.589752) (xy 176.617893 -334.00746)
			(xy 225.00285 -334.00746) (xy 225.006921 -333.951838) (xy 225.019047 -333.897401) (xy 225.03897 -333.84531)
			(xy 225.066266 -333.796675) (xy 225.100352 -333.752532) (xy 225.140501 -333.713823) (xy 225.185859 -333.681372)
			(xy 225.235459 -333.655871) (xy 225.288243 -333.637864) (xy 225.343086 -333.627734) (xy 225.39882 -333.625697)
			(xy 225.454257 -333.631797) (xy 225.508214 -333.645903) (xy 225.559543 -333.667715) (xy 225.607149 -333.696769)
			(xy 225.650017 -333.732444) (xy 225.687234 -333.773981) (xy 225.718007 -333.820494) (xy 225.72409 -333.83347)
			(xy 225.95916 -333.83347) (xy 225.963231 -333.777848) (xy 225.975357 -333.723411) (xy 225.99528 -333.67132)
			(xy 226.022576 -333.622685) (xy 226.056662 -333.578542) (xy 226.096811 -333.539833) (xy 226.142169 -333.507382)
			(xy 226.191769 -333.481881) (xy 226.244553 -333.463874) (xy 226.299396 -333.453744) (xy 226.35513 -333.451707)
			(xy 226.410567 -333.457807) (xy 226.464524 -333.471913) (xy 226.515853 -333.493725) (xy 226.563459 -333.522779)
			(xy 226.606327 -333.558454) (xy 226.643544 -333.599991) (xy 226.674317 -333.646504) (xy 226.697989 -333.697001)
			(xy 226.714057 -333.750408) (xy 226.722177 -333.805584) (xy 226.722686 -333.83347) (xy 226.722177 -333.861356)
			(xy 226.714057 -333.916532) (xy 226.697989 -333.969939) (xy 226.674317 -334.020436) (xy 226.643544 -334.066949)
			(xy 226.606327 -334.108486) (xy 226.563459 -334.144161) (xy 226.515853 -334.173215) (xy 226.464524 -334.195027)
			(xy 226.410567 -334.209133) (xy 226.35513 -334.215233) (xy 226.299396 -334.213196) (xy 226.244553 -334.203066)
			(xy 226.191769 -334.185059) (xy 226.142169 -334.159558) (xy 226.096811 -334.127107) (xy 226.056662 -334.088398)
			(xy 226.022576 -334.044255) (xy 225.99528 -333.99562) (xy 225.975357 -333.943529) (xy 225.963231 -333.889092)
			(xy 225.95916 -333.83347) (xy 225.72409 -333.83347) (xy 225.741679 -333.870991) (xy 225.757747 -333.924398)
			(xy 225.765867 -333.979574) (xy 225.766376 -334.00746) (xy 225.765867 -334.035346) (xy 225.757747 -334.090522)
			(xy 225.741679 -334.143929) (xy 225.718007 -334.194426) (xy 225.687234 -334.240939) (xy 225.650017 -334.282476)
			(xy 225.607149 -334.318151) (xy 225.559543 -334.347205) (xy 225.511899 -334.367451) (xy 230.428778 -334.367451)
			(xy 230.428778 -334.312949) (xy 230.436534 -334.259001) (xy 230.451889 -334.206706) (xy 230.474531 -334.157129)
			(xy 230.503997 -334.111279) (xy 230.539688 -334.070088) (xy 230.580879 -334.034397) (xy 230.626729 -334.004931)
			(xy 230.676306 -333.982289) (xy 230.728601 -333.966934) (xy 230.782549 -333.959178) (xy 230.8098 -333.958692)
			(xy 230.837644 -333.959212) (xy 230.892732 -333.967366) (xy 230.919528 -333.974948) (xy 230.933923 -333.97882)
			(xy 230.963724 -333.978783) (xy 230.992248 -333.970151) (xy 231.017068 -333.953656) (xy 231.036074 -333.930703)
			(xy 231.047651 -333.903242) (xy 231.050812 -333.873609) (xy 231.04856 -333.85887) (xy 231.045567 -333.841563)
			(xy 231.042388 -333.806583) (xy 231.04221 -333.78902) (xy 231.042633 -333.761766) (xy 231.050388 -333.707811)
			(xy 231.065742 -333.65551) (xy 231.088383 -333.605926) (xy 231.117851 -333.560069) (xy 231.153544 -333.518872)
			(xy 231.194737 -333.483174) (xy 231.240591 -333.453702) (xy 231.290173 -333.431056) (xy 231.342473 -333.415696)
			(xy 231.396426 -333.407936) (xy 231.450935 -333.407934) (xy 231.504889 -333.415688) (xy 231.557191 -333.431042)
			(xy 231.606775 -333.453684) (xy 231.652632 -333.483151) (xy 231.693829 -333.518845) (xy 231.729526 -333.560038)
			(xy 231.758998 -333.605892) (xy 231.781644 -333.655474) (xy 231.797004 -333.707774) (xy 231.804764 -333.761727)
			(xy 231.804766 -333.816236) (xy 231.797012 -333.87019) (xy 231.781657 -333.922491) (xy 231.759016 -333.972075)
			(xy 231.729549 -334.017932) (xy 231.693855 -334.059129) (xy 231.652662 -334.094827) (xy 231.606808 -334.124298)
			(xy 231.557226 -334.146945) (xy 231.504926 -334.162304) (xy 231.450972 -334.170064) (xy 231.423718 -334.170528)
			(xy 231.395874 -334.170025) (xy 231.340786 -334.161859) (xy 231.31399 -334.154272) (xy 231.299572 -334.150513)
			(xy 231.269792 -334.150548) (xy 231.241287 -334.159169) (xy 231.21648 -334.175645) (xy 231.197478 -334.198575)
			(xy 231.185896 -334.22601) (xy 231.182718 -334.25562) (xy 231.184958 -334.27035) (xy 231.187953 -334.287656)
			(xy 231.191131 -334.322637) (xy 231.191308 -334.3402) (xy 231.190822 -334.367451) (xy 231.183066 -334.421399)
			(xy 231.167711 -334.473694) (xy 231.145069 -334.523271) (xy 231.115603 -334.569121) (xy 231.079912 -334.610312)
			(xy 231.038721 -334.646003) (xy 230.992871 -334.675469) (xy 230.943294 -334.698111) (xy 230.890999 -334.713466)
			(xy 230.837051 -334.721222) (xy 230.782549 -334.721222) (xy 230.728601 -334.713466) (xy 230.676306 -334.698111)
			(xy 230.626729 -334.675469) (xy 230.580879 -334.646003) (xy 230.539688 -334.610312) (xy 230.503997 -334.569121)
			(xy 230.474531 -334.523271) (xy 230.451889 -334.473694) (xy 230.436534 -334.421399) (xy 230.428778 -334.367451)
			(xy 225.511899 -334.367451) (xy 225.508214 -334.369017) (xy 225.454257 -334.383123) (xy 225.39882 -334.389223)
			(xy 225.343086 -334.387186) (xy 225.288243 -334.377056) (xy 225.235459 -334.359049) (xy 225.185859 -334.333548)
			(xy 225.140501 -334.301097) (xy 225.100352 -334.262388) (xy 225.066266 -334.218245) (xy 225.03897 -334.16961)
			(xy 225.019047 -334.117519) (xy 225.006921 -334.063082) (xy 225.00285 -334.00746) (xy 176.617893 -334.00746)
			(xy 174.40732 -335.467706) (xy 239.44656 -335.467706) (xy 239.450631 -335.412084) (xy 239.462757 -335.357647)
			(xy 239.48268 -335.305556) (xy 239.509976 -335.256921) (xy 239.544062 -335.212778) (xy 239.584211 -335.174069)
			(xy 239.629569 -335.141618) (xy 239.679169 -335.116117) (xy 239.731953 -335.09811) (xy 239.786796 -335.08798)
			(xy 239.84253 -335.085943) (xy 239.897967 -335.092043) (xy 239.951924 -335.106149) (xy 240.003253 -335.127961)
			(xy 240.050859 -335.157015) (xy 240.093727 -335.19269) (xy 240.130944 -335.234227) (xy 240.161717 -335.28074)
			(xy 240.185389 -335.331237) (xy 240.201457 -335.384644) (xy 240.209577 -335.43982) (xy 240.210086 -335.467706)
			(xy 240.210007 -335.472024) (xy 251.205236 -335.472024) (xy 251.209307 -335.416402) (xy 251.221433 -335.361965)
			(xy 251.241356 -335.309874) (xy 251.268652 -335.261239) (xy 251.302738 -335.217096) (xy 251.342887 -335.178387)
			(xy 251.388245 -335.145936) (xy 251.437845 -335.120435) (xy 251.490629 -335.102428) (xy 251.545472 -335.092298)
			(xy 251.601206 -335.090261) (xy 251.656643 -335.096361) (xy 251.7106 -335.110467) (xy 251.761929 -335.132279)
			(xy 251.809535 -335.161333) (xy 251.852403 -335.197008) (xy 251.88962 -335.238545) (xy 251.920393 -335.285058)
			(xy 251.944065 -335.335555) (xy 251.960133 -335.388962) (xy 251.968253 -335.444138) (xy 251.968762 -335.472024)
			(xy 251.968253 -335.49991) (xy 251.960133 -335.555086) (xy 251.944065 -335.608493) (xy 251.920393 -335.65899)
			(xy 251.88962 -335.705503) (xy 251.852403 -335.74704) (xy 251.809535 -335.782715) (xy 251.761929 -335.811769)
			(xy 251.7106 -335.833581) (xy 251.656643 -335.847687) (xy 251.601206 -335.853787) (xy 251.545472 -335.85175)
			(xy 251.490629 -335.84162) (xy 251.437845 -335.823613) (xy 251.388245 -335.798112) (xy 251.342887 -335.765661)
			(xy 251.302738 -335.726952) (xy 251.268652 -335.682809) (xy 251.241356 -335.634174) (xy 251.221433 -335.582083)
			(xy 251.209307 -335.527646) (xy 251.205236 -335.472024) (xy 240.210007 -335.472024) (xy 240.209577 -335.495592)
			(xy 240.201457 -335.550768) (xy 240.185389 -335.604175) (xy 240.161717 -335.654672) (xy 240.130944 -335.701185)
			(xy 240.093727 -335.742722) (xy 240.050859 -335.778397) (xy 240.003253 -335.807451) (xy 239.951924 -335.829263)
			(xy 239.897967 -335.843369) (xy 239.84253 -335.849469) (xy 239.786796 -335.847432) (xy 239.731953 -335.837302)
			(xy 239.679169 -335.819295) (xy 239.629569 -335.793794) (xy 239.584211 -335.761343) (xy 239.544062 -335.722634)
			(xy 239.509976 -335.678491) (xy 239.48268 -335.629856) (xy 239.462757 -335.577765) (xy 239.450631 -335.523328)
			(xy 239.44656 -335.467706) (xy 174.40732 -335.467706) (xy 173.351444 -336.16519) (xy 173.34992 -336.16646)
			(xy 171.885363 -337.266026) (xy 234.403392 -337.266026) (xy 234.403392 -336.402426) (xy 234.403882 -336.372458)
			(xy 234.411705 -336.313036) (xy 234.427218 -336.255143) (xy 234.450154 -336.19977) (xy 234.480121 -336.147864)
			(xy 234.516608 -336.100314) (xy 234.558988 -336.057934) (xy 234.606538 -336.021447) (xy 234.658444 -335.99148)
			(xy 234.713817 -335.968544) (xy 234.77171 -335.953031) (xy 234.831132 -335.945208) (xy 234.891068 -335.945208)
			(xy 234.95049 -335.953031) (xy 235.008383 -335.968544) (xy 235.063756 -335.99148) (xy 235.115662 -336.021447)
			(xy 235.163212 -336.057934) (xy 235.205592 -336.100314) (xy 235.242079 -336.147864) (xy 235.272046 -336.19977)
			(xy 235.294982 -336.255143) (xy 235.310495 -336.313036) (xy 235.318318 -336.372458) (xy 235.318808 -336.402426)
			(xy 235.318808 -336.55889) (xy 240.234214 -336.55889) (xy 240.238285 -336.503268) (xy 240.250411 -336.448831)
			(xy 240.270334 -336.39674) (xy 240.29763 -336.348105) (xy 240.331716 -336.303962) (xy 240.371865 -336.265253)
			(xy 240.417223 -336.232802) (xy 240.466823 -336.207301) (xy 240.519607 -336.189294) (xy 240.57445 -336.179164)
			(xy 240.630184 -336.177127) (xy 240.685621 -336.183227) (xy 240.739578 -336.197333) (xy 240.790907 -336.219145)
			(xy 240.838513 -336.248199) (xy 240.881381 -336.283874) (xy 240.918598 -336.325411) (xy 240.949371 -336.371924)
			(xy 240.973043 -336.422421) (xy 240.989111 -336.475828) (xy 240.997231 -336.531004) (xy 240.99774 -336.55889)
			(xy 240.997231 -336.586776) (xy 240.989111 -336.641952) (xy 240.973043 -336.695359) (xy 240.949371 -336.745856)
			(xy 240.918598 -336.792369) (xy 240.881381 -336.833906) (xy 240.838513 -336.869581) (xy 240.790907 -336.898635)
			(xy 240.739578 -336.920447) (xy 240.685621 -336.934553) (xy 240.630184 -336.940653) (xy 240.57445 -336.938616)
			(xy 240.519607 -336.928486) (xy 240.466823 -336.910479) (xy 240.417223 -336.884978) (xy 240.371865 -336.852527)
			(xy 240.331716 -336.813818) (xy 240.29763 -336.769675) (xy 240.270334 -336.72104) (xy 240.250411 -336.668949)
			(xy 240.238285 -336.614512) (xy 240.234214 -336.55889) (xy 235.318808 -336.55889) (xy 235.318808 -337.070192)
			(xy 251.234194 -337.070192) (xy 251.234658 -337.043878) (xy 251.241894 -336.991749) (xy 251.256214 -336.941107)
			(xy 251.277347 -336.892908) (xy 251.304893 -336.848064) (xy 251.338332 -336.807425) (xy 251.357384 -336.789268)
			(xy 251.364799 -336.781758) (xy 251.373316 -336.762469) (xy 251.373894 -336.75193) (xy 251.373894 -336.677254)
			(xy 251.373351 -336.666706) (xy 251.364826 -336.64741) (xy 251.357384 -336.639916) (xy 251.33834 -336.621749)
			(xy 251.304883 -336.581121) (xy 251.277322 -336.536283) (xy 251.256182 -336.488085) (xy 251.241862 -336.43744)
			(xy 251.234634 -336.385307) (xy 251.234194 -336.358992) (xy 251.23467 -336.33174) (xy 251.242428 -336.277792)
			(xy 251.257784 -336.225497) (xy 251.280426 -336.17592) (xy 251.309894 -336.130069) (xy 251.345586 -336.088879)
			(xy 251.386777 -336.053188) (xy 251.432629 -336.023722) (xy 251.482207 -336.001081) (xy 251.534502 -335.985726)
			(xy 251.58845 -335.97797) (xy 251.615702 -335.977484) (xy 251.642016 -335.977955) (xy 251.694144 -335.98519)
			(xy 251.744786 -335.999509) (xy 251.792985 -336.02064) (xy 251.837829 -336.048186) (xy 251.878469 -336.081623)
			(xy 251.896626 -336.100674) (xy 251.904139 -336.108085) (xy 251.923426 -336.116605) (xy 251.933964 -336.117184)
			(xy 252.00864 -336.117184) (xy 252.019188 -336.116641) (xy 252.038484 -336.108116) (xy 252.045978 -336.100674)
			(xy 252.065798 -336.079886) (xy 252.11057 -336.043911) (xy 252.160228 -336.015051) (xy 252.21365 -335.993958)
			(xy 252.269629 -335.981109) (xy 252.326902 -335.976794) (xy 252.384175 -335.981109) (xy 252.440154 -335.993958)
			(xy 252.493576 -336.015051) (xy 252.543234 -336.043911) (xy 252.588006 -336.079886) (xy 252.607826 -336.100674)
			(xy 252.615339 -336.108085) (xy 252.634626 -336.116605) (xy 252.645164 -336.117184) (xy 252.71984 -336.117184)
			(xy 252.730388 -336.116641) (xy 252.749684 -336.108116) (xy 252.757178 -336.100674) (xy 252.775346 -336.081631)
			(xy 252.815974 -336.048174) (xy 252.860812 -336.020614) (xy 252.90901 -335.999473) (xy 252.959655 -335.985153)
			(xy 253.011787 -335.977925) (xy 253.038102 -335.977484) (xy 253.065353 -335.977976) (xy 253.1193 -335.985732)
			(xy 253.171594 -336.001087) (xy 253.221171 -336.023728) (xy 253.267021 -336.053194) (xy 253.308211 -336.088885)
			(xy 253.343902 -336.130074) (xy 253.373369 -336.175924) (xy 253.39601 -336.2255) (xy 253.411366 -336.277794)
			(xy 253.419124 -336.331741) (xy 253.41961 -336.358992) (xy 253.419134 -336.385306) (xy 253.4119 -336.437434)
			(xy 253.397583 -336.488076) (xy 253.376452 -336.536275) (xy 253.348908 -336.581119) (xy 253.315471 -336.621759)
			(xy 253.29642 -336.639916) (xy 253.289012 -336.647432) (xy 253.280491 -336.666716) (xy 253.27991 -336.677254)
			(xy 253.27991 -336.75193) (xy 253.280461 -336.762477) (xy 253.28898 -336.781773) (xy 253.29642 -336.789268)
			(xy 253.315505 -336.807394) (xy 253.348959 -336.84803) (xy 253.376514 -336.892877) (xy 253.397647 -336.941083)
			(xy 253.411958 -336.991736) (xy 253.419175 -337.043874) (xy 253.41961 -337.070192) (xy 253.419137 -337.097445)
			(xy 253.411381 -337.151395) (xy 253.396026 -337.203693) (xy 253.373385 -337.253273) (xy 253.343918 -337.299126)
			(xy 253.308225 -337.340318) (xy 253.267034 -337.376012) (xy 253.221181 -337.40548) (xy 253.171602 -337.428123)
			(xy 253.119305 -337.443479) (xy 253.065355 -337.451237) (xy 253.038102 -337.4517) (xy 253.011788 -337.451231)
			(xy 252.95966 -337.443997) (xy 252.909017 -337.429678) (xy 252.860818 -337.408546) (xy 252.815974 -337.381)
			(xy 252.775335 -337.347561) (xy 252.757178 -337.32851) (xy 252.749665 -337.321098) (xy 252.730379 -337.312579)
			(xy 252.71984 -337.312) (xy 252.645164 -337.312) (xy 252.634617 -337.31255) (xy 252.615321 -337.321071)
			(xy 252.607826 -337.32851) (xy 252.588006 -337.349298) (xy 252.543234 -337.385273) (xy 252.493576 -337.414133)
			(xy 252.440154 -337.435226) (xy 252.384175 -337.448075) (xy 252.326902 -337.45239) (xy 252.269629 -337.448075)
			(xy 252.21365 -337.435226) (xy 252.160228 -337.414133) (xy 252.11057 -337.385273) (xy 252.065798 -337.349298)
			(xy 252.045978 -337.32851) (xy 252.038465 -337.321098) (xy 252.019179 -337.312579) (xy 252.00864 -337.312)
			(xy 251.933964 -337.312) (xy 251.923417 -337.31255) (xy 251.904121 -337.321071) (xy 251.896626 -337.32851)
			(xy 251.878453 -337.347548) (xy 251.837827 -337.381006) (xy 251.79299 -337.408567) (xy 251.744793 -337.429709)
			(xy 251.694148 -337.44403) (xy 251.642017 -337.451259) (xy 251.615702 -337.4517) (xy 251.588449 -337.451243)
			(xy 251.534497 -337.443486) (xy 251.482199 -337.42813) (xy 251.432618 -337.405487) (xy 251.386765 -337.376018)
			(xy 251.345572 -337.340324) (xy 251.309878 -337.299131) (xy 251.28041 -337.253277) (xy 251.257768 -337.203696)
			(xy 251.242413 -337.151397) (xy 251.234657 -337.097445) (xy 251.234194 -337.070192) (xy 235.318808 -337.070192)
			(xy 235.318808 -337.266026) (xy 235.318318 -337.295994) (xy 235.310495 -337.355416) (xy 235.294982 -337.413309)
			(xy 235.272046 -337.468682) (xy 235.242079 -337.520588) (xy 235.205592 -337.568138) (xy 235.163212 -337.610518)
			(xy 235.115662 -337.647005) (xy 235.063756 -337.676972) (xy 235.008383 -337.699908) (xy 234.95049 -337.715421)
			(xy 234.891068 -337.723244) (xy 234.831132 -337.723244) (xy 234.77171 -337.715421) (xy 234.713817 -337.699908)
			(xy 234.658444 -337.676972) (xy 234.606538 -337.647005) (xy 234.558988 -337.610518) (xy 234.516608 -337.568138)
			(xy 234.480121 -337.520588) (xy 234.450154 -337.468682) (xy 234.427218 -337.413309) (xy 234.411705 -337.355416)
			(xy 234.403882 -337.295994) (xy 234.403392 -337.266026) (xy 171.885363 -337.266026) (xy 169.7841 -338.84362)
			(xy 201.544174 -338.84362) (xy 201.544663 -338.817307) (xy 201.551895 -338.76518) (xy 201.56621 -338.714538)
			(xy 201.587339 -338.666339) (xy 201.61488 -338.621495) (xy 201.648315 -338.580854) (xy 201.667364 -338.562696)
			(xy 201.674764 -338.555173) (xy 201.683291 -338.535894) (xy 201.683874 -338.525358) (xy 201.683874 -338.450682)
			(xy 201.683322 -338.440135) (xy 201.674804 -338.420839) (xy 201.667364 -338.413344) (xy 201.648281 -338.395216)
			(xy 201.614828 -338.354579) (xy 201.587274 -338.309733) (xy 201.56614 -338.261527) (xy 201.551828 -338.210875)
			(xy 201.544609 -338.158738) (xy 201.544174 -338.13242) (xy 201.54466 -338.105169) (xy 201.552416 -338.051221)
			(xy 201.567771 -337.998926) (xy 201.590413 -337.949349) (xy 201.619879 -337.903499) (xy 201.65557 -337.862308)
			(xy 201.696761 -337.826617) (xy 201.742611 -337.797151) (xy 201.792188 -337.774509) (xy 201.844483 -337.759154)
			(xy 201.898431 -337.751398) (xy 201.952933 -337.751398) (xy 202.006881 -337.759154) (xy 202.059176 -337.774509)
			(xy 202.108753 -337.797151) (xy 202.154603 -337.826617) (xy 202.195794 -337.862308) (xy 202.231485 -337.903499)
			(xy 202.260951 -337.949349) (xy 202.283593 -337.998926) (xy 202.298948 -338.051221) (xy 202.306704 -338.105169)
			(xy 202.30719 -338.13242) (xy 202.306739 -338.158735) (xy 202.299501 -338.210864) (xy 202.285179 -338.261507)
			(xy 202.264044 -338.309706) (xy 202.236495 -338.354549) (xy 202.203053 -338.395188) (xy 202.184 -338.413344)
			(xy 202.176577 -338.420847) (xy 202.168065 -338.440141) (xy 202.16749 -338.450682) (xy 202.16749 -338.525358)
			(xy 202.168031 -338.535906) (xy 202.176558 -338.555202) (xy 202.184 -338.562696) (xy 202.203047 -338.580861)
			(xy 202.236505 -338.621488) (xy 202.264065 -338.666327) (xy 202.285205 -338.714526) (xy 202.299524 -338.765172)
			(xy 202.30675 -338.817304) (xy 202.30719 -338.84362) (xy 202.306704 -338.870871) (xy 202.298948 -338.924819)
			(xy 202.283593 -338.977114) (xy 202.260951 -339.026691) (xy 202.231485 -339.072541) (xy 202.195794 -339.113732)
			(xy 202.154603 -339.149423) (xy 202.108753 -339.178889) (xy 202.059176 -339.201531) (xy 202.006881 -339.216886)
			(xy 201.952933 -339.224642) (xy 201.898431 -339.224642) (xy 201.844483 -339.216886) (xy 201.792188 -339.201531)
			(xy 201.742611 -339.178889) (xy 201.696761 -339.149423) (xy 201.65557 -339.113732) (xy 201.619879 -339.072541)
			(xy 201.590413 -339.026691) (xy 201.567771 -338.977114) (xy 201.552416 -338.924819) (xy 201.54466 -338.870871)
			(xy 201.544174 -338.84362) (xy 169.7841 -338.84362) (xy 167.030908 -340.910672) (xy 167.028114 -340.912704)
			(xy 166.803324 -341.115396) (xy 166.626794 -341.275924) (xy 166.62527 -341.277448) (xy 166.10327 -341.799448)
			(xy 231.047318 -341.799448) (xy 231.047318 -341.744952) (xy 231.055074 -341.691011) (xy 231.070427 -341.638723)
			(xy 231.093065 -341.589151) (xy 231.122527 -341.543306) (xy 231.158213 -341.502121) (xy 231.199398 -341.466433)
			(xy 231.245242 -341.436969) (xy 231.294813 -341.41433) (xy 231.347101 -341.398976) (xy 231.401042 -341.391219)
			(xy 231.42829 -341.390732) (xy 231.456426 -341.391179) (xy 231.51209 -341.399433) (xy 231.565936 -341.415778)
			(xy 231.616795 -341.439859) (xy 231.663563 -341.471153) (xy 231.705224 -341.508981) (xy 231.723438 -341.530432)
			(xy 231.730819 -341.538715) (xy 231.750723 -341.548461) (xy 231.761792 -341.549228) (xy 231.850438 -341.550752)
			(xy 231.870758 -341.541862) (xy 231.878124 -341.53348) (xy 231.896316 -341.513539) (xy 231.937357 -341.478478)
			(xy 231.982928 -341.449551) (xy 232.032122 -341.427334) (xy 232.083955 -341.412271) (xy 232.137393 -341.404662)
			(xy 232.164382 -341.404194) (xy 232.191636 -341.404652) (xy 232.245589 -341.412407) (xy 232.297889 -341.427762)
			(xy 232.347472 -341.450403) (xy 232.393328 -341.479871) (xy 232.434523 -341.515565) (xy 232.470218 -341.556758)
			(xy 232.499688 -341.602612) (xy 232.522332 -341.652194) (xy 232.537689 -341.704493) (xy 232.545447 -341.758446)
			(xy 232.545447 -341.812954) (xy 232.537689 -341.866907) (xy 232.522332 -341.919206) (xy 232.499688 -341.968788)
			(xy 232.470218 -342.014642) (xy 232.434523 -342.055835) (xy 232.393328 -342.091529) (xy 232.347472 -342.120997)
			(xy 232.297889 -342.143638) (xy 232.245589 -342.158993) (xy 232.191636 -342.166748) (xy 232.164382 -342.16721)
			(xy 232.136248 -342.166698) (xy 232.080588 -342.158455) (xy 232.026744 -342.142122) (xy 231.975885 -342.118053)
			(xy 231.929115 -342.086771) (xy 231.887451 -342.048955) (xy 231.869234 -342.02751) (xy 231.861858 -342.019221)
			(xy 231.84195 -342.009477) (xy 231.83088 -342.008714) (xy 231.742234 -342.00719) (xy 231.721914 -342.01608)
			(xy 231.714548 -342.024462) (xy 231.696358 -342.044406) (xy 231.655318 -342.079468) (xy 231.609747 -342.108397)
			(xy 231.560553 -342.130614) (xy 231.508719 -342.145676) (xy 231.455279 -342.153282) (xy 231.42829 -342.153748)
			(xy 231.401042 -342.153181) (xy 231.347101 -342.145424) (xy 231.294813 -342.13007) (xy 231.245242 -342.107431)
			(xy 231.199398 -342.077967) (xy 231.158213 -342.042279) (xy 231.122527 -342.001094) (xy 231.093065 -341.955249)
			(xy 231.070427 -341.905677) (xy 231.055074 -341.853389) (xy 231.047318 -341.799448) (xy 166.10327 -341.799448)
			(xy 165.994588 -341.90813) (xy 165.985213 -341.918141) (xy 165.971689 -341.941989) (xy 165.964994 -341.968574)
			(xy 165.965611 -341.995983) (xy 165.973496 -342.02224) (xy 165.980364 -342.034114) (xy 165.985236 -342.041201)
			(xy 165.998706 -342.051874) (xy 166.01495 -342.057486) (xy 166.023544 -342.057736) (xy 166.158672 -342.057736)
			(xy 166.190459 -342.05841) (xy 166.253146 -342.069) (xy 166.283386 -342.078818) (xy 166.291514 -342.081612)
			(xy 166.412672 -342.081612) (xy 166.442469 -342.082203) (xy 166.501334 -342.091493) (xy 166.558045 -342.109804)
			(xy 166.584884 -342.12276) (xy 166.594047 -342.126906) (xy 166.61409 -342.128361) (xy 166.623746 -342.125554)
			(xy 166.649002 -342.11773) (xy 166.701197 -342.109306) (xy 166.727632 -342.10879) (xy 166.753618 -342.109302)
			(xy 166.804949 -342.117437) (xy 166.854375 -342.1335) (xy 166.900681 -342.157098) (xy 166.942725 -342.187649)
			(xy 166.979472 -342.2244) (xy 167.010019 -342.266447) (xy 167.033612 -342.312754) (xy 167.049671 -342.362183)
			(xy 167.057801 -342.413514) (xy 167.057801 -342.465486) (xy 167.057597 -342.466773) (xy 168.0227 -342.466773)
			(xy 168.0227 -342.412227) (xy 168.030463 -342.358237) (xy 168.045831 -342.305902) (xy 168.068491 -342.256286)
			(xy 168.097981 -342.210401) (xy 168.133702 -342.16918) (xy 168.174927 -342.133462) (xy 168.220815 -342.103975)
			(xy 168.270432 -342.081319) (xy 168.322769 -342.065956) (xy 168.376759 -342.058197) (xy 168.404032 -342.057736)
			(xy 169.267632 -342.057736) (xy 169.2949 -342.058229) (xy 169.34888 -342.065994) (xy 169.401205 -342.081362)
			(xy 169.450811 -342.10402) (xy 169.496688 -342.133506) (xy 169.537901 -342.169222) (xy 169.573613 -342.210438)
			(xy 169.603095 -342.256317) (xy 169.625749 -342.305925) (xy 169.641113 -342.358252) (xy 169.648874 -342.412232)
			(xy 169.648874 -342.466768) (xy 169.648874 -342.466769) (xy 171.131722 -342.466769) (xy 171.131722 -342.412231)
			(xy 171.139484 -342.358248) (xy 171.154849 -342.305918) (xy 171.177505 -342.256309) (xy 171.20699 -342.210428)
			(xy 171.242705 -342.16921) (xy 171.283921 -342.133495) (xy 171.329802 -342.104009) (xy 171.379411 -342.081352)
			(xy 171.43174 -342.065986) (xy 171.485723 -342.058223) (xy 171.512992 -342.057736) (xy 172.376592 -342.057736)
			(xy 172.403863 -342.058203) (xy 172.457851 -342.065964) (xy 172.510184 -342.08133) (xy 172.559798 -342.103987)
			(xy 172.605682 -342.133474) (xy 172.646903 -342.169191) (xy 172.682621 -342.210411) (xy 172.71211 -342.256295)
			(xy 172.734768 -342.305908) (xy 172.750134 -342.358241) (xy 172.757896 -342.412229) (xy 172.757896 -342.466767)
			(xy 174.240722 -342.466767) (xy 174.240722 -342.412233) (xy 174.248483 -342.358253) (xy 174.263846 -342.305927)
			(xy 174.286499 -342.25632) (xy 174.31598 -342.210441) (xy 174.35169 -342.169224) (xy 174.392902 -342.133509)
			(xy 174.438778 -342.104022) (xy 174.488382 -342.081363) (xy 174.540706 -342.065993) (xy 174.594685 -342.058226)
			(xy 174.621952 -342.057736) (xy 175.485552 -342.057736) (xy 175.512825 -342.0582) (xy 175.566817 -342.065957)
			(xy 175.619155 -342.081319) (xy 175.668774 -342.103974) (xy 175.714663 -342.13346) (xy 175.755889 -342.169177)
			(xy 175.791612 -342.210398) (xy 175.821103 -342.256284) (xy 175.843764 -342.3059) (xy 175.859133 -342.358236)
			(xy 175.866896 -342.412227) (xy 175.866896 -342.466772) (xy 177.3496 -342.466772) (xy 177.3496 -342.412228)
			(xy 177.357362 -342.35824) (xy 177.372729 -342.305906) (xy 177.395388 -342.256292) (xy 177.424876 -342.210407)
			(xy 177.460595 -342.169187) (xy 177.501817 -342.133469) (xy 177.547703 -342.103982) (xy 177.597317 -342.081325)
			(xy 177.649652 -342.065959) (xy 177.70364 -342.058199) (xy 177.730912 -342.057736) (xy 178.594512 -342.057736)
			(xy 178.621781 -342.058227) (xy 178.675763 -342.06599) (xy 178.728091 -342.081357) (xy 178.777699 -342.104013)
			(xy 178.823578 -342.133499) (xy 178.864794 -342.169214) (xy 178.900508 -342.210432) (xy 178.929992 -342.256312)
			(xy 178.952648 -342.305921) (xy 178.968012 -342.358249) (xy 178.975774 -342.412231) (xy 178.975774 -342.466768)
			(xy 180.458622 -342.466768) (xy 180.458622 -342.412232) (xy 180.466383 -342.35825) (xy 180.481747 -342.305923)
			(xy 180.504402 -342.256314) (xy 180.533885 -342.210434) (xy 180.569597 -342.169217) (xy 180.610812 -342.133502)
			(xy 180.65669 -342.104015) (xy 180.706296 -342.081357) (xy 180.758623 -342.065989) (xy 180.812604 -342.058224)
			(xy 180.839872 -342.057736) (xy 181.703472 -342.057736) (xy 181.730744 -342.058202) (xy 181.784734 -342.06596)
			(xy 181.83707 -342.081324) (xy 181.886686 -342.10398) (xy 181.932573 -342.133467) (xy 181.973796 -342.169184)
			(xy 182.009516 -342.210405) (xy 182.039007 -342.256289) (xy 182.061666 -342.305904) (xy 182.077034 -342.358239)
			(xy 182.084796 -342.412228) (xy 182.084796 -342.466772) (xy 182.084796 -342.466773) (xy 183.5675 -342.466773)
			(xy 183.5675 -342.412227) (xy 183.575263 -342.358237) (xy 183.590631 -342.305902) (xy 183.613291 -342.256286)
			(xy 183.642781 -342.210401) (xy 183.678502 -342.16918) (xy 183.719727 -342.133462) (xy 183.765615 -342.103975)
			(xy 183.815232 -342.081319) (xy 183.867569 -342.065956) (xy 183.921559 -342.058197) (xy 183.948832 -342.057736)
			(xy 184.812432 -342.057736) (xy 184.8397 -342.058229) (xy 184.89368 -342.065994) (xy 184.946005 -342.081362)
			(xy 184.995611 -342.10402) (xy 185.041488 -342.133506) (xy 185.082701 -342.169222) (xy 185.118413 -342.210438)
			(xy 185.147895 -342.256317) (xy 185.170549 -342.305925) (xy 185.185913 -342.358252) (xy 185.193674 -342.412232)
			(xy 185.193674 -342.466768) (xy 185.193674 -342.466769) (xy 186.676522 -342.466769) (xy 186.676522 -342.412231)
			(xy 186.684284 -342.358248) (xy 186.699649 -342.305918) (xy 186.722305 -342.256309) (xy 186.75179 -342.210428)
			(xy 186.787505 -342.16921) (xy 186.828721 -342.133495) (xy 186.874602 -342.104009) (xy 186.924211 -342.081352)
			(xy 186.97654 -342.065986) (xy 187.030523 -342.058223) (xy 187.057792 -342.057736) (xy 187.921392 -342.057736)
			(xy 187.948663 -342.058203) (xy 188.002651 -342.065964) (xy 188.054984 -342.08133) (xy 188.104598 -342.103987)
			(xy 188.150482 -342.133474) (xy 188.191703 -342.169191) (xy 188.227421 -342.210411) (xy 188.25691 -342.256295)
			(xy 188.279568 -342.305908) (xy 188.294934 -342.358241) (xy 188.302696 -342.412229) (xy 188.302696 -342.466767)
			(xy 189.785522 -342.466767) (xy 189.785522 -342.412233) (xy 189.793283 -342.358253) (xy 189.808646 -342.305927)
			(xy 189.831299 -342.25632) (xy 189.86078 -342.210441) (xy 189.89649 -342.169224) (xy 189.937702 -342.133509)
			(xy 189.983578 -342.104022) (xy 190.033182 -342.081363) (xy 190.085506 -342.065993) (xy 190.139485 -342.058226)
			(xy 190.166752 -342.057736) (xy 191.030352 -342.057736) (xy 191.057625 -342.0582) (xy 191.111617 -342.065957)
			(xy 191.163955 -342.081319) (xy 191.213574 -342.103974) (xy 191.259463 -342.13346) (xy 191.300689 -342.169177)
			(xy 191.336412 -342.210398) (xy 191.365903 -342.256284) (xy 191.388564 -342.3059) (xy 191.403933 -342.358236)
			(xy 191.411696 -342.412227) (xy 191.411696 -342.466772) (xy 192.8944 -342.466772) (xy 192.8944 -342.412228)
			(xy 192.902162 -342.35824) (xy 192.917529 -342.305906) (xy 192.940188 -342.256292) (xy 192.969676 -342.210407)
			(xy 193.005395 -342.169187) (xy 193.046617 -342.133469) (xy 193.092503 -342.103982) (xy 193.142117 -342.081325)
			(xy 193.194452 -342.065959) (xy 193.24844 -342.058199) (xy 193.275712 -342.057736) (xy 194.139312 -342.057736)
			(xy 194.166581 -342.058227) (xy 194.220563 -342.06599) (xy 194.272891 -342.081357) (xy 194.322499 -342.104013)
			(xy 194.368378 -342.133499) (xy 194.409594 -342.169214) (xy 194.445308 -342.210432) (xy 194.474792 -342.256312)
			(xy 194.497448 -342.305921) (xy 194.512812 -342.358249) (xy 194.520574 -342.412231) (xy 194.520574 -342.466768)
			(xy 196.003422 -342.466768) (xy 196.003422 -342.412232) (xy 196.011183 -342.35825) (xy 196.026547 -342.305923)
			(xy 196.049202 -342.256314) (xy 196.078685 -342.210434) (xy 196.114397 -342.169217) (xy 196.155612 -342.133502)
			(xy 196.20149 -342.104015) (xy 196.251096 -342.081357) (xy 196.303423 -342.065989) (xy 196.357404 -342.058224)
			(xy 196.384672 -342.057736) (xy 197.248272 -342.057736) (xy 197.275544 -342.058202) (xy 197.329534 -342.06596)
			(xy 197.38187 -342.081324) (xy 197.431486 -342.10398) (xy 197.477373 -342.133467) (xy 197.518596 -342.169184)
			(xy 197.554316 -342.210405) (xy 197.583807 -342.256289) (xy 197.606466 -342.305904) (xy 197.621834 -342.358239)
			(xy 197.629596 -342.412228) (xy 197.629596 -342.466772) (xy 197.621834 -342.520761) (xy 197.606466 -342.573096)
			(xy 197.583807 -342.622711) (xy 197.554316 -342.668595) (xy 197.518596 -342.709816) (xy 197.477373 -342.745533)
			(xy 197.431486 -342.77502) (xy 197.38187 -342.797676) (xy 197.329534 -342.81304) (xy 197.275544 -342.820798)
			(xy 197.248272 -342.82126) (xy 196.384672 -342.82126) (xy 196.357404 -342.820776) (xy 196.303423 -342.813011)
			(xy 196.251096 -342.797643) (xy 196.20149 -342.774985) (xy 196.155612 -342.745498) (xy 196.114397 -342.709783)
			(xy 196.078685 -342.668566) (xy 196.049202 -342.622686) (xy 196.026547 -342.573077) (xy 196.011183 -342.52075)
			(xy 196.003422 -342.466768) (xy 194.520574 -342.466768) (xy 194.520574 -342.466769) (xy 194.512812 -342.520751)
			(xy 194.497448 -342.573079) (xy 194.474792 -342.622688) (xy 194.445308 -342.668568) (xy 194.409594 -342.709786)
			(xy 194.368378 -342.745501) (xy 194.322499 -342.774987) (xy 194.272891 -342.797643) (xy 194.220563 -342.81301)
			(xy 194.166581 -342.820773) (xy 194.139312 -342.82126) (xy 193.275712 -342.82126) (xy 193.24844 -342.820801)
			(xy 193.194452 -342.813041) (xy 193.142117 -342.797675) (xy 193.092503 -342.775018) (xy 193.046617 -342.745531)
			(xy 193.005395 -342.709813) (xy 192.969676 -342.668593) (xy 192.940188 -342.622708) (xy 192.917529 -342.573094)
			(xy 192.902162 -342.52076) (xy 192.8944 -342.466772) (xy 191.411696 -342.466772) (xy 191.411696 -342.466773)
			(xy 191.403933 -342.520764) (xy 191.388564 -342.5731) (xy 191.365903 -342.622716) (xy 191.336412 -342.668602)
			(xy 191.300689 -342.709823) (xy 191.259463 -342.74554) (xy 191.213574 -342.775026) (xy 191.163955 -342.797681)
			(xy 191.111617 -342.813043) (xy 191.057625 -342.8208) (xy 191.030352 -342.82126) (xy 190.166752 -342.82126)
			(xy 190.139485 -342.820774) (xy 190.085506 -342.813007) (xy 190.033182 -342.797637) (xy 189.983578 -342.774978)
			(xy 189.937702 -342.745491) (xy 189.89649 -342.709776) (xy 189.86078 -342.668559) (xy 189.831299 -342.62268)
			(xy 189.808646 -342.573073) (xy 189.793283 -342.520747) (xy 189.785522 -342.466767) (xy 188.302696 -342.466767)
			(xy 188.302696 -342.466771) (xy 188.294934 -342.520759) (xy 188.279568 -342.573092) (xy 188.25691 -342.622705)
			(xy 188.227421 -342.668589) (xy 188.191703 -342.709809) (xy 188.150482 -342.745526) (xy 188.104598 -342.775013)
			(xy 188.054984 -342.79767) (xy 188.002651 -342.813036) (xy 187.948663 -342.820797) (xy 187.921392 -342.82126)
			(xy 187.057792 -342.82126) (xy 187.030523 -342.820777) (xy 186.97654 -342.813014) (xy 186.924211 -342.797648)
			(xy 186.874602 -342.774991) (xy 186.828721 -342.745505) (xy 186.787505 -342.70979) (xy 186.75179 -342.668572)
			(xy 186.722305 -342.622691) (xy 186.699649 -342.573082) (xy 186.684284 -342.520752) (xy 186.676522 -342.466769)
			(xy 185.193674 -342.466769) (xy 185.185913 -342.520748) (xy 185.170549 -342.573075) (xy 185.147895 -342.622683)
			(xy 185.118413 -342.668562) (xy 185.082701 -342.709778) (xy 185.041488 -342.745494) (xy 184.995611 -342.77498)
			(xy 184.946005 -342.797638) (xy 184.89368 -342.813006) (xy 184.8397 -342.820771) (xy 184.812432 -342.82126)
			(xy 183.948832 -342.82126) (xy 183.921559 -342.820803) (xy 183.867569 -342.813044) (xy 183.815232 -342.797681)
			(xy 183.765615 -342.775025) (xy 183.719727 -342.745538) (xy 183.678502 -342.70982) (xy 183.642781 -342.668599)
			(xy 183.613291 -342.622714) (xy 183.590631 -342.573098) (xy 183.575263 -342.520763) (xy 183.5675 -342.466773)
			(xy 182.084796 -342.466773) (xy 182.077034 -342.520761) (xy 182.061666 -342.573096) (xy 182.039007 -342.622711)
			(xy 182.009516 -342.668595) (xy 181.973796 -342.709816) (xy 181.932573 -342.745533) (xy 181.886686 -342.77502)
			(xy 181.83707 -342.797676) (xy 181.784734 -342.81304) (xy 181.730744 -342.820798) (xy 181.703472 -342.82126)
			(xy 180.839872 -342.82126) (xy 180.812604 -342.820776) (xy 180.758623 -342.813011) (xy 180.706296 -342.797643)
			(xy 180.65669 -342.774985) (xy 180.610812 -342.745498) (xy 180.569597 -342.709783) (xy 180.533885 -342.668566)
			(xy 180.504402 -342.622686) (xy 180.481747 -342.573077) (xy 180.466383 -342.52075) (xy 180.458622 -342.466768)
			(xy 178.975774 -342.466768) (xy 178.975774 -342.466769) (xy 178.968012 -342.520751) (xy 178.952648 -342.573079)
			(xy 178.929992 -342.622688) (xy 178.900508 -342.668568) (xy 178.864794 -342.709786) (xy 178.823578 -342.745501)
			(xy 178.777699 -342.774987) (xy 178.728091 -342.797643) (xy 178.675763 -342.81301) (xy 178.621781 -342.820773)
			(xy 178.594512 -342.82126) (xy 177.730912 -342.82126) (xy 177.70364 -342.820801) (xy 177.649652 -342.813041)
			(xy 177.597317 -342.797675) (xy 177.547703 -342.775018) (xy 177.501817 -342.745531) (xy 177.460595 -342.709813)
			(xy 177.424876 -342.668593) (xy 177.395388 -342.622708) (xy 177.372729 -342.573094) (xy 177.357362 -342.52076)
			(xy 177.3496 -342.466772) (xy 175.866896 -342.466772) (xy 175.866896 -342.466773) (xy 175.859133 -342.520764)
			(xy 175.843764 -342.5731) (xy 175.821103 -342.622716) (xy 175.791612 -342.668602) (xy 175.755889 -342.709823)
			(xy 175.714663 -342.74554) (xy 175.668774 -342.775026) (xy 175.619155 -342.797681) (xy 175.566817 -342.813043)
			(xy 175.512825 -342.8208) (xy 175.485552 -342.82126) (xy 174.621952 -342.82126) (xy 174.594685 -342.820774)
			(xy 174.540706 -342.813007) (xy 174.488382 -342.797637) (xy 174.438778 -342.774978) (xy 174.392902 -342.745491)
			(xy 174.35169 -342.709776) (xy 174.31598 -342.668559) (xy 174.286499 -342.62268) (xy 174.263846 -342.573073)
			(xy 174.248483 -342.520747) (xy 174.240722 -342.466767) (xy 172.757896 -342.466767) (xy 172.757896 -342.466771)
			(xy 172.750134 -342.520759) (xy 172.734768 -342.573092) (xy 172.71211 -342.622705) (xy 172.682621 -342.668589)
			(xy 172.646903 -342.709809) (xy 172.605682 -342.745526) (xy 172.559798 -342.775013) (xy 172.510184 -342.79767)
			(xy 172.457851 -342.813036) (xy 172.403863 -342.820797) (xy 172.376592 -342.82126) (xy 171.512992 -342.82126)
			(xy 171.485723 -342.820777) (xy 171.43174 -342.813014) (xy 171.379411 -342.797648) (xy 171.329802 -342.774991)
			(xy 171.283921 -342.745505) (xy 171.242705 -342.70979) (xy 171.20699 -342.668572) (xy 171.177505 -342.622691)
			(xy 171.154849 -342.573082) (xy 171.139484 -342.520752) (xy 171.131722 -342.466769) (xy 169.648874 -342.466769)
			(xy 169.641113 -342.520748) (xy 169.625749 -342.573075) (xy 169.603095 -342.622683) (xy 169.573613 -342.668562)
			(xy 169.537901 -342.709778) (xy 169.496688 -342.745494) (xy 169.450811 -342.77498) (xy 169.401205 -342.797638)
			(xy 169.34888 -342.813006) (xy 169.2949 -342.820771) (xy 169.267632 -342.82126) (xy 168.404032 -342.82126)
			(xy 168.376759 -342.820803) (xy 168.322769 -342.813044) (xy 168.270432 -342.797681) (xy 168.220815 -342.775025)
			(xy 168.174927 -342.745538) (xy 168.133702 -342.70982) (xy 168.097981 -342.668599) (xy 168.068491 -342.622714)
			(xy 168.045831 -342.573098) (xy 168.030463 -342.520763) (xy 168.0227 -342.466773) (xy 167.057597 -342.466773)
			(xy 167.049671 -342.516817) (xy 167.033612 -342.566246) (xy 167.010019 -342.612553) (xy 166.979472 -342.6546)
			(xy 166.942725 -342.691351) (xy 166.900681 -342.721902) (xy 166.854375 -342.7455) (xy 166.804949 -342.761563)
			(xy 166.753618 -342.769698) (xy 166.727632 -342.770206) (xy 166.713723 -342.770082) (xy 166.686001 -342.767789)
			(xy 166.67226 -342.765634) (xy 166.66233 -342.764469) (xy 166.642858 -342.768916) (xy 166.634414 -342.77427)
			(xy 166.61 -342.79099) (xy 166.557092 -342.817487) (xy 166.500728 -342.835495) (xy 166.442258 -342.844583)
			(xy 166.412672 -342.845136) (xy 165.548564 -342.845136) (xy 165.516714 -342.844476) (xy 165.453899 -342.833883)
			(xy 165.423596 -342.824054) (xy 165.415468 -342.82126) (xy 165.295072 -342.82126) (xy 165.270765 -342.820846)
			(xy 165.222552 -342.814611) (xy 165.175519 -342.802308) (xy 165.152832 -342.793574) (xy 165.152578 -342.793574)
			(xy 165.143239 -342.790355) (xy 165.123506 -342.790523) (xy 165.105294 -342.798124) (xy 165.097968 -342.80475)
			(xy 162.410353 -345.492365) (xy 164.91387 -345.492365) (xy 164.91387 -345.437835) (xy 164.92163 -345.383861)
			(xy 164.936992 -345.33154) (xy 164.959644 -345.281937) (xy 164.989123 -345.236063) (xy 165.024831 -345.194851)
			(xy 165.066041 -345.15914) (xy 165.111913 -345.129657) (xy 165.161513 -345.107002) (xy 165.213833 -345.091636)
			(xy 165.267807 -345.083872) (xy 165.295072 -345.083384) (xy 166.158672 -345.083384) (xy 166.185948 -345.083754)
			(xy 166.239944 -345.091514) (xy 166.292286 -345.106879) (xy 166.341909 -345.129538) (xy 166.387802 -345.159028)
			(xy 166.42903 -345.19475) (xy 166.464755 -345.235976) (xy 166.494249 -345.281866) (xy 166.516911 -345.331487)
			(xy 166.532281 -345.383829) (xy 166.540044 -345.437824) (xy 166.540044 -345.492369) (xy 168.022747 -345.492369)
			(xy 168.022747 -345.437831) (xy 168.03051 -345.383848) (xy 168.045876 -345.331519) (xy 168.068533 -345.281909)
			(xy 168.09802 -345.23603) (xy 168.133736 -345.194814) (xy 168.174955 -345.159101) (xy 168.220838 -345.129617)
			(xy 168.270449 -345.106964) (xy 168.322779 -345.091603) (xy 168.376763 -345.083845) (xy 168.404032 -345.083384)
			(xy 169.267632 -345.083384) (xy 169.294903 -345.083781) (xy 169.34889 -345.091547) (xy 169.401222 -345.106917)
			(xy 169.450834 -345.129578) (xy 169.496716 -345.159068) (xy 169.537935 -345.194788) (xy 169.573651 -345.236009)
			(xy 169.603138 -345.281894) (xy 169.625794 -345.331508) (xy 169.64116 -345.383842) (xy 169.648922 -345.437829)
			(xy 169.648922 -345.492366) (xy 171.13177 -345.492366) (xy 171.13177 -345.437834) (xy 171.139531 -345.383858)
			(xy 171.154894 -345.331535) (xy 171.177547 -345.281932) (xy 171.207028 -345.236057) (xy 171.242738 -345.194844)
			(xy 171.28395 -345.159133) (xy 171.329825 -345.129651) (xy 171.379428 -345.106997) (xy 171.43175 -345.091633)
			(xy 171.485726 -345.083871) (xy 171.512992 -345.083384) (xy 172.376592 -345.083384) (xy 172.403867 -345.083755)
			(xy 172.457861 -345.091517) (xy 172.510201 -345.106885) (xy 172.559821 -345.129544) (xy 172.605711 -345.159035)
			(xy 172.646937 -345.194757) (xy 172.68266 -345.235982) (xy 172.712152 -345.281872) (xy 172.734813 -345.331492)
			(xy 172.750181 -345.383831) (xy 172.757944 -345.437825) (xy 172.757944 -345.492364) (xy 174.24077 -345.492364)
			(xy 174.24077 -345.437836) (xy 174.24853 -345.383863) (xy 174.263891 -345.331544) (xy 174.286541 -345.281943)
			(xy 174.316019 -345.23607) (xy 174.351724 -345.194858) (xy 174.392931 -345.159147) (xy 174.438801 -345.129664)
			(xy 174.488399 -345.107008) (xy 174.540716 -345.09164) (xy 174.594688 -345.083874) (xy 174.621952 -345.083384)
			(xy 175.485552 -345.083384) (xy 175.512829 -345.083752) (xy 175.566827 -345.09151) (xy 175.619172 -345.106874)
			(xy 175.668797 -345.129531) (xy 175.714692 -345.159021) (xy 175.755923 -345.194743) (xy 175.79165 -345.235969)
			(xy 175.821146 -345.281861) (xy 175.843809 -345.331483) (xy 175.85918 -345.383826) (xy 175.866944 -345.437824)
			(xy 175.866944 -345.492368) (xy 177.349647 -345.492368) (xy 177.349647 -345.437832) (xy 177.357409 -345.38385)
			(xy 177.372774 -345.331523) (xy 177.39543 -345.281915) (xy 177.424915 -345.236036) (xy 177.460629 -345.194821)
			(xy 177.501846 -345.159108) (xy 177.547726 -345.129624) (xy 177.597334 -345.10697) (xy 177.649662 -345.091606)
			(xy 177.703644 -345.083847) (xy 177.730912 -345.083384) (xy 178.594512 -345.083384) (xy 178.621784 -345.083779)
			(xy 178.675773 -345.091543) (xy 178.728107 -345.106912) (xy 178.777722 -345.129571) (xy 178.823607 -345.159061)
			(xy 178.864828 -345.194781) (xy 178.900546 -345.236003) (xy 178.930035 -345.281889) (xy 178.952693 -345.331504)
			(xy 178.968059 -345.383839) (xy 178.975821 -345.437828) (xy 178.975821 -345.492365) (xy 180.45867 -345.492365)
			(xy 180.45867 -345.437835) (xy 180.46643 -345.383861) (xy 180.481792 -345.33154) (xy 180.504444 -345.281937)
			(xy 180.533923 -345.236063) (xy 180.569631 -345.194851) (xy 180.610841 -345.15914) (xy 180.656713 -345.129657)
			(xy 180.706313 -345.107002) (xy 180.758633 -345.091636) (xy 180.812607 -345.083872) (xy 180.839872 -345.083384)
			(xy 181.703472 -345.083384) (xy 181.730748 -345.083754) (xy 181.784744 -345.091514) (xy 181.837086 -345.106879)
			(xy 181.886709 -345.129538) (xy 181.932602 -345.159028) (xy 181.97383 -345.19475) (xy 182.009555 -345.235976)
			(xy 182.039049 -345.281866) (xy 182.061711 -345.331487) (xy 182.077081 -345.383829) (xy 182.084844 -345.437824)
			(xy 182.084844 -345.492369) (xy 183.567547 -345.492369) (xy 183.567547 -345.437831) (xy 183.57531 -345.383848)
			(xy 183.590676 -345.331519) (xy 183.613333 -345.281909) (xy 183.64282 -345.23603) (xy 183.678536 -345.194814)
			(xy 183.719755 -345.159101) (xy 183.765638 -345.129617) (xy 183.815249 -345.106964) (xy 183.867579 -345.091603)
			(xy 183.921563 -345.083845) (xy 183.948832 -345.083384) (xy 184.812432 -345.083384) (xy 184.839703 -345.083781)
			(xy 184.89369 -345.091547) (xy 184.946022 -345.106917) (xy 184.995634 -345.129578) (xy 185.041516 -345.159068)
			(xy 185.082735 -345.194788) (xy 185.118451 -345.236009) (xy 185.147938 -345.281894) (xy 185.170594 -345.331508)
			(xy 185.18596 -345.383842) (xy 185.193722 -345.437829) (xy 185.193722 -345.492366) (xy 186.67657 -345.492366)
			(xy 186.67657 -345.437834) (xy 186.684331 -345.383858) (xy 186.699694 -345.331535) (xy 186.722347 -345.281932)
			(xy 186.751828 -345.236057) (xy 186.787538 -345.194844) (xy 186.82875 -345.159133) (xy 186.874625 -345.129651)
			(xy 186.924228 -345.106997) (xy 186.97655 -345.091633) (xy 187.030526 -345.083871) (xy 187.057792 -345.083384)
			(xy 187.921392 -345.083384) (xy 187.948667 -345.083755) (xy 188.002661 -345.091517) (xy 188.055001 -345.106885)
			(xy 188.104621 -345.129544) (xy 188.150511 -345.159035) (xy 188.191737 -345.194757) (xy 188.22746 -345.235982)
			(xy 188.256952 -345.281872) (xy 188.279613 -345.331492) (xy 188.294981 -345.383831) (xy 188.302744 -345.437825)
			(xy 188.302744 -345.492364) (xy 189.78557 -345.492364) (xy 189.78557 -345.437836) (xy 189.79333 -345.383863)
			(xy 189.808691 -345.331544) (xy 189.831341 -345.281943) (xy 189.860819 -345.23607) (xy 189.896524 -345.194858)
			(xy 189.937731 -345.159147) (xy 189.983601 -345.129664) (xy 190.033199 -345.107008) (xy 190.085516 -345.09164)
			(xy 190.139488 -345.083874) (xy 190.166752 -345.083384) (xy 191.030352 -345.083384) (xy 191.057629 -345.083752)
			(xy 191.111627 -345.09151) (xy 191.163972 -345.106874) (xy 191.213597 -345.129531) (xy 191.259492 -345.159021)
			(xy 191.300723 -345.194743) (xy 191.33645 -345.235969) (xy 191.365946 -345.281861) (xy 191.388609 -345.331483)
			(xy 191.40398 -345.383826) (xy 191.411744 -345.437824) (xy 191.411744 -345.492368) (xy 192.894447 -345.492368)
			(xy 192.894447 -345.437832) (xy 192.902209 -345.38385) (xy 192.917574 -345.331523) (xy 192.94023 -345.281915)
			(xy 192.969715 -345.236036) (xy 193.005429 -345.194821) (xy 193.046646 -345.159108) (xy 193.092526 -345.129624)
			(xy 193.142134 -345.10697) (xy 193.194462 -345.091606) (xy 193.248444 -345.083847) (xy 193.275712 -345.083384)
			(xy 194.139312 -345.083384) (xy 194.166584 -345.083779) (xy 194.220573 -345.091543) (xy 194.272907 -345.106912)
			(xy 194.322522 -345.129571) (xy 194.368407 -345.159061) (xy 194.409628 -345.194781) (xy 194.445346 -345.236003)
			(xy 194.474835 -345.281889) (xy 194.497493 -345.331504) (xy 194.512859 -345.383839) (xy 194.520621 -345.437828)
			(xy 194.520621 -345.492365) (xy 196.00347 -345.492365) (xy 196.00347 -345.437835) (xy 196.01123 -345.383861)
			(xy 196.026592 -345.33154) (xy 196.049244 -345.281937) (xy 196.078723 -345.236063) (xy 196.114431 -345.194851)
			(xy 196.155641 -345.15914) (xy 196.201513 -345.129657) (xy 196.251113 -345.107002) (xy 196.303433 -345.091636)
			(xy 196.357407 -345.083872) (xy 196.384672 -345.083384) (xy 197.248272 -345.083384) (xy 197.275548 -345.083754)
			(xy 197.329544 -345.091514) (xy 197.381886 -345.106879) (xy 197.431509 -345.129538) (xy 197.477402 -345.159028)
			(xy 197.51863 -345.19475) (xy 197.554355 -345.235976) (xy 197.583849 -345.281866) (xy 197.606511 -345.331487)
			(xy 197.621881 -345.383829) (xy 197.628314 -345.42857) (xy 229.27894 -345.42857) (xy 229.283011 -345.372948)
			(xy 229.295137 -345.318511) (xy 229.31506 -345.26642) (xy 229.342356 -345.217785) (xy 229.376442 -345.173642)
			(xy 229.416591 -345.134933) (xy 229.461949 -345.102482) (xy 229.511549 -345.076981) (xy 229.564333 -345.058974)
			(xy 229.619176 -345.048844) (xy 229.67491 -345.046807) (xy 229.730347 -345.052907) (xy 229.784304 -345.067013)
			(xy 229.835633 -345.088825) (xy 229.883239 -345.117879) (xy 229.926107 -345.153554) (xy 229.963324 -345.195091)
			(xy 229.994097 -345.241604) (xy 230.017769 -345.292101) (xy 230.033837 -345.345508) (xy 230.041957 -345.400684)
			(xy 230.042466 -345.42857) (xy 230.041957 -345.456456) (xy 230.033837 -345.511632) (xy 230.017769 -345.565039)
			(xy 229.994097 -345.615536) (xy 229.963324 -345.662049) (xy 229.926107 -345.703586) (xy 229.883239 -345.739261)
			(xy 229.835633 -345.768315) (xy 229.784304 -345.790127) (xy 229.730347 -345.804233) (xy 229.67491 -345.810333)
			(xy 229.619176 -345.808296) (xy 229.564333 -345.798166) (xy 229.511549 -345.780159) (xy 229.461949 -345.754658)
			(xy 229.416591 -345.722207) (xy 229.376442 -345.683498) (xy 229.342356 -345.639355) (xy 229.31506 -345.59072)
			(xy 229.295137 -345.538629) (xy 229.283011 -345.484192) (xy 229.27894 -345.42857) (xy 197.628314 -345.42857)
			(xy 197.629644 -345.437824) (xy 197.629644 -345.492376) (xy 197.621881 -345.546371) (xy 197.606511 -345.598713)
			(xy 197.583849 -345.648334) (xy 197.554355 -345.694224) (xy 197.51863 -345.73545) (xy 197.477402 -345.771172)
			(xy 197.431509 -345.800662) (xy 197.381886 -345.823321) (xy 197.349125 -345.832938) (xy 235.125004 -345.832938)
			(xy 235.129075 -345.777316) (xy 235.141201 -345.722879) (xy 235.161124 -345.670788) (xy 235.18842 -345.622153)
			(xy 235.222506 -345.57801) (xy 235.262655 -345.539301) (xy 235.308013 -345.50685) (xy 235.357613 -345.481349)
			(xy 235.410397 -345.463342) (xy 235.46524 -345.453212) (xy 235.520974 -345.451175) (xy 235.576411 -345.457275)
			(xy 235.630368 -345.471381) (xy 235.681697 -345.493193) (xy 235.729303 -345.522247) (xy 235.772171 -345.557922)
			(xy 235.809388 -345.599459) (xy 235.840161 -345.645972) (xy 235.863833 -345.696469) (xy 235.879901 -345.749876)
			(xy 235.888021 -345.805052) (xy 235.88853 -345.832938) (xy 235.888021 -345.860824) (xy 235.879901 -345.916)
			(xy 235.87226 -345.941396) (xy 250.769118 -345.941396) (xy 250.773189 -345.885774) (xy 250.785315 -345.831337)
			(xy 250.805238 -345.779246) (xy 250.832534 -345.730611) (xy 250.86662 -345.686468) (xy 250.906769 -345.647759)
			(xy 250.952127 -345.615308) (xy 251.001727 -345.589807) (xy 251.054511 -345.5718) (xy 251.109354 -345.56167)
			(xy 251.165088 -345.559633) (xy 251.220525 -345.565733) (xy 251.274482 -345.579839) (xy 251.325811 -345.601651)
			(xy 251.373417 -345.630705) (xy 251.416285 -345.66638) (xy 251.453502 -345.707917) (xy 251.484275 -345.75443)
			(xy 251.507947 -345.804927) (xy 251.524015 -345.858334) (xy 251.532135 -345.91351) (xy 251.532644 -345.941396)
			(xy 251.532135 -345.969282) (xy 251.526296 -346.00896) (xy 252.661928 -346.00896) (xy 252.661928 -345.827096)
			(xy 252.662442 -345.79316) (xy 252.670333 -345.725747) (xy 252.685963 -345.659699) (xy 252.709121 -345.595899)
			(xy 252.739499 -345.535204) (xy 252.757686 -345.506548) (xy 252.762712 -345.498018) (xy 252.766512 -345.478607)
			(xy 252.762717 -345.459195) (xy 252.757686 -345.450668) (xy 252.739499 -345.422013) (xy 252.70913 -345.361314)
			(xy 252.685974 -345.297514) (xy 252.670343 -345.231467) (xy 252.662444 -345.164056) (xy 252.661928 -345.13012)
			(xy 252.661928 -344.948256) (xy 252.662396 -344.915376) (xy 252.669758 -344.850028) (xy 252.684394 -344.785917)
			(xy 252.706121 -344.72385) (xy 252.734666 -344.664607) (xy 252.769668 -344.608936) (xy 252.810687 -344.557537)
			(xy 252.833632 -344.533982) (xy 252.96241 -344.405204) (xy 252.985964 -344.382261) (xy 253.03738 -344.34127)
			(xy 253.093059 -344.306286) (xy 253.152301 -344.27775) (xy 253.214363 -344.25602) (xy 253.278466 -344.241368)
			(xy 253.343806 -344.233977) (xy 253.376684 -344.2335) (xy 253.657608 -344.2335) (xy 253.667616 -344.233018)
			(xy 253.686108 -344.225356) (xy 253.700261 -344.211201) (xy 253.70792 -344.192708) (xy 253.708408 -344.1827)
			(xy 253.708408 -336.80273) (xy 253.708903 -336.769877) (xy 253.716262 -336.704586) (xy 253.730881 -336.640527)
			(xy 253.752575 -336.578507) (xy 253.781072 -336.519303) (xy 253.816014 -336.46366) (xy 253.856963 -336.412275)
			(xy 253.879858 -336.38871) (xy 262.18896 -328.079608) (xy 262.212537 -328.05669) (xy 262.263949 -328.015696)
			(xy 262.319623 -327.98071) (xy 262.378861 -327.952171) (xy 262.44092 -327.930436) (xy 262.50502 -327.915779)
			(xy 262.570357 -327.908384) (xy 262.603234 -327.907904) (xy 266.700508 -327.907904) (xy 266.732688 -327.908374)
			(xy 266.796659 -327.91543) (xy 266.859475 -327.929446) (xy 266.920378 -327.950254) (xy 266.978638 -327.977602)
			(xy 267.006324 -327.99401) (xy 267.014599 -327.998712) (xy 267.03332 -328.002076) (xy 267.051968 -327.99833)
			(xy 267.060172 -327.993502) (xy 267.088505 -327.975955) (xy 267.14837 -327.946665) (xy 267.211172 -327.92436)
			(xy 267.276101 -327.909329) (xy 267.342317 -327.901767) (xy 267.37564 -327.9013) (xy 267.411029 -327.901772)
			(xy 267.481292 -327.910306) (xy 267.550015 -327.927244) (xy 267.616195 -327.95234) (xy 267.678869 -327.985228)
			(xy 267.737124 -328.025429) (xy 267.790109 -328.072356) (xy 267.837054 -328.125327) (xy 267.877273 -328.183568)
			(xy 267.910182 -328.246232) (xy 267.935299 -328.312404) (xy 267.95226 -328.381121) (xy 267.960817 -328.451381)
			(xy 267.961364 -328.48677) (xy 267.961364 -328.752708) (xy 267.960902 -328.785562) (xy 267.953538 -328.850855)
			(xy 267.938915 -328.914914) (xy 267.917216 -328.976935) (xy 267.888713 -329.036138) (xy 267.853766 -329.091781)
			(xy 267.812812 -329.143164) (xy 267.789914 -329.166728) (xy 267.231368 -329.725274) (xy 267.207815 -329.748184)
			(xy 267.156436 -329.789147) (xy 267.100794 -329.824101) (xy 267.041588 -329.852604) (xy 266.979564 -329.8743)
			(xy 266.9155 -329.888916) (xy 266.850203 -329.896267) (xy 266.817348 -329.896724) (xy 262.700008 -329.896724)
			(xy 262.689938 -329.897147) (xy 262.67134 -329.904869) (xy 262.66394 -329.91171) (xy 255.354582 -337.221068)
			(xy 255.347761 -337.228483) (xy 255.340031 -337.247071) (xy 255.339596 -337.257136) (xy 255.339596 -339.693758)
			(xy 266.115798 -339.693758) (xy 266.119869 -339.638136) (xy 266.131995 -339.583699) (xy 266.151918 -339.531608)
			(xy 266.179214 -339.482973) (xy 266.2133 -339.43883) (xy 266.253449 -339.400121) (xy 266.298807 -339.36767)
			(xy 266.348407 -339.342169) (xy 266.401191 -339.324162) (xy 266.456034 -339.314032) (xy 266.511768 -339.311995)
			(xy 266.567205 -339.318095) (xy 266.621162 -339.332201) (xy 266.672491 -339.354013) (xy 266.720097 -339.383067)
			(xy 266.762965 -339.418742) (xy 266.800182 -339.460279) (xy 266.830955 -339.506792) (xy 266.854627 -339.557289)
			(xy 266.870695 -339.610696) (xy 266.878815 -339.665872) (xy 266.879324 -339.693758) (xy 266.878815 -339.721644)
			(xy 266.870695 -339.77682) (xy 266.854627 -339.830227) (xy 266.830955 -339.880724) (xy 266.800182 -339.927237)
			(xy 266.762965 -339.968774) (xy 266.720097 -340.004449) (xy 266.672491 -340.033503) (xy 266.621162 -340.055315)
			(xy 266.567205 -340.069421) (xy 266.511768 -340.075521) (xy 266.456034 -340.073484) (xy 266.401191 -340.063354)
			(xy 266.348407 -340.045347) (xy 266.298807 -340.019846) (xy 266.253449 -339.987395) (xy 266.2133 -339.948686)
			(xy 266.179214 -339.904543) (xy 266.151918 -339.855908) (xy 266.131995 -339.803817) (xy 266.119869 -339.74938)
			(xy 266.115798 -339.693758) (xy 255.339596 -339.693758) (xy 255.339596 -342.060022) (xy 255.91262 -342.060022)
			(xy 255.91262 -341.196422) (xy 255.91311 -341.166438) (xy 255.920938 -341.106982) (xy 255.936459 -341.049057)
			(xy 255.959408 -340.993653) (xy 255.989392 -340.941719) (xy 256.025898 -340.894143) (xy 256.068303 -340.851738)
			(xy 256.115879 -340.815232) (xy 256.167813 -340.785248) (xy 256.223217 -340.762299) (xy 256.281142 -340.746778)
			(xy 256.340598 -340.73895) (xy 256.400566 -340.73895) (xy 256.460022 -340.746778) (xy 256.517947 -340.762299)
			(xy 256.573351 -340.785248) (xy 256.625285 -340.815232) (xy 256.672861 -340.851738) (xy 256.715266 -340.894143)
			(xy 256.751772 -340.941719) (xy 256.781756 -340.993653) (xy 256.804705 -341.049057) (xy 256.820226 -341.106982)
			(xy 256.828054 -341.166438) (xy 256.828544 -341.196422) (xy 256.828544 -342.060022) (xy 256.828054 -342.090006)
			(xy 256.820226 -342.149462) (xy 256.804705 -342.207387) (xy 256.781756 -342.262791) (xy 256.751772 -342.314725)
			(xy 256.715266 -342.362301) (xy 256.672861 -342.404706) (xy 256.625285 -342.441212) (xy 256.573351 -342.471196)
			(xy 256.517947 -342.494145) (xy 256.460022 -342.509666) (xy 256.400566 -342.517494) (xy 256.340598 -342.517494)
			(xy 256.281142 -342.509666) (xy 256.223217 -342.494145) (xy 256.167813 -342.471196) (xy 256.115879 -342.441212)
			(xy 256.068303 -342.404706) (xy 256.025898 -342.362301) (xy 255.989392 -342.314725) (xy 255.959408 -342.262791)
			(xy 255.936459 -342.207387) (xy 255.920938 -342.149462) (xy 255.91311 -342.090006) (xy 255.91262 -342.060022)
			(xy 255.339596 -342.060022) (xy 255.339596 -343.0651) (xy 265.321032 -343.0651) (xy 265.325103 -343.009478)
			(xy 265.337229 -342.955041) (xy 265.357152 -342.90295) (xy 265.384448 -342.854315) (xy 265.418534 -342.810172)
			(xy 265.458683 -342.771463) (xy 265.504041 -342.739012) (xy 265.553641 -342.713511) (xy 265.606425 -342.695504)
			(xy 265.661268 -342.685374) (xy 265.717002 -342.683337) (xy 265.772439 -342.689437) (xy 265.826396 -342.703543)
			(xy 265.877725 -342.725355) (xy 265.925331 -342.754409) (xy 265.968199 -342.790084) (xy 266.005416 -342.831621)
			(xy 266.036189 -342.878134) (xy 266.059861 -342.928631) (xy 266.075929 -342.982038) (xy 266.084049 -343.037214)
			(xy 266.084558 -343.0651) (xy 266.084049 -343.092986) (xy 266.075929 -343.148162) (xy 266.059861 -343.201569)
			(xy 266.036189 -343.252066) (xy 266.005416 -343.298579) (xy 265.968199 -343.340116) (xy 265.925331 -343.375791)
			(xy 265.877725 -343.404845) (xy 265.826396 -343.426657) (xy 265.772439 -343.440763) (xy 265.717002 -343.446863)
			(xy 265.661268 -343.444826) (xy 265.606425 -343.434696) (xy 265.553641 -343.416689) (xy 265.504041 -343.391188)
			(xy 265.458683 -343.358737) (xy 265.418534 -343.320028) (xy 265.384448 -343.275885) (xy 265.357152 -343.22725)
			(xy 265.337229 -343.175159) (xy 265.325103 -343.120722) (xy 265.321032 -343.0651) (xy 255.339596 -343.0651)
			(xy 255.339596 -345.653868) (xy 257.171696 -345.653868) (xy 257.175767 -345.598246) (xy 257.187893 -345.543809)
			(xy 257.207816 -345.491718) (xy 257.235112 -345.443083) (xy 257.269198 -345.39894) (xy 257.309347 -345.360231)
			(xy 257.354705 -345.32778) (xy 257.404305 -345.302279) (xy 257.457089 -345.284272) (xy 257.511932 -345.274142)
			(xy 257.567666 -345.272105) (xy 257.623103 -345.278205) (xy 257.67706 -345.292311) (xy 257.728389 -345.314123)
			(xy 257.775995 -345.343177) (xy 257.818863 -345.378852) (xy 257.85608 -345.420389) (xy 257.886853 -345.466902)
			(xy 257.910525 -345.517399) (xy 257.926593 -345.570806) (xy 257.934713 -345.625982) (xy 257.935222 -345.653868)
			(xy 257.934713 -345.681754) (xy 257.926593 -345.73693) (xy 257.910525 -345.790337) (xy 257.886853 -345.840834)
			(xy 257.85608 -345.887347) (xy 257.818863 -345.928884) (xy 257.775995 -345.964559) (xy 257.728389 -345.993613)
			(xy 257.67706 -346.015425) (xy 257.623103 -346.029531) (xy 257.567666 -346.035631) (xy 257.511932 -346.033594)
			(xy 257.457089 -346.023464) (xy 257.404305 -346.005457) (xy 257.354705 -345.979956) (xy 257.309347 -345.947505)
			(xy 257.269198 -345.908796) (xy 257.235112 -345.864653) (xy 257.207816 -345.816018) (xy 257.187893 -345.763927)
			(xy 257.175767 -345.70949) (xy 257.171696 -345.653868) (xy 255.339596 -345.653868) (xy 255.339596 -346.435934)
			(xy 259.550914 -346.435934) (xy 259.554985 -346.380312) (xy 259.567111 -346.325875) (xy 259.587034 -346.273784)
			(xy 259.61433 -346.225149) (xy 259.648416 -346.181006) (xy 259.688565 -346.142297) (xy 259.733923 -346.109846)
			(xy 259.783523 -346.084345) (xy 259.836307 -346.066338) (xy 259.89115 -346.056208) (xy 259.946884 -346.054171)
			(xy 260.002321 -346.060271) (xy 260.056278 -346.074377) (xy 260.107607 -346.096189) (xy 260.155213 -346.125243)
			(xy 260.198081 -346.160918) (xy 260.235298 -346.202455) (xy 260.266071 -346.248968) (xy 260.289743 -346.299465)
			(xy 260.305811 -346.352872) (xy 260.313931 -346.408048) (xy 260.31444 -346.435934) (xy 260.313931 -346.46382)
			(xy 260.305811 -346.518996) (xy 260.289743 -346.572403) (xy 260.266071 -346.6229) (xy 260.235298 -346.669413)
			(xy 260.198081 -346.71095) (xy 260.155213 -346.746625) (xy 260.107607 -346.775679) (xy 260.056278 -346.797491)
			(xy 260.002321 -346.811597) (xy 259.946884 -346.817697) (xy 259.89115 -346.81566) (xy 259.836307 -346.80553)
			(xy 259.783523 -346.787523) (xy 259.733923 -346.762022) (xy 259.688565 -346.729571) (xy 259.648416 -346.690862)
			(xy 259.61433 -346.646719) (xy 259.587034 -346.598084) (xy 259.567111 -346.545993) (xy 259.554985 -346.491556)
			(xy 259.550914 -346.435934) (xy 255.339596 -346.435934) (xy 255.339596 -347.68409) (xy 255.611882 -347.68409)
			(xy 255.615953 -347.628468) (xy 255.628079 -347.574031) (xy 255.648002 -347.52194) (xy 255.675298 -347.473305)
			(xy 255.709384 -347.429162) (xy 255.749533 -347.390453) (xy 255.794891 -347.358002) (xy 255.844491 -347.332501)
			(xy 255.897275 -347.314494) (xy 255.952118 -347.304364) (xy 256.007852 -347.302327) (xy 256.063289 -347.308427)
			(xy 256.117246 -347.322533) (xy 256.168575 -347.344345) (xy 256.216181 -347.373399) (xy 256.259049 -347.409074)
			(xy 256.296266 -347.450611) (xy 256.327039 -347.497124) (xy 256.350711 -347.547621) (xy 256.366779 -347.601028)
			(xy 256.374899 -347.656204) (xy 256.375408 -347.68409) (xy 256.374899 -347.711976) (xy 256.366779 -347.767152)
			(xy 256.350711 -347.820559) (xy 256.327039 -347.871056) (xy 256.296266 -347.917569) (xy 256.259049 -347.959106)
			(xy 256.216181 -347.994781) (xy 256.168575 -348.023835) (xy 256.117246 -348.045647) (xy 256.063289 -348.059753)
			(xy 256.007852 -348.065853) (xy 255.952118 -348.063816) (xy 255.897275 -348.053686) (xy 255.844491 -348.035679)
			(xy 255.794891 -348.010178) (xy 255.749533 -347.977727) (xy 255.709384 -347.939018) (xy 255.675298 -347.894875)
			(xy 255.648002 -347.84624) (xy 255.628079 -347.794149) (xy 255.615953 -347.739712) (xy 255.611882 -347.68409)
			(xy 255.339596 -347.68409) (xy 255.339596 -349.773494) (xy 258.543296 -349.773494) (xy 258.547367 -349.717872)
			(xy 258.559493 -349.663435) (xy 258.579416 -349.611344) (xy 258.606712 -349.562709) (xy 258.640798 -349.518566)
			(xy 258.680947 -349.479857) (xy 258.726305 -349.447406) (xy 258.775905 -349.421905) (xy 258.828689 -349.403898)
			(xy 258.883532 -349.393768) (xy 258.939266 -349.391731) (xy 258.994703 -349.397831) (xy 259.04866 -349.411937)
			(xy 259.099989 -349.433749) (xy 259.147595 -349.462803) (xy 259.190463 -349.498478) (xy 259.22768 -349.540015)
			(xy 259.258453 -349.586528) (xy 259.282125 -349.637025) (xy 259.298193 -349.690432) (xy 259.306313 -349.745608)
			(xy 259.306822 -349.773494) (xy 259.306313 -349.80138) (xy 259.298193 -349.856556) (xy 259.282125 -349.909963)
			(xy 259.258453 -349.96046) (xy 259.22768 -350.006973) (xy 259.190463 -350.04851) (xy 259.147595 -350.084185)
			(xy 259.099989 -350.113239) (xy 259.04866 -350.135051) (xy 258.994703 -350.149157) (xy 258.939266 -350.155257)
			(xy 258.883532 -350.15322) (xy 258.828689 -350.14309) (xy 258.775905 -350.125083) (xy 258.726305 -350.099582)
			(xy 258.680947 -350.067131) (xy 258.640798 -350.028422) (xy 258.606712 -349.984279) (xy 258.579416 -349.935644)
			(xy 258.559493 -349.883553) (xy 258.547367 -349.829116) (xy 258.543296 -349.773494) (xy 255.339596 -349.773494)
			(xy 255.339596 -350.184974) (xy 255.339103 -350.217827) (xy 255.331743 -350.283118) (xy 255.317124 -350.347177)
			(xy 255.29543 -350.409197) (xy 255.266932 -350.468401) (xy 255.23199 -350.524044) (xy 255.191041 -350.575429)
			(xy 255.168146 -350.598994) (xy 255.044702 -350.722438) (xy 255.74828 -350.722438) (xy 255.752351 -350.666816)
			(xy 255.764477 -350.612379) (xy 255.7844 -350.560288) (xy 255.811696 -350.511653) (xy 255.845782 -350.46751)
			(xy 255.885931 -350.428801) (xy 255.931289 -350.39635) (xy 255.980889 -350.370849) (xy 256.033673 -350.352842)
			(xy 256.088516 -350.342712) (xy 256.14425 -350.340675) (xy 256.199687 -350.346775) (xy 256.253644 -350.360881)
			(xy 256.304973 -350.382693) (xy 256.352579 -350.411747) (xy 256.395447 -350.447422) (xy 256.432664 -350.488959)
			(xy 256.463437 -350.535472) (xy 256.487109 -350.585969) (xy 256.503177 -350.639376) (xy 256.511297 -350.694552)
			(xy 256.511806 -350.722438) (xy 256.511297 -350.750324) (xy 256.503177 -350.8055) (xy 256.487109 -350.858907)
			(xy 256.463437 -350.909404) (xy 256.432664 -350.955917) (xy 256.395447 -350.997454) (xy 256.352579 -351.033129)
			(xy 256.304973 -351.062183) (xy 256.253644 -351.083995) (xy 256.199687 -351.098101) (xy 256.14425 -351.104201)
			(xy 256.088516 -351.102164) (xy 256.033673 -351.092034) (xy 255.980889 -351.074027) (xy 255.931289 -351.048526)
			(xy 255.885931 -351.016075) (xy 255.845782 -350.977366) (xy 255.811696 -350.933223) (xy 255.7844 -350.884588)
			(xy 255.764477 -350.832497) (xy 255.752351 -350.77806) (xy 255.74828 -350.722438) (xy 255.044702 -350.722438)
			(xy 254.528066 -351.239074) (xy 254.504514 -351.261985) (xy 254.453135 -351.302948) (xy 254.397492 -351.337901)
			(xy 254.338287 -351.366405) (xy 254.276262 -351.388101) (xy 254.212198 -351.402716) (xy 254.146901 -351.410067)
			(xy 254.114046 -351.410524) (xy 253.339854 -351.410524) (xy 253.304452 -351.409987) (xy 253.234164 -351.401451)
			(xy 253.165416 -351.384507) (xy 253.099211 -351.359403) (xy 253.036514 -351.326505) (xy 252.978237 -351.286292)
			(xy 252.92523 -351.23935) (xy 252.878265 -351.186363) (xy 252.838027 -351.128104) (xy 252.805101 -351.06542)
			(xy 252.779969 -350.999226) (xy 252.762995 -350.930486) (xy 252.754428 -350.860202) (xy 252.753876 -350.8248)
			(xy 252.754355 -350.791595) (xy 252.761866 -350.725612) (xy 252.776793 -350.660901) (xy 252.798943 -350.598295)
			(xy 252.828032 -350.538595) (xy 252.863687 -350.482569) (xy 252.905451 -350.430935) (xy 252.952787 -350.384357)
			(xy 253.005087 -350.343431) (xy 253.061681 -350.308684) (xy 253.121842 -350.280561) (xy 253.184797 -350.259423)
			(xy 253.217172 -350.25203) (xy 253.217426 -350.25203) (xy 253.228557 -350.249107) (xy 253.246666 -350.234932)
			(xy 253.252224 -350.224852) (xy 253.29261 -350.143064) (xy 253.292864 -350.119696) (xy 253.287784 -350.109282)
			(xy 253.274434 -350.079921) (xy 253.253518 -350.018905) (xy 253.239432 -349.955961) (xy 253.232346 -349.891851)
			(xy 253.231904 -349.8596) (xy 253.232343 -349.826719) (xy 253.23971 -349.761371) (xy 253.254352 -349.697259)
			(xy 253.276084 -349.635192) (xy 253.304633 -349.57595) (xy 253.339639 -349.520279) (xy 253.380661 -349.46888)
			(xy 253.403608 -349.445326) (xy 253.501144 -349.34779) (xy 253.509209 -349.3388) (xy 253.51664 -349.315858)
			(xy 253.515368 -349.303848) (xy 253.500128 -349.210122) (xy 253.485396 -349.190564) (xy 253.474474 -349.18523)
			(xy 253.45096 -349.173085) (xy 253.407297 -349.143174) (xy 253.368186 -349.107517) (xy 253.334376 -349.066799)
			(xy 253.306515 -349.021801) (xy 253.285138 -348.973385) (xy 253.270655 -348.92248) (xy 253.263343 -348.870063)
			(xy 253.262892 -348.8436) (xy 253.263438 -348.815118) (xy 253.271936 -348.758791) (xy 253.288712 -348.704353)
			(xy 253.313394 -348.653013) (xy 253.345434 -348.605913) (xy 253.384119 -348.564099) (xy 253.42859 -348.528501)
			(xy 253.477859 -348.499908) (xy 253.53083 -348.478958) (xy 253.586328 -348.466114) (xy 253.614682 -348.463362)
			(xy 253.614936 -348.463362) (xy 253.624211 -348.462111) (xy 253.641016 -348.453908) (xy 253.647702 -348.44736)
			(xy 253.694946 -348.39656) (xy 253.701088 -348.389275) (xy 253.708007 -348.371536) (xy 253.708408 -348.362016)
			(xy 253.708408 -348.258384) (xy 253.708033 -348.248856) (xy 253.701125 -348.231101) (xy 253.694946 -348.22384)
			(xy 253.647702 -348.17304) (xy 253.641059 -348.166428) (xy 253.624235 -348.158202) (xy 253.614936 -348.157038)
			(xy 253.614428 -348.157038) (xy 253.587424 -348.154425) (xy 253.534483 -348.142568) (xy 253.483757 -348.123329)
			(xy 253.436269 -348.097095) (xy 253.392979 -348.064396) (xy 253.354758 -348.025893) (xy 253.32238 -347.982362)
			(xy 253.296497 -347.934683) (xy 253.277633 -347.883816) (xy 253.266167 -347.830789) (xy 253.262331 -347.776673)
			(xy 253.266203 -347.72256) (xy 253.277704 -347.669541) (xy 253.296602 -347.618687) (xy 253.322517 -347.571024)
			(xy 253.354924 -347.527515) (xy 253.39317 -347.489037) (xy 253.436482 -347.456367) (xy 253.483987 -347.430165)
			(xy 253.534726 -347.410959) (xy 253.587674 -347.399138) (xy 253.614682 -347.396562) (xy 253.614936 -347.396562)
			(xy 253.624211 -347.395311) (xy 253.641016 -347.387108) (xy 253.647702 -347.38056) (xy 253.694946 -347.32976)
			(xy 253.701088 -347.322475) (xy 253.708007 -347.304736) (xy 253.708408 -347.295216) (xy 253.708408 -346.774516)
			(xy 253.707968 -346.764497) (xy 253.700305 -346.745982) (xy 253.686139 -346.731809) (xy 253.667627 -346.724137)
			(xy 253.657608 -346.723716) (xy 253.376684 -346.723716) (xy 253.343803 -346.723282) (xy 253.278455 -346.715913)
			(xy 253.214343 -346.70127) (xy 253.152276 -346.679537) (xy 253.093034 -346.650988) (xy 253.037363 -346.615981)
			(xy 252.985964 -346.574959) (xy 252.96241 -346.552012) (xy 252.833632 -346.423234) (xy 252.810716 -346.399655)
			(xy 252.769721 -346.348244) (xy 252.734734 -346.29257) (xy 252.706194 -346.233333) (xy 252.68446 -346.171274)
			(xy 252.669803 -346.107174) (xy 252.662408 -346.041837) (xy 252.661928 -346.00896) (xy 251.526296 -346.00896)
			(xy 251.524015 -346.024458) (xy 251.507947 -346.077865) (xy 251.484275 -346.128362) (xy 251.453502 -346.174875)
			(xy 251.416285 -346.216412) (xy 251.373417 -346.252087) (xy 251.325811 -346.281141) (xy 251.274482 -346.302953)
			(xy 251.220525 -346.317059) (xy 251.165088 -346.323159) (xy 251.109354 -346.321122) (xy 251.054511 -346.310992)
			(xy 251.001727 -346.292985) (xy 250.952127 -346.267484) (xy 250.906769 -346.235033) (xy 250.86662 -346.196324)
			(xy 250.832534 -346.152181) (xy 250.805238 -346.103546) (xy 250.785315 -346.051455) (xy 250.773189 -345.997018)
			(xy 250.769118 -345.941396) (xy 235.87226 -345.941396) (xy 235.863833 -345.969407) (xy 235.840161 -346.019904)
			(xy 235.809388 -346.066417) (xy 235.772171 -346.107954) (xy 235.729303 -346.143629) (xy 235.681697 -346.172683)
			(xy 235.630368 -346.194495) (xy 235.576411 -346.208601) (xy 235.520974 -346.214701) (xy 235.46524 -346.212664)
			(xy 235.410397 -346.202534) (xy 235.357613 -346.184527) (xy 235.308013 -346.159026) (xy 235.262655 -346.126575)
			(xy 235.222506 -346.087866) (xy 235.18842 -346.043723) (xy 235.161124 -345.995088) (xy 235.141201 -345.942997)
			(xy 235.129075 -345.88856) (xy 235.125004 -345.832938) (xy 197.349125 -345.832938) (xy 197.329544 -345.838686)
			(xy 197.275548 -345.846446) (xy 197.248272 -345.846908) (xy 196.384672 -345.846908) (xy 196.357407 -345.846328)
			(xy 196.303433 -345.838564) (xy 196.251113 -345.823198) (xy 196.201513 -345.800543) (xy 196.155641 -345.77106)
			(xy 196.114431 -345.735349) (xy 196.078723 -345.694137) (xy 196.049244 -345.648263) (xy 196.026592 -345.59866)
			(xy 196.01123 -345.546339) (xy 196.00347 -345.492365) (xy 194.520621 -345.492365) (xy 194.520621 -345.492372)
			(xy 194.512859 -345.546361) (xy 194.497493 -345.598696) (xy 194.474835 -345.648311) (xy 194.445346 -345.694197)
			(xy 194.409628 -345.735419) (xy 194.368407 -345.771139) (xy 194.322522 -345.800629) (xy 194.272907 -345.823288)
			(xy 194.220573 -345.838657) (xy 194.166584 -345.846421) (xy 194.139312 -345.846908) (xy 193.275712 -345.846908)
			(xy 193.248444 -345.846353) (xy 193.194462 -345.838594) (xy 193.142134 -345.82323) (xy 193.092526 -345.800576)
			(xy 193.046646 -345.771092) (xy 193.005429 -345.735379) (xy 192.969715 -345.694164) (xy 192.94023 -345.648285)
			(xy 192.917574 -345.598677) (xy 192.902209 -345.54635) (xy 192.894447 -345.492368) (xy 191.411744 -345.492368)
			(xy 191.411744 -345.492376) (xy 191.40398 -345.546374) (xy 191.388609 -345.598717) (xy 191.365946 -345.648339)
			(xy 191.33645 -345.694231) (xy 191.300723 -345.735457) (xy 191.259492 -345.771179) (xy 191.213597 -345.800669)
			(xy 191.163972 -345.823326) (xy 191.111627 -345.83869) (xy 191.057629 -345.846448) (xy 191.030352 -345.846908)
			(xy 190.166752 -345.846908) (xy 190.139488 -345.846326) (xy 190.085516 -345.83856) (xy 190.033199 -345.823192)
			(xy 189.983601 -345.800536) (xy 189.937731 -345.771053) (xy 189.896524 -345.735342) (xy 189.860819 -345.69413)
			(xy 189.831341 -345.648257) (xy 189.808691 -345.598656) (xy 189.79333 -345.546337) (xy 189.78557 -345.492364)
			(xy 188.302744 -345.492364) (xy 188.302744 -345.492375) (xy 188.294981 -345.546369) (xy 188.279613 -345.598708)
			(xy 188.256952 -345.648328) (xy 188.22746 -345.694218) (xy 188.191737 -345.735443) (xy 188.150511 -345.771165)
			(xy 188.104621 -345.800656) (xy 188.055001 -345.823315) (xy 188.002661 -345.838683) (xy 187.948667 -345.846445)
			(xy 187.921392 -345.846908) (xy 187.057792 -345.846908) (xy 187.030526 -345.846329) (xy 186.97655 -345.838567)
			(xy 186.924228 -345.823203) (xy 186.874625 -345.800549) (xy 186.82875 -345.771067) (xy 186.787538 -345.735356)
			(xy 186.751828 -345.694143) (xy 186.722347 -345.648268) (xy 186.699694 -345.598665) (xy 186.684331 -345.546342)
			(xy 186.67657 -345.492366) (xy 185.193722 -345.492366) (xy 185.193722 -345.492371) (xy 185.18596 -345.546358)
			(xy 185.170594 -345.598692) (xy 185.147938 -345.648306) (xy 185.118451 -345.694191) (xy 185.082735 -345.735412)
			(xy 185.041516 -345.771132) (xy 184.995634 -345.800622) (xy 184.946022 -345.823283) (xy 184.89369 -345.838653)
			(xy 184.839703 -345.846419) (xy 184.812432 -345.846908) (xy 183.948832 -345.846908) (xy 183.921563 -345.846355)
			(xy 183.867579 -345.838597) (xy 183.815249 -345.823236) (xy 183.765638 -345.800583) (xy 183.719755 -345.771099)
			(xy 183.678536 -345.735386) (xy 183.64282 -345.69417) (xy 183.613333 -345.648291) (xy 183.590676 -345.598681)
			(xy 183.57531 -345.546352) (xy 183.567547 -345.492369) (xy 182.084844 -345.492369) (xy 182.084844 -345.492376)
			(xy 182.077081 -345.546371) (xy 182.061711 -345.598713) (xy 182.039049 -345.648334) (xy 182.009555 -345.694224)
			(xy 181.97383 -345.73545) (xy 181.932602 -345.771172) (xy 181.886709 -345.800662) (xy 181.837086 -345.823321)
			(xy 181.784744 -345.838686) (xy 181.730748 -345.846446) (xy 181.703472 -345.846908) (xy 180.839872 -345.846908)
			(xy 180.812607 -345.846328) (xy 180.758633 -345.838564) (xy 180.706313 -345.823198) (xy 180.656713 -345.800543)
			(xy 180.610841 -345.77106) (xy 180.569631 -345.735349) (xy 180.533923 -345.694137) (xy 180.504444 -345.648263)
			(xy 180.481792 -345.59866) (xy 180.46643 -345.546339) (xy 180.45867 -345.492365) (xy 178.975821 -345.492365)
			(xy 178.975821 -345.492372) (xy 178.968059 -345.546361) (xy 178.952693 -345.598696) (xy 178.930035 -345.648311)
			(xy 178.900546 -345.694197) (xy 178.864828 -345.735419) (xy 178.823607 -345.771139) (xy 178.777722 -345.800629)
			(xy 178.728107 -345.823288) (xy 178.675773 -345.838657) (xy 178.621784 -345.846421) (xy 178.594512 -345.846908)
			(xy 177.730912 -345.846908) (xy 177.703644 -345.846353) (xy 177.649662 -345.838594) (xy 177.597334 -345.82323)
			(xy 177.547726 -345.800576) (xy 177.501846 -345.771092) (xy 177.460629 -345.735379) (xy 177.424915 -345.694164)
			(xy 177.39543 -345.648285) (xy 177.372774 -345.598677) (xy 177.357409 -345.54635) (xy 177.349647 -345.492368)
			(xy 175.866944 -345.492368) (xy 175.866944 -345.492376) (xy 175.85918 -345.546374) (xy 175.843809 -345.598717)
			(xy 175.821146 -345.648339) (xy 175.79165 -345.694231) (xy 175.755923 -345.735457) (xy 175.714692 -345.771179)
			(xy 175.668797 -345.800669) (xy 175.619172 -345.823326) (xy 175.566827 -345.83869) (xy 175.512829 -345.846448)
			(xy 175.485552 -345.846908) (xy 174.621952 -345.846908) (xy 174.594688 -345.846326) (xy 174.540716 -345.83856)
			(xy 174.488399 -345.823192) (xy 174.438801 -345.800536) (xy 174.392931 -345.771053) (xy 174.351724 -345.735342)
			(xy 174.316019 -345.69413) (xy 174.286541 -345.648257) (xy 174.263891 -345.598656) (xy 174.24853 -345.546337)
			(xy 174.24077 -345.492364) (xy 172.757944 -345.492364) (xy 172.757944 -345.492375) (xy 172.750181 -345.546369)
			(xy 172.734813 -345.598708) (xy 172.712152 -345.648328) (xy 172.68266 -345.694218) (xy 172.646937 -345.735443)
			(xy 172.605711 -345.771165) (xy 172.559821 -345.800656) (xy 172.510201 -345.823315) (xy 172.457861 -345.838683)
			(xy 172.403867 -345.846445) (xy 172.376592 -345.846908) (xy 171.512992 -345.846908) (xy 171.485726 -345.846329)
			(xy 171.43175 -345.838567) (xy 171.379428 -345.823203) (xy 171.329825 -345.800549) (xy 171.28395 -345.771067)
			(xy 171.242738 -345.735356) (xy 171.207028 -345.694143) (xy 171.177547 -345.648268) (xy 171.154894 -345.598665)
			(xy 171.139531 -345.546342) (xy 171.13177 -345.492366) (xy 169.648922 -345.492366) (xy 169.648922 -345.492371)
			(xy 169.64116 -345.546358) (xy 169.625794 -345.598692) (xy 169.603138 -345.648306) (xy 169.573651 -345.694191)
			(xy 169.537935 -345.735412) (xy 169.496716 -345.771132) (xy 169.450834 -345.800622) (xy 169.401222 -345.823283)
			(xy 169.34889 -345.838653) (xy 169.294903 -345.846419) (xy 169.267632 -345.846908) (xy 168.404032 -345.846908)
			(xy 168.376763 -345.846355) (xy 168.322779 -345.838597) (xy 168.270449 -345.823236) (xy 168.220838 -345.800583)
			(xy 168.174955 -345.771099) (xy 168.133736 -345.735386) (xy 168.09802 -345.69417) (xy 168.068533 -345.648291)
			(xy 168.045876 -345.598681) (xy 168.03051 -345.546352) (xy 168.022747 -345.492369) (xy 166.540044 -345.492369)
			(xy 166.540044 -345.492376) (xy 166.532281 -345.546371) (xy 166.516911 -345.598713) (xy 166.494249 -345.648334)
			(xy 166.464755 -345.694224) (xy 166.42903 -345.73545) (xy 166.387802 -345.771172) (xy 166.341909 -345.800662)
			(xy 166.292286 -345.823321) (xy 166.239944 -345.838686) (xy 166.185948 -345.846446) (xy 166.158672 -345.846908)
			(xy 165.295072 -345.846908) (xy 165.267807 -345.846328) (xy 165.213833 -345.838564) (xy 165.161513 -345.823198)
			(xy 165.111913 -345.800543) (xy 165.066041 -345.77106) (xy 165.024831 -345.735349) (xy 164.989123 -345.694137)
			(xy 164.959644 -345.648263) (xy 164.936992 -345.59866) (xy 164.92163 -345.546339) (xy 164.91387 -345.492365)
			(xy 162.410353 -345.492365) (xy 160.984762 -346.917956) (xy 245.50903 -346.917956) (xy 245.50903 -346.83326)
			(xy 245.517081 -346.748946) (xy 245.53311 -346.66578) (xy 245.556971 -346.584513) (xy 245.58845 -346.505883)
			(xy 245.627261 -346.430602) (xy 245.673051 -346.35935) (xy 245.725407 -346.292774) (xy 245.783855 -346.231476)
			(xy 245.847865 -346.176011) (xy 245.916857 -346.126882) (xy 245.990207 -346.084533) (xy 246.06725 -346.049349)
			(xy 246.147289 -346.021647) (xy 246.229598 -346.001679) (xy 246.313433 -345.989626) (xy 246.398034 -345.985596)
			(xy 246.482635 -345.989626) (xy 246.56647 -346.001679) (xy 246.648779 -346.021647) (xy 246.728818 -346.049349)
			(xy 246.805861 -346.084533) (xy 246.879211 -346.126882) (xy 246.948203 -346.176011) (xy 247.012213 -346.231476)
			(xy 247.070661 -346.292774) (xy 247.123017 -346.35935) (xy 247.168807 -346.430602) (xy 247.207618 -346.505883)
			(xy 247.239097 -346.584513) (xy 247.262958 -346.66578) (xy 247.278987 -346.748946) (xy 247.287038 -346.83326)
			(xy 247.287542 -346.875608) (xy 247.287038 -346.917956) (xy 247.278987 -347.00227) (xy 247.262958 -347.085436)
			(xy 247.239097 -347.166703) (xy 247.207618 -347.245333) (xy 247.168807 -347.320614) (xy 247.123017 -347.391866)
			(xy 247.070661 -347.458442) (xy 247.012213 -347.51974) (xy 246.948203 -347.575205) (xy 246.879211 -347.624334)
			(xy 246.805861 -347.666683) (xy 246.728818 -347.701867) (xy 246.648779 -347.729569) (xy 246.56647 -347.749537)
			(xy 246.482635 -347.76159) (xy 246.398034 -347.765621) (xy 246.313433 -347.76159) (xy 246.229598 -347.749537)
			(xy 246.147289 -347.729569) (xy 246.06725 -347.701867) (xy 245.990207 -347.666683) (xy 245.916857 -347.624334)
			(xy 245.847865 -347.575205) (xy 245.783855 -347.51974) (xy 245.725407 -347.458442) (xy 245.673051 -347.391866)
			(xy 245.627261 -347.320614) (xy 245.58845 -347.245333) (xy 245.556971 -347.166703) (xy 245.53311 -347.085436)
			(xy 245.517081 -347.00227) (xy 245.50903 -346.917956) (xy 160.984762 -346.917956) (xy 159.289646 -348.613072)
			(xy 161.804792 -348.613072) (xy 161.804792 -348.558528) (xy 161.812554 -348.504538) (xy 161.827921 -348.452203)
			(xy 161.850581 -348.402588) (xy 161.88007 -348.356703) (xy 161.91579 -348.315481) (xy 161.957012 -348.279763)
			(xy 162.002899 -348.250275) (xy 162.052515 -348.227617) (xy 162.10485 -348.212252) (xy 162.15884 -348.204491)
			(xy 162.186112 -348.204028) (xy 163.049712 -348.204028) (xy 163.07698 -348.204535) (xy 163.130961 -348.212298)
			(xy 163.183288 -348.227664) (xy 163.232895 -348.25032) (xy 163.278773 -348.279806) (xy 163.319988 -348.31552)
			(xy 163.355701 -348.356736) (xy 163.385185 -348.402615) (xy 163.40784 -348.452224) (xy 163.423204 -348.504551)
			(xy 163.430966 -348.558532) (xy 163.430966 -348.613068) (xy 163.430966 -348.613069) (xy 164.913814 -348.613069)
			(xy 164.913814 -348.558531) (xy 164.921576 -348.504549) (xy 164.93694 -348.45222) (xy 164.959595 -348.40261)
			(xy 164.989079 -348.35673) (xy 165.024792 -348.315512) (xy 165.066007 -348.279795) (xy 165.111886 -348.250308)
			(xy 165.161494 -348.22765) (xy 165.213821 -348.212281) (xy 165.267803 -348.204516) (xy 165.295072 -348.204028)
			(xy 166.158672 -348.204028) (xy 166.185944 -348.20451) (xy 166.239932 -348.212268) (xy 166.292267 -348.227632)
			(xy 166.341882 -348.250287) (xy 166.387768 -348.279773) (xy 166.42899 -348.31549) (xy 166.46471 -348.356709)
			(xy 166.494199 -348.402593) (xy 166.516859 -348.452207) (xy 166.532226 -348.504541) (xy 166.539988 -348.558528)
			(xy 166.539988 -348.613072) (xy 166.539988 -348.613073) (xy 168.022692 -348.613073) (xy 168.022692 -348.558527)
			(xy 168.030455 -348.504536) (xy 168.045823 -348.452199) (xy 168.068484 -348.402583) (xy 168.097975 -348.356696)
			(xy 168.133697 -348.315474) (xy 168.174922 -348.279756) (xy 168.220811 -348.250268) (xy 168.270429 -348.227612)
			(xy 168.322767 -348.212248) (xy 168.376759 -348.204489) (xy 168.404032 -348.204028) (xy 169.267632 -348.204028)
			(xy 169.294899 -348.204537) (xy 169.348878 -348.212302) (xy 169.401202 -348.227669) (xy 169.450807 -348.250327)
			(xy 169.496683 -348.279813) (xy 169.537895 -348.315527) (xy 169.573606 -348.356743) (xy 169.603088 -348.402621)
			(xy 169.625742 -348.452228) (xy 169.641105 -348.504553) (xy 169.648866 -348.558533) (xy 169.648866 -348.613067)
			(xy 169.648866 -348.61307) (xy 171.131714 -348.61307) (xy 171.131714 -348.55853) (xy 171.139476 -348.504546)
			(xy 171.154841 -348.452216) (xy 171.177498 -348.402605) (xy 171.206984 -348.356723) (xy 171.242699 -348.315505)
			(xy 171.283917 -348.279788) (xy 171.329798 -348.250301) (xy 171.379408 -348.227644) (xy 171.431738 -348.212278)
			(xy 171.485722 -348.204515) (xy 171.512992 -348.204028) (xy 172.376592 -348.204028) (xy 172.403863 -348.204511)
			(xy 172.457849 -348.212272) (xy 172.510181 -348.227637) (xy 172.559794 -348.250294) (xy 172.605678 -348.27978)
			(xy 172.646898 -348.315497) (xy 172.682615 -348.356716) (xy 172.712103 -348.402599) (xy 172.73476 -348.452211)
			(xy 172.750126 -348.504543) (xy 172.757889 -348.558529) (xy 172.757889 -348.613068) (xy 174.240714 -348.613068)
			(xy 174.240714 -348.558532) (xy 174.248475 -348.504551) (xy 174.263838 -348.452224) (xy 174.286492 -348.402616)
			(xy 174.315974 -348.356736) (xy 174.351685 -348.315519) (xy 174.392898 -348.279803) (xy 174.438774 -348.250315)
			(xy 174.488379 -348.227655) (xy 174.540704 -348.212285) (xy 174.594684 -348.204518) (xy 174.621952 -348.204028)
			(xy 175.485552 -348.204028) (xy 175.512825 -348.204508) (xy 175.566815 -348.212265) (xy 175.619152 -348.227626)
			(xy 175.66877 -348.250281) (xy 175.714659 -348.279766) (xy 175.755883 -348.315483) (xy 175.791605 -348.356703)
			(xy 175.821096 -348.402588) (xy 175.843757 -348.452203) (xy 175.859125 -348.504538) (xy 175.866888 -348.558528)
			(xy 175.866888 -348.613072) (xy 177.349592 -348.613072) (xy 177.349592 -348.558528) (xy 177.357354 -348.504538)
			(xy 177.372721 -348.452203) (xy 177.395381 -348.402588) (xy 177.42487 -348.356703) (xy 177.46059 -348.315481)
			(xy 177.501812 -348.279763) (xy 177.547699 -348.250275) (xy 177.597315 -348.227617) (xy 177.64965 -348.212252)
			(xy 177.70364 -348.204491) (xy 177.730912 -348.204028) (xy 178.594512 -348.204028) (xy 178.62178 -348.204535)
			(xy 178.675761 -348.212298) (xy 178.728088 -348.227664) (xy 178.777695 -348.25032) (xy 178.823573 -348.279806)
			(xy 178.864788 -348.31552) (xy 178.900501 -348.356736) (xy 178.929985 -348.402615) (xy 178.95264 -348.452224)
			(xy 178.968004 -348.504551) (xy 178.975766 -348.558532) (xy 178.975766 -348.613068) (xy 178.975766 -348.613069)
			(xy 180.458614 -348.613069) (xy 180.458614 -348.558531) (xy 180.466376 -348.504549) (xy 180.48174 -348.45222)
			(xy 180.504395 -348.40261) (xy 180.533879 -348.35673) (xy 180.569592 -348.315512) (xy 180.610807 -348.279795)
			(xy 180.656686 -348.250308) (xy 180.706294 -348.22765) (xy 180.758621 -348.212281) (xy 180.812603 -348.204516)
			(xy 180.839872 -348.204028) (xy 181.703472 -348.204028) (xy 181.730744 -348.20451) (xy 181.784732 -348.212268)
			(xy 181.837067 -348.227632) (xy 181.886682 -348.250287) (xy 181.932568 -348.279773) (xy 181.97379 -348.31549)
			(xy 182.00951 -348.356709) (xy 182.038999 -348.402593) (xy 182.061659 -348.452207) (xy 182.077026 -348.504541)
			(xy 182.084788 -348.558528) (xy 182.084788 -348.613072) (xy 182.084788 -348.613073) (xy 183.567492 -348.613073)
			(xy 183.567492 -348.558527) (xy 183.575255 -348.504536) (xy 183.590623 -348.452199) (xy 183.613284 -348.402583)
			(xy 183.642775 -348.356696) (xy 183.678497 -348.315474) (xy 183.719722 -348.279756) (xy 183.765611 -348.250268)
			(xy 183.815229 -348.227612) (xy 183.867567 -348.212248) (xy 183.921559 -348.204489) (xy 183.948832 -348.204028)
			(xy 184.812432 -348.204028) (xy 184.839699 -348.204537) (xy 184.893678 -348.212302) (xy 184.946002 -348.227669)
			(xy 184.995607 -348.250327) (xy 185.041483 -348.279813) (xy 185.082695 -348.315527) (xy 185.118406 -348.356743)
			(xy 185.147888 -348.402621) (xy 185.170542 -348.452228) (xy 185.185905 -348.504553) (xy 185.193666 -348.558533)
			(xy 185.193666 -348.613067) (xy 185.193666 -348.61307) (xy 186.676514 -348.61307) (xy 186.676514 -348.55853)
			(xy 186.684276 -348.504546) (xy 186.699641 -348.452216) (xy 186.722298 -348.402605) (xy 186.751784 -348.356723)
			(xy 186.787499 -348.315505) (xy 186.828717 -348.279788) (xy 186.874598 -348.250301) (xy 186.924208 -348.227644)
			(xy 186.976538 -348.212278) (xy 187.030522 -348.204515) (xy 187.057792 -348.204028) (xy 187.921392 -348.204028)
			(xy 187.948663 -348.204511) (xy 188.002649 -348.212272) (xy 188.054981 -348.227637) (xy 188.104594 -348.250294)
			(xy 188.150478 -348.27978) (xy 188.191698 -348.315497) (xy 188.227415 -348.356716) (xy 188.256903 -348.402599)
			(xy 188.27956 -348.452211) (xy 188.294926 -348.504543) (xy 188.302689 -348.558529) (xy 188.302689 -348.613068)
			(xy 189.785514 -348.613068) (xy 189.785514 -348.558532) (xy 189.793275 -348.504551) (xy 189.808638 -348.452224)
			(xy 189.831292 -348.402616) (xy 189.860774 -348.356736) (xy 189.896485 -348.315519) (xy 189.937698 -348.279803)
			(xy 189.983574 -348.250315) (xy 190.033179 -348.227655) (xy 190.085504 -348.212285) (xy 190.139484 -348.204518)
			(xy 190.166752 -348.204028) (xy 191.030352 -348.204028) (xy 191.057625 -348.204508) (xy 191.111615 -348.212265)
			(xy 191.163952 -348.227626) (xy 191.21357 -348.250281) (xy 191.259459 -348.279766) (xy 191.300683 -348.315483)
			(xy 191.336405 -348.356703) (xy 191.365896 -348.402588) (xy 191.388557 -348.452203) (xy 191.403925 -348.504538)
			(xy 191.411688 -348.558528) (xy 191.411688 -348.613072) (xy 192.894392 -348.613072) (xy 192.894392 -348.558528)
			(xy 192.902154 -348.504538) (xy 192.917521 -348.452203) (xy 192.940181 -348.402588) (xy 192.96967 -348.356703)
			(xy 193.00539 -348.315481) (xy 193.046612 -348.279763) (xy 193.092499 -348.250275) (xy 193.142115 -348.227617)
			(xy 193.19445 -348.212252) (xy 193.24844 -348.204491) (xy 193.275712 -348.204028) (xy 194.139312 -348.204028)
			(xy 194.16658 -348.204535) (xy 194.220561 -348.212298) (xy 194.272888 -348.227664) (xy 194.322495 -348.25032)
			(xy 194.368373 -348.279806) (xy 194.409588 -348.31552) (xy 194.445301 -348.356736) (xy 194.474785 -348.402615)
			(xy 194.49744 -348.452224) (xy 194.50429 -348.475554) (xy 236.142528 -348.475554) (xy 236.146599 -348.419932)
			(xy 236.158725 -348.365495) (xy 236.178648 -348.313404) (xy 236.205944 -348.264769) (xy 236.24003 -348.220626)
			(xy 236.280179 -348.181917) (xy 236.325537 -348.149466) (xy 236.375137 -348.123965) (xy 236.427921 -348.105958)
			(xy 236.482764 -348.095828) (xy 236.538498 -348.093791) (xy 236.593935 -348.099891) (xy 236.647892 -348.113997)
			(xy 236.699221 -348.135809) (xy 236.746827 -348.164863) (xy 236.789695 -348.200538) (xy 236.826912 -348.242075)
			(xy 236.857685 -348.288588) (xy 236.881357 -348.339085) (xy 236.897425 -348.392492) (xy 236.902555 -348.427353)
			(xy 240.622271 -348.427353) (xy 240.622271 -348.372847) (xy 240.630029 -348.318896) (xy 240.645386 -348.266598)
			(xy 240.668029 -348.217018) (xy 240.697499 -348.171166) (xy 240.733194 -348.129974) (xy 240.774388 -348.094282)
			(xy 240.820243 -348.064816) (xy 240.869824 -348.042176) (xy 240.922123 -348.026823) (xy 240.976075 -348.019069)
			(xy 241.003328 -348.018608) (xy 241.032243 -348.019175) (xy 241.089412 -348.027893) (xy 241.14461 -348.045141)
			(xy 241.196572 -348.070524) (xy 241.244107 -348.103459) (xy 241.286126 -348.143192) (xy 241.304318 -348.165674)
			(xy 241.311914 -348.174492) (xy 241.332824 -348.184666) (xy 241.34445 -348.185232) (xy 241.424206 -348.185232)
			(xy 241.43584 -348.184706) (xy 241.456751 -348.17451) (xy 241.464338 -348.165674) (xy 241.482501 -348.143167)
			(xy 241.524527 -348.103434) (xy 241.572068 -348.070499) (xy 241.624035 -348.045115) (xy 241.679237 -348.027863)
			(xy 241.73641 -348.01914) (xy 241.765328 -348.018608) (xy 241.792579 -348.019064) (xy 241.846526 -348.026824)
			(xy 241.89882 -348.042182) (xy 241.948395 -348.064826) (xy 241.994244 -348.094294) (xy 242.035433 -348.129987)
			(xy 242.071123 -348.171178) (xy 242.100588 -348.217029) (xy 242.123228 -348.266607) (xy 242.138582 -348.318901)
			(xy 242.146338 -348.372849) (xy 242.146338 -348.427351) (xy 242.138582 -348.481299) (xy 242.123228 -348.533593)
			(xy 242.100588 -348.583171) (xy 242.071123 -348.629022) (xy 242.035433 -348.670213) (xy 241.994244 -348.705906)
			(xy 241.948395 -348.735374) (xy 241.89882 -348.758018) (xy 241.846526 -348.773376) (xy 241.792579 -348.781136)
			(xy 241.765328 -348.781624) (xy 241.73641 -348.781115) (xy 241.679237 -348.772388) (xy 241.624037 -348.75513)
			(xy 241.572075 -348.729737) (xy 241.524541 -348.69679) (xy 241.482527 -348.657046) (xy 241.464338 -348.634558)
			(xy 241.456712 -348.625771) (xy 241.435825 -348.615578) (xy 241.424206 -348.615) (xy 241.34445 -348.615)
			(xy 241.332816 -348.615525) (xy 241.311907 -348.625724) (xy 241.304318 -348.634558) (xy 241.286106 -348.657024)
			(xy 241.244092 -348.696762) (xy 241.196562 -348.729705) (xy 241.144604 -348.755096) (xy 241.08941 -348.772356)
			(xy 241.032243 -348.781088) (xy 241.003328 -348.781624) (xy 240.976075 -348.781131) (xy 240.922123 -348.773377)
			(xy 240.869824 -348.758024) (xy 240.820243 -348.735384) (xy 240.774388 -348.705918) (xy 240.733194 -348.670226)
			(xy 240.697499 -348.629034) (xy 240.668029 -348.583182) (xy 240.645386 -348.533602) (xy 240.630029 -348.481304)
			(xy 240.622271 -348.427353) (xy 236.902555 -348.427353) (xy 236.905545 -348.447668) (xy 236.906054 -348.475554)
			(xy 236.905545 -348.50344) (xy 236.897425 -348.558616) (xy 236.881357 -348.612023) (xy 236.857685 -348.66252)
			(xy 236.826912 -348.709033) (xy 236.789695 -348.75057) (xy 236.746827 -348.786245) (xy 236.699221 -348.815299)
			(xy 236.647892 -348.837111) (xy 236.593935 -348.851217) (xy 236.538498 -348.857317) (xy 236.482764 -348.85528)
			(xy 236.427921 -348.84515) (xy 236.375137 -348.827143) (xy 236.325537 -348.801642) (xy 236.280179 -348.769191)
			(xy 236.24003 -348.730482) (xy 236.205944 -348.686339) (xy 236.178648 -348.637704) (xy 236.158725 -348.585613)
			(xy 236.146599 -348.531176) (xy 236.142528 -348.475554) (xy 194.50429 -348.475554) (xy 194.512804 -348.504551)
			(xy 194.520566 -348.558532) (xy 194.520566 -348.613068) (xy 194.512804 -348.667049) (xy 194.49744 -348.719376)
			(xy 194.474785 -348.768985) (xy 194.445301 -348.814864) (xy 194.409588 -348.85608) (xy 194.368373 -348.891794)
			(xy 194.322495 -348.92128) (xy 194.272888 -348.943936) (xy 194.220561 -348.959302) (xy 194.16658 -348.967065)
			(xy 194.139312 -348.967552) (xy 193.275712 -348.967552) (xy 193.24844 -348.967109) (xy 193.19445 -348.959348)
			(xy 193.142115 -348.943983) (xy 193.092499 -348.921325) (xy 193.046612 -348.891837) (xy 193.00539 -348.856119)
			(xy 192.96967 -348.814897) (xy 192.940181 -348.769012) (xy 192.917521 -348.719397) (xy 192.902154 -348.667062)
			(xy 192.894392 -348.613072) (xy 191.411688 -348.613072) (xy 191.403925 -348.667062) (xy 191.388557 -348.719397)
			(xy 191.365896 -348.769012) (xy 191.336405 -348.814897) (xy 191.300683 -348.856117) (xy 191.259459 -348.891834)
			(xy 191.21357 -348.921319) (xy 191.163952 -348.943974) (xy 191.111615 -348.959335) (xy 191.057625 -348.967092)
			(xy 191.030352 -348.967552) (xy 190.166752 -348.967552) (xy 190.139484 -348.967082) (xy 190.085504 -348.959315)
			(xy 190.033179 -348.943945) (xy 189.983574 -348.921285) (xy 189.937698 -348.891797) (xy 189.896485 -348.856081)
			(xy 189.860774 -348.814864) (xy 189.831292 -348.768984) (xy 189.808638 -348.719376) (xy 189.793275 -348.667049)
			(xy 189.785514 -348.613068) (xy 188.302689 -348.613068) (xy 188.302689 -348.613071) (xy 188.294926 -348.667057)
			(xy 188.27956 -348.719389) (xy 188.256903 -348.769001) (xy 188.227415 -348.814884) (xy 188.191698 -348.856103)
			(xy 188.150478 -348.89182) (xy 188.104594 -348.921306) (xy 188.054981 -348.943963) (xy 188.002649 -348.959328)
			(xy 187.948663 -348.967089) (xy 187.921392 -348.967552) (xy 187.057792 -348.967552) (xy 187.030522 -348.967085)
			(xy 186.976538 -348.959322) (xy 186.924208 -348.943956) (xy 186.874598 -348.921299) (xy 186.828717 -348.891812)
			(xy 186.787499 -348.856095) (xy 186.751784 -348.814877) (xy 186.722298 -348.768995) (xy 186.699641 -348.719384)
			(xy 186.684276 -348.667054) (xy 186.676514 -348.61307) (xy 185.193666 -348.61307) (xy 185.185905 -348.667047)
			(xy 185.170542 -348.719372) (xy 185.147888 -348.768979) (xy 185.118406 -348.814857) (xy 185.082695 -348.856073)
			(xy 185.041483 -348.891787) (xy 184.995607 -348.921273) (xy 184.946002 -348.943931) (xy 184.893678 -348.959298)
			(xy 184.839699 -348.967063) (xy 184.812432 -348.967552) (xy 183.948832 -348.967552) (xy 183.921559 -348.967111)
			(xy 183.867567 -348.959352) (xy 183.815229 -348.943988) (xy 183.765611 -348.921332) (xy 183.719722 -348.891844)
			(xy 183.678497 -348.856126) (xy 183.642775 -348.814904) (xy 183.613284 -348.769017) (xy 183.590623 -348.719401)
			(xy 183.575255 -348.667064) (xy 183.567492 -348.613073) (xy 182.084788 -348.613073) (xy 182.077026 -348.667059)
			(xy 182.061659 -348.719393) (xy 182.038999 -348.769007) (xy 182.00951 -348.814891) (xy 181.97379 -348.85611)
			(xy 181.932568 -348.891827) (xy 181.886682 -348.921313) (xy 181.837067 -348.943968) (xy 181.784732 -348.959332)
			(xy 181.730744 -348.96709) (xy 181.703472 -348.967552) (xy 180.839872 -348.967552) (xy 180.812603 -348.967084)
			(xy 180.758621 -348.959319) (xy 180.706294 -348.94395) (xy 180.656686 -348.921292) (xy 180.610807 -348.891805)
			(xy 180.569592 -348.856088) (xy 180.533879 -348.81487) (xy 180.504395 -348.76899) (xy 180.48174 -348.71938)
			(xy 180.466376 -348.667051) (xy 180.458614 -348.613069) (xy 178.975766 -348.613069) (xy 178.968004 -348.667049)
			(xy 178.95264 -348.719376) (xy 178.929985 -348.768985) (xy 178.900501 -348.814864) (xy 178.864788 -348.85608)
			(xy 178.823573 -348.891794) (xy 178.777695 -348.92128) (xy 178.728088 -348.943936) (xy 178.675761 -348.959302)
			(xy 178.62178 -348.967065) (xy 178.594512 -348.967552) (xy 177.730912 -348.967552) (xy 177.70364 -348.967109)
			(xy 177.64965 -348.959348) (xy 177.597315 -348.943983) (xy 177.547699 -348.921325) (xy 177.501812 -348.891837)
			(xy 177.46059 -348.856119) (xy 177.42487 -348.814897) (xy 177.395381 -348.769012) (xy 177.372721 -348.719397)
			(xy 177.357354 -348.667062) (xy 177.349592 -348.613072) (xy 175.866888 -348.613072) (xy 175.859125 -348.667062)
			(xy 175.843757 -348.719397) (xy 175.821096 -348.769012) (xy 175.791605 -348.814897) (xy 175.755883 -348.856117)
			(xy 175.714659 -348.891834) (xy 175.66877 -348.921319) (xy 175.619152 -348.943974) (xy 175.566815 -348.959335)
			(xy 175.512825 -348.967092) (xy 175.485552 -348.967552) (xy 174.621952 -348.967552) (xy 174.594684 -348.967082)
			(xy 174.540704 -348.959315) (xy 174.488379 -348.943945) (xy 174.438774 -348.921285) (xy 174.392898 -348.891797)
			(xy 174.351685 -348.856081) (xy 174.315974 -348.814864) (xy 174.286492 -348.768984) (xy 174.263838 -348.719376)
			(xy 174.248475 -348.667049) (xy 174.240714 -348.613068) (xy 172.757889 -348.613068) (xy 172.757889 -348.613071)
			(xy 172.750126 -348.667057) (xy 172.73476 -348.719389) (xy 172.712103 -348.769001) (xy 172.682615 -348.814884)
			(xy 172.646898 -348.856103) (xy 172.605678 -348.89182) (xy 172.559794 -348.921306) (xy 172.510181 -348.943963)
			(xy 172.457849 -348.959328) (xy 172.403863 -348.967089) (xy 172.376592 -348.967552) (xy 171.512992 -348.967552)
			(xy 171.485722 -348.967085) (xy 171.431738 -348.959322) (xy 171.379408 -348.943956) (xy 171.329798 -348.921299)
			(xy 171.283917 -348.891812) (xy 171.242699 -348.856095) (xy 171.206984 -348.814877) (xy 171.177498 -348.768995)
			(xy 171.154841 -348.719384) (xy 171.139476 -348.667054) (xy 171.131714 -348.61307) (xy 169.648866 -348.61307)
			(xy 169.641105 -348.667047) (xy 169.625742 -348.719372) (xy 169.603088 -348.768979) (xy 169.573606 -348.814857)
			(xy 169.537895 -348.856073) (xy 169.496683 -348.891787) (xy 169.450807 -348.921273) (xy 169.401202 -348.943931)
			(xy 169.348878 -348.959298) (xy 169.294899 -348.967063) (xy 169.267632 -348.967552) (xy 168.404032 -348.967552)
			(xy 168.376759 -348.967111) (xy 168.322767 -348.959352) (xy 168.270429 -348.943988) (xy 168.220811 -348.921332)
			(xy 168.174922 -348.891844) (xy 168.133697 -348.856126) (xy 168.097975 -348.814904) (xy 168.068484 -348.769017)
			(xy 168.045823 -348.719401) (xy 168.030455 -348.667064) (xy 168.022692 -348.613073) (xy 166.539988 -348.613073)
			(xy 166.532226 -348.667059) (xy 166.516859 -348.719393) (xy 166.494199 -348.769007) (xy 166.46471 -348.814891)
			(xy 166.42899 -348.85611) (xy 166.387768 -348.891827) (xy 166.341882 -348.921313) (xy 166.292267 -348.943968)
			(xy 166.239932 -348.959332) (xy 166.185944 -348.96709) (xy 166.158672 -348.967552) (xy 165.295072 -348.967552)
			(xy 165.267803 -348.967084) (xy 165.213821 -348.959319) (xy 165.161494 -348.94395) (xy 165.111886 -348.921292)
			(xy 165.066007 -348.891805) (xy 165.024792 -348.856088) (xy 164.989079 -348.81487) (xy 164.959595 -348.76899)
			(xy 164.93694 -348.71938) (xy 164.921576 -348.667051) (xy 164.913814 -348.613069) (xy 163.430966 -348.613069)
			(xy 163.423204 -348.667049) (xy 163.40784 -348.719376) (xy 163.385185 -348.768985) (xy 163.355701 -348.814864)
			(xy 163.319988 -348.85608) (xy 163.278773 -348.891794) (xy 163.232895 -348.92128) (xy 163.183288 -348.943936)
			(xy 163.130961 -348.959302) (xy 163.07698 -348.967065) (xy 163.049712 -348.967552) (xy 162.186112 -348.967552)
			(xy 162.15884 -348.967109) (xy 162.10485 -348.959348) (xy 162.052515 -348.943983) (xy 162.002899 -348.921325)
			(xy 161.957012 -348.891837) (xy 161.91579 -348.856119) (xy 161.88007 -348.814897) (xy 161.850581 -348.769012)
			(xy 161.827921 -348.719397) (xy 161.812554 -348.667062) (xy 161.804792 -348.613072) (xy 159.289646 -348.613072)
			(xy 159.030162 -348.872556) (xy 159.028638 -348.87408) (xy 158.632402 -349.302832) (xy 204.379574 -349.302832)
			(xy 204.383645 -349.24721) (xy 204.395771 -349.192773) (xy 204.415694 -349.140682) (xy 204.44299 -349.092047)
			(xy 204.477076 -349.047904) (xy 204.517225 -349.009195) (xy 204.562583 -348.976744) (xy 204.612183 -348.951243)
			(xy 204.664967 -348.933236) (xy 204.71981 -348.923106) (xy 204.775544 -348.921069) (xy 204.830981 -348.927169)
			(xy 204.884938 -348.941275) (xy 204.936267 -348.963087) (xy 204.983873 -348.992141) (xy 205.026741 -349.027816)
			(xy 205.063958 -349.069353) (xy 205.094731 -349.115866) (xy 205.118403 -349.166363) (xy 205.134471 -349.21977)
			(xy 205.134584 -349.220536) (xy 205.395574 -349.220536) (xy 205.399645 -349.164914) (xy 205.411771 -349.110477)
			(xy 205.431694 -349.058386) (xy 205.45899 -349.009751) (xy 205.493076 -348.965608) (xy 205.533225 -348.926899)
			(xy 205.578583 -348.894448) (xy 205.628183 -348.868947) (xy 205.680967 -348.85094) (xy 205.73581 -348.84081)
			(xy 205.791544 -348.838773) (xy 205.846981 -348.844873) (xy 205.900938 -348.858979) (xy 205.952267 -348.880791)
			(xy 205.983722 -348.899988) (xy 248.580146 -348.899988) (xy 248.584217 -348.844366) (xy 248.596343 -348.789929)
			(xy 248.616266 -348.737838) (xy 248.643562 -348.689203) (xy 248.677648 -348.64506) (xy 248.717797 -348.606351)
			(xy 248.763155 -348.5739) (xy 248.812755 -348.548399) (xy 248.865539 -348.530392) (xy 248.920382 -348.520262)
			(xy 248.976116 -348.518225) (xy 249.031553 -348.524325) (xy 249.08551 -348.538431) (xy 249.136839 -348.560243)
			(xy 249.184445 -348.589297) (xy 249.227313 -348.624972) (xy 249.26453 -348.666509) (xy 249.295303 -348.713022)
			(xy 249.318975 -348.763519) (xy 249.335043 -348.816926) (xy 249.343163 -348.872102) (xy 249.343672 -348.899988)
			(xy 249.343163 -348.927874) (xy 249.335043 -348.98305) (xy 249.318975 -349.036457) (xy 249.295303 -349.086954)
			(xy 249.26453 -349.133467) (xy 249.227313 -349.175004) (xy 249.184445 -349.210679) (xy 249.136839 -349.239733)
			(xy 249.08551 -349.261545) (xy 249.031553 -349.275651) (xy 248.976116 -349.281751) (xy 248.920382 -349.279714)
			(xy 248.865539 -349.269584) (xy 248.812755 -349.251577) (xy 248.763155 -349.226076) (xy 248.717797 -349.193625)
			(xy 248.677648 -349.154916) (xy 248.643562 -349.110773) (xy 248.616266 -349.062138) (xy 248.596343 -349.010047)
			(xy 248.584217 -348.95561) (xy 248.580146 -348.899988) (xy 205.983722 -348.899988) (xy 205.999873 -348.909845)
			(xy 206.042741 -348.94552) (xy 206.079958 -348.987057) (xy 206.110731 -349.03357) (xy 206.134403 -349.084067)
			(xy 206.150471 -349.137474) (xy 206.158591 -349.19265) (xy 206.1591 -349.220536) (xy 206.158591 -349.248422)
			(xy 206.150471 -349.303598) (xy 206.134403 -349.357005) (xy 206.110731 -349.407502) (xy 206.079958 -349.454015)
			(xy 206.062937 -349.473012) (xy 236.12678 -349.473012) (xy 236.130851 -349.41739) (xy 236.142977 -349.362953)
			(xy 236.1629 -349.310862) (xy 236.190196 -349.262227) (xy 236.224282 -349.218084) (xy 236.264431 -349.179375)
			(xy 236.309789 -349.146924) (xy 236.359389 -349.121423) (xy 236.412173 -349.103416) (xy 236.467016 -349.093286)
			(xy 236.52275 -349.091249) (xy 236.578187 -349.097349) (xy 236.632144 -349.111455) (xy 236.683473 -349.133267)
			(xy 236.731079 -349.162321) (xy 236.773947 -349.197996) (xy 236.811164 -349.239533) (xy 236.841937 -349.286046)
			(xy 236.865609 -349.336543) (xy 236.881677 -349.38995) (xy 236.887181 -349.42735) (xy 240.762792 -349.42735)
			(xy 240.762792 -349.37285) (xy 240.770548 -349.318905) (xy 240.785902 -349.266613) (xy 240.808542 -349.217039)
			(xy 240.838006 -349.171191) (xy 240.873695 -349.130002) (xy 240.914883 -349.094312) (xy 240.96073 -349.064847)
			(xy 241.010304 -349.042206) (xy 241.062596 -349.02685) (xy 241.11654 -349.019093) (xy 241.14379 -349.018606)
			(xy 241.172707 -349.019129) (xy 241.229878 -349.027857) (xy 241.285077 -349.045114) (xy 241.337038 -349.070505)
			(xy 241.384572 -349.103447) (xy 241.42659 -349.143187) (xy 241.44478 -349.165672) (xy 241.452393 -349.174472)
			(xy 241.47329 -349.184657) (xy 241.484912 -349.18523) (xy 241.564668 -349.18523) (xy 241.5763 -349.184683)
			(xy 241.597211 -349.174502) (xy 241.6048 -349.165672) (xy 241.622984 -349.143183) (xy 241.665006 -349.103449)
			(xy 241.712543 -349.070512) (xy 241.764505 -349.045125) (xy 241.819704 -349.027869) (xy 241.876874 -349.019141)
			(xy 241.90579 -349.018606) (xy 241.933044 -349.01904) (xy 241.986998 -349.026796) (xy 242.039299 -349.042152)
			(xy 242.088883 -349.064795) (xy 242.134739 -349.094264) (xy 242.175934 -349.129959) (xy 242.21163 -349.171153)
			(xy 242.2411 -349.217009) (xy 242.263744 -349.266591) (xy 242.279102 -349.318892) (xy 242.286859 -349.372846)
			(xy 242.286859 -349.427354) (xy 242.279102 -349.481308) (xy 242.263744 -349.533609) (xy 242.2411 -349.583191)
			(xy 242.21163 -349.629047) (xy 242.175934 -349.670241) (xy 242.134739 -349.705936) (xy 242.088883 -349.735405)
			(xy 242.039299 -349.758048) (xy 241.986998 -349.773404) (xy 241.933044 -349.78116) (xy 241.90579 -349.781622)
			(xy 241.876874 -349.781069) (xy 241.819703 -349.772351) (xy 241.764504 -349.755102) (xy 241.712541 -349.729717)
			(xy 241.665007 -349.696778) (xy 241.62299 -349.65704) (xy 241.6048 -349.634556) (xy 241.597191 -349.625752)
			(xy 241.576291 -349.615568) (xy 241.564668 -349.614998) (xy 241.484912 -349.614998) (xy 241.473283 -349.615559)
			(xy 241.452373 -349.625733) (xy 241.44478 -349.634556) (xy 241.426589 -349.65704) (xy 241.384571 -349.696777)
			(xy 241.337036 -349.729717) (xy 241.285075 -349.755106) (xy 241.229876 -349.772362) (xy 241.172706 -349.781088)
			(xy 241.14379 -349.781622) (xy 241.11654 -349.781107) (xy 241.062596 -349.77335) (xy 241.010304 -349.757994)
			(xy 240.96073 -349.735353) (xy 240.914883 -349.705888) (xy 240.873695 -349.670198) (xy 240.838006 -349.629009)
			(xy 240.808542 -349.583161) (xy 240.785902 -349.533587) (xy 240.770548 -349.481295) (xy 240.762792 -349.42735)
			(xy 236.887181 -349.42735) (xy 236.889797 -349.445126) (xy 236.890306 -349.473012) (xy 236.889797 -349.500898)
			(xy 236.881677 -349.556074) (xy 236.865609 -349.609481) (xy 236.841937 -349.659978) (xy 236.811164 -349.706491)
			(xy 236.773947 -349.748028) (xy 236.731079 -349.783703) (xy 236.683473 -349.812757) (xy 236.632144 -349.834569)
			(xy 236.578187 -349.848675) (xy 236.52275 -349.854775) (xy 236.467016 -349.852738) (xy 236.412173 -349.842608)
			(xy 236.359389 -349.824601) (xy 236.309789 -349.7991) (xy 236.264431 -349.766649) (xy 236.224282 -349.72794)
			(xy 236.190196 -349.683797) (xy 236.1629 -349.635162) (xy 236.142977 -349.583071) (xy 236.130851 -349.528634)
			(xy 236.12678 -349.473012) (xy 206.062937 -349.473012) (xy 206.042741 -349.495552) (xy 205.999873 -349.531227)
			(xy 205.952267 -349.560281) (xy 205.900938 -349.582093) (xy 205.846981 -349.596199) (xy 205.791544 -349.602299)
			(xy 205.73581 -349.600262) (xy 205.680967 -349.590132) (xy 205.628183 -349.572125) (xy 205.578583 -349.546624)
			(xy 205.533225 -349.514173) (xy 205.493076 -349.475464) (xy 205.45899 -349.431321) (xy 205.431694 -349.382686)
			(xy 205.411771 -349.330595) (xy 205.399645 -349.276158) (xy 205.395574 -349.220536) (xy 205.134584 -349.220536)
			(xy 205.142591 -349.274946) (xy 205.1431 -349.302832) (xy 205.142591 -349.330718) (xy 205.134471 -349.385894)
			(xy 205.118403 -349.439301) (xy 205.094731 -349.489798) (xy 205.063958 -349.536311) (xy 205.026741 -349.577848)
			(xy 204.983873 -349.613523) (xy 204.936267 -349.642577) (xy 204.884938 -349.664389) (xy 204.830981 -349.678495)
			(xy 204.775544 -349.684595) (xy 204.71981 -349.682558) (xy 204.664967 -349.672428) (xy 204.612183 -349.654421)
			(xy 204.562583 -349.62892) (xy 204.517225 -349.596469) (xy 204.477076 -349.55776) (xy 204.44299 -349.513617)
			(xy 204.415694 -349.464982) (xy 204.395771 -349.412891) (xy 204.383645 -349.358454) (xy 204.379574 -349.302832)
			(xy 158.632402 -349.302832) (xy 158.080535 -349.899986) (xy 248.589544 -349.899986) (xy 248.593615 -349.844364)
			(xy 248.605741 -349.789927) (xy 248.625664 -349.737836) (xy 248.65296 -349.689201) (xy 248.687046 -349.645058)
			(xy 248.727195 -349.606349) (xy 248.772553 -349.573898) (xy 248.822153 -349.548397) (xy 248.874937 -349.53039)
			(xy 248.92978 -349.52026) (xy 248.985514 -349.518223) (xy 249.040951 -349.524323) (xy 249.094908 -349.538429)
			(xy 249.146237 -349.560241) (xy 249.193843 -349.589295) (xy 249.236711 -349.62497) (xy 249.273928 -349.666507)
			(xy 249.304701 -349.71302) (xy 249.328373 -349.763517) (xy 249.344441 -349.816924) (xy 249.352561 -349.8721)
			(xy 249.35307 -349.899986) (xy 249.352561 -349.927872) (xy 249.344441 -349.983048) (xy 249.328373 -350.036455)
			(xy 249.304701 -350.086952) (xy 249.273928 -350.133465) (xy 249.236711 -350.175002) (xy 249.193843 -350.210677)
			(xy 249.146237 -350.239731) (xy 249.094908 -350.261543) (xy 249.040951 -350.275649) (xy 248.985514 -350.281749)
			(xy 248.92978 -350.279712) (xy 248.874937 -350.269582) (xy 248.822153 -350.251575) (xy 248.772553 -350.226074)
			(xy 248.727195 -350.193623) (xy 248.687046 -350.154914) (xy 248.65296 -350.110771) (xy 248.625664 -350.062136)
			(xy 248.605741 -350.010045) (xy 248.593615 -349.955608) (xy 248.589544 -349.899986) (xy 158.080535 -349.899986)
			(xy 157.329611 -350.712532) (xy 207.046574 -350.712532) (xy 207.050645 -350.65691) (xy 207.062771 -350.602473)
			(xy 207.082694 -350.550382) (xy 207.10999 -350.501747) (xy 207.144076 -350.457604) (xy 207.184225 -350.418895)
			(xy 207.229583 -350.386444) (xy 207.279183 -350.360943) (xy 207.331967 -350.342936) (xy 207.38681 -350.332806)
			(xy 207.442544 -350.330769) (xy 207.497981 -350.336869) (xy 207.551938 -350.350975) (xy 207.603267 -350.372787)
			(xy 207.606005 -350.374458) (xy 236.132368 -350.374458) (xy 236.136439 -350.318836) (xy 236.148565 -350.264399)
			(xy 236.168488 -350.212308) (xy 236.195784 -350.163673) (xy 236.22987 -350.11953) (xy 236.270019 -350.080821)
			(xy 236.315377 -350.04837) (xy 236.364977 -350.022869) (xy 236.417761 -350.004862) (xy 236.472604 -349.994732)
			(xy 236.528338 -349.992695) (xy 236.583775 -349.998795) (xy 236.637732 -350.012901) (xy 236.689061 -350.034713)
			(xy 236.736667 -350.063767) (xy 236.779535 -350.099442) (xy 236.816752 -350.140979) (xy 236.847525 -350.187492)
			(xy 236.871197 -350.237989) (xy 236.887265 -350.291396) (xy 236.895385 -350.346572) (xy 236.895894 -350.374458)
			(xy 236.895385 -350.402344) (xy 236.891705 -350.427353) (xy 240.784067 -350.427353) (xy 240.784067 -350.372847)
			(xy 240.791825 -350.318895) (xy 240.807182 -350.266597) (xy 240.829825 -350.217017) (xy 240.859295 -350.171164)
			(xy 240.89499 -350.129972) (xy 240.936185 -350.094279) (xy 240.98204 -350.064813) (xy 241.031621 -350.042173)
			(xy 241.083921 -350.026819) (xy 241.137873 -350.019066) (xy 241.165126 -350.018604) (xy 241.193321 -350.019079)
			(xy 241.249098 -350.027377) (xy 241.303047 -350.043788) (xy 241.353997 -350.067955) (xy 241.400838 -350.099352)
			(xy 241.442551 -350.137298) (xy 241.460782 -350.158812) (xy 241.46838 -350.167237) (xy 241.488824 -350.176999)
			(xy 241.500152 -350.177608) (xy 241.578892 -350.177608) (xy 241.590208 -350.176941) (xy 241.610641 -350.167201)
			(xy 241.618262 -350.158812) (xy 241.636496 -350.137297) (xy 241.67819 -350.099327) (xy 241.725025 -350.067915)
			(xy 241.775978 -350.043748) (xy 241.829936 -350.027353) (xy 241.885721 -350.019089) (xy 241.913918 -350.018604)
			(xy 241.941169 -350.019067) (xy 241.995117 -350.026826) (xy 242.047411 -350.042183) (xy 242.096987 -350.064826)
			(xy 242.142837 -350.094294) (xy 242.184026 -350.129986) (xy 242.219717 -350.171177) (xy 242.249183 -350.217028)
			(xy 242.271823 -350.266606) (xy 242.287178 -350.318901) (xy 242.294934 -350.372849) (xy 242.294934 -350.427351)
			(xy 242.287178 -350.481299) (xy 242.271823 -350.533594) (xy 242.249183 -350.583172) (xy 242.219717 -350.629023)
			(xy 242.184026 -350.670214) (xy 242.142837 -350.705906) (xy 242.096987 -350.735374) (xy 242.047411 -350.758017)
			(xy 241.995117 -350.773374) (xy 241.941169 -350.781133) (xy 241.913918 -350.78162) (xy 241.885724 -350.781105)
			(xy 241.82995 -350.772814) (xy 241.776001 -350.756411) (xy 241.725052 -350.732251) (xy 241.67821 -350.700861)
			(xy 241.636494 -350.662923) (xy 241.618262 -350.641412) (xy 241.610684 -350.632966) (xy 241.590225 -350.623214)
			(xy 241.578892 -350.622616) (xy 241.500152 -350.622616) (xy 241.488831 -350.623244) (xy 241.468398 -350.633011)
			(xy 241.460782 -350.641412) (xy 241.442585 -350.662958) (xy 241.400882 -350.700926) (xy 241.354039 -350.732333)
			(xy 241.303079 -350.756495) (xy 241.249115 -350.772883) (xy 241.193325 -350.781139) (xy 241.165126 -350.78162)
			(xy 241.137873 -350.781134) (xy 241.083921 -350.773381) (xy 241.031621 -350.758027) (xy 240.98204 -350.735387)
			(xy 240.936185 -350.705921) (xy 240.89499 -350.670228) (xy 240.859295 -350.629036) (xy 240.829825 -350.583183)
			(xy 240.807182 -350.533603) (xy 240.791825 -350.481305) (xy 240.784067 -350.427353) (xy 236.891705 -350.427353)
			(xy 236.887265 -350.45752) (xy 236.871197 -350.510927) (xy 236.847525 -350.561424) (xy 236.816752 -350.607937)
			(xy 236.779535 -350.649474) (xy 236.736667 -350.685149) (xy 236.689061 -350.714203) (xy 236.637732 -350.736015)
			(xy 236.583775 -350.750121) (xy 236.528338 -350.756221) (xy 236.472604 -350.754184) (xy 236.417761 -350.744054)
			(xy 236.364977 -350.726047) (xy 236.315377 -350.700546) (xy 236.270019 -350.668095) (xy 236.22987 -350.629386)
			(xy 236.195784 -350.585243) (xy 236.168488 -350.536608) (xy 236.148565 -350.484517) (xy 236.136439 -350.43008)
			(xy 236.132368 -350.374458) (xy 207.606005 -350.374458) (xy 207.650873 -350.401841) (xy 207.693741 -350.437516)
			(xy 207.730958 -350.479053) (xy 207.761731 -350.525566) (xy 207.785403 -350.576063) (xy 207.801471 -350.62947)
			(xy 207.809591 -350.684646) (xy 207.8101 -350.712532) (xy 207.809591 -350.740418) (xy 207.801471 -350.795594)
			(xy 207.785403 -350.849001) (xy 207.761731 -350.899498) (xy 207.761409 -350.899984) (xy 248.573288 -350.899984)
			(xy 248.577359 -350.844362) (xy 248.589485 -350.789925) (xy 248.609408 -350.737834) (xy 248.636704 -350.689199)
			(xy 248.67079 -350.645056) (xy 248.710939 -350.606347) (xy 248.756297 -350.573896) (xy 248.805897 -350.548395)
			(xy 248.858681 -350.530388) (xy 248.913524 -350.520258) (xy 248.969258 -350.518221) (xy 249.024695 -350.524321)
			(xy 249.078652 -350.538427) (xy 249.129981 -350.560239) (xy 249.177587 -350.589293) (xy 249.220455 -350.624968)
			(xy 249.257672 -350.666505) (xy 249.288445 -350.713018) (xy 249.312117 -350.763515) (xy 249.328185 -350.816922)
			(xy 249.336305 -350.872098) (xy 249.336814 -350.899984) (xy 249.336305 -350.92787) (xy 249.328185 -350.983046)
			(xy 249.312117 -351.036453) (xy 249.288445 -351.08695) (xy 249.257672 -351.133463) (xy 249.220455 -351.175)
			(xy 249.177587 -351.210675) (xy 249.129981 -351.239729) (xy 249.078652 -351.261541) (xy 249.024695 -351.275647)
			(xy 248.969258 -351.281747) (xy 248.913524 -351.27971) (xy 248.858681 -351.26958) (xy 248.805897 -351.251573)
			(xy 248.756297 -351.226072) (xy 248.710939 -351.193621) (xy 248.67079 -351.154912) (xy 248.636704 -351.110769)
			(xy 248.609408 -351.062134) (xy 248.589485 -351.010043) (xy 248.577359 -350.955606) (xy 248.573288 -350.899984)
			(xy 207.761409 -350.899984) (xy 207.730958 -350.946011) (xy 207.693741 -350.987548) (xy 207.650873 -351.023223)
			(xy 207.603267 -351.052277) (xy 207.551938 -351.074089) (xy 207.497981 -351.088195) (xy 207.442544 -351.094295)
			(xy 207.38681 -351.092258) (xy 207.331967 -351.082128) (xy 207.279183 -351.064121) (xy 207.229583 -351.03862)
			(xy 207.184225 -351.006169) (xy 207.144076 -350.96746) (xy 207.10999 -350.923317) (xy 207.082694 -350.874682)
			(xy 207.062771 -350.822591) (xy 207.050645 -350.768154) (xy 207.046574 -350.712532) (xy 157.329611 -350.712532)
			(xy 156.47371 -351.638669) (xy 161.804839 -351.638669) (xy 161.804839 -351.584131) (xy 161.812601 -351.530149)
			(xy 161.827966 -351.47782) (xy 161.850623 -351.428211) (xy 161.880108 -351.382331) (xy 161.915824 -351.341115)
			(xy 161.957041 -351.305401) (xy 162.002922 -351.275917) (xy 162.052531 -351.253262) (xy 162.10486 -351.237899)
			(xy 162.158843 -351.230139) (xy 162.186112 -351.229676) (xy 163.049712 -351.229676) (xy 163.076984 -351.230087)
			(xy 163.130971 -351.237851) (xy 163.183304 -351.253219) (xy 163.232918 -351.275878) (xy 163.278802 -351.305367)
			(xy 163.320022 -351.341086) (xy 163.35574 -351.382308) (xy 163.385228 -351.428192) (xy 163.407885 -351.477807)
			(xy 163.423251 -351.530141) (xy 163.431014 -351.584128) (xy 163.431014 -351.638665) (xy 164.913862 -351.638665)
			(xy 164.913862 -351.584135) (xy 164.921622 -351.530159) (xy 164.936985 -351.477837) (xy 164.959637 -351.428233)
			(xy 164.989117 -351.382358) (xy 165.024826 -351.341146) (xy 165.066036 -351.305434) (xy 165.111909 -351.27595)
			(xy 165.16151 -351.253295) (xy 165.213831 -351.237928) (xy 165.267807 -351.230164) (xy 165.295072 -351.229676)
			(xy 166.158672 -351.229676) (xy 166.185947 -351.230062) (xy 166.239942 -351.237821) (xy 166.292284 -351.253187)
			(xy 166.341905 -351.275845) (xy 166.387797 -351.305335) (xy 166.429024 -351.341056) (xy 166.464748 -351.382281)
			(xy 166.494242 -351.42817) (xy 166.516903 -351.47779) (xy 166.532273 -351.53013) (xy 166.540036 -351.584125)
			(xy 166.540036 -351.63867) (xy 168.022739 -351.63867) (xy 168.022739 -351.58413) (xy 168.030502 -351.530146)
			(xy 168.045868 -351.477816) (xy 168.068526 -351.428206) (xy 168.098013 -351.382325) (xy 168.133731 -351.341108)
			(xy 168.174951 -351.305394) (xy 168.220834 -351.27591) (xy 168.270446 -351.253257) (xy 168.322777 -351.237895)
			(xy 168.376762 -351.230137) (xy 168.404032 -351.229676) (xy 169.267632 -351.229676) (xy 169.294903 -351.230089)
			(xy 169.348888 -351.237855) (xy 169.401219 -351.253224) (xy 169.45083 -351.275885) (xy 169.496712 -351.305374)
			(xy 169.537929 -351.341093) (xy 169.573645 -351.382314) (xy 169.603131 -351.428198) (xy 169.625787 -351.477811)
			(xy 169.641152 -351.530143) (xy 169.648914 -351.584129) (xy 169.648914 -351.638666) (xy 171.131762 -351.638666)
			(xy 171.131762 -351.584134) (xy 171.139523 -351.530156) (xy 171.154886 -351.477832) (xy 171.17754 -351.428228)
			(xy 171.207022 -351.382352) (xy 171.242733 -351.341138) (xy 171.283945 -351.305427) (xy 171.329821 -351.275944)
			(xy 171.379425 -351.253289) (xy 171.431748 -351.237925) (xy 171.485726 -351.230163) (xy 171.512992 -351.229676)
			(xy 172.376592 -351.229676) (xy 172.403866 -351.230063) (xy 172.457859 -351.237825) (xy 172.510198 -351.253192)
			(xy 172.559817 -351.275851) (xy 172.605706 -351.305342) (xy 172.646932 -351.341063) (xy 172.682653 -351.382287)
			(xy 172.712145 -351.428176) (xy 172.734805 -351.477794) (xy 172.750173 -351.530133) (xy 172.757936 -351.584126)
			(xy 172.757936 -351.638664) (xy 174.240762 -351.638664) (xy 174.240762 -351.584136) (xy 174.248522 -351.530162)
			(xy 174.263883 -351.477841) (xy 174.286534 -351.428239) (xy 174.316012 -351.382365) (xy 174.351719 -351.341153)
			(xy 174.392926 -351.305441) (xy 174.438797 -351.275957) (xy 174.488396 -351.2533) (xy 174.540715 -351.237932)
			(xy 174.594688 -351.230166) (xy 174.621952 -351.229676) (xy 175.485552 -351.229676) (xy 175.512828 -351.23006)
			(xy 175.566825 -351.237818) (xy 175.619169 -351.253181) (xy 175.668793 -351.275838) (xy 175.714687 -351.305328)
			(xy 175.755917 -351.341049) (xy 175.791644 -351.382274) (xy 175.821139 -351.428165) (xy 175.843802 -351.477786)
			(xy 175.859172 -351.530128) (xy 175.866936 -351.584124) (xy 175.866936 -351.638669) (xy 177.349639 -351.638669)
			(xy 177.349639 -351.584131) (xy 177.357401 -351.530149) (xy 177.372766 -351.47782) (xy 177.395423 -351.428211)
			(xy 177.424908 -351.382331) (xy 177.460624 -351.341115) (xy 177.501841 -351.305401) (xy 177.547722 -351.275917)
			(xy 177.597331 -351.253262) (xy 177.64966 -351.237899) (xy 177.703643 -351.230139) (xy 177.730912 -351.229676)
			(xy 178.594512 -351.229676) (xy 178.621784 -351.230087) (xy 178.675771 -351.237851) (xy 178.728104 -351.253219)
			(xy 178.777718 -351.275878) (xy 178.823602 -351.305367) (xy 178.864822 -351.341086) (xy 178.90054 -351.382308)
			(xy 178.930028 -351.428192) (xy 178.952685 -351.477807) (xy 178.968051 -351.530141) (xy 178.975814 -351.584128)
			(xy 178.975814 -351.638665) (xy 180.458662 -351.638665) (xy 180.458662 -351.584135) (xy 180.466422 -351.530159)
			(xy 180.481785 -351.477837) (xy 180.504437 -351.428233) (xy 180.533917 -351.382358) (xy 180.569626 -351.341146)
			(xy 180.610836 -351.305434) (xy 180.656709 -351.27595) (xy 180.70631 -351.253295) (xy 180.758631 -351.237928)
			(xy 180.812607 -351.230164) (xy 180.839872 -351.229676) (xy 181.703472 -351.229676) (xy 181.730747 -351.230062)
			(xy 181.784742 -351.237821) (xy 181.837084 -351.253187) (xy 181.886705 -351.275845) (xy 181.932597 -351.305335)
			(xy 181.973824 -351.341056) (xy 182.009548 -351.382281) (xy 182.039042 -351.42817) (xy 182.061703 -351.47779)
			(xy 182.077073 -351.53013) (xy 182.084836 -351.584125) (xy 182.084836 -351.63867) (xy 183.567539 -351.63867)
			(xy 183.567539 -351.58413) (xy 183.575302 -351.530146) (xy 183.590668 -351.477816) (xy 183.613326 -351.428206)
			(xy 183.642813 -351.382325) (xy 183.678531 -351.341108) (xy 183.719751 -351.305394) (xy 183.765634 -351.27591)
			(xy 183.815246 -351.253257) (xy 183.867577 -351.237895) (xy 183.921562 -351.230137) (xy 183.948832 -351.229676)
			(xy 184.812432 -351.229676) (xy 184.839703 -351.230089) (xy 184.893688 -351.237855) (xy 184.946019 -351.253224)
			(xy 184.99563 -351.275885) (xy 185.041512 -351.305374) (xy 185.082729 -351.341093) (xy 185.118445 -351.382314)
			(xy 185.147931 -351.428198) (xy 185.170587 -351.477811) (xy 185.185952 -351.530143) (xy 185.193714 -351.584129)
			(xy 185.193714 -351.638666) (xy 186.676562 -351.638666) (xy 186.676562 -351.584134) (xy 186.684323 -351.530156)
			(xy 186.699686 -351.477832) (xy 186.72234 -351.428228) (xy 186.751822 -351.382352) (xy 186.787533 -351.341138)
			(xy 186.828745 -351.305427) (xy 186.874621 -351.275944) (xy 186.924225 -351.253289) (xy 186.976548 -351.237925)
			(xy 187.030526 -351.230163) (xy 187.057792 -351.229676) (xy 187.921392 -351.229676) (xy 187.948666 -351.230063)
			(xy 188.002659 -351.237825) (xy 188.054998 -351.253192) (xy 188.104617 -351.275851) (xy 188.150506 -351.305342)
			(xy 188.191732 -351.341063) (xy 188.227453 -351.382287) (xy 188.256945 -351.428176) (xy 188.279605 -351.477794)
			(xy 188.294973 -351.530133) (xy 188.302736 -351.584126) (xy 188.302736 -351.638664) (xy 189.785562 -351.638664)
			(xy 189.785562 -351.584136) (xy 189.793322 -351.530162) (xy 189.808683 -351.477841) (xy 189.831334 -351.428239)
			(xy 189.860812 -351.382365) (xy 189.896519 -351.341153) (xy 189.937726 -351.305441) (xy 189.983597 -351.275957)
			(xy 190.033196 -351.2533) (xy 190.085515 -351.237932) (xy 190.139488 -351.230166) (xy 190.166752 -351.229676)
			(xy 191.030352 -351.229676) (xy 191.057628 -351.23006) (xy 191.111625 -351.237818) (xy 191.163969 -351.253181)
			(xy 191.213593 -351.275838) (xy 191.259487 -351.305328) (xy 191.300717 -351.341049) (xy 191.336444 -351.382274)
			(xy 191.365939 -351.428165) (xy 191.388602 -351.477786) (xy 191.403972 -351.530128) (xy 191.411736 -351.584124)
			(xy 191.411736 -351.638669) (xy 192.894439 -351.638669) (xy 192.894439 -351.584131) (xy 192.902201 -351.530149)
			(xy 192.917566 -351.47782) (xy 192.940223 -351.428211) (xy 192.969708 -351.382331) (xy 193.005424 -351.341115)
			(xy 193.046641 -351.305401) (xy 193.092522 -351.275917) (xy 193.142131 -351.253262) (xy 193.19446 -351.237899)
			(xy 193.248443 -351.230139) (xy 193.275712 -351.229676) (xy 194.139312 -351.229676) (xy 194.166584 -351.230087)
			(xy 194.220571 -351.237851) (xy 194.272904 -351.253219) (xy 194.322518 -351.275878) (xy 194.368402 -351.305367)
			(xy 194.409622 -351.341086) (xy 194.44534 -351.382308) (xy 194.474828 -351.428192) (xy 194.491002 -351.46361)
			(xy 204.379574 -351.46361) (xy 204.383645 -351.407988) (xy 204.395771 -351.353551) (xy 204.415694 -351.30146)
			(xy 204.44299 -351.252825) (xy 204.477076 -351.208682) (xy 204.517225 -351.169973) (xy 204.562583 -351.137522)
			(xy 204.612183 -351.112021) (xy 204.664967 -351.094014) (xy 204.71981 -351.083884) (xy 204.775544 -351.081847)
			(xy 204.830981 -351.087947) (xy 204.884938 -351.102053) (xy 204.936267 -351.123865) (xy 204.983873 -351.152919)
			(xy 205.026741 -351.188594) (xy 205.063958 -351.230131) (xy 205.094731 -351.276644) (xy 205.118403 -351.327141)
			(xy 205.124996 -351.349056) (xy 233.362752 -351.349056) (xy 233.366823 -351.293434) (xy 233.378949 -351.238997)
			(xy 233.398872 -351.186906) (xy 233.426168 -351.138271) (xy 233.460254 -351.094128) (xy 233.500403 -351.055419)
			(xy 233.545761 -351.022968) (xy 233.595361 -350.997467) (xy 233.648145 -350.97946) (xy 233.702988 -350.96933)
			(xy 233.758722 -350.967293) (xy 233.814159 -350.973393) (xy 233.868116 -350.987499) (xy 233.919445 -351.009311)
			(xy 233.967051 -351.038365) (xy 234.009919 -351.07404) (xy 234.047136 -351.115577) (xy 234.077909 -351.16209)
			(xy 234.101581 -351.212587) (xy 234.117649 -351.265994) (xy 234.125769 -351.32117) (xy 234.126106 -351.339658)
			(xy 236.132368 -351.339658) (xy 236.136439 -351.284036) (xy 236.148565 -351.229599) (xy 236.168488 -351.177508)
			(xy 236.195784 -351.128873) (xy 236.22987 -351.08473) (xy 236.270019 -351.046021) (xy 236.315377 -351.01357)
			(xy 236.364977 -350.988069) (xy 236.417761 -350.970062) (xy 236.472604 -350.959932) (xy 236.528338 -350.957895)
			(xy 236.583775 -350.963995) (xy 236.637732 -350.978101) (xy 236.689061 -350.999913) (xy 236.736667 -351.028967)
			(xy 236.779535 -351.064642) (xy 236.816752 -351.106179) (xy 236.847525 -351.152692) (xy 236.871197 -351.203189)
			(xy 236.887265 -351.256596) (xy 236.895385 -351.311772) (xy 236.895894 -351.339658) (xy 236.895385 -351.367544)
			(xy 236.890592 -351.40011) (xy 241.568476 -351.40011) (xy 241.572547 -351.344488) (xy 241.584673 -351.290051)
			(xy 241.604596 -351.23796) (xy 241.631892 -351.189325) (xy 241.665978 -351.145182) (xy 241.706127 -351.106473)
			(xy 241.751485 -351.074022) (xy 241.801085 -351.048521) (xy 241.853869 -351.030514) (xy 241.908712 -351.020384)
			(xy 241.964446 -351.018347) (xy 242.019883 -351.024447) (xy 242.07384 -351.038553) (xy 242.125169 -351.060365)
			(xy 242.172775 -351.089419) (xy 242.215643 -351.125094) (xy 242.25286 -351.166631) (xy 242.283633 -351.213144)
			(xy 242.307305 -351.263641) (xy 242.323373 -351.317048) (xy 242.331493 -351.372224) (xy 242.332002 -351.40011)
			(xy 242.331493 -351.427996) (xy 242.323373 -351.483172) (xy 242.307305 -351.536579) (xy 242.283633 -351.587076)
			(xy 242.25286 -351.633589) (xy 242.215643 -351.675126) (xy 242.172775 -351.710801) (xy 242.125169 -351.739855)
			(xy 242.07384 -351.761667) (xy 242.019883 -351.775773) (xy 241.964446 -351.781873) (xy 241.908712 -351.779836)
			(xy 241.853869 -351.769706) (xy 241.801085 -351.751699) (xy 241.751485 -351.726198) (xy 241.706127 -351.693747)
			(xy 241.665978 -351.655038) (xy 241.631892 -351.610895) (xy 241.604596 -351.56226) (xy 241.584673 -351.510169)
			(xy 241.572547 -351.455732) (xy 241.568476 -351.40011) (xy 236.890592 -351.40011) (xy 236.887265 -351.42272)
			(xy 236.871197 -351.476127) (xy 236.847525 -351.526624) (xy 236.816752 -351.573137) (xy 236.779535 -351.614674)
			(xy 236.736667 -351.650349) (xy 236.689061 -351.679403) (xy 236.637732 -351.701215) (xy 236.583775 -351.715321)
			(xy 236.528338 -351.721421) (xy 236.472604 -351.719384) (xy 236.417761 -351.709254) (xy 236.364977 -351.691247)
			(xy 236.315377 -351.665746) (xy 236.270019 -351.633295) (xy 236.22987 -351.594586) (xy 236.195784 -351.550443)
			(xy 236.168488 -351.501808) (xy 236.148565 -351.449717) (xy 236.136439 -351.39528) (xy 236.132368 -351.339658)
			(xy 234.126106 -351.339658) (xy 234.126278 -351.349056) (xy 234.125769 -351.376942) (xy 234.117649 -351.432118)
			(xy 234.101581 -351.485525) (xy 234.077909 -351.536022) (xy 234.047136 -351.582535) (xy 234.009919 -351.624072)
			(xy 233.967051 -351.659747) (xy 233.919445 -351.688801) (xy 233.868116 -351.710613) (xy 233.814159 -351.724719)
			(xy 233.758722 -351.730819) (xy 233.702988 -351.728782) (xy 233.648145 -351.718652) (xy 233.595361 -351.700645)
			(xy 233.545761 -351.675144) (xy 233.500403 -351.642693) (xy 233.460254 -351.603984) (xy 233.426168 -351.559841)
			(xy 233.398872 -351.511206) (xy 233.378949 -351.459115) (xy 233.366823 -351.404678) (xy 233.362752 -351.349056)
			(xy 205.124996 -351.349056) (xy 205.134471 -351.380548) (xy 205.142591 -351.435724) (xy 205.1431 -351.46361)
			(xy 205.142591 -351.491496) (xy 205.134471 -351.546672) (xy 205.118403 -351.600079) (xy 205.094731 -351.650576)
			(xy 205.063958 -351.697089) (xy 205.026741 -351.738626) (xy 204.983873 -351.774301) (xy 204.936267 -351.803355)
			(xy 204.884938 -351.825167) (xy 204.830981 -351.839273) (xy 204.775544 -351.845373) (xy 204.71981 -351.843336)
			(xy 204.664967 -351.833206) (xy 204.612183 -351.815199) (xy 204.562583 -351.789698) (xy 204.517225 -351.757247)
			(xy 204.477076 -351.718538) (xy 204.44299 -351.674395) (xy 204.415694 -351.62576) (xy 204.395771 -351.573669)
			(xy 204.383645 -351.519232) (xy 204.379574 -351.46361) (xy 194.491002 -351.46361) (xy 194.497485 -351.477807)
			(xy 194.512851 -351.530141) (xy 194.520614 -351.584128) (xy 194.520614 -351.638672) (xy 194.512851 -351.692659)
			(xy 194.497485 -351.744993) (xy 194.474828 -351.794608) (xy 194.44534 -351.840492) (xy 194.409622 -351.881714)
			(xy 194.368402 -351.917433) (xy 194.322518 -351.946922) (xy 194.272904 -351.969581) (xy 194.220571 -351.984949)
			(xy 194.166584 -351.992713) (xy 194.139312 -351.9932) (xy 193.275712 -351.9932) (xy 193.248443 -351.992661)
			(xy 193.19446 -351.984901) (xy 193.142131 -351.969538) (xy 193.092522 -351.946883) (xy 193.046641 -351.917399)
			(xy 193.005424 -351.881685) (xy 192.969708 -351.840469) (xy 192.940223 -351.794589) (xy 192.917566 -351.74498)
			(xy 192.902201 -351.692651) (xy 192.894439 -351.638669) (xy 191.411736 -351.638669) (xy 191.411736 -351.638676)
			(xy 191.403972 -351.692672) (xy 191.388602 -351.745014) (xy 191.365939 -351.794635) (xy 191.336444 -351.840526)
			(xy 191.300717 -351.881751) (xy 191.259487 -351.917472) (xy 191.213593 -351.946962) (xy 191.163969 -351.969619)
			(xy 191.111625 -351.984982) (xy 191.057628 -351.99274) (xy 191.030352 -351.9932) (xy 190.166752 -351.9932)
			(xy 190.139488 -351.992634) (xy 190.085515 -351.984868) (xy 190.033196 -351.9695) (xy 189.983597 -351.946843)
			(xy 189.937726 -351.917359) (xy 189.896519 -351.881647) (xy 189.860812 -351.840435) (xy 189.831334 -351.794561)
			(xy 189.808683 -351.744959) (xy 189.793322 -351.692639) (xy 189.785562 -351.638664) (xy 188.302736 -351.638664)
			(xy 188.302736 -351.638674) (xy 188.294973 -351.692667) (xy 188.279605 -351.745006) (xy 188.256945 -351.794624)
			(xy 188.227453 -351.840513) (xy 188.191732 -351.881737) (xy 188.150506 -351.917458) (xy 188.104617 -351.946949)
			(xy 188.054998 -351.969608) (xy 188.002659 -351.984975) (xy 187.948666 -351.992737) (xy 187.921392 -351.9932)
			(xy 187.057792 -351.9932) (xy 187.030526 -351.992637) (xy 186.976548 -351.984875) (xy 186.924225 -351.969511)
			(xy 186.874621 -351.946856) (xy 186.828745 -351.917373) (xy 186.787533 -351.881662) (xy 186.751822 -351.840448)
			(xy 186.72234 -351.794572) (xy 186.699686 -351.744968) (xy 186.684323 -351.692644) (xy 186.676562 -351.638666)
			(xy 185.193714 -351.638666) (xy 185.193714 -351.638671) (xy 185.185952 -351.692657) (xy 185.170587 -351.744989)
			(xy 185.147931 -351.794602) (xy 185.118445 -351.840486) (xy 185.082729 -351.881707) (xy 185.041512 -351.917426)
			(xy 184.99563 -351.946915) (xy 184.946019 -351.969576) (xy 184.893688 -351.984945) (xy 184.839703 -351.992711)
			(xy 184.812432 -351.9932) (xy 183.948832 -351.9932) (xy 183.921562 -351.992663) (xy 183.867577 -351.984905)
			(xy 183.815246 -351.969543) (xy 183.765634 -351.94689) (xy 183.719751 -351.917406) (xy 183.678531 -351.881692)
			(xy 183.642813 -351.840475) (xy 183.613326 -351.794594) (xy 183.590668 -351.744984) (xy 183.575302 -351.692654)
			(xy 183.567539 -351.63867) (xy 182.084836 -351.63867) (xy 182.084836 -351.638675) (xy 182.077073 -351.69267)
			(xy 182.061703 -351.74501) (xy 182.039042 -351.79463) (xy 182.009548 -351.840519) (xy 181.973824 -351.881744)
			(xy 181.932597 -351.917465) (xy 181.886705 -351.946955) (xy 181.837084 -351.969613) (xy 181.784742 -351.984979)
			(xy 181.730747 -351.992738) (xy 181.703472 -351.9932) (xy 180.839872 -351.9932) (xy 180.812607 -351.992636)
			(xy 180.758631 -351.984872) (xy 180.70631 -351.969505) (xy 180.656709 -351.94685) (xy 180.610836 -351.917366)
			(xy 180.569626 -351.881654) (xy 180.533917 -351.840442) (xy 180.504437 -351.794567) (xy 180.481785 -351.744963)
			(xy 180.466422 -351.692641) (xy 180.458662 -351.638665) (xy 178.975814 -351.638665) (xy 178.975814 -351.638672)
			(xy 178.968051 -351.692659) (xy 178.952685 -351.744993) (xy 178.930028 -351.794608) (xy 178.90054 -351.840492)
			(xy 178.864822 -351.881714) (xy 178.823602 -351.917433) (xy 178.777718 -351.946922) (xy 178.728104 -351.969581)
			(xy 178.675771 -351.984949) (xy 178.621784 -351.992713) (xy 178.594512 -351.9932) (xy 177.730912 -351.9932)
			(xy 177.703643 -351.992661) (xy 177.64966 -351.984901) (xy 177.597331 -351.969538) (xy 177.547722 -351.946883)
			(xy 177.501841 -351.917399) (xy 177.460624 -351.881685) (xy 177.424908 -351.840469) (xy 177.395423 -351.794589)
			(xy 177.372766 -351.74498) (xy 177.357401 -351.692651) (xy 177.349639 -351.638669) (xy 175.866936 -351.638669)
			(xy 175.866936 -351.638676) (xy 175.859172 -351.692672) (xy 175.843802 -351.745014) (xy 175.821139 -351.794635)
			(xy 175.791644 -351.840526) (xy 175.755917 -351.881751) (xy 175.714687 -351.917472) (xy 175.668793 -351.946962)
			(xy 175.619169 -351.969619) (xy 175.566825 -351.984982) (xy 175.512828 -351.99274) (xy 175.485552 -351.9932)
			(xy 174.621952 -351.9932) (xy 174.594688 -351.992634) (xy 174.540715 -351.984868) (xy 174.488396 -351.9695)
			(xy 174.438797 -351.946843) (xy 174.392926 -351.917359) (xy 174.351719 -351.881647) (xy 174.316012 -351.840435)
			(xy 174.286534 -351.794561) (xy 174.263883 -351.744959) (xy 174.248522 -351.692639) (xy 174.240762 -351.638664)
			(xy 172.757936 -351.638664) (xy 172.757936 -351.638674) (xy 172.750173 -351.692667) (xy 172.734805 -351.745006)
			(xy 172.712145 -351.794624) (xy 172.682653 -351.840513) (xy 172.646932 -351.881737) (xy 172.605706 -351.917458)
			(xy 172.559817 -351.946949) (xy 172.510198 -351.969608) (xy 172.457859 -351.984975) (xy 172.403866 -351.992737)
			(xy 172.376592 -351.9932) (xy 171.512992 -351.9932) (xy 171.485726 -351.992637) (xy 171.431748 -351.984875)
			(xy 171.379425 -351.969511) (xy 171.329821 -351.946856) (xy 171.283945 -351.917373) (xy 171.242733 -351.881662)
			(xy 171.207022 -351.840448) (xy 171.17754 -351.794572) (xy 171.154886 -351.744968) (xy 171.139523 -351.692644)
			(xy 171.131762 -351.638666) (xy 169.648914 -351.638666) (xy 169.648914 -351.638671) (xy 169.641152 -351.692657)
			(xy 169.625787 -351.744989) (xy 169.603131 -351.794602) (xy 169.573645 -351.840486) (xy 169.537929 -351.881707)
			(xy 169.496712 -351.917426) (xy 169.45083 -351.946915) (xy 169.401219 -351.969576) (xy 169.348888 -351.984945)
			(xy 169.294903 -351.992711) (xy 169.267632 -351.9932) (xy 168.404032 -351.9932) (xy 168.376762 -351.992663)
			(xy 168.322777 -351.984905) (xy 168.270446 -351.969543) (xy 168.220834 -351.94689) (xy 168.174951 -351.917406)
			(xy 168.133731 -351.881692) (xy 168.098013 -351.840475) (xy 168.068526 -351.794594) (xy 168.045868 -351.744984)
			(xy 168.030502 -351.692654) (xy 168.022739 -351.63867) (xy 166.540036 -351.63867) (xy 166.540036 -351.638675)
			(xy 166.532273 -351.69267) (xy 166.516903 -351.74501) (xy 166.494242 -351.79463) (xy 166.464748 -351.840519)
			(xy 166.429024 -351.881744) (xy 166.387797 -351.917465) (xy 166.341905 -351.946955) (xy 166.292284 -351.969613)
			(xy 166.239942 -351.984979) (xy 166.185947 -351.992738) (xy 166.158672 -351.9932) (xy 165.295072 -351.9932)
			(xy 165.267807 -351.992636) (xy 165.213831 -351.984872) (xy 165.16151 -351.969505) (xy 165.111909 -351.94685)
			(xy 165.066036 -351.917366) (xy 165.024826 -351.881654) (xy 164.989117 -351.840442) (xy 164.959637 -351.794567)
			(xy 164.936985 -351.744963) (xy 164.921622 -351.692641) (xy 164.913862 -351.638665) (xy 163.431014 -351.638665)
			(xy 163.431014 -351.638672) (xy 163.423251 -351.692659) (xy 163.407885 -351.744993) (xy 163.385228 -351.794608)
			(xy 163.35574 -351.840492) (xy 163.320022 -351.881714) (xy 163.278802 -351.917433) (xy 163.232918 -351.946922)
			(xy 163.183304 -351.969581) (xy 163.130971 -351.984949) (xy 163.076984 -351.992713) (xy 163.049712 -351.9932)
			(xy 162.186112 -351.9932) (xy 162.158843 -351.992661) (xy 162.10486 -351.984901) (xy 162.052531 -351.969538)
			(xy 162.002922 -351.946883) (xy 161.957041 -351.917399) (xy 161.915824 -351.881685) (xy 161.880108 -351.840469)
			(xy 161.850623 -351.794589) (xy 161.827966 -351.74498) (xy 161.812601 -351.692651) (xy 161.804839 -351.638669)
			(xy 156.47371 -351.638669) (xy 155.982924 -352.16973) (xy 155.855237 -352.307906) (xy 233.389422 -352.307906)
			(xy 233.393493 -352.252284) (xy 233.405619 -352.197847) (xy 233.425542 -352.145756) (xy 233.452838 -352.097121)
			(xy 233.486924 -352.052978) (xy 233.527073 -352.014269) (xy 233.572431 -351.981818) (xy 233.622031 -351.956317)
			(xy 233.674815 -351.93831) (xy 233.729658 -351.92818) (xy 233.785392 -351.926143) (xy 233.840829 -351.932243)
			(xy 233.894786 -351.946349) (xy 233.946115 -351.968161) (xy 233.993721 -351.997215) (xy 234.036589 -352.03289)
			(xy 234.073806 -352.074427) (xy 234.104579 -352.12094) (xy 234.128251 -352.171437) (xy 234.144319 -352.224844)
			(xy 234.152439 -352.28002) (xy 234.152892 -352.304858) (xy 236.132368 -352.304858) (xy 236.136439 -352.249236)
			(xy 236.148565 -352.194799) (xy 236.168488 -352.142708) (xy 236.195784 -352.094073) (xy 236.22987 -352.04993)
			(xy 236.270019 -352.011221) (xy 236.315377 -351.97877) (xy 236.364977 -351.953269) (xy 236.417761 -351.935262)
			(xy 236.472604 -351.925132) (xy 236.528338 -351.923095) (xy 236.583775 -351.929195) (xy 236.637732 -351.943301)
			(xy 236.689061 -351.965113) (xy 236.736667 -351.994167) (xy 236.779535 -352.029842) (xy 236.816752 -352.071379)
			(xy 236.847525 -352.117892) (xy 236.871197 -352.168389) (xy 236.887265 -352.221796) (xy 236.895385 -352.276972)
			(xy 236.895894 -352.304858) (xy 236.895385 -352.332744) (xy 236.887265 -352.38792) (xy 236.883598 -352.400108)
			(xy 241.607846 -352.400108) (xy 241.611917 -352.344486) (xy 241.624043 -352.290049) (xy 241.643966 -352.237958)
			(xy 241.671262 -352.189323) (xy 241.705348 -352.14518) (xy 241.745497 -352.106471) (xy 241.790855 -352.07402)
			(xy 241.840455 -352.048519) (xy 241.893239 -352.030512) (xy 241.948082 -352.020382) (xy 242.003816 -352.018345)
			(xy 242.059253 -352.024445) (xy 242.11321 -352.038551) (xy 242.164539 -352.060363) (xy 242.179346 -352.0694)
			(xy 248.537476 -352.0694) (xy 248.537962 -352.042149) (xy 248.545718 -351.988201) (xy 248.561073 -351.935906)
			(xy 248.583715 -351.886329) (xy 248.613181 -351.840479) (xy 248.648872 -351.799288) (xy 248.690063 -351.763597)
			(xy 248.735913 -351.734131) (xy 248.78549 -351.711489) (xy 248.837785 -351.696134) (xy 248.891733 -351.688378)
			(xy 248.946235 -351.688378) (xy 249.000183 -351.696134) (xy 249.052478 -351.711489) (xy 249.102055 -351.734131)
			(xy 249.147905 -351.763597) (xy 249.189096 -351.799288) (xy 249.224787 -351.840479) (xy 249.254253 -351.886329)
			(xy 249.276895 -351.935906) (xy 249.29225 -351.988201) (xy 249.300006 -352.042149) (xy 249.300492 -352.0694)
			(xy 249.30006 -352.09683) (xy 249.292182 -352.151123) (xy 249.276617 -352.20373) (xy 249.253686 -352.253569)
			(xy 249.223861 -352.299614) (xy 249.187754 -352.340918) (xy 249.146109 -352.376632) (xy 249.1232 -352.391726)
			(xy 249.11084 -352.400294) (xy 249.091263 -352.423097) (xy 249.079171 -352.45061) (xy 249.07561 -352.480453)
			(xy 249.080889 -352.510039) (xy 249.094552 -352.536808) (xy 249.115414 -352.558442) (xy 249.12828 -352.566224)
			(xy 249.153419 -352.580761) (xy 249.199351 -352.616288) (xy 249.239371 -352.658364) (xy 249.272556 -352.706016)
			(xy 249.29814 -352.758145) (xy 249.315532 -352.813548) (xy 249.324332 -352.870946) (xy 249.324876 -352.89998)
			(xy 249.32439 -352.927231) (xy 249.316634 -352.981179) (xy 249.301279 -353.033474) (xy 249.278637 -353.083051)
			(xy 249.249171 -353.128901) (xy 249.21348 -353.170092) (xy 249.172289 -353.205783) (xy 249.126439 -353.235249)
			(xy 249.076862 -353.257891) (xy 249.024567 -353.273246) (xy 248.970619 -353.281002) (xy 248.916117 -353.281002)
			(xy 248.862169 -353.273246) (xy 248.809874 -353.257891) (xy 248.760297 -353.235249) (xy 248.714447 -353.205783)
			(xy 248.673256 -353.170092) (xy 248.637565 -353.128901) (xy 248.608099 -353.083051) (xy 248.585457 -353.033474)
			(xy 248.570102 -352.981179) (xy 248.562346 -352.927231) (xy 248.56186 -352.89998) (xy 248.562376 -352.872553)
			(xy 248.570242 -352.818265) (xy 248.585793 -352.765661) (xy 248.608711 -352.715823) (xy 248.638523 -352.669777)
			(xy 248.674617 -352.62847) (xy 248.716249 -352.592751) (xy 248.739152 -352.577654) (xy 248.751525 -352.569107)
			(xy 248.771093 -352.546296) (xy 248.783177 -352.518779) (xy 248.786733 -352.488937) (xy 248.781453 -352.45935)
			(xy 248.767793 -352.43258) (xy 248.746936 -352.410942) (xy 248.734072 -352.403156) (xy 248.708914 -352.388652)
			(xy 248.662984 -352.353117) (xy 248.622966 -352.311035) (xy 248.589784 -352.263378) (xy 248.564204 -352.211244)
			(xy 248.546815 -352.155837) (xy 248.538019 -352.098436) (xy 248.537476 -352.0694) (xy 242.179346 -352.0694)
			(xy 242.212145 -352.089417) (xy 242.255013 -352.125092) (xy 242.29223 -352.166629) (xy 242.323003 -352.213142)
			(xy 242.346675 -352.263639) (xy 242.362743 -352.317046) (xy 242.370863 -352.372222) (xy 242.371372 -352.400108)
			(xy 242.370863 -352.427994) (xy 242.362743 -352.48317) (xy 242.346675 -352.536577) (xy 242.323003 -352.587074)
			(xy 242.29223 -352.633587) (xy 242.255013 -352.675124) (xy 242.212145 -352.710799) (xy 242.164539 -352.739853)
			(xy 242.11321 -352.761665) (xy 242.059253 -352.775771) (xy 242.003816 -352.781871) (xy 241.948082 -352.779834)
			(xy 241.893239 -352.769704) (xy 241.840455 -352.751697) (xy 241.790855 -352.726196) (xy 241.745497 -352.693745)
			(xy 241.705348 -352.655036) (xy 241.671262 -352.610893) (xy 241.643966 -352.562258) (xy 241.624043 -352.510167)
			(xy 241.611917 -352.45573) (xy 241.607846 -352.400108) (xy 236.883598 -352.400108) (xy 236.871197 -352.441327)
			(xy 236.847525 -352.491824) (xy 236.816752 -352.538337) (xy 236.779535 -352.579874) (xy 236.736667 -352.615549)
			(xy 236.689061 -352.644603) (xy 236.637732 -352.666415) (xy 236.583775 -352.680521) (xy 236.528338 -352.686621)
			(xy 236.472604 -352.684584) (xy 236.417761 -352.674454) (xy 236.364977 -352.656447) (xy 236.315377 -352.630946)
			(xy 236.270019 -352.598495) (xy 236.22987 -352.559786) (xy 236.195784 -352.515643) (xy 236.168488 -352.467008)
			(xy 236.148565 -352.414917) (xy 236.136439 -352.36048) (xy 236.132368 -352.304858) (xy 234.152892 -352.304858)
			(xy 234.152948 -352.307906) (xy 234.152439 -352.335792) (xy 234.144319 -352.390968) (xy 234.128251 -352.444375)
			(xy 234.104579 -352.494872) (xy 234.073806 -352.541385) (xy 234.036589 -352.582922) (xy 233.993721 -352.618597)
			(xy 233.946115 -352.647651) (xy 233.894786 -352.669463) (xy 233.840829 -352.683569) (xy 233.785392 -352.689669)
			(xy 233.729658 -352.687632) (xy 233.674815 -352.677502) (xy 233.622031 -352.659495) (xy 233.572431 -352.633994)
			(xy 233.527073 -352.601543) (xy 233.486924 -352.562834) (xy 233.452838 -352.518691) (xy 233.425542 -352.470056)
			(xy 233.405619 -352.417965) (xy 233.393493 -352.363528) (xy 233.389422 -352.307906) (xy 155.855237 -352.307906)
			(xy 155.182062 -353.036378) (xy 155.176696 -353.042711) (xy 155.169955 -353.057869) (xy 155.168854 -353.066096)
			(xy 155.1686 -353.070668) (xy 155.1686 -353.270058) (xy 236.132368 -353.270058) (xy 236.136439 -353.214436)
			(xy 236.148565 -353.159999) (xy 236.168488 -353.107908) (xy 236.195784 -353.059273) (xy 236.22987 -353.01513)
			(xy 236.270019 -352.976421) (xy 236.315377 -352.94397) (xy 236.364977 -352.918469) (xy 236.417761 -352.900462)
			(xy 236.472604 -352.890332) (xy 236.528338 -352.888295) (xy 236.583775 -352.894395) (xy 236.637732 -352.908501)
			(xy 236.689061 -352.930313) (xy 236.736667 -352.959367) (xy 236.779535 -352.995042) (xy 236.816752 -353.036579)
			(xy 236.847525 -353.083092) (xy 236.871197 -353.133589) (xy 236.887265 -353.186996) (xy 236.895385 -353.242172)
			(xy 236.895894 -353.270058) (xy 236.895385 -353.297944) (xy 236.887265 -353.35312) (xy 236.873129 -353.400106)
			(xy 241.556538 -353.400106) (xy 241.560609 -353.344484) (xy 241.572735 -353.290047) (xy 241.592658 -353.237956)
			(xy 241.619954 -353.189321) (xy 241.65404 -353.145178) (xy 241.694189 -353.106469) (xy 241.739547 -353.074018)
			(xy 241.789147 -353.048517) (xy 241.841931 -353.03051) (xy 241.896774 -353.02038) (xy 241.952508 -353.018343)
			(xy 242.007945 -353.024443) (xy 242.061902 -353.038549) (xy 242.113231 -353.060361) (xy 242.160837 -353.089415)
			(xy 242.203705 -353.12509) (xy 242.240922 -353.166627) (xy 242.271695 -353.21314) (xy 242.295367 -353.263637)
			(xy 242.311435 -353.317044) (xy 242.319555 -353.37222) (xy 242.320064 -353.400106) (xy 242.319555 -353.427992)
			(xy 242.311435 -353.483168) (xy 242.295367 -353.536575) (xy 242.271695 -353.587072) (xy 242.240922 -353.633585)
			(xy 242.203705 -353.675122) (xy 242.160837 -353.710797) (xy 242.113231 -353.739851) (xy 242.061902 -353.761663)
			(xy 242.007945 -353.775769) (xy 241.952508 -353.781869) (xy 241.896774 -353.779832) (xy 241.841931 -353.769702)
			(xy 241.789147 -353.751695) (xy 241.739547 -353.726194) (xy 241.694189 -353.693743) (xy 241.65404 -353.655034)
			(xy 241.619954 -353.610891) (xy 241.592658 -353.562256) (xy 241.572735 -353.510165) (xy 241.560609 -353.455728)
			(xy 241.556538 -353.400106) (xy 236.873129 -353.400106) (xy 236.871197 -353.406527) (xy 236.847525 -353.457024)
			(xy 236.816752 -353.503537) (xy 236.779535 -353.545074) (xy 236.736667 -353.580749) (xy 236.689061 -353.609803)
			(xy 236.637732 -353.631615) (xy 236.583775 -353.645721) (xy 236.528338 -353.651821) (xy 236.472604 -353.649784)
			(xy 236.417761 -353.639654) (xy 236.364977 -353.621647) (xy 236.315377 -353.596146) (xy 236.270019 -353.563695)
			(xy 236.22987 -353.524986) (xy 236.195784 -353.480843) (xy 236.168488 -353.432208) (xy 236.148565 -353.380117)
			(xy 236.136439 -353.32568) (xy 236.132368 -353.270058) (xy 155.1686 -353.270058) (xy 155.1686 -354.235258)
			(xy 236.132368 -354.235258) (xy 236.136439 -354.179636) (xy 236.148565 -354.125199) (xy 236.168488 -354.073108)
			(xy 236.195784 -354.024473) (xy 236.22987 -353.98033) (xy 236.270019 -353.941621) (xy 236.315377 -353.90917)
			(xy 236.364977 -353.883669) (xy 236.417761 -353.865662) (xy 236.472604 -353.855532) (xy 236.528338 -353.853495)
			(xy 236.583775 -353.859595) (xy 236.637732 -353.873701) (xy 236.689061 -353.895513) (xy 236.696793 -353.900232)
			(xy 248.573288 -353.900232) (xy 248.577359 -353.84461) (xy 248.589485 -353.790173) (xy 248.609408 -353.738082)
			(xy 248.636704 -353.689447) (xy 248.67079 -353.645304) (xy 248.710939 -353.606595) (xy 248.756297 -353.574144)
			(xy 248.805897 -353.548643) (xy 248.858681 -353.530636) (xy 248.913524 -353.520506) (xy 248.969258 -353.518469)
			(xy 249.024695 -353.524569) (xy 249.078652 -353.538675) (xy 249.129981 -353.560487) (xy 249.177587 -353.589541)
			(xy 249.220455 -353.625216) (xy 249.257672 -353.666753) (xy 249.288445 -353.713266) (xy 249.312117 -353.763763)
			(xy 249.328185 -353.81717) (xy 249.336305 -353.872346) (xy 249.336814 -353.900232) (xy 249.336305 -353.928118)
			(xy 249.328185 -353.983294) (xy 249.312117 -354.036701) (xy 249.288445 -354.087198) (xy 249.257672 -354.133711)
			(xy 249.220455 -354.175248) (xy 249.177587 -354.210923) (xy 249.129981 -354.239977) (xy 249.078652 -354.261789)
			(xy 249.024695 -354.275895) (xy 248.969258 -354.281995) (xy 248.913524 -354.279958) (xy 248.858681 -354.269828)
			(xy 248.805897 -354.251821) (xy 248.756297 -354.22632) (xy 248.710939 -354.193869) (xy 248.67079 -354.15516)
			(xy 248.636704 -354.111017) (xy 248.609408 -354.062382) (xy 248.589485 -354.010291) (xy 248.577359 -353.955854)
			(xy 248.573288 -353.900232) (xy 236.696793 -353.900232) (xy 236.736667 -353.924567) (xy 236.779535 -353.960242)
			(xy 236.816752 -354.001779) (xy 236.847525 -354.048292) (xy 236.871197 -354.098789) (xy 236.887265 -354.152196)
			(xy 236.895385 -354.207372) (xy 236.895894 -354.235258) (xy 236.895385 -354.263144) (xy 236.887265 -354.31832)
			(xy 236.871197 -354.371727) (xy 236.857894 -354.400104) (xy 241.526312 -354.400104) (xy 241.530383 -354.344482)
			(xy 241.542509 -354.290045) (xy 241.562432 -354.237954) (xy 241.589728 -354.189319) (xy 241.623814 -354.145176)
			(xy 241.663963 -354.106467) (xy 241.709321 -354.074016) (xy 241.758921 -354.048515) (xy 241.811705 -354.030508)
			(xy 241.866548 -354.020378) (xy 241.922282 -354.018341) (xy 241.977719 -354.024441) (xy 242.031676 -354.038547)
			(xy 242.083005 -354.060359) (xy 242.130611 -354.089413) (xy 242.173479 -354.125088) (xy 242.210696 -354.166625)
			(xy 242.241469 -354.213138) (xy 242.265141 -354.263635) (xy 242.281209 -354.317042) (xy 242.289329 -354.372218)
			(xy 242.289838 -354.400104) (xy 242.289329 -354.42799) (xy 242.281209 -354.483166) (xy 242.265141 -354.536573)
			(xy 242.241469 -354.58707) (xy 242.210696 -354.633583) (xy 242.173479 -354.67512) (xy 242.130611 -354.710795)
			(xy 242.083005 -354.739849) (xy 242.031676 -354.761661) (xy 241.977719 -354.775767) (xy 241.922282 -354.781867)
			(xy 241.866548 -354.77983) (xy 241.811705 -354.7697) (xy 241.758921 -354.751693) (xy 241.709321 -354.726192)
			(xy 241.663963 -354.693741) (xy 241.623814 -354.655032) (xy 241.589728 -354.610889) (xy 241.562432 -354.562254)
			(xy 241.542509 -354.510163) (xy 241.530383 -354.455726) (xy 241.526312 -354.400104) (xy 236.857894 -354.400104)
			(xy 236.847525 -354.422224) (xy 236.816752 -354.468737) (xy 236.779535 -354.510274) (xy 236.736667 -354.545949)
			(xy 236.689061 -354.575003) (xy 236.637732 -354.596815) (xy 236.583775 -354.610921) (xy 236.528338 -354.617021)
			(xy 236.472604 -354.614984) (xy 236.417761 -354.604854) (xy 236.364977 -354.586847) (xy 236.315377 -354.561346)
			(xy 236.270019 -354.528895) (xy 236.22987 -354.490186) (xy 236.195784 -354.446043) (xy 236.168488 -354.397408)
			(xy 236.148565 -354.345317) (xy 236.136439 -354.29088) (xy 236.132368 -354.235258) (xy 155.1686 -354.235258)
			(xy 155.1686 -354.759368) (xy 158.695906 -354.759368) (xy 158.695906 -354.704832) (xy 158.703667 -354.65085)
			(xy 158.719031 -354.598521) (xy 158.741685 -354.548912) (xy 158.771167 -354.503031) (xy 158.806879 -354.461813)
			(xy 158.848093 -354.426096) (xy 158.89397 -354.396608) (xy 158.943576 -354.373948) (xy 158.995903 -354.358577)
			(xy 159.049884 -354.35081) (xy 159.077152 -354.35032) (xy 159.940752 -354.35032) (xy 159.968024 -354.350816)
			(xy 160.022013 -354.358572) (xy 160.074349 -354.373934) (xy 160.123966 -354.396588) (xy 160.169854 -354.426072)
			(xy 160.211078 -354.461788) (xy 160.246799 -354.503008) (xy 160.276289 -354.548891) (xy 160.298949 -354.598506)
			(xy 160.314317 -354.65084) (xy 160.32208 -354.704828) (xy 160.32208 -354.759372) (xy 160.32208 -354.759373)
			(xy 161.804784 -354.759373) (xy 161.804784 -354.704827) (xy 161.812546 -354.650837) (xy 161.827914 -354.598501)
			(xy 161.850573 -354.548884) (xy 161.880064 -354.502998) (xy 161.915784 -354.461776) (xy 161.957008 -354.426056)
			(xy 162.002895 -354.396568) (xy 162.052512 -354.37391) (xy 162.104848 -354.358544) (xy 162.158839 -354.350783)
			(xy 162.186112 -354.35032) (xy 163.049712 -354.35032) (xy 163.07698 -354.350843) (xy 163.130959 -354.358606)
			(xy 163.183285 -354.373972) (xy 163.232891 -354.396627) (xy 163.278768 -354.426112) (xy 163.319983 -354.461826)
			(xy 163.355695 -354.503041) (xy 163.385178 -354.548919) (xy 163.407833 -354.598526) (xy 163.423197 -354.650852)
			(xy 163.430958 -354.704832) (xy 163.430958 -354.759368) (xy 163.430958 -354.759369) (xy 164.913806 -354.759369)
			(xy 164.913806 -354.704831) (xy 164.921568 -354.650847) (xy 164.936932 -354.598517) (xy 164.959588 -354.548907)
			(xy 164.989072 -354.503025) (xy 165.024786 -354.461806) (xy 165.066002 -354.426089) (xy 165.111882 -354.396601)
			(xy 165.161491 -354.373942) (xy 165.21382 -354.358574) (xy 165.267803 -354.350808) (xy 165.295072 -354.35032)
			(xy 166.158672 -354.35032) (xy 166.185943 -354.350818) (xy 166.23993 -354.358576) (xy 166.292264 -354.373939)
			(xy 166.341878 -354.396594) (xy 166.387763 -354.42608) (xy 166.428985 -354.461795) (xy 166.464704 -354.503014)
			(xy 166.494192 -354.548897) (xy 166.516851 -354.59851) (xy 166.532218 -354.650842) (xy 166.53998 -354.704829)
			(xy 166.53998 -354.759371) (xy 166.53998 -354.759374) (xy 168.022684 -354.759374) (xy 168.022684 -354.704826)
			(xy 168.030447 -354.650834) (xy 168.045816 -354.598496) (xy 168.068477 -354.548879) (xy 168.097969 -354.502991)
			(xy 168.133691 -354.461768) (xy 168.174917 -354.426049) (xy 168.220807 -354.396561) (xy 168.270426 -354.373904)
			(xy 168.322765 -354.35854) (xy 168.376758 -354.350781) (xy 168.404032 -354.35032) (xy 169.267632 -354.35032)
			(xy 169.294899 -354.350845) (xy 169.348876 -354.35861) (xy 169.401199 -354.373977) (xy 169.450803 -354.396634)
			(xy 169.496678 -354.426119) (xy 169.53789 -354.461833) (xy 169.5736 -354.503048) (xy 169.603081 -354.548925)
			(xy 169.625734 -354.598531) (xy 169.641097 -354.650855) (xy 169.648858 -354.704833) (xy 169.648858 -354.759367)
			(xy 169.648858 -354.75937) (xy 171.131706 -354.75937) (xy 171.131706 -354.70483) (xy 171.139468 -354.650844)
			(xy 171.154834 -354.598513) (xy 171.177491 -354.548901) (xy 171.206977 -354.503018) (xy 171.242693 -354.461799)
			(xy 171.283912 -354.426082) (xy 171.329794 -354.396594) (xy 171.379405 -354.373937) (xy 171.431736 -354.35857)
			(xy 171.485722 -354.350807) (xy 171.512992 -354.35032) (xy 172.376592 -354.35032) (xy 172.403862 -354.350819)
			(xy 172.457847 -354.35858) (xy 172.510178 -354.373945) (xy 172.55979 -354.396601) (xy 172.605673 -354.426087)
			(xy 172.646892 -354.461802) (xy 172.682609 -354.503021) (xy 172.712096 -354.548903) (xy 172.734753 -354.598514)
			(xy 172.750119 -354.650845) (xy 172.757881 -354.70483) (xy 172.757881 -354.759368) (xy 174.240706 -354.759368)
			(xy 174.240706 -354.704832) (xy 174.248467 -354.65085) (xy 174.263831 -354.598521) (xy 174.286485 -354.548912)
			(xy 174.315967 -354.503031) (xy 174.351679 -354.461813) (xy 174.392893 -354.426096) (xy 174.43877 -354.396608)
			(xy 174.488376 -354.373948) (xy 174.540703 -354.358577) (xy 174.594684 -354.35081) (xy 174.621952 -354.35032)
			(xy 175.485552 -354.35032) (xy 175.512824 -354.350816) (xy 175.566813 -354.358572) (xy 175.619149 -354.373934)
			(xy 175.668766 -354.396588) (xy 175.714654 -354.426072) (xy 175.755878 -354.461788) (xy 175.791599 -354.503008)
			(xy 175.821089 -354.548891) (xy 175.843749 -354.598506) (xy 175.859117 -354.65084) (xy 175.86688 -354.704828)
			(xy 175.86688 -354.759372) (xy 175.86688 -354.759373) (xy 177.349584 -354.759373) (xy 177.349584 -354.704827)
			(xy 177.357346 -354.650837) (xy 177.372714 -354.598501) (xy 177.395373 -354.548884) (xy 177.424864 -354.502998)
			(xy 177.460584 -354.461776) (xy 177.501808 -354.426056) (xy 177.547695 -354.396568) (xy 177.597312 -354.37391)
			(xy 177.649648 -354.358544) (xy 177.703639 -354.350783) (xy 177.730912 -354.35032) (xy 178.594512 -354.35032)
			(xy 178.62178 -354.350843) (xy 178.675759 -354.358606) (xy 178.728085 -354.373972) (xy 178.777691 -354.396627)
			(xy 178.823568 -354.426112) (xy 178.864783 -354.461826) (xy 178.900495 -354.503041) (xy 178.929978 -354.548919)
			(xy 178.952633 -354.598526) (xy 178.967997 -354.650852) (xy 178.975758 -354.704832) (xy 178.975758 -354.759368)
			(xy 178.975758 -354.759369) (xy 180.458606 -354.759369) (xy 180.458606 -354.704831) (xy 180.466368 -354.650847)
			(xy 180.481732 -354.598517) (xy 180.504388 -354.548907) (xy 180.533872 -354.503025) (xy 180.569586 -354.461806)
			(xy 180.610802 -354.426089) (xy 180.656682 -354.396601) (xy 180.706291 -354.373942) (xy 180.75862 -354.358574)
			(xy 180.812603 -354.350808) (xy 180.839872 -354.35032) (xy 181.703472 -354.35032) (xy 181.730743 -354.350818)
			(xy 181.78473 -354.358576) (xy 181.837064 -354.373939) (xy 181.886678 -354.396594) (xy 181.932563 -354.42608)
			(xy 181.973785 -354.461795) (xy 182.009504 -354.503014) (xy 182.038992 -354.548897) (xy 182.061651 -354.59851)
			(xy 182.077018 -354.650842) (xy 182.08478 -354.704829) (xy 182.08478 -354.735472) (xy 183.567508 -354.735472)
			(xy 183.567508 -354.680928) (xy 183.57527 -354.626939) (xy 183.590638 -354.574605) (xy 183.613298 -354.52499)
			(xy 183.642788 -354.479106) (xy 183.678508 -354.437885) (xy 183.719731 -354.402169) (xy 183.765618 -354.372682)
			(xy 183.815235 -354.350027) (xy 183.86757 -354.334664) (xy 183.92156 -354.326905) (xy 183.948832 -354.326444)
			(xy 184.812432 -354.326444) (xy 184.8397 -354.326921) (xy 184.893681 -354.334686) (xy 184.946008 -354.350054)
			(xy 184.995615 -354.372713) (xy 185.041492 -354.4022) (xy 185.082707 -354.437916) (xy 185.118419 -354.479133)
			(xy 185.147903 -354.525013) (xy 185.170557 -354.574622) (xy 185.185921 -354.62695) (xy 185.193682 -354.680932)
			(xy 185.193682 -354.735468) (xy 185.193682 -354.735469) (xy 186.67653 -354.735469) (xy 186.67653 -354.680931)
			(xy 186.684292 -354.626949) (xy 186.699656 -354.574621) (xy 186.722312 -354.525012) (xy 186.751796 -354.479133)
			(xy 186.78751 -354.437916) (xy 186.828726 -354.402201) (xy 186.874605 -354.372716) (xy 186.924214 -354.350059)
			(xy 186.976542 -354.334693) (xy 187.030523 -354.326931) (xy 187.057792 -354.326444) (xy 187.921392 -354.326444)
			(xy 187.948664 -354.326895) (xy 188.002652 -354.334656) (xy 188.054987 -354.350022) (xy 188.104602 -354.37268)
			(xy 188.150487 -354.402167) (xy 188.191709 -354.437885) (xy 188.227428 -354.479106) (xy 188.256917 -354.524991)
			(xy 188.279575 -354.574606) (xy 188.294942 -354.62694) (xy 188.302704 -354.680928) (xy 188.302704 -354.735472)
			(xy 188.294942 -354.78946) (xy 188.279575 -354.841794) (xy 188.256917 -354.891409) (xy 188.227428 -354.937294)
			(xy 188.191709 -354.978515) (xy 188.15161 -355.01326) (xy 201.179174 -355.01326) (xy 201.183245 -354.957638)
			(xy 201.195371 -354.903201) (xy 201.215294 -354.85111) (xy 201.24259 -354.802475) (xy 201.276676 -354.758332)
			(xy 201.316825 -354.719623) (xy 201.362183 -354.687172) (xy 201.411783 -354.661671) (xy 201.464567 -354.643664)
			(xy 201.51941 -354.633534) (xy 201.575144 -354.631497) (xy 201.630581 -354.637597) (xy 201.684538 -354.651703)
			(xy 201.735867 -354.673515) (xy 201.783473 -354.702569) (xy 201.826341 -354.738244) (xy 201.863558 -354.779781)
			(xy 201.894331 -354.826294) (xy 201.918003 -354.876791) (xy 201.934071 -354.930198) (xy 201.942191 -354.985374)
			(xy 201.9427 -355.01326) (xy 201.942191 -355.041146) (xy 201.934071 -355.096322) (xy 201.918003 -355.149729)
			(xy 201.894331 -355.200226) (xy 201.894178 -355.200458) (xy 236.132368 -355.200458) (xy 236.136439 -355.144836)
			(xy 236.148565 -355.090399) (xy 236.168488 -355.038308) (xy 236.195784 -354.989673) (xy 236.22987 -354.94553)
			(xy 236.270019 -354.906821) (xy 236.315377 -354.87437) (xy 236.364977 -354.848869) (xy 236.417761 -354.830862)
			(xy 236.472604 -354.820732) (xy 236.528338 -354.818695) (xy 236.583775 -354.824795) (xy 236.637732 -354.838901)
			(xy 236.689061 -354.860713) (xy 236.736667 -354.889767) (xy 236.779535 -354.925442) (xy 236.816752 -354.966979)
			(xy 236.847525 -355.013492) (xy 236.871197 -355.063989) (xy 236.887265 -355.117396) (xy 236.895385 -355.172572)
			(xy 236.895894 -355.200458) (xy 238.265968 -355.200458) (xy 238.270039 -355.144836) (xy 238.282165 -355.090399)
			(xy 238.302088 -355.038308) (xy 238.329384 -354.989673) (xy 238.36347 -354.94553) (xy 238.403619 -354.906821)
			(xy 238.448977 -354.87437) (xy 238.498577 -354.848869) (xy 238.551361 -354.830862) (xy 238.606204 -354.820732)
			(xy 238.661938 -354.818695) (xy 238.717375 -354.824795) (xy 238.771332 -354.838901) (xy 238.822661 -354.860713)
			(xy 238.870267 -354.889767) (xy 238.88284 -354.90023) (xy 248.54992 -354.90023) (xy 248.553991 -354.844608)
			(xy 248.566117 -354.790171) (xy 248.58604 -354.73808) (xy 248.613336 -354.689445) (xy 248.647422 -354.645302)
			(xy 248.687571 -354.606593) (xy 248.732929 -354.574142) (xy 248.782529 -354.548641) (xy 248.835313 -354.530634)
			(xy 248.890156 -354.520504) (xy 248.94589 -354.518467) (xy 249.001327 -354.524567) (xy 249.055284 -354.538673)
			(xy 249.106613 -354.560485) (xy 249.154219 -354.589539) (xy 249.197087 -354.625214) (xy 249.234304 -354.666751)
			(xy 249.265077 -354.713264) (xy 249.288749 -354.763761) (xy 249.304817 -354.817168) (xy 249.312937 -354.872344)
			(xy 249.313446 -354.90023) (xy 249.312937 -354.928116) (xy 249.304817 -354.983292) (xy 249.288749 -355.036699)
			(xy 249.265077 -355.087196) (xy 249.234304 -355.133709) (xy 249.21 -355.160834) (xy 249.921774 -355.160834)
			(xy 249.925845 -355.105212) (xy 249.937971 -355.050775) (xy 249.957894 -354.998684) (xy 249.98519 -354.950049)
			(xy 250.019276 -354.905906) (xy 250.059425 -354.867197) (xy 250.104783 -354.834746) (xy 250.154383 -354.809245)
			(xy 250.207167 -354.791238) (xy 250.26201 -354.781108) (xy 250.317744 -354.779071) (xy 250.373181 -354.785171)
			(xy 250.427138 -354.799277) (xy 250.478467 -354.821089) (xy 250.526073 -354.850143) (xy 250.568941 -354.885818)
			(xy 250.606158 -354.927355) (xy 250.636931 -354.973868) (xy 250.660603 -355.024365) (xy 250.676671 -355.077772)
			(xy 250.684791 -355.132948) (xy 250.6853 -355.160834) (xy 253.273304 -355.160834) (xy 253.277375 -355.105212)
			(xy 253.289501 -355.050775) (xy 253.309424 -354.998684) (xy 253.33672 -354.950049) (xy 253.370806 -354.905906)
			(xy 253.410955 -354.867197) (xy 253.456313 -354.834746) (xy 253.505913 -354.809245) (xy 253.558697 -354.791238)
			(xy 253.61354 -354.781108) (xy 253.669274 -354.779071) (xy 253.724711 -354.785171) (xy 253.778668 -354.799277)
			(xy 253.829997 -354.821089) (xy 253.877603 -354.850143) (xy 253.920471 -354.885818) (xy 253.957688 -354.927355)
			(xy 253.988461 -354.973868) (xy 254.012133 -355.024365) (xy 254.028201 -355.077772) (xy 254.036321 -355.132948)
			(xy 254.03683 -355.160834) (xy 254.036321 -355.18872) (xy 254.028201 -355.243896) (xy 254.012133 -355.297303)
			(xy 253.988461 -355.3478) (xy 253.957688 -355.394313) (xy 253.920471 -355.43585) (xy 253.877603 -355.471525)
			(xy 253.829997 -355.500579) (xy 253.778668 -355.522391) (xy 253.724711 -355.536497) (xy 253.669274 -355.542597)
			(xy 253.61354 -355.54056) (xy 253.558697 -355.53043) (xy 253.505913 -355.512423) (xy 253.456313 -355.486922)
			(xy 253.410955 -355.454471) (xy 253.370806 -355.415762) (xy 253.33672 -355.371619) (xy 253.309424 -355.322984)
			(xy 253.289501 -355.270893) (xy 253.277375 -355.216456) (xy 253.273304 -355.160834) (xy 250.6853 -355.160834)
			(xy 250.684791 -355.18872) (xy 250.676671 -355.243896) (xy 250.660603 -355.297303) (xy 250.636931 -355.3478)
			(xy 250.606158 -355.394313) (xy 250.568941 -355.43585) (xy 250.526073 -355.471525) (xy 250.478467 -355.500579)
			(xy 250.427138 -355.522391) (xy 250.373181 -355.536497) (xy 250.317744 -355.542597) (xy 250.26201 -355.54056)
			(xy 250.207167 -355.53043) (xy 250.154383 -355.512423) (xy 250.104783 -355.486922) (xy 250.059425 -355.454471)
			(xy 250.019276 -355.415762) (xy 249.98519 -355.371619) (xy 249.957894 -355.322984) (xy 249.937971 -355.270893)
			(xy 249.925845 -355.216456) (xy 249.921774 -355.160834) (xy 249.21 -355.160834) (xy 249.197087 -355.175246)
			(xy 249.154219 -355.210921) (xy 249.106613 -355.239975) (xy 249.055284 -355.261787) (xy 249.001327 -355.275893)
			(xy 248.94589 -355.281993) (xy 248.890156 -355.279956) (xy 248.835313 -355.269826) (xy 248.782529 -355.251819)
			(xy 248.732929 -355.226318) (xy 248.687571 -355.193867) (xy 248.647422 -355.155158) (xy 248.613336 -355.111015)
			(xy 248.58604 -355.06238) (xy 248.566117 -355.010289) (xy 248.553991 -354.955852) (xy 248.54992 -354.90023)
			(xy 238.88284 -354.90023) (xy 238.913135 -354.925442) (xy 238.950352 -354.966979) (xy 238.981125 -355.013492)
			(xy 239.004797 -355.063989) (xy 239.020865 -355.117396) (xy 239.028985 -355.172572) (xy 239.029494 -355.200458)
			(xy 239.028985 -355.228344) (xy 239.020865 -355.28352) (xy 239.004797 -355.336927) (xy 238.981125 -355.387424)
			(xy 238.950352 -355.433937) (xy 238.913135 -355.475474) (xy 238.870267 -355.511149) (xy 238.822661 -355.540203)
			(xy 238.771332 -355.562015) (xy 238.717375 -355.576121) (xy 238.661938 -355.582221) (xy 238.606204 -355.580184)
			(xy 238.551361 -355.570054) (xy 238.498577 -355.552047) (xy 238.448977 -355.526546) (xy 238.403619 -355.494095)
			(xy 238.36347 -355.455386) (xy 238.329384 -355.411243) (xy 238.302088 -355.362608) (xy 238.282165 -355.310517)
			(xy 238.270039 -355.25608) (xy 238.265968 -355.200458) (xy 236.895894 -355.200458) (xy 236.895385 -355.228344)
			(xy 236.887265 -355.28352) (xy 236.871197 -355.336927) (xy 236.847525 -355.387424) (xy 236.816752 -355.433937)
			(xy 236.779535 -355.475474) (xy 236.736667 -355.511149) (xy 236.689061 -355.540203) (xy 236.637732 -355.562015)
			(xy 236.583775 -355.576121) (xy 236.528338 -355.582221) (xy 236.472604 -355.580184) (xy 236.417761 -355.570054)
			(xy 236.364977 -355.552047) (xy 236.315377 -355.526546) (xy 236.270019 -355.494095) (xy 236.22987 -355.455386)
			(xy 236.195784 -355.411243) (xy 236.168488 -355.362608) (xy 236.148565 -355.310517) (xy 236.136439 -355.25608)
			(xy 236.132368 -355.200458) (xy 201.894178 -355.200458) (xy 201.863558 -355.246739) (xy 201.826341 -355.288276)
			(xy 201.783473 -355.323951) (xy 201.735867 -355.353005) (xy 201.684538 -355.374817) (xy 201.630581 -355.388923)
			(xy 201.575144 -355.395023) (xy 201.51941 -355.392986) (xy 201.464567 -355.382856) (xy 201.411783 -355.364849)
			(xy 201.362183 -355.339348) (xy 201.316825 -355.306897) (xy 201.276676 -355.268188) (xy 201.24259 -355.224045)
			(xy 201.215294 -355.17541) (xy 201.195371 -355.123319) (xy 201.183245 -355.068882) (xy 201.179174 -355.01326)
			(xy 188.15161 -355.01326) (xy 188.150487 -355.014233) (xy 188.104602 -355.04372) (xy 188.054987 -355.066378)
			(xy 188.002652 -355.081744) (xy 187.948664 -355.089505) (xy 187.921392 -355.089968) (xy 187.057792 -355.089968)
			(xy 187.030523 -355.089469) (xy 186.976542 -355.081707) (xy 186.924214 -355.066341) (xy 186.874605 -355.043684)
			(xy 186.828726 -355.014199) (xy 186.78751 -354.978484) (xy 186.751796 -354.937267) (xy 186.722312 -354.891388)
			(xy 186.699656 -354.841779) (xy 186.684292 -354.789451) (xy 186.67653 -354.735469) (xy 185.193682 -354.735469)
			(xy 185.185921 -354.78945) (xy 185.170557 -354.841778) (xy 185.147903 -354.891387) (xy 185.118419 -354.937267)
			(xy 185.082707 -354.978484) (xy 185.041492 -355.0142) (xy 184.995615 -355.043687) (xy 184.946008 -355.066346)
			(xy 184.893681 -355.081714) (xy 184.8397 -355.089479) (xy 184.812432 -355.089968) (xy 183.948832 -355.089968)
			(xy 183.92156 -355.089495) (xy 183.86757 -355.081736) (xy 183.815235 -355.066373) (xy 183.765618 -355.043718)
			(xy 183.719731 -355.014231) (xy 183.678508 -354.978515) (xy 183.642788 -354.937294) (xy 183.613298 -354.89141)
			(xy 183.590638 -354.841795) (xy 183.57527 -354.789461) (xy 183.567508 -354.735472) (xy 182.08478 -354.735472)
			(xy 182.08478 -354.759371) (xy 182.077018 -354.813358) (xy 182.061651 -354.86569) (xy 182.038992 -354.915303)
			(xy 182.009504 -354.961186) (xy 181.973785 -355.002405) (xy 181.932563 -355.03812) (xy 181.886678 -355.067606)
			(xy 181.837064 -355.090261) (xy 181.78473 -355.105624) (xy 181.730743 -355.113382) (xy 181.703472 -355.113844)
			(xy 180.839872 -355.113844) (xy 180.812603 -355.113392) (xy 180.75862 -355.105626) (xy 180.706291 -355.090258)
			(xy 180.656682 -355.067599) (xy 180.610802 -355.038111) (xy 180.569586 -355.002394) (xy 180.533872 -354.961175)
			(xy 180.504388 -354.915293) (xy 180.481732 -354.865683) (xy 180.466368 -354.813353) (xy 180.458606 -354.759369)
			(xy 178.975758 -354.759369) (xy 178.967997 -354.813348) (xy 178.952633 -354.865674) (xy 178.929978 -354.915281)
			(xy 178.900495 -354.961159) (xy 178.864783 -355.002374) (xy 178.823568 -355.038088) (xy 178.777691 -355.067573)
			(xy 178.728085 -355.090228) (xy 178.675759 -355.105594) (xy 178.62178 -355.113357) (xy 178.594512 -355.113844)
			(xy 177.730912 -355.113844) (xy 177.703639 -355.113417) (xy 177.649648 -355.105656) (xy 177.597312 -355.09029)
			(xy 177.547695 -355.067632) (xy 177.501808 -355.038144) (xy 177.460584 -355.002424) (xy 177.424864 -354.961202)
			(xy 177.395373 -354.915316) (xy 177.372714 -354.865699) (xy 177.357346 -354.813363) (xy 177.349584 -354.759373)
			(xy 175.86688 -354.759373) (xy 175.859117 -354.81336) (xy 175.843749 -354.865694) (xy 175.821089 -354.915309)
			(xy 175.791599 -354.961192) (xy 175.755878 -355.002412) (xy 175.714654 -355.038128) (xy 175.668766 -355.067612)
			(xy 175.619149 -355.090266) (xy 175.566813 -355.105628) (xy 175.512824 -355.113384) (xy 175.485552 -355.113844)
			(xy 174.621952 -355.113844) (xy 174.594684 -355.11339) (xy 174.540703 -355.105623) (xy 174.488376 -355.090252)
			(xy 174.43877 -355.067592) (xy 174.392893 -355.038104) (xy 174.351679 -355.002387) (xy 174.315967 -354.961169)
			(xy 174.286485 -354.915288) (xy 174.263831 -354.865679) (xy 174.248467 -354.81335) (xy 174.240706 -354.759368)
			(xy 172.757881 -354.759368) (xy 172.757881 -354.75937) (xy 172.750119 -354.813355) (xy 172.734753 -354.865686)
			(xy 172.712096 -354.915297) (xy 172.682609 -354.961179) (xy 172.646892 -355.002398) (xy 172.605673 -355.038113)
			(xy 172.55979 -355.067599) (xy 172.510178 -355.090255) (xy 172.457847 -355.10562) (xy 172.403862 -355.113381)
			(xy 172.376592 -355.113844) (xy 171.512992 -355.113844) (xy 171.485722 -355.113393) (xy 171.431736 -355.10563)
			(xy 171.379405 -355.090263) (xy 171.329794 -355.067606) (xy 171.283912 -355.038118) (xy 171.242693 -355.002401)
			(xy 171.206977 -354.961182) (xy 171.177491 -354.915299) (xy 171.154834 -354.865687) (xy 171.139468 -354.813356)
			(xy 171.131706 -354.75937) (xy 169.648858 -354.75937) (xy 169.641097 -354.813345) (xy 169.625734 -354.865669)
			(xy 169.603081 -354.915275) (xy 169.5736 -354.961152) (xy 169.53789 -355.002367) (xy 169.496678 -355.038081)
			(xy 169.450803 -355.067566) (xy 169.401199 -355.090223) (xy 169.348876 -355.10559) (xy 169.294899 -355.113355)
			(xy 169.267632 -355.113844) (xy 168.404032 -355.113844) (xy 168.376758 -355.113419) (xy 168.322765 -355.10566)
			(xy 168.270426 -355.090296) (xy 168.220807 -355.067639) (xy 168.174917 -355.038151) (xy 168.133691 -355.002432)
			(xy 168.097969 -354.961209) (xy 168.068477 -354.915321) (xy 168.045816 -354.865704) (xy 168.030447 -354.813366)
			(xy 168.022684 -354.759374) (xy 166.53998 -354.759374) (xy 166.532218 -354.813358) (xy 166.516851 -354.86569)
			(xy 166.494192 -354.915303) (xy 166.464704 -354.961186) (xy 166.428985 -355.002405) (xy 166.387763 -355.03812)
			(xy 166.341878 -355.067606) (xy 166.292264 -355.090261) (xy 166.23993 -355.105624) (xy 166.185943 -355.113382)
			(xy 166.158672 -355.113844) (xy 165.295072 -355.113844) (xy 165.267803 -355.113392) (xy 165.21382 -355.105626)
			(xy 165.161491 -355.090258) (xy 165.111882 -355.067599) (xy 165.066002 -355.038111) (xy 165.024786 -355.002394)
			(xy 164.989072 -354.961175) (xy 164.959588 -354.915293) (xy 164.936932 -354.865683) (xy 164.921568 -354.813353)
			(xy 164.913806 -354.759369) (xy 163.430958 -354.759369) (xy 163.423197 -354.813348) (xy 163.407833 -354.865674)
			(xy 163.385178 -354.915281) (xy 163.355695 -354.961159) (xy 163.319983 -355.002374) (xy 163.278768 -355.038088)
			(xy 163.232891 -355.067573) (xy 163.183285 -355.090228) (xy 163.130959 -355.105594) (xy 163.07698 -355.113357)
			(xy 163.049712 -355.113844) (xy 162.186112 -355.113844) (xy 162.158839 -355.113417) (xy 162.104848 -355.105656)
			(xy 162.052512 -355.09029) (xy 162.002895 -355.067632) (xy 161.957008 -355.038144) (xy 161.915784 -355.002424)
			(xy 161.880064 -354.961202) (xy 161.850573 -354.915316) (xy 161.827914 -354.865699) (xy 161.812546 -354.813363)
			(xy 161.804784 -354.759373) (xy 160.32208 -354.759373) (xy 160.314317 -354.81336) (xy 160.298949 -354.865694)
			(xy 160.276289 -354.915309) (xy 160.246799 -354.961192) (xy 160.211078 -355.002412) (xy 160.169854 -355.038128)
			(xy 160.123966 -355.067612) (xy 160.074349 -355.090266) (xy 160.022013 -355.105628) (xy 159.968024 -355.113384)
			(xy 159.940752 -355.113844) (xy 159.077152 -355.113844) (xy 159.049884 -355.11339) (xy 158.995903 -355.105623)
			(xy 158.943576 -355.090252) (xy 158.89397 -355.067592) (xy 158.848093 -355.038104) (xy 158.806879 -355.002387)
			(xy 158.771167 -354.961169) (xy 158.741685 -354.915288) (xy 158.719031 -354.865679) (xy 158.703667 -354.81335)
			(xy 158.695906 -354.759368) (xy 155.1686 -354.759368) (xy 155.1686 -356.021894) (xy 205.409798 -356.021894)
			(xy 205.413869 -355.966272) (xy 205.425995 -355.911835) (xy 205.445918 -355.859744) (xy 205.473214 -355.811109)
			(xy 205.5073 -355.766966) (xy 205.547449 -355.728257) (xy 205.592807 -355.695806) (xy 205.642407 -355.670305)
			(xy 205.695191 -355.652298) (xy 205.750034 -355.642168) (xy 205.805768 -355.640131) (xy 205.861205 -355.646231)
			(xy 205.915162 -355.660337) (xy 205.966491 -355.682149) (xy 206.014097 -355.711203) (xy 206.056965 -355.746878)
			(xy 206.094182 -355.788415) (xy 206.124955 -355.834928) (xy 206.148627 -355.885425) (xy 206.164695 -355.938832)
			(xy 206.172815 -355.994008) (xy 206.173324 -356.021894) (xy 206.172815 -356.04978) (xy 206.164695 -356.104956)
			(xy 206.148627 -356.158363) (xy 206.145207 -356.165658) (xy 236.132368 -356.165658) (xy 236.136439 -356.110036)
			(xy 236.148565 -356.055599) (xy 236.168488 -356.003508) (xy 236.195784 -355.954873) (xy 236.22987 -355.91073)
			(xy 236.270019 -355.872021) (xy 236.315377 -355.83957) (xy 236.364977 -355.814069) (xy 236.417761 -355.796062)
			(xy 236.472604 -355.785932) (xy 236.528338 -355.783895) (xy 236.583775 -355.789995) (xy 236.637732 -355.804101)
			(xy 236.689061 -355.825913) (xy 236.736667 -355.854967) (xy 236.779535 -355.890642) (xy 236.816752 -355.932179)
			(xy 236.847525 -355.978692) (xy 236.871197 -356.029189) (xy 236.887265 -356.082596) (xy 236.895385 -356.137772)
			(xy 236.895894 -356.165658) (xy 238.265968 -356.165658) (xy 238.270039 -356.110036) (xy 238.282165 -356.055599)
			(xy 238.302088 -356.003508) (xy 238.329384 -355.954873) (xy 238.36347 -355.91073) (xy 238.403619 -355.872021)
			(xy 238.448977 -355.83957) (xy 238.498577 -355.814069) (xy 238.551361 -355.796062) (xy 238.606204 -355.785932)
			(xy 238.661938 -355.783895) (xy 238.717375 -355.789995) (xy 238.771332 -355.804101) (xy 238.822661 -355.825913)
			(xy 238.870267 -355.854967) (xy 238.913135 -355.890642) (xy 238.950352 -355.932179) (xy 238.981125 -355.978692)
			(xy 239.004797 -356.029189) (xy 239.008878 -356.042752) (xy 249.589499 -356.042752) (xy 249.589499 -355.988248)
			(xy 249.597257 -355.9343) (xy 249.612613 -355.882004) (xy 249.635256 -355.832427) (xy 249.664725 -355.786577)
			(xy 249.700419 -355.745388) (xy 249.741612 -355.709698) (xy 249.787466 -355.680235) (xy 249.837046 -355.657598)
			(xy 249.889343 -355.642247) (xy 249.943292 -355.634496) (xy 249.970544 -355.634036) (xy 249.99946 -355.634581)
			(xy 250.056631 -355.643302) (xy 250.11183 -355.660554) (xy 250.163792 -355.685941) (xy 250.211326 -355.71888)
			(xy 250.253344 -355.758618) (xy 250.271534 -355.781102) (xy 250.279136 -355.789915) (xy 250.30004 -355.800095)
			(xy 250.311666 -355.80066) (xy 250.391422 -355.80066) (xy 250.403056 -355.800133) (xy 250.423966 -355.789937)
			(xy 250.431554 -355.781102) (xy 250.449771 -355.758641) (xy 250.491786 -355.718904) (xy 250.539315 -355.685963)
			(xy 250.591271 -355.66057) (xy 250.646464 -355.643309) (xy 250.70363 -355.634574) (xy 250.732544 -355.634036)
			(xy 250.759796 -355.634437) (xy 250.813746 -355.642199) (xy 250.866041 -355.65756) (xy 250.915618 -355.680206)
			(xy 250.961469 -355.709677) (xy 251.002658 -355.745373) (xy 251.038349 -355.786567) (xy 251.067815 -355.83242)
			(xy 251.090455 -355.882) (xy 251.10581 -355.934298) (xy 251.113566 -355.988248) (xy 251.113566 -356.042752)
			(xy 251.10581 -356.096702) (xy 251.090455 -356.149) (xy 251.067815 -356.19858) (xy 251.038349 -356.244433)
			(xy 251.002658 -356.285627) (xy 250.961469 -356.321323) (xy 250.915618 -356.350794) (xy 250.866041 -356.37344)
			(xy 250.813746 -356.388801) (xy 250.759796 -356.396563) (xy 250.732544 -356.397052) (xy 250.703627 -356.39652)
			(xy 250.646456 -356.387797) (xy 250.591257 -356.370543) (xy 250.539294 -356.345154) (xy 250.49176 -356.312211)
			(xy 250.449744 -356.272471) (xy 250.431554 -356.249986) (xy 250.423959 -356.241166) (xy 250.403049 -356.23099)
			(xy 250.391422 -356.230428) (xy 250.311666 -356.230428) (xy 250.300032 -356.230952) (xy 250.279122 -356.241151)
			(xy 250.271534 -356.249986) (xy 250.25332 -356.27245) (xy 250.211306 -356.312187) (xy 250.163776 -356.345129)
			(xy 250.111819 -356.370521) (xy 250.056625 -356.387781) (xy 249.999459 -356.396515) (xy 249.970544 -356.397052)
			(xy 249.943292 -356.396504) (xy 249.889343 -356.388753) (xy 249.837046 -356.373402) (xy 249.787466 -356.350765)
			(xy 249.741612 -356.321302) (xy 249.700419 -356.285612) (xy 249.664725 -356.244423) (xy 249.635256 -356.198573)
			(xy 249.612613 -356.148996) (xy 249.597257 -356.0967) (xy 249.589499 -356.042752) (xy 239.008878 -356.042752)
			(xy 239.020865 -356.082596) (xy 239.028985 -356.137772) (xy 239.029494 -356.165658) (xy 239.028985 -356.193544)
			(xy 239.020865 -356.24872) (xy 239.004797 -356.302127) (xy 238.981125 -356.352624) (xy 238.950352 -356.399137)
			(xy 238.913135 -356.440674) (xy 238.870267 -356.476349) (xy 238.822661 -356.505403) (xy 238.771332 -356.527215)
			(xy 238.717375 -356.541321) (xy 238.661938 -356.547421) (xy 238.606204 -356.545384) (xy 238.551361 -356.535254)
			(xy 238.498577 -356.517247) (xy 238.448977 -356.491746) (xy 238.403619 -356.459295) (xy 238.36347 -356.420586)
			(xy 238.329384 -356.376443) (xy 238.302088 -356.327808) (xy 238.282165 -356.275717) (xy 238.270039 -356.22128)
			(xy 238.265968 -356.165658) (xy 236.895894 -356.165658) (xy 236.895385 -356.193544) (xy 236.887265 -356.24872)
			(xy 236.871197 -356.302127) (xy 236.847525 -356.352624) (xy 236.816752 -356.399137) (xy 236.779535 -356.440674)
			(xy 236.736667 -356.476349) (xy 236.689061 -356.505403) (xy 236.637732 -356.527215) (xy 236.583775 -356.541321)
			(xy 236.528338 -356.547421) (xy 236.472604 -356.545384) (xy 236.417761 -356.535254) (xy 236.364977 -356.517247)
			(xy 236.315377 -356.491746) (xy 236.270019 -356.459295) (xy 236.22987 -356.420586) (xy 236.195784 -356.376443)
			(xy 236.168488 -356.327808) (xy 236.148565 -356.275717) (xy 236.136439 -356.22128) (xy 236.132368 -356.165658)
			(xy 206.145207 -356.165658) (xy 206.124955 -356.20886) (xy 206.094182 -356.255373) (xy 206.056965 -356.29691)
			(xy 206.014097 -356.332585) (xy 205.966491 -356.361639) (xy 205.915162 -356.383451) (xy 205.861205 -356.397557)
			(xy 205.805768 -356.403657) (xy 205.750034 -356.40162) (xy 205.695191 -356.39149) (xy 205.642407 -356.373483)
			(xy 205.592807 -356.347982) (xy 205.547449 -356.315531) (xy 205.5073 -356.276822) (xy 205.473214 -356.232679)
			(xy 205.445918 -356.184044) (xy 205.425995 -356.131953) (xy 205.413869 -356.077516) (xy 205.409798 -356.021894)
			(xy 155.1686 -356.021894) (xy 155.1686 -356.644194) (xy 155.169108 -356.650798) (xy 155.169842 -356.655658)
			(xy 155.172902 -356.664998) (xy 155.175204 -356.66934) (xy 155.178506 -356.674928) (xy 155.18003 -356.678484)
			(xy 155.181695 -356.682937) (xy 155.183481 -356.692273) (xy 155.183586 -356.697026) (xy 155.183586 -356.811326)
			(xy 204.000098 -356.811326) (xy 204.004169 -356.755704) (xy 204.016295 -356.701267) (xy 204.036218 -356.649176)
			(xy 204.063514 -356.600541) (xy 204.0976 -356.556398) (xy 204.137749 -356.517689) (xy 204.183107 -356.485238)
			(xy 204.232707 -356.459737) (xy 204.285491 -356.44173) (xy 204.340334 -356.4316) (xy 204.396068 -356.429563)
			(xy 204.451505 -356.435663) (xy 204.505462 -356.449769) (xy 204.556791 -356.471581) (xy 204.604397 -356.500635)
			(xy 204.647265 -356.53631) (xy 204.684482 -356.577847) (xy 204.715255 -356.62436) (xy 204.738927 -356.674857)
			(xy 204.754995 -356.728264) (xy 204.763115 -356.78344) (xy 204.763624 -356.811326) (xy 204.763115 -356.839212)
			(xy 204.754995 -356.894388) (xy 204.738927 -356.947795) (xy 204.715255 -356.998292) (xy 204.684482 -357.044805)
			(xy 204.647265 -357.086342) (xy 204.604397 -357.122017) (xy 204.589911 -357.130858) (xy 236.132368 -357.130858)
			(xy 236.136439 -357.075236) (xy 236.148565 -357.020799) (xy 236.168488 -356.968708) (xy 236.195784 -356.920073)
			(xy 236.22987 -356.87593) (xy 236.270019 -356.837221) (xy 236.315377 -356.80477) (xy 236.364977 -356.779269)
			(xy 236.417761 -356.761262) (xy 236.472604 -356.751132) (xy 236.528338 -356.749095) (xy 236.583775 -356.755195)
			(xy 236.637732 -356.769301) (xy 236.689061 -356.791113) (xy 236.736667 -356.820167) (xy 236.779535 -356.855842)
			(xy 236.816752 -356.897379) (xy 236.847525 -356.943892) (xy 236.871197 -356.994389) (xy 236.887265 -357.047796)
			(xy 236.895385 -357.102972) (xy 236.895894 -357.130858) (xy 236.895385 -357.158744) (xy 236.890705 -357.190548)
			(xy 239.453672 -357.190548) (xy 239.457743 -357.134926) (xy 239.469869 -357.080489) (xy 239.489792 -357.028398)
			(xy 239.517088 -356.979763) (xy 239.551174 -356.93562) (xy 239.591323 -356.896911) (xy 239.636681 -356.86446)
			(xy 239.686281 -356.838959) (xy 239.739065 -356.820952) (xy 239.793908 -356.810822) (xy 239.849642 -356.808785)
			(xy 239.905079 -356.814885) (xy 239.959036 -356.828991) (xy 240.010365 -356.850803) (xy 240.057971 -356.879857)
			(xy 240.100839 -356.915532) (xy 240.138056 -356.957069) (xy 240.168829 -357.003582) (xy 240.192501 -357.054079)
			(xy 240.208569 -357.107486) (xy 240.216689 -357.162662) (xy 240.217198 -357.190548) (xy 240.469672 -357.190548)
			(xy 240.473743 -357.134926) (xy 240.485869 -357.080489) (xy 240.505792 -357.028398) (xy 240.533088 -356.979763)
			(xy 240.567174 -356.93562) (xy 240.607323 -356.896911) (xy 240.652681 -356.86446) (xy 240.702281 -356.838959)
			(xy 240.755065 -356.820952) (xy 240.809908 -356.810822) (xy 240.865642 -356.808785) (xy 240.921079 -356.814885)
			(xy 240.975036 -356.828991) (xy 241.026365 -356.850803) (xy 241.073971 -356.879857) (xy 241.116839 -356.915532)
			(xy 241.154056 -356.957069) (xy 241.184829 -357.003582) (xy 241.208501 -357.054079) (xy 241.224569 -357.107486)
			(xy 241.232689 -357.162662) (xy 241.233198 -357.190548) (xy 241.232689 -357.218434) (xy 241.224569 -357.27361)
			(xy 241.208501 -357.327017) (xy 241.184829 -357.377514) (xy 241.154056 -357.424027) (xy 241.116839 -357.465564)
			(xy 241.073971 -357.501239) (xy 241.026365 -357.530293) (xy 240.975036 -357.552105) (xy 240.921079 -357.566211)
			(xy 240.865642 -357.572311) (xy 240.809908 -357.570274) (xy 240.755065 -357.560144) (xy 240.702281 -357.542137)
			(xy 240.652681 -357.516636) (xy 240.607323 -357.484185) (xy 240.567174 -357.445476) (xy 240.533088 -357.401333)
			(xy 240.505792 -357.352698) (xy 240.485869 -357.300607) (xy 240.473743 -357.24617) (xy 240.469672 -357.190548)
			(xy 240.217198 -357.190548) (xy 240.216689 -357.218434) (xy 240.208569 -357.27361) (xy 240.192501 -357.327017)
			(xy 240.168829 -357.377514) (xy 240.138056 -357.424027) (xy 240.100839 -357.465564) (xy 240.057971 -357.501239)
			(xy 240.010365 -357.530293) (xy 239.959036 -357.552105) (xy 239.905079 -357.566211) (xy 239.849642 -357.572311)
			(xy 239.793908 -357.570274) (xy 239.739065 -357.560144) (xy 239.686281 -357.542137) (xy 239.636681 -357.516636)
			(xy 239.591323 -357.484185) (xy 239.551174 -357.445476) (xy 239.517088 -357.401333) (xy 239.489792 -357.352698)
			(xy 239.469869 -357.300607) (xy 239.457743 -357.24617) (xy 239.453672 -357.190548) (xy 236.890705 -357.190548)
			(xy 236.887265 -357.21392) (xy 236.871197 -357.267327) (xy 236.847525 -357.317824) (xy 236.816752 -357.364337)
			(xy 236.779535 -357.405874) (xy 236.736667 -357.441549) (xy 236.689061 -357.470603) (xy 236.637732 -357.492415)
			(xy 236.583775 -357.506521) (xy 236.528338 -357.512621) (xy 236.472604 -357.510584) (xy 236.417761 -357.500454)
			(xy 236.364977 -357.482447) (xy 236.315377 -357.456946) (xy 236.270019 -357.424495) (xy 236.22987 -357.385786)
			(xy 236.195784 -357.341643) (xy 236.168488 -357.293008) (xy 236.148565 -357.240917) (xy 236.136439 -357.18648)
			(xy 236.132368 -357.130858) (xy 204.589911 -357.130858) (xy 204.556791 -357.151071) (xy 204.505462 -357.172883)
			(xy 204.451505 -357.186989) (xy 204.396068 -357.193089) (xy 204.340334 -357.191052) (xy 204.285491 -357.180922)
			(xy 204.232707 -357.162915) (xy 204.183107 -357.137414) (xy 204.137749 -357.104963) (xy 204.0976 -357.066254)
			(xy 204.063514 -357.022111) (xy 204.036218 -356.973476) (xy 204.016295 -356.921385) (xy 204.004169 -356.866948)
			(xy 204.000098 -356.811326) (xy 155.183586 -356.811326) (xy 155.183586 -357.784965) (xy 158.695954 -357.784965)
			(xy 158.695954 -357.730435) (xy 158.703714 -357.67646) (xy 158.719076 -357.624138) (xy 158.741727 -357.574535)
			(xy 158.771206 -357.52866) (xy 158.806913 -357.487447) (xy 158.848122 -357.451735) (xy 158.893993 -357.42225)
			(xy 158.943593 -357.399593) (xy 158.995913 -357.384224) (xy 159.049887 -357.376458) (xy 159.077152 -357.375968)
			(xy 159.940752 -357.375968) (xy 159.968027 -357.376368) (xy 160.022024 -357.384125) (xy 160.074366 -357.399489)
			(xy 160.123989 -357.422145) (xy 160.169883 -357.451634) (xy 160.211112 -357.487354) (xy 160.246837 -357.528579)
			(xy 160.276332 -357.574468) (xy 160.298994 -357.624089) (xy 160.314364 -357.676429) (xy 160.322128 -357.730425)
			(xy 160.322128 -357.784969) (xy 161.804831 -357.784969) (xy 161.804831 -357.730431) (xy 161.812593 -357.676447)
			(xy 161.827959 -357.624117) (xy 161.850616 -357.574507) (xy 161.880102 -357.528627) (xy 161.915818 -357.487409)
			(xy 161.957036 -357.451695) (xy 162.002918 -357.42221) (xy 162.052529 -357.399555) (xy 162.104859 -357.384191)
			(xy 162.158843 -357.376431) (xy 162.186112 -357.375968) (xy 163.049712 -357.375968) (xy 163.076983 -357.376395)
			(xy 163.130969 -357.384159) (xy 163.183302 -357.399527) (xy 163.232914 -357.422185) (xy 163.278797 -357.451674)
			(xy 163.320017 -357.487392) (xy 163.355733 -357.528612) (xy 163.385221 -357.574496) (xy 163.407878 -357.62411)
			(xy 163.423244 -357.676442) (xy 163.431006 -357.730429) (xy 163.431006 -357.784966) (xy 164.913854 -357.784966)
			(xy 164.913854 -357.730434) (xy 164.921615 -357.676457) (xy 164.936977 -357.624134) (xy 164.95963 -357.57453)
			(xy 164.989111 -357.528654) (xy 165.02482 -357.48744) (xy 165.066031 -357.451727) (xy 165.111905 -357.422243)
			(xy 165.161508 -357.399587) (xy 165.21383 -357.384221) (xy 165.267806 -357.376456) (xy 165.295072 -357.375968)
			(xy 166.158672 -357.375968) (xy 166.185946 -357.37637) (xy 166.239941 -357.384129) (xy 166.292281 -357.399494)
			(xy 166.341901 -357.422152) (xy 166.387792 -357.451641) (xy 166.429019 -357.487361) (xy 166.464742 -357.528585)
			(xy 166.494235 -357.574474) (xy 166.516896 -357.624093) (xy 166.532265 -357.676432) (xy 166.540028 -357.730426)
			(xy 166.540028 -357.78497) (xy 168.022732 -357.78497) (xy 168.022732 -357.73043) (xy 168.030494 -357.676444)
			(xy 168.045861 -357.624113) (xy 168.068519 -357.574502) (xy 168.098007 -357.52862) (xy 168.133725 -357.487402)
			(xy 168.174946 -357.451688) (xy 168.22083 -357.422203) (xy 168.270443 -357.399549) (xy 168.322776 -357.384187)
			(xy 168.376762 -357.376429) (xy 168.404032 -357.375968) (xy 169.267632 -357.375968) (xy 169.294902 -357.376397)
			(xy 169.348886 -357.384163) (xy 169.401216 -357.399532) (xy 169.450826 -357.422192) (xy 169.496707 -357.451681)
			(xy 169.537924 -357.487399) (xy 169.573638 -357.528619) (xy 169.603124 -357.574502) (xy 169.625779 -357.624114)
			(xy 169.641144 -357.676445) (xy 169.648906 -357.73043) (xy 169.648906 -357.784967) (xy 171.131754 -357.784967)
			(xy 171.131754 -357.730433) (xy 171.139515 -357.676454) (xy 171.154879 -357.62413) (xy 171.177533 -357.574524)
			(xy 171.207016 -357.528647) (xy 171.242727 -357.487433) (xy 171.283941 -357.45172) (xy 171.329817 -357.422237)
			(xy 171.379422 -357.399582) (xy 171.431747 -357.384217) (xy 171.485725 -357.376455) (xy 171.512992 -357.375968)
			(xy 172.376592 -357.375968) (xy 172.403866 -357.376371) (xy 172.457857 -357.384133) (xy 172.510195 -357.3995)
			(xy 172.559813 -357.422159) (xy 172.605702 -357.451648) (xy 172.646926 -357.487368) (xy 172.682647 -357.528592)
			(xy 172.712138 -357.57448) (xy 172.734798 -357.624097) (xy 172.750165 -357.676435) (xy 172.757928 -357.730426)
			(xy 172.757928 -357.784965) (xy 174.240754 -357.784965) (xy 174.240754 -357.730435) (xy 174.248514 -357.67646)
			(xy 174.263876 -357.624138) (xy 174.286527 -357.574535) (xy 174.316006 -357.52866) (xy 174.351713 -357.487447)
			(xy 174.392922 -357.451735) (xy 174.438793 -357.42225) (xy 174.488393 -357.399593) (xy 174.540713 -357.384224)
			(xy 174.594687 -357.376458) (xy 174.621952 -357.375968) (xy 175.485552 -357.375968) (xy 175.512827 -357.376368)
			(xy 175.566824 -357.384125) (xy 175.619166 -357.399489) (xy 175.668789 -357.422145) (xy 175.714683 -357.451634)
			(xy 175.755912 -357.487354) (xy 175.791637 -357.528579) (xy 175.821132 -357.574468) (xy 175.843794 -357.624089)
			(xy 175.859164 -357.676429) (xy 175.866928 -357.730425) (xy 175.866928 -357.784969) (xy 177.349631 -357.784969)
			(xy 177.349631 -357.730431) (xy 177.357393 -357.676447) (xy 177.372759 -357.624117) (xy 177.395416 -357.574507)
			(xy 177.424902 -357.528627) (xy 177.460618 -357.487409) (xy 177.501836 -357.451695) (xy 177.547718 -357.42221)
			(xy 177.597329 -357.399555) (xy 177.649659 -357.384191) (xy 177.703643 -357.376431) (xy 177.730912 -357.375968)
			(xy 178.594512 -357.375968) (xy 178.621783 -357.376395) (xy 178.675769 -357.384159) (xy 178.728102 -357.399527)
			(xy 178.777714 -357.422185) (xy 178.823597 -357.451674) (xy 178.864817 -357.487392) (xy 178.900533 -357.528612)
			(xy 178.930021 -357.574496) (xy 178.952678 -357.62411) (xy 178.968044 -357.676442) (xy 178.975806 -357.730429)
			(xy 178.975806 -357.784966) (xy 180.458654 -357.784966) (xy 180.458654 -357.730434) (xy 180.466415 -357.676457)
			(xy 180.481777 -357.624134) (xy 180.50443 -357.57453) (xy 180.533911 -357.528654) (xy 180.56962 -357.48744)
			(xy 180.610831 -357.451727) (xy 180.656705 -357.422243) (xy 180.706308 -357.399587) (xy 180.75863 -357.384221)
			(xy 180.812606 -357.376456) (xy 180.839872 -357.375968) (xy 181.703472 -357.375968) (xy 181.730746 -357.37637)
			(xy 181.784741 -357.384129) (xy 181.837081 -357.399494) (xy 181.886701 -357.422152) (xy 181.932592 -357.451641)
			(xy 181.973819 -357.487361) (xy 182.009542 -357.528585) (xy 182.039035 -357.574474) (xy 182.061696 -357.624093)
			(xy 182.077065 -357.676432) (xy 182.084828 -357.730426) (xy 182.084828 -357.761176) (xy 183.567456 -357.761176)
			(xy 183.567456 -357.706624) (xy 183.57522 -357.652628) (xy 183.590589 -357.600287) (xy 183.613252 -357.550665)
			(xy 183.642746 -357.504775) (xy 183.678471 -357.463549) (xy 183.7197 -357.427827) (xy 183.765593 -357.398337)
			(xy 183.815217 -357.375678) (xy 183.867559 -357.360313) (xy 183.921556 -357.352553) (xy 183.948832 -357.352092)
			(xy 184.812432 -357.352092) (xy 184.839697 -357.352672) (xy 184.89367 -357.360437) (xy 184.94599 -357.375803)
			(xy 184.99559 -357.398458) (xy 185.041461 -357.427942) (xy 185.08267 -357.463653) (xy 185.118378 -357.504864)
			(xy 185.147857 -357.550738) (xy 185.170508 -357.60034) (xy 185.18587 -357.652661) (xy 185.19363 -357.706635)
			(xy 185.19363 -357.761165) (xy 185.193629 -357.761172) (xy 186.676479 -357.761172) (xy 186.676479 -357.706628)
			(xy 186.684241 -357.652638) (xy 186.699608 -357.600303) (xy 186.722266 -357.550688) (xy 186.751755 -357.504801)
			(xy 186.787473 -357.463579) (xy 186.828695 -357.42786) (xy 186.87458 -357.39837) (xy 186.924196 -357.37571)
			(xy 186.97653 -357.360343) (xy 187.03052 -357.352579) (xy 187.057792 -357.352092) (xy 187.921392 -357.352092)
			(xy 187.94866 -357.352647) (xy 188.002641 -357.360407) (xy 188.054969 -357.375771) (xy 188.104577 -357.398425)
			(xy 188.150456 -357.427909) (xy 188.191672 -357.463622) (xy 188.227386 -357.504838) (xy 188.256871 -357.550716)
			(xy 188.279526 -357.600324) (xy 188.294891 -357.652651) (xy 188.302653 -357.706632) (xy 188.302653 -357.761168)
			(xy 188.294891 -357.815149) (xy 188.279526 -357.867476) (xy 188.256871 -357.917084) (xy 188.227386 -357.962962)
			(xy 188.191672 -358.004178) (xy 188.150456 -358.039891) (xy 188.104577 -358.069375) (xy 188.054969 -358.092029)
			(xy 188.002641 -358.107393) (xy 187.94866 -358.115153) (xy 187.921392 -358.115616) (xy 187.057792 -358.115616)
			(xy 187.03052 -358.115221) (xy 186.97653 -358.107457) (xy 186.924196 -358.092089) (xy 186.87458 -358.06943)
			(xy 186.828695 -358.03994) (xy 186.787473 -358.004221) (xy 186.751755 -357.962999) (xy 186.722266 -357.917112)
			(xy 186.699608 -357.867497) (xy 186.684241 -357.815162) (xy 186.676479 -357.761172) (xy 185.193629 -357.761172)
			(xy 185.18587 -357.815139) (xy 185.170508 -357.86746) (xy 185.147857 -357.917062) (xy 185.118378 -357.962936)
			(xy 185.08267 -358.004147) (xy 185.041461 -358.039858) (xy 184.99559 -358.069342) (xy 184.94599 -358.091997)
			(xy 184.89367 -358.107363) (xy 184.839697 -358.115128) (xy 184.812432 -358.115616) (xy 183.948832 -358.115616)
			(xy 183.921556 -358.115247) (xy 183.867559 -358.107487) (xy 183.815217 -358.092122) (xy 183.765593 -358.069463)
			(xy 183.7197 -358.039973) (xy 183.678471 -358.004251) (xy 183.642746 -357.963025) (xy 183.613252 -357.917135)
			(xy 183.590589 -357.867513) (xy 183.57522 -357.815172) (xy 183.567456 -357.761176) (xy 182.084828 -357.761176)
			(xy 182.084828 -357.784974) (xy 182.077065 -357.838968) (xy 182.061696 -357.891307) (xy 182.039035 -357.940926)
			(xy 182.009542 -357.986815) (xy 181.973819 -358.028039) (xy 181.932592 -358.063759) (xy 181.886701 -358.093248)
			(xy 181.837081 -358.115906) (xy 181.784741 -358.131271) (xy 181.730746 -358.13903) (xy 181.703472 -358.139492)
			(xy 180.839872 -358.139492) (xy 180.812606 -358.138944) (xy 180.75863 -358.131179) (xy 180.706308 -358.115813)
			(xy 180.656705 -358.093157) (xy 180.610831 -358.063673) (xy 180.56962 -358.02796) (xy 180.533911 -357.986746)
			(xy 180.50443 -357.94087) (xy 180.481777 -357.891266) (xy 180.466415 -357.838943) (xy 180.458654 -357.784966)
			(xy 178.975806 -357.784966) (xy 178.975806 -357.784971) (xy 178.968044 -357.838958) (xy 178.952678 -357.89129)
			(xy 178.930021 -357.940904) (xy 178.900533 -357.986788) (xy 178.864817 -358.028008) (xy 178.823597 -358.063726)
			(xy 178.777714 -358.093215) (xy 178.728102 -358.115873) (xy 178.675769 -358.131241) (xy 178.621783 -358.139005)
			(xy 178.594512 -358.139492) (xy 177.730912 -358.139492) (xy 177.703643 -358.138969) (xy 177.649659 -358.131209)
			(xy 177.597329 -358.115845) (xy 177.547718 -358.09319) (xy 177.501836 -358.063705) (xy 177.460618 -358.027991)
			(xy 177.424902 -357.986773) (xy 177.395416 -357.940893) (xy 177.372759 -357.891283) (xy 177.357393 -357.838953)
			(xy 177.349631 -357.784969) (xy 175.866928 -357.784969) (xy 175.866928 -357.784975) (xy 175.859164 -357.838971)
			(xy 175.843794 -357.891311) (xy 175.821132 -357.940932) (xy 175.791637 -357.986821) (xy 175.755912 -358.028046)
			(xy 175.714683 -358.063766) (xy 175.668789 -358.093255) (xy 175.619166 -358.115911) (xy 175.566824 -358.131275)
			(xy 175.512827 -358.139032) (xy 175.485552 -358.139492) (xy 174.621952 -358.139492) (xy 174.594687 -358.138942)
			(xy 174.540713 -358.131176) (xy 174.488393 -358.115807) (xy 174.438793 -358.09315) (xy 174.392922 -358.063665)
			(xy 174.351713 -358.027953) (xy 174.316006 -357.98674) (xy 174.286527 -357.940865) (xy 174.263876 -357.891262)
			(xy 174.248514 -357.83894) (xy 174.240754 -357.784965) (xy 172.757928 -357.784965) (xy 172.757928 -357.784974)
			(xy 172.750165 -357.838965) (xy 172.734798 -357.891303) (xy 172.712138 -357.94092) (xy 172.682647 -357.986808)
			(xy 172.646926 -358.028032) (xy 172.605702 -358.063752) (xy 172.559813 -358.093241) (xy 172.510195 -358.1159)
			(xy 172.457857 -358.131267) (xy 172.403866 -358.139029) (xy 172.376592 -358.139492) (xy 171.512992 -358.139492)
			(xy 171.485725 -358.138945) (xy 171.431747 -358.131183) (xy 171.379422 -358.115818) (xy 171.329817 -358.093163)
			(xy 171.283941 -358.06368) (xy 171.242727 -358.027967) (xy 171.207016 -357.986753) (xy 171.177533 -357.940876)
			(xy 171.154879 -357.89127) (xy 171.139515 -357.838946) (xy 171.131754 -357.784967) (xy 169.648906 -357.784967)
			(xy 169.648906 -357.78497) (xy 169.641144 -357.838955) (xy 169.625779 -357.891286) (xy 169.603124 -357.940898)
			(xy 169.573638 -357.986781) (xy 169.537924 -358.028001) (xy 169.496707 -358.063719) (xy 169.450826 -358.093208)
			(xy 169.401216 -358.115868) (xy 169.348886 -358.131237) (xy 169.294902 -358.139003) (xy 169.267632 -358.139492)
			(xy 168.404032 -358.139492) (xy 168.376762 -358.138971) (xy 168.322776 -358.131213) (xy 168.270443 -358.115851)
			(xy 168.22083 -358.093197) (xy 168.174946 -358.063712) (xy 168.133725 -358.027998) (xy 168.098007 -357.98678)
			(xy 168.068519 -357.940898) (xy 168.045861 -357.891287) (xy 168.030494 -357.838956) (xy 168.022732 -357.78497)
			(xy 166.540028 -357.78497) (xy 166.540028 -357.784974) (xy 166.532265 -357.838968) (xy 166.516896 -357.891307)
			(xy 166.494235 -357.940926) (xy 166.464742 -357.986815) (xy 166.429019 -358.028039) (xy 166.387792 -358.063759)
			(xy 166.341901 -358.093248) (xy 166.292281 -358.115906) (xy 166.239941 -358.131271) (xy 166.185946 -358.13903)
			(xy 166.158672 -358.139492) (xy 165.295072 -358.139492) (xy 165.267806 -358.138944) (xy 165.21383 -358.131179)
			(xy 165.161508 -358.115813) (xy 165.111905 -358.093157) (xy 165.066031 -358.063673) (xy 165.02482 -358.02796)
			(xy 164.989111 -357.986746) (xy 164.95963 -357.94087) (xy 164.936977 -357.891266) (xy 164.921615 -357.838943)
			(xy 164.913854 -357.784966) (xy 163.431006 -357.784966) (xy 163.431006 -357.784971) (xy 163.423244 -357.838958)
			(xy 163.407878 -357.89129) (xy 163.385221 -357.940904) (xy 163.355733 -357.986788) (xy 163.320017 -358.028008)
			(xy 163.278797 -358.063726) (xy 163.232914 -358.093215) (xy 163.183302 -358.115873) (xy 163.130969 -358.131241)
			(xy 163.076983 -358.139005) (xy 163.049712 -358.139492) (xy 162.186112 -358.139492) (xy 162.158843 -358.138969)
			(xy 162.104859 -358.131209) (xy 162.052529 -358.115845) (xy 162.002918 -358.09319) (xy 161.957036 -358.063705)
			(xy 161.915818 -358.027991) (xy 161.880102 -357.986773) (xy 161.850616 -357.940893) (xy 161.827959 -357.891283)
			(xy 161.812593 -357.838953) (xy 161.804831 -357.784969) (xy 160.322128 -357.784969) (xy 160.322128 -357.784975)
			(xy 160.314364 -357.838971) (xy 160.298994 -357.891311) (xy 160.276332 -357.940932) (xy 160.246837 -357.986821)
			(xy 160.211112 -358.028046) (xy 160.169883 -358.063766) (xy 160.123989 -358.093255) (xy 160.074366 -358.115911)
			(xy 160.022024 -358.131275) (xy 159.968027 -358.139032) (xy 159.940752 -358.139492) (xy 159.077152 -358.139492)
			(xy 159.049887 -358.138942) (xy 158.995913 -358.131176) (xy 158.943593 -358.115807) (xy 158.893993 -358.09315)
			(xy 158.848122 -358.063665) (xy 158.806913 -358.027953) (xy 158.771206 -357.98674) (xy 158.741727 -357.940865)
			(xy 158.719076 -357.891262) (xy 158.703714 -357.83894) (xy 158.695954 -357.784965) (xy 155.183586 -357.784965)
			(xy 155.183586 -358.388158) (xy 198.676258 -358.388158) (xy 198.680329 -358.332536) (xy 198.692455 -358.278099)
			(xy 198.712378 -358.226008) (xy 198.739674 -358.177373) (xy 198.77376 -358.13323) (xy 198.813909 -358.094521)
			(xy 198.859267 -358.06207) (xy 198.908867 -358.036569) (xy 198.961651 -358.018562) (xy 199.016494 -358.008432)
			(xy 199.072228 -358.006395) (xy 199.127665 -358.012495) (xy 199.181622 -358.026601) (xy 199.232951 -358.048413)
			(xy 199.242535 -358.054262) (xy 240.979625 -358.054262) (xy 240.979625 -357.99975) (xy 240.987382 -357.945794)
			(xy 241.002739 -357.893491) (xy 241.025383 -357.843906) (xy 241.054854 -357.798048) (xy 241.090551 -357.756851)
			(xy 241.131748 -357.721154) (xy 241.177606 -357.691683) (xy 241.227191 -357.669039) (xy 241.279494 -357.653682)
			(xy 241.33345 -357.645925) (xy 241.360706 -357.645462) (xy 241.386106 -357.646224) (xy 241.400221 -357.646776)
			(xy 241.427834 -357.64085) (xy 241.452769 -357.627589) (xy 241.47312 -357.608007) (xy 241.487331 -357.583601)
			(xy 241.494315 -357.556237) (xy 241.493539 -357.528005) (xy 241.489738 -357.514398) (xy 241.481556 -357.486534)
			(xy 241.472755 -357.429134) (xy 241.472212 -357.400098) (xy 241.47268 -357.372847) (xy 241.480436 -357.3189)
			(xy 241.495791 -357.266607) (xy 241.518432 -357.21703) (xy 241.547898 -357.171181) (xy 241.583589 -357.129991)
			(xy 241.624778 -357.0943) (xy 241.670627 -357.064834) (xy 241.720204 -357.042193) (xy 241.772497 -357.026837)
			(xy 241.826444 -357.01908) (xy 241.880945 -357.019079) (xy 241.934892 -357.026835) (xy 241.987186 -357.042189)
			(xy 242.036763 -357.064829) (xy 242.082613 -357.094293) (xy 242.123804 -357.129983) (xy 242.159496 -357.171172)
			(xy 242.188963 -357.217021) (xy 242.211605 -357.266597) (xy 242.226961 -357.31889) (xy 242.234719 -357.372837)
			(xy 242.234721 -357.427338) (xy 242.226967 -357.481285) (xy 242.211614 -357.53358) (xy 242.188975 -357.583157)
			(xy 242.159511 -357.629008) (xy 242.123822 -357.670199) (xy 242.082634 -357.705891) (xy 242.036786 -357.735359)
			(xy 241.98721 -357.758002) (xy 241.934917 -357.77336) (xy 241.880971 -357.781119) (xy 241.85372 -357.781606)
			(xy 241.82832 -357.780844) (xy 241.814205 -357.780356) (xy 241.7866 -357.786274) (xy 241.76167 -357.799525)
			(xy 241.741322 -357.819096) (xy 241.72711 -357.84349) (xy 241.720122 -357.870844) (xy 241.720891 -357.899066)
			(xy 241.724688 -357.91267) (xy 241.732863 -357.940536) (xy 241.736916 -357.966956) (xy 245.50903 -357.966956)
			(xy 245.50903 -357.88226) (xy 245.517081 -357.797946) (xy 245.53311 -357.71478) (xy 245.556971 -357.633513)
			(xy 245.58845 -357.554883) (xy 245.627261 -357.479602) (xy 245.673051 -357.40835) (xy 245.725407 -357.341774)
			(xy 245.783855 -357.280476) (xy 245.847865 -357.225011) (xy 245.916857 -357.175882) (xy 245.990207 -357.133533)
			(xy 246.06725 -357.098349) (xy 246.147289 -357.070647) (xy 246.229598 -357.050679) (xy 246.313433 -357.038626)
			(xy 246.398034 -357.034596) (xy 246.482635 -357.038626) (xy 246.56647 -357.050679) (xy 246.648779 -357.070647)
			(xy 246.728818 -357.098349) (xy 246.805861 -357.133533) (xy 246.879211 -357.175882) (xy 246.948203 -357.225011)
			(xy 247.012213 -357.280476) (xy 247.070661 -357.341774) (xy 247.123017 -357.40835) (xy 247.168807 -357.479602)
			(xy 247.207618 -357.554883) (xy 247.239097 -357.633513) (xy 247.262958 -357.71478) (xy 247.278987 -357.797946)
			(xy 247.287038 -357.88226) (xy 247.287542 -357.924608) (xy 247.287038 -357.966956) (xy 247.278987 -358.05127)
			(xy 247.262958 -358.134436) (xy 247.239097 -358.215703) (xy 247.207618 -358.294333) (xy 247.168807 -358.369614)
			(xy 247.123017 -358.440866) (xy 247.070661 -358.507442) (xy 247.012213 -358.56874) (xy 246.948203 -358.624205)
			(xy 246.879211 -358.673334) (xy 246.805861 -358.715683) (xy 246.728818 -358.750867) (xy 246.648779 -358.778569)
			(xy 246.56647 -358.798537) (xy 246.482635 -358.81059) (xy 246.398034 -358.814621) (xy 246.313433 -358.81059)
			(xy 246.229598 -358.798537) (xy 246.147289 -358.778569) (xy 246.06725 -358.750867) (xy 245.990207 -358.715683)
			(xy 245.916857 -358.673334) (xy 245.847865 -358.624205) (xy 245.783855 -358.56874) (xy 245.725407 -358.507442)
			(xy 245.673051 -358.440866) (xy 245.627261 -358.369614) (xy 245.58845 -358.294333) (xy 245.556971 -358.215703)
			(xy 245.53311 -358.134436) (xy 245.517081 -358.05127) (xy 245.50903 -357.966956) (xy 241.736916 -357.966956)
			(xy 241.741668 -357.997935) (xy 241.742214 -358.02697) (xy 241.741777 -358.054226) (xy 241.734024 -358.108182)
			(xy 241.71867 -358.160487) (xy 241.696029 -358.210073) (xy 241.666561 -358.255933) (xy 241.630866 -358.297132)
			(xy 241.589671 -358.332832) (xy 241.543816 -358.362305) (xy 241.494232 -358.384953) (xy 241.441929 -358.400313)
			(xy 241.387974 -358.408074) (xy 241.333462 -358.408076) (xy 241.279506 -358.400321) (xy 241.227202 -358.384966)
			(xy 241.177616 -358.362323) (xy 241.131757 -358.332853) (xy 241.090559 -358.297158) (xy 241.054861 -358.255962)
			(xy 241.025389 -358.210105) (xy 241.002743 -358.16052) (xy 240.987384 -358.108218) (xy 240.979625 -358.054262)
			(xy 199.242535 -358.054262) (xy 199.280557 -358.077467) (xy 199.323425 -358.113142) (xy 199.360642 -358.154679)
			(xy 199.391415 -358.201192) (xy 199.415087 -358.251689) (xy 199.431155 -358.305096) (xy 199.439275 -358.360272)
			(xy 199.439784 -358.388158) (xy 199.439275 -358.416044) (xy 199.431155 -358.47122) (xy 199.415087 -358.524627)
			(xy 199.391415 -358.575124) (xy 199.360642 -358.621637) (xy 199.323425 -358.663174) (xy 199.280557 -358.698849)
			(xy 199.232951 -358.727903) (xy 199.181622 -358.749715) (xy 199.127665 -358.763821) (xy 199.072228 -358.769921)
			(xy 199.016494 -358.767884) (xy 198.961651 -358.757754) (xy 198.908867 -358.739747) (xy 198.859267 -358.714246)
			(xy 198.813909 -358.681795) (xy 198.77376 -358.643086) (xy 198.739674 -358.598943) (xy 198.712378 -358.550308)
			(xy 198.692455 -358.498217) (xy 198.680329 -358.44378) (xy 198.676258 -358.388158) (xy 155.183586 -358.388158)
			(xy 155.183586 -362.492798) (xy 155.184602 -362.502196) (xy 155.186199 -362.509508) (xy 155.193036 -362.522814)
			(xy 155.198064 -362.528358) (xy 156.175202 -363.504988) (xy 156.177234 -363.506512)
		)
		(stroke
			(width 0)
			(type solid)
		)
		(fill yes)
		(layer "In15.Cu")
		(net "GND")
	)
	(gr_poly
		(pts
			(xy 268.642846 -315.960506) (xy 268.653002 -315.960057) (xy 268.671732 -315.952197) (xy 268.679168 -315.945266)
			(xy 268.737334 -315.88583) (xy 268.7447 -315.867034) (xy 268.744446 -315.85662) (xy 268.744446 -315.849762)
			(xy 268.744968 -315.824507) (xy 268.753281 -315.774685) (xy 268.769682 -315.726911) (xy 268.793723 -315.682488)
			(xy 268.824747 -315.642628) (xy 268.861909 -315.608418) (xy 268.904195 -315.580792) (xy 268.950451 -315.560502)
			(xy 268.999416 -315.548102) (xy 269.049754 -315.543931) (xy 269.100092 -315.548102) (xy 269.149057 -315.560502)
			(xy 269.195313 -315.580792) (xy 269.237599 -315.608418) (xy 269.274761 -315.642628) (xy 269.305785 -315.682488)
			(xy 269.329826 -315.726911) (xy 269.346227 -315.774685) (xy 269.35454 -315.824507) (xy 269.355062 -315.849762)
			(xy 269.355062 -315.85662) (xy 269.354808 -315.867034) (xy 269.362174 -315.88583) (xy 269.42034 -315.945266)
			(xy 269.427766 -315.95221) (xy 269.446503 -315.960058) (xy 269.456662 -315.960506) (xy 269.592806 -315.960506)
			(xy 269.602965 -315.960064) (xy 269.621706 -315.952215) (xy 269.629128 -315.945266) (xy 269.687294 -315.88583)
			(xy 269.69466 -315.867034) (xy 269.694406 -315.85662) (xy 269.694406 -315.849762) (xy 269.694928 -315.824507)
			(xy 269.703241 -315.774685) (xy 269.719642 -315.726911) (xy 269.743683 -315.682488) (xy 269.774707 -315.642628)
			(xy 269.811869 -315.608418) (xy 269.854155 -315.580792) (xy 269.900411 -315.560502) (xy 269.949376 -315.548102)
			(xy 269.999714 -315.543931) (xy 270.050052 -315.548102) (xy 270.099017 -315.560502) (xy 270.145273 -315.580792)
			(xy 270.187559 -315.608418) (xy 270.224721 -315.642628) (xy 270.255745 -315.682488) (xy 270.279786 -315.726911)
			(xy 270.296187 -315.774685) (xy 270.3045 -315.824507) (xy 270.305022 -315.849762) (xy 270.305022 -315.85662)
			(xy 270.304768 -315.867034) (xy 270.312134 -315.88583) (xy 270.3703 -315.945266) (xy 270.377724 -315.952217)
			(xy 270.396461 -315.960079) (xy 270.406622 -315.960506) (xy 270.54302 -315.960506) (xy 270.553178 -315.960062)
			(xy 270.571915 -315.952209) (xy 270.579342 -315.945266) (xy 270.637508 -315.88583) (xy 270.644874 -315.867034)
			(xy 270.64462 -315.85662) (xy 270.64462 -315.849762) (xy 270.645142 -315.824507) (xy 270.653455 -315.774685)
			(xy 270.669856 -315.726911) (xy 270.693897 -315.682488) (xy 270.724921 -315.642628) (xy 270.762083 -315.608418)
			(xy 270.804369 -315.580792) (xy 270.850625 -315.560502) (xy 270.89959 -315.548102) (xy 270.949928 -315.543931)
			(xy 271.000266 -315.548102) (xy 271.049231 -315.560502) (xy 271.095487 -315.580792) (xy 271.137773 -315.608418)
			(xy 271.174935 -315.642628) (xy 271.205959 -315.682488) (xy 271.23 -315.726911) (xy 271.246401 -315.774685)
			(xy 271.254714 -315.824507) (xy 271.255236 -315.849762) (xy 271.255236 -315.85662) (xy 271.254982 -315.867034)
			(xy 271.262348 -315.88583) (xy 271.320514 -315.945266) (xy 271.327939 -315.952214) (xy 271.346676 -315.960072)
			(xy 271.356836 -315.960506) (xy 271.47139 -315.960506) (xy 271.481542 -315.960049) (xy 271.50026 -315.952178)
			(xy 271.507712 -315.945266) (xy 271.565878 -315.88583) (xy 271.573244 -315.867288) (xy 271.57299 -315.85662)
			(xy 271.572736 -315.849762) (xy 271.57324 -315.824054) (xy 271.581283 -315.773272) (xy 271.597171 -315.724373)
			(xy 271.620514 -315.678561) (xy 271.650735 -315.636965) (xy 271.687091 -315.600609) (xy 271.728687 -315.570388)
			(xy 271.774499 -315.547045) (xy 271.823398 -315.531157) (xy 271.87418 -315.523114) (xy 271.925596 -315.523114)
			(xy 271.976378 -315.531157) (xy 272.025277 -315.547045) (xy 272.071089 -315.570388) (xy 272.112685 -315.600609)
			(xy 272.149041 -315.636965) (xy 272.179262 -315.678561) (xy 272.202605 -315.724373) (xy 272.218493 -315.773272)
			(xy 272.226536 -315.824054) (xy 272.22704 -315.849762) (xy 272.226786 -315.85662) (xy 272.226532 -315.867288)
			(xy 272.233898 -315.88583) (xy 272.292064 -315.945266) (xy 272.299486 -315.952222) (xy 272.318223 -315.960098)
			(xy 272.328386 -315.960506) (xy 272.44294 -315.960506) (xy 272.453096 -315.960058) (xy 272.471828 -315.9522)
			(xy 272.479262 -315.945266) (xy 272.537428 -315.88583) (xy 272.544794 -315.867034) (xy 272.54454 -315.85662)
			(xy 272.54454 -315.849762) (xy 272.545062 -315.824507) (xy 272.553375 -315.774685) (xy 272.569776 -315.726911)
			(xy 272.593817 -315.682488) (xy 272.624841 -315.642628) (xy 272.662003 -315.608418) (xy 272.704289 -315.580792)
			(xy 272.750545 -315.560502) (xy 272.79951 -315.548102) (xy 272.849848 -315.543931) (xy 272.900186 -315.548102)
			(xy 272.949151 -315.560502) (xy 272.995407 -315.580792) (xy 273.037693 -315.608418) (xy 273.074855 -315.642628)
			(xy 273.105879 -315.682488) (xy 273.12992 -315.726911) (xy 273.146321 -315.774685) (xy 273.154634 -315.824507)
			(xy 273.155156 -315.849762) (xy 273.155156 -315.85662) (xy 273.154902 -315.867034) (xy 273.162268 -315.88583)
			(xy 273.220434 -315.945266) (xy 273.22786 -315.952211) (xy 273.246597 -315.960061) (xy 273.256756 -315.960506)
			(xy 273.37131 -315.960506) (xy 273.381469 -315.960064) (xy 273.400208 -315.952213) (xy 273.407632 -315.945266)
			(xy 273.465798 -315.88583) (xy 273.473164 -315.867288) (xy 273.47291 -315.85662) (xy 273.472656 -315.849762)
			(xy 273.47316 -315.824054) (xy 273.481203 -315.773272) (xy 273.497091 -315.724373) (xy 273.520434 -315.678561)
			(xy 273.550655 -315.636965) (xy 273.587011 -315.600609) (xy 273.628607 -315.570388) (xy 273.674419 -315.547045)
			(xy 273.723318 -315.531157) (xy 273.7741 -315.523114) (xy 273.825516 -315.523114) (xy 273.876298 -315.531157)
			(xy 273.925197 -315.547045) (xy 273.971009 -315.570388) (xy 274.012605 -315.600609) (xy 274.048961 -315.636965)
			(xy 274.079182 -315.678561) (xy 274.102525 -315.724373) (xy 274.118413 -315.773272) (xy 274.126456 -315.824054)
			(xy 274.12696 -315.849762) (xy 274.126706 -315.85662) (xy 274.126452 -315.867288) (xy 274.133818 -315.88583)
			(xy 274.191984 -315.945266) (xy 274.199407 -315.952219) (xy 274.218144 -315.960088) (xy 274.228306 -315.960506)
			(xy 274.34286 -315.960506) (xy 274.353015 -315.960054) (xy 274.371741 -315.952191) (xy 274.379182 -315.945266)
			(xy 274.437348 -315.88583) (xy 274.444714 -315.867034) (xy 274.44446 -315.85662) (xy 274.44446 -315.849762)
			(xy 274.444982 -315.824507) (xy 274.453295 -315.774685) (xy 274.469696 -315.726911) (xy 274.493737 -315.682488)
			(xy 274.524761 -315.642628) (xy 274.561923 -315.608418) (xy 274.604209 -315.580792) (xy 274.650465 -315.560502)
			(xy 274.69943 -315.548102) (xy 274.749768 -315.543931) (xy 274.800106 -315.548102) (xy 274.849071 -315.560502)
			(xy 274.895327 -315.580792) (xy 274.937613 -315.608418) (xy 274.974775 -315.642628) (xy 275.005799 -315.682488)
			(xy 275.02984 -315.726911) (xy 275.046241 -315.774685) (xy 275.054554 -315.824507) (xy 275.055076 -315.849762)
			(xy 275.055076 -315.85662) (xy 275.054822 -315.867034) (xy 275.062188 -315.88583) (xy 275.120354 -315.945266)
			(xy 275.127776 -315.952224) (xy 275.146512 -315.960103) (xy 275.156676 -315.960506) (xy 275.27123 -315.960506)
			(xy 275.281387 -315.96006) (xy 275.300121 -315.952204) (xy 275.307552 -315.945266) (xy 275.365718 -315.88583)
			(xy 275.373084 -315.867288) (xy 275.37283 -315.85662) (xy 275.372576 -315.849762) (xy 275.37308 -315.824054)
			(xy 275.381123 -315.773272) (xy 275.397011 -315.724373) (xy 275.420354 -315.678561) (xy 275.450575 -315.636965)
			(xy 275.486931 -315.600609) (xy 275.528527 -315.570388) (xy 275.574339 -315.547045) (xy 275.623238 -315.531157)
			(xy 275.67402 -315.523114) (xy 275.725436 -315.523114) (xy 275.776218 -315.531157) (xy 275.825117 -315.547045)
			(xy 275.870929 -315.570388) (xy 275.912525 -315.600609) (xy 275.948881 -315.636965) (xy 275.979102 -315.678561)
			(xy 276.002445 -315.724373) (xy 276.018333 -315.773272) (xy 276.026376 -315.824054) (xy 276.02688 -315.849762)
			(xy 276.026626 -315.85662) (xy 276.026372 -315.867288) (xy 276.033738 -315.88583) (xy 276.091904 -315.945266)
			(xy 276.099328 -315.952216) (xy 276.118065 -315.960077) (xy 276.128226 -315.960506) (xy 276.24278 -315.960506)
			(xy 276.252933 -315.960051) (xy 276.271654 -315.952182) (xy 276.279102 -315.945266) (xy 276.337268 -315.88583)
			(xy 276.344634 -315.867034) (xy 276.34438 -315.85662) (xy 276.34438 -315.849762) (xy 276.344902 -315.824507)
			(xy 276.353215 -315.774685) (xy 276.369616 -315.726911) (xy 276.393657 -315.682488) (xy 276.424681 -315.642628)
			(xy 276.461843 -315.608418) (xy 276.504129 -315.580792) (xy 276.550385 -315.560502) (xy 276.59935 -315.548102)
			(xy 276.649688 -315.543931) (xy 276.700026 -315.548102) (xy 276.748991 -315.560502) (xy 276.795247 -315.580792)
			(xy 276.837533 -315.608418) (xy 276.874695 -315.642628) (xy 276.905719 -315.682488) (xy 276.92976 -315.726911)
			(xy 276.946161 -315.774685) (xy 276.954474 -315.824507) (xy 276.954996 -315.849762) (xy 276.954996 -315.85662)
			(xy 276.954742 -315.867034) (xy 276.962108 -315.88583) (xy 277.020274 -315.945266) (xy 277.027697 -315.952221)
			(xy 277.046434 -315.960093) (xy 277.056596 -315.960506) (xy 277.171404 -315.960506) (xy 277.181563 -315.960065)
			(xy 277.200304 -315.952216) (xy 277.207726 -315.945266) (xy 277.265892 -315.88583) (xy 277.273258 -315.867288)
			(xy 277.273004 -315.85662) (xy 277.273004 -315.849762) (xy 277.273508 -315.824074) (xy 277.281545 -315.773331)
			(xy 277.297421 -315.72447) (xy 277.320745 -315.678694) (xy 277.350942 -315.63713) (xy 277.38727 -315.600802)
			(xy 277.428834 -315.570605) (xy 277.47461 -315.547281) (xy 277.523471 -315.531405) (xy 277.574214 -315.523368)
			(xy 277.62559 -315.523368) (xy 277.676333 -315.531405) (xy 277.725194 -315.547281) (xy 277.77097 -315.570605)
			(xy 277.812534 -315.600802) (xy 277.848862 -315.63713) (xy 277.879059 -315.678694) (xy 277.902383 -315.72447)
			(xy 277.918259 -315.773331) (xy 277.926296 -315.824074) (xy 277.9268 -315.849762) (xy 277.9268 -315.85662)
			(xy 277.926546 -315.867288) (xy 277.933912 -315.88583) (xy 277.992078 -315.945266) (xy 277.999501 -315.95222)
			(xy 278.018238 -315.960091) (xy 278.0284 -315.960506) (xy 278.142954 -315.960506) (xy 278.153109 -315.960056)
			(xy 278.171837 -315.952194) (xy 278.179276 -315.945266) (xy 278.237442 -315.88583) (xy 278.244808 -315.867034)
			(xy 278.244554 -315.85662) (xy 278.244554 -315.849762) (xy 278.245076 -315.824507) (xy 278.253389 -315.774685)
			(xy 278.26979 -315.726911) (xy 278.293831 -315.682488) (xy 278.324855 -315.642628) (xy 278.362017 -315.608418)
			(xy 278.404303 -315.580792) (xy 278.450559 -315.560502) (xy 278.499524 -315.548102) (xy 278.549862 -315.543931)
			(xy 278.6002 -315.548102) (xy 278.649165 -315.560502) (xy 278.695421 -315.580792) (xy 278.737707 -315.608418)
			(xy 278.774869 -315.642628) (xy 278.805893 -315.682488) (xy 278.829934 -315.726911) (xy 278.846335 -315.774685)
			(xy 278.854648 -315.824507) (xy 278.85517 -315.849762) (xy 278.85517 -315.85662) (xy 278.854916 -315.867034)
			(xy 278.862282 -315.88583) (xy 278.920448 -315.945266) (xy 278.92787 -315.952225) (xy 278.946606 -315.960106)
			(xy 278.95677 -315.960506) (xy 279.071324 -315.960506) (xy 279.081482 -315.960061) (xy 279.100217 -315.952207)
			(xy 279.107646 -315.945266) (xy 279.165812 -315.88583) (xy 279.173178 -315.867288) (xy 279.172924 -315.85662)
			(xy 279.172924 -315.849762) (xy 279.173428 -315.824074) (xy 279.181465 -315.773331) (xy 279.197341 -315.72447)
			(xy 279.220665 -315.678694) (xy 279.250862 -315.63713) (xy 279.28719 -315.600802) (xy 279.328754 -315.570605)
			(xy 279.37453 -315.547281) (xy 279.423391 -315.531405) (xy 279.474134 -315.523368) (xy 279.52551 -315.523368)
			(xy 279.576253 -315.531405) (xy 279.625114 -315.547281) (xy 279.67089 -315.570605) (xy 279.712454 -315.600802)
			(xy 279.748782 -315.63713) (xy 279.778979 -315.678694) (xy 279.802303 -315.72447) (xy 279.818179 -315.773331)
			(xy 279.826216 -315.824074) (xy 279.82672 -315.849762) (xy 279.82672 -315.85662) (xy 279.826466 -315.867288)
			(xy 279.833832 -315.88583) (xy 279.891998 -315.945266) (xy 279.899422 -315.952217) (xy 279.918159 -315.96008)
			(xy 279.92832 -315.960506) (xy 280.042874 -315.960506) (xy 280.053027 -315.960052) (xy 280.07175 -315.952185)
			(xy 280.079196 -315.945266) (xy 280.137362 -315.88583) (xy 280.144728 -315.867034) (xy 280.144474 -315.85662)
			(xy 280.144474 -315.849762) (xy 280.144996 -315.824507) (xy 280.153309 -315.774685) (xy 280.16971 -315.726911)
			(xy 280.193751 -315.682488) (xy 280.224775 -315.642628) (xy 280.261937 -315.608418) (xy 280.304223 -315.580792)
			(xy 280.350479 -315.560502) (xy 280.399444 -315.548102) (xy 280.449782 -315.543931) (xy 280.50012 -315.548102)
			(xy 280.549085 -315.560502) (xy 280.595341 -315.580792) (xy 280.637627 -315.608418) (xy 280.674789 -315.642628)
			(xy 280.705813 -315.682488) (xy 280.729854 -315.726911) (xy 280.746255 -315.774685) (xy 280.754568 -315.824507)
			(xy 280.75509 -315.849762) (xy 280.75509 -315.85662) (xy 280.754836 -315.867034) (xy 280.762202 -315.88583)
			(xy 280.820368 -315.945266) (xy 280.827791 -315.952222) (xy 280.846527 -315.960096) (xy 280.85669 -315.960506)
			(xy 280.971244 -315.960506) (xy 280.9814 -315.960057) (xy 281.00013 -315.952198) (xy 281.007566 -315.945266)
			(xy 281.065732 -315.88583) (xy 281.073098 -315.867288) (xy 281.072844 -315.85662) (xy 281.072844 -315.849762)
			(xy 281.073348 -315.824074) (xy 281.081385 -315.773331) (xy 281.097261 -315.72447) (xy 281.120585 -315.678694)
			(xy 281.150782 -315.63713) (xy 281.18711 -315.600802) (xy 281.228674 -315.570605) (xy 281.27445 -315.547281)
			(xy 281.323311 -315.531405) (xy 281.374054 -315.523368) (xy 281.42543 -315.523368) (xy 281.476173 -315.531405)
			(xy 281.525034 -315.547281) (xy 281.57081 -315.570605) (xy 281.612374 -315.600802) (xy 281.648702 -315.63713)
			(xy 281.678899 -315.678694) (xy 281.702223 -315.72447) (xy 281.718099 -315.773331) (xy 281.726136 -315.824074)
			(xy 281.72664 -315.849762) (xy 281.72664 -315.85662) (xy 281.726386 -315.867288) (xy 281.733752 -315.88583)
			(xy 281.791918 -315.945266) (xy 281.799343 -315.952214) (xy 281.81808 -315.96007) (xy 281.82824 -315.960506)
			(xy 281.942794 -315.960506) (xy 281.952954 -315.960067) (xy 281.971698 -315.95222) (xy 281.979116 -315.945266)
			(xy 282.037282 -315.88583) (xy 282.044648 -315.867034) (xy 282.044394 -315.85662) (xy 282.044394 -315.849762)
			(xy 282.044916 -315.824507) (xy 282.053229 -315.774685) (xy 282.06963 -315.726911) (xy 282.093671 -315.682488)
			(xy 282.124695 -315.642628) (xy 282.161857 -315.608418) (xy 282.204143 -315.580792) (xy 282.250399 -315.560502)
			(xy 282.299364 -315.548102) (xy 282.349702 -315.543931) (xy 282.40004 -315.548102) (xy 282.449005 -315.560502)
			(xy 282.495261 -315.580792) (xy 282.537547 -315.608418) (xy 282.574709 -315.642628) (xy 282.605733 -315.682488)
			(xy 282.629774 -315.726911) (xy 282.646175 -315.774685) (xy 282.654488 -315.824507) (xy 282.65501 -315.849762)
			(xy 282.65501 -315.85662) (xy 282.654756 -315.867034) (xy 282.662122 -315.88583) (xy 282.720288 -315.945266)
			(xy 282.727712 -315.952218) (xy 282.746448 -315.960086) (xy 282.75661 -315.960506) (xy 282.871418 -315.960506)
			(xy 282.881576 -315.960062) (xy 282.900313 -315.952209) (xy 282.90774 -315.945266) (xy 282.965906 -315.88583)
			(xy 282.973272 -315.867288) (xy 282.973018 -315.85662) (xy 282.972764 -315.849762) (xy 282.973268 -315.824054)
			(xy 282.981311 -315.773272) (xy 282.997199 -315.724373) (xy 283.020542 -315.678561) (xy 283.050763 -315.636965)
			(xy 283.087119 -315.600609) (xy 283.128715 -315.570388) (xy 283.174527 -315.547045) (xy 283.223426 -315.531157)
			(xy 283.274208 -315.523114) (xy 283.325624 -315.523114) (xy 283.376406 -315.531157) (xy 283.425305 -315.547045)
			(xy 283.471117 -315.570388) (xy 283.512713 -315.600609) (xy 283.549069 -315.636965) (xy 283.57929 -315.678561)
			(xy 283.602633 -315.724373) (xy 283.618521 -315.773272) (xy 283.626564 -315.824054) (xy 283.627068 -315.849762)
			(xy 283.626814 -315.85662) (xy 283.62656 -315.867288) (xy 283.633926 -315.88583) (xy 283.692092 -315.945266)
			(xy 283.699516 -315.952218) (xy 283.718253 -315.960084) (xy 283.728414 -315.960506) (xy 283.842968 -315.960506)
			(xy 283.853122 -315.960053) (xy 283.871846 -315.952188) (xy 283.87929 -315.945266) (xy 283.937456 -315.88583)
			(xy 283.944822 -315.867034) (xy 283.944568 -315.85662) (xy 283.944568 -315.849762) (xy 283.94509 -315.824507)
			(xy 283.953403 -315.774685) (xy 283.969804 -315.726911) (xy 283.993845 -315.682488) (xy 284.024869 -315.642628)
			(xy 284.062031 -315.608418) (xy 284.104317 -315.580792) (xy 284.150573 -315.560502) (xy 284.199538 -315.548102)
			(xy 284.249876 -315.543931) (xy 284.300214 -315.548102) (xy 284.349179 -315.560502) (xy 284.395435 -315.580792)
			(xy 284.437721 -315.608418) (xy 284.474883 -315.642628) (xy 284.505907 -315.682488) (xy 284.529948 -315.726911)
			(xy 284.546349 -315.774685) (xy 284.554662 -315.824507) (xy 284.555184 -315.849762) (xy 284.555184 -315.85662)
			(xy 284.55493 -315.867034) (xy 284.562296 -315.88583) (xy 284.620462 -315.945266) (xy 284.627884 -315.952222)
			(xy 284.646621 -315.960099) (xy 284.656784 -315.960506) (xy 284.771338 -315.960506) (xy 284.781494 -315.960058)
			(xy 284.800226 -315.952201) (xy 284.80766 -315.945266) (xy 284.865826 -315.88583) (xy 284.873192 -315.867288)
			(xy 284.872938 -315.85662) (xy 284.872684 -315.849762) (xy 284.873188 -315.824054) (xy 284.881231 -315.773272)
			(xy 284.897119 -315.724373) (xy 284.920462 -315.678561) (xy 284.950683 -315.636965) (xy 284.987039 -315.600609)
			(xy 285.028635 -315.570388) (xy 285.074447 -315.547045) (xy 285.123346 -315.531157) (xy 285.174128 -315.523114)
			(xy 285.225544 -315.523114) (xy 285.276326 -315.531157) (xy 285.325225 -315.547045) (xy 285.371037 -315.570388)
			(xy 285.412633 -315.600609) (xy 285.448989 -315.636965) (xy 285.47921 -315.678561) (xy 285.502553 -315.724373)
			(xy 285.518441 -315.773272) (xy 285.526484 -315.824054) (xy 285.526988 -315.849762) (xy 285.526734 -315.85662)
			(xy 285.52648 -315.867288) (xy 285.533846 -315.88583) (xy 285.592012 -315.945266) (xy 285.599437 -315.952214)
			(xy 285.618174 -315.960073) (xy 285.628334 -315.960506) (xy 285.742888 -315.960506) (xy 285.75304 -315.960049)
			(xy 285.771759 -315.952179) (xy 285.77921 -315.945266) (xy 285.837376 -315.88583) (xy 285.844742 -315.867034)
			(xy 285.844488 -315.85662) (xy 285.844488 -315.849762) (xy 285.84501 -315.824507) (xy 285.853323 -315.774685)
			(xy 285.869724 -315.726911) (xy 285.893765 -315.682488) (xy 285.924789 -315.642628) (xy 285.961951 -315.608418)
			(xy 286.004237 -315.580792) (xy 286.050493 -315.560502) (xy 286.099458 -315.548102) (xy 286.149796 -315.543931)
			(xy 286.200134 -315.548102) (xy 286.249099 -315.560502) (xy 286.295355 -315.580792) (xy 286.337641 -315.608418)
			(xy 286.374803 -315.642628) (xy 286.405827 -315.682488) (xy 286.429868 -315.726911) (xy 286.446269 -315.774685)
			(xy 286.454582 -315.824507) (xy 286.455104 -315.849762) (xy 286.455104 -315.85662) (xy 286.45485 -315.867034)
			(xy 286.462216 -315.88583) (xy 286.520382 -315.945266) (xy 286.527805 -315.952219) (xy 286.546542 -315.960089)
			(xy 286.556704 -315.960506) (xy 286.671258 -315.960506) (xy 286.681413 -315.960055) (xy 286.700139 -315.952192)
			(xy 286.70758 -315.945266) (xy 286.765746 -315.88583) (xy 286.773112 -315.867288) (xy 286.772858 -315.85662)
			(xy 286.772604 -315.849762) (xy 286.773108 -315.824054) (xy 286.781151 -315.773272) (xy 286.797039 -315.724373)
			(xy 286.820382 -315.678561) (xy 286.850603 -315.636965) (xy 286.886959 -315.600609) (xy 286.928555 -315.570388)
			(xy 286.974367 -315.547045) (xy 287.023266 -315.531157) (xy 287.074048 -315.523114) (xy 287.125464 -315.523114)
			(xy 287.176246 -315.531157) (xy 287.225145 -315.547045) (xy 287.270957 -315.570388) (xy 287.312553 -315.600609)
			(xy 287.348909 -315.636965) (xy 287.37913 -315.678561) (xy 287.402473 -315.724373) (xy 287.418361 -315.773272)
			(xy 287.426404 -315.824054) (xy 287.426908 -315.849762) (xy 287.426654 -315.85662) (xy 287.4264 -315.867288)
			(xy 287.433766 -315.88583) (xy 287.491932 -315.945266) (xy 287.499358 -315.952211) (xy 287.518095 -315.960062)
			(xy 287.528254 -315.960506) (xy 287.642808 -315.960506) (xy 287.652967 -315.960064) (xy 287.671707 -315.952214)
			(xy 287.67913 -315.945266) (xy 287.737296 -315.88583) (xy 287.744662 -315.867034) (xy 287.744408 -315.85662)
			(xy 287.744408 -315.849762) (xy 287.74493 -315.824507) (xy 287.753243 -315.774685) (xy 287.769644 -315.726911)
			(xy 287.793685 -315.682488) (xy 287.824709 -315.642628) (xy 287.861871 -315.608418) (xy 287.904157 -315.580792)
			(xy 287.950413 -315.560502) (xy 287.999378 -315.548102) (xy 288.049716 -315.543931) (xy 288.100054 -315.548102)
			(xy 288.149019 -315.560502) (xy 288.195275 -315.580792) (xy 288.237561 -315.608418) (xy 288.274723 -315.642628)
			(xy 288.305747 -315.682488) (xy 288.329788 -315.726911) (xy 288.346189 -315.774685) (xy 288.354502 -315.824507)
			(xy 288.355024 -315.849762) (xy 288.355024 -315.85662) (xy 288.35477 -315.867034) (xy 288.362136 -315.88583)
			(xy 288.420302 -315.945266) (xy 288.427726 -315.952216) (xy 288.446463 -315.960078) (xy 288.456624 -315.960506)
			(xy 288.571432 -315.960506) (xy 288.581589 -315.96006) (xy 288.600322 -315.952203) (xy 288.607754 -315.945266)
			(xy 288.66592 -315.88583) (xy 288.673286 -315.867288) (xy 288.673032 -315.85662) (xy 288.673032 -315.849762)
			(xy 288.673536 -315.824074) (xy 288.681573 -315.773331) (xy 288.697449 -315.72447) (xy 288.720773 -315.678694)
			(xy 288.75097 -315.63713) (xy 288.787298 -315.600802) (xy 288.828862 -315.570605) (xy 288.874638 -315.547281)
			(xy 288.923499 -315.531405) (xy 288.974242 -315.523368) (xy 289.025618 -315.523368) (xy 289.076361 -315.531405)
			(xy 289.125222 -315.547281) (xy 289.170998 -315.570605) (xy 289.212562 -315.600802) (xy 289.24889 -315.63713)
			(xy 289.279087 -315.678694) (xy 289.302411 -315.72447) (xy 289.318287 -315.773331) (xy 289.326324 -315.824074)
			(xy 289.326828 -315.849762) (xy 289.326828 -315.85662) (xy 289.326574 -315.867288) (xy 289.33394 -315.88583)
			(xy 289.392106 -315.945266) (xy 289.39953 -315.952216) (xy 289.418267 -315.960076) (xy 289.428428 -315.960506)
			(xy 289.542982 -315.960506) (xy 289.553135 -315.96005) (xy 289.571855 -315.952181) (xy 289.579304 -315.945266)
			(xy 289.63747 -315.88583) (xy 289.644836 -315.867034) (xy 289.644582 -315.85662) (xy 289.644582 -315.849762)
			(xy 289.645104 -315.824507) (xy 289.653417 -315.774685) (xy 289.669818 -315.726911) (xy 289.693859 -315.682488)
			(xy 289.724883 -315.642628) (xy 289.762045 -315.608418) (xy 289.804331 -315.580792) (xy 289.850587 -315.560502)
			(xy 289.899552 -315.548102) (xy 289.94989 -315.543931) (xy 290.000228 -315.548102) (xy 290.049193 -315.560502)
			(xy 290.095449 -315.580792) (xy 290.137735 -315.608418) (xy 290.174897 -315.642628) (xy 290.205921 -315.682488)
			(xy 290.229962 -315.726911) (xy 290.246363 -315.774685) (xy 290.254676 -315.824507) (xy 290.255198 -315.849762)
			(xy 290.255198 -315.85662) (xy 290.254944 -315.867034) (xy 290.26231 -315.88583) (xy 290.320476 -315.945266)
			(xy 290.327899 -315.95222) (xy 290.346636 -315.960092) (xy 290.356798 -315.960506) (xy 290.471352 -315.960506)
			(xy 290.481507 -315.960056) (xy 290.500235 -315.952195) (xy 290.507674 -315.945266) (xy 290.56584 -315.88583)
			(xy 290.573206 -315.867288) (xy 290.572952 -315.85662) (xy 290.572952 -315.849762) (xy 290.573456 -315.824074)
			(xy 290.581493 -315.773331) (xy 290.597369 -315.72447) (xy 290.620693 -315.678694) (xy 290.65089 -315.63713)
			(xy 290.687218 -315.600802) (xy 290.728782 -315.570605) (xy 290.774558 -315.547281) (xy 290.823419 -315.531405)
			(xy 290.874162 -315.523368) (xy 290.925538 -315.523368) (xy 290.976281 -315.531405) (xy 291.025142 -315.547281)
			(xy 291.070918 -315.570605) (xy 291.112482 -315.600802) (xy 291.14881 -315.63713) (xy 291.179007 -315.678694)
			(xy 291.202331 -315.72447) (xy 291.218207 -315.773331) (xy 291.226244 -315.824074) (xy 291.226748 -315.849762)
			(xy 291.226748 -315.85662) (xy 291.226494 -315.867288) (xy 291.23386 -315.88583) (xy 291.292026 -315.945266)
			(xy 291.299452 -315.952212) (xy 291.318189 -315.960065) (xy 291.328348 -315.960506) (xy 291.442902 -315.960506)
			(xy 291.453061 -315.960065) (xy 291.471803 -315.952217) (xy 291.479224 -315.945266) (xy 291.53739 -315.88583)
			(xy 291.544756 -315.867034) (xy 291.544502 -315.85662) (xy 291.544502 -315.849762) (xy 291.545024 -315.824507)
			(xy 291.553337 -315.774685) (xy 291.569738 -315.726911) (xy 291.593779 -315.682488) (xy 291.624803 -315.642628)
			(xy 291.661965 -315.608418) (xy 291.704251 -315.580792) (xy 291.750507 -315.560502) (xy 291.799472 -315.548102)
			(xy 291.84981 -315.543931) (xy 291.900148 -315.548102) (xy 291.949113 -315.560502) (xy 291.995369 -315.580792)
			(xy 292.037655 -315.608418) (xy 292.074817 -315.642628) (xy 292.105841 -315.682488) (xy 292.129882 -315.726911)
			(xy 292.146283 -315.774685) (xy 292.154596 -315.824507) (xy 292.155118 -315.849762) (xy 292.155118 -315.85662)
			(xy 292.154864 -315.867034) (xy 292.16223 -315.88583) (xy 292.220396 -315.945266) (xy 292.22782 -315.952217)
			(xy 292.246557 -315.960081) (xy 292.256718 -315.960506) (xy 292.371272 -315.960506) (xy 292.381426 -315.960052)
			(xy 292.400148 -315.952186) (xy 292.407594 -315.945266) (xy 292.46576 -315.88583) (xy 292.473126 -315.867288)
			(xy 292.472872 -315.85662) (xy 292.472872 -315.849762) (xy 292.473376 -315.824074) (xy 292.481413 -315.773331)
			(xy 292.497289 -315.72447) (xy 292.520613 -315.678694) (xy 292.55081 -315.63713) (xy 292.587138 -315.600802)
			(xy 292.628702 -315.570605) (xy 292.674478 -315.547281) (xy 292.723339 -315.531405) (xy 292.774082 -315.523368)
			(xy 292.825458 -315.523368) (xy 292.876201 -315.531405) (xy 292.925062 -315.547281) (xy 292.970838 -315.570605)
			(xy 293.012402 -315.600802) (xy 293.04873 -315.63713) (xy 293.078927 -315.678694) (xy 293.102251 -315.72447)
			(xy 293.118127 -315.773331) (xy 293.126164 -315.824074) (xy 293.126668 -315.849762) (xy 293.126668 -315.85662)
			(xy 293.126414 -315.867288) (xy 293.13378 -315.88583) (xy 293.191946 -315.945266) (xy 293.199367 -315.952225)
			(xy 293.218104 -315.960107) (xy 293.228268 -315.960506) (xy 293.342822 -315.960506) (xy 293.35298 -315.960061)
			(xy 293.371716 -315.952208) (xy 293.379144 -315.945266) (xy 293.43731 -315.88583) (xy 293.444676 -315.867034)
			(xy 293.444422 -315.85662) (xy 293.444422 -315.849762) (xy 293.444944 -315.824507) (xy 293.453257 -315.774685)
			(xy 293.469658 -315.726911) (xy 293.493699 -315.682488) (xy 293.524723 -315.642628) (xy 293.561885 -315.608418)
			(xy 293.604171 -315.580792) (xy 293.650427 -315.560502) (xy 293.699392 -315.548102) (xy 293.74973 -315.543931)
			(xy 293.800068 -315.548102) (xy 293.849033 -315.560502) (xy 293.895289 -315.580792) (xy 293.937575 -315.608418)
			(xy 293.974737 -315.642628) (xy 294.005761 -315.682488) (xy 294.029802 -315.726911) (xy 294.046203 -315.774685)
			(xy 294.054516 -315.824507) (xy 294.055038 -315.849762) (xy 294.055038 -315.85662) (xy 294.054784 -315.867034)
			(xy 294.06215 -315.88583) (xy 294.120316 -315.945266) (xy 294.127741 -315.952214) (xy 294.146478 -315.960071)
			(xy 294.156638 -315.960506) (xy 294.271192 -315.960506) (xy 294.281352 -315.960067) (xy 294.300096 -315.952221)
			(xy 294.307514 -315.945266) (xy 294.36568 -315.88583) (xy 294.373046 -315.867288) (xy 294.372792 -315.85662)
			(xy 294.372792 -315.849762) (xy 294.373296 -315.824074) (xy 294.381333 -315.773331) (xy 294.397209 -315.72447)
			(xy 294.420533 -315.678694) (xy 294.45073 -315.63713) (xy 294.487058 -315.600802) (xy 294.528622 -315.570605)
			(xy 294.574398 -315.547281) (xy 294.623259 -315.531405) (xy 294.674002 -315.523368) (xy 294.725378 -315.523368)
			(xy 294.776121 -315.531405) (xy 294.824982 -315.547281) (xy 294.870758 -315.570605) (xy 294.912322 -315.600802)
			(xy 294.94865 -315.63713) (xy 294.978847 -315.678694) (xy 295.002171 -315.72447) (xy 295.018047 -315.773331)
			(xy 295.026084 -315.824074) (xy 295.026588 -315.849762) (xy 295.026588 -315.85662) (xy 295.026334 -315.867288)
			(xy 295.0337 -315.88583) (xy 295.091866 -315.945266) (xy 295.099288 -315.952222) (xy 295.118025 -315.960097)
			(xy 295.128188 -315.960506) (xy 295.242996 -315.960506) (xy 295.253156 -315.960066) (xy 295.271899 -315.952219)
			(xy 295.279318 -315.945266) (xy 295.337484 -315.88583) (xy 295.34485 -315.867034) (xy 295.344596 -315.85662)
			(xy 295.344596 -315.849762) (xy 295.345118 -315.824507) (xy 295.353431 -315.774685) (xy 295.369832 -315.726911)
			(xy 295.393873 -315.682488) (xy 295.424897 -315.642628) (xy 295.462059 -315.608418) (xy 295.504345 -315.580792)
			(xy 295.550601 -315.560502) (xy 295.599566 -315.548102) (xy 295.649904 -315.543931) (xy 295.700242 -315.548102)
			(xy 295.749207 -315.560502) (xy 295.795463 -315.580792) (xy 295.837749 -315.608418) (xy 295.874911 -315.642628)
			(xy 295.905935 -315.682488) (xy 295.929976 -315.726911) (xy 295.946377 -315.774685) (xy 295.95469 -315.824507)
			(xy 295.955212 -315.849762) (xy 295.955212 -315.85662) (xy 295.954958 -315.867034) (xy 295.962324 -315.88583)
			(xy 296.02049 -315.945266) (xy 296.027914 -315.952218) (xy 296.04665 -315.960085) (xy 296.056812 -315.960506)
			(xy 296.171366 -315.960506) (xy 296.18152 -315.960053) (xy 296.200245 -315.952188) (xy 296.207688 -315.945266)
			(xy 296.265854 -315.88583) (xy 296.27322 -315.867288) (xy 296.272966 -315.85662) (xy 296.272712 -315.849762)
			(xy 296.273216 -315.824054) (xy 296.281259 -315.773272) (xy 296.297147 -315.724373) (xy 296.32049 -315.678561)
			(xy 296.350711 -315.636965) (xy 296.387067 -315.600609) (xy 296.428663 -315.570388) (xy 296.474475 -315.547045)
			(xy 296.523374 -315.531157) (xy 296.574156 -315.523114) (xy 296.625572 -315.523114) (xy 296.676354 -315.531157)
			(xy 296.725253 -315.547045) (xy 296.771065 -315.570388) (xy 296.812661 -315.600609) (xy 296.849017 -315.636965)
			(xy 296.879238 -315.678561) (xy 296.902581 -315.724373) (xy 296.918469 -315.773272) (xy 296.926512 -315.824054)
			(xy 296.927016 -315.849762) (xy 296.926762 -315.85662) (xy 296.926508 -315.867288) (xy 296.933874 -315.88583)
			(xy 296.99204 -315.945266) (xy 296.999466 -315.95221) (xy 297.018203 -315.960058) (xy 297.028362 -315.960506)
			(xy 297.142916 -315.960506) (xy 297.153074 -315.960063) (xy 297.171812 -315.95221) (xy 297.179238 -315.945266)
			(xy 297.237404 -315.88583) (xy 297.24477 -315.867034) (xy 297.244516 -315.85662) (xy 297.244516 -315.849762)
			(xy 297.245038 -315.824507) (xy 297.253351 -315.774685) (xy 297.269752 -315.726911) (xy 297.293793 -315.682488)
			(xy 297.324817 -315.642628) (xy 297.361979 -315.608418) (xy 297.404265 -315.580792) (xy 297.450521 -315.560502)
			(xy 297.499486 -315.548102) (xy 297.549824 -315.543931) (xy 297.600162 -315.548102) (xy 297.649127 -315.560502)
			(xy 297.695383 -315.580792) (xy 297.737669 -315.608418) (xy 297.774831 -315.642628) (xy 297.805855 -315.682488)
			(xy 297.829896 -315.726911) (xy 297.846297 -315.774685) (xy 297.85461 -315.824507) (xy 297.855132 -315.849762)
			(xy 297.855132 -315.85662) (xy 297.854878 -315.867034) (xy 297.862244 -315.88583) (xy 297.92041 -315.945266)
			(xy 297.927835 -315.952215) (xy 297.946572 -315.960074) (xy 297.956732 -315.960506) (xy 298.071286 -315.960506)
			(xy 298.081438 -315.96005) (xy 298.100158 -315.95218) (xy 298.107608 -315.945266) (xy 298.165774 -315.88583)
			(xy 298.17314 -315.867288) (xy 298.172886 -315.85662) (xy 298.172632 -315.849762) (xy 298.173136 -315.824054)
			(xy 298.181179 -315.773272) (xy 298.197067 -315.724373) (xy 298.22041 -315.678561) (xy 298.250631 -315.636965)
			(xy 298.286987 -315.600609) (xy 298.328583 -315.570388) (xy 298.374395 -315.547045) (xy 298.423294 -315.531157)
			(xy 298.474076 -315.523114) (xy 298.525492 -315.523114) (xy 298.576274 -315.531157) (xy 298.625173 -315.547045)
			(xy 298.670985 -315.570388) (xy 298.712581 -315.600609) (xy 298.748937 -315.636965) (xy 298.779158 -315.678561)
			(xy 298.802501 -315.724373) (xy 298.818389 -315.773272) (xy 298.826432 -315.824054) (xy 298.826936 -315.849762)
			(xy 298.826682 -315.85662) (xy 298.826428 -315.867288) (xy 298.833794 -315.88583) (xy 298.89196 -315.945266)
			(xy 298.899382 -315.952223) (xy 298.918119 -315.9601) (xy 298.928282 -315.960506) (xy 299.042836 -315.960506)
			(xy 299.052993 -315.960059) (xy 299.071725 -315.952202) (xy 299.079158 -315.945266) (xy 299.137324 -315.88583)
			(xy 299.14469 -315.867034) (xy 299.144436 -315.85662) (xy 299.144436 -315.849762) (xy 299.144885 -315.825772)
			(xy 299.152397 -315.778384) (xy 299.167229 -315.732754) (xy 299.189017 -315.690006) (xy 299.217224 -315.651193)
			(xy 299.251156 -315.617271) (xy 299.289976 -315.589074) (xy 299.33273 -315.567298) (xy 299.378364 -315.552478)
			(xy 299.425754 -315.544979) (xy 299.449744 -315.544454) (xy 299.474619 -315.54494) (xy 299.523712 -315.552999)
			(xy 299.570848 -315.568912) (xy 299.61478 -315.592258) (xy 299.654344 -315.62242) (xy 299.688494 -315.658598)
			(xy 299.716325 -315.699836) (xy 299.727112 -315.722254) (xy 299.732446 -315.733684) (xy 299.752004 -315.748924)
			(xy 299.846492 -315.765688) (xy 299.858662 -315.767132) (xy 299.882022 -315.759843) (xy 299.891196 -315.751718)
			(xy 300.30166 -315.341254) (xy 300.309764 -315.332069) (xy 300.31704 -315.30872) (xy 300.31563 -315.29655)
			(xy 300.298866 -315.202062) (xy 300.283626 -315.182504) (xy 300.272196 -315.17717) (xy 300.249804 -315.166334)
			(xy 300.208577 -315.138502) (xy 300.172406 -315.104356) (xy 300.142245 -315.0648) (xy 300.118894 -315.020879)
			(xy 300.10297 -314.973755) (xy 300.094892 -314.924673) (xy 300.094396 -314.899802) (xy 300.094855 -314.875862)
			(xy 300.102313 -314.828566) (xy 300.117064 -314.783014) (xy 300.138744 -314.740323) (xy 300.166823 -314.70154)
			(xy 300.200612 -314.667616) (xy 300.239283 -314.639382) (xy 300.281887 -314.617532) (xy 300.327379 -314.6026)
			(xy 300.350936 -314.598304) (xy 300.369478 -314.59551) (xy 300.393608 -314.567062) (xy 300.393608 -314.282582)
			(xy 300.369478 -314.254134) (xy 300.350936 -314.25134) (xy 300.325999 -314.246777) (xy 300.277994 -314.230489)
			(xy 300.233337 -314.2065) (xy 300.193251 -314.175469) (xy 300.158838 -314.138247) (xy 300.131041 -314.095856)
			(xy 300.110622 -314.049458) (xy 300.098141 -314.000325) (xy 300.093942 -313.949807) (xy 300.098139 -313.899288)
			(xy 300.110617 -313.850155) (xy 300.131034 -313.803756) (xy 300.15883 -313.761363) (xy 300.193242 -313.72414)
			(xy 300.233325 -313.693107) (xy 300.277982 -313.669117) (xy 300.325986 -313.652826) (xy 300.350936 -313.648344)
			(xy 300.369478 -313.64555) (xy 300.393608 -313.617102) (xy 300.393608 -313.332622) (xy 300.369478 -313.304174)
			(xy 300.350936 -313.30138) (xy 300.326004 -313.296817) (xy 300.278009 -313.28053) (xy 300.233361 -313.256545)
			(xy 300.193285 -313.225519) (xy 300.158879 -313.188303) (xy 300.131088 -313.145919) (xy 300.110675 -313.099529)
			(xy 300.098198 -313.050406) (xy 300.094002 -312.999897) (xy 300.098199 -312.949388) (xy 300.110677 -312.900266)
			(xy 300.131091 -312.853876) (xy 300.158883 -312.811492) (xy 300.193289 -312.774277) (xy 300.233366 -312.743252)
			(xy 300.278015 -312.719268) (xy 300.326009 -312.702982) (xy 300.350936 -312.698384) (xy 300.369478 -312.69559)
			(xy 300.393608 -312.667142) (xy 300.393608 -312.404506) (xy 300.369224 -312.376058) (xy 300.350428 -312.373264)
			(xy 300.324984 -312.368895) (xy 300.275805 -312.353199) (xy 300.229701 -312.329973) (xy 300.187818 -312.299793)
			(xy 300.151196 -312.263409) (xy 300.120743 -312.221724) (xy 300.097217 -312.175773) (xy 300.0812 -312.126698)
			(xy 300.07309 -312.075715) (xy 300.07309 -312.024092) (xy 300.081198 -311.973109) (xy 300.097214 -311.924033)
			(xy 300.12074 -311.878081) (xy 300.151192 -311.836396) (xy 300.187813 -311.800011) (xy 300.229696 -311.769831)
			(xy 300.275798 -311.746604) (xy 300.324978 -311.730906) (xy 300.350428 -311.72658) (xy 300.369224 -311.723786)
			(xy 300.393608 -311.695338) (xy 300.393608 -311.454546) (xy 300.369224 -311.426098) (xy 300.350428 -311.423304)
			(xy 300.324989 -311.418935) (xy 300.275819 -311.403241) (xy 300.229724 -311.380017) (xy 300.18785 -311.349842)
			(xy 300.151235 -311.313464) (xy 300.120789 -311.271785) (xy 300.097268 -311.225842) (xy 300.081255 -311.176775)
			(xy 300.073149 -311.125801) (xy 300.07315 -311.074187) (xy 300.081258 -311.023214) (xy 300.097272 -310.974147)
			(xy 300.120795 -310.928205) (xy 300.151243 -310.886528) (xy 300.187859 -310.850151) (xy 300.229734 -310.819977)
			(xy 300.275829 -310.796755) (xy 300.325 -310.781062) (xy 300.350428 -310.77662) (xy 300.369224 -310.773826)
			(xy 300.393608 -310.745378) (xy 300.393608 -310.482488) (xy 300.369478 -310.45404) (xy 300.350936 -310.451246)
			(xy 300.325998 -310.446683) (xy 300.277993 -310.430394) (xy 300.233334 -310.406406) (xy 300.193248 -310.375374)
			(xy 300.158834 -310.338152) (xy 300.131036 -310.29576) (xy 300.110616 -310.24936) (xy 300.098136 -310.200227)
			(xy 300.093936 -310.149708) (xy 300.098133 -310.099188) (xy 300.110611 -310.050054) (xy 300.131028 -310.003654)
			(xy 300.158824 -309.96126) (xy 300.193237 -309.924036) (xy 300.233321 -309.893003) (xy 300.277979 -309.869012)
			(xy 300.325983 -309.852721) (xy 300.350936 -309.84825) (xy 300.369478 -309.845456) (xy 300.393608 -309.817008)
			(xy 300.393608 -305.11623) (xy 300.393173 -305.106165) (xy 300.385441 -305.087578) (xy 300.378622 -305.080162)
			(xy 300.052994 -304.754534) (xy 300.046158 -304.747132) (xy 300.038449 -304.728534) (xy 300.038008 -304.718466)
			(xy 300.038008 -304.7111) (xy 300.030388 -304.692558) (xy 300.013624 -304.675794) (xy 300.006221 -304.66896)
			(xy 299.987623 -304.661254) (xy 299.977556 -304.660808) (xy 282.247848 -304.660808) (xy 282.235199 -304.661472)
			(xy 282.21292 -304.673455) (xy 282.20543 -304.683668) (xy 282.151582 -304.76571) (xy 282.14955 -304.79111)
			(xy 282.15463 -304.803048) (xy 282.162654 -304.822317) (xy 282.173957 -304.862498) (xy 282.179681 -304.903844)
			(xy 282.18003 -304.924714) (xy 282.179508 -304.949969) (xy 282.171195 -304.999791) (xy 282.154794 -305.047565)
			(xy 282.130753 -305.091988) (xy 282.099729 -305.131848) (xy 282.062567 -305.166058) (xy 282.020281 -305.193684)
			(xy 281.974025 -305.213974) (xy 281.92506 -305.226374) (xy 281.874722 -305.230545) (xy 281.824384 -305.226374)
			(xy 281.775419 -305.213974) (xy 281.729163 -305.193684) (xy 281.686877 -305.166058) (xy 281.649715 -305.131848)
			(xy 281.618691 -305.091988) (xy 281.59465 -305.047565) (xy 281.578249 -304.999791) (xy 281.569936 -304.949969)
			(xy 281.569414 -304.924714) (xy 281.569774 -304.903845) (xy 281.575499 -304.862501) (xy 281.586803 -304.822322)
			(xy 281.594814 -304.803048) (xy 281.599894 -304.79111) (xy 281.597862 -304.76571) (xy 281.544014 -304.683668)
			(xy 281.536498 -304.67348) (xy 281.514238 -304.661488) (xy 281.501596 -304.660808) (xy 281.297888 -304.660808)
			(xy 281.285246 -304.661485) (xy 281.26299 -304.673483) (xy 281.25547 -304.683668) (xy 281.201622 -304.76571)
			(xy 281.19959 -304.79111) (xy 281.20467 -304.803048) (xy 281.212695 -304.822317) (xy 281.224 -304.862498)
			(xy 281.229725 -304.903844) (xy 281.23007 -304.924714) (xy 281.229548 -304.949969) (xy 281.221235 -304.999791)
			(xy 281.204834 -305.047565) (xy 281.180793 -305.091988) (xy 281.149769 -305.131848) (xy 281.112607 -305.166058)
			(xy 281.070321 -305.193684) (xy 281.024065 -305.213974) (xy 280.9751 -305.226374) (xy 280.924762 -305.230545)
			(xy 280.874424 -305.226374) (xy 280.825459 -305.213974) (xy 280.779203 -305.193684) (xy 280.736917 -305.166058)
			(xy 280.699755 -305.131848) (xy 280.668731 -305.091988) (xy 280.64469 -305.047565) (xy 280.628289 -304.999791)
			(xy 280.619976 -304.949969) (xy 280.619454 -304.924714) (xy 280.619814 -304.903845) (xy 280.62554 -304.862501)
			(xy 280.636846 -304.822323) (xy 280.644854 -304.803048) (xy 280.649934 -304.79111) (xy 280.647902 -304.76571)
			(xy 280.594054 -304.683668) (xy 280.586541 -304.673474) (xy 280.564282 -304.661464) (xy 280.551636 -304.660808)
			(xy 280.347928 -304.660808) (xy 280.335281 -304.661476) (xy 280.31301 -304.673465) (xy 280.30551 -304.683668)
			(xy 280.251662 -304.76571) (xy 280.24963 -304.79111) (xy 280.25471 -304.803048) (xy 280.262734 -304.822317)
			(xy 280.274038 -304.862498) (xy 280.279763 -304.903844) (xy 280.28011 -304.924714) (xy 280.279588 -304.949969)
			(xy 280.271275 -304.999791) (xy 280.254874 -305.047565) (xy 280.230833 -305.091988) (xy 280.199809 -305.131848)
			(xy 280.162647 -305.166058) (xy 280.120361 -305.193684) (xy 280.074105 -305.213974) (xy 280.02514 -305.226374)
			(xy 279.974802 -305.230545) (xy 279.924464 -305.226374) (xy 279.875499 -305.213974) (xy 279.829243 -305.193684)
			(xy 279.786957 -305.166058) (xy 279.749795 -305.131848) (xy 279.718771 -305.091988) (xy 279.69473 -305.047565)
			(xy 279.678329 -304.999791) (xy 279.670016 -304.949969) (xy 279.669494 -304.924714) (xy 279.669854 -304.903845)
			(xy 279.675578 -304.862501) (xy 279.686882 -304.822321) (xy 279.694894 -304.803048) (xy 279.699974 -304.79111)
			(xy 279.697942 -304.76571) (xy 279.644094 -304.683668) (xy 279.636576 -304.673484) (xy 279.614317 -304.6615)
			(xy 279.601676 -304.660808) (xy 279.59304 -304.660808) (xy 279.582974 -304.660374) (xy 279.564385 -304.652646)
			(xy 279.556972 -304.645822) (xy 279.173432 -304.262282) (xy 279.14473 -304.255932) (xy 279.130506 -304.261266)
			(xy 279.104977 -304.270045) (xy 279.051832 -304.279502) (xy 279.024842 -304.280062) (xy 279.000848 -304.279619)
			(xy 278.95345 -304.272117) (xy 278.90781 -304.257292) (xy 278.865051 -304.235508) (xy 278.826228 -304.207302)
			(xy 278.792295 -304.173369) (xy 278.76409 -304.134545) (xy 278.742307 -304.091787) (xy 278.727482 -304.046146)
			(xy 278.719981 -303.998748) (xy 278.719534 -303.974754) (xy 278.719974 -303.951108) (xy 278.727261 -303.904382)
			(xy 278.741669 -303.859339) (xy 278.762854 -303.817057) (xy 278.790307 -303.77855) (xy 278.823372 -303.74474)
			(xy 278.861258 -303.716434) (xy 278.903056 -303.694312) (xy 278.925274 -303.68621) (xy 278.940768 -303.680876)
			(xy 278.959564 -303.65446) (xy 278.959564 -303.345088) (xy 278.940768 -303.318672) (xy 278.925274 -303.313338)
			(xy 278.901603 -303.304624) (xy 278.857275 -303.280563) (xy 278.817506 -303.249541) (xy 278.783379 -303.212403)
			(xy 278.755821 -303.17016) (xy 278.735583 -303.123961) (xy 278.723216 -303.075063) (xy 278.719056 -303.024798)
			(xy 278.723217 -302.974533) (xy 278.735585 -302.925635) (xy 278.755823 -302.879437) (xy 278.783381 -302.837194)
			(xy 278.817509 -302.800056) (xy 278.857278 -302.769035) (xy 278.901607 -302.744974) (xy 278.925274 -302.73625)
			(xy 278.940768 -302.730916) (xy 278.959564 -302.7045) (xy 278.959564 -302.311054) (xy 278.959132 -302.300988)
			(xy 278.951402 -302.282399) (xy 278.944578 -302.274986) (xy 278.560022 -301.89043) (xy 278.552621 -301.883593)
			(xy 278.534022 -301.875882) (xy 278.523954 -301.875444) (xy 277.731728 -301.875444) (xy 277.722076 -301.879762)
			(xy 277.702726 -301.887808) (xy 277.662375 -301.899124) (xy 277.620856 -301.904814) (xy 277.599902 -301.905162)
			(xy 277.578947 -301.904836) (xy 277.537425 -301.899144) (xy 277.497073 -301.887825) (xy 277.477728 -301.879762)
			(xy 277.468076 -301.875444) (xy 276.781514 -301.875444) (xy 276.771862 -301.879762) (xy 276.752513 -301.887814)
			(xy 276.712163 -301.899141) (xy 276.670643 -301.904843) (xy 276.649688 -301.905162) (xy 276.628733 -301.904835)
			(xy 276.587212 -301.899141) (xy 276.54686 -301.88782) (xy 276.527514 -301.879762) (xy 276.517862 -301.875444)
			(xy 275.831554 -301.875444) (xy 275.821902 -301.879762) (xy 275.802552 -301.88781) (xy 275.762202 -301.899129)
			(xy 275.720682 -301.904823) (xy 275.699728 -301.905162) (xy 275.678774 -301.904831) (xy 275.637256 -301.899129)
			(xy 275.596908 -301.887802) (xy 275.577554 -301.879762) (xy 275.567902 -301.875444) (xy 274.940014 -301.875444)
			(xy 274.933346 -301.875636) (xy 274.920469 -301.879105) (xy 274.914614 -301.882302) (xy 274.889415 -301.896281)
			(xy 274.835317 -301.916116) (xy 274.778579 -301.92616) (xy 274.749768 -301.926752) (xy 274.720957 -301.926168)
			(xy 274.664217 -301.916122) (xy 274.610114 -301.896293) (xy 274.584922 -301.882302) (xy 274.579043 -301.879166)
			(xy 274.566181 -301.875704) (xy 274.559522 -301.875444) (xy 273.990054 -301.875444) (xy 273.983388 -301.875644)
			(xy 273.970519 -301.879126) (xy 273.964654 -301.882302) (xy 273.939456 -301.896284) (xy 273.885358 -301.916126)
			(xy 273.828619 -301.926177) (xy 273.799808 -301.926752) (xy 273.770998 -301.926163) (xy 273.714263 -301.916107)
			(xy 273.660166 -301.896271) (xy 273.634962 -301.882302) (xy 273.629084 -301.879161) (xy 273.616222 -301.87569)
			(xy 273.609562 -301.875444) (xy 272.981674 -301.875444) (xy 272.972022 -301.879762) (xy 272.952672 -301.887811)
			(xy 272.912322 -301.899133) (xy 272.870803 -301.90483) (xy 272.849848 -301.905162) (xy 272.828893 -301.904832)
			(xy 272.787374 -301.899133) (xy 272.747025 -301.887808) (xy 272.727674 -301.879762) (xy 272.718022 -301.875444)
			(xy 272.090134 -301.875444) (xy 272.083465 -301.875633) (xy 272.070585 -301.879098) (xy 272.064734 -301.882302)
			(xy 272.039536 -301.896283) (xy 271.985437 -301.916121) (xy 271.928699 -301.926168) (xy 271.899888 -301.926752)
			(xy 271.871079 -301.926161) (xy 271.814345 -301.916102) (xy 271.76025 -301.896263) (xy 271.735042 -301.882302)
			(xy 271.729164 -301.879163) (xy 271.716301 -301.875697) (xy 271.709642 -301.875444) (xy 271.140174 -301.875444)
			(xy 271.133507 -301.875641) (xy 271.120635 -301.879119) (xy 271.114774 -301.882302) (xy 271.089576 -301.896286)
			(xy 271.035479 -301.916131) (xy 270.97874 -301.926185) (xy 270.949928 -301.926752) (xy 270.921118 -301.926164)
			(xy 270.864381 -301.916112) (xy 270.810282 -301.896278) (xy 270.785082 -301.882302) (xy 270.779205 -301.879159)
			(xy 270.766343 -301.875682) (xy 270.759682 -301.875444) (xy 270.13154 -301.875444) (xy 270.121888 -301.879762)
			(xy 270.102538 -301.887809) (xy 270.062187 -301.899126) (xy 270.020668 -301.904818) (xy 269.999714 -301.905162)
			(xy 269.97876 -301.90483) (xy 269.937242 -301.899126) (xy 269.896895 -301.887797) (xy 269.87754 -301.879762)
			(xy 269.867888 -301.875444) (xy 269.18158 -301.875444) (xy 269.171928 -301.879762) (xy 269.152578 -301.887812)
			(xy 269.112228 -301.899134) (xy 269.070709 -301.904832) (xy 269.049754 -301.905162) (xy 269.028799 -301.904833)
			(xy 268.98728 -301.899134) (xy 268.94693 -301.88781) (xy 268.92758 -301.879762) (xy 268.917928 -301.875444)
			(xy 267.74013 -301.875444) (xy 267.730067 -301.875007) (xy 267.711486 -301.867268) (xy 267.704062 -301.860458)
			(xy 267.12164 -301.278036) (xy 267.114799 -301.270636) (xy 267.107082 -301.252037) (xy 267.106654 -301.241968)
			(xy 267.106654 -300.809914) (xy 267.107094 -300.799852) (xy 267.114837 -300.781275) (xy 267.12164 -300.773846)
			(xy 267.126466 -300.76902) (xy 267.126466 -287.396428) (xy 267.126029 -287.386364) (xy 267.118292 -287.367782)
			(xy 267.11148 -287.36036) (xy 266.757658 -287.006538) (xy 266.750151 -286.999678) (xy 266.731334 -286.992014)
			(xy 266.711016 -286.992226) (xy 266.701524 -286.99587) (xy 266.600432 -287.039558) (xy 266.583668 -287.065974)
			(xy 266.584176 -287.081722) (xy 266.58443 -287.093914) (xy 266.583966 -287.121169) (xy 266.576207 -287.175123)
			(xy 266.560848 -287.227423) (xy 266.538202 -287.277006) (xy 266.50873 -287.32286) (xy 266.473033 -287.364054)
			(xy 266.431836 -287.399749) (xy 266.385979 -287.429217) (xy 266.336394 -287.451858) (xy 266.284093 -287.467213)
			(xy 266.230138 -287.474968) (xy 266.175629 -287.474966) (xy 266.121675 -287.467206) (xy 266.069374 -287.451847)
			(xy 266.019792 -287.429201) (xy 265.973937 -287.399729) (xy 265.932744 -287.364031) (xy 265.89705 -287.322834)
			(xy 265.867582 -287.276976) (xy 265.844941 -287.227392) (xy 265.829586 -287.17509) (xy 265.821832 -287.121135)
			(xy 265.821834 -287.066626) (xy 265.829595 -287.012672) (xy 265.844954 -286.960372) (xy 265.867601 -286.91079)
			(xy 265.897073 -286.864935) (xy 265.932771 -286.823742) (xy 265.973968 -286.788048) (xy 266.019826 -286.758581)
			(xy 266.069411 -286.73594) (xy 266.121713 -286.720586) (xy 266.175667 -286.712831) (xy 266.202922 -286.712406)
			(xy 266.215114 -286.71266) (xy 266.230862 -286.713168) (xy 266.257278 -286.696404) (xy 266.300966 -286.595312)
			(xy 266.304635 -286.585817) (xy 266.304898 -286.56548) (xy 266.297207 -286.546652) (xy 266.290298 -286.539178)
			(xy 266.094464 -286.343344) (xy 266.087066 -286.336499) (xy 266.068467 -286.32877) (xy 266.058396 -286.328358)
			(xy 264.341102 -286.328358) (xy 264.312146 -286.354012) (xy 264.310114 -286.37357) (xy 264.306837 -286.399262)
			(xy 264.294234 -286.449498) (xy 264.274955 -286.497569) (xy 264.249353 -286.542592) (xy 264.217898 -286.58374)
			(xy 264.181169 -286.620257) (xy 264.160762 -286.636206) (xy 264.151364 -286.643572) (xy 264.14095 -286.664146)
			(xy 264.139426 -286.768032) (xy 264.149332 -286.789114) (xy 264.158476 -286.79648) (xy 264.1803 -286.814711)
			(xy 264.218829 -286.856533) (xy 264.25073 -286.903606) (xy 264.275297 -286.954889) (xy 264.291988 -287.009248)
			(xy 264.300433 -287.065482) (xy 264.30097 -287.093914) (xy 264.934444 -287.093914) (xy 264.938515 -287.038292)
			(xy 264.950641 -286.983855) (xy 264.970564 -286.931764) (xy 264.99786 -286.883129) (xy 265.031946 -286.838986)
			(xy 265.072095 -286.800277) (xy 265.117453 -286.767826) (xy 265.167053 -286.742325) (xy 265.219837 -286.724318)
			(xy 265.27468 -286.714188) (xy 265.330414 -286.712151) (xy 265.385851 -286.718251) (xy 265.439808 -286.732357)
			(xy 265.491137 -286.754169) (xy 265.538743 -286.783223) (xy 265.581611 -286.818898) (xy 265.618828 -286.860435)
			(xy 265.649601 -286.906948) (xy 265.673273 -286.957445) (xy 265.689341 -287.010852) (xy 265.697461 -287.066028)
			(xy 265.69797 -287.093914) (xy 265.697461 -287.1218) (xy 265.689341 -287.176976) (xy 265.673273 -287.230383)
			(xy 265.649601 -287.28088) (xy 265.618828 -287.327393) (xy 265.581611 -287.36893) (xy 265.538743 -287.404605)
			(xy 265.491137 -287.433659) (xy 265.439808 -287.455471) (xy 265.385851 -287.469577) (xy 265.330414 -287.475677)
			(xy 265.27468 -287.47364) (xy 265.219837 -287.46351) (xy 265.167053 -287.445503) (xy 265.117453 -287.420002)
			(xy 265.072095 -287.387551) (xy 265.031946 -287.348842) (xy 264.99786 -287.304699) (xy 264.970564 -287.256064)
			(xy 264.950641 -287.203973) (xy 264.938515 -287.149536) (xy 264.934444 -287.093914) (xy 264.30097 -287.093914)
			(xy 264.300484 -287.121165) (xy 264.292728 -287.175113) (xy 264.277373 -287.227408) (xy 264.254731 -287.276985)
			(xy 264.225265 -287.322835) (xy 264.189574 -287.364026) (xy 264.148383 -287.399717) (xy 264.102533 -287.429183)
			(xy 264.052956 -287.451825) (xy 264.000661 -287.46718) (xy 263.946713 -287.474936) (xy 263.892211 -287.474936)
			(xy 263.838263 -287.46718) (xy 263.785968 -287.451825) (xy 263.736391 -287.429183) (xy 263.690541 -287.399717)
			(xy 263.64935 -287.364026) (xy 263.613659 -287.322835) (xy 263.584193 -287.276985) (xy 263.561551 -287.227408)
			(xy 263.546196 -287.175113) (xy 263.53844 -287.121165) (xy 263.537954 -287.093914) (xy 263.538517 -287.064534)
			(xy 263.547564 -287.006475) (xy 263.565401 -286.950487) (xy 263.591607 -286.897894) (xy 263.625563 -286.849937)
			(xy 263.666466 -286.807751) (xy 263.689592 -286.789622) (xy 263.69899 -286.782256) (xy 263.709404 -286.761682)
			(xy 263.710928 -286.657796) (xy 263.701022 -286.636714) (xy 263.691878 -286.629348) (xy 263.668874 -286.610161)
			(xy 263.628611 -286.565809) (xy 263.595782 -286.515705) (xy 263.571195 -286.461082) (xy 263.555457 -286.403285)
			(xy 263.55167 -286.37357) (xy 263.549638 -286.354012) (xy 263.520682 -286.328358) (xy 261.168134 -286.328358)
			(xy 261.139178 -286.354012) (xy 261.137146 -286.37357) (xy 261.133619 -286.401241) (xy 261.119519 -286.45521)
			(xy 261.09771 -286.506551) (xy 261.068658 -286.554169) (xy 261.032981 -286.597049) (xy 260.991441 -286.634277)
			(xy 260.944922 -286.665058) (xy 260.894416 -286.688737) (xy 260.841001 -286.70481) (xy 260.785814 -286.712933)
			(xy 260.730034 -286.712933) (xy 260.674847 -286.70481) (xy 260.621432 -286.688737) (xy 260.570926 -286.665058)
			(xy 260.524407 -286.634277) (xy 260.482867 -286.597049) (xy 260.44719 -286.554169) (xy 260.418138 -286.506551)
			(xy 260.396329 -286.45521) (xy 260.382229 -286.401241) (xy 260.378702 -286.37357) (xy 260.37667 -286.354012)
			(xy 260.347714 -286.328358) (xy 260.279134 -286.328358) (xy 260.250178 -286.354012) (xy 260.248146 -286.37357)
			(xy 260.244619 -286.401241) (xy 260.230519 -286.45521) (xy 260.20871 -286.506551) (xy 260.179658 -286.554169)
			(xy 260.143981 -286.597049) (xy 260.102441 -286.634277) (xy 260.055922 -286.665058) (xy 260.005416 -286.688737)
			(xy 259.952001 -286.70481) (xy 259.896814 -286.712933) (xy 259.841034 -286.712933) (xy 259.785847 -286.70481)
			(xy 259.732432 -286.688737) (xy 259.681926 -286.665058) (xy 259.635407 -286.634277) (xy 259.593867 -286.597049)
			(xy 259.55819 -286.554169) (xy 259.529138 -286.506551) (xy 259.507329 -286.45521) (xy 259.493229 -286.401241)
			(xy 259.489702 -286.37357) (xy 259.48767 -286.354012) (xy 259.458714 -286.328358) (xy 258.803648 -286.328358)
			(xy 258.774692 -286.354012) (xy 258.77266 -286.37357) (xy 258.769133 -286.401241) (xy 258.755033 -286.45521)
			(xy 258.733224 -286.506551) (xy 258.704172 -286.554169) (xy 258.668495 -286.597049) (xy 258.626955 -286.634277)
			(xy 258.580436 -286.665058) (xy 258.52993 -286.688737) (xy 258.476515 -286.70481) (xy 258.421328 -286.712933)
			(xy 258.365548 -286.712933) (xy 258.310361 -286.70481) (xy 258.256946 -286.688737) (xy 258.20644 -286.665058)
			(xy 258.159921 -286.634277) (xy 258.118381 -286.597049) (xy 258.082704 -286.554169) (xy 258.053652 -286.506551)
			(xy 258.031843 -286.45521) (xy 258.017743 -286.401241) (xy 258.014216 -286.37357) (xy 258.012184 -286.354012)
			(xy 257.983228 -286.328358) (xy 249.62485 -286.328358) (xy 249.614785 -286.328792) (xy 249.596199 -286.336525)
			(xy 249.588782 -286.343344) (xy 249.085354 -286.846772) (xy 249.078513 -286.854172) (xy 249.070796 -286.872771)
			(xy 249.070368 -286.88284) (xy 249.070368 -288.230056) (xy 258.01142 -288.230056) (xy 258.015491 -288.174434)
			(xy 258.027617 -288.119997) (xy 258.04754 -288.067906) (xy 258.074836 -288.019271) (xy 258.108922 -287.975128)
			(xy 258.149071 -287.936419) (xy 258.194429 -287.903968) (xy 258.244029 -287.878467) (xy 258.296813 -287.86046)
			(xy 258.351656 -287.85033) (xy 258.40739 -287.848293) (xy 258.462827 -287.854393) (xy 258.516784 -287.868499)
			(xy 258.568113 -287.890311) (xy 258.615719 -287.919365) (xy 258.658587 -287.95504) (xy 258.695804 -287.996577)
			(xy 258.726577 -288.04309) (xy 258.750249 -288.093587) (xy 258.766317 -288.146994) (xy 258.774437 -288.20217)
			(xy 258.774946 -288.230056) (xy 259.496558 -288.230056) (xy 259.500629 -288.174434) (xy 259.512755 -288.119997)
			(xy 259.532678 -288.067906) (xy 259.559974 -288.019271) (xy 259.59406 -287.975128) (xy 259.634209 -287.936419)
			(xy 259.679567 -287.903968) (xy 259.729167 -287.878467) (xy 259.781951 -287.86046) (xy 259.836794 -287.85033)
			(xy 259.892528 -287.848293) (xy 259.947965 -287.854393) (xy 260.001922 -287.868499) (xy 260.053251 -287.890311)
			(xy 260.100857 -287.919365) (xy 260.143725 -287.95504) (xy 260.180942 -287.996577) (xy 260.211715 -288.04309)
			(xy 260.235387 -288.093587) (xy 260.251455 -288.146994) (xy 260.259575 -288.20217) (xy 260.260084 -288.230056)
			(xy 260.259575 -288.257942) (xy 260.251455 -288.313118) (xy 260.235387 -288.366525) (xy 260.211715 -288.417022)
			(xy 260.180942 -288.463535) (xy 260.143725 -288.505072) (xy 260.100857 -288.540747) (xy 260.053251 -288.569801)
			(xy 260.001922 -288.591613) (xy 259.947965 -288.605719) (xy 259.892528 -288.611819) (xy 259.836794 -288.609782)
			(xy 259.781951 -288.599652) (xy 259.729167 -288.581645) (xy 259.679567 -288.556144) (xy 259.634209 -288.523693)
			(xy 259.59406 -288.484984) (xy 259.559974 -288.440841) (xy 259.532678 -288.392206) (xy 259.512755 -288.340115)
			(xy 259.500629 -288.285678) (xy 259.496558 -288.230056) (xy 258.774946 -288.230056) (xy 258.774437 -288.257942)
			(xy 258.766317 -288.313118) (xy 258.750249 -288.366525) (xy 258.726577 -288.417022) (xy 258.695804 -288.463535)
			(xy 258.658587 -288.505072) (xy 258.615719 -288.540747) (xy 258.568113 -288.569801) (xy 258.516784 -288.591613)
			(xy 258.462827 -288.605719) (xy 258.40739 -288.611819) (xy 258.351656 -288.609782) (xy 258.296813 -288.599652)
			(xy 258.244029 -288.581645) (xy 258.194429 -288.556144) (xy 258.149071 -288.523693) (xy 258.108922 -288.484984)
			(xy 258.074836 -288.440841) (xy 258.04754 -288.392206) (xy 258.027617 -288.340115) (xy 258.015491 -288.285678)
			(xy 258.01142 -288.230056) (xy 249.070368 -288.230056) (xy 249.070368 -289.532314) (xy 258.01142 -289.532314)
			(xy 258.015491 -289.476692) (xy 258.027617 -289.422255) (xy 258.04754 -289.370164) (xy 258.074836 -289.321529)
			(xy 258.108922 -289.277386) (xy 258.149071 -289.238677) (xy 258.194429 -289.206226) (xy 258.244029 -289.180725)
			(xy 258.296813 -289.162718) (xy 258.351656 -289.152588) (xy 258.40739 -289.150551) (xy 258.462827 -289.156651)
			(xy 258.516784 -289.170757) (xy 258.568113 -289.192569) (xy 258.615719 -289.221623) (xy 258.658587 -289.257298)
			(xy 258.695804 -289.298835) (xy 258.726577 -289.345348) (xy 258.750249 -289.395845) (xy 258.766317 -289.449252)
			(xy 258.774437 -289.504428) (xy 258.774946 -289.532314) (xy 259.486906 -289.532314) (xy 259.490977 -289.476692)
			(xy 259.503103 -289.422255) (xy 259.523026 -289.370164) (xy 259.550322 -289.321529) (xy 259.584408 -289.277386)
			(xy 259.624557 -289.238677) (xy 259.669915 -289.206226) (xy 259.719515 -289.180725) (xy 259.772299 -289.162718)
			(xy 259.827142 -289.152588) (xy 259.882876 -289.150551) (xy 259.938313 -289.156651) (xy 259.99227 -289.170757)
			(xy 260.043599 -289.192569) (xy 260.091205 -289.221623) (xy 260.134073 -289.257298) (xy 260.17129 -289.298835)
			(xy 260.202063 -289.345348) (xy 260.225735 -289.395845) (xy 260.241803 -289.449252) (xy 260.249923 -289.504428)
			(xy 260.250432 -289.532314) (xy 260.375906 -289.532314) (xy 260.379977 -289.476692) (xy 260.392103 -289.422255)
			(xy 260.412026 -289.370164) (xy 260.439322 -289.321529) (xy 260.473408 -289.277386) (xy 260.513557 -289.238677)
			(xy 260.558915 -289.206226) (xy 260.608515 -289.180725) (xy 260.661299 -289.162718) (xy 260.716142 -289.152588)
			(xy 260.771876 -289.150551) (xy 260.827313 -289.156651) (xy 260.88127 -289.170757) (xy 260.932599 -289.192569)
			(xy 260.980205 -289.221623) (xy 261.023073 -289.257298) (xy 261.06029 -289.298835) (xy 261.091063 -289.345348)
			(xy 261.114735 -289.395845) (xy 261.130803 -289.449252) (xy 261.138923 -289.504428) (xy 261.139432 -289.532314)
			(xy 261.138923 -289.5602) (xy 261.130803 -289.615376) (xy 261.114735 -289.668783) (xy 261.091063 -289.71928)
			(xy 261.06029 -289.765793) (xy 261.023073 -289.80733) (xy 260.980205 -289.843005) (xy 260.932599 -289.872059)
			(xy 260.88127 -289.893871) (xy 260.827313 -289.907977) (xy 260.771876 -289.914077) (xy 260.716142 -289.91204)
			(xy 260.661299 -289.90191) (xy 260.608515 -289.883903) (xy 260.558915 -289.858402) (xy 260.513557 -289.825951)
			(xy 260.473408 -289.787242) (xy 260.439322 -289.743099) (xy 260.412026 -289.694464) (xy 260.392103 -289.642373)
			(xy 260.379977 -289.587936) (xy 260.375906 -289.532314) (xy 260.250432 -289.532314) (xy 260.249923 -289.5602)
			(xy 260.241803 -289.615376) (xy 260.225735 -289.668783) (xy 260.202063 -289.71928) (xy 260.17129 -289.765793)
			(xy 260.134073 -289.80733) (xy 260.091205 -289.843005) (xy 260.043599 -289.872059) (xy 259.99227 -289.893871)
			(xy 259.938313 -289.907977) (xy 259.882876 -289.914077) (xy 259.827142 -289.91204) (xy 259.772299 -289.90191)
			(xy 259.719515 -289.883903) (xy 259.669915 -289.858402) (xy 259.624557 -289.825951) (xy 259.584408 -289.787242)
			(xy 259.550322 -289.743099) (xy 259.523026 -289.694464) (xy 259.503103 -289.642373) (xy 259.490977 -289.587936)
			(xy 259.486906 -289.532314) (xy 258.774946 -289.532314) (xy 258.774437 -289.5602) (xy 258.766317 -289.615376)
			(xy 258.750249 -289.668783) (xy 258.726577 -289.71928) (xy 258.695804 -289.765793) (xy 258.658587 -289.80733)
			(xy 258.615719 -289.843005) (xy 258.568113 -289.872059) (xy 258.516784 -289.893871) (xy 258.462827 -289.907977)
			(xy 258.40739 -289.914077) (xy 258.351656 -289.91204) (xy 258.296813 -289.90191) (xy 258.244029 -289.883903)
			(xy 258.194429 -289.858402) (xy 258.149071 -289.825951) (xy 258.108922 -289.787242) (xy 258.074836 -289.743099)
			(xy 258.04754 -289.694464) (xy 258.027617 -289.642373) (xy 258.015491 -289.587936) (xy 258.01142 -289.532314)
			(xy 249.070368 -289.532314) (xy 249.070368 -290.294314) (xy 263.537954 -290.294314) (xy 263.53852 -290.264933)
			(xy 263.547548 -290.206868) (xy 263.565376 -290.150875) (xy 263.591583 -290.09828) (xy 263.625547 -290.050328)
			(xy 263.666466 -290.008154) (xy 263.689592 -289.990022) (xy 263.69899 -289.982656) (xy 263.709404 -289.962082)
			(xy 263.710928 -289.858196) (xy 263.701022 -289.837114) (xy 263.691878 -289.829748) (xy 263.670018 -289.811556)
			(xy 263.63148 -289.769733) (xy 263.599575 -289.722655) (xy 263.57501 -289.671363) (xy 263.558329 -289.616993)
			(xy 263.549902 -289.56075) (xy 263.549384 -289.532314) (xy 263.54987 -289.505063) (xy 263.557626 -289.451115)
			(xy 263.572981 -289.39882) (xy 263.595623 -289.349243) (xy 263.625089 -289.303393) (xy 263.66078 -289.262202)
			(xy 263.701971 -289.226511) (xy 263.747821 -289.197045) (xy 263.797398 -289.174403) (xy 263.849693 -289.159048)
			(xy 263.903641 -289.151292) (xy 263.958143 -289.151292) (xy 264.012091 -289.159048) (xy 264.064386 -289.174403)
			(xy 264.113963 -289.197045) (xy 264.159813 -289.226511) (xy 264.201004 -289.262202) (xy 264.236695 -289.303393)
			(xy 264.266161 -289.349243) (xy 264.288803 -289.39882) (xy 264.304158 -289.451115) (xy 264.311914 -289.505063)
			(xy 264.3124 -289.532314) (xy 264.311872 -289.561697) (xy 264.302839 -289.619764) (xy 264.285005 -289.675759)
			(xy 264.258791 -289.728354) (xy 264.224818 -289.776305) (xy 264.183891 -289.818476) (xy 264.160762 -289.836606)
			(xy 264.151364 -289.843972) (xy 264.14095 -289.864546) (xy 264.139426 -289.968432) (xy 264.149332 -289.989514)
			(xy 264.158476 -289.99688) (xy 264.180292 -290.015123) (xy 264.218835 -290.056933) (xy 264.250747 -290.104001)
			(xy 264.275319 -290.155284) (xy 264.292009 -290.209645) (xy 264.300447 -290.265881) (xy 264.30097 -290.294314)
			(xy 264.934444 -290.294314) (xy 264.938515 -290.238692) (xy 264.950641 -290.184255) (xy 264.970564 -290.132164)
			(xy 264.99786 -290.083529) (xy 265.031946 -290.039386) (xy 265.072095 -290.000677) (xy 265.117453 -289.968226)
			(xy 265.167053 -289.942725) (xy 265.219837 -289.924718) (xy 265.27468 -289.914588) (xy 265.330414 -289.912551)
			(xy 265.385851 -289.918651) (xy 265.439808 -289.932757) (xy 265.491137 -289.954569) (xy 265.538743 -289.983623)
			(xy 265.581611 -290.019298) (xy 265.618828 -290.060835) (xy 265.649601 -290.107348) (xy 265.673273 -290.157845)
			(xy 265.689341 -290.211252) (xy 265.697461 -290.266428) (xy 265.69797 -290.294314) (xy 265.820904 -290.294314)
			(xy 265.824975 -290.238692) (xy 265.837101 -290.184255) (xy 265.857024 -290.132164) (xy 265.88432 -290.083529)
			(xy 265.918406 -290.039386) (xy 265.958555 -290.000677) (xy 266.003913 -289.968226) (xy 266.053513 -289.942725)
			(xy 266.106297 -289.924718) (xy 266.16114 -289.914588) (xy 266.216874 -289.912551) (xy 266.272311 -289.918651)
			(xy 266.326268 -289.932757) (xy 266.377597 -289.954569) (xy 266.425203 -289.983623) (xy 266.468071 -290.019298)
			(xy 266.505288 -290.060835) (xy 266.536061 -290.107348) (xy 266.559733 -290.157845) (xy 266.575801 -290.211252)
			(xy 266.583921 -290.266428) (xy 266.58443 -290.294314) (xy 266.583921 -290.3222) (xy 266.575801 -290.377376)
			(xy 266.559733 -290.430783) (xy 266.536061 -290.48128) (xy 266.505288 -290.527793) (xy 266.468071 -290.56933)
			(xy 266.425203 -290.605005) (xy 266.377597 -290.634059) (xy 266.326268 -290.655871) (xy 266.272311 -290.669977)
			(xy 266.216874 -290.676077) (xy 266.16114 -290.67404) (xy 266.106297 -290.66391) (xy 266.053513 -290.645903)
			(xy 266.003913 -290.620402) (xy 265.958555 -290.587951) (xy 265.918406 -290.549242) (xy 265.88432 -290.505099)
			(xy 265.857024 -290.456464) (xy 265.837101 -290.404373) (xy 265.824975 -290.349936) (xy 265.820904 -290.294314)
			(xy 265.69797 -290.294314) (xy 265.697461 -290.3222) (xy 265.689341 -290.377376) (xy 265.673273 -290.430783)
			(xy 265.649601 -290.48128) (xy 265.618828 -290.527793) (xy 265.581611 -290.56933) (xy 265.538743 -290.605005)
			(xy 265.491137 -290.634059) (xy 265.439808 -290.655871) (xy 265.385851 -290.669977) (xy 265.330414 -290.676077)
			(xy 265.27468 -290.67404) (xy 265.219837 -290.66391) (xy 265.167053 -290.645903) (xy 265.117453 -290.620402)
			(xy 265.072095 -290.587951) (xy 265.031946 -290.549242) (xy 264.99786 -290.505099) (xy 264.970564 -290.456464)
			(xy 264.950641 -290.404373) (xy 264.938515 -290.349936) (xy 264.934444 -290.294314) (xy 264.30097 -290.294314)
			(xy 264.300484 -290.321565) (xy 264.292728 -290.375513) (xy 264.277373 -290.427808) (xy 264.254731 -290.477385)
			(xy 264.225265 -290.523235) (xy 264.189574 -290.564426) (xy 264.148383 -290.600117) (xy 264.102533 -290.629583)
			(xy 264.052956 -290.652225) (xy 264.000661 -290.66758) (xy 263.946713 -290.675336) (xy 263.892211 -290.675336)
			(xy 263.838263 -290.66758) (xy 263.785968 -290.652225) (xy 263.736391 -290.629583) (xy 263.690541 -290.600117)
			(xy 263.64935 -290.564426) (xy 263.613659 -290.523235) (xy 263.584193 -290.477385) (xy 263.561551 -290.427808)
			(xy 263.546196 -290.375513) (xy 263.53844 -290.321565) (xy 263.537954 -290.294314) (xy 249.070368 -290.294314)
			(xy 249.070368 -291.430456) (xy 258.01142 -291.430456) (xy 258.015491 -291.374834) (xy 258.027617 -291.320397)
			(xy 258.04754 -291.268306) (xy 258.074836 -291.219671) (xy 258.108922 -291.175528) (xy 258.149071 -291.136819)
			(xy 258.194429 -291.104368) (xy 258.244029 -291.078867) (xy 258.296813 -291.06086) (xy 258.351656 -291.05073)
			(xy 258.40739 -291.048693) (xy 258.462827 -291.054793) (xy 258.516784 -291.068899) (xy 258.568113 -291.090711)
			(xy 258.615719 -291.119765) (xy 258.658587 -291.15544) (xy 258.695804 -291.196977) (xy 258.726577 -291.24349)
			(xy 258.750249 -291.293987) (xy 258.766317 -291.347394) (xy 258.774437 -291.40257) (xy 258.774946 -291.430456)
			(xy 259.496558 -291.430456) (xy 259.500629 -291.374834) (xy 259.512755 -291.320397) (xy 259.532678 -291.268306)
			(xy 259.559974 -291.219671) (xy 259.59406 -291.175528) (xy 259.634209 -291.136819) (xy 259.679567 -291.104368)
			(xy 259.729167 -291.078867) (xy 259.781951 -291.06086) (xy 259.836794 -291.05073) (xy 259.892528 -291.048693)
			(xy 259.947965 -291.054793) (xy 260.001922 -291.068899) (xy 260.053251 -291.090711) (xy 260.100857 -291.119765)
			(xy 260.143725 -291.15544) (xy 260.180942 -291.196977) (xy 260.211715 -291.24349) (xy 260.235387 -291.293987)
			(xy 260.251455 -291.347394) (xy 260.259575 -291.40257) (xy 260.260084 -291.430456) (xy 260.259575 -291.458342)
			(xy 260.251455 -291.513518) (xy 260.235387 -291.566925) (xy 260.211715 -291.617422) (xy 260.180942 -291.663935)
			(xy 260.143725 -291.705472) (xy 260.100857 -291.741147) (xy 260.053251 -291.770201) (xy 260.001922 -291.792013)
			(xy 259.947965 -291.806119) (xy 259.892528 -291.812219) (xy 259.836794 -291.810182) (xy 259.781951 -291.800052)
			(xy 259.729167 -291.782045) (xy 259.679567 -291.756544) (xy 259.634209 -291.724093) (xy 259.59406 -291.685384)
			(xy 259.559974 -291.641241) (xy 259.532678 -291.592606) (xy 259.512755 -291.540515) (xy 259.500629 -291.486078)
			(xy 259.496558 -291.430456) (xy 258.774946 -291.430456) (xy 258.774437 -291.458342) (xy 258.766317 -291.513518)
			(xy 258.750249 -291.566925) (xy 258.726577 -291.617422) (xy 258.695804 -291.663935) (xy 258.658587 -291.705472)
			(xy 258.615719 -291.741147) (xy 258.568113 -291.770201) (xy 258.516784 -291.792013) (xy 258.462827 -291.806119)
			(xy 258.40739 -291.812219) (xy 258.351656 -291.810182) (xy 258.296813 -291.800052) (xy 258.244029 -291.782045)
			(xy 258.194429 -291.756544) (xy 258.149071 -291.724093) (xy 258.108922 -291.685384) (xy 258.074836 -291.641241)
			(xy 258.04754 -291.592606) (xy 258.027617 -291.540515) (xy 258.015491 -291.486078) (xy 258.01142 -291.430456)
			(xy 249.070368 -291.430456) (xy 249.070368 -292.732714) (xy 258.01142 -292.732714) (xy 258.015491 -292.677092)
			(xy 258.027617 -292.622655) (xy 258.04754 -292.570564) (xy 258.074836 -292.521929) (xy 258.108922 -292.477786)
			(xy 258.149071 -292.439077) (xy 258.194429 -292.406626) (xy 258.244029 -292.381125) (xy 258.296813 -292.363118)
			(xy 258.351656 -292.352988) (xy 258.40739 -292.350951) (xy 258.462827 -292.357051) (xy 258.516784 -292.371157)
			(xy 258.568113 -292.392969) (xy 258.615719 -292.422023) (xy 258.658587 -292.457698) (xy 258.695804 -292.499235)
			(xy 258.726577 -292.545748) (xy 258.750249 -292.596245) (xy 258.766317 -292.649652) (xy 258.774437 -292.704828)
			(xy 258.774946 -292.732714) (xy 259.486906 -292.732714) (xy 259.490977 -292.677092) (xy 259.503103 -292.622655)
			(xy 259.523026 -292.570564) (xy 259.550322 -292.521929) (xy 259.584408 -292.477786) (xy 259.624557 -292.439077)
			(xy 259.669915 -292.406626) (xy 259.719515 -292.381125) (xy 259.772299 -292.363118) (xy 259.827142 -292.352988)
			(xy 259.882876 -292.350951) (xy 259.938313 -292.357051) (xy 259.99227 -292.371157) (xy 260.043599 -292.392969)
			(xy 260.091205 -292.422023) (xy 260.134073 -292.457698) (xy 260.17129 -292.499235) (xy 260.202063 -292.545748)
			(xy 260.225735 -292.596245) (xy 260.241803 -292.649652) (xy 260.249923 -292.704828) (xy 260.250432 -292.732714)
			(xy 260.375906 -292.732714) (xy 260.379977 -292.677092) (xy 260.392103 -292.622655) (xy 260.412026 -292.570564)
			(xy 260.439322 -292.521929) (xy 260.473408 -292.477786) (xy 260.513557 -292.439077) (xy 260.558915 -292.406626)
			(xy 260.608515 -292.381125) (xy 260.661299 -292.363118) (xy 260.716142 -292.352988) (xy 260.771876 -292.350951)
			(xy 260.827313 -292.357051) (xy 260.88127 -292.371157) (xy 260.932599 -292.392969) (xy 260.980205 -292.422023)
			(xy 261.023073 -292.457698) (xy 261.06029 -292.499235) (xy 261.091063 -292.545748) (xy 261.114735 -292.596245)
			(xy 261.130803 -292.649652) (xy 261.138923 -292.704828) (xy 261.139432 -292.732714) (xy 261.138923 -292.7606)
			(xy 261.130803 -292.815776) (xy 261.114735 -292.869183) (xy 261.091063 -292.91968) (xy 261.06029 -292.966193)
			(xy 261.023073 -293.00773) (xy 260.980205 -293.043405) (xy 260.932599 -293.072459) (xy 260.88127 -293.094271)
			(xy 260.827313 -293.108377) (xy 260.771876 -293.114477) (xy 260.716142 -293.11244) (xy 260.661299 -293.10231)
			(xy 260.608515 -293.084303) (xy 260.558915 -293.058802) (xy 260.513557 -293.026351) (xy 260.473408 -292.987642)
			(xy 260.439322 -292.943499) (xy 260.412026 -292.894864) (xy 260.392103 -292.842773) (xy 260.379977 -292.788336)
			(xy 260.375906 -292.732714) (xy 260.250432 -292.732714) (xy 260.249923 -292.7606) (xy 260.241803 -292.815776)
			(xy 260.225735 -292.869183) (xy 260.202063 -292.91968) (xy 260.17129 -292.966193) (xy 260.134073 -293.00773)
			(xy 260.091205 -293.043405) (xy 260.043599 -293.072459) (xy 259.99227 -293.094271) (xy 259.938313 -293.108377)
			(xy 259.882876 -293.114477) (xy 259.827142 -293.11244) (xy 259.772299 -293.10231) (xy 259.719515 -293.084303)
			(xy 259.669915 -293.058802) (xy 259.624557 -293.026351) (xy 259.584408 -292.987642) (xy 259.550322 -292.943499)
			(xy 259.523026 -292.894864) (xy 259.503103 -292.842773) (xy 259.490977 -292.788336) (xy 259.486906 -292.732714)
			(xy 258.774946 -292.732714) (xy 258.774437 -292.7606) (xy 258.766317 -292.815776) (xy 258.750249 -292.869183)
			(xy 258.726577 -292.91968) (xy 258.695804 -292.966193) (xy 258.658587 -293.00773) (xy 258.615719 -293.043405)
			(xy 258.568113 -293.072459) (xy 258.516784 -293.094271) (xy 258.462827 -293.108377) (xy 258.40739 -293.114477)
			(xy 258.351656 -293.11244) (xy 258.296813 -293.10231) (xy 258.244029 -293.084303) (xy 258.194429 -293.058802)
			(xy 258.149071 -293.026351) (xy 258.108922 -292.987642) (xy 258.074836 -292.943499) (xy 258.04754 -292.894864)
			(xy 258.027617 -292.842773) (xy 258.015491 -292.788336) (xy 258.01142 -292.732714) (xy 249.070368 -292.732714)
			(xy 249.070368 -293.300404) (xy 249.070791 -293.310475) (xy 249.078503 -293.329081) (xy 249.085354 -293.336472)
			(xy 249.243596 -293.494714) (xy 263.537954 -293.494714) (xy 263.53852 -293.465333) (xy 263.547548 -293.407268)
			(xy 263.565376 -293.351275) (xy 263.591583 -293.29868) (xy 263.625547 -293.250728) (xy 263.666466 -293.208554)
			(xy 263.689592 -293.190422) (xy 263.69899 -293.183056) (xy 263.709404 -293.162482) (xy 263.710928 -293.058596)
			(xy 263.701022 -293.037514) (xy 263.691878 -293.030148) (xy 263.670018 -293.011956) (xy 263.63148 -292.970133)
			(xy 263.599575 -292.923055) (xy 263.57501 -292.871763) (xy 263.558329 -292.817393) (xy 263.549902 -292.76115)
			(xy 263.549384 -292.732714) (xy 263.54987 -292.705463) (xy 263.557626 -292.651515) (xy 263.572981 -292.59922)
			(xy 263.595623 -292.549643) (xy 263.625089 -292.503793) (xy 263.66078 -292.462602) (xy 263.701971 -292.426911)
			(xy 263.747821 -292.397445) (xy 263.797398 -292.374803) (xy 263.849693 -292.359448) (xy 263.903641 -292.351692)
			(xy 263.958143 -292.351692) (xy 264.012091 -292.359448) (xy 264.064386 -292.374803) (xy 264.113963 -292.397445)
			(xy 264.159813 -292.426911) (xy 264.201004 -292.462602) (xy 264.236695 -292.503793) (xy 264.266161 -292.549643)
			(xy 264.288803 -292.59922) (xy 264.304158 -292.651515) (xy 264.311914 -292.705463) (xy 264.3124 -292.732714)
			(xy 264.311872 -292.762097) (xy 264.302839 -292.820164) (xy 264.285005 -292.876159) (xy 264.258791 -292.928754)
			(xy 264.224818 -292.976705) (xy 264.183891 -293.018876) (xy 264.160762 -293.037006) (xy 264.151364 -293.044372)
			(xy 264.14095 -293.064946) (xy 264.139426 -293.168832) (xy 264.149332 -293.189914) (xy 264.158476 -293.19728)
			(xy 264.180292 -293.215523) (xy 264.218835 -293.257333) (xy 264.250747 -293.304401) (xy 264.275319 -293.355684)
			(xy 264.292009 -293.410045) (xy 264.300447 -293.466281) (xy 264.30097 -293.494714) (xy 264.934444 -293.494714)
			(xy 264.938515 -293.439092) (xy 264.950641 -293.384655) (xy 264.970564 -293.332564) (xy 264.99786 -293.283929)
			(xy 265.031946 -293.239786) (xy 265.072095 -293.201077) (xy 265.117453 -293.168626) (xy 265.167053 -293.143125)
			(xy 265.219837 -293.125118) (xy 265.27468 -293.114988) (xy 265.330414 -293.112951) (xy 265.385851 -293.119051)
			(xy 265.439808 -293.133157) (xy 265.491137 -293.154969) (xy 265.538743 -293.184023) (xy 265.581611 -293.219698)
			(xy 265.618828 -293.261235) (xy 265.649601 -293.307748) (xy 265.673273 -293.358245) (xy 265.689341 -293.411652)
			(xy 265.697461 -293.466828) (xy 265.69797 -293.494714) (xy 265.820904 -293.494714) (xy 265.824975 -293.439092)
			(xy 265.837101 -293.384655) (xy 265.857024 -293.332564) (xy 265.88432 -293.283929) (xy 265.918406 -293.239786)
			(xy 265.958555 -293.201077) (xy 266.003913 -293.168626) (xy 266.053513 -293.143125) (xy 266.106297 -293.125118)
			(xy 266.16114 -293.114988) (xy 266.216874 -293.112951) (xy 266.272311 -293.119051) (xy 266.326268 -293.133157)
			(xy 266.377597 -293.154969) (xy 266.425203 -293.184023) (xy 266.468071 -293.219698) (xy 266.505288 -293.261235)
			(xy 266.536061 -293.307748) (xy 266.559733 -293.358245) (xy 266.575801 -293.411652) (xy 266.583921 -293.466828)
			(xy 266.58443 -293.494714) (xy 266.583921 -293.5226) (xy 266.575801 -293.577776) (xy 266.559733 -293.631183)
			(xy 266.536061 -293.68168) (xy 266.505288 -293.728193) (xy 266.468071 -293.76973) (xy 266.425203 -293.805405)
			(xy 266.377597 -293.834459) (xy 266.326268 -293.856271) (xy 266.272311 -293.870377) (xy 266.216874 -293.876477)
			(xy 266.16114 -293.87444) (xy 266.106297 -293.86431) (xy 266.053513 -293.846303) (xy 266.003913 -293.820802)
			(xy 265.958555 -293.788351) (xy 265.918406 -293.749642) (xy 265.88432 -293.705499) (xy 265.857024 -293.656864)
			(xy 265.837101 -293.604773) (xy 265.824975 -293.550336) (xy 265.820904 -293.494714) (xy 265.69797 -293.494714)
			(xy 265.697461 -293.5226) (xy 265.689341 -293.577776) (xy 265.673273 -293.631183) (xy 265.649601 -293.68168)
			(xy 265.618828 -293.728193) (xy 265.581611 -293.76973) (xy 265.538743 -293.805405) (xy 265.491137 -293.834459)
			(xy 265.439808 -293.856271) (xy 265.385851 -293.870377) (xy 265.330414 -293.876477) (xy 265.27468 -293.87444)
			(xy 265.219837 -293.86431) (xy 265.167053 -293.846303) (xy 265.117453 -293.820802) (xy 265.072095 -293.788351)
			(xy 265.031946 -293.749642) (xy 264.99786 -293.705499) (xy 264.970564 -293.656864) (xy 264.950641 -293.604773)
			(xy 264.938515 -293.550336) (xy 264.934444 -293.494714) (xy 264.30097 -293.494714) (xy 264.300484 -293.521965)
			(xy 264.292728 -293.575913) (xy 264.277373 -293.628208) (xy 264.254731 -293.677785) (xy 264.225265 -293.723635)
			(xy 264.189574 -293.764826) (xy 264.148383 -293.800517) (xy 264.102533 -293.829983) (xy 264.052956 -293.852625)
			(xy 264.000661 -293.86798) (xy 263.946713 -293.875736) (xy 263.892211 -293.875736) (xy 263.838263 -293.86798)
			(xy 263.785968 -293.852625) (xy 263.736391 -293.829983) (xy 263.690541 -293.800517) (xy 263.64935 -293.764826)
			(xy 263.613659 -293.723635) (xy 263.584193 -293.677785) (xy 263.561551 -293.628208) (xy 263.546196 -293.575913)
			(xy 263.53844 -293.521965) (xy 263.537954 -293.494714) (xy 249.243596 -293.494714) (xy 249.805952 -294.05707)
			(xy 249.813352 -294.063911) (xy 249.83195 -294.071632) (xy 249.84202 -294.072056) (xy 251.615702 -294.072056)
			(xy 251.621036 -294.070786) (xy 251.710857 -294.051577) (xy 251.892121 -294.021763) (xy 252.074737 -294.001847)
			(xy 252.258166 -293.991888) (xy 252.350016 -293.991284) (xy 252.441865 -293.991896) (xy 252.625294 -294.001863)
			(xy 252.80791 -294.021778) (xy 252.989174 -294.051583) (xy 253.078996 -294.070786) (xy 253.08433 -294.072056)
			(xy 254.067056 -294.072056) (xy 254.07712 -294.072491) (xy 254.095705 -294.080226) (xy 254.103124 -294.087042)
			(xy 254.646938 -294.630856) (xy 258.01142 -294.630856) (xy 258.015491 -294.575234) (xy 258.027617 -294.520797)
			(xy 258.04754 -294.468706) (xy 258.074836 -294.420071) (xy 258.108922 -294.375928) (xy 258.149071 -294.337219)
			(xy 258.194429 -294.304768) (xy 258.244029 -294.279267) (xy 258.296813 -294.26126) (xy 258.351656 -294.25113)
			(xy 258.40739 -294.249093) (xy 258.462827 -294.255193) (xy 258.516784 -294.269299) (xy 258.568113 -294.291111)
			(xy 258.615719 -294.320165) (xy 258.658587 -294.35584) (xy 258.695804 -294.397377) (xy 258.726577 -294.44389)
			(xy 258.750249 -294.494387) (xy 258.766317 -294.547794) (xy 258.774437 -294.60297) (xy 258.774946 -294.630856)
			(xy 259.496558 -294.630856) (xy 259.500629 -294.575234) (xy 259.512755 -294.520797) (xy 259.532678 -294.468706)
			(xy 259.559974 -294.420071) (xy 259.59406 -294.375928) (xy 259.634209 -294.337219) (xy 259.679567 -294.304768)
			(xy 259.729167 -294.279267) (xy 259.781951 -294.26126) (xy 259.836794 -294.25113) (xy 259.892528 -294.249093)
			(xy 259.947965 -294.255193) (xy 260.001922 -294.269299) (xy 260.053251 -294.291111) (xy 260.100857 -294.320165)
			(xy 260.143725 -294.35584) (xy 260.180942 -294.397377) (xy 260.211715 -294.44389) (xy 260.235387 -294.494387)
			(xy 260.251455 -294.547794) (xy 260.259575 -294.60297) (xy 260.260084 -294.630856) (xy 260.259575 -294.658742)
			(xy 260.251455 -294.713918) (xy 260.235387 -294.767325) (xy 260.211715 -294.817822) (xy 260.180942 -294.864335)
			(xy 260.143725 -294.905872) (xy 260.100857 -294.941547) (xy 260.053251 -294.970601) (xy 260.001922 -294.992413)
			(xy 259.947965 -295.006519) (xy 259.892528 -295.012619) (xy 259.836794 -295.010582) (xy 259.781951 -295.000452)
			(xy 259.729167 -294.982445) (xy 259.679567 -294.956944) (xy 259.634209 -294.924493) (xy 259.59406 -294.885784)
			(xy 259.559974 -294.841641) (xy 259.532678 -294.793006) (xy 259.512755 -294.740915) (xy 259.500629 -294.686478)
			(xy 259.496558 -294.630856) (xy 258.774946 -294.630856) (xy 258.774437 -294.658742) (xy 258.766317 -294.713918)
			(xy 258.750249 -294.767325) (xy 258.726577 -294.817822) (xy 258.695804 -294.864335) (xy 258.658587 -294.905872)
			(xy 258.615719 -294.941547) (xy 258.568113 -294.970601) (xy 258.516784 -294.992413) (xy 258.462827 -295.006519)
			(xy 258.40739 -295.012619) (xy 258.351656 -295.010582) (xy 258.296813 -295.000452) (xy 258.244029 -294.982445)
			(xy 258.194429 -294.956944) (xy 258.149071 -294.924493) (xy 258.108922 -294.885784) (xy 258.074836 -294.841641)
			(xy 258.04754 -294.793006) (xy 258.027617 -294.740915) (xy 258.015491 -294.686478) (xy 258.01142 -294.630856)
			(xy 254.646938 -294.630856) (xy 255.930146 -295.914064) (xy 255.936988 -295.921463) (xy 255.941824 -295.933114)
			(xy 258.01142 -295.933114) (xy 258.015491 -295.877492) (xy 258.027617 -295.823055) (xy 258.04754 -295.770964)
			(xy 258.074836 -295.722329) (xy 258.108922 -295.678186) (xy 258.149071 -295.639477) (xy 258.194429 -295.607026)
			(xy 258.244029 -295.581525) (xy 258.296813 -295.563518) (xy 258.351656 -295.553388) (xy 258.40739 -295.551351)
			(xy 258.462827 -295.557451) (xy 258.516784 -295.571557) (xy 258.568113 -295.593369) (xy 258.615719 -295.622423)
			(xy 258.658587 -295.658098) (xy 258.695804 -295.699635) (xy 258.726577 -295.746148) (xy 258.750249 -295.796645)
			(xy 258.766317 -295.850052) (xy 258.774437 -295.905228) (xy 258.774946 -295.933114) (xy 259.486906 -295.933114)
			(xy 259.490977 -295.877492) (xy 259.503103 -295.823055) (xy 259.523026 -295.770964) (xy 259.550322 -295.722329)
			(xy 259.584408 -295.678186) (xy 259.624557 -295.639477) (xy 259.669915 -295.607026) (xy 259.719515 -295.581525)
			(xy 259.772299 -295.563518) (xy 259.827142 -295.553388) (xy 259.882876 -295.551351) (xy 259.938313 -295.557451)
			(xy 259.99227 -295.571557) (xy 260.043599 -295.593369) (xy 260.091205 -295.622423) (xy 260.134073 -295.658098)
			(xy 260.17129 -295.699635) (xy 260.202063 -295.746148) (xy 260.225735 -295.796645) (xy 260.241803 -295.850052)
			(xy 260.249923 -295.905228) (xy 260.250432 -295.933114) (xy 260.375906 -295.933114) (xy 260.379977 -295.877492)
			(xy 260.392103 -295.823055) (xy 260.412026 -295.770964) (xy 260.439322 -295.722329) (xy 260.473408 -295.678186)
			(xy 260.513557 -295.639477) (xy 260.558915 -295.607026) (xy 260.608515 -295.581525) (xy 260.661299 -295.563518)
			(xy 260.716142 -295.553388) (xy 260.771876 -295.551351) (xy 260.827313 -295.557451) (xy 260.88127 -295.571557)
			(xy 260.932599 -295.593369) (xy 260.980205 -295.622423) (xy 261.023073 -295.658098) (xy 261.06029 -295.699635)
			(xy 261.091063 -295.746148) (xy 261.114735 -295.796645) (xy 261.130803 -295.850052) (xy 261.138923 -295.905228)
			(xy 261.139432 -295.933114) (xy 261.138923 -295.961) (xy 261.130803 -296.016176) (xy 261.114735 -296.069583)
			(xy 261.091063 -296.12008) (xy 261.06029 -296.166593) (xy 261.023073 -296.20813) (xy 260.980205 -296.243805)
			(xy 260.932599 -296.272859) (xy 260.88127 -296.294671) (xy 260.827313 -296.308777) (xy 260.771876 -296.314877)
			(xy 260.716142 -296.31284) (xy 260.661299 -296.30271) (xy 260.608515 -296.284703) (xy 260.558915 -296.259202)
			(xy 260.513557 -296.226751) (xy 260.473408 -296.188042) (xy 260.439322 -296.143899) (xy 260.412026 -296.095264)
			(xy 260.392103 -296.043173) (xy 260.379977 -295.988736) (xy 260.375906 -295.933114) (xy 260.250432 -295.933114)
			(xy 260.249923 -295.961) (xy 260.241803 -296.016176) (xy 260.225735 -296.069583) (xy 260.202063 -296.12008)
			(xy 260.17129 -296.166593) (xy 260.134073 -296.20813) (xy 260.091205 -296.243805) (xy 260.043599 -296.272859)
			(xy 259.99227 -296.294671) (xy 259.938313 -296.308777) (xy 259.882876 -296.314877) (xy 259.827142 -296.31284)
			(xy 259.772299 -296.30271) (xy 259.719515 -296.284703) (xy 259.669915 -296.259202) (xy 259.624557 -296.226751)
			(xy 259.584408 -296.188042) (xy 259.550322 -296.143899) (xy 259.523026 -296.095264) (xy 259.503103 -296.043173)
			(xy 259.490977 -295.988736) (xy 259.486906 -295.933114) (xy 258.774946 -295.933114) (xy 258.774437 -295.961)
			(xy 258.766317 -296.016176) (xy 258.750249 -296.069583) (xy 258.726577 -296.12008) (xy 258.695804 -296.166593)
			(xy 258.658587 -296.20813) (xy 258.615719 -296.243805) (xy 258.568113 -296.272859) (xy 258.516784 -296.294671)
			(xy 258.462827 -296.308777) (xy 258.40739 -296.314877) (xy 258.351656 -296.31284) (xy 258.296813 -296.30271)
			(xy 258.244029 -296.284703) (xy 258.194429 -296.259202) (xy 258.149071 -296.226751) (xy 258.108922 -296.188042)
			(xy 258.074836 -296.143899) (xy 258.04754 -296.095264) (xy 258.027617 -296.043173) (xy 258.015491 -295.988736)
			(xy 258.01142 -295.933114) (xy 255.941824 -295.933114) (xy 255.944708 -295.940062) (xy 255.945132 -295.950132)
			(xy 255.945132 -296.695114) (xy 263.537954 -296.695114) (xy 263.53852 -296.665733) (xy 263.547548 -296.607668)
			(xy 263.565376 -296.551675) (xy 263.591583 -296.49908) (xy 263.625547 -296.451128) (xy 263.666466 -296.408954)
			(xy 263.689592 -296.390822) (xy 263.69899 -296.383456) (xy 263.709404 -296.362882) (xy 263.710928 -296.258996)
			(xy 263.701022 -296.237914) (xy 263.691878 -296.230548) (xy 263.670018 -296.212356) (xy 263.63148 -296.170533)
			(xy 263.599575 -296.123455) (xy 263.57501 -296.072163) (xy 263.558329 -296.017793) (xy 263.549902 -295.96155)
			(xy 263.549384 -295.933114) (xy 263.54987 -295.905863) (xy 263.557626 -295.851915) (xy 263.572981 -295.79962)
			(xy 263.595623 -295.750043) (xy 263.625089 -295.704193) (xy 263.66078 -295.663002) (xy 263.701971 -295.627311)
			(xy 263.747821 -295.597845) (xy 263.797398 -295.575203) (xy 263.849693 -295.559848) (xy 263.903641 -295.552092)
			(xy 263.958143 -295.552092) (xy 264.012091 -295.559848) (xy 264.064386 -295.575203) (xy 264.113963 -295.597845)
			(xy 264.159813 -295.627311) (xy 264.201004 -295.663002) (xy 264.236695 -295.704193) (xy 264.266161 -295.750043)
			(xy 264.288803 -295.79962) (xy 264.304158 -295.851915) (xy 264.311914 -295.905863) (xy 264.3124 -295.933114)
			(xy 264.311872 -295.962497) (xy 264.302839 -296.020564) (xy 264.285005 -296.076559) (xy 264.258791 -296.129154)
			(xy 264.224818 -296.177105) (xy 264.183891 -296.219276) (xy 264.160762 -296.237406) (xy 264.151364 -296.244772)
			(xy 264.14095 -296.265346) (xy 264.139426 -296.369232) (xy 264.149332 -296.390314) (xy 264.158476 -296.39768)
			(xy 264.180292 -296.415923) (xy 264.218835 -296.457733) (xy 264.250747 -296.504801) (xy 264.275319 -296.556084)
			(xy 264.292009 -296.610445) (xy 264.300447 -296.666681) (xy 264.30097 -296.695114) (xy 264.934444 -296.695114)
			(xy 264.938515 -296.639492) (xy 264.950641 -296.585055) (xy 264.970564 -296.532964) (xy 264.99786 -296.484329)
			(xy 265.031946 -296.440186) (xy 265.072095 -296.401477) (xy 265.117453 -296.369026) (xy 265.167053 -296.343525)
			(xy 265.219837 -296.325518) (xy 265.27468 -296.315388) (xy 265.330414 -296.313351) (xy 265.385851 -296.319451)
			(xy 265.439808 -296.333557) (xy 265.491137 -296.355369) (xy 265.538743 -296.384423) (xy 265.581611 -296.420098)
			(xy 265.618828 -296.461635) (xy 265.649601 -296.508148) (xy 265.673273 -296.558645) (xy 265.689341 -296.612052)
			(xy 265.697461 -296.667228) (xy 265.69797 -296.695114) (xy 265.820904 -296.695114) (xy 265.824975 -296.639492)
			(xy 265.837101 -296.585055) (xy 265.857024 -296.532964) (xy 265.88432 -296.484329) (xy 265.918406 -296.440186)
			(xy 265.958555 -296.401477) (xy 266.003913 -296.369026) (xy 266.053513 -296.343525) (xy 266.106297 -296.325518)
			(xy 266.16114 -296.315388) (xy 266.216874 -296.313351) (xy 266.272311 -296.319451) (xy 266.326268 -296.333557)
			(xy 266.377597 -296.355369) (xy 266.425203 -296.384423) (xy 266.468071 -296.420098) (xy 266.505288 -296.461635)
			(xy 266.536061 -296.508148) (xy 266.559733 -296.558645) (xy 266.575801 -296.612052) (xy 266.583921 -296.667228)
			(xy 266.58443 -296.695114) (xy 266.583921 -296.723) (xy 266.575801 -296.778176) (xy 266.559733 -296.831583)
			(xy 266.536061 -296.88208) (xy 266.505288 -296.928593) (xy 266.468071 -296.97013) (xy 266.425203 -297.005805)
			(xy 266.377597 -297.034859) (xy 266.326268 -297.056671) (xy 266.272311 -297.070777) (xy 266.216874 -297.076877)
			(xy 266.16114 -297.07484) (xy 266.106297 -297.06471) (xy 266.053513 -297.046703) (xy 266.003913 -297.021202)
			(xy 265.958555 -296.988751) (xy 265.918406 -296.950042) (xy 265.88432 -296.905899) (xy 265.857024 -296.857264)
			(xy 265.837101 -296.805173) (xy 265.824975 -296.750736) (xy 265.820904 -296.695114) (xy 265.69797 -296.695114)
			(xy 265.697461 -296.723) (xy 265.689341 -296.778176) (xy 265.673273 -296.831583) (xy 265.649601 -296.88208)
			(xy 265.618828 -296.928593) (xy 265.581611 -296.97013) (xy 265.538743 -297.005805) (xy 265.491137 -297.034859)
			(xy 265.439808 -297.056671) (xy 265.385851 -297.070777) (xy 265.330414 -297.076877) (xy 265.27468 -297.07484)
			(xy 265.219837 -297.06471) (xy 265.167053 -297.046703) (xy 265.117453 -297.021202) (xy 265.072095 -296.988751)
			(xy 265.031946 -296.950042) (xy 264.99786 -296.905899) (xy 264.970564 -296.857264) (xy 264.950641 -296.805173)
			(xy 264.938515 -296.750736) (xy 264.934444 -296.695114) (xy 264.30097 -296.695114) (xy 264.300484 -296.722365)
			(xy 264.292728 -296.776313) (xy 264.277373 -296.828608) (xy 264.254731 -296.878185) (xy 264.225265 -296.924035)
			(xy 264.189574 -296.965226) (xy 264.148383 -297.000917) (xy 264.102533 -297.030383) (xy 264.052956 -297.053025)
			(xy 264.000661 -297.06838) (xy 263.946713 -297.076136) (xy 263.892211 -297.076136) (xy 263.838263 -297.06838)
			(xy 263.785968 -297.053025) (xy 263.736391 -297.030383) (xy 263.690541 -297.000917) (xy 263.64935 -296.965226)
			(xy 263.613659 -296.924035) (xy 263.584193 -296.878185) (xy 263.561551 -296.828608) (xy 263.546196 -296.776313)
			(xy 263.53844 -296.722365) (xy 263.537954 -296.695114) (xy 255.945132 -296.695114) (xy 255.945132 -297.831256)
			(xy 258.01142 -297.831256) (xy 258.015491 -297.775634) (xy 258.027617 -297.721197) (xy 258.04754 -297.669106)
			(xy 258.074836 -297.620471) (xy 258.108922 -297.576328) (xy 258.149071 -297.537619) (xy 258.194429 -297.505168)
			(xy 258.244029 -297.479667) (xy 258.296813 -297.46166) (xy 258.351656 -297.45153) (xy 258.40739 -297.449493)
			(xy 258.462827 -297.455593) (xy 258.516784 -297.469699) (xy 258.568113 -297.491511) (xy 258.615719 -297.520565)
			(xy 258.658587 -297.55624) (xy 258.695804 -297.597777) (xy 258.726577 -297.64429) (xy 258.750249 -297.694787)
			(xy 258.766317 -297.748194) (xy 258.774437 -297.80337) (xy 258.774946 -297.831256) (xy 258.774437 -297.859142)
			(xy 258.766317 -297.914318) (xy 258.750249 -297.967725) (xy 258.726577 -298.018222) (xy 258.695804 -298.064735)
			(xy 258.658587 -298.106272) (xy 258.615719 -298.141947) (xy 258.568113 -298.171001) (xy 258.516784 -298.192813)
			(xy 258.462827 -298.206919) (xy 258.40739 -298.213019) (xy 258.351656 -298.210982) (xy 258.296813 -298.200852)
			(xy 258.244029 -298.182845) (xy 258.194429 -298.157344) (xy 258.149071 -298.124893) (xy 258.108922 -298.086184)
			(xy 258.074836 -298.042041) (xy 258.04754 -297.993406) (xy 258.027617 -297.941315) (xy 258.015491 -297.886878)
			(xy 258.01142 -297.831256) (xy 255.945132 -297.831256) (xy 255.945132 -299.133514) (xy 258.01142 -299.133514)
			(xy 258.015491 -299.077892) (xy 258.027617 -299.023455) (xy 258.04754 -298.971364) (xy 258.074836 -298.922729)
			(xy 258.108922 -298.878586) (xy 258.149071 -298.839877) (xy 258.194429 -298.807426) (xy 258.244029 -298.781925)
			(xy 258.296813 -298.763918) (xy 258.351656 -298.753788) (xy 258.40739 -298.751751) (xy 258.462827 -298.757851)
			(xy 258.516784 -298.771957) (xy 258.568113 -298.793769) (xy 258.615719 -298.822823) (xy 258.658587 -298.858498)
			(xy 258.695804 -298.900035) (xy 258.726577 -298.946548) (xy 258.750249 -298.997045) (xy 258.766317 -299.050452)
			(xy 258.774437 -299.105628) (xy 258.774946 -299.133514) (xy 259.487416 -299.133514) (xy 259.487921 -299.105172)
			(xy 259.496306 -299.049112) (xy 259.512894 -298.994909) (xy 259.53732 -298.943758) (xy 259.569045 -298.896784)
			(xy 259.607372 -298.855021) (xy 259.651457 -298.819389) (xy 259.67563 -298.804584) (xy 259.68821 -298.796603)
			(xy 259.708492 -298.774803) (xy 259.721622 -298.748078) (xy 259.726483 -298.718702) (xy 259.722662 -298.689172)
			(xy 259.710483 -298.662001) (xy 259.690983 -298.639499) (xy 259.678678 -298.631102) (xy 259.655814 -298.615989)
			(xy 259.614221 -298.580303) (xy 259.578163 -298.539032) (xy 259.548382 -298.493025) (xy 259.525492 -298.44323)
			(xy 259.509964 -298.390672) (xy 259.502116 -298.336432) (xy 259.50164 -298.30903) (xy 259.502126 -298.281779)
			(xy 259.509882 -298.227831) (xy 259.525237 -298.175536) (xy 259.547879 -298.125959) (xy 259.577345 -298.080109)
			(xy 259.613036 -298.038918) (xy 259.654227 -298.003227) (xy 259.700077 -297.973761) (xy 259.749654 -297.951119)
			(xy 259.801949 -297.935764) (xy 259.855897 -297.928008) (xy 259.910399 -297.928008) (xy 259.964347 -297.935764)
			(xy 260.016642 -297.951119) (xy 260.066219 -297.973761) (xy 260.112069 -298.003227) (xy 260.15326 -298.038918)
			(xy 260.188951 -298.080109) (xy 260.218417 -298.125959) (xy 260.241059 -298.175536) (xy 260.256414 -298.227831)
			(xy 260.26417 -298.281779) (xy 260.264656 -298.30903) (xy 260.264121 -298.337371) (xy 260.255743 -298.393431)
			(xy 260.239161 -298.447633) (xy 260.214741 -298.498785) (xy 260.18302 -298.54576) (xy 260.144696 -298.587523)
			(xy 260.100614 -298.623155) (xy 260.076442 -298.63796) (xy 260.063824 -298.645884) (xy 260.043544 -298.667698)
			(xy 260.030419 -298.694434) (xy 260.025564 -298.72382) (xy 260.029393 -298.753358) (xy 260.041578 -298.780535)
			(xy 260.061086 -298.803043) (xy 260.073394 -298.811442) (xy 260.096271 -298.826535) (xy 260.137866 -298.862224)
			(xy 260.173924 -298.903498) (xy 260.203704 -298.949508) (xy 260.226592 -298.999306) (xy 260.242117 -299.051868)
			(xy 260.249959 -299.106111) (xy 260.250432 -299.133514) (xy 260.375906 -299.133514) (xy 260.379977 -299.077892)
			(xy 260.392103 -299.023455) (xy 260.412026 -298.971364) (xy 260.439322 -298.922729) (xy 260.473408 -298.878586)
			(xy 260.513557 -298.839877) (xy 260.558915 -298.807426) (xy 260.608515 -298.781925) (xy 260.661299 -298.763918)
			(xy 260.716142 -298.753788) (xy 260.771876 -298.751751) (xy 260.827313 -298.757851) (xy 260.88127 -298.771957)
			(xy 260.932599 -298.793769) (xy 260.980205 -298.822823) (xy 261.023073 -298.858498) (xy 261.06029 -298.900035)
			(xy 261.091063 -298.946548) (xy 261.114735 -298.997045) (xy 261.130803 -299.050452) (xy 261.138923 -299.105628)
			(xy 261.139432 -299.133514) (xy 261.138923 -299.1614) (xy 261.130803 -299.216576) (xy 261.114735 -299.269983)
			(xy 261.091063 -299.32048) (xy 261.06029 -299.366993) (xy 261.023073 -299.40853) (xy 260.980205 -299.444205)
			(xy 260.932599 -299.473259) (xy 260.88127 -299.495071) (xy 260.827313 -299.509177) (xy 260.771876 -299.515277)
			(xy 260.716142 -299.51324) (xy 260.661299 -299.50311) (xy 260.608515 -299.485103) (xy 260.558915 -299.459602)
			(xy 260.513557 -299.427151) (xy 260.473408 -299.388442) (xy 260.439322 -299.344299) (xy 260.412026 -299.295664)
			(xy 260.392103 -299.243573) (xy 260.379977 -299.189136) (xy 260.375906 -299.133514) (xy 260.250432 -299.133514)
			(xy 260.249946 -299.160765) (xy 260.24219 -299.214713) (xy 260.226835 -299.267008) (xy 260.204193 -299.316585)
			(xy 260.174727 -299.362435) (xy 260.139036 -299.403626) (xy 260.097845 -299.439317) (xy 260.051995 -299.468783)
			(xy 260.002418 -299.491425) (xy 259.950123 -299.50678) (xy 259.896175 -299.514536) (xy 259.841673 -299.514536)
			(xy 259.787725 -299.50678) (xy 259.73543 -299.491425) (xy 259.685853 -299.468783) (xy 259.640003 -299.439317)
			(xy 259.598812 -299.403626) (xy 259.563121 -299.362435) (xy 259.533655 -299.316585) (xy 259.511013 -299.267008)
			(xy 259.495658 -299.214713) (xy 259.487902 -299.160765) (xy 259.487416 -299.133514) (xy 258.774946 -299.133514)
			(xy 258.774437 -299.1614) (xy 258.766317 -299.216576) (xy 258.750249 -299.269983) (xy 258.726577 -299.32048)
			(xy 258.695804 -299.366993) (xy 258.658587 -299.40853) (xy 258.615719 -299.444205) (xy 258.568113 -299.473259)
			(xy 258.516784 -299.495071) (xy 258.462827 -299.509177) (xy 258.40739 -299.515277) (xy 258.351656 -299.51324)
			(xy 258.296813 -299.50311) (xy 258.244029 -299.485103) (xy 258.194429 -299.459602) (xy 258.149071 -299.427151)
			(xy 258.108922 -299.388442) (xy 258.074836 -299.344299) (xy 258.04754 -299.295664) (xy 258.027617 -299.243573)
			(xy 258.015491 -299.189136) (xy 258.01142 -299.133514) (xy 255.945132 -299.133514) (xy 255.945132 -299.895514)
			(xy 263.537954 -299.895514) (xy 263.53852 -299.866133) (xy 263.547548 -299.808068) (xy 263.565376 -299.752075)
			(xy 263.591583 -299.69948) (xy 263.625547 -299.651528) (xy 263.666466 -299.609354) (xy 263.689592 -299.591222)
			(xy 263.69899 -299.583856) (xy 263.709404 -299.563282) (xy 263.710928 -299.459396) (xy 263.701022 -299.438314)
			(xy 263.691878 -299.430948) (xy 263.670018 -299.412756) (xy 263.63148 -299.370933) (xy 263.599575 -299.323855)
			(xy 263.57501 -299.272563) (xy 263.558329 -299.218193) (xy 263.549902 -299.16195) (xy 263.549384 -299.133514)
			(xy 263.54987 -299.106263) (xy 263.557626 -299.052315) (xy 263.572981 -299.00002) (xy 263.595623 -298.950443)
			(xy 263.625089 -298.904593) (xy 263.66078 -298.863402) (xy 263.701971 -298.827711) (xy 263.747821 -298.798245)
			(xy 263.797398 -298.775603) (xy 263.849693 -298.760248) (xy 263.903641 -298.752492) (xy 263.958143 -298.752492)
			(xy 264.012091 -298.760248) (xy 264.064386 -298.775603) (xy 264.113963 -298.798245) (xy 264.159813 -298.827711)
			(xy 264.201004 -298.863402) (xy 264.236695 -298.904593) (xy 264.266161 -298.950443) (xy 264.288803 -299.00002)
			(xy 264.304158 -299.052315) (xy 264.311914 -299.106263) (xy 264.3124 -299.133514) (xy 264.311872 -299.162897)
			(xy 264.302839 -299.220964) (xy 264.285005 -299.276959) (xy 264.258791 -299.329554) (xy 264.224818 -299.377505)
			(xy 264.183891 -299.419676) (xy 264.160762 -299.437806) (xy 264.151364 -299.445172) (xy 264.14095 -299.465746)
			(xy 264.139426 -299.569632) (xy 264.149332 -299.590714) (xy 264.158476 -299.59808) (xy 264.180292 -299.616323)
			(xy 264.218835 -299.658133) (xy 264.250747 -299.705201) (xy 264.275319 -299.756484) (xy 264.292009 -299.810845)
			(xy 264.300447 -299.867081) (xy 264.30097 -299.895514) (xy 264.934444 -299.895514) (xy 264.938515 -299.839892)
			(xy 264.950641 -299.785455) (xy 264.970564 -299.733364) (xy 264.99786 -299.684729) (xy 265.031946 -299.640586)
			(xy 265.072095 -299.601877) (xy 265.117453 -299.569426) (xy 265.167053 -299.543925) (xy 265.219837 -299.525918)
			(xy 265.27468 -299.515788) (xy 265.330414 -299.513751) (xy 265.385851 -299.519851) (xy 265.439808 -299.533957)
			(xy 265.491137 -299.555769) (xy 265.538743 -299.584823) (xy 265.581611 -299.620498) (xy 265.618828 -299.662035)
			(xy 265.649601 -299.708548) (xy 265.673273 -299.759045) (xy 265.689341 -299.812452) (xy 265.697461 -299.867628)
			(xy 265.69797 -299.895514) (xy 265.820904 -299.895514) (xy 265.824975 -299.839892) (xy 265.837101 -299.785455)
			(xy 265.857024 -299.733364) (xy 265.88432 -299.684729) (xy 265.918406 -299.640586) (xy 265.958555 -299.601877)
			(xy 266.003913 -299.569426) (xy 266.053513 -299.543925) (xy 266.106297 -299.525918) (xy 266.16114 -299.515788)
			(xy 266.216874 -299.513751) (xy 266.272311 -299.519851) (xy 266.326268 -299.533957) (xy 266.377597 -299.555769)
			(xy 266.425203 -299.584823) (xy 266.468071 -299.620498) (xy 266.505288 -299.662035) (xy 266.536061 -299.708548)
			(xy 266.559733 -299.759045) (xy 266.575801 -299.812452) (xy 266.583921 -299.867628) (xy 266.58443 -299.895514)
			(xy 266.583921 -299.9234) (xy 266.575801 -299.978576) (xy 266.559733 -300.031983) (xy 266.536061 -300.08248)
			(xy 266.505288 -300.128993) (xy 266.468071 -300.17053) (xy 266.425203 -300.206205) (xy 266.377597 -300.235259)
			(xy 266.326268 -300.257071) (xy 266.272311 -300.271177) (xy 266.216874 -300.277277) (xy 266.16114 -300.27524)
			(xy 266.106297 -300.26511) (xy 266.053513 -300.247103) (xy 266.003913 -300.221602) (xy 265.958555 -300.189151)
			(xy 265.918406 -300.150442) (xy 265.88432 -300.106299) (xy 265.857024 -300.057664) (xy 265.837101 -300.005573)
			(xy 265.824975 -299.951136) (xy 265.820904 -299.895514) (xy 265.69797 -299.895514) (xy 265.697461 -299.9234)
			(xy 265.689341 -299.978576) (xy 265.673273 -300.031983) (xy 265.649601 -300.08248) (xy 265.618828 -300.128993)
			(xy 265.581611 -300.17053) (xy 265.538743 -300.206205) (xy 265.491137 -300.235259) (xy 265.439808 -300.257071)
			(xy 265.385851 -300.271177) (xy 265.330414 -300.277277) (xy 265.27468 -300.27524) (xy 265.219837 -300.26511)
			(xy 265.167053 -300.247103) (xy 265.117453 -300.221602) (xy 265.072095 -300.189151) (xy 265.031946 -300.150442)
			(xy 264.99786 -300.106299) (xy 264.970564 -300.057664) (xy 264.950641 -300.005573) (xy 264.938515 -299.951136)
			(xy 264.934444 -299.895514) (xy 264.30097 -299.895514) (xy 264.300484 -299.922765) (xy 264.292728 -299.976713)
			(xy 264.277373 -300.029008) (xy 264.254731 -300.078585) (xy 264.225265 -300.124435) (xy 264.189574 -300.165626)
			(xy 264.148383 -300.201317) (xy 264.102533 -300.230783) (xy 264.052956 -300.253425) (xy 264.000661 -300.26878)
			(xy 263.946713 -300.276536) (xy 263.892211 -300.276536) (xy 263.838263 -300.26878) (xy 263.785968 -300.253425)
			(xy 263.736391 -300.230783) (xy 263.690541 -300.201317) (xy 263.64935 -300.165626) (xy 263.613659 -300.124435)
			(xy 263.584193 -300.078585) (xy 263.561551 -300.029008) (xy 263.546196 -299.976713) (xy 263.53844 -299.922765)
			(xy 263.537954 -299.895514) (xy 255.945132 -299.895514) (xy 255.945132 -301.031656) (xy 258.01142 -301.031656)
			(xy 258.015491 -300.976034) (xy 258.027617 -300.921597) (xy 258.04754 -300.869506) (xy 258.074836 -300.820871)
			(xy 258.108922 -300.776728) (xy 258.149071 -300.738019) (xy 258.194429 -300.705568) (xy 258.244029 -300.680067)
			(xy 258.296813 -300.66206) (xy 258.351656 -300.65193) (xy 258.40739 -300.649893) (xy 258.462827 -300.655993)
			(xy 258.516784 -300.670099) (xy 258.568113 -300.691911) (xy 258.615719 -300.720965) (xy 258.658587 -300.75664)
			(xy 258.695804 -300.798177) (xy 258.726577 -300.84469) (xy 258.750249 -300.895187) (xy 258.766317 -300.948594)
			(xy 258.767028 -300.953424) (xy 259.495288 -300.953424) (xy 259.499359 -300.897802) (xy 259.511485 -300.843365)
			(xy 259.531408 -300.791274) (xy 259.558704 -300.742639) (xy 259.59279 -300.698496) (xy 259.632939 -300.659787)
			(xy 259.678297 -300.627336) (xy 259.727897 -300.601835) (xy 259.780681 -300.583828) (xy 259.835524 -300.573698)
			(xy 259.891258 -300.571661) (xy 259.946695 -300.577761) (xy 260.000652 -300.591867) (xy 260.051981 -300.613679)
			(xy 260.099587 -300.642733) (xy 260.142455 -300.678408) (xy 260.179672 -300.719945) (xy 260.210445 -300.766458)
			(xy 260.234117 -300.816955) (xy 260.250185 -300.870362) (xy 260.258305 -300.925538) (xy 260.258814 -300.953424)
			(xy 260.258305 -300.98131) (xy 260.250185 -301.036486) (xy 260.234117 -301.089893) (xy 260.210445 -301.14039)
			(xy 260.179672 -301.186903) (xy 260.142455 -301.22844) (xy 260.099587 -301.264115) (xy 260.051981 -301.293169)
			(xy 260.000652 -301.314981) (xy 259.946695 -301.329087) (xy 259.891258 -301.335187) (xy 259.835524 -301.33315)
			(xy 259.780681 -301.32302) (xy 259.727897 -301.305013) (xy 259.678297 -301.279512) (xy 259.632939 -301.247061)
			(xy 259.59279 -301.208352) (xy 259.558704 -301.164209) (xy 259.531408 -301.115574) (xy 259.511485 -301.063483)
			(xy 259.499359 -301.009046) (xy 259.495288 -300.953424) (xy 258.767028 -300.953424) (xy 258.774437 -301.00377)
			(xy 258.774946 -301.031656) (xy 258.774437 -301.059542) (xy 258.766317 -301.114718) (xy 258.750249 -301.168125)
			(xy 258.726577 -301.218622) (xy 258.695804 -301.265135) (xy 258.658587 -301.306672) (xy 258.615719 -301.342347)
			(xy 258.568113 -301.371401) (xy 258.516784 -301.393213) (xy 258.462827 -301.407319) (xy 258.40739 -301.413419)
			(xy 258.351656 -301.411382) (xy 258.296813 -301.401252) (xy 258.244029 -301.383245) (xy 258.194429 -301.357744)
			(xy 258.149071 -301.325293) (xy 258.108922 -301.286584) (xy 258.074836 -301.242441) (xy 258.04754 -301.193806)
			(xy 258.027617 -301.141715) (xy 258.015491 -301.087278) (xy 258.01142 -301.031656) (xy 255.945132 -301.031656)
			(xy 255.945132 -302.550068) (xy 267.793736 -302.550068) (xy 267.797696 -302.501014) (xy 267.809473 -302.45323)
			(xy 267.828764 -302.407954) (xy 267.855067 -302.366358) (xy 267.887702 -302.329521) (xy 267.925823 -302.298396)
			(xy 267.968444 -302.273789) (xy 268.01446 -302.256337) (xy 268.062679 -302.246493) (xy 268.111854 -302.244512)
			(xy 268.160709 -302.250444) (xy 268.20798 -302.264136) (xy 268.252442 -302.285234) (xy 268.292945 -302.31319)
			(xy 268.328438 -302.347282) (xy 268.358003 -302.386626) (xy 268.380874 -302.430203) (xy 268.396458 -302.476884)
			(xy 268.404353 -302.525461) (xy 268.404848 -302.550068) (xy 268.404353 -302.574675) (xy 268.404215 -302.575522)
			(xy 268.723106 -302.575522) (xy 268.723106 -302.524106) (xy 268.731149 -302.473324) (xy 268.747037 -302.424425)
			(xy 268.77038 -302.378613) (xy 268.800601 -302.337017) (xy 268.836957 -302.300661) (xy 268.878553 -302.27044)
			(xy 268.924365 -302.247097) (xy 268.973264 -302.231209) (xy 269.024046 -302.223166) (xy 269.075462 -302.223166)
			(xy 269.126244 -302.231209) (xy 269.175143 -302.247097) (xy 269.220955 -302.27044) (xy 269.262551 -302.300661)
			(xy 269.298907 -302.337017) (xy 269.329128 -302.378613) (xy 269.352471 -302.424425) (xy 269.368359 -302.473324)
			(xy 269.376402 -302.524106) (xy 269.376906 -302.549814) (xy 269.376402 -302.575522) (xy 269.673066 -302.575522)
			(xy 269.673066 -302.524106) (xy 269.681109 -302.473324) (xy 269.696997 -302.424425) (xy 269.72034 -302.378613)
			(xy 269.750561 -302.337017) (xy 269.786917 -302.300661) (xy 269.828513 -302.27044) (xy 269.874325 -302.247097)
			(xy 269.923224 -302.231209) (xy 269.974006 -302.223166) (xy 270.025422 -302.223166) (xy 270.076204 -302.231209)
			(xy 270.125103 -302.247097) (xy 270.170915 -302.27044) (xy 270.212511 -302.300661) (xy 270.248867 -302.337017)
			(xy 270.279088 -302.378613) (xy 270.302431 -302.424425) (xy 270.318319 -302.473324) (xy 270.326362 -302.524106)
			(xy 270.326866 -302.549814) (xy 270.644124 -302.549814) (xy 270.648084 -302.50076) (xy 270.659861 -302.452976)
			(xy 270.679152 -302.4077) (xy 270.705455 -302.366104) (xy 270.73809 -302.329267) (xy 270.776211 -302.298142)
			(xy 270.818832 -302.273535) (xy 270.864848 -302.256083) (xy 270.913067 -302.246239) (xy 270.962242 -302.244258)
			(xy 271.011097 -302.25019) (xy 271.058368 -302.263882) (xy 271.10283 -302.28498) (xy 271.143333 -302.312936)
			(xy 271.178826 -302.347028) (xy 271.208391 -302.386372) (xy 271.231262 -302.429949) (xy 271.246846 -302.47663)
			(xy 271.254741 -302.525207) (xy 271.255236 -302.549814) (xy 271.594084 -302.549814) (xy 271.598044 -302.50076)
			(xy 271.609821 -302.452976) (xy 271.629112 -302.4077) (xy 271.655415 -302.366104) (xy 271.68805 -302.329267)
			(xy 271.726171 -302.298142) (xy 271.768792 -302.273535) (xy 271.814808 -302.256083) (xy 271.863027 -302.246239)
			(xy 271.912202 -302.244258) (xy 271.961057 -302.25019) (xy 272.008328 -302.263882) (xy 272.05279 -302.28498)
			(xy 272.093293 -302.312936) (xy 272.128786 -302.347028) (xy 272.158351 -302.386372) (xy 272.181222 -302.429949)
			(xy 272.196806 -302.47663) (xy 272.204701 -302.525207) (xy 272.205196 -302.549814) (xy 272.544044 -302.549814)
			(xy 272.548004 -302.50076) (xy 272.559781 -302.452976) (xy 272.579072 -302.4077) (xy 272.605375 -302.366104)
			(xy 272.63801 -302.329267) (xy 272.676131 -302.298142) (xy 272.718752 -302.273535) (xy 272.764768 -302.256083)
			(xy 272.812987 -302.246239) (xy 272.862162 -302.244258) (xy 272.911017 -302.25019) (xy 272.958288 -302.263882)
			(xy 273.00275 -302.28498) (xy 273.043253 -302.312936) (xy 273.078746 -302.347028) (xy 273.108311 -302.386372)
			(xy 273.131182 -302.429949) (xy 273.146766 -302.47663) (xy 273.154661 -302.525207) (xy 273.155156 -302.549814)
			(xy 273.494004 -302.549814) (xy 273.497964 -302.50076) (xy 273.509741 -302.452976) (xy 273.529032 -302.4077)
			(xy 273.555335 -302.366104) (xy 273.58797 -302.329267) (xy 273.626091 -302.298142) (xy 273.668712 -302.273535)
			(xy 273.714728 -302.256083) (xy 273.762947 -302.246239) (xy 273.812122 -302.244258) (xy 273.860977 -302.25019)
			(xy 273.908248 -302.263882) (xy 273.95271 -302.28498) (xy 273.993213 -302.312936) (xy 274.028706 -302.347028)
			(xy 274.058271 -302.386372) (xy 274.081142 -302.429949) (xy 274.096726 -302.47663) (xy 274.104621 -302.525207)
			(xy 274.105116 -302.549814) (xy 274.443964 -302.549814) (xy 274.447924 -302.50076) (xy 274.459701 -302.452976)
			(xy 274.478992 -302.4077) (xy 274.505295 -302.366104) (xy 274.53793 -302.329267) (xy 274.576051 -302.298142)
			(xy 274.618672 -302.273535) (xy 274.664688 -302.256083) (xy 274.712907 -302.246239) (xy 274.762082 -302.244258)
			(xy 274.810937 -302.25019) (xy 274.858208 -302.263882) (xy 274.90267 -302.28498) (xy 274.943173 -302.312936)
			(xy 274.978666 -302.347028) (xy 275.008231 -302.386372) (xy 275.031102 -302.429949) (xy 275.046686 -302.47663)
			(xy 275.054581 -302.525207) (xy 275.055076 -302.549814) (xy 275.054581 -302.574421) (xy 275.054402 -302.575522)
			(xy 275.37308 -302.575522) (xy 275.37308 -302.524106) (xy 275.381123 -302.473324) (xy 275.397011 -302.424425)
			(xy 275.420354 -302.378613) (xy 275.450575 -302.337017) (xy 275.486931 -302.300661) (xy 275.528527 -302.27044)
			(xy 275.574339 -302.247097) (xy 275.623238 -302.231209) (xy 275.67402 -302.223166) (xy 275.725436 -302.223166)
			(xy 275.776218 -302.231209) (xy 275.825117 -302.247097) (xy 275.870929 -302.27044) (xy 275.912525 -302.300661)
			(xy 275.948881 -302.337017) (xy 275.979102 -302.378613) (xy 276.002445 -302.424425) (xy 276.018333 -302.473324)
			(xy 276.026376 -302.524106) (xy 276.02688 -302.549814) (xy 276.026376 -302.575522) (xy 276.32304 -302.575522)
			(xy 276.32304 -302.524106) (xy 276.331083 -302.473324) (xy 276.346971 -302.424425) (xy 276.370314 -302.378613)
			(xy 276.400535 -302.337017) (xy 276.436891 -302.300661) (xy 276.478487 -302.27044) (xy 276.524299 -302.247097)
			(xy 276.573198 -302.231209) (xy 276.62398 -302.223166) (xy 276.675396 -302.223166) (xy 276.726178 -302.231209)
			(xy 276.775077 -302.247097) (xy 276.820889 -302.27044) (xy 276.862485 -302.300661) (xy 276.898841 -302.337017)
			(xy 276.929062 -302.378613) (xy 276.952405 -302.424425) (xy 276.968293 -302.473324) (xy 276.976336 -302.524106)
			(xy 276.97684 -302.549814) (xy 277.294098 -302.549814) (xy 277.298058 -302.50076) (xy 277.309835 -302.452976)
			(xy 277.329126 -302.4077) (xy 277.355429 -302.366104) (xy 277.388064 -302.329267) (xy 277.426185 -302.298142)
			(xy 277.468806 -302.273535) (xy 277.514822 -302.256083) (xy 277.563041 -302.246239) (xy 277.612216 -302.244258)
			(xy 277.661071 -302.25019) (xy 277.708342 -302.263882) (xy 277.752804 -302.28498) (xy 277.793307 -302.312936)
			(xy 277.8288 -302.347028) (xy 277.858365 -302.386372) (xy 277.881236 -302.429949) (xy 277.89682 -302.47663)
			(xy 277.904715 -302.525207) (xy 277.90521 -302.549814) (xy 277.904715 -302.574421) (xy 277.89682 -302.622998)
			(xy 277.881236 -302.669679) (xy 277.858365 -302.713256) (xy 277.8288 -302.7526) (xy 277.793307 -302.786692)
			(xy 277.752804 -302.814648) (xy 277.708342 -302.835746) (xy 277.661071 -302.849438) (xy 277.612216 -302.85537)
			(xy 277.563041 -302.853389) (xy 277.514822 -302.843545) (xy 277.468806 -302.826093) (xy 277.426185 -302.801486)
			(xy 277.388064 -302.770361) (xy 277.355429 -302.733524) (xy 277.329126 -302.691928) (xy 277.309835 -302.646652)
			(xy 277.298058 -302.598868) (xy 277.294098 -302.549814) (xy 276.97684 -302.549814) (xy 276.976336 -302.575522)
			(xy 276.968293 -302.626304) (xy 276.952405 -302.675203) (xy 276.929062 -302.721015) (xy 276.898841 -302.762611)
			(xy 276.862485 -302.798967) (xy 276.820889 -302.829188) (xy 276.775077 -302.852531) (xy 276.726178 -302.868419)
			(xy 276.675396 -302.876462) (xy 276.62398 -302.876462) (xy 276.573198 -302.868419) (xy 276.524299 -302.852531)
			(xy 276.478487 -302.829188) (xy 276.436891 -302.798967) (xy 276.400535 -302.762611) (xy 276.370314 -302.721015)
			(xy 276.346971 -302.675203) (xy 276.331083 -302.626304) (xy 276.32304 -302.575522) (xy 276.026376 -302.575522)
			(xy 276.018333 -302.626304) (xy 276.002445 -302.675203) (xy 275.979102 -302.721015) (xy 275.948881 -302.762611)
			(xy 275.912525 -302.798967) (xy 275.870929 -302.829188) (xy 275.825117 -302.852531) (xy 275.776218 -302.868419)
			(xy 275.725436 -302.876462) (xy 275.67402 -302.876462) (xy 275.623238 -302.868419) (xy 275.574339 -302.852531)
			(xy 275.528527 -302.829188) (xy 275.486931 -302.798967) (xy 275.450575 -302.762611) (xy 275.420354 -302.721015)
			(xy 275.397011 -302.675203) (xy 275.381123 -302.626304) (xy 275.37308 -302.575522) (xy 275.054402 -302.575522)
			(xy 275.046686 -302.622998) (xy 275.031102 -302.669679) (xy 275.008231 -302.713256) (xy 274.978666 -302.7526)
			(xy 274.943173 -302.786692) (xy 274.90267 -302.814648) (xy 274.858208 -302.835746) (xy 274.810937 -302.849438)
			(xy 274.762082 -302.85537) (xy 274.712907 -302.853389) (xy 274.664688 -302.843545) (xy 274.618672 -302.826093)
			(xy 274.576051 -302.801486) (xy 274.53793 -302.770361) (xy 274.505295 -302.733524) (xy 274.478992 -302.691928)
			(xy 274.459701 -302.646652) (xy 274.447924 -302.598868) (xy 274.443964 -302.549814) (xy 274.105116 -302.549814)
			(xy 274.104621 -302.574421) (xy 274.096726 -302.622998) (xy 274.081142 -302.669679) (xy 274.058271 -302.713256)
			(xy 274.028706 -302.7526) (xy 273.993213 -302.786692) (xy 273.95271 -302.814648) (xy 273.908248 -302.835746)
			(xy 273.860977 -302.849438) (xy 273.812122 -302.85537) (xy 273.762947 -302.853389) (xy 273.714728 -302.843545)
			(xy 273.668712 -302.826093) (xy 273.626091 -302.801486) (xy 273.58797 -302.770361) (xy 273.555335 -302.733524)
			(xy 273.529032 -302.691928) (xy 273.509741 -302.646652) (xy 273.497964 -302.598868) (xy 273.494004 -302.549814)
			(xy 273.155156 -302.549814) (xy 273.154661 -302.574421) (xy 273.146766 -302.622998) (xy 273.131182 -302.669679)
			(xy 273.108311 -302.713256) (xy 273.078746 -302.7526) (xy 273.043253 -302.786692) (xy 273.00275 -302.814648)
			(xy 272.958288 -302.835746) (xy 272.911017 -302.849438) (xy 272.862162 -302.85537) (xy 272.812987 -302.853389)
			(xy 272.764768 -302.843545) (xy 272.718752 -302.826093) (xy 272.676131 -302.801486) (xy 272.63801 -302.770361)
			(xy 272.605375 -302.733524) (xy 272.579072 -302.691928) (xy 272.559781 -302.646652) (xy 272.548004 -302.598868)
			(xy 272.544044 -302.549814) (xy 272.205196 -302.549814) (xy 272.204701 -302.574421) (xy 272.196806 -302.622998)
			(xy 272.181222 -302.669679) (xy 272.158351 -302.713256) (xy 272.128786 -302.7526) (xy 272.093293 -302.786692)
			(xy 272.05279 -302.814648) (xy 272.008328 -302.835746) (xy 271.961057 -302.849438) (xy 271.912202 -302.85537)
			(xy 271.863027 -302.853389) (xy 271.814808 -302.843545) (xy 271.768792 -302.826093) (xy 271.726171 -302.801486)
			(xy 271.68805 -302.770361) (xy 271.655415 -302.733524) (xy 271.629112 -302.691928) (xy 271.609821 -302.646652)
			(xy 271.598044 -302.598868) (xy 271.594084 -302.549814) (xy 271.255236 -302.549814) (xy 271.254741 -302.574421)
			(xy 271.246846 -302.622998) (xy 271.231262 -302.669679) (xy 271.208391 -302.713256) (xy 271.178826 -302.7526)
			(xy 271.143333 -302.786692) (xy 271.10283 -302.814648) (xy 271.058368 -302.835746) (xy 271.011097 -302.849438)
			(xy 270.962242 -302.85537) (xy 270.913067 -302.853389) (xy 270.864848 -302.843545) (xy 270.818832 -302.826093)
			(xy 270.776211 -302.801486) (xy 270.73809 -302.770361) (xy 270.705455 -302.733524) (xy 270.679152 -302.691928)
			(xy 270.659861 -302.646652) (xy 270.648084 -302.598868) (xy 270.644124 -302.549814) (xy 270.326866 -302.549814)
			(xy 270.326362 -302.575522) (xy 270.318319 -302.626304) (xy 270.302431 -302.675203) (xy 270.279088 -302.721015)
			(xy 270.248867 -302.762611) (xy 270.212511 -302.798967) (xy 270.170915 -302.829188) (xy 270.125103 -302.852531)
			(xy 270.076204 -302.868419) (xy 270.025422 -302.876462) (xy 269.974006 -302.876462) (xy 269.923224 -302.868419)
			(xy 269.874325 -302.852531) (xy 269.828513 -302.829188) (xy 269.786917 -302.798967) (xy 269.750561 -302.762611)
			(xy 269.72034 -302.721015) (xy 269.696997 -302.675203) (xy 269.681109 -302.626304) (xy 269.673066 -302.575522)
			(xy 269.376402 -302.575522) (xy 269.368359 -302.626304) (xy 269.352471 -302.675203) (xy 269.329128 -302.721015)
			(xy 269.298907 -302.762611) (xy 269.262551 -302.798967) (xy 269.220955 -302.829188) (xy 269.175143 -302.852531)
			(xy 269.126244 -302.868419) (xy 269.075462 -302.876462) (xy 269.024046 -302.876462) (xy 268.973264 -302.868419)
			(xy 268.924365 -302.852531) (xy 268.878553 -302.829188) (xy 268.836957 -302.798967) (xy 268.800601 -302.762611)
			(xy 268.77038 -302.721015) (xy 268.747037 -302.675203) (xy 268.731149 -302.626304) (xy 268.723106 -302.575522)
			(xy 268.404215 -302.575522) (xy 268.396458 -302.623252) (xy 268.380874 -302.669933) (xy 268.358003 -302.71351)
			(xy 268.328438 -302.752854) (xy 268.292945 -302.786946) (xy 268.252442 -302.814902) (xy 268.20798 -302.836)
			(xy 268.160709 -302.849692) (xy 268.111854 -302.855624) (xy 268.062679 -302.853643) (xy 268.01446 -302.843799)
			(xy 267.968444 -302.826347) (xy 267.925823 -302.80174) (xy 267.887702 -302.770615) (xy 267.855067 -302.733778)
			(xy 267.828764 -302.692182) (xy 267.809473 -302.646906) (xy 267.797696 -302.599122) (xy 267.793736 -302.550068)
			(xy 255.945132 -302.550068) (xy 255.945132 -303.499774) (xy 268.74395 -303.499774) (xy 268.74791 -303.45072)
			(xy 268.759687 -303.402936) (xy 268.778978 -303.35766) (xy 268.805281 -303.316064) (xy 268.837916 -303.279227)
			(xy 268.876037 -303.248102) (xy 268.918658 -303.223495) (xy 268.964674 -303.206043) (xy 269.012893 -303.196199)
			(xy 269.062068 -303.194218) (xy 269.110923 -303.20015) (xy 269.158194 -303.213842) (xy 269.202656 -303.23494)
			(xy 269.243159 -303.262896) (xy 269.278652 -303.296988) (xy 269.308217 -303.336332) (xy 269.331088 -303.379909)
			(xy 269.346672 -303.42659) (xy 269.354567 -303.475167) (xy 269.355062 -303.499774) (xy 269.69391 -303.499774)
			(xy 269.69787 -303.45072) (xy 269.709647 -303.402936) (xy 269.728938 -303.35766) (xy 269.755241 -303.316064)
			(xy 269.787876 -303.279227) (xy 269.825997 -303.248102) (xy 269.868618 -303.223495) (xy 269.914634 -303.206043)
			(xy 269.962853 -303.196199) (xy 270.012028 -303.194218) (xy 270.060883 -303.20015) (xy 270.108154 -303.213842)
			(xy 270.152616 -303.23494) (xy 270.193119 -303.262896) (xy 270.228612 -303.296988) (xy 270.258177 -303.336332)
			(xy 270.281048 -303.379909) (xy 270.296632 -303.42659) (xy 270.304527 -303.475167) (xy 270.305022 -303.499774)
			(xy 270.304527 -303.524381) (xy 270.304348 -303.525482) (xy 270.62328 -303.525482) (xy 270.62328 -303.474066)
			(xy 270.631323 -303.423284) (xy 270.647211 -303.374385) (xy 270.670554 -303.328573) (xy 270.700775 -303.286977)
			(xy 270.737131 -303.250621) (xy 270.778727 -303.2204) (xy 270.824539 -303.197057) (xy 270.873438 -303.181169)
			(xy 270.92422 -303.173126) (xy 270.975636 -303.173126) (xy 271.026418 -303.181169) (xy 271.075317 -303.197057)
			(xy 271.121129 -303.2204) (xy 271.162725 -303.250621) (xy 271.199081 -303.286977) (xy 271.229302 -303.328573)
			(xy 271.252645 -303.374385) (xy 271.268533 -303.423284) (xy 271.276576 -303.474066) (xy 271.27708 -303.499774)
			(xy 271.276576 -303.525482) (xy 271.57324 -303.525482) (xy 271.57324 -303.474066) (xy 271.581283 -303.423284)
			(xy 271.597171 -303.374385) (xy 271.620514 -303.328573) (xy 271.650735 -303.286977) (xy 271.687091 -303.250621)
			(xy 271.728687 -303.2204) (xy 271.774499 -303.197057) (xy 271.823398 -303.181169) (xy 271.87418 -303.173126)
			(xy 271.925596 -303.173126) (xy 271.976378 -303.181169) (xy 272.025277 -303.197057) (xy 272.071089 -303.2204)
			(xy 272.112685 -303.250621) (xy 272.149041 -303.286977) (xy 272.179262 -303.328573) (xy 272.202605 -303.374385)
			(xy 272.218493 -303.423284) (xy 272.226536 -303.474066) (xy 272.22704 -303.499774) (xy 272.544044 -303.499774)
			(xy 272.548004 -303.45072) (xy 272.559781 -303.402936) (xy 272.579072 -303.35766) (xy 272.605375 -303.316064)
			(xy 272.63801 -303.279227) (xy 272.676131 -303.248102) (xy 272.718752 -303.223495) (xy 272.764768 -303.206043)
			(xy 272.812987 -303.196199) (xy 272.862162 -303.194218) (xy 272.911017 -303.20015) (xy 272.958288 -303.213842)
			(xy 273.00275 -303.23494) (xy 273.043253 -303.262896) (xy 273.078746 -303.296988) (xy 273.108311 -303.336332)
			(xy 273.131182 -303.379909) (xy 273.146766 -303.42659) (xy 273.154661 -303.475167) (xy 273.155156 -303.499774)
			(xy 273.154661 -303.524381) (xy 273.154482 -303.525482) (xy 273.47316 -303.525482) (xy 273.47316 -303.474066)
			(xy 273.481203 -303.423284) (xy 273.497091 -303.374385) (xy 273.520434 -303.328573) (xy 273.550655 -303.286977)
			(xy 273.587011 -303.250621) (xy 273.628607 -303.2204) (xy 273.674419 -303.197057) (xy 273.723318 -303.181169)
			(xy 273.7741 -303.173126) (xy 273.825516 -303.173126) (xy 273.876298 -303.181169) (xy 273.925197 -303.197057)
			(xy 273.971009 -303.2204) (xy 274.012605 -303.250621) (xy 274.048961 -303.286977) (xy 274.079182 -303.328573)
			(xy 274.102525 -303.374385) (xy 274.118413 -303.423284) (xy 274.126456 -303.474066) (xy 274.12696 -303.499774)
			(xy 274.126456 -303.525482) (xy 274.42312 -303.525482) (xy 274.42312 -303.474066) (xy 274.431163 -303.423284)
			(xy 274.447051 -303.374385) (xy 274.470394 -303.328573) (xy 274.500615 -303.286977) (xy 274.536971 -303.250621)
			(xy 274.578567 -303.2204) (xy 274.624379 -303.197057) (xy 274.673278 -303.181169) (xy 274.72406 -303.173126)
			(xy 274.775476 -303.173126) (xy 274.826258 -303.181169) (xy 274.875157 -303.197057) (xy 274.920969 -303.2204)
			(xy 274.962565 -303.250621) (xy 274.998921 -303.286977) (xy 275.029142 -303.328573) (xy 275.052485 -303.374385)
			(xy 275.068373 -303.423284) (xy 275.076416 -303.474066) (xy 275.07692 -303.499774) (xy 275.393924 -303.499774)
			(xy 275.397884 -303.45072) (xy 275.409661 -303.402936) (xy 275.428952 -303.35766) (xy 275.455255 -303.316064)
			(xy 275.48789 -303.279227) (xy 275.526011 -303.248102) (xy 275.568632 -303.223495) (xy 275.614648 -303.206043)
			(xy 275.662867 -303.196199) (xy 275.712042 -303.194218) (xy 275.760897 -303.20015) (xy 275.808168 -303.213842)
			(xy 275.85263 -303.23494) (xy 275.893133 -303.262896) (xy 275.928626 -303.296988) (xy 275.958191 -303.336332)
			(xy 275.981062 -303.379909) (xy 275.996646 -303.42659) (xy 276.004541 -303.475167) (xy 276.005036 -303.499774)
			(xy 276.343884 -303.499774) (xy 276.347844 -303.45072) (xy 276.359621 -303.402936) (xy 276.378912 -303.35766)
			(xy 276.405215 -303.316064) (xy 276.43785 -303.279227) (xy 276.475971 -303.248102) (xy 276.518592 -303.223495)
			(xy 276.564608 -303.206043) (xy 276.612827 -303.196199) (xy 276.662002 -303.194218) (xy 276.710857 -303.20015)
			(xy 276.758128 -303.213842) (xy 276.80259 -303.23494) (xy 276.843093 -303.262896) (xy 276.878586 -303.296988)
			(xy 276.908151 -303.336332) (xy 276.931022 -303.379909) (xy 276.946606 -303.42659) (xy 276.954501 -303.475167)
			(xy 276.954996 -303.499774) (xy 277.294098 -303.499774) (xy 277.298058 -303.45072) (xy 277.309835 -303.402936)
			(xy 277.329126 -303.35766) (xy 277.355429 -303.316064) (xy 277.388064 -303.279227) (xy 277.426185 -303.248102)
			(xy 277.468806 -303.223495) (xy 277.514822 -303.206043) (xy 277.563041 -303.196199) (xy 277.612216 -303.194218)
			(xy 277.661071 -303.20015) (xy 277.708342 -303.213842) (xy 277.752804 -303.23494) (xy 277.793307 -303.262896)
			(xy 277.8288 -303.296988) (xy 277.858365 -303.336332) (xy 277.881236 -303.379909) (xy 277.89682 -303.42659)
			(xy 277.904715 -303.475167) (xy 277.90521 -303.499774) (xy 277.904715 -303.524381) (xy 277.89682 -303.572958)
			(xy 277.881236 -303.619639) (xy 277.858365 -303.663216) (xy 277.8288 -303.70256) (xy 277.793307 -303.736652)
			(xy 277.752804 -303.764608) (xy 277.708342 -303.785706) (xy 277.661071 -303.799398) (xy 277.612216 -303.80533)
			(xy 277.563041 -303.803349) (xy 277.514822 -303.793505) (xy 277.468806 -303.776053) (xy 277.426185 -303.751446)
			(xy 277.388064 -303.720321) (xy 277.355429 -303.683484) (xy 277.329126 -303.641888) (xy 277.309835 -303.596612)
			(xy 277.298058 -303.548828) (xy 277.294098 -303.499774) (xy 276.954996 -303.499774) (xy 276.954501 -303.524381)
			(xy 276.946606 -303.572958) (xy 276.931022 -303.619639) (xy 276.908151 -303.663216) (xy 276.878586 -303.70256)
			(xy 276.843093 -303.736652) (xy 276.80259 -303.764608) (xy 276.758128 -303.785706) (xy 276.710857 -303.799398)
			(xy 276.662002 -303.80533) (xy 276.612827 -303.803349) (xy 276.564608 -303.793505) (xy 276.518592 -303.776053)
			(xy 276.475971 -303.751446) (xy 276.43785 -303.720321) (xy 276.405215 -303.683484) (xy 276.378912 -303.641888)
			(xy 276.359621 -303.596612) (xy 276.347844 -303.548828) (xy 276.343884 -303.499774) (xy 276.005036 -303.499774)
			(xy 276.004541 -303.524381) (xy 275.996646 -303.572958) (xy 275.981062 -303.619639) (xy 275.958191 -303.663216)
			(xy 275.928626 -303.70256) (xy 275.893133 -303.736652) (xy 275.85263 -303.764608) (xy 275.808168 -303.785706)
			(xy 275.760897 -303.799398) (xy 275.712042 -303.80533) (xy 275.662867 -303.803349) (xy 275.614648 -303.793505)
			(xy 275.568632 -303.776053) (xy 275.526011 -303.751446) (xy 275.48789 -303.720321) (xy 275.455255 -303.683484)
			(xy 275.428952 -303.641888) (xy 275.409661 -303.596612) (xy 275.397884 -303.548828) (xy 275.393924 -303.499774)
			(xy 275.07692 -303.499774) (xy 275.076416 -303.525482) (xy 275.068373 -303.576264) (xy 275.052485 -303.625163)
			(xy 275.029142 -303.670975) (xy 274.998921 -303.712571) (xy 274.962565 -303.748927) (xy 274.920969 -303.779148)
			(xy 274.875157 -303.802491) (xy 274.826258 -303.818379) (xy 274.775476 -303.826422) (xy 274.72406 -303.826422)
			(xy 274.673278 -303.818379) (xy 274.624379 -303.802491) (xy 274.578567 -303.779148) (xy 274.536971 -303.748927)
			(xy 274.500615 -303.712571) (xy 274.470394 -303.670975) (xy 274.447051 -303.625163) (xy 274.431163 -303.576264)
			(xy 274.42312 -303.525482) (xy 274.126456 -303.525482) (xy 274.118413 -303.576264) (xy 274.102525 -303.625163)
			(xy 274.079182 -303.670975) (xy 274.048961 -303.712571) (xy 274.012605 -303.748927) (xy 273.971009 -303.779148)
			(xy 273.925197 -303.802491) (xy 273.876298 -303.818379) (xy 273.825516 -303.826422) (xy 273.7741 -303.826422)
			(xy 273.723318 -303.818379) (xy 273.674419 -303.802491) (xy 273.628607 -303.779148) (xy 273.587011 -303.748927)
			(xy 273.550655 -303.712571) (xy 273.520434 -303.670975) (xy 273.497091 -303.625163) (xy 273.481203 -303.576264)
			(xy 273.47316 -303.525482) (xy 273.154482 -303.525482) (xy 273.146766 -303.572958) (xy 273.131182 -303.619639)
			(xy 273.108311 -303.663216) (xy 273.078746 -303.70256) (xy 273.043253 -303.736652) (xy 273.00275 -303.764608)
			(xy 272.958288 -303.785706) (xy 272.911017 -303.799398) (xy 272.862162 -303.80533) (xy 272.812987 -303.803349)
			(xy 272.764768 -303.793505) (xy 272.718752 -303.776053) (xy 272.676131 -303.751446) (xy 272.63801 -303.720321)
			(xy 272.605375 -303.683484) (xy 272.579072 -303.641888) (xy 272.559781 -303.596612) (xy 272.548004 -303.548828)
			(xy 272.544044 -303.499774) (xy 272.22704 -303.499774) (xy 272.226536 -303.525482) (xy 272.218493 -303.576264)
			(xy 272.202605 -303.625163) (xy 272.179262 -303.670975) (xy 272.149041 -303.712571) (xy 272.112685 -303.748927)
			(xy 272.071089 -303.779148) (xy 272.025277 -303.802491) (xy 271.976378 -303.818379) (xy 271.925596 -303.826422)
			(xy 271.87418 -303.826422) (xy 271.823398 -303.818379) (xy 271.774499 -303.802491) (xy 271.728687 -303.779148)
			(xy 271.687091 -303.748927) (xy 271.650735 -303.712571) (xy 271.620514 -303.670975) (xy 271.597171 -303.625163)
			(xy 271.581283 -303.576264) (xy 271.57324 -303.525482) (xy 271.276576 -303.525482) (xy 271.268533 -303.576264)
			(xy 271.252645 -303.625163) (xy 271.229302 -303.670975) (xy 271.199081 -303.712571) (xy 271.162725 -303.748927)
			(xy 271.121129 -303.779148) (xy 271.075317 -303.802491) (xy 271.026418 -303.818379) (xy 270.975636 -303.826422)
			(xy 270.92422 -303.826422) (xy 270.873438 -303.818379) (xy 270.824539 -303.802491) (xy 270.778727 -303.779148)
			(xy 270.737131 -303.748927) (xy 270.700775 -303.712571) (xy 270.670554 -303.670975) (xy 270.647211 -303.625163)
			(xy 270.631323 -303.576264) (xy 270.62328 -303.525482) (xy 270.304348 -303.525482) (xy 270.296632 -303.572958)
			(xy 270.281048 -303.619639) (xy 270.258177 -303.663216) (xy 270.228612 -303.70256) (xy 270.193119 -303.736652)
			(xy 270.152616 -303.764608) (xy 270.108154 -303.785706) (xy 270.060883 -303.799398) (xy 270.012028 -303.80533)
			(xy 269.962853 -303.803349) (xy 269.914634 -303.793505) (xy 269.868618 -303.776053) (xy 269.825997 -303.751446)
			(xy 269.787876 -303.720321) (xy 269.755241 -303.683484) (xy 269.728938 -303.641888) (xy 269.709647 -303.596612)
			(xy 269.69787 -303.548828) (xy 269.69391 -303.499774) (xy 269.355062 -303.499774) (xy 269.354567 -303.524381)
			(xy 269.346672 -303.572958) (xy 269.331088 -303.619639) (xy 269.308217 -303.663216) (xy 269.278652 -303.70256)
			(xy 269.243159 -303.736652) (xy 269.202656 -303.764608) (xy 269.158194 -303.785706) (xy 269.110923 -303.799398)
			(xy 269.062068 -303.80533) (xy 269.012893 -303.803349) (xy 268.964674 -303.793505) (xy 268.918658 -303.776053)
			(xy 268.876037 -303.751446) (xy 268.837916 -303.720321) (xy 268.805281 -303.683484) (xy 268.778978 -303.641888)
			(xy 268.759687 -303.596612) (xy 268.74791 -303.548828) (xy 268.74395 -303.499774) (xy 255.945132 -303.499774)
			(xy 255.945132 -304.449988) (xy 267.793736 -304.449988) (xy 267.797696 -304.400934) (xy 267.809473 -304.35315)
			(xy 267.828764 -304.307874) (xy 267.855067 -304.266278) (xy 267.887702 -304.229441) (xy 267.925823 -304.198316)
			(xy 267.968444 -304.173709) (xy 268.01446 -304.156257) (xy 268.062679 -304.146413) (xy 268.111854 -304.144432)
			(xy 268.160709 -304.150364) (xy 268.20798 -304.164056) (xy 268.252442 -304.185154) (xy 268.292945 -304.21311)
			(xy 268.328438 -304.247202) (xy 268.358003 -304.286546) (xy 268.380874 -304.330123) (xy 268.396458 -304.376804)
			(xy 268.404353 -304.425381) (xy 268.404848 -304.449988) (xy 268.404353 -304.474595) (xy 268.404215 -304.475442)
			(xy 268.723106 -304.475442) (xy 268.723106 -304.424026) (xy 268.731149 -304.373244) (xy 268.747037 -304.324345)
			(xy 268.77038 -304.278533) (xy 268.800601 -304.236937) (xy 268.836957 -304.200581) (xy 268.878553 -304.17036)
			(xy 268.924365 -304.147017) (xy 268.973264 -304.131129) (xy 269.024046 -304.123086) (xy 269.075462 -304.123086)
			(xy 269.126244 -304.131129) (xy 269.175143 -304.147017) (xy 269.220955 -304.17036) (xy 269.262551 -304.200581)
			(xy 269.298907 -304.236937) (xy 269.329128 -304.278533) (xy 269.352471 -304.324345) (xy 269.368359 -304.373244)
			(xy 269.376402 -304.424026) (xy 269.376906 -304.449734) (xy 269.376402 -304.475442) (xy 269.673066 -304.475442)
			(xy 269.673066 -304.424026) (xy 269.681109 -304.373244) (xy 269.696997 -304.324345) (xy 269.72034 -304.278533)
			(xy 269.750561 -304.236937) (xy 269.786917 -304.200581) (xy 269.828513 -304.17036) (xy 269.874325 -304.147017)
			(xy 269.923224 -304.131129) (xy 269.974006 -304.123086) (xy 270.025422 -304.123086) (xy 270.076204 -304.131129)
			(xy 270.125103 -304.147017) (xy 270.170915 -304.17036) (xy 270.212511 -304.200581) (xy 270.248867 -304.236937)
			(xy 270.279088 -304.278533) (xy 270.302431 -304.324345) (xy 270.318319 -304.373244) (xy 270.326362 -304.424026)
			(xy 270.326866 -304.449734) (xy 270.644124 -304.449734) (xy 270.648084 -304.40068) (xy 270.659861 -304.352896)
			(xy 270.679152 -304.30762) (xy 270.705455 -304.266024) (xy 270.73809 -304.229187) (xy 270.776211 -304.198062)
			(xy 270.818832 -304.173455) (xy 270.864848 -304.156003) (xy 270.913067 -304.146159) (xy 270.962242 -304.144178)
			(xy 271.011097 -304.15011) (xy 271.058368 -304.163802) (xy 271.10283 -304.1849) (xy 271.143333 -304.212856)
			(xy 271.178826 -304.246948) (xy 271.208391 -304.286292) (xy 271.231262 -304.329869) (xy 271.246846 -304.37655)
			(xy 271.254741 -304.425127) (xy 271.255236 -304.449734) (xy 271.594084 -304.449734) (xy 271.598044 -304.40068)
			(xy 271.609821 -304.352896) (xy 271.629112 -304.30762) (xy 271.655415 -304.266024) (xy 271.68805 -304.229187)
			(xy 271.726171 -304.198062) (xy 271.768792 -304.173455) (xy 271.814808 -304.156003) (xy 271.863027 -304.146159)
			(xy 271.912202 -304.144178) (xy 271.961057 -304.15011) (xy 272.008328 -304.163802) (xy 272.05279 -304.1849)
			(xy 272.093293 -304.212856) (xy 272.128786 -304.246948) (xy 272.158351 -304.286292) (xy 272.181222 -304.329869)
			(xy 272.196806 -304.37655) (xy 272.204701 -304.425127) (xy 272.205196 -304.449734) (xy 272.544044 -304.449734)
			(xy 272.548004 -304.40068) (xy 272.559781 -304.352896) (xy 272.579072 -304.30762) (xy 272.605375 -304.266024)
			(xy 272.63801 -304.229187) (xy 272.676131 -304.198062) (xy 272.718752 -304.173455) (xy 272.764768 -304.156003)
			(xy 272.812987 -304.146159) (xy 272.862162 -304.144178) (xy 272.911017 -304.15011) (xy 272.958288 -304.163802)
			(xy 273.00275 -304.1849) (xy 273.043253 -304.212856) (xy 273.078746 -304.246948) (xy 273.108311 -304.286292)
			(xy 273.131182 -304.329869) (xy 273.146766 -304.37655) (xy 273.154661 -304.425127) (xy 273.155156 -304.449734)
			(xy 273.494004 -304.449734) (xy 273.497964 -304.40068) (xy 273.509741 -304.352896) (xy 273.529032 -304.30762)
			(xy 273.555335 -304.266024) (xy 273.58797 -304.229187) (xy 273.626091 -304.198062) (xy 273.668712 -304.173455)
			(xy 273.714728 -304.156003) (xy 273.762947 -304.146159) (xy 273.812122 -304.144178) (xy 273.860977 -304.15011)
			(xy 273.908248 -304.163802) (xy 273.95271 -304.1849) (xy 273.993213 -304.212856) (xy 274.028706 -304.246948)
			(xy 274.058271 -304.286292) (xy 274.081142 -304.329869) (xy 274.096726 -304.37655) (xy 274.104621 -304.425127)
			(xy 274.105116 -304.449734) (xy 274.443964 -304.449734) (xy 274.447924 -304.40068) (xy 274.459701 -304.352896)
			(xy 274.478992 -304.30762) (xy 274.505295 -304.266024) (xy 274.53793 -304.229187) (xy 274.576051 -304.198062)
			(xy 274.618672 -304.173455) (xy 274.664688 -304.156003) (xy 274.712907 -304.146159) (xy 274.762082 -304.144178)
			(xy 274.810937 -304.15011) (xy 274.858208 -304.163802) (xy 274.90267 -304.1849) (xy 274.943173 -304.212856)
			(xy 274.978666 -304.246948) (xy 275.008231 -304.286292) (xy 275.031102 -304.329869) (xy 275.046686 -304.37655)
			(xy 275.054581 -304.425127) (xy 275.055076 -304.449734) (xy 275.054581 -304.474341) (xy 275.054402 -304.475442)
			(xy 275.37308 -304.475442) (xy 275.37308 -304.424026) (xy 275.381123 -304.373244) (xy 275.397011 -304.324345)
			(xy 275.420354 -304.278533) (xy 275.450575 -304.236937) (xy 275.486931 -304.200581) (xy 275.528527 -304.17036)
			(xy 275.574339 -304.147017) (xy 275.623238 -304.131129) (xy 275.67402 -304.123086) (xy 275.725436 -304.123086)
			(xy 275.776218 -304.131129) (xy 275.825117 -304.147017) (xy 275.870929 -304.17036) (xy 275.912525 -304.200581)
			(xy 275.948881 -304.236937) (xy 275.979102 -304.278533) (xy 276.002445 -304.324345) (xy 276.018333 -304.373244)
			(xy 276.026376 -304.424026) (xy 276.02688 -304.449734) (xy 276.026376 -304.475442) (xy 276.32304 -304.475442)
			(xy 276.32304 -304.424026) (xy 276.331083 -304.373244) (xy 276.346971 -304.324345) (xy 276.370314 -304.278533)
			(xy 276.400535 -304.236937) (xy 276.436891 -304.200581) (xy 276.478487 -304.17036) (xy 276.524299 -304.147017)
			(xy 276.573198 -304.131129) (xy 276.62398 -304.123086) (xy 276.675396 -304.123086) (xy 276.726178 -304.131129)
			(xy 276.775077 -304.147017) (xy 276.820889 -304.17036) (xy 276.862485 -304.200581) (xy 276.898841 -304.236937)
			(xy 276.929062 -304.278533) (xy 276.952405 -304.324345) (xy 276.968293 -304.373244) (xy 276.976336 -304.424026)
			(xy 276.97684 -304.449734) (xy 277.294098 -304.449734) (xy 277.298058 -304.40068) (xy 277.309835 -304.352896)
			(xy 277.329126 -304.30762) (xy 277.355429 -304.266024) (xy 277.388064 -304.229187) (xy 277.426185 -304.198062)
			(xy 277.468806 -304.173455) (xy 277.514822 -304.156003) (xy 277.563041 -304.146159) (xy 277.612216 -304.144178)
			(xy 277.661071 -304.15011) (xy 277.708342 -304.163802) (xy 277.752804 -304.1849) (xy 277.793307 -304.212856)
			(xy 277.8288 -304.246948) (xy 277.858365 -304.286292) (xy 277.881236 -304.329869) (xy 277.89682 -304.37655)
			(xy 277.904715 -304.425127) (xy 277.90521 -304.449734) (xy 277.904715 -304.474341) (xy 277.89682 -304.522918)
			(xy 277.881236 -304.569599) (xy 277.858365 -304.613176) (xy 277.8288 -304.65252) (xy 277.793307 -304.686612)
			(xy 277.752804 -304.714568) (xy 277.708342 -304.735666) (xy 277.661071 -304.749358) (xy 277.612216 -304.75529)
			(xy 277.563041 -304.753309) (xy 277.514822 -304.743465) (xy 277.468806 -304.726013) (xy 277.426185 -304.701406)
			(xy 277.388064 -304.670281) (xy 277.355429 -304.633444) (xy 277.329126 -304.591848) (xy 277.309835 -304.546572)
			(xy 277.298058 -304.498788) (xy 277.294098 -304.449734) (xy 276.97684 -304.449734) (xy 276.976336 -304.475442)
			(xy 276.968293 -304.526224) (xy 276.952405 -304.575123) (xy 276.929062 -304.620935) (xy 276.898841 -304.662531)
			(xy 276.862485 -304.698887) (xy 276.820889 -304.729108) (xy 276.775077 -304.752451) (xy 276.726178 -304.768339)
			(xy 276.675396 -304.776382) (xy 276.62398 -304.776382) (xy 276.573198 -304.768339) (xy 276.524299 -304.752451)
			(xy 276.478487 -304.729108) (xy 276.436891 -304.698887) (xy 276.400535 -304.662531) (xy 276.370314 -304.620935)
			(xy 276.346971 -304.575123) (xy 276.331083 -304.526224) (xy 276.32304 -304.475442) (xy 276.026376 -304.475442)
			(xy 276.018333 -304.526224) (xy 276.002445 -304.575123) (xy 275.979102 -304.620935) (xy 275.948881 -304.662531)
			(xy 275.912525 -304.698887) (xy 275.870929 -304.729108) (xy 275.825117 -304.752451) (xy 275.776218 -304.768339)
			(xy 275.725436 -304.776382) (xy 275.67402 -304.776382) (xy 275.623238 -304.768339) (xy 275.574339 -304.752451)
			(xy 275.528527 -304.729108) (xy 275.486931 -304.698887) (xy 275.450575 -304.662531) (xy 275.420354 -304.620935)
			(xy 275.397011 -304.575123) (xy 275.381123 -304.526224) (xy 275.37308 -304.475442) (xy 275.054402 -304.475442)
			(xy 275.046686 -304.522918) (xy 275.031102 -304.569599) (xy 275.008231 -304.613176) (xy 274.978666 -304.65252)
			(xy 274.943173 -304.686612) (xy 274.90267 -304.714568) (xy 274.858208 -304.735666) (xy 274.810937 -304.749358)
			(xy 274.762082 -304.75529) (xy 274.712907 -304.753309) (xy 274.664688 -304.743465) (xy 274.618672 -304.726013)
			(xy 274.576051 -304.701406) (xy 274.53793 -304.670281) (xy 274.505295 -304.633444) (xy 274.478992 -304.591848)
			(xy 274.459701 -304.546572) (xy 274.447924 -304.498788) (xy 274.443964 -304.449734) (xy 274.105116 -304.449734)
			(xy 274.104621 -304.474341) (xy 274.096726 -304.522918) (xy 274.081142 -304.569599) (xy 274.058271 -304.613176)
			(xy 274.028706 -304.65252) (xy 273.993213 -304.686612) (xy 273.95271 -304.714568) (xy 273.908248 -304.735666)
			(xy 273.860977 -304.749358) (xy 273.812122 -304.75529) (xy 273.762947 -304.753309) (xy 273.714728 -304.743465)
			(xy 273.668712 -304.726013) (xy 273.626091 -304.701406) (xy 273.58797 -304.670281) (xy 273.555335 -304.633444)
			(xy 273.529032 -304.591848) (xy 273.509741 -304.546572) (xy 273.497964 -304.498788) (xy 273.494004 -304.449734)
			(xy 273.155156 -304.449734) (xy 273.154661 -304.474341) (xy 273.146766 -304.522918) (xy 273.131182 -304.569599)
			(xy 273.108311 -304.613176) (xy 273.078746 -304.65252) (xy 273.043253 -304.686612) (xy 273.00275 -304.714568)
			(xy 272.958288 -304.735666) (xy 272.911017 -304.749358) (xy 272.862162 -304.75529) (xy 272.812987 -304.753309)
			(xy 272.764768 -304.743465) (xy 272.718752 -304.726013) (xy 272.676131 -304.701406) (xy 272.63801 -304.670281)
			(xy 272.605375 -304.633444) (xy 272.579072 -304.591848) (xy 272.559781 -304.546572) (xy 272.548004 -304.498788)
			(xy 272.544044 -304.449734) (xy 272.205196 -304.449734) (xy 272.204701 -304.474341) (xy 272.196806 -304.522918)
			(xy 272.181222 -304.569599) (xy 272.158351 -304.613176) (xy 272.128786 -304.65252) (xy 272.093293 -304.686612)
			(xy 272.05279 -304.714568) (xy 272.008328 -304.735666) (xy 271.961057 -304.749358) (xy 271.912202 -304.75529)
			(xy 271.863027 -304.753309) (xy 271.814808 -304.743465) (xy 271.768792 -304.726013) (xy 271.726171 -304.701406)
			(xy 271.68805 -304.670281) (xy 271.655415 -304.633444) (xy 271.629112 -304.591848) (xy 271.609821 -304.546572)
			(xy 271.598044 -304.498788) (xy 271.594084 -304.449734) (xy 271.255236 -304.449734) (xy 271.254741 -304.474341)
			(xy 271.246846 -304.522918) (xy 271.231262 -304.569599) (xy 271.208391 -304.613176) (xy 271.178826 -304.65252)
			(xy 271.143333 -304.686612) (xy 271.10283 -304.714568) (xy 271.058368 -304.735666) (xy 271.011097 -304.749358)
			(xy 270.962242 -304.75529) (xy 270.913067 -304.753309) (xy 270.864848 -304.743465) (xy 270.818832 -304.726013)
			(xy 270.776211 -304.701406) (xy 270.73809 -304.670281) (xy 270.705455 -304.633444) (xy 270.679152 -304.591848)
			(xy 270.659861 -304.546572) (xy 270.648084 -304.498788) (xy 270.644124 -304.449734) (xy 270.326866 -304.449734)
			(xy 270.326362 -304.475442) (xy 270.318319 -304.526224) (xy 270.302431 -304.575123) (xy 270.279088 -304.620935)
			(xy 270.248867 -304.662531) (xy 270.212511 -304.698887) (xy 270.170915 -304.729108) (xy 270.125103 -304.752451)
			(xy 270.076204 -304.768339) (xy 270.025422 -304.776382) (xy 269.974006 -304.776382) (xy 269.923224 -304.768339)
			(xy 269.874325 -304.752451) (xy 269.828513 -304.729108) (xy 269.786917 -304.698887) (xy 269.750561 -304.662531)
			(xy 269.72034 -304.620935) (xy 269.696997 -304.575123) (xy 269.681109 -304.526224) (xy 269.673066 -304.475442)
			(xy 269.376402 -304.475442) (xy 269.368359 -304.526224) (xy 269.352471 -304.575123) (xy 269.329128 -304.620935)
			(xy 269.298907 -304.662531) (xy 269.262551 -304.698887) (xy 269.220955 -304.729108) (xy 269.175143 -304.752451)
			(xy 269.126244 -304.768339) (xy 269.075462 -304.776382) (xy 269.024046 -304.776382) (xy 268.973264 -304.768339)
			(xy 268.924365 -304.752451) (xy 268.878553 -304.729108) (xy 268.836957 -304.698887) (xy 268.800601 -304.662531)
			(xy 268.77038 -304.620935) (xy 268.747037 -304.575123) (xy 268.731149 -304.526224) (xy 268.723106 -304.475442)
			(xy 268.404215 -304.475442) (xy 268.396458 -304.523172) (xy 268.380874 -304.569853) (xy 268.358003 -304.61343)
			(xy 268.328438 -304.652774) (xy 268.292945 -304.686866) (xy 268.252442 -304.714822) (xy 268.20798 -304.73592)
			(xy 268.160709 -304.749612) (xy 268.111854 -304.755544) (xy 268.062679 -304.753563) (xy 268.01446 -304.743719)
			(xy 267.968444 -304.726267) (xy 267.925823 -304.70166) (xy 267.887702 -304.670535) (xy 267.855067 -304.633698)
			(xy 267.828764 -304.592102) (xy 267.809473 -304.546826) (xy 267.797696 -304.499042) (xy 267.793736 -304.449988)
			(xy 255.945132 -304.449988) (xy 255.945132 -304.924714) (xy 278.719038 -304.924714) (xy 278.722998 -304.87566)
			(xy 278.734775 -304.827876) (xy 278.754066 -304.7826) (xy 278.780369 -304.741004) (xy 278.813004 -304.704167)
			(xy 278.851125 -304.673042) (xy 278.893746 -304.648435) (xy 278.939762 -304.630983) (xy 278.987981 -304.621139)
			(xy 279.037156 -304.619158) (xy 279.086011 -304.62509) (xy 279.133282 -304.638782) (xy 279.177744 -304.65988)
			(xy 279.218247 -304.687836) (xy 279.25374 -304.721928) (xy 279.283305 -304.761272) (xy 279.306176 -304.804849)
			(xy 279.32176 -304.85153) (xy 279.329655 -304.900107) (xy 279.33015 -304.924714) (xy 279.329655 -304.949321)
			(xy 279.32176 -304.997898) (xy 279.306176 -305.044579) (xy 279.283305 -305.088156) (xy 279.25374 -305.1275)
			(xy 279.218247 -305.161592) (xy 279.177744 -305.189548) (xy 279.133282 -305.210646) (xy 279.086011 -305.224338)
			(xy 279.037156 -305.23027) (xy 278.987981 -305.228289) (xy 278.939762 -305.218445) (xy 278.893746 -305.200993)
			(xy 278.851125 -305.176386) (xy 278.813004 -305.145261) (xy 278.780369 -305.108424) (xy 278.754066 -305.066828)
			(xy 278.734775 -305.021552) (xy 278.722998 -304.973768) (xy 278.719038 -304.924714) (xy 255.945132 -304.924714)
			(xy 255.945132 -306.244344) (xy 258.80912 -306.244344) (xy 258.809122 -306.189831) (xy 258.816882 -306.135873)
			(xy 258.832242 -306.083569) (xy 258.85489 -306.033984) (xy 258.884365 -305.988127) (xy 258.920065 -305.946931)
			(xy 258.961266 -305.911235) (xy 259.007127 -305.881767) (xy 259.056715 -305.859125) (xy 259.109021 -305.843772)
			(xy 259.16298 -305.836018) (xy 259.190236 -305.835558) (xy 259.219446 -305.836574) (xy 259.233236 -305.837162)
			(xy 259.260291 -305.831747) (xy 259.28491 -305.81929) (xy 259.305298 -305.800699) (xy 259.319966 -305.77733)
			(xy 259.327847 -305.750888) (xy 259.328363 -305.723302) (xy 259.325364 -305.709828) (xy 259.31965 -305.686238)
			(xy 259.313536 -305.638086) (xy 259.313172 -305.613816) (xy 259.313638 -305.586561) (xy 259.321393 -305.532607)
			(xy 259.336748 -305.480305) (xy 259.35939 -305.430721) (xy 259.388859 -305.384864) (xy 259.424554 -305.343668)
			(xy 259.465748 -305.307971) (xy 259.511603 -305.2785) (xy 259.561186 -305.255855) (xy 259.613487 -305.240497)
			(xy 259.667441 -305.232739) (xy 259.721951 -305.232739) (xy 259.775905 -305.240496) (xy 259.828206 -305.255852)
			(xy 259.877789 -305.278496) (xy 259.923645 -305.307966) (xy 259.964841 -305.343662) (xy 260.000536 -305.384858)
			(xy 260.010234 -305.399948) (xy 268.74395 -305.399948) (xy 268.74791 -305.350894) (xy 268.759687 -305.30311)
			(xy 268.778978 -305.257834) (xy 268.805281 -305.216238) (xy 268.837916 -305.179401) (xy 268.876037 -305.148276)
			(xy 268.918658 -305.123669) (xy 268.964674 -305.106217) (xy 269.012893 -305.096373) (xy 269.062068 -305.094392)
			(xy 269.110923 -305.100324) (xy 269.158194 -305.114016) (xy 269.202656 -305.135114) (xy 269.243159 -305.16307)
			(xy 269.278652 -305.197162) (xy 269.308217 -305.236506) (xy 269.331088 -305.280083) (xy 269.346672 -305.326764)
			(xy 269.354567 -305.375341) (xy 269.355062 -305.399948) (xy 269.69391 -305.399948) (xy 269.69787 -305.350894)
			(xy 269.709647 -305.30311) (xy 269.728938 -305.257834) (xy 269.755241 -305.216238) (xy 269.787876 -305.179401)
			(xy 269.825997 -305.148276) (xy 269.868618 -305.123669) (xy 269.914634 -305.106217) (xy 269.962853 -305.096373)
			(xy 270.012028 -305.094392) (xy 270.060883 -305.100324) (xy 270.108154 -305.114016) (xy 270.152616 -305.135114)
			(xy 270.193119 -305.16307) (xy 270.228612 -305.197162) (xy 270.258177 -305.236506) (xy 270.281048 -305.280083)
			(xy 270.296632 -305.326764) (xy 270.304527 -305.375341) (xy 270.305022 -305.399948) (xy 270.304527 -305.424555)
			(xy 270.304348 -305.425656) (xy 270.62328 -305.425656) (xy 270.62328 -305.37424) (xy 270.631323 -305.323458)
			(xy 270.647211 -305.274559) (xy 270.670554 -305.228747) (xy 270.700775 -305.187151) (xy 270.737131 -305.150795)
			(xy 270.778727 -305.120574) (xy 270.824539 -305.097231) (xy 270.873438 -305.081343) (xy 270.92422 -305.0733)
			(xy 270.975636 -305.0733) (xy 271.026418 -305.081343) (xy 271.075317 -305.097231) (xy 271.121129 -305.120574)
			(xy 271.162725 -305.150795) (xy 271.199081 -305.187151) (xy 271.229302 -305.228747) (xy 271.252645 -305.274559)
			(xy 271.268533 -305.323458) (xy 271.276576 -305.37424) (xy 271.27708 -305.399948) (xy 271.276576 -305.425656)
			(xy 271.57324 -305.425656) (xy 271.57324 -305.37424) (xy 271.581283 -305.323458) (xy 271.597171 -305.274559)
			(xy 271.620514 -305.228747) (xy 271.650735 -305.187151) (xy 271.687091 -305.150795) (xy 271.728687 -305.120574)
			(xy 271.774499 -305.097231) (xy 271.823398 -305.081343) (xy 271.87418 -305.0733) (xy 271.925596 -305.0733)
			(xy 271.976378 -305.081343) (xy 272.025277 -305.097231) (xy 272.071089 -305.120574) (xy 272.112685 -305.150795)
			(xy 272.149041 -305.187151) (xy 272.179262 -305.228747) (xy 272.202605 -305.274559) (xy 272.218493 -305.323458)
			(xy 272.226536 -305.37424) (xy 272.22704 -305.399948) (xy 272.544044 -305.399948) (xy 272.548004 -305.350894)
			(xy 272.559781 -305.30311) (xy 272.579072 -305.257834) (xy 272.605375 -305.216238) (xy 272.63801 -305.179401)
			(xy 272.676131 -305.148276) (xy 272.718752 -305.123669) (xy 272.764768 -305.106217) (xy 272.812987 -305.096373)
			(xy 272.862162 -305.094392) (xy 272.911017 -305.100324) (xy 272.958288 -305.114016) (xy 273.00275 -305.135114)
			(xy 273.043253 -305.16307) (xy 273.078746 -305.197162) (xy 273.108311 -305.236506) (xy 273.131182 -305.280083)
			(xy 273.146766 -305.326764) (xy 273.154661 -305.375341) (xy 273.155156 -305.399948) (xy 273.154661 -305.424555)
			(xy 273.154482 -305.425656) (xy 273.47316 -305.425656) (xy 273.47316 -305.37424) (xy 273.481203 -305.323458)
			(xy 273.497091 -305.274559) (xy 273.520434 -305.228747) (xy 273.550655 -305.187151) (xy 273.587011 -305.150795)
			(xy 273.628607 -305.120574) (xy 273.674419 -305.097231) (xy 273.723318 -305.081343) (xy 273.7741 -305.0733)
			(xy 273.825516 -305.0733) (xy 273.876298 -305.081343) (xy 273.925197 -305.097231) (xy 273.971009 -305.120574)
			(xy 274.012605 -305.150795) (xy 274.048961 -305.187151) (xy 274.079182 -305.228747) (xy 274.102525 -305.274559)
			(xy 274.118413 -305.323458) (xy 274.126456 -305.37424) (xy 274.12696 -305.399948) (xy 274.126456 -305.425656)
			(xy 274.42312 -305.425656) (xy 274.42312 -305.37424) (xy 274.431163 -305.323458) (xy 274.447051 -305.274559)
			(xy 274.470394 -305.228747) (xy 274.500615 -305.187151) (xy 274.536971 -305.150795) (xy 274.578567 -305.120574)
			(xy 274.624379 -305.097231) (xy 274.673278 -305.081343) (xy 274.72406 -305.0733) (xy 274.775476 -305.0733)
			(xy 274.826258 -305.081343) (xy 274.875157 -305.097231) (xy 274.920969 -305.120574) (xy 274.962565 -305.150795)
			(xy 274.998921 -305.187151) (xy 275.029142 -305.228747) (xy 275.052485 -305.274559) (xy 275.068373 -305.323458)
			(xy 275.076416 -305.37424) (xy 275.07692 -305.399948) (xy 275.393924 -305.399948) (xy 275.397884 -305.350894)
			(xy 275.409661 -305.30311) (xy 275.428952 -305.257834) (xy 275.455255 -305.216238) (xy 275.48789 -305.179401)
			(xy 275.526011 -305.148276) (xy 275.568632 -305.123669) (xy 275.614648 -305.106217) (xy 275.662867 -305.096373)
			(xy 275.712042 -305.094392) (xy 275.760897 -305.100324) (xy 275.808168 -305.114016) (xy 275.85263 -305.135114)
			(xy 275.893133 -305.16307) (xy 275.928626 -305.197162) (xy 275.958191 -305.236506) (xy 275.981062 -305.280083)
			(xy 275.996646 -305.326764) (xy 276.004541 -305.375341) (xy 276.005036 -305.399948) (xy 276.343884 -305.399948)
			(xy 276.347844 -305.350894) (xy 276.359621 -305.30311) (xy 276.378912 -305.257834) (xy 276.405215 -305.216238)
			(xy 276.43785 -305.179401) (xy 276.475971 -305.148276) (xy 276.518592 -305.123669) (xy 276.564608 -305.106217)
			(xy 276.612827 -305.096373) (xy 276.662002 -305.094392) (xy 276.710857 -305.100324) (xy 276.758128 -305.114016)
			(xy 276.80259 -305.135114) (xy 276.843093 -305.16307) (xy 276.878586 -305.197162) (xy 276.908151 -305.236506)
			(xy 276.931022 -305.280083) (xy 276.946606 -305.326764) (xy 276.954501 -305.375341) (xy 276.954996 -305.399948)
			(xy 277.294098 -305.399948) (xy 277.298058 -305.350894) (xy 277.309835 -305.30311) (xy 277.329126 -305.257834)
			(xy 277.355429 -305.216238) (xy 277.388064 -305.179401) (xy 277.426185 -305.148276) (xy 277.468806 -305.123669)
			(xy 277.514822 -305.106217) (xy 277.563041 -305.096373) (xy 277.612216 -305.094392) (xy 277.661071 -305.100324)
			(xy 277.708342 -305.114016) (xy 277.752804 -305.135114) (xy 277.793307 -305.16307) (xy 277.8288 -305.197162)
			(xy 277.858365 -305.236506) (xy 277.881236 -305.280083) (xy 277.89682 -305.326764) (xy 277.904715 -305.375341)
			(xy 277.90521 -305.399948) (xy 277.904715 -305.424555) (xy 277.89682 -305.473132) (xy 277.881236 -305.519813)
			(xy 277.858365 -305.56339) (xy 277.8288 -305.602734) (xy 277.793307 -305.636826) (xy 277.752804 -305.664782)
			(xy 277.708342 -305.68588) (xy 277.661071 -305.699572) (xy 277.612216 -305.705504) (xy 277.563041 -305.703523)
			(xy 277.514822 -305.693679) (xy 277.468806 -305.676227) (xy 277.426185 -305.65162) (xy 277.388064 -305.620495)
			(xy 277.355429 -305.583658) (xy 277.329126 -305.542062) (xy 277.309835 -305.496786) (xy 277.298058 -305.449002)
			(xy 277.294098 -305.399948) (xy 276.954996 -305.399948) (xy 276.954501 -305.424555) (xy 276.946606 -305.473132)
			(xy 276.931022 -305.519813) (xy 276.908151 -305.56339) (xy 276.878586 -305.602734) (xy 276.843093 -305.636826)
			(xy 276.80259 -305.664782) (xy 276.758128 -305.68588) (xy 276.710857 -305.699572) (xy 276.662002 -305.705504)
			(xy 276.612827 -305.703523) (xy 276.564608 -305.693679) (xy 276.518592 -305.676227) (xy 276.475971 -305.65162)
			(xy 276.43785 -305.620495) (xy 276.405215 -305.583658) (xy 276.378912 -305.542062) (xy 276.359621 -305.496786)
			(xy 276.347844 -305.449002) (xy 276.343884 -305.399948) (xy 276.005036 -305.399948) (xy 276.004541 -305.424555)
			(xy 275.996646 -305.473132) (xy 275.981062 -305.519813) (xy 275.958191 -305.56339) (xy 275.928626 -305.602734)
			(xy 275.893133 -305.636826) (xy 275.85263 -305.664782) (xy 275.808168 -305.68588) (xy 275.760897 -305.699572)
			(xy 275.712042 -305.705504) (xy 275.662867 -305.703523) (xy 275.614648 -305.693679) (xy 275.568632 -305.676227)
			(xy 275.526011 -305.65162) (xy 275.48789 -305.620495) (xy 275.455255 -305.583658) (xy 275.428952 -305.542062)
			(xy 275.409661 -305.496786) (xy 275.397884 -305.449002) (xy 275.393924 -305.399948) (xy 275.07692 -305.399948)
			(xy 275.076416 -305.425656) (xy 275.068373 -305.476438) (xy 275.052485 -305.525337) (xy 275.029142 -305.571149)
			(xy 274.998921 -305.612745) (xy 274.962565 -305.649101) (xy 274.920969 -305.679322) (xy 274.875157 -305.702665)
			(xy 274.826258 -305.718553) (xy 274.775476 -305.726596) (xy 274.72406 -305.726596) (xy 274.673278 -305.718553)
			(xy 274.624379 -305.702665) (xy 274.578567 -305.679322) (xy 274.536971 -305.649101) (xy 274.500615 -305.612745)
			(xy 274.470394 -305.571149) (xy 274.447051 -305.525337) (xy 274.431163 -305.476438) (xy 274.42312 -305.425656)
			(xy 274.126456 -305.425656) (xy 274.118413 -305.476438) (xy 274.102525 -305.525337) (xy 274.079182 -305.571149)
			(xy 274.048961 -305.612745) (xy 274.012605 -305.649101) (xy 273.971009 -305.679322) (xy 273.925197 -305.702665)
			(xy 273.876298 -305.718553) (xy 273.825516 -305.726596) (xy 273.7741 -305.726596) (xy 273.723318 -305.718553)
			(xy 273.674419 -305.702665) (xy 273.628607 -305.679322) (xy 273.587011 -305.649101) (xy 273.550655 -305.612745)
			(xy 273.520434 -305.571149) (xy 273.497091 -305.525337) (xy 273.481203 -305.476438) (xy 273.47316 -305.425656)
			(xy 273.154482 -305.425656) (xy 273.146766 -305.473132) (xy 273.131182 -305.519813) (xy 273.108311 -305.56339)
			(xy 273.078746 -305.602734) (xy 273.043253 -305.636826) (xy 273.00275 -305.664782) (xy 272.958288 -305.68588)
			(xy 272.911017 -305.699572) (xy 272.862162 -305.705504) (xy 272.812987 -305.703523) (xy 272.764768 -305.693679)
			(xy 272.718752 -305.676227) (xy 272.676131 -305.65162) (xy 272.63801 -305.620495) (xy 272.605375 -305.583658)
			(xy 272.579072 -305.542062) (xy 272.559781 -305.496786) (xy 272.548004 -305.449002) (xy 272.544044 -305.399948)
			(xy 272.22704 -305.399948) (xy 272.226536 -305.425656) (xy 272.218493 -305.476438) (xy 272.202605 -305.525337)
			(xy 272.179262 -305.571149) (xy 272.149041 -305.612745) (xy 272.112685 -305.649101) (xy 272.071089 -305.679322)
			(xy 272.025277 -305.702665) (xy 271.976378 -305.718553) (xy 271.925596 -305.726596) (xy 271.87418 -305.726596)
			(xy 271.823398 -305.718553) (xy 271.774499 -305.702665) (xy 271.728687 -305.679322) (xy 271.687091 -305.649101)
			(xy 271.650735 -305.612745) (xy 271.620514 -305.571149) (xy 271.597171 -305.525337) (xy 271.581283 -305.476438)
			(xy 271.57324 -305.425656) (xy 271.276576 -305.425656) (xy 271.268533 -305.476438) (xy 271.252645 -305.525337)
			(xy 271.229302 -305.571149) (xy 271.199081 -305.612745) (xy 271.162725 -305.649101) (xy 271.121129 -305.679322)
			(xy 271.075317 -305.702665) (xy 271.026418 -305.718553) (xy 270.975636 -305.726596) (xy 270.92422 -305.726596)
			(xy 270.873438 -305.718553) (xy 270.824539 -305.702665) (xy 270.778727 -305.679322) (xy 270.737131 -305.649101)
			(xy 270.700775 -305.612745) (xy 270.670554 -305.571149) (xy 270.647211 -305.525337) (xy 270.631323 -305.476438)
			(xy 270.62328 -305.425656) (xy 270.304348 -305.425656) (xy 270.296632 -305.473132) (xy 270.281048 -305.519813)
			(xy 270.258177 -305.56339) (xy 270.228612 -305.602734) (xy 270.193119 -305.636826) (xy 270.152616 -305.664782)
			(xy 270.108154 -305.68588) (xy 270.060883 -305.699572) (xy 270.012028 -305.705504) (xy 269.962853 -305.703523)
			(xy 269.914634 -305.693679) (xy 269.868618 -305.676227) (xy 269.825997 -305.65162) (xy 269.787876 -305.620495)
			(xy 269.755241 -305.583658) (xy 269.728938 -305.542062) (xy 269.709647 -305.496786) (xy 269.69787 -305.449002)
			(xy 269.69391 -305.399948) (xy 269.355062 -305.399948) (xy 269.354567 -305.424555) (xy 269.346672 -305.473132)
			(xy 269.331088 -305.519813) (xy 269.308217 -305.56339) (xy 269.278652 -305.602734) (xy 269.243159 -305.636826)
			(xy 269.202656 -305.664782) (xy 269.158194 -305.68588) (xy 269.110923 -305.699572) (xy 269.062068 -305.705504)
			(xy 269.012893 -305.703523) (xy 268.964674 -305.693679) (xy 268.918658 -305.676227) (xy 268.876037 -305.65162)
			(xy 268.837916 -305.620495) (xy 268.805281 -305.583658) (xy 268.778978 -305.542062) (xy 268.759687 -305.496786)
			(xy 268.74791 -305.449002) (xy 268.74395 -305.399948) (xy 260.010234 -305.399948) (xy 260.030006 -305.430714)
			(xy 260.052649 -305.480298) (xy 260.068005 -305.532599) (xy 260.075762 -305.586553) (xy 260.075761 -305.641063)
			(xy 260.068002 -305.695017) (xy 260.052643 -305.747317) (xy 260.029998 -305.7969) (xy 260.000527 -305.842755)
			(xy 259.972646 -305.874928) (xy 278.719038 -305.874928) (xy 278.722998 -305.825874) (xy 278.734775 -305.77809)
			(xy 278.754066 -305.732814) (xy 278.780369 -305.691218) (xy 278.813004 -305.654381) (xy 278.851125 -305.623256)
			(xy 278.893746 -305.598649) (xy 278.939762 -305.581197) (xy 278.987981 -305.571353) (xy 279.037156 -305.569372)
			(xy 279.086011 -305.575304) (xy 279.133282 -305.588996) (xy 279.177744 -305.610094) (xy 279.218247 -305.63805)
			(xy 279.25374 -305.672142) (xy 279.283305 -305.711486) (xy 279.306176 -305.755063) (xy 279.32176 -305.801744)
			(xy 279.329655 -305.850321) (xy 279.33015 -305.874928) (xy 279.668998 -305.874928) (xy 279.672958 -305.825874)
			(xy 279.684735 -305.77809) (xy 279.704026 -305.732814) (xy 279.730329 -305.691218) (xy 279.762964 -305.654381)
			(xy 279.801085 -305.623256) (xy 279.843706 -305.598649) (xy 279.889722 -305.581197) (xy 279.937941 -305.571353)
			(xy 279.987116 -305.569372) (xy 280.035971 -305.575304) (xy 280.083242 -305.588996) (xy 280.127704 -305.610094)
			(xy 280.168207 -305.63805) (xy 280.2037 -305.672142) (xy 280.233265 -305.711486) (xy 280.256136 -305.755063)
			(xy 280.27172 -305.801744) (xy 280.279615 -305.850321) (xy 280.28011 -305.874928) (xy 280.618958 -305.874928)
			(xy 280.622918 -305.825874) (xy 280.634695 -305.77809) (xy 280.653986 -305.732814) (xy 280.680289 -305.691218)
			(xy 280.712924 -305.654381) (xy 280.751045 -305.623256) (xy 280.793666 -305.598649) (xy 280.839682 -305.581197)
			(xy 280.887901 -305.571353) (xy 280.937076 -305.569372) (xy 280.985931 -305.575304) (xy 281.033202 -305.588996)
			(xy 281.077664 -305.610094) (xy 281.118167 -305.63805) (xy 281.15366 -305.672142) (xy 281.183225 -305.711486)
			(xy 281.206096 -305.755063) (xy 281.22168 -305.801744) (xy 281.229575 -305.850321) (xy 281.23007 -305.874928)
			(xy 281.568918 -305.874928) (xy 281.572878 -305.825874) (xy 281.584655 -305.77809) (xy 281.603946 -305.732814)
			(xy 281.630249 -305.691218) (xy 281.662884 -305.654381) (xy 281.701005 -305.623256) (xy 281.743626 -305.598649)
			(xy 281.789642 -305.581197) (xy 281.837861 -305.571353) (xy 281.887036 -305.569372) (xy 281.935891 -305.575304)
			(xy 281.983162 -305.588996) (xy 282.027624 -305.610094) (xy 282.068127 -305.63805) (xy 282.10362 -305.672142)
			(xy 282.133185 -305.711486) (xy 282.156056 -305.755063) (xy 282.17164 -305.801744) (xy 282.179535 -305.850321)
			(xy 282.18003 -305.874928) (xy 282.519132 -305.874928) (xy 282.523092 -305.825874) (xy 282.534869 -305.77809)
			(xy 282.55416 -305.732814) (xy 282.580463 -305.691218) (xy 282.613098 -305.654381) (xy 282.651219 -305.623256)
			(xy 282.69384 -305.598649) (xy 282.739856 -305.581197) (xy 282.788075 -305.571353) (xy 282.83725 -305.569372)
			(xy 282.886105 -305.575304) (xy 282.933376 -305.588996) (xy 282.977838 -305.610094) (xy 283.018341 -305.63805)
			(xy 283.053834 -305.672142) (xy 283.083399 -305.711486) (xy 283.10627 -305.755063) (xy 283.121854 -305.801744)
			(xy 283.129749 -305.850321) (xy 283.130244 -305.874928) (xy 283.469092 -305.874928) (xy 283.473052 -305.825874)
			(xy 283.484829 -305.77809) (xy 283.50412 -305.732814) (xy 283.530423 -305.691218) (xy 283.563058 -305.654381)
			(xy 283.601179 -305.623256) (xy 283.6438 -305.598649) (xy 283.689816 -305.581197) (xy 283.738035 -305.571353)
			(xy 283.78721 -305.569372) (xy 283.836065 -305.575304) (xy 283.883336 -305.588996) (xy 283.927798 -305.610094)
			(xy 283.968301 -305.63805) (xy 284.003794 -305.672142) (xy 284.033359 -305.711486) (xy 284.05623 -305.755063)
			(xy 284.071814 -305.801744) (xy 284.079709 -305.850321) (xy 284.080204 -305.874928) (xy 284.419052 -305.874928)
			(xy 284.423012 -305.825874) (xy 284.434789 -305.77809) (xy 284.45408 -305.732814) (xy 284.480383 -305.691218)
			(xy 284.513018 -305.654381) (xy 284.551139 -305.623256) (xy 284.59376 -305.598649) (xy 284.639776 -305.581197)
			(xy 284.687995 -305.571353) (xy 284.73717 -305.569372) (xy 284.786025 -305.575304) (xy 284.833296 -305.588996)
			(xy 284.877758 -305.610094) (xy 284.918261 -305.63805) (xy 284.953754 -305.672142) (xy 284.983319 -305.711486)
			(xy 285.00619 -305.755063) (xy 285.021774 -305.801744) (xy 285.029669 -305.850321) (xy 285.030164 -305.874928)
			(xy 285.369012 -305.874928) (xy 285.372972 -305.825874) (xy 285.384749 -305.77809) (xy 285.40404 -305.732814)
			(xy 285.430343 -305.691218) (xy 285.462978 -305.654381) (xy 285.501099 -305.623256) (xy 285.54372 -305.598649)
			(xy 285.589736 -305.581197) (xy 285.637955 -305.571353) (xy 285.68713 -305.569372) (xy 285.735985 -305.575304)
			(xy 285.783256 -305.588996) (xy 285.827718 -305.610094) (xy 285.868221 -305.63805) (xy 285.903714 -305.672142)
			(xy 285.933279 -305.711486) (xy 285.95615 -305.755063) (xy 285.971734 -305.801744) (xy 285.979629 -305.850321)
			(xy 285.980124 -305.874928) (xy 286.318972 -305.874928) (xy 286.322932 -305.825874) (xy 286.334709 -305.77809)
			(xy 286.354 -305.732814) (xy 286.380303 -305.691218) (xy 286.412938 -305.654381) (xy 286.451059 -305.623256)
			(xy 286.49368 -305.598649) (xy 286.539696 -305.581197) (xy 286.587915 -305.571353) (xy 286.63709 -305.569372)
			(xy 286.685945 -305.575304) (xy 286.733216 -305.588996) (xy 286.777678 -305.610094) (xy 286.818181 -305.63805)
			(xy 286.853674 -305.672142) (xy 286.883239 -305.711486) (xy 286.90611 -305.755063) (xy 286.921694 -305.801744)
			(xy 286.929589 -305.850321) (xy 286.930084 -305.874928) (xy 287.268932 -305.874928) (xy 287.272892 -305.825874)
			(xy 287.284669 -305.77809) (xy 287.30396 -305.732814) (xy 287.330263 -305.691218) (xy 287.362898 -305.654381)
			(xy 287.401019 -305.623256) (xy 287.44364 -305.598649) (xy 287.489656 -305.581197) (xy 287.537875 -305.571353)
			(xy 287.58705 -305.569372) (xy 287.635905 -305.575304) (xy 287.683176 -305.588996) (xy 287.727638 -305.610094)
			(xy 287.768141 -305.63805) (xy 287.803634 -305.672142) (xy 287.833199 -305.711486) (xy 287.85607 -305.755063)
			(xy 287.871654 -305.801744) (xy 287.879549 -305.850321) (xy 287.880044 -305.874928) (xy 288.218892 -305.874928)
			(xy 288.222852 -305.825874) (xy 288.234629 -305.77809) (xy 288.25392 -305.732814) (xy 288.280223 -305.691218)
			(xy 288.312858 -305.654381) (xy 288.350979 -305.623256) (xy 288.3936 -305.598649) (xy 288.439616 -305.581197)
			(xy 288.487835 -305.571353) (xy 288.53701 -305.569372) (xy 288.585865 -305.575304) (xy 288.633136 -305.588996)
			(xy 288.677598 -305.610094) (xy 288.718101 -305.63805) (xy 288.753594 -305.672142) (xy 288.783159 -305.711486)
			(xy 288.80603 -305.755063) (xy 288.821614 -305.801744) (xy 288.829509 -305.850321) (xy 288.830004 -305.874928)
			(xy 289.169106 -305.874928) (xy 289.173066 -305.825874) (xy 289.184843 -305.77809) (xy 289.204134 -305.732814)
			(xy 289.230437 -305.691218) (xy 289.263072 -305.654381) (xy 289.301193 -305.623256) (xy 289.343814 -305.598649)
			(xy 289.38983 -305.581197) (xy 289.438049 -305.571353) (xy 289.487224 -305.569372) (xy 289.536079 -305.575304)
			(xy 289.58335 -305.588996) (xy 289.627812 -305.610094) (xy 289.668315 -305.63805) (xy 289.703808 -305.672142)
			(xy 289.733373 -305.711486) (xy 289.756244 -305.755063) (xy 289.771828 -305.801744) (xy 289.779723 -305.850321)
			(xy 289.780218 -305.874928) (xy 290.119066 -305.874928) (xy 290.123026 -305.825874) (xy 290.134803 -305.77809)
			(xy 290.154094 -305.732814) (xy 290.180397 -305.691218) (xy 290.213032 -305.654381) (xy 290.251153 -305.623256)
			(xy 290.293774 -305.598649) (xy 290.33979 -305.581197) (xy 290.388009 -305.571353) (xy 290.437184 -305.569372)
			(xy 290.486039 -305.575304) (xy 290.53331 -305.588996) (xy 290.577772 -305.610094) (xy 290.618275 -305.63805)
			(xy 290.653768 -305.672142) (xy 290.683333 -305.711486) (xy 290.706204 -305.755063) (xy 290.721788 -305.801744)
			(xy 290.729683 -305.850321) (xy 290.730178 -305.874928) (xy 292.018986 -305.874928) (xy 292.022946 -305.825874)
			(xy 292.034723 -305.77809) (xy 292.054014 -305.732814) (xy 292.080317 -305.691218) (xy 292.112952 -305.654381)
			(xy 292.151073 -305.623256) (xy 292.193694 -305.598649) (xy 292.23971 -305.581197) (xy 292.287929 -305.571353)
			(xy 292.337104 -305.569372) (xy 292.385959 -305.575304) (xy 292.43323 -305.588996) (xy 292.477692 -305.610094)
			(xy 292.518195 -305.63805) (xy 292.553688 -305.672142) (xy 292.583253 -305.711486) (xy 292.606124 -305.755063)
			(xy 292.621708 -305.801744) (xy 292.629603 -305.850321) (xy 292.630098 -305.874928) (xy 292.968946 -305.874928)
			(xy 292.972906 -305.825874) (xy 292.984683 -305.77809) (xy 293.003974 -305.732814) (xy 293.030277 -305.691218)
			(xy 293.062912 -305.654381) (xy 293.101033 -305.623256) (xy 293.143654 -305.598649) (xy 293.18967 -305.581197)
			(xy 293.237889 -305.571353) (xy 293.287064 -305.569372) (xy 293.335919 -305.575304) (xy 293.38319 -305.588996)
			(xy 293.427652 -305.610094) (xy 293.468155 -305.63805) (xy 293.503648 -305.672142) (xy 293.533213 -305.711486)
			(xy 293.556084 -305.755063) (xy 293.571668 -305.801744) (xy 293.579563 -305.850321) (xy 293.580058 -305.874928)
			(xy 293.918906 -305.874928) (xy 293.922866 -305.825874) (xy 293.934643 -305.77809) (xy 293.953934 -305.732814)
			(xy 293.980237 -305.691218) (xy 294.012872 -305.654381) (xy 294.050993 -305.623256) (xy 294.093614 -305.598649)
			(xy 294.13963 -305.581197) (xy 294.187849 -305.571353) (xy 294.237024 -305.569372) (xy 294.285879 -305.575304)
			(xy 294.33315 -305.588996) (xy 294.377612 -305.610094) (xy 294.418115 -305.63805) (xy 294.453608 -305.672142)
			(xy 294.483173 -305.711486) (xy 294.506044 -305.755063) (xy 294.521628 -305.801744) (xy 294.529523 -305.850321)
			(xy 294.530018 -305.874928) (xy 294.86912 -305.874928) (xy 294.87308 -305.825874) (xy 294.884857 -305.77809)
			(xy 294.904148 -305.732814) (xy 294.930451 -305.691218) (xy 294.963086 -305.654381) (xy 295.001207 -305.623256)
			(xy 295.043828 -305.598649) (xy 295.089844 -305.581197) (xy 295.138063 -305.571353) (xy 295.187238 -305.569372)
			(xy 295.236093 -305.575304) (xy 295.283364 -305.588996) (xy 295.327826 -305.610094) (xy 295.368329 -305.63805)
			(xy 295.403822 -305.672142) (xy 295.433387 -305.711486) (xy 295.456258 -305.755063) (xy 295.471842 -305.801744)
			(xy 295.479737 -305.850321) (xy 295.480232 -305.874928) (xy 295.81908 -305.874928) (xy 295.82304 -305.825874)
			(xy 295.834817 -305.77809) (xy 295.854108 -305.732814) (xy 295.880411 -305.691218) (xy 295.913046 -305.654381)
			(xy 295.951167 -305.623256) (xy 295.993788 -305.598649) (xy 296.039804 -305.581197) (xy 296.088023 -305.571353)
			(xy 296.137198 -305.569372) (xy 296.186053 -305.575304) (xy 296.233324 -305.588996) (xy 296.277786 -305.610094)
			(xy 296.318289 -305.63805) (xy 296.353782 -305.672142) (xy 296.383347 -305.711486) (xy 296.406218 -305.755063)
			(xy 296.421802 -305.801744) (xy 296.429697 -305.850321) (xy 296.430192 -305.874928) (xy 296.76904 -305.874928)
			(xy 296.773 -305.825874) (xy 296.784777 -305.77809) (xy 296.804068 -305.732814) (xy 296.830371 -305.691218)
			(xy 296.863006 -305.654381) (xy 296.901127 -305.623256) (xy 296.943748 -305.598649) (xy 296.989764 -305.581197)
			(xy 297.037983 -305.571353) (xy 297.087158 -305.569372) (xy 297.136013 -305.575304) (xy 297.183284 -305.588996)
			(xy 297.227746 -305.610094) (xy 297.268249 -305.63805) (xy 297.303742 -305.672142) (xy 297.333307 -305.711486)
			(xy 297.356178 -305.755063) (xy 297.371762 -305.801744) (xy 297.379657 -305.850321) (xy 297.380152 -305.874928)
			(xy 297.719 -305.874928) (xy 297.72296 -305.825874) (xy 297.734737 -305.77809) (xy 297.754028 -305.732814)
			(xy 297.780331 -305.691218) (xy 297.812966 -305.654381) (xy 297.851087 -305.623256) (xy 297.893708 -305.598649)
			(xy 297.939724 -305.581197) (xy 297.987943 -305.571353) (xy 298.037118 -305.569372) (xy 298.085973 -305.575304)
			(xy 298.133244 -305.588996) (xy 298.177706 -305.610094) (xy 298.218209 -305.63805) (xy 298.253702 -305.672142)
			(xy 298.283267 -305.711486) (xy 298.306138 -305.755063) (xy 298.321722 -305.801744) (xy 298.329617 -305.850321)
			(xy 298.330112 -305.874928) (xy 298.66896 -305.874928) (xy 298.67292 -305.825874) (xy 298.684697 -305.77809)
			(xy 298.703988 -305.732814) (xy 298.730291 -305.691218) (xy 298.762926 -305.654381) (xy 298.801047 -305.623256)
			(xy 298.843668 -305.598649) (xy 298.889684 -305.581197) (xy 298.937903 -305.571353) (xy 298.987078 -305.569372)
			(xy 299.035933 -305.575304) (xy 299.083204 -305.588996) (xy 299.127666 -305.610094) (xy 299.168169 -305.63805)
			(xy 299.203662 -305.672142) (xy 299.233227 -305.711486) (xy 299.256098 -305.755063) (xy 299.271682 -305.801744)
			(xy 299.279577 -305.850321) (xy 299.280072 -305.874928) (xy 299.61892 -305.874928) (xy 299.62288 -305.825874)
			(xy 299.634657 -305.77809) (xy 299.653948 -305.732814) (xy 299.680251 -305.691218) (xy 299.712886 -305.654381)
			(xy 299.751007 -305.623256) (xy 299.793628 -305.598649) (xy 299.839644 -305.581197) (xy 299.887863 -305.571353)
			(xy 299.937038 -305.569372) (xy 299.985893 -305.575304) (xy 300.033164 -305.588996) (xy 300.077626 -305.610094)
			(xy 300.118129 -305.63805) (xy 300.153622 -305.672142) (xy 300.183187 -305.711486) (xy 300.206058 -305.755063)
			(xy 300.221642 -305.801744) (xy 300.229537 -305.850321) (xy 300.230032 -305.874928) (xy 300.229537 -305.899535)
			(xy 300.221642 -305.948112) (xy 300.206058 -305.994793) (xy 300.183187 -306.03837) (xy 300.153622 -306.077714)
			(xy 300.118129 -306.111806) (xy 300.077626 -306.139762) (xy 300.033164 -306.16086) (xy 299.985893 -306.174552)
			(xy 299.937038 -306.180484) (xy 299.887863 -306.178503) (xy 299.839644 -306.168659) (xy 299.793628 -306.151207)
			(xy 299.751007 -306.1266) (xy 299.712886 -306.095475) (xy 299.680251 -306.058638) (xy 299.653948 -306.017042)
			(xy 299.634657 -305.971766) (xy 299.62288 -305.923982) (xy 299.61892 -305.874928) (xy 299.280072 -305.874928)
			(xy 299.279577 -305.899535) (xy 299.271682 -305.948112) (xy 299.256098 -305.994793) (xy 299.233227 -306.03837)
			(xy 299.203662 -306.077714) (xy 299.168169 -306.111806) (xy 299.127666 -306.139762) (xy 299.083204 -306.16086)
			(xy 299.035933 -306.174552) (xy 298.987078 -306.180484) (xy 298.937903 -306.178503) (xy 298.889684 -306.168659)
			(xy 298.843668 -306.151207) (xy 298.801047 -306.1266) (xy 298.762926 -306.095475) (xy 298.730291 -306.058638)
			(xy 298.703988 -306.017042) (xy 298.684697 -305.971766) (xy 298.67292 -305.923982) (xy 298.66896 -305.874928)
			(xy 298.330112 -305.874928) (xy 298.329617 -305.899535) (xy 298.321722 -305.948112) (xy 298.306138 -305.994793)
			(xy 298.283267 -306.03837) (xy 298.253702 -306.077714) (xy 298.218209 -306.111806) (xy 298.177706 -306.139762)
			(xy 298.133244 -306.16086) (xy 298.085973 -306.174552) (xy 298.037118 -306.180484) (xy 297.987943 -306.178503)
			(xy 297.939724 -306.168659) (xy 297.893708 -306.151207) (xy 297.851087 -306.1266) (xy 297.812966 -306.095475)
			(xy 297.780331 -306.058638) (xy 297.754028 -306.017042) (xy 297.734737 -305.971766) (xy 297.72296 -305.923982)
			(xy 297.719 -305.874928) (xy 297.380152 -305.874928) (xy 297.379657 -305.899535) (xy 297.371762 -305.948112)
			(xy 297.356178 -305.994793) (xy 297.333307 -306.03837) (xy 297.303742 -306.077714) (xy 297.268249 -306.111806)
			(xy 297.227746 -306.139762) (xy 297.183284 -306.16086) (xy 297.136013 -306.174552) (xy 297.087158 -306.180484)
			(xy 297.037983 -306.178503) (xy 296.989764 -306.168659) (xy 296.943748 -306.151207) (xy 296.901127 -306.1266)
			(xy 296.863006 -306.095475) (xy 296.830371 -306.058638) (xy 296.804068 -306.017042) (xy 296.784777 -305.971766)
			(xy 296.773 -305.923982) (xy 296.76904 -305.874928) (xy 296.430192 -305.874928) (xy 296.429697 -305.899535)
			(xy 296.421802 -305.948112) (xy 296.406218 -305.994793) (xy 296.383347 -306.03837) (xy 296.353782 -306.077714)
			(xy 296.318289 -306.111806) (xy 296.277786 -306.139762) (xy 296.233324 -306.16086) (xy 296.186053 -306.174552)
			(xy 296.137198 -306.180484) (xy 296.088023 -306.178503) (xy 296.039804 -306.168659) (xy 295.993788 -306.151207)
			(xy 295.951167 -306.1266) (xy 295.913046 -306.095475) (xy 295.880411 -306.058638) (xy 295.854108 -306.017042)
			(xy 295.834817 -305.971766) (xy 295.82304 -305.923982) (xy 295.81908 -305.874928) (xy 295.480232 -305.874928)
			(xy 295.479737 -305.899535) (xy 295.471842 -305.948112) (xy 295.456258 -305.994793) (xy 295.433387 -306.03837)
			(xy 295.403822 -306.077714) (xy 295.368329 -306.111806) (xy 295.327826 -306.139762) (xy 295.283364 -306.16086)
			(xy 295.236093 -306.174552) (xy 295.187238 -306.180484) (xy 295.138063 -306.178503) (xy 295.089844 -306.168659)
			(xy 295.043828 -306.151207) (xy 295.001207 -306.1266) (xy 294.963086 -306.095475) (xy 294.930451 -306.058638)
			(xy 294.904148 -306.017042) (xy 294.884857 -305.971766) (xy 294.87308 -305.923982) (xy 294.86912 -305.874928)
			(xy 294.530018 -305.874928) (xy 294.529523 -305.899535) (xy 294.521628 -305.948112) (xy 294.506044 -305.994793)
			(xy 294.483173 -306.03837) (xy 294.453608 -306.077714) (xy 294.418115 -306.111806) (xy 294.377612 -306.139762)
			(xy 294.33315 -306.16086) (xy 294.285879 -306.174552) (xy 294.237024 -306.180484) (xy 294.187849 -306.178503)
			(xy 294.13963 -306.168659) (xy 294.093614 -306.151207) (xy 294.050993 -306.1266) (xy 294.012872 -306.095475)
			(xy 293.980237 -306.058638) (xy 293.953934 -306.017042) (xy 293.934643 -305.971766) (xy 293.922866 -305.923982)
			(xy 293.918906 -305.874928) (xy 293.580058 -305.874928) (xy 293.579563 -305.899535) (xy 293.571668 -305.948112)
			(xy 293.556084 -305.994793) (xy 293.533213 -306.03837) (xy 293.503648 -306.077714) (xy 293.468155 -306.111806)
			(xy 293.427652 -306.139762) (xy 293.38319 -306.16086) (xy 293.335919 -306.174552) (xy 293.287064 -306.180484)
			(xy 293.237889 -306.178503) (xy 293.18967 -306.168659) (xy 293.143654 -306.151207) (xy 293.101033 -306.1266)
			(xy 293.062912 -306.095475) (xy 293.030277 -306.058638) (xy 293.003974 -306.017042) (xy 292.984683 -305.971766)
			(xy 292.972906 -305.923982) (xy 292.968946 -305.874928) (xy 292.630098 -305.874928) (xy 292.629603 -305.899535)
			(xy 292.621708 -305.948112) (xy 292.606124 -305.994793) (xy 292.583253 -306.03837) (xy 292.553688 -306.077714)
			(xy 292.518195 -306.111806) (xy 292.477692 -306.139762) (xy 292.43323 -306.16086) (xy 292.385959 -306.174552)
			(xy 292.337104 -306.180484) (xy 292.287929 -306.178503) (xy 292.23971 -306.168659) (xy 292.193694 -306.151207)
			(xy 292.151073 -306.1266) (xy 292.112952 -306.095475) (xy 292.080317 -306.058638) (xy 292.054014 -306.017042)
			(xy 292.034723 -305.971766) (xy 292.022946 -305.923982) (xy 292.018986 -305.874928) (xy 290.730178 -305.874928)
			(xy 290.729683 -305.899535) (xy 290.721788 -305.948112) (xy 290.706204 -305.994793) (xy 290.683333 -306.03837)
			(xy 290.653768 -306.077714) (xy 290.618275 -306.111806) (xy 290.577772 -306.139762) (xy 290.53331 -306.16086)
			(xy 290.486039 -306.174552) (xy 290.437184 -306.180484) (xy 290.388009 -306.178503) (xy 290.33979 -306.168659)
			(xy 290.293774 -306.151207) (xy 290.251153 -306.1266) (xy 290.213032 -306.095475) (xy 290.180397 -306.058638)
			(xy 290.154094 -306.017042) (xy 290.134803 -305.971766) (xy 290.123026 -305.923982) (xy 290.119066 -305.874928)
			(xy 289.780218 -305.874928) (xy 289.779723 -305.899535) (xy 289.771828 -305.948112) (xy 289.756244 -305.994793)
			(xy 289.733373 -306.03837) (xy 289.703808 -306.077714) (xy 289.668315 -306.111806) (xy 289.627812 -306.139762)
			(xy 289.58335 -306.16086) (xy 289.536079 -306.174552) (xy 289.487224 -306.180484) (xy 289.438049 -306.178503)
			(xy 289.38983 -306.168659) (xy 289.343814 -306.151207) (xy 289.301193 -306.1266) (xy 289.263072 -306.095475)
			(xy 289.230437 -306.058638) (xy 289.204134 -306.017042) (xy 289.184843 -305.971766) (xy 289.173066 -305.923982)
			(xy 289.169106 -305.874928) (xy 288.830004 -305.874928) (xy 288.829509 -305.899535) (xy 288.821614 -305.948112)
			(xy 288.80603 -305.994793) (xy 288.783159 -306.03837) (xy 288.753594 -306.077714) (xy 288.718101 -306.111806)
			(xy 288.677598 -306.139762) (xy 288.633136 -306.16086) (xy 288.585865 -306.174552) (xy 288.53701 -306.180484)
			(xy 288.487835 -306.178503) (xy 288.439616 -306.168659) (xy 288.3936 -306.151207) (xy 288.350979 -306.1266)
			(xy 288.312858 -306.095475) (xy 288.280223 -306.058638) (xy 288.25392 -306.017042) (xy 288.234629 -305.971766)
			(xy 288.222852 -305.923982) (xy 288.218892 -305.874928) (xy 287.880044 -305.874928) (xy 287.879549 -305.899535)
			(xy 287.871654 -305.948112) (xy 287.85607 -305.994793) (xy 287.833199 -306.03837) (xy 287.803634 -306.077714)
			(xy 287.768141 -306.111806) (xy 287.727638 -306.139762) (xy 287.683176 -306.16086) (xy 287.635905 -306.174552)
			(xy 287.58705 -306.180484) (xy 287.537875 -306.178503) (xy 287.489656 -306.168659) (xy 287.44364 -306.151207)
			(xy 287.401019 -306.1266) (xy 287.362898 -306.095475) (xy 287.330263 -306.058638) (xy 287.30396 -306.017042)
			(xy 287.284669 -305.971766) (xy 287.272892 -305.923982) (xy 287.268932 -305.874928) (xy 286.930084 -305.874928)
			(xy 286.929589 -305.899535) (xy 286.921694 -305.948112) (xy 286.90611 -305.994793) (xy 286.883239 -306.03837)
			(xy 286.853674 -306.077714) (xy 286.818181 -306.111806) (xy 286.777678 -306.139762) (xy 286.733216 -306.16086)
			(xy 286.685945 -306.174552) (xy 286.63709 -306.180484) (xy 286.587915 -306.178503) (xy 286.539696 -306.168659)
			(xy 286.49368 -306.151207) (xy 286.451059 -306.1266) (xy 286.412938 -306.095475) (xy 286.380303 -306.058638)
			(xy 286.354 -306.017042) (xy 286.334709 -305.971766) (xy 286.322932 -305.923982) (xy 286.318972 -305.874928)
			(xy 285.980124 -305.874928) (xy 285.979629 -305.899535) (xy 285.971734 -305.948112) (xy 285.95615 -305.994793)
			(xy 285.933279 -306.03837) (xy 285.903714 -306.077714) (xy 285.868221 -306.111806) (xy 285.827718 -306.139762)
			(xy 285.783256 -306.16086) (xy 285.735985 -306.174552) (xy 285.68713 -306.180484) (xy 285.637955 -306.178503)
			(xy 285.589736 -306.168659) (xy 285.54372 -306.151207) (xy 285.501099 -306.1266) (xy 285.462978 -306.095475)
			(xy 285.430343 -306.058638) (xy 285.40404 -306.017042) (xy 285.384749 -305.971766) (xy 285.372972 -305.923982)
			(xy 285.369012 -305.874928) (xy 285.030164 -305.874928) (xy 285.029669 -305.899535) (xy 285.021774 -305.948112)
			(xy 285.00619 -305.994793) (xy 284.983319 -306.03837) (xy 284.953754 -306.077714) (xy 284.918261 -306.111806)
			(xy 284.877758 -306.139762) (xy 284.833296 -306.16086) (xy 284.786025 -306.174552) (xy 284.73717 -306.180484)
			(xy 284.687995 -306.178503) (xy 284.639776 -306.168659) (xy 284.59376 -306.151207) (xy 284.551139 -306.1266)
			(xy 284.513018 -306.095475) (xy 284.480383 -306.058638) (xy 284.45408 -306.017042) (xy 284.434789 -305.971766)
			(xy 284.423012 -305.923982) (xy 284.419052 -305.874928) (xy 284.080204 -305.874928) (xy 284.079709 -305.899535)
			(xy 284.071814 -305.948112) (xy 284.05623 -305.994793) (xy 284.033359 -306.03837) (xy 284.003794 -306.077714)
			(xy 283.968301 -306.111806) (xy 283.927798 -306.139762) (xy 283.883336 -306.16086) (xy 283.836065 -306.174552)
			(xy 283.78721 -306.180484) (xy 283.738035 -306.178503) (xy 283.689816 -306.168659) (xy 283.6438 -306.151207)
			(xy 283.601179 -306.1266) (xy 283.563058 -306.095475) (xy 283.530423 -306.058638) (xy 283.50412 -306.017042)
			(xy 283.484829 -305.971766) (xy 283.473052 -305.923982) (xy 283.469092 -305.874928) (xy 283.130244 -305.874928)
			(xy 283.129749 -305.899535) (xy 283.121854 -305.948112) (xy 283.10627 -305.994793) (xy 283.083399 -306.03837)
			(xy 283.053834 -306.077714) (xy 283.018341 -306.111806) (xy 282.977838 -306.139762) (xy 282.933376 -306.16086)
			(xy 282.886105 -306.174552) (xy 282.83725 -306.180484) (xy 282.788075 -306.178503) (xy 282.739856 -306.168659)
			(xy 282.69384 -306.151207) (xy 282.651219 -306.1266) (xy 282.613098 -306.095475) (xy 282.580463 -306.058638)
			(xy 282.55416 -306.017042) (xy 282.534869 -305.971766) (xy 282.523092 -305.923982) (xy 282.519132 -305.874928)
			(xy 282.18003 -305.874928) (xy 282.179535 -305.899535) (xy 282.17164 -305.948112) (xy 282.156056 -305.994793)
			(xy 282.133185 -306.03837) (xy 282.10362 -306.077714) (xy 282.068127 -306.111806) (xy 282.027624 -306.139762)
			(xy 281.983162 -306.16086) (xy 281.935891 -306.174552) (xy 281.887036 -306.180484) (xy 281.837861 -306.178503)
			(xy 281.789642 -306.168659) (xy 281.743626 -306.151207) (xy 281.701005 -306.1266) (xy 281.662884 -306.095475)
			(xy 281.630249 -306.058638) (xy 281.603946 -306.017042) (xy 281.584655 -305.971766) (xy 281.572878 -305.923982)
			(xy 281.568918 -305.874928) (xy 281.23007 -305.874928) (xy 281.229575 -305.899535) (xy 281.22168 -305.948112)
			(xy 281.206096 -305.994793) (xy 281.183225 -306.03837) (xy 281.15366 -306.077714) (xy 281.118167 -306.111806)
			(xy 281.077664 -306.139762) (xy 281.033202 -306.16086) (xy 280.985931 -306.174552) (xy 280.937076 -306.180484)
			(xy 280.887901 -306.178503) (xy 280.839682 -306.168659) (xy 280.793666 -306.151207) (xy 280.751045 -306.1266)
			(xy 280.712924 -306.095475) (xy 280.680289 -306.058638) (xy 280.653986 -306.017042) (xy 280.634695 -305.971766)
			(xy 280.622918 -305.923982) (xy 280.618958 -305.874928) (xy 280.28011 -305.874928) (xy 280.279615 -305.899535)
			(xy 280.27172 -305.948112) (xy 280.256136 -305.994793) (xy 280.233265 -306.03837) (xy 280.2037 -306.077714)
			(xy 280.168207 -306.111806) (xy 280.127704 -306.139762) (xy 280.083242 -306.16086) (xy 280.035971 -306.174552)
			(xy 279.987116 -306.180484) (xy 279.937941 -306.178503) (xy 279.889722 -306.168659) (xy 279.843706 -306.151207)
			(xy 279.801085 -306.1266) (xy 279.762964 -306.095475) (xy 279.730329 -306.058638) (xy 279.704026 -306.017042)
			(xy 279.684735 -305.971766) (xy 279.672958 -305.923982) (xy 279.668998 -305.874928) (xy 279.33015 -305.874928)
			(xy 279.329655 -305.899535) (xy 279.32176 -305.948112) (xy 279.306176 -305.994793) (xy 279.283305 -306.03837)
			(xy 279.25374 -306.077714) (xy 279.218247 -306.111806) (xy 279.177744 -306.139762) (xy 279.133282 -306.16086)
			(xy 279.086011 -306.174552) (xy 279.037156 -306.180484) (xy 278.987981 -306.178503) (xy 278.939762 -306.168659)
			(xy 278.893746 -306.151207) (xy 278.851125 -306.1266) (xy 278.813004 -306.095475) (xy 278.780369 -306.058638)
			(xy 278.754066 -306.017042) (xy 278.734775 -305.971766) (xy 278.722998 -305.923982) (xy 278.719038 -305.874928)
			(xy 259.972646 -305.874928) (xy 259.964829 -305.883949) (xy 259.923633 -305.919643) (xy 259.877775 -305.949111)
			(xy 259.828191 -305.971753) (xy 259.775889 -305.987108) (xy 259.721935 -305.994863) (xy 259.69468 -305.995324)
			(xy 259.66547 -305.994308) (xy 259.65168 -305.993757) (xy 259.62463 -305.999167) (xy 259.600013 -306.011618)
			(xy 259.579627 -306.030203) (xy 259.564957 -306.053565) (xy 259.557075 -306.080001) (xy 259.556555 -306.107583)
			(xy 259.559552 -306.121054) (xy 259.565263 -306.144645) (xy 259.571379 -306.192797) (xy 259.571744 -306.217066)
			(xy 259.571281 -306.244322) (xy 259.563528 -306.298281) (xy 259.548299 -306.350162) (xy 267.793736 -306.350162)
			(xy 267.797696 -306.301108) (xy 267.809473 -306.253324) (xy 267.828764 -306.208048) (xy 267.855067 -306.166452)
			(xy 267.887702 -306.129615) (xy 267.925823 -306.09849) (xy 267.968444 -306.073883) (xy 268.01446 -306.056431)
			(xy 268.062679 -306.046587) (xy 268.111854 -306.044606) (xy 268.160709 -306.050538) (xy 268.20798 -306.06423)
			(xy 268.252442 -306.085328) (xy 268.292945 -306.113284) (xy 268.328438 -306.147376) (xy 268.358003 -306.18672)
			(xy 268.380874 -306.230297) (xy 268.396458 -306.276978) (xy 268.404353 -306.325555) (xy 268.404848 -306.350162)
			(xy 268.404353 -306.374769) (xy 268.404215 -306.375616) (xy 268.723106 -306.375616) (xy 268.723106 -306.3242)
			(xy 268.731149 -306.273418) (xy 268.747037 -306.224519) (xy 268.77038 -306.178707) (xy 268.800601 -306.137111)
			(xy 268.836957 -306.100755) (xy 268.878553 -306.070534) (xy 268.924365 -306.047191) (xy 268.973264 -306.031303)
			(xy 269.024046 -306.02326) (xy 269.075462 -306.02326) (xy 269.126244 -306.031303) (xy 269.175143 -306.047191)
			(xy 269.220955 -306.070534) (xy 269.262551 -306.100755) (xy 269.298907 -306.137111) (xy 269.329128 -306.178707)
			(xy 269.352471 -306.224519) (xy 269.368359 -306.273418) (xy 269.376402 -306.3242) (xy 269.376906 -306.349908)
			(xy 269.376402 -306.375616) (xy 269.673066 -306.375616) (xy 269.673066 -306.3242) (xy 269.681109 -306.273418)
			(xy 269.696997 -306.224519) (xy 269.72034 -306.178707) (xy 269.750561 -306.137111) (xy 269.786917 -306.100755)
			(xy 269.828513 -306.070534) (xy 269.874325 -306.047191) (xy 269.923224 -306.031303) (xy 269.974006 -306.02326)
			(xy 270.025422 -306.02326) (xy 270.076204 -306.031303) (xy 270.125103 -306.047191) (xy 270.170915 -306.070534)
			(xy 270.212511 -306.100755) (xy 270.248867 -306.137111) (xy 270.279088 -306.178707) (xy 270.302431 -306.224519)
			(xy 270.318319 -306.273418) (xy 270.326362 -306.3242) (xy 270.326866 -306.349908) (xy 270.644124 -306.349908)
			(xy 270.648084 -306.300854) (xy 270.659861 -306.25307) (xy 270.679152 -306.207794) (xy 270.705455 -306.166198)
			(xy 270.73809 -306.129361) (xy 270.776211 -306.098236) (xy 270.818832 -306.073629) (xy 270.864848 -306.056177)
			(xy 270.913067 -306.046333) (xy 270.962242 -306.044352) (xy 271.011097 -306.050284) (xy 271.058368 -306.063976)
			(xy 271.10283 -306.085074) (xy 271.143333 -306.11303) (xy 271.178826 -306.147122) (xy 271.208391 -306.186466)
			(xy 271.231262 -306.230043) (xy 271.246846 -306.276724) (xy 271.254741 -306.325301) (xy 271.255236 -306.349908)
			(xy 271.594084 -306.349908) (xy 271.598044 -306.300854) (xy 271.609821 -306.25307) (xy 271.629112 -306.207794)
			(xy 271.655415 -306.166198) (xy 271.68805 -306.129361) (xy 271.726171 -306.098236) (xy 271.768792 -306.073629)
			(xy 271.814808 -306.056177) (xy 271.863027 -306.046333) (xy 271.912202 -306.044352) (xy 271.961057 -306.050284)
			(xy 272.008328 -306.063976) (xy 272.05279 -306.085074) (xy 272.093293 -306.11303) (xy 272.128786 -306.147122)
			(xy 272.158351 -306.186466) (xy 272.181222 -306.230043) (xy 272.196806 -306.276724) (xy 272.204701 -306.325301)
			(xy 272.205196 -306.349908) (xy 272.544044 -306.349908) (xy 272.548004 -306.300854) (xy 272.559781 -306.25307)
			(xy 272.579072 -306.207794) (xy 272.605375 -306.166198) (xy 272.63801 -306.129361) (xy 272.676131 -306.098236)
			(xy 272.718752 -306.073629) (xy 272.764768 -306.056177) (xy 272.812987 -306.046333) (xy 272.862162 -306.044352)
			(xy 272.911017 -306.050284) (xy 272.958288 -306.063976) (xy 273.00275 -306.085074) (xy 273.043253 -306.11303)
			(xy 273.078746 -306.147122) (xy 273.108311 -306.186466) (xy 273.131182 -306.230043) (xy 273.146766 -306.276724)
			(xy 273.154661 -306.325301) (xy 273.155156 -306.349908) (xy 273.494004 -306.349908) (xy 273.497964 -306.300854)
			(xy 273.509741 -306.25307) (xy 273.529032 -306.207794) (xy 273.555335 -306.166198) (xy 273.58797 -306.129361)
			(xy 273.626091 -306.098236) (xy 273.668712 -306.073629) (xy 273.714728 -306.056177) (xy 273.762947 -306.046333)
			(xy 273.812122 -306.044352) (xy 273.860977 -306.050284) (xy 273.908248 -306.063976) (xy 273.95271 -306.085074)
			(xy 273.993213 -306.11303) (xy 274.028706 -306.147122) (xy 274.058271 -306.186466) (xy 274.081142 -306.230043)
			(xy 274.096726 -306.276724) (xy 274.104621 -306.325301) (xy 274.105116 -306.349908) (xy 274.443964 -306.349908)
			(xy 274.447924 -306.300854) (xy 274.459701 -306.25307) (xy 274.478992 -306.207794) (xy 274.505295 -306.166198)
			(xy 274.53793 -306.129361) (xy 274.576051 -306.098236) (xy 274.618672 -306.073629) (xy 274.664688 -306.056177)
			(xy 274.712907 -306.046333) (xy 274.762082 -306.044352) (xy 274.810937 -306.050284) (xy 274.858208 -306.063976)
			(xy 274.90267 -306.085074) (xy 274.943173 -306.11303) (xy 274.978666 -306.147122) (xy 275.008231 -306.186466)
			(xy 275.031102 -306.230043) (xy 275.046686 -306.276724) (xy 275.054581 -306.325301) (xy 275.055076 -306.349908)
			(xy 275.054581 -306.374515) (xy 275.054402 -306.375616) (xy 275.37308 -306.375616) (xy 275.37308 -306.3242)
			(xy 275.381123 -306.273418) (xy 275.397011 -306.224519) (xy 275.420354 -306.178707) (xy 275.450575 -306.137111)
			(xy 275.486931 -306.100755) (xy 275.528527 -306.070534) (xy 275.574339 -306.047191) (xy 275.623238 -306.031303)
			(xy 275.67402 -306.02326) (xy 275.725436 -306.02326) (xy 275.776218 -306.031303) (xy 275.825117 -306.047191)
			(xy 275.870929 -306.070534) (xy 275.912525 -306.100755) (xy 275.948881 -306.137111) (xy 275.979102 -306.178707)
			(xy 276.002445 -306.224519) (xy 276.018333 -306.273418) (xy 276.026376 -306.3242) (xy 276.02688 -306.349908)
			(xy 276.026376 -306.375616) (xy 276.32304 -306.375616) (xy 276.32304 -306.3242) (xy 276.331083 -306.273418)
			(xy 276.346971 -306.224519) (xy 276.370314 -306.178707) (xy 276.400535 -306.137111) (xy 276.436891 -306.100755)
			(xy 276.478487 -306.070534) (xy 276.524299 -306.047191) (xy 276.573198 -306.031303) (xy 276.62398 -306.02326)
			(xy 276.675396 -306.02326) (xy 276.726178 -306.031303) (xy 276.775077 -306.047191) (xy 276.820889 -306.070534)
			(xy 276.862485 -306.100755) (xy 276.898841 -306.137111) (xy 276.929062 -306.178707) (xy 276.952405 -306.224519)
			(xy 276.968293 -306.273418) (xy 276.976336 -306.3242) (xy 276.97684 -306.349908) (xy 277.294098 -306.349908)
			(xy 277.298058 -306.300854) (xy 277.309835 -306.25307) (xy 277.329126 -306.207794) (xy 277.355429 -306.166198)
			(xy 277.388064 -306.129361) (xy 277.426185 -306.098236) (xy 277.468806 -306.073629) (xy 277.514822 -306.056177)
			(xy 277.563041 -306.046333) (xy 277.612216 -306.044352) (xy 277.661071 -306.050284) (xy 277.708342 -306.063976)
			(xy 277.752804 -306.085074) (xy 277.793307 -306.11303) (xy 277.8288 -306.147122) (xy 277.858365 -306.186466)
			(xy 277.881236 -306.230043) (xy 277.89682 -306.276724) (xy 277.904715 -306.325301) (xy 277.90521 -306.349908)
			(xy 277.904715 -306.374515) (xy 277.89682 -306.423092) (xy 277.881236 -306.469773) (xy 277.858365 -306.51335)
			(xy 277.8288 -306.552694) (xy 277.793307 -306.586786) (xy 277.752804 -306.614742) (xy 277.708342 -306.63584)
			(xy 277.661071 -306.649532) (xy 277.612216 -306.655464) (xy 277.563041 -306.653483) (xy 277.514822 -306.643639)
			(xy 277.468806 -306.626187) (xy 277.426185 -306.60158) (xy 277.388064 -306.570455) (xy 277.355429 -306.533618)
			(xy 277.329126 -306.492022) (xy 277.309835 -306.446746) (xy 277.298058 -306.398962) (xy 277.294098 -306.349908)
			(xy 276.97684 -306.349908) (xy 276.976336 -306.375616) (xy 276.968293 -306.426398) (xy 276.952405 -306.475297)
			(xy 276.929062 -306.521109) (xy 276.898841 -306.562705) (xy 276.862485 -306.599061) (xy 276.820889 -306.629282)
			(xy 276.775077 -306.652625) (xy 276.726178 -306.668513) (xy 276.675396 -306.676556) (xy 276.62398 -306.676556)
			(xy 276.573198 -306.668513) (xy 276.524299 -306.652625) (xy 276.478487 -306.629282) (xy 276.436891 -306.599061)
			(xy 276.400535 -306.562705) (xy 276.370314 -306.521109) (xy 276.346971 -306.475297) (xy 276.331083 -306.426398)
			(xy 276.32304 -306.375616) (xy 276.026376 -306.375616) (xy 276.018333 -306.426398) (xy 276.002445 -306.475297)
			(xy 275.979102 -306.521109) (xy 275.948881 -306.562705) (xy 275.912525 -306.599061) (xy 275.870929 -306.629282)
			(xy 275.825117 -306.652625) (xy 275.776218 -306.668513) (xy 275.725436 -306.676556) (xy 275.67402 -306.676556)
			(xy 275.623238 -306.668513) (xy 275.574339 -306.652625) (xy 275.528527 -306.629282) (xy 275.486931 -306.599061)
			(xy 275.450575 -306.562705) (xy 275.420354 -306.521109) (xy 275.397011 -306.475297) (xy 275.381123 -306.426398)
			(xy 275.37308 -306.375616) (xy 275.054402 -306.375616) (xy 275.046686 -306.423092) (xy 275.031102 -306.469773)
			(xy 275.008231 -306.51335) (xy 274.978666 -306.552694) (xy 274.943173 -306.586786) (xy 274.90267 -306.614742)
			(xy 274.858208 -306.63584) (xy 274.810937 -306.649532) (xy 274.762082 -306.655464) (xy 274.712907 -306.653483)
			(xy 274.664688 -306.643639) (xy 274.618672 -306.626187) (xy 274.576051 -306.60158) (xy 274.53793 -306.570455)
			(xy 274.505295 -306.533618) (xy 274.478992 -306.492022) (xy 274.459701 -306.446746) (xy 274.447924 -306.398962)
			(xy 274.443964 -306.349908) (xy 274.105116 -306.349908) (xy 274.104621 -306.374515) (xy 274.096726 -306.423092)
			(xy 274.081142 -306.469773) (xy 274.058271 -306.51335) (xy 274.028706 -306.552694) (xy 273.993213 -306.586786)
			(xy 273.95271 -306.614742) (xy 273.908248 -306.63584) (xy 273.860977 -306.649532) (xy 273.812122 -306.655464)
			(xy 273.762947 -306.653483) (xy 273.714728 -306.643639) (xy 273.668712 -306.626187) (xy 273.626091 -306.60158)
			(xy 273.58797 -306.570455) (xy 273.555335 -306.533618) (xy 273.529032 -306.492022) (xy 273.509741 -306.446746)
			(xy 273.497964 -306.398962) (xy 273.494004 -306.349908) (xy 273.155156 -306.349908) (xy 273.154661 -306.374515)
			(xy 273.146766 -306.423092) (xy 273.131182 -306.469773) (xy 273.108311 -306.51335) (xy 273.078746 -306.552694)
			(xy 273.043253 -306.586786) (xy 273.00275 -306.614742) (xy 272.958288 -306.63584) (xy 272.911017 -306.649532)
			(xy 272.862162 -306.655464) (xy 272.812987 -306.653483) (xy 272.764768 -306.643639) (xy 272.718752 -306.626187)
			(xy 272.676131 -306.60158) (xy 272.63801 -306.570455) (xy 272.605375 -306.533618) (xy 272.579072 -306.492022)
			(xy 272.559781 -306.446746) (xy 272.548004 -306.398962) (xy 272.544044 -306.349908) (xy 272.205196 -306.349908)
			(xy 272.204701 -306.374515) (xy 272.196806 -306.423092) (xy 272.181222 -306.469773) (xy 272.158351 -306.51335)
			(xy 272.128786 -306.552694) (xy 272.093293 -306.586786) (xy 272.05279 -306.614742) (xy 272.008328 -306.63584)
			(xy 271.961057 -306.649532) (xy 271.912202 -306.655464) (xy 271.863027 -306.653483) (xy 271.814808 -306.643639)
			(xy 271.768792 -306.626187) (xy 271.726171 -306.60158) (xy 271.68805 -306.570455) (xy 271.655415 -306.533618)
			(xy 271.629112 -306.492022) (xy 271.609821 -306.446746) (xy 271.598044 -306.398962) (xy 271.594084 -306.349908)
			(xy 271.255236 -306.349908) (xy 271.254741 -306.374515) (xy 271.246846 -306.423092) (xy 271.231262 -306.469773)
			(xy 271.208391 -306.51335) (xy 271.178826 -306.552694) (xy 271.143333 -306.586786) (xy 271.10283 -306.614742)
			(xy 271.058368 -306.63584) (xy 271.011097 -306.649532) (xy 270.962242 -306.655464) (xy 270.913067 -306.653483)
			(xy 270.864848 -306.643639) (xy 270.818832 -306.626187) (xy 270.776211 -306.60158) (xy 270.73809 -306.570455)
			(xy 270.705455 -306.533618) (xy 270.679152 -306.492022) (xy 270.659861 -306.446746) (xy 270.648084 -306.398962)
			(xy 270.644124 -306.349908) (xy 270.326866 -306.349908) (xy 270.326362 -306.375616) (xy 270.318319 -306.426398)
			(xy 270.302431 -306.475297) (xy 270.279088 -306.521109) (xy 270.248867 -306.562705) (xy 270.212511 -306.599061)
			(xy 270.170915 -306.629282) (xy 270.125103 -306.652625) (xy 270.076204 -306.668513) (xy 270.025422 -306.676556)
			(xy 269.974006 -306.676556) (xy 269.923224 -306.668513) (xy 269.874325 -306.652625) (xy 269.828513 -306.629282)
			(xy 269.786917 -306.599061) (xy 269.750561 -306.562705) (xy 269.72034 -306.521109) (xy 269.696997 -306.475297)
			(xy 269.681109 -306.426398) (xy 269.673066 -306.375616) (xy 269.376402 -306.375616) (xy 269.368359 -306.426398)
			(xy 269.352471 -306.475297) (xy 269.329128 -306.521109) (xy 269.298907 -306.562705) (xy 269.262551 -306.599061)
			(xy 269.220955 -306.629282) (xy 269.175143 -306.652625) (xy 269.126244 -306.668513) (xy 269.075462 -306.676556)
			(xy 269.024046 -306.676556) (xy 268.973264 -306.668513) (xy 268.924365 -306.652625) (xy 268.878553 -306.629282)
			(xy 268.836957 -306.599061) (xy 268.800601 -306.562705) (xy 268.77038 -306.521109) (xy 268.747037 -306.475297)
			(xy 268.731149 -306.426398) (xy 268.723106 -306.375616) (xy 268.404215 -306.375616) (xy 268.396458 -306.423346)
			(xy 268.380874 -306.470027) (xy 268.358003 -306.513604) (xy 268.328438 -306.552948) (xy 268.292945 -306.58704)
			(xy 268.252442 -306.614996) (xy 268.20798 -306.636094) (xy 268.160709 -306.649786) (xy 268.111854 -306.655718)
			(xy 268.062679 -306.653737) (xy 268.01446 -306.643893) (xy 267.968444 -306.626441) (xy 267.925823 -306.601834)
			(xy 267.887702 -306.570709) (xy 267.855067 -306.533872) (xy 267.828764 -306.492276) (xy 267.809473 -306.447)
			(xy 267.797696 -306.399216) (xy 267.793736 -306.350162) (xy 259.548299 -306.350162) (xy 259.548174 -306.350587)
			(xy 259.525532 -306.400175) (xy 259.496063 -306.446036) (xy 259.460368 -306.487236) (xy 259.419172 -306.522937)
			(xy 259.373314 -306.552411) (xy 259.323729 -306.575058) (xy 259.271425 -306.590418) (xy 259.217467 -306.598178)
			(xy 259.162954 -306.59818) (xy 259.108996 -306.590423) (xy 259.056691 -306.575066) (xy 259.007105 -306.552421)
			(xy 258.961245 -306.522949) (xy 258.920047 -306.487251) (xy 258.884349 -306.446053) (xy 258.854878 -306.400194)
			(xy 258.832233 -306.350607) (xy 258.816877 -306.298302) (xy 258.80912 -306.244344) (xy 255.945132 -306.244344)
			(xy 255.945132 -306.8193) (xy 261.957056 -306.8193) (xy 261.961127 -306.763678) (xy 261.973253 -306.709241)
			(xy 261.993176 -306.65715) (xy 262.020472 -306.608515) (xy 262.054558 -306.564372) (xy 262.094707 -306.525663)
			(xy 262.140065 -306.493212) (xy 262.189665 -306.467711) (xy 262.242449 -306.449704) (xy 262.297292 -306.439574)
			(xy 262.353026 -306.437537) (xy 262.408463 -306.443637) (xy 262.46242 -306.457743) (xy 262.513749 -306.479555)
			(xy 262.561355 -306.508609) (xy 262.604223 -306.544284) (xy 262.64144 -306.585821) (xy 262.672213 -306.632334)
			(xy 262.695885 -306.682831) (xy 262.711953 -306.736238) (xy 262.720073 -306.791414) (xy 262.720582 -306.8193)
			(xy 262.72048 -306.824888) (xy 278.719038 -306.824888) (xy 278.722998 -306.775834) (xy 278.734775 -306.72805)
			(xy 278.754066 -306.682774) (xy 278.780369 -306.641178) (xy 278.813004 -306.604341) (xy 278.851125 -306.573216)
			(xy 278.893746 -306.548609) (xy 278.939762 -306.531157) (xy 278.987981 -306.521313) (xy 279.037156 -306.519332)
			(xy 279.086011 -306.525264) (xy 279.133282 -306.538956) (xy 279.177744 -306.560054) (xy 279.218247 -306.58801)
			(xy 279.25374 -306.622102) (xy 279.283305 -306.661446) (xy 279.306176 -306.705023) (xy 279.32176 -306.751704)
			(xy 279.329655 -306.800281) (xy 279.33015 -306.824888) (xy 279.668998 -306.824888) (xy 279.672958 -306.775834)
			(xy 279.684735 -306.72805) (xy 279.704026 -306.682774) (xy 279.730329 -306.641178) (xy 279.762964 -306.604341)
			(xy 279.801085 -306.573216) (xy 279.843706 -306.548609) (xy 279.889722 -306.531157) (xy 279.937941 -306.521313)
			(xy 279.987116 -306.519332) (xy 280.035971 -306.525264) (xy 280.083242 -306.538956) (xy 280.127704 -306.560054)
			(xy 280.168207 -306.58801) (xy 280.2037 -306.622102) (xy 280.233265 -306.661446) (xy 280.256136 -306.705023)
			(xy 280.27172 -306.751704) (xy 280.279615 -306.800281) (xy 280.28011 -306.824888) (xy 280.618958 -306.824888)
			(xy 280.622918 -306.775834) (xy 280.634695 -306.72805) (xy 280.653986 -306.682774) (xy 280.680289 -306.641178)
			(xy 280.712924 -306.604341) (xy 280.751045 -306.573216) (xy 280.793666 -306.548609) (xy 280.839682 -306.531157)
			(xy 280.887901 -306.521313) (xy 280.937076 -306.519332) (xy 280.985931 -306.525264) (xy 281.033202 -306.538956)
			(xy 281.077664 -306.560054) (xy 281.118167 -306.58801) (xy 281.15366 -306.622102) (xy 281.183225 -306.661446)
			(xy 281.206096 -306.705023) (xy 281.22168 -306.751704) (xy 281.229575 -306.800281) (xy 281.23007 -306.824888)
			(xy 281.568918 -306.824888) (xy 281.572878 -306.775834) (xy 281.584655 -306.72805) (xy 281.603946 -306.682774)
			(xy 281.630249 -306.641178) (xy 281.662884 -306.604341) (xy 281.701005 -306.573216) (xy 281.743626 -306.548609)
			(xy 281.789642 -306.531157) (xy 281.837861 -306.521313) (xy 281.887036 -306.519332) (xy 281.935891 -306.525264)
			(xy 281.983162 -306.538956) (xy 282.027624 -306.560054) (xy 282.068127 -306.58801) (xy 282.10362 -306.622102)
			(xy 282.133185 -306.661446) (xy 282.156056 -306.705023) (xy 282.17164 -306.751704) (xy 282.179535 -306.800281)
			(xy 282.18003 -306.824888) (xy 282.519132 -306.824888) (xy 282.523092 -306.775834) (xy 282.534869 -306.72805)
			(xy 282.55416 -306.682774) (xy 282.580463 -306.641178) (xy 282.613098 -306.604341) (xy 282.651219 -306.573216)
			(xy 282.69384 -306.548609) (xy 282.739856 -306.531157) (xy 282.788075 -306.521313) (xy 282.83725 -306.519332)
			(xy 282.886105 -306.525264) (xy 282.933376 -306.538956) (xy 282.977838 -306.560054) (xy 283.018341 -306.58801)
			(xy 283.053834 -306.622102) (xy 283.083399 -306.661446) (xy 283.10627 -306.705023) (xy 283.121854 -306.751704)
			(xy 283.129749 -306.800281) (xy 283.130244 -306.824888) (xy 283.469092 -306.824888) (xy 283.473052 -306.775834)
			(xy 283.484829 -306.72805) (xy 283.50412 -306.682774) (xy 283.530423 -306.641178) (xy 283.563058 -306.604341)
			(xy 283.601179 -306.573216) (xy 283.6438 -306.548609) (xy 283.689816 -306.531157) (xy 283.738035 -306.521313)
			(xy 283.78721 -306.519332) (xy 283.836065 -306.525264) (xy 283.883336 -306.538956) (xy 283.927798 -306.560054)
			(xy 283.968301 -306.58801) (xy 284.003794 -306.622102) (xy 284.033359 -306.661446) (xy 284.05623 -306.705023)
			(xy 284.071814 -306.751704) (xy 284.079709 -306.800281) (xy 284.080204 -306.824888) (xy 284.419052 -306.824888)
			(xy 284.423012 -306.775834) (xy 284.434789 -306.72805) (xy 284.45408 -306.682774) (xy 284.480383 -306.641178)
			(xy 284.513018 -306.604341) (xy 284.551139 -306.573216) (xy 284.59376 -306.548609) (xy 284.639776 -306.531157)
			(xy 284.687995 -306.521313) (xy 284.73717 -306.519332) (xy 284.786025 -306.525264) (xy 284.833296 -306.538956)
			(xy 284.877758 -306.560054) (xy 284.918261 -306.58801) (xy 284.953754 -306.622102) (xy 284.983319 -306.661446)
			(xy 285.00619 -306.705023) (xy 285.021774 -306.751704) (xy 285.029669 -306.800281) (xy 285.030164 -306.824888)
			(xy 285.369012 -306.824888) (xy 285.372972 -306.775834) (xy 285.384749 -306.72805) (xy 285.40404 -306.682774)
			(xy 285.430343 -306.641178) (xy 285.462978 -306.604341) (xy 285.501099 -306.573216) (xy 285.54372 -306.548609)
			(xy 285.589736 -306.531157) (xy 285.637955 -306.521313) (xy 285.68713 -306.519332) (xy 285.735985 -306.525264)
			(xy 285.783256 -306.538956) (xy 285.827718 -306.560054) (xy 285.868221 -306.58801) (xy 285.903714 -306.622102)
			(xy 285.933279 -306.661446) (xy 285.95615 -306.705023) (xy 285.971734 -306.751704) (xy 285.979629 -306.800281)
			(xy 285.980124 -306.824888) (xy 286.318972 -306.824888) (xy 286.322932 -306.775834) (xy 286.334709 -306.72805)
			(xy 286.354 -306.682774) (xy 286.380303 -306.641178) (xy 286.412938 -306.604341) (xy 286.451059 -306.573216)
			(xy 286.49368 -306.548609) (xy 286.539696 -306.531157) (xy 286.587915 -306.521313) (xy 286.63709 -306.519332)
			(xy 286.685945 -306.525264) (xy 286.733216 -306.538956) (xy 286.777678 -306.560054) (xy 286.818181 -306.58801)
			(xy 286.853674 -306.622102) (xy 286.883239 -306.661446) (xy 286.90611 -306.705023) (xy 286.921694 -306.751704)
			(xy 286.929589 -306.800281) (xy 286.930084 -306.824888) (xy 287.268932 -306.824888) (xy 287.272892 -306.775834)
			(xy 287.284669 -306.72805) (xy 287.30396 -306.682774) (xy 287.330263 -306.641178) (xy 287.362898 -306.604341)
			(xy 287.401019 -306.573216) (xy 287.44364 -306.548609) (xy 287.489656 -306.531157) (xy 287.537875 -306.521313)
			(xy 287.58705 -306.519332) (xy 287.635905 -306.525264) (xy 287.683176 -306.538956) (xy 287.727638 -306.560054)
			(xy 287.768141 -306.58801) (xy 287.803634 -306.622102) (xy 287.833199 -306.661446) (xy 287.85607 -306.705023)
			(xy 287.871654 -306.751704) (xy 287.879549 -306.800281) (xy 287.880044 -306.824888) (xy 288.218892 -306.824888)
			(xy 288.222852 -306.775834) (xy 288.234629 -306.72805) (xy 288.25392 -306.682774) (xy 288.280223 -306.641178)
			(xy 288.312858 -306.604341) (xy 288.350979 -306.573216) (xy 288.3936 -306.548609) (xy 288.439616 -306.531157)
			(xy 288.487835 -306.521313) (xy 288.53701 -306.519332) (xy 288.585865 -306.525264) (xy 288.633136 -306.538956)
			(xy 288.677598 -306.560054) (xy 288.718101 -306.58801) (xy 288.753594 -306.622102) (xy 288.783159 -306.661446)
			(xy 288.80603 -306.705023) (xy 288.821614 -306.751704) (xy 288.829509 -306.800281) (xy 288.830004 -306.824888)
			(xy 289.169106 -306.824888) (xy 289.173066 -306.775834) (xy 289.184843 -306.72805) (xy 289.204134 -306.682774)
			(xy 289.230437 -306.641178) (xy 289.263072 -306.604341) (xy 289.301193 -306.573216) (xy 289.343814 -306.548609)
			(xy 289.38983 -306.531157) (xy 289.438049 -306.521313) (xy 289.487224 -306.519332) (xy 289.536079 -306.525264)
			(xy 289.58335 -306.538956) (xy 289.627812 -306.560054) (xy 289.668315 -306.58801) (xy 289.703808 -306.622102)
			(xy 289.733373 -306.661446) (xy 289.756244 -306.705023) (xy 289.771828 -306.751704) (xy 289.779723 -306.800281)
			(xy 289.780218 -306.824888) (xy 290.119066 -306.824888) (xy 290.123026 -306.775834) (xy 290.134803 -306.72805)
			(xy 290.154094 -306.682774) (xy 290.180397 -306.641178) (xy 290.213032 -306.604341) (xy 290.251153 -306.573216)
			(xy 290.293774 -306.548609) (xy 290.33979 -306.531157) (xy 290.388009 -306.521313) (xy 290.437184 -306.519332)
			(xy 290.486039 -306.525264) (xy 290.53331 -306.538956) (xy 290.577772 -306.560054) (xy 290.618275 -306.58801)
			(xy 290.653768 -306.622102) (xy 290.683333 -306.661446) (xy 290.706204 -306.705023) (xy 290.721788 -306.751704)
			(xy 290.729683 -306.800281) (xy 290.730178 -306.824888) (xy 292.018986 -306.824888) (xy 292.022946 -306.775834)
			(xy 292.034723 -306.72805) (xy 292.054014 -306.682774) (xy 292.080317 -306.641178) (xy 292.112952 -306.604341)
			(xy 292.151073 -306.573216) (xy 292.193694 -306.548609) (xy 292.23971 -306.531157) (xy 292.287929 -306.521313)
			(xy 292.337104 -306.519332) (xy 292.385959 -306.525264) (xy 292.43323 -306.538956) (xy 292.477692 -306.560054)
			(xy 292.518195 -306.58801) (xy 292.553688 -306.622102) (xy 292.583253 -306.661446) (xy 292.606124 -306.705023)
			(xy 292.621708 -306.751704) (xy 292.629603 -306.800281) (xy 292.630098 -306.824888) (xy 292.968946 -306.824888)
			(xy 292.972906 -306.775834) (xy 292.984683 -306.72805) (xy 293.003974 -306.682774) (xy 293.030277 -306.641178)
			(xy 293.062912 -306.604341) (xy 293.101033 -306.573216) (xy 293.143654 -306.548609) (xy 293.18967 -306.531157)
			(xy 293.237889 -306.521313) (xy 293.287064 -306.519332) (xy 293.335919 -306.525264) (xy 293.38319 -306.538956)
			(xy 293.427652 -306.560054) (xy 293.468155 -306.58801) (xy 293.503648 -306.622102) (xy 293.533213 -306.661446)
			(xy 293.556084 -306.705023) (xy 293.571668 -306.751704) (xy 293.579563 -306.800281) (xy 293.580058 -306.824888)
			(xy 293.918906 -306.824888) (xy 293.922866 -306.775834) (xy 293.934643 -306.72805) (xy 293.953934 -306.682774)
			(xy 293.980237 -306.641178) (xy 294.012872 -306.604341) (xy 294.050993 -306.573216) (xy 294.093614 -306.548609)
			(xy 294.13963 -306.531157) (xy 294.187849 -306.521313) (xy 294.237024 -306.519332) (xy 294.285879 -306.525264)
			(xy 294.33315 -306.538956) (xy 294.377612 -306.560054) (xy 294.418115 -306.58801) (xy 294.453608 -306.622102)
			(xy 294.483173 -306.661446) (xy 294.506044 -306.705023) (xy 294.521628 -306.751704) (xy 294.529523 -306.800281)
			(xy 294.530018 -306.824888) (xy 294.86912 -306.824888) (xy 294.87308 -306.775834) (xy 294.884857 -306.72805)
			(xy 294.904148 -306.682774) (xy 294.930451 -306.641178) (xy 294.963086 -306.604341) (xy 295.001207 -306.573216)
			(xy 295.043828 -306.548609) (xy 295.089844 -306.531157) (xy 295.138063 -306.521313) (xy 295.187238 -306.519332)
			(xy 295.236093 -306.525264) (xy 295.283364 -306.538956) (xy 295.327826 -306.560054) (xy 295.368329 -306.58801)
			(xy 295.403822 -306.622102) (xy 295.433387 -306.661446) (xy 295.456258 -306.705023) (xy 295.471842 -306.751704)
			(xy 295.479737 -306.800281) (xy 295.480232 -306.824888) (xy 295.81908 -306.824888) (xy 295.82304 -306.775834)
			(xy 295.834817 -306.72805) (xy 295.854108 -306.682774) (xy 295.880411 -306.641178) (xy 295.913046 -306.604341)
			(xy 295.951167 -306.573216) (xy 295.993788 -306.548609) (xy 296.039804 -306.531157) (xy 296.088023 -306.521313)
			(xy 296.137198 -306.519332) (xy 296.186053 -306.525264) (xy 296.233324 -306.538956) (xy 296.277786 -306.560054)
			(xy 296.318289 -306.58801) (xy 296.353782 -306.622102) (xy 296.383347 -306.661446) (xy 296.406218 -306.705023)
			(xy 296.421802 -306.751704) (xy 296.429697 -306.800281) (xy 296.430192 -306.824888) (xy 296.76904 -306.824888)
			(xy 296.773 -306.775834) (xy 296.784777 -306.72805) (xy 296.804068 -306.682774) (xy 296.830371 -306.641178)
			(xy 296.863006 -306.604341) (xy 296.901127 -306.573216) (xy 296.943748 -306.548609) (xy 296.989764 -306.531157)
			(xy 297.037983 -306.521313) (xy 297.087158 -306.519332) (xy 297.136013 -306.525264) (xy 297.183284 -306.538956)
			(xy 297.227746 -306.560054) (xy 297.268249 -306.58801) (xy 297.303742 -306.622102) (xy 297.333307 -306.661446)
			(xy 297.356178 -306.705023) (xy 297.371762 -306.751704) (xy 297.379657 -306.800281) (xy 297.380152 -306.824888)
			(xy 297.719 -306.824888) (xy 297.72296 -306.775834) (xy 297.734737 -306.72805) (xy 297.754028 -306.682774)
			(xy 297.780331 -306.641178) (xy 297.812966 -306.604341) (xy 297.851087 -306.573216) (xy 297.893708 -306.548609)
			(xy 297.939724 -306.531157) (xy 297.987943 -306.521313) (xy 298.037118 -306.519332) (xy 298.085973 -306.525264)
			(xy 298.133244 -306.538956) (xy 298.177706 -306.560054) (xy 298.218209 -306.58801) (xy 298.253702 -306.622102)
			(xy 298.283267 -306.661446) (xy 298.306138 -306.705023) (xy 298.321722 -306.751704) (xy 298.329617 -306.800281)
			(xy 298.330112 -306.824888) (xy 298.66896 -306.824888) (xy 298.67292 -306.775834) (xy 298.684697 -306.72805)
			(xy 298.703988 -306.682774) (xy 298.730291 -306.641178) (xy 298.762926 -306.604341) (xy 298.801047 -306.573216)
			(xy 298.843668 -306.548609) (xy 298.889684 -306.531157) (xy 298.937903 -306.521313) (xy 298.987078 -306.519332)
			(xy 299.035933 -306.525264) (xy 299.083204 -306.538956) (xy 299.127666 -306.560054) (xy 299.168169 -306.58801)
			(xy 299.203662 -306.622102) (xy 299.233227 -306.661446) (xy 299.256098 -306.705023) (xy 299.271682 -306.751704)
			(xy 299.279577 -306.800281) (xy 299.280072 -306.824888) (xy 299.61892 -306.824888) (xy 299.62288 -306.775834)
			(xy 299.634657 -306.72805) (xy 299.653948 -306.682774) (xy 299.680251 -306.641178) (xy 299.712886 -306.604341)
			(xy 299.751007 -306.573216) (xy 299.793628 -306.548609) (xy 299.839644 -306.531157) (xy 299.887863 -306.521313)
			(xy 299.937038 -306.519332) (xy 299.985893 -306.525264) (xy 300.033164 -306.538956) (xy 300.077626 -306.560054)
			(xy 300.118129 -306.58801) (xy 300.153622 -306.622102) (xy 300.183187 -306.661446) (xy 300.206058 -306.705023)
			(xy 300.221642 -306.751704) (xy 300.229537 -306.800281) (xy 300.230032 -306.824888) (xy 300.229537 -306.849495)
			(xy 300.221642 -306.898072) (xy 300.206058 -306.944753) (xy 300.183187 -306.98833) (xy 300.153622 -307.027674)
			(xy 300.118129 -307.061766) (xy 300.077626 -307.089722) (xy 300.033164 -307.11082) (xy 299.985893 -307.124512)
			(xy 299.937038 -307.130444) (xy 299.887863 -307.128463) (xy 299.839644 -307.118619) (xy 299.793628 -307.101167)
			(xy 299.751007 -307.07656) (xy 299.712886 -307.045435) (xy 299.680251 -307.008598) (xy 299.653948 -306.967002)
			(xy 299.634657 -306.921726) (xy 299.62288 -306.873942) (xy 299.61892 -306.824888) (xy 299.280072 -306.824888)
			(xy 299.279577 -306.849495) (xy 299.271682 -306.898072) (xy 299.256098 -306.944753) (xy 299.233227 -306.98833)
			(xy 299.203662 -307.027674) (xy 299.168169 -307.061766) (xy 299.127666 -307.089722) (xy 299.083204 -307.11082)
			(xy 299.035933 -307.124512) (xy 298.987078 -307.130444) (xy 298.937903 -307.128463) (xy 298.889684 -307.118619)
			(xy 298.843668 -307.101167) (xy 298.801047 -307.07656) (xy 298.762926 -307.045435) (xy 298.730291 -307.008598)
			(xy 298.703988 -306.967002) (xy 298.684697 -306.921726) (xy 298.67292 -306.873942) (xy 298.66896 -306.824888)
			(xy 298.330112 -306.824888) (xy 298.329617 -306.849495) (xy 298.321722 -306.898072) (xy 298.306138 -306.944753)
			(xy 298.283267 -306.98833) (xy 298.253702 -307.027674) (xy 298.218209 -307.061766) (xy 298.177706 -307.089722)
			(xy 298.133244 -307.11082) (xy 298.085973 -307.124512) (xy 298.037118 -307.130444) (xy 297.987943 -307.128463)
			(xy 297.939724 -307.118619) (xy 297.893708 -307.101167) (xy 297.851087 -307.07656) (xy 297.812966 -307.045435)
			(xy 297.780331 -307.008598) (xy 297.754028 -306.967002) (xy 297.734737 -306.921726) (xy 297.72296 -306.873942)
			(xy 297.719 -306.824888) (xy 297.380152 -306.824888) (xy 297.379657 -306.849495) (xy 297.371762 -306.898072)
			(xy 297.356178 -306.944753) (xy 297.333307 -306.98833) (xy 297.303742 -307.027674) (xy 297.268249 -307.061766)
			(xy 297.227746 -307.089722) (xy 297.183284 -307.11082) (xy 297.136013 -307.124512) (xy 297.087158 -307.130444)
			(xy 297.037983 -307.128463) (xy 296.989764 -307.118619) (xy 296.943748 -307.101167) (xy 296.901127 -307.07656)
			(xy 296.863006 -307.045435) (xy 296.830371 -307.008598) (xy 296.804068 -306.967002) (xy 296.784777 -306.921726)
			(xy 296.773 -306.873942) (xy 296.76904 -306.824888) (xy 296.430192 -306.824888) (xy 296.429697 -306.849495)
			(xy 296.421802 -306.898072) (xy 296.406218 -306.944753) (xy 296.383347 -306.98833) (xy 296.353782 -307.027674)
			(xy 296.318289 -307.061766) (xy 296.277786 -307.089722) (xy 296.233324 -307.11082) (xy 296.186053 -307.124512)
			(xy 296.137198 -307.130444) (xy 296.088023 -307.128463) (xy 296.039804 -307.118619) (xy 295.993788 -307.101167)
			(xy 295.951167 -307.07656) (xy 295.913046 -307.045435) (xy 295.880411 -307.008598) (xy 295.854108 -306.967002)
			(xy 295.834817 -306.921726) (xy 295.82304 -306.873942) (xy 295.81908 -306.824888) (xy 295.480232 -306.824888)
			(xy 295.479737 -306.849495) (xy 295.471842 -306.898072) (xy 295.456258 -306.944753) (xy 295.433387 -306.98833)
			(xy 295.403822 -307.027674) (xy 295.368329 -307.061766) (xy 295.327826 -307.089722) (xy 295.283364 -307.11082)
			(xy 295.236093 -307.124512) (xy 295.187238 -307.130444) (xy 295.138063 -307.128463) (xy 295.089844 -307.118619)
			(xy 295.043828 -307.101167) (xy 295.001207 -307.07656) (xy 294.963086 -307.045435) (xy 294.930451 -307.008598)
			(xy 294.904148 -306.967002) (xy 294.884857 -306.921726) (xy 294.87308 -306.873942) (xy 294.86912 -306.824888)
			(xy 294.530018 -306.824888) (xy 294.529523 -306.849495) (xy 294.521628 -306.898072) (xy 294.506044 -306.944753)
			(xy 294.483173 -306.98833) (xy 294.453608 -307.027674) (xy 294.418115 -307.061766) (xy 294.377612 -307.089722)
			(xy 294.33315 -307.11082) (xy 294.285879 -307.124512) (xy 294.237024 -307.130444) (xy 294.187849 -307.128463)
			(xy 294.13963 -307.118619) (xy 294.093614 -307.101167) (xy 294.050993 -307.07656) (xy 294.012872 -307.045435)
			(xy 293.980237 -307.008598) (xy 293.953934 -306.967002) (xy 293.934643 -306.921726) (xy 293.922866 -306.873942)
			(xy 293.918906 -306.824888) (xy 293.580058 -306.824888) (xy 293.579563 -306.849495) (xy 293.571668 -306.898072)
			(xy 293.556084 -306.944753) (xy 293.533213 -306.98833) (xy 293.503648 -307.027674) (xy 293.468155 -307.061766)
			(xy 293.427652 -307.089722) (xy 293.38319 -307.11082) (xy 293.335919 -307.124512) (xy 293.287064 -307.130444)
			(xy 293.237889 -307.128463) (xy 293.18967 -307.118619) (xy 293.143654 -307.101167) (xy 293.101033 -307.07656)
			(xy 293.062912 -307.045435) (xy 293.030277 -307.008598) (xy 293.003974 -306.967002) (xy 292.984683 -306.921726)
			(xy 292.972906 -306.873942) (xy 292.968946 -306.824888) (xy 292.630098 -306.824888) (xy 292.629603 -306.849495)
			(xy 292.621708 -306.898072) (xy 292.606124 -306.944753) (xy 292.583253 -306.98833) (xy 292.553688 -307.027674)
			(xy 292.518195 -307.061766) (xy 292.477692 -307.089722) (xy 292.43323 -307.11082) (xy 292.385959 -307.124512)
			(xy 292.337104 -307.130444) (xy 292.287929 -307.128463) (xy 292.23971 -307.118619) (xy 292.193694 -307.101167)
			(xy 292.151073 -307.07656) (xy 292.112952 -307.045435) (xy 292.080317 -307.008598) (xy 292.054014 -306.967002)
			(xy 292.034723 -306.921726) (xy 292.022946 -306.873942) (xy 292.018986 -306.824888) (xy 290.730178 -306.824888)
			(xy 290.729683 -306.849495) (xy 290.721788 -306.898072) (xy 290.706204 -306.944753) (xy 290.683333 -306.98833)
			(xy 290.653768 -307.027674) (xy 290.618275 -307.061766) (xy 290.577772 -307.089722) (xy 290.53331 -307.11082)
			(xy 290.486039 -307.124512) (xy 290.437184 -307.130444) (xy 290.388009 -307.128463) (xy 290.33979 -307.118619)
			(xy 290.293774 -307.101167) (xy 290.251153 -307.07656) (xy 290.213032 -307.045435) (xy 290.180397 -307.008598)
			(xy 290.154094 -306.967002) (xy 290.134803 -306.921726) (xy 290.123026 -306.873942) (xy 290.119066 -306.824888)
			(xy 289.780218 -306.824888) (xy 289.779723 -306.849495) (xy 289.771828 -306.898072) (xy 289.756244 -306.944753)
			(xy 289.733373 -306.98833) (xy 289.703808 -307.027674) (xy 289.668315 -307.061766) (xy 289.627812 -307.089722)
			(xy 289.58335 -307.11082) (xy 289.536079 -307.124512) (xy 289.487224 -307.130444) (xy 289.438049 -307.128463)
			(xy 289.38983 -307.118619) (xy 289.343814 -307.101167) (xy 289.301193 -307.07656) (xy 289.263072 -307.045435)
			(xy 289.230437 -307.008598) (xy 289.204134 -306.967002) (xy 289.184843 -306.921726) (xy 289.173066 -306.873942)
			(xy 289.169106 -306.824888) (xy 288.830004 -306.824888) (xy 288.829509 -306.849495) (xy 288.821614 -306.898072)
			(xy 288.80603 -306.944753) (xy 288.783159 -306.98833) (xy 288.753594 -307.027674) (xy 288.718101 -307.061766)
			(xy 288.677598 -307.089722) (xy 288.633136 -307.11082) (xy 288.585865 -307.124512) (xy 288.53701 -307.130444)
			(xy 288.487835 -307.128463) (xy 288.439616 -307.118619) (xy 288.3936 -307.101167) (xy 288.350979 -307.07656)
			(xy 288.312858 -307.045435) (xy 288.280223 -307.008598) (xy 288.25392 -306.967002) (xy 288.234629 -306.921726)
			(xy 288.222852 -306.873942) (xy 288.218892 -306.824888) (xy 287.880044 -306.824888) (xy 287.879549 -306.849495)
			(xy 287.871654 -306.898072) (xy 287.85607 -306.944753) (xy 287.833199 -306.98833) (xy 287.803634 -307.027674)
			(xy 287.768141 -307.061766) (xy 287.727638 -307.089722) (xy 287.683176 -307.11082) (xy 287.635905 -307.124512)
			(xy 287.58705 -307.130444) (xy 287.537875 -307.128463) (xy 287.489656 -307.118619) (xy 287.44364 -307.101167)
			(xy 287.401019 -307.07656) (xy 287.362898 -307.045435) (xy 287.330263 -307.008598) (xy 287.30396 -306.967002)
			(xy 287.284669 -306.921726) (xy 287.272892 -306.873942) (xy 287.268932 -306.824888) (xy 286.930084 -306.824888)
			(xy 286.929589 -306.849495) (xy 286.921694 -306.898072) (xy 286.90611 -306.944753) (xy 286.883239 -306.98833)
			(xy 286.853674 -307.027674) (xy 286.818181 -307.061766) (xy 286.777678 -307.089722) (xy 286.733216 -307.11082)
			(xy 286.685945 -307.124512) (xy 286.63709 -307.130444) (xy 286.587915 -307.128463) (xy 286.539696 -307.118619)
			(xy 286.49368 -307.101167) (xy 286.451059 -307.07656) (xy 286.412938 -307.045435) (xy 286.380303 -307.008598)
			(xy 286.354 -306.967002) (xy 286.334709 -306.921726) (xy 286.322932 -306.873942) (xy 286.318972 -306.824888)
			(xy 285.980124 -306.824888) (xy 285.979629 -306.849495) (xy 285.971734 -306.898072) (xy 285.95615 -306.944753)
			(xy 285.933279 -306.98833) (xy 285.903714 -307.027674) (xy 285.868221 -307.061766) (xy 285.827718 -307.089722)
			(xy 285.783256 -307.11082) (xy 285.735985 -307.124512) (xy 285.68713 -307.130444) (xy 285.637955 -307.128463)
			(xy 285.589736 -307.118619) (xy 285.54372 -307.101167) (xy 285.501099 -307.07656) (xy 285.462978 -307.045435)
			(xy 285.430343 -307.008598) (xy 285.40404 -306.967002) (xy 285.384749 -306.921726) (xy 285.372972 -306.873942)
			(xy 285.369012 -306.824888) (xy 285.030164 -306.824888) (xy 285.029669 -306.849495) (xy 285.021774 -306.898072)
			(xy 285.00619 -306.944753) (xy 284.983319 -306.98833) (xy 284.953754 -307.027674) (xy 284.918261 -307.061766)
			(xy 284.877758 -307.089722) (xy 284.833296 -307.11082) (xy 284.786025 -307.124512) (xy 284.73717 -307.130444)
			(xy 284.687995 -307.128463) (xy 284.639776 -307.118619) (xy 284.59376 -307.101167) (xy 284.551139 -307.07656)
			(xy 284.513018 -307.045435) (xy 284.480383 -307.008598) (xy 284.45408 -306.967002) (xy 284.434789 -306.921726)
			(xy 284.423012 -306.873942) (xy 284.419052 -306.824888) (xy 284.080204 -306.824888) (xy 284.079709 -306.849495)
			(xy 284.071814 -306.898072) (xy 284.05623 -306.944753) (xy 284.033359 -306.98833) (xy 284.003794 -307.027674)
			(xy 283.968301 -307.061766) (xy 283.927798 -307.089722) (xy 283.883336 -307.11082) (xy 283.836065 -307.124512)
			(xy 283.78721 -307.130444) (xy 283.738035 -307.128463) (xy 283.689816 -307.118619) (xy 283.6438 -307.101167)
			(xy 283.601179 -307.07656) (xy 283.563058 -307.045435) (xy 283.530423 -307.008598) (xy 283.50412 -306.967002)
			(xy 283.484829 -306.921726) (xy 283.473052 -306.873942) (xy 283.469092 -306.824888) (xy 283.130244 -306.824888)
			(xy 283.129749 -306.849495) (xy 283.121854 -306.898072) (xy 283.10627 -306.944753) (xy 283.083399 -306.98833)
			(xy 283.053834 -307.027674) (xy 283.018341 -307.061766) (xy 282.977838 -307.089722) (xy 282.933376 -307.11082)
			(xy 282.886105 -307.124512) (xy 282.83725 -307.130444) (xy 282.788075 -307.128463) (xy 282.739856 -307.118619)
			(xy 282.69384 -307.101167) (xy 282.651219 -307.07656) (xy 282.613098 -307.045435) (xy 282.580463 -307.008598)
			(xy 282.55416 -306.967002) (xy 282.534869 -306.921726) (xy 282.523092 -306.873942) (xy 282.519132 -306.824888)
			(xy 282.18003 -306.824888) (xy 282.179535 -306.849495) (xy 282.17164 -306.898072) (xy 282.156056 -306.944753)
			(xy 282.133185 -306.98833) (xy 282.10362 -307.027674) (xy 282.068127 -307.061766) (xy 282.027624 -307.089722)
			(xy 281.983162 -307.11082) (xy 281.935891 -307.124512) (xy 281.887036 -307.130444) (xy 281.837861 -307.128463)
			(xy 281.789642 -307.118619) (xy 281.743626 -307.101167) (xy 281.701005 -307.07656) (xy 281.662884 -307.045435)
			(xy 281.630249 -307.008598) (xy 281.603946 -306.967002) (xy 281.584655 -306.921726) (xy 281.572878 -306.873942)
			(xy 281.568918 -306.824888) (xy 281.23007 -306.824888) (xy 281.229575 -306.849495) (xy 281.22168 -306.898072)
			(xy 281.206096 -306.944753) (xy 281.183225 -306.98833) (xy 281.15366 -307.027674) (xy 281.118167 -307.061766)
			(xy 281.077664 -307.089722) (xy 281.033202 -307.11082) (xy 280.985931 -307.124512) (xy 280.937076 -307.130444)
			(xy 280.887901 -307.128463) (xy 280.839682 -307.118619) (xy 280.793666 -307.101167) (xy 280.751045 -307.07656)
			(xy 280.712924 -307.045435) (xy 280.680289 -307.008598) (xy 280.653986 -306.967002) (xy 280.634695 -306.921726)
			(xy 280.622918 -306.873942) (xy 280.618958 -306.824888) (xy 280.28011 -306.824888) (xy 280.279615 -306.849495)
			(xy 280.27172 -306.898072) (xy 280.256136 -306.944753) (xy 280.233265 -306.98833) (xy 280.2037 -307.027674)
			(xy 280.168207 -307.061766) (xy 280.127704 -307.089722) (xy 280.083242 -307.11082) (xy 280.035971 -307.124512)
			(xy 279.987116 -307.130444) (xy 279.937941 -307.128463) (xy 279.889722 -307.118619) (xy 279.843706 -307.101167)
			(xy 279.801085 -307.07656) (xy 279.762964 -307.045435) (xy 279.730329 -307.008598) (xy 279.704026 -306.967002)
			(xy 279.684735 -306.921726) (xy 279.672958 -306.873942) (xy 279.668998 -306.824888) (xy 279.33015 -306.824888)
			(xy 279.329655 -306.849495) (xy 279.32176 -306.898072) (xy 279.306176 -306.944753) (xy 279.283305 -306.98833)
			(xy 279.25374 -307.027674) (xy 279.218247 -307.061766) (xy 279.177744 -307.089722) (xy 279.133282 -307.11082)
			(xy 279.086011 -307.124512) (xy 279.037156 -307.130444) (xy 278.987981 -307.128463) (xy 278.939762 -307.118619)
			(xy 278.893746 -307.101167) (xy 278.851125 -307.07656) (xy 278.813004 -307.045435) (xy 278.780369 -307.008598)
			(xy 278.754066 -306.967002) (xy 278.734775 -306.921726) (xy 278.722998 -306.873942) (xy 278.719038 -306.824888)
			(xy 262.72048 -306.824888) (xy 262.720073 -306.847186) (xy 262.711953 -306.902362) (xy 262.695885 -306.955769)
			(xy 262.672213 -307.006266) (xy 262.64144 -307.052779) (xy 262.604223 -307.094316) (xy 262.561355 -307.129991)
			(xy 262.513749 -307.159045) (xy 262.46242 -307.180857) (xy 262.408463 -307.194963) (xy 262.353026 -307.201063)
			(xy 262.297292 -307.199026) (xy 262.242449 -307.188896) (xy 262.189665 -307.170889) (xy 262.140065 -307.145388)
			(xy 262.094707 -307.112937) (xy 262.054558 -307.074228) (xy 262.020472 -307.030085) (xy 261.993176 -306.98145)
			(xy 261.973253 -306.929359) (xy 261.961127 -306.874922) (xy 261.957056 -306.8193) (xy 255.945132 -306.8193)
			(xy 255.945132 -307.4924) (xy 263.930382 -307.4924) (xy 263.934453 -307.436778) (xy 263.946579 -307.382341)
			(xy 263.966502 -307.33025) (xy 263.993798 -307.281615) (xy 264.027884 -307.237472) (xy 264.068033 -307.198763)
			(xy 264.113391 -307.166312) (xy 264.162991 -307.140811) (xy 264.215775 -307.122804) (xy 264.270618 -307.112674)
			(xy 264.326352 -307.110637) (xy 264.381789 -307.116737) (xy 264.435746 -307.130843) (xy 264.487075 -307.152655)
			(xy 264.534681 -307.181709) (xy 264.577549 -307.217384) (xy 264.614766 -307.258921) (xy 264.641857 -307.299868)
			(xy 268.74395 -307.299868) (xy 268.74791 -307.250814) (xy 268.759687 -307.20303) (xy 268.778978 -307.157754)
			(xy 268.805281 -307.116158) (xy 268.837916 -307.079321) (xy 268.876037 -307.048196) (xy 268.918658 -307.023589)
			(xy 268.964674 -307.006137) (xy 269.012893 -306.996293) (xy 269.062068 -306.994312) (xy 269.110923 -307.000244)
			(xy 269.158194 -307.013936) (xy 269.202656 -307.035034) (xy 269.243159 -307.06299) (xy 269.278652 -307.097082)
			(xy 269.308217 -307.136426) (xy 269.331088 -307.180003) (xy 269.346672 -307.226684) (xy 269.354567 -307.275261)
			(xy 269.355062 -307.299868) (xy 269.69391 -307.299868) (xy 269.69787 -307.250814) (xy 269.709647 -307.20303)
			(xy 269.728938 -307.157754) (xy 269.755241 -307.116158) (xy 269.787876 -307.079321) (xy 269.825997 -307.048196)
			(xy 269.868618 -307.023589) (xy 269.914634 -307.006137) (xy 269.962853 -306.996293) (xy 270.012028 -306.994312)
			(xy 270.060883 -307.000244) (xy 270.108154 -307.013936) (xy 270.152616 -307.035034) (xy 270.193119 -307.06299)
			(xy 270.228612 -307.097082) (xy 270.258177 -307.136426) (xy 270.281048 -307.180003) (xy 270.296632 -307.226684)
			(xy 270.304527 -307.275261) (xy 270.305022 -307.299868) (xy 270.304527 -307.324475) (xy 270.304348 -307.325576)
			(xy 270.62328 -307.325576) (xy 270.62328 -307.27416) (xy 270.631323 -307.223378) (xy 270.647211 -307.174479)
			(xy 270.670554 -307.128667) (xy 270.700775 -307.087071) (xy 270.737131 -307.050715) (xy 270.778727 -307.020494)
			(xy 270.824539 -306.997151) (xy 270.873438 -306.981263) (xy 270.92422 -306.97322) (xy 270.975636 -306.97322)
			(xy 271.026418 -306.981263) (xy 271.075317 -306.997151) (xy 271.121129 -307.020494) (xy 271.162725 -307.050715)
			(xy 271.199081 -307.087071) (xy 271.229302 -307.128667) (xy 271.252645 -307.174479) (xy 271.268533 -307.223378)
			(xy 271.276576 -307.27416) (xy 271.27708 -307.299868) (xy 271.276576 -307.325576) (xy 271.57324 -307.325576)
			(xy 271.57324 -307.27416) (xy 271.581283 -307.223378) (xy 271.597171 -307.174479) (xy 271.620514 -307.128667)
			(xy 271.650735 -307.087071) (xy 271.687091 -307.050715) (xy 271.728687 -307.020494) (xy 271.774499 -306.997151)
			(xy 271.823398 -306.981263) (xy 271.87418 -306.97322) (xy 271.925596 -306.97322) (xy 271.976378 -306.981263)
			(xy 272.025277 -306.997151) (xy 272.071089 -307.020494) (xy 272.112685 -307.050715) (xy 272.149041 -307.087071)
			(xy 272.179262 -307.128667) (xy 272.202605 -307.174479) (xy 272.218493 -307.223378) (xy 272.226536 -307.27416)
			(xy 272.22704 -307.299868) (xy 272.544044 -307.299868) (xy 272.548004 -307.250814) (xy 272.559781 -307.20303)
			(xy 272.579072 -307.157754) (xy 272.605375 -307.116158) (xy 272.63801 -307.079321) (xy 272.676131 -307.048196)
			(xy 272.718752 -307.023589) (xy 272.764768 -307.006137) (xy 272.812987 -306.996293) (xy 272.862162 -306.994312)
			(xy 272.911017 -307.000244) (xy 272.958288 -307.013936) (xy 273.00275 -307.035034) (xy 273.043253 -307.06299)
			(xy 273.078746 -307.097082) (xy 273.108311 -307.136426) (xy 273.131182 -307.180003) (xy 273.146766 -307.226684)
			(xy 273.154661 -307.275261) (xy 273.155156 -307.299868) (xy 273.154661 -307.324475) (xy 273.154482 -307.325576)
			(xy 273.47316 -307.325576) (xy 273.47316 -307.27416) (xy 273.481203 -307.223378) (xy 273.497091 -307.174479)
			(xy 273.520434 -307.128667) (xy 273.550655 -307.087071) (xy 273.587011 -307.050715) (xy 273.628607 -307.020494)
			(xy 273.674419 -306.997151) (xy 273.723318 -306.981263) (xy 273.7741 -306.97322) (xy 273.825516 -306.97322)
			(xy 273.876298 -306.981263) (xy 273.925197 -306.997151) (xy 273.971009 -307.020494) (xy 274.012605 -307.050715)
			(xy 274.048961 -307.087071) (xy 274.079182 -307.128667) (xy 274.102525 -307.174479) (xy 274.118413 -307.223378)
			(xy 274.126456 -307.27416) (xy 274.12696 -307.299868) (xy 274.126456 -307.325576) (xy 274.42312 -307.325576)
			(xy 274.42312 -307.27416) (xy 274.431163 -307.223378) (xy 274.447051 -307.174479) (xy 274.470394 -307.128667)
			(xy 274.500615 -307.087071) (xy 274.536971 -307.050715) (xy 274.578567 -307.020494) (xy 274.624379 -306.997151)
			(xy 274.673278 -306.981263) (xy 274.72406 -306.97322) (xy 274.775476 -306.97322) (xy 274.826258 -306.981263)
			(xy 274.875157 -306.997151) (xy 274.920969 -307.020494) (xy 274.962565 -307.050715) (xy 274.998921 -307.087071)
			(xy 275.029142 -307.128667) (xy 275.052485 -307.174479) (xy 275.068373 -307.223378) (xy 275.076416 -307.27416)
			(xy 275.07692 -307.299868) (xy 275.393924 -307.299868) (xy 275.397884 -307.250814) (xy 275.409661 -307.20303)
			(xy 275.428952 -307.157754) (xy 275.455255 -307.116158) (xy 275.48789 -307.079321) (xy 275.526011 -307.048196)
			(xy 275.568632 -307.023589) (xy 275.614648 -307.006137) (xy 275.662867 -306.996293) (xy 275.712042 -306.994312)
			(xy 275.760897 -307.000244) (xy 275.808168 -307.013936) (xy 275.85263 -307.035034) (xy 275.893133 -307.06299)
			(xy 275.928626 -307.097082) (xy 275.958191 -307.136426) (xy 275.981062 -307.180003) (xy 275.996646 -307.226684)
			(xy 276.004541 -307.275261) (xy 276.005036 -307.299868) (xy 276.343884 -307.299868) (xy 276.347844 -307.250814)
			(xy 276.359621 -307.20303) (xy 276.378912 -307.157754) (xy 276.405215 -307.116158) (xy 276.43785 -307.079321)
			(xy 276.475971 -307.048196) (xy 276.518592 -307.023589) (xy 276.564608 -307.006137) (xy 276.612827 -306.996293)
			(xy 276.662002 -306.994312) (xy 276.710857 -307.000244) (xy 276.758128 -307.013936) (xy 276.80259 -307.035034)
			(xy 276.843093 -307.06299) (xy 276.878586 -307.097082) (xy 276.908151 -307.136426) (xy 276.931022 -307.180003)
			(xy 276.946606 -307.226684) (xy 276.954501 -307.275261) (xy 276.954996 -307.299868) (xy 277.294098 -307.299868)
			(xy 277.298058 -307.250814) (xy 277.309835 -307.20303) (xy 277.329126 -307.157754) (xy 277.355429 -307.116158)
			(xy 277.388064 -307.079321) (xy 277.426185 -307.048196) (xy 277.468806 -307.023589) (xy 277.514822 -307.006137)
			(xy 277.563041 -306.996293) (xy 277.612216 -306.994312) (xy 277.661071 -307.000244) (xy 277.708342 -307.013936)
			(xy 277.752804 -307.035034) (xy 277.793307 -307.06299) (xy 277.8288 -307.097082) (xy 277.858365 -307.136426)
			(xy 277.881236 -307.180003) (xy 277.89682 -307.226684) (xy 277.904715 -307.275261) (xy 277.90521 -307.299868)
			(xy 277.904715 -307.324475) (xy 277.89682 -307.373052) (xy 277.881236 -307.419733) (xy 277.858365 -307.46331)
			(xy 277.8288 -307.502654) (xy 277.793307 -307.536746) (xy 277.752804 -307.564702) (xy 277.708342 -307.5858)
			(xy 277.661071 -307.599492) (xy 277.612216 -307.605424) (xy 277.563041 -307.603443) (xy 277.514822 -307.593599)
			(xy 277.468806 -307.576147) (xy 277.426185 -307.55154) (xy 277.388064 -307.520415) (xy 277.355429 -307.483578)
			(xy 277.329126 -307.441982) (xy 277.309835 -307.396706) (xy 277.298058 -307.348922) (xy 277.294098 -307.299868)
			(xy 276.954996 -307.299868) (xy 276.954501 -307.324475) (xy 276.946606 -307.373052) (xy 276.931022 -307.419733)
			(xy 276.908151 -307.46331) (xy 276.878586 -307.502654) (xy 276.843093 -307.536746) (xy 276.80259 -307.564702)
			(xy 276.758128 -307.5858) (xy 276.710857 -307.599492) (xy 276.662002 -307.605424) (xy 276.612827 -307.603443)
			(xy 276.564608 -307.593599) (xy 276.518592 -307.576147) (xy 276.475971 -307.55154) (xy 276.43785 -307.520415)
			(xy 276.405215 -307.483578) (xy 276.378912 -307.441982) (xy 276.359621 -307.396706) (xy 276.347844 -307.348922)
			(xy 276.343884 -307.299868) (xy 276.005036 -307.299868) (xy 276.004541 -307.324475) (xy 275.996646 -307.373052)
			(xy 275.981062 -307.419733) (xy 275.958191 -307.46331) (xy 275.928626 -307.502654) (xy 275.893133 -307.536746)
			(xy 275.85263 -307.564702) (xy 275.808168 -307.5858) (xy 275.760897 -307.599492) (xy 275.712042 -307.605424)
			(xy 275.662867 -307.603443) (xy 275.614648 -307.593599) (xy 275.568632 -307.576147) (xy 275.526011 -307.55154)
			(xy 275.48789 -307.520415) (xy 275.455255 -307.483578) (xy 275.428952 -307.441982) (xy 275.409661 -307.396706)
			(xy 275.397884 -307.348922) (xy 275.393924 -307.299868) (xy 275.07692 -307.299868) (xy 275.076416 -307.325576)
			(xy 275.068373 -307.376358) (xy 275.052485 -307.425257) (xy 275.029142 -307.471069) (xy 274.998921 -307.512665)
			(xy 274.962565 -307.549021) (xy 274.920969 -307.579242) (xy 274.875157 -307.602585) (xy 274.826258 -307.618473)
			(xy 274.775476 -307.626516) (xy 274.72406 -307.626516) (xy 274.673278 -307.618473) (xy 274.624379 -307.602585)
			(xy 274.578567 -307.579242) (xy 274.536971 -307.549021) (xy 274.500615 -307.512665) (xy 274.470394 -307.471069)
			(xy 274.447051 -307.425257) (xy 274.431163 -307.376358) (xy 274.42312 -307.325576) (xy 274.126456 -307.325576)
			(xy 274.118413 -307.376358) (xy 274.102525 -307.425257) (xy 274.079182 -307.471069) (xy 274.048961 -307.512665)
			(xy 274.012605 -307.549021) (xy 273.971009 -307.579242) (xy 273.925197 -307.602585) (xy 273.876298 -307.618473)
			(xy 273.825516 -307.626516) (xy 273.7741 -307.626516) (xy 273.723318 -307.618473) (xy 273.674419 -307.602585)
			(xy 273.628607 -307.579242) (xy 273.587011 -307.549021) (xy 273.550655 -307.512665) (xy 273.520434 -307.471069)
			(xy 273.497091 -307.425257) (xy 273.481203 -307.376358) (xy 273.47316 -307.325576) (xy 273.154482 -307.325576)
			(xy 273.146766 -307.373052) (xy 273.131182 -307.419733) (xy 273.108311 -307.46331) (xy 273.078746 -307.502654)
			(xy 273.043253 -307.536746) (xy 273.00275 -307.564702) (xy 272.958288 -307.5858) (xy 272.911017 -307.599492)
			(xy 272.862162 -307.605424) (xy 272.812987 -307.603443) (xy 272.764768 -307.593599) (xy 272.718752 -307.576147)
			(xy 272.676131 -307.55154) (xy 272.63801 -307.520415) (xy 272.605375 -307.483578) (xy 272.579072 -307.441982)
			(xy 272.559781 -307.396706) (xy 272.548004 -307.348922) (xy 272.544044 -307.299868) (xy 272.22704 -307.299868)
			(xy 272.226536 -307.325576) (xy 272.218493 -307.376358) (xy 272.202605 -307.425257) (xy 272.179262 -307.471069)
			(xy 272.149041 -307.512665) (xy 272.112685 -307.549021) (xy 272.071089 -307.579242) (xy 272.025277 -307.602585)
			(xy 271.976378 -307.618473) (xy 271.925596 -307.626516) (xy 271.87418 -307.626516) (xy 271.823398 -307.618473)
			(xy 271.774499 -307.602585) (xy 271.728687 -307.579242) (xy 271.687091 -307.549021) (xy 271.650735 -307.512665)
			(xy 271.620514 -307.471069) (xy 271.597171 -307.425257) (xy 271.581283 -307.376358) (xy 271.57324 -307.325576)
			(xy 271.276576 -307.325576) (xy 271.268533 -307.376358) (xy 271.252645 -307.425257) (xy 271.229302 -307.471069)
			(xy 271.199081 -307.512665) (xy 271.162725 -307.549021) (xy 271.121129 -307.579242) (xy 271.075317 -307.602585)
			(xy 271.026418 -307.618473) (xy 270.975636 -307.626516) (xy 270.92422 -307.626516) (xy 270.873438 -307.618473)
			(xy 270.824539 -307.602585) (xy 270.778727 -307.579242) (xy 270.737131 -307.549021) (xy 270.700775 -307.512665)
			(xy 270.670554 -307.471069) (xy 270.647211 -307.425257) (xy 270.631323 -307.376358) (xy 270.62328 -307.325576)
			(xy 270.304348 -307.325576) (xy 270.296632 -307.373052) (xy 270.281048 -307.419733) (xy 270.258177 -307.46331)
			(xy 270.228612 -307.502654) (xy 270.193119 -307.536746) (xy 270.152616 -307.564702) (xy 270.108154 -307.5858)
			(xy 270.060883 -307.599492) (xy 270.012028 -307.605424) (xy 269.962853 -307.603443) (xy 269.914634 -307.593599)
			(xy 269.868618 -307.576147) (xy 269.825997 -307.55154) (xy 269.787876 -307.520415) (xy 269.755241 -307.483578)
			(xy 269.728938 -307.441982) (xy 269.709647 -307.396706) (xy 269.69787 -307.348922) (xy 269.69391 -307.299868)
			(xy 269.355062 -307.299868) (xy 269.354567 -307.324475) (xy 269.346672 -307.373052) (xy 269.331088 -307.419733)
			(xy 269.308217 -307.46331) (xy 269.278652 -307.502654) (xy 269.243159 -307.536746) (xy 269.202656 -307.564702)
			(xy 269.158194 -307.5858) (xy 269.110923 -307.599492) (xy 269.062068 -307.605424) (xy 269.012893 -307.603443)
			(xy 268.964674 -307.593599) (xy 268.918658 -307.576147) (xy 268.876037 -307.55154) (xy 268.837916 -307.520415)
			(xy 268.805281 -307.483578) (xy 268.778978 -307.441982) (xy 268.759687 -307.396706) (xy 268.74791 -307.348922)
			(xy 268.74395 -307.299868) (xy 264.641857 -307.299868) (xy 264.645539 -307.305434) (xy 264.669211 -307.355931)
			(xy 264.685279 -307.409338) (xy 264.693399 -307.464514) (xy 264.693908 -307.4924) (xy 264.693399 -307.520286)
			(xy 264.685279 -307.575462) (xy 264.669211 -307.628869) (xy 264.645539 -307.679366) (xy 264.614766 -307.725879)
			(xy 264.577549 -307.767416) (xy 264.568619 -307.774848) (xy 278.719038 -307.774848) (xy 278.722998 -307.725794)
			(xy 278.734775 -307.67801) (xy 278.754066 -307.632734) (xy 278.780369 -307.591138) (xy 278.813004 -307.554301)
			(xy 278.851125 -307.523176) (xy 278.893746 -307.498569) (xy 278.939762 -307.481117) (xy 278.987981 -307.471273)
			(xy 279.037156 -307.469292) (xy 279.086011 -307.475224) (xy 279.133282 -307.488916) (xy 279.177744 -307.510014)
			(xy 279.218247 -307.53797) (xy 279.25374 -307.572062) (xy 279.283305 -307.611406) (xy 279.306176 -307.654983)
			(xy 279.32176 -307.701664) (xy 279.329655 -307.750241) (xy 279.33015 -307.774848) (xy 279.668998 -307.774848)
			(xy 279.672958 -307.725794) (xy 279.684735 -307.67801) (xy 279.704026 -307.632734) (xy 279.730329 -307.591138)
			(xy 279.762964 -307.554301) (xy 279.801085 -307.523176) (xy 279.843706 -307.498569) (xy 279.889722 -307.481117)
			(xy 279.937941 -307.471273) (xy 279.987116 -307.469292) (xy 280.035971 -307.475224) (xy 280.083242 -307.488916)
			(xy 280.127704 -307.510014) (xy 280.168207 -307.53797) (xy 280.2037 -307.572062) (xy 280.233265 -307.611406)
			(xy 280.256136 -307.654983) (xy 280.27172 -307.701664) (xy 280.279615 -307.750241) (xy 280.28011 -307.774848)
			(xy 280.618958 -307.774848) (xy 280.622918 -307.725794) (xy 280.634695 -307.67801) (xy 280.653986 -307.632734)
			(xy 280.680289 -307.591138) (xy 280.712924 -307.554301) (xy 280.751045 -307.523176) (xy 280.793666 -307.498569)
			(xy 280.839682 -307.481117) (xy 280.887901 -307.471273) (xy 280.937076 -307.469292) (xy 280.985931 -307.475224)
			(xy 281.033202 -307.488916) (xy 281.077664 -307.510014) (xy 281.118167 -307.53797) (xy 281.15366 -307.572062)
			(xy 281.183225 -307.611406) (xy 281.206096 -307.654983) (xy 281.22168 -307.701664) (xy 281.229575 -307.750241)
			(xy 281.23007 -307.774848) (xy 281.568918 -307.774848) (xy 281.572878 -307.725794) (xy 281.584655 -307.67801)
			(xy 281.603946 -307.632734) (xy 281.630249 -307.591138) (xy 281.662884 -307.554301) (xy 281.701005 -307.523176)
			(xy 281.743626 -307.498569) (xy 281.789642 -307.481117) (xy 281.837861 -307.471273) (xy 281.887036 -307.469292)
			(xy 281.935891 -307.475224) (xy 281.983162 -307.488916) (xy 282.027624 -307.510014) (xy 282.068127 -307.53797)
			(xy 282.10362 -307.572062) (xy 282.133185 -307.611406) (xy 282.156056 -307.654983) (xy 282.17164 -307.701664)
			(xy 282.179535 -307.750241) (xy 282.18003 -307.774848) (xy 282.519132 -307.774848) (xy 282.523092 -307.725794)
			(xy 282.534869 -307.67801) (xy 282.55416 -307.632734) (xy 282.580463 -307.591138) (xy 282.613098 -307.554301)
			(xy 282.651219 -307.523176) (xy 282.69384 -307.498569) (xy 282.739856 -307.481117) (xy 282.788075 -307.471273)
			(xy 282.83725 -307.469292) (xy 282.886105 -307.475224) (xy 282.933376 -307.488916) (xy 282.977838 -307.510014)
			(xy 283.018341 -307.53797) (xy 283.053834 -307.572062) (xy 283.083399 -307.611406) (xy 283.10627 -307.654983)
			(xy 283.121854 -307.701664) (xy 283.129749 -307.750241) (xy 283.130244 -307.774848) (xy 283.469092 -307.774848)
			(xy 283.473052 -307.725794) (xy 283.484829 -307.67801) (xy 283.50412 -307.632734) (xy 283.530423 -307.591138)
			(xy 283.563058 -307.554301) (xy 283.601179 -307.523176) (xy 283.6438 -307.498569) (xy 283.689816 -307.481117)
			(xy 283.738035 -307.471273) (xy 283.78721 -307.469292) (xy 283.836065 -307.475224) (xy 283.883336 -307.488916)
			(xy 283.927798 -307.510014) (xy 283.968301 -307.53797) (xy 284.003794 -307.572062) (xy 284.033359 -307.611406)
			(xy 284.05623 -307.654983) (xy 284.071814 -307.701664) (xy 284.079709 -307.750241) (xy 284.080204 -307.774848)
			(xy 284.419052 -307.774848) (xy 284.423012 -307.725794) (xy 284.434789 -307.67801) (xy 284.45408 -307.632734)
			(xy 284.480383 -307.591138) (xy 284.513018 -307.554301) (xy 284.551139 -307.523176) (xy 284.59376 -307.498569)
			(xy 284.639776 -307.481117) (xy 284.687995 -307.471273) (xy 284.73717 -307.469292) (xy 284.786025 -307.475224)
			(xy 284.833296 -307.488916) (xy 284.877758 -307.510014) (xy 284.918261 -307.53797) (xy 284.953754 -307.572062)
			(xy 284.983319 -307.611406) (xy 285.00619 -307.654983) (xy 285.021774 -307.701664) (xy 285.029669 -307.750241)
			(xy 285.030164 -307.774848) (xy 285.369012 -307.774848) (xy 285.372972 -307.725794) (xy 285.384749 -307.67801)
			(xy 285.40404 -307.632734) (xy 285.430343 -307.591138) (xy 285.462978 -307.554301) (xy 285.501099 -307.523176)
			(xy 285.54372 -307.498569) (xy 285.589736 -307.481117) (xy 285.637955 -307.471273) (xy 285.68713 -307.469292)
			(xy 285.735985 -307.475224) (xy 285.783256 -307.488916) (xy 285.827718 -307.510014) (xy 285.868221 -307.53797)
			(xy 285.903714 -307.572062) (xy 285.933279 -307.611406) (xy 285.95615 -307.654983) (xy 285.971734 -307.701664)
			(xy 285.979629 -307.750241) (xy 285.980124 -307.774848) (xy 286.318972 -307.774848) (xy 286.322932 -307.725794)
			(xy 286.334709 -307.67801) (xy 286.354 -307.632734) (xy 286.380303 -307.591138) (xy 286.412938 -307.554301)
			(xy 286.451059 -307.523176) (xy 286.49368 -307.498569) (xy 286.539696 -307.481117) (xy 286.587915 -307.471273)
			(xy 286.63709 -307.469292) (xy 286.685945 -307.475224) (xy 286.733216 -307.488916) (xy 286.777678 -307.510014)
			(xy 286.818181 -307.53797) (xy 286.853674 -307.572062) (xy 286.883239 -307.611406) (xy 286.90611 -307.654983)
			(xy 286.921694 -307.701664) (xy 286.929589 -307.750241) (xy 286.930084 -307.774848) (xy 287.268932 -307.774848)
			(xy 287.272892 -307.725794) (xy 287.284669 -307.67801) (xy 287.30396 -307.632734) (xy 287.330263 -307.591138)
			(xy 287.362898 -307.554301) (xy 287.401019 -307.523176) (xy 287.44364 -307.498569) (xy 287.489656 -307.481117)
			(xy 287.537875 -307.471273) (xy 287.58705 -307.469292) (xy 287.635905 -307.475224) (xy 287.683176 -307.488916)
			(xy 287.727638 -307.510014) (xy 287.768141 -307.53797) (xy 287.803634 -307.572062) (xy 287.833199 -307.611406)
			(xy 287.85607 -307.654983) (xy 287.871654 -307.701664) (xy 287.879549 -307.750241) (xy 287.880044 -307.774848)
			(xy 288.219146 -307.774848) (xy 288.223106 -307.725794) (xy 288.234883 -307.67801) (xy 288.254174 -307.632734)
			(xy 288.280477 -307.591138) (xy 288.313112 -307.554301) (xy 288.351233 -307.523176) (xy 288.393854 -307.498569)
			(xy 288.43987 -307.481117) (xy 288.488089 -307.471273) (xy 288.537264 -307.469292) (xy 288.586119 -307.475224)
			(xy 288.63339 -307.488916) (xy 288.677852 -307.510014) (xy 288.718355 -307.53797) (xy 288.753848 -307.572062)
			(xy 288.783413 -307.611406) (xy 288.806284 -307.654983) (xy 288.821868 -307.701664) (xy 288.829763 -307.750241)
			(xy 288.830258 -307.774848) (xy 289.169106 -307.774848) (xy 289.173066 -307.725794) (xy 289.184843 -307.67801)
			(xy 289.204134 -307.632734) (xy 289.230437 -307.591138) (xy 289.263072 -307.554301) (xy 289.301193 -307.523176)
			(xy 289.343814 -307.498569) (xy 289.38983 -307.481117) (xy 289.438049 -307.471273) (xy 289.487224 -307.469292)
			(xy 289.536079 -307.475224) (xy 289.58335 -307.488916) (xy 289.627812 -307.510014) (xy 289.668315 -307.53797)
			(xy 289.703808 -307.572062) (xy 289.733373 -307.611406) (xy 289.756244 -307.654983) (xy 289.771828 -307.701664)
			(xy 289.779723 -307.750241) (xy 289.780218 -307.774848) (xy 290.119066 -307.774848) (xy 290.123026 -307.725794)
			(xy 290.134803 -307.67801) (xy 290.154094 -307.632734) (xy 290.180397 -307.591138) (xy 290.213032 -307.554301)
			(xy 290.251153 -307.523176) (xy 290.293774 -307.498569) (xy 290.33979 -307.481117) (xy 290.388009 -307.471273)
			(xy 290.437184 -307.469292) (xy 290.486039 -307.475224) (xy 290.53331 -307.488916) (xy 290.577772 -307.510014)
			(xy 290.618275 -307.53797) (xy 290.653768 -307.572062) (xy 290.683333 -307.611406) (xy 290.706204 -307.654983)
			(xy 290.721788 -307.701664) (xy 290.729683 -307.750241) (xy 290.730178 -307.774848) (xy 292.018986 -307.774848)
			(xy 292.022946 -307.725794) (xy 292.034723 -307.67801) (xy 292.054014 -307.632734) (xy 292.080317 -307.591138)
			(xy 292.112952 -307.554301) (xy 292.151073 -307.523176) (xy 292.193694 -307.498569) (xy 292.23971 -307.481117)
			(xy 292.287929 -307.471273) (xy 292.337104 -307.469292) (xy 292.385959 -307.475224) (xy 292.43323 -307.488916)
			(xy 292.477692 -307.510014) (xy 292.518195 -307.53797) (xy 292.553688 -307.572062) (xy 292.583253 -307.611406)
			(xy 292.606124 -307.654983) (xy 292.621708 -307.701664) (xy 292.629603 -307.750241) (xy 292.630098 -307.774848)
			(xy 292.968946 -307.774848) (xy 292.972906 -307.725794) (xy 292.984683 -307.67801) (xy 293.003974 -307.632734)
			(xy 293.030277 -307.591138) (xy 293.062912 -307.554301) (xy 293.101033 -307.523176) (xy 293.143654 -307.498569)
			(xy 293.18967 -307.481117) (xy 293.237889 -307.471273) (xy 293.287064 -307.469292) (xy 293.335919 -307.475224)
			(xy 293.38319 -307.488916) (xy 293.427652 -307.510014) (xy 293.468155 -307.53797) (xy 293.503648 -307.572062)
			(xy 293.533213 -307.611406) (xy 293.556084 -307.654983) (xy 293.571668 -307.701664) (xy 293.579563 -307.750241)
			(xy 293.580058 -307.774848) (xy 293.918906 -307.774848) (xy 293.922866 -307.725794) (xy 293.934643 -307.67801)
			(xy 293.953934 -307.632734) (xy 293.980237 -307.591138) (xy 294.012872 -307.554301) (xy 294.050993 -307.523176)
			(xy 294.093614 -307.498569) (xy 294.13963 -307.481117) (xy 294.187849 -307.471273) (xy 294.237024 -307.469292)
			(xy 294.285879 -307.475224) (xy 294.33315 -307.488916) (xy 294.377612 -307.510014) (xy 294.418115 -307.53797)
			(xy 294.453608 -307.572062) (xy 294.483173 -307.611406) (xy 294.506044 -307.654983) (xy 294.521628 -307.701664)
			(xy 294.529523 -307.750241) (xy 294.530013 -307.774594) (xy 294.868866 -307.774594) (xy 294.872826 -307.72554)
			(xy 294.884603 -307.677756) (xy 294.903894 -307.63248) (xy 294.930197 -307.590884) (xy 294.962832 -307.554047)
			(xy 295.000953 -307.522922) (xy 295.043574 -307.498315) (xy 295.08959 -307.480863) (xy 295.137809 -307.471019)
			(xy 295.186984 -307.469038) (xy 295.235839 -307.47497) (xy 295.28311 -307.488662) (xy 295.327572 -307.50976)
			(xy 295.368075 -307.537716) (xy 295.403568 -307.571808) (xy 295.433133 -307.611152) (xy 295.456004 -307.654729)
			(xy 295.471588 -307.70141) (xy 295.479483 -307.749987) (xy 295.479978 -307.774594) (xy 295.81908 -307.774594)
			(xy 295.82304 -307.72554) (xy 295.834817 -307.677756) (xy 295.854108 -307.63248) (xy 295.880411 -307.590884)
			(xy 295.913046 -307.554047) (xy 295.951167 -307.522922) (xy 295.993788 -307.498315) (xy 296.039804 -307.480863)
			(xy 296.088023 -307.471019) (xy 296.137198 -307.469038) (xy 296.186053 -307.47497) (xy 296.233324 -307.488662)
			(xy 296.277786 -307.50976) (xy 296.318289 -307.537716) (xy 296.353782 -307.571808) (xy 296.383347 -307.611152)
			(xy 296.406218 -307.654729) (xy 296.421802 -307.70141) (xy 296.429697 -307.749987) (xy 296.430192 -307.774594)
			(xy 296.430187 -307.774848) (xy 296.76904 -307.774848) (xy 296.773 -307.725794) (xy 296.784777 -307.67801)
			(xy 296.804068 -307.632734) (xy 296.830371 -307.591138) (xy 296.863006 -307.554301) (xy 296.901127 -307.523176)
			(xy 296.943748 -307.498569) (xy 296.989764 -307.481117) (xy 297.037983 -307.471273) (xy 297.087158 -307.469292)
			(xy 297.136013 -307.475224) (xy 297.183284 -307.488916) (xy 297.227746 -307.510014) (xy 297.268249 -307.53797)
			(xy 297.303742 -307.572062) (xy 297.333307 -307.611406) (xy 297.356178 -307.654983) (xy 297.371762 -307.701664)
			(xy 297.379657 -307.750241) (xy 297.380152 -307.774848) (xy 297.719 -307.774848) (xy 297.72296 -307.725794)
			(xy 297.734737 -307.67801) (xy 297.754028 -307.632734) (xy 297.780331 -307.591138) (xy 297.812966 -307.554301)
			(xy 297.851087 -307.523176) (xy 297.893708 -307.498569) (xy 297.939724 -307.481117) (xy 297.987943 -307.471273)
			(xy 298.037118 -307.469292) (xy 298.085973 -307.475224) (xy 298.133244 -307.488916) (xy 298.177706 -307.510014)
			(xy 298.218209 -307.53797) (xy 298.253702 -307.572062) (xy 298.283267 -307.611406) (xy 298.306138 -307.654983)
			(xy 298.321722 -307.701664) (xy 298.329617 -307.750241) (xy 298.330112 -307.774848) (xy 298.66896 -307.774848)
			(xy 298.67292 -307.725794) (xy 298.684697 -307.67801) (xy 298.703988 -307.632734) (xy 298.730291 -307.591138)
			(xy 298.762926 -307.554301) (xy 298.801047 -307.523176) (xy 298.843668 -307.498569) (xy 298.889684 -307.481117)
			(xy 298.937903 -307.471273) (xy 298.987078 -307.469292) (xy 299.035933 -307.475224) (xy 299.083204 -307.488916)
			(xy 299.127666 -307.510014) (xy 299.168169 -307.53797) (xy 299.203662 -307.572062) (xy 299.233227 -307.611406)
			(xy 299.256098 -307.654983) (xy 299.271682 -307.701664) (xy 299.279577 -307.750241) (xy 299.280072 -307.774848)
			(xy 299.61892 -307.774848) (xy 299.62288 -307.725794) (xy 299.634657 -307.67801) (xy 299.653948 -307.632734)
			(xy 299.680251 -307.591138) (xy 299.712886 -307.554301) (xy 299.751007 -307.523176) (xy 299.793628 -307.498569)
			(xy 299.839644 -307.481117) (xy 299.887863 -307.471273) (xy 299.937038 -307.469292) (xy 299.985893 -307.475224)
			(xy 300.033164 -307.488916) (xy 300.077626 -307.510014) (xy 300.118129 -307.53797) (xy 300.153622 -307.572062)
			(xy 300.183187 -307.611406) (xy 300.206058 -307.654983) (xy 300.221642 -307.701664) (xy 300.229537 -307.750241)
			(xy 300.230032 -307.774848) (xy 300.229537 -307.799455) (xy 300.221642 -307.848032) (xy 300.206058 -307.894713)
			(xy 300.183187 -307.93829) (xy 300.153622 -307.977634) (xy 300.118129 -308.011726) (xy 300.077626 -308.039682)
			(xy 300.033164 -308.06078) (xy 299.985893 -308.074472) (xy 299.937038 -308.080404) (xy 299.887863 -308.078423)
			(xy 299.839644 -308.068579) (xy 299.793628 -308.051127) (xy 299.751007 -308.02652) (xy 299.712886 -307.995395)
			(xy 299.680251 -307.958558) (xy 299.653948 -307.916962) (xy 299.634657 -307.871686) (xy 299.62288 -307.823902)
			(xy 299.61892 -307.774848) (xy 299.280072 -307.774848) (xy 299.279577 -307.799455) (xy 299.271682 -307.848032)
			(xy 299.256098 -307.894713) (xy 299.233227 -307.93829) (xy 299.203662 -307.977634) (xy 299.168169 -308.011726)
			(xy 299.127666 -308.039682) (xy 299.083204 -308.06078) (xy 299.035933 -308.074472) (xy 298.987078 -308.080404)
			(xy 298.937903 -308.078423) (xy 298.889684 -308.068579) (xy 298.843668 -308.051127) (xy 298.801047 -308.02652)
			(xy 298.762926 -307.995395) (xy 298.730291 -307.958558) (xy 298.703988 -307.916962) (xy 298.684697 -307.871686)
			(xy 298.67292 -307.823902) (xy 298.66896 -307.774848) (xy 298.330112 -307.774848) (xy 298.329617 -307.799455)
			(xy 298.321722 -307.848032) (xy 298.306138 -307.894713) (xy 298.283267 -307.93829) (xy 298.253702 -307.977634)
			(xy 298.218209 -308.011726) (xy 298.177706 -308.039682) (xy 298.133244 -308.06078) (xy 298.085973 -308.074472)
			(xy 298.037118 -308.080404) (xy 297.987943 -308.078423) (xy 297.939724 -308.068579) (xy 297.893708 -308.051127)
			(xy 297.851087 -308.02652) (xy 297.812966 -307.995395) (xy 297.780331 -307.958558) (xy 297.754028 -307.916962)
			(xy 297.734737 -307.871686) (xy 297.72296 -307.823902) (xy 297.719 -307.774848) (xy 297.380152 -307.774848)
			(xy 297.379657 -307.799455) (xy 297.371762 -307.848032) (xy 297.356178 -307.894713) (xy 297.333307 -307.93829)
			(xy 297.303742 -307.977634) (xy 297.268249 -308.011726) (xy 297.227746 -308.039682) (xy 297.183284 -308.06078)
			(xy 297.136013 -308.074472) (xy 297.087158 -308.080404) (xy 297.037983 -308.078423) (xy 296.989764 -308.068579)
			(xy 296.943748 -308.051127) (xy 296.901127 -308.02652) (xy 296.863006 -307.995395) (xy 296.830371 -307.958558)
			(xy 296.804068 -307.916962) (xy 296.784777 -307.871686) (xy 296.773 -307.823902) (xy 296.76904 -307.774848)
			(xy 296.430187 -307.774848) (xy 296.429697 -307.799201) (xy 296.421802 -307.847778) (xy 296.406218 -307.894459)
			(xy 296.383347 -307.938036) (xy 296.353782 -307.97738) (xy 296.318289 -308.011472) (xy 296.277786 -308.039428)
			(xy 296.233324 -308.060526) (xy 296.186053 -308.074218) (xy 296.137198 -308.08015) (xy 296.088023 -308.078169)
			(xy 296.039804 -308.068325) (xy 295.993788 -308.050873) (xy 295.951167 -308.026266) (xy 295.913046 -307.995141)
			(xy 295.880411 -307.958304) (xy 295.854108 -307.916708) (xy 295.834817 -307.871432) (xy 295.82304 -307.823648)
			(xy 295.81908 -307.774594) (xy 295.479978 -307.774594) (xy 295.479483 -307.799201) (xy 295.471588 -307.847778)
			(xy 295.456004 -307.894459) (xy 295.433133 -307.938036) (xy 295.403568 -307.97738) (xy 295.368075 -308.011472)
			(xy 295.327572 -308.039428) (xy 295.28311 -308.060526) (xy 295.235839 -308.074218) (xy 295.186984 -308.08015)
			(xy 295.137809 -308.078169) (xy 295.08959 -308.068325) (xy 295.043574 -308.050873) (xy 295.000953 -308.026266)
			(xy 294.962832 -307.995141) (xy 294.930197 -307.958304) (xy 294.903894 -307.916708) (xy 294.884603 -307.871432)
			(xy 294.872826 -307.823648) (xy 294.868866 -307.774594) (xy 294.530013 -307.774594) (xy 294.530018 -307.774848)
			(xy 294.529523 -307.799455) (xy 294.521628 -307.848032) (xy 294.506044 -307.894713) (xy 294.483173 -307.93829)
			(xy 294.453608 -307.977634) (xy 294.418115 -308.011726) (xy 294.377612 -308.039682) (xy 294.33315 -308.06078)
			(xy 294.285879 -308.074472) (xy 294.237024 -308.080404) (xy 294.187849 -308.078423) (xy 294.13963 -308.068579)
			(xy 294.093614 -308.051127) (xy 294.050993 -308.02652) (xy 294.012872 -307.995395) (xy 293.980237 -307.958558)
			(xy 293.953934 -307.916962) (xy 293.934643 -307.871686) (xy 293.922866 -307.823902) (xy 293.918906 -307.774848)
			(xy 293.580058 -307.774848) (xy 293.579563 -307.799455) (xy 293.571668 -307.848032) (xy 293.556084 -307.894713)
			(xy 293.533213 -307.93829) (xy 293.503648 -307.977634) (xy 293.468155 -308.011726) (xy 293.427652 -308.039682)
			(xy 293.38319 -308.06078) (xy 293.335919 -308.074472) (xy 293.287064 -308.080404) (xy 293.237889 -308.078423)
			(xy 293.18967 -308.068579) (xy 293.143654 -308.051127) (xy 293.101033 -308.02652) (xy 293.062912 -307.995395)
			(xy 293.030277 -307.958558) (xy 293.003974 -307.916962) (xy 292.984683 -307.871686) (xy 292.972906 -307.823902)
			(xy 292.968946 -307.774848) (xy 292.630098 -307.774848) (xy 292.629603 -307.799455) (xy 292.621708 -307.848032)
			(xy 292.606124 -307.894713) (xy 292.583253 -307.93829) (xy 292.553688 -307.977634) (xy 292.518195 -308.011726)
			(xy 292.477692 -308.039682) (xy 292.43323 -308.06078) (xy 292.385959 -308.074472) (xy 292.337104 -308.080404)
			(xy 292.287929 -308.078423) (xy 292.23971 -308.068579) (xy 292.193694 -308.051127) (xy 292.151073 -308.02652)
			(xy 292.112952 -307.995395) (xy 292.080317 -307.958558) (xy 292.054014 -307.916962) (xy 292.034723 -307.871686)
			(xy 292.022946 -307.823902) (xy 292.018986 -307.774848) (xy 290.730178 -307.774848) (xy 290.729683 -307.799455)
			(xy 290.721788 -307.848032) (xy 290.706204 -307.894713) (xy 290.683333 -307.93829) (xy 290.653768 -307.977634)
			(xy 290.618275 -308.011726) (xy 290.577772 -308.039682) (xy 290.53331 -308.06078) (xy 290.486039 -308.074472)
			(xy 290.437184 -308.080404) (xy 290.388009 -308.078423) (xy 290.33979 -308.068579) (xy 290.293774 -308.051127)
			(xy 290.251153 -308.02652) (xy 290.213032 -307.995395) (xy 290.180397 -307.958558) (xy 290.154094 -307.916962)
			(xy 290.134803 -307.871686) (xy 290.123026 -307.823902) (xy 290.119066 -307.774848) (xy 289.780218 -307.774848)
			(xy 289.779723 -307.799455) (xy 289.771828 -307.848032) (xy 289.756244 -307.894713) (xy 289.733373 -307.93829)
			(xy 289.703808 -307.977634) (xy 289.668315 -308.011726) (xy 289.627812 -308.039682) (xy 289.58335 -308.06078)
			(xy 289.536079 -308.074472) (xy 289.487224 -308.080404) (xy 289.438049 -308.078423) (xy 289.38983 -308.068579)
			(xy 289.343814 -308.051127) (xy 289.301193 -308.02652) (xy 289.263072 -307.995395) (xy 289.230437 -307.958558)
			(xy 289.204134 -307.916962) (xy 289.184843 -307.871686) (xy 289.173066 -307.823902) (xy 289.169106 -307.774848)
			(xy 288.830258 -307.774848) (xy 288.829763 -307.799455) (xy 288.821868 -307.848032) (xy 288.806284 -307.894713)
			(xy 288.783413 -307.93829) (xy 288.753848 -307.977634) (xy 288.718355 -308.011726) (xy 288.677852 -308.039682)
			(xy 288.63339 -308.06078) (xy 288.586119 -308.074472) (xy 288.537264 -308.080404) (xy 288.488089 -308.078423)
			(xy 288.43987 -308.068579) (xy 288.393854 -308.051127) (xy 288.351233 -308.02652) (xy 288.313112 -307.995395)
			(xy 288.280477 -307.958558) (xy 288.254174 -307.916962) (xy 288.234883 -307.871686) (xy 288.223106 -307.823902)
			(xy 288.219146 -307.774848) (xy 287.880044 -307.774848) (xy 287.879549 -307.799455) (xy 287.871654 -307.848032)
			(xy 287.85607 -307.894713) (xy 287.833199 -307.93829) (xy 287.803634 -307.977634) (xy 287.768141 -308.011726)
			(xy 287.727638 -308.039682) (xy 287.683176 -308.06078) (xy 287.635905 -308.074472) (xy 287.58705 -308.080404)
			(xy 287.537875 -308.078423) (xy 287.489656 -308.068579) (xy 287.44364 -308.051127) (xy 287.401019 -308.02652)
			(xy 287.362898 -307.995395) (xy 287.330263 -307.958558) (xy 287.30396 -307.916962) (xy 287.284669 -307.871686)
			(xy 287.272892 -307.823902) (xy 287.268932 -307.774848) (xy 286.930084 -307.774848) (xy 286.929589 -307.799455)
			(xy 286.921694 -307.848032) (xy 286.90611 -307.894713) (xy 286.883239 -307.93829) (xy 286.853674 -307.977634)
			(xy 286.818181 -308.011726) (xy 286.777678 -308.039682) (xy 286.733216 -308.06078) (xy 286.685945 -308.074472)
			(xy 286.63709 -308.080404) (xy 286.587915 -308.078423) (xy 286.539696 -308.068579) (xy 286.49368 -308.051127)
			(xy 286.451059 -308.02652) (xy 286.412938 -307.995395) (xy 286.380303 -307.958558) (xy 286.354 -307.916962)
			(xy 286.334709 -307.871686) (xy 286.322932 -307.823902) (xy 286.318972 -307.774848) (xy 285.980124 -307.774848)
			(xy 285.979629 -307.799455) (xy 285.971734 -307.848032) (xy 285.95615 -307.894713) (xy 285.933279 -307.93829)
			(xy 285.903714 -307.977634) (xy 285.868221 -308.011726) (xy 285.827718 -308.039682) (xy 285.783256 -308.06078)
			(xy 285.735985 -308.074472) (xy 285.68713 -308.080404) (xy 285.637955 -308.078423) (xy 285.589736 -308.068579)
			(xy 285.54372 -308.051127) (xy 285.501099 -308.02652) (xy 285.462978 -307.995395) (xy 285.430343 -307.958558)
			(xy 285.40404 -307.916962) (xy 285.384749 -307.871686) (xy 285.372972 -307.823902) (xy 285.369012 -307.774848)
			(xy 285.030164 -307.774848) (xy 285.029669 -307.799455) (xy 285.021774 -307.848032) (xy 285.00619 -307.894713)
			(xy 284.983319 -307.93829) (xy 284.953754 -307.977634) (xy 284.918261 -308.011726) (xy 284.877758 -308.039682)
			(xy 284.833296 -308.06078) (xy 284.786025 -308.074472) (xy 284.73717 -308.080404) (xy 284.687995 -308.078423)
			(xy 284.639776 -308.068579) (xy 284.59376 -308.051127) (xy 284.551139 -308.02652) (xy 284.513018 -307.995395)
			(xy 284.480383 -307.958558) (xy 284.45408 -307.916962) (xy 284.434789 -307.871686) (xy 284.423012 -307.823902)
			(xy 284.419052 -307.774848) (xy 284.080204 -307.774848) (xy 284.079709 -307.799455) (xy 284.071814 -307.848032)
			(xy 284.05623 -307.894713) (xy 284.033359 -307.93829) (xy 284.003794 -307.977634) (xy 283.968301 -308.011726)
			(xy 283.927798 -308.039682) (xy 283.883336 -308.06078) (xy 283.836065 -308.074472) (xy 283.78721 -308.080404)
			(xy 283.738035 -308.078423) (xy 283.689816 -308.068579) (xy 283.6438 -308.051127) (xy 283.601179 -308.02652)
			(xy 283.563058 -307.995395) (xy 283.530423 -307.958558) (xy 283.50412 -307.916962) (xy 283.484829 -307.871686)
			(xy 283.473052 -307.823902) (xy 283.469092 -307.774848) (xy 283.130244 -307.774848) (xy 283.129749 -307.799455)
			(xy 283.121854 -307.848032) (xy 283.10627 -307.894713) (xy 283.083399 -307.93829) (xy 283.053834 -307.977634)
			(xy 283.018341 -308.011726) (xy 282.977838 -308.039682) (xy 282.933376 -308.06078) (xy 282.886105 -308.074472)
			(xy 282.83725 -308.080404) (xy 282.788075 -308.078423) (xy 282.739856 -308.068579) (xy 282.69384 -308.051127)
			(xy 282.651219 -308.02652) (xy 282.613098 -307.995395) (xy 282.580463 -307.958558) (xy 282.55416 -307.916962)
			(xy 282.534869 -307.871686) (xy 282.523092 -307.823902) (xy 282.519132 -307.774848) (xy 282.18003 -307.774848)
			(xy 282.179535 -307.799455) (xy 282.17164 -307.848032) (xy 282.156056 -307.894713) (xy 282.133185 -307.93829)
			(xy 282.10362 -307.977634) (xy 282.068127 -308.011726) (xy 282.027624 -308.039682) (xy 281.983162 -308.06078)
			(xy 281.935891 -308.074472) (xy 281.887036 -308.080404) (xy 281.837861 -308.078423) (xy 281.789642 -308.068579)
			(xy 281.743626 -308.051127) (xy 281.701005 -308.02652) (xy 281.662884 -307.995395) (xy 281.630249 -307.958558)
			(xy 281.603946 -307.916962) (xy 281.584655 -307.871686) (xy 281.572878 -307.823902) (xy 281.568918 -307.774848)
			(xy 281.23007 -307.774848) (xy 281.229575 -307.799455) (xy 281.22168 -307.848032) (xy 281.206096 -307.894713)
			(xy 281.183225 -307.93829) (xy 281.15366 -307.977634) (xy 281.118167 -308.011726) (xy 281.077664 -308.039682)
			(xy 281.033202 -308.06078) (xy 280.985931 -308.074472) (xy 280.937076 -308.080404) (xy 280.887901 -308.078423)
			(xy 280.839682 -308.068579) (xy 280.793666 -308.051127) (xy 280.751045 -308.02652) (xy 280.712924 -307.995395)
			(xy 280.680289 -307.958558) (xy 280.653986 -307.916962) (xy 280.634695 -307.871686) (xy 280.622918 -307.823902)
			(xy 280.618958 -307.774848) (xy 280.28011 -307.774848) (xy 280.279615 -307.799455) (xy 280.27172 -307.848032)
			(xy 280.256136 -307.894713) (xy 280.233265 -307.93829) (xy 280.2037 -307.977634) (xy 280.168207 -308.011726)
			(xy 280.127704 -308.039682) (xy 280.083242 -308.06078) (xy 280.035971 -308.074472) (xy 279.987116 -308.080404)
			(xy 279.937941 -308.078423) (xy 279.889722 -308.068579) (xy 279.843706 -308.051127) (xy 279.801085 -308.02652)
			(xy 279.762964 -307.995395) (xy 279.730329 -307.958558) (xy 279.704026 -307.916962) (xy 279.684735 -307.871686)
			(xy 279.672958 -307.823902) (xy 279.668998 -307.774848) (xy 279.33015 -307.774848) (xy 279.329655 -307.799455)
			(xy 279.32176 -307.848032) (xy 279.306176 -307.894713) (xy 279.283305 -307.93829) (xy 279.25374 -307.977634)
			(xy 279.218247 -308.011726) (xy 279.177744 -308.039682) (xy 279.133282 -308.06078) (xy 279.086011 -308.074472)
			(xy 279.037156 -308.080404) (xy 278.987981 -308.078423) (xy 278.939762 -308.068579) (xy 278.893746 -308.051127)
			(xy 278.851125 -308.02652) (xy 278.813004 -307.995395) (xy 278.780369 -307.958558) (xy 278.754066 -307.916962)
			(xy 278.734775 -307.871686) (xy 278.722998 -307.823902) (xy 278.719038 -307.774848) (xy 264.568619 -307.774848)
			(xy 264.534681 -307.803091) (xy 264.487075 -307.832145) (xy 264.435746 -307.853957) (xy 264.381789 -307.868063)
			(xy 264.326352 -307.874163) (xy 264.270618 -307.872126) (xy 264.215775 -307.861996) (xy 264.162991 -307.843989)
			(xy 264.113391 -307.818488) (xy 264.068033 -307.786037) (xy 264.027884 -307.747328) (xy 263.993798 -307.703185)
			(xy 263.966502 -307.65455) (xy 263.946579 -307.602459) (xy 263.934453 -307.548022) (xy 263.930382 -307.4924)
			(xy 255.945132 -307.4924) (xy 255.945132 -308.450488) (xy 260.278116 -308.450488) (xy 260.282187 -308.394866)
			(xy 260.294313 -308.340429) (xy 260.314236 -308.288338) (xy 260.341532 -308.239703) (xy 260.375618 -308.19556)
			(xy 260.415767 -308.156851) (xy 260.461125 -308.1244) (xy 260.510725 -308.098899) (xy 260.563509 -308.080892)
			(xy 260.618352 -308.070762) (xy 260.674086 -308.068725) (xy 260.729523 -308.074825) (xy 260.78348 -308.088931)
			(xy 260.834809 -308.110743) (xy 260.882415 -308.139797) (xy 260.925283 -308.175472) (xy 260.9625 -308.217009)
			(xy 260.984381 -308.250082) (xy 267.793736 -308.250082) (xy 267.797696 -308.201028) (xy 267.809473 -308.153244)
			(xy 267.828764 -308.107968) (xy 267.855067 -308.066372) (xy 267.887702 -308.029535) (xy 267.925823 -307.99841)
			(xy 267.968444 -307.973803) (xy 268.01446 -307.956351) (xy 268.062679 -307.946507) (xy 268.111854 -307.944526)
			(xy 268.160709 -307.950458) (xy 268.20798 -307.96415) (xy 268.252442 -307.985248) (xy 268.292945 -308.013204)
			(xy 268.328438 -308.047296) (xy 268.358003 -308.08664) (xy 268.380874 -308.130217) (xy 268.396458 -308.176898)
			(xy 268.404353 -308.225475) (xy 268.404848 -308.250082) (xy 268.404353 -308.274689) (xy 268.404215 -308.275536)
			(xy 268.723106 -308.275536) (xy 268.723106 -308.22412) (xy 268.731149 -308.173338) (xy 268.747037 -308.124439)
			(xy 268.77038 -308.078627) (xy 268.800601 -308.037031) (xy 268.836957 -308.000675) (xy 268.878553 -307.970454)
			(xy 268.924365 -307.947111) (xy 268.973264 -307.931223) (xy 269.024046 -307.92318) (xy 269.075462 -307.92318)
			(xy 269.126244 -307.931223) (xy 269.175143 -307.947111) (xy 269.220955 -307.970454) (xy 269.262551 -308.000675)
			(xy 269.298907 -308.037031) (xy 269.329128 -308.078627) (xy 269.352471 -308.124439) (xy 269.368359 -308.173338)
			(xy 269.376402 -308.22412) (xy 269.376906 -308.249828) (xy 269.376402 -308.275536) (xy 269.673066 -308.275536)
			(xy 269.673066 -308.22412) (xy 269.681109 -308.173338) (xy 269.696997 -308.124439) (xy 269.72034 -308.078627)
			(xy 269.750561 -308.037031) (xy 269.786917 -308.000675) (xy 269.828513 -307.970454) (xy 269.874325 -307.947111)
			(xy 269.923224 -307.931223) (xy 269.974006 -307.92318) (xy 270.025422 -307.92318) (xy 270.076204 -307.931223)
			(xy 270.125103 -307.947111) (xy 270.170915 -307.970454) (xy 270.212511 -308.000675) (xy 270.248867 -308.037031)
			(xy 270.279088 -308.078627) (xy 270.302431 -308.124439) (xy 270.318319 -308.173338) (xy 270.326362 -308.22412)
			(xy 270.326866 -308.249828) (xy 270.644124 -308.249828) (xy 270.648084 -308.200774) (xy 270.659861 -308.15299)
			(xy 270.679152 -308.107714) (xy 270.705455 -308.066118) (xy 270.73809 -308.029281) (xy 270.776211 -307.998156)
			(xy 270.818832 -307.973549) (xy 270.864848 -307.956097) (xy 270.913067 -307.946253) (xy 270.962242 -307.944272)
			(xy 271.011097 -307.950204) (xy 271.058368 -307.963896) (xy 271.10283 -307.984994) (xy 271.143333 -308.01295)
			(xy 271.178826 -308.047042) (xy 271.208391 -308.086386) (xy 271.231262 -308.129963) (xy 271.246846 -308.176644)
			(xy 271.254741 -308.225221) (xy 271.255236 -308.249828) (xy 271.594084 -308.249828) (xy 271.598044 -308.200774)
			(xy 271.609821 -308.15299) (xy 271.629112 -308.107714) (xy 271.655415 -308.066118) (xy 271.68805 -308.029281)
			(xy 271.726171 -307.998156) (xy 271.768792 -307.973549) (xy 271.814808 -307.956097) (xy 271.863027 -307.946253)
			(xy 271.912202 -307.944272) (xy 271.961057 -307.950204) (xy 272.008328 -307.963896) (xy 272.05279 -307.984994)
			(xy 272.093293 -308.01295) (xy 272.128786 -308.047042) (xy 272.158351 -308.086386) (xy 272.181222 -308.129963)
			(xy 272.196806 -308.176644) (xy 272.204701 -308.225221) (xy 272.205196 -308.249828) (xy 272.544044 -308.249828)
			(xy 272.548004 -308.200774) (xy 272.559781 -308.15299) (xy 272.579072 -308.107714) (xy 272.605375 -308.066118)
			(xy 272.63801 -308.029281) (xy 272.676131 -307.998156) (xy 272.718752 -307.973549) (xy 272.764768 -307.956097)
			(xy 272.812987 -307.946253) (xy 272.862162 -307.944272) (xy 272.911017 -307.950204) (xy 272.958288 -307.963896)
			(xy 273.00275 -307.984994) (xy 273.043253 -308.01295) (xy 273.078746 -308.047042) (xy 273.108311 -308.086386)
			(xy 273.131182 -308.129963) (xy 273.146766 -308.176644) (xy 273.154661 -308.225221) (xy 273.155156 -308.249828)
			(xy 273.494004 -308.249828) (xy 273.497964 -308.200774) (xy 273.509741 -308.15299) (xy 273.529032 -308.107714)
			(xy 273.555335 -308.066118) (xy 273.58797 -308.029281) (xy 273.626091 -307.998156) (xy 273.668712 -307.973549)
			(xy 273.714728 -307.956097) (xy 273.762947 -307.946253) (xy 273.812122 -307.944272) (xy 273.860977 -307.950204)
			(xy 273.908248 -307.963896) (xy 273.95271 -307.984994) (xy 273.993213 -308.01295) (xy 274.028706 -308.047042)
			(xy 274.058271 -308.086386) (xy 274.081142 -308.129963) (xy 274.096726 -308.176644) (xy 274.104621 -308.225221)
			(xy 274.105116 -308.249828) (xy 274.443964 -308.249828) (xy 274.447924 -308.200774) (xy 274.459701 -308.15299)
			(xy 274.478992 -308.107714) (xy 274.505295 -308.066118) (xy 274.53793 -308.029281) (xy 274.576051 -307.998156)
			(xy 274.618672 -307.973549) (xy 274.664688 -307.956097) (xy 274.712907 -307.946253) (xy 274.762082 -307.944272)
			(xy 274.810937 -307.950204) (xy 274.858208 -307.963896) (xy 274.90267 -307.984994) (xy 274.943173 -308.01295)
			(xy 274.978666 -308.047042) (xy 275.008231 -308.086386) (xy 275.031102 -308.129963) (xy 275.046686 -308.176644)
			(xy 275.054581 -308.225221) (xy 275.055076 -308.249828) (xy 275.054581 -308.274435) (xy 275.054402 -308.275536)
			(xy 275.37308 -308.275536) (xy 275.37308 -308.22412) (xy 275.381123 -308.173338) (xy 275.397011 -308.124439)
			(xy 275.420354 -308.078627) (xy 275.450575 -308.037031) (xy 275.486931 -308.000675) (xy 275.528527 -307.970454)
			(xy 275.574339 -307.947111) (xy 275.623238 -307.931223) (xy 275.67402 -307.92318) (xy 275.725436 -307.92318)
			(xy 275.776218 -307.931223) (xy 275.825117 -307.947111) (xy 275.870929 -307.970454) (xy 275.912525 -308.000675)
			(xy 275.948881 -308.037031) (xy 275.979102 -308.078627) (xy 276.002445 -308.124439) (xy 276.018333 -308.173338)
			(xy 276.026376 -308.22412) (xy 276.02688 -308.249828) (xy 276.026376 -308.275536) (xy 276.32304 -308.275536)
			(xy 276.32304 -308.22412) (xy 276.331083 -308.173338) (xy 276.346971 -308.124439) (xy 276.370314 -308.078627)
			(xy 276.400535 -308.037031) (xy 276.436891 -308.000675) (xy 276.478487 -307.970454) (xy 276.524299 -307.947111)
			(xy 276.573198 -307.931223) (xy 276.62398 -307.92318) (xy 276.675396 -307.92318) (xy 276.726178 -307.931223)
			(xy 276.775077 -307.947111) (xy 276.820889 -307.970454) (xy 276.862485 -308.000675) (xy 276.898841 -308.037031)
			(xy 276.929062 -308.078627) (xy 276.952405 -308.124439) (xy 276.968293 -308.173338) (xy 276.976336 -308.22412)
			(xy 276.97684 -308.249828) (xy 277.294098 -308.249828) (xy 277.298058 -308.200774) (xy 277.309835 -308.15299)
			(xy 277.329126 -308.107714) (xy 277.355429 -308.066118) (xy 277.388064 -308.029281) (xy 277.426185 -307.998156)
			(xy 277.468806 -307.973549) (xy 277.514822 -307.956097) (xy 277.563041 -307.946253) (xy 277.612216 -307.944272)
			(xy 277.661071 -307.950204) (xy 277.708342 -307.963896) (xy 277.752804 -307.984994) (xy 277.793307 -308.01295)
			(xy 277.8288 -308.047042) (xy 277.858365 -308.086386) (xy 277.881236 -308.129963) (xy 277.89682 -308.176644)
			(xy 277.904715 -308.225221) (xy 277.90521 -308.249828) (xy 277.904715 -308.274435) (xy 277.89682 -308.323012)
			(xy 277.881236 -308.369693) (xy 277.858365 -308.41327) (xy 277.8288 -308.452614) (xy 277.793307 -308.486706)
			(xy 277.752804 -308.514662) (xy 277.708342 -308.53576) (xy 277.661071 -308.549452) (xy 277.612216 -308.555384)
			(xy 277.563041 -308.553403) (xy 277.514822 -308.543559) (xy 277.468806 -308.526107) (xy 277.426185 -308.5015)
			(xy 277.388064 -308.470375) (xy 277.355429 -308.433538) (xy 277.329126 -308.391942) (xy 277.309835 -308.346666)
			(xy 277.298058 -308.298882) (xy 277.294098 -308.249828) (xy 276.97684 -308.249828) (xy 276.976336 -308.275536)
			(xy 276.968293 -308.326318) (xy 276.952405 -308.375217) (xy 276.929062 -308.421029) (xy 276.898841 -308.462625)
			(xy 276.862485 -308.498981) (xy 276.820889 -308.529202) (xy 276.775077 -308.552545) (xy 276.726178 -308.568433)
			(xy 276.675396 -308.576476) (xy 276.62398 -308.576476) (xy 276.573198 -308.568433) (xy 276.524299 -308.552545)
			(xy 276.478487 -308.529202) (xy 276.436891 -308.498981) (xy 276.400535 -308.462625) (xy 276.370314 -308.421029)
			(xy 276.346971 -308.375217) (xy 276.331083 -308.326318) (xy 276.32304 -308.275536) (xy 276.026376 -308.275536)
			(xy 276.018333 -308.326318) (xy 276.002445 -308.375217) (xy 275.979102 -308.421029) (xy 275.948881 -308.462625)
			(xy 275.912525 -308.498981) (xy 275.870929 -308.529202) (xy 275.825117 -308.552545) (xy 275.776218 -308.568433)
			(xy 275.725436 -308.576476) (xy 275.67402 -308.576476) (xy 275.623238 -308.568433) (xy 275.574339 -308.552545)
			(xy 275.528527 -308.529202) (xy 275.486931 -308.498981) (xy 275.450575 -308.462625) (xy 275.420354 -308.421029)
			(xy 275.397011 -308.375217) (xy 275.381123 -308.326318) (xy 275.37308 -308.275536) (xy 275.054402 -308.275536)
			(xy 275.046686 -308.323012) (xy 275.031102 -308.369693) (xy 275.008231 -308.41327) (xy 274.978666 -308.452614)
			(xy 274.943173 -308.486706) (xy 274.90267 -308.514662) (xy 274.858208 -308.53576) (xy 274.810937 -308.549452)
			(xy 274.762082 -308.555384) (xy 274.712907 -308.553403) (xy 274.664688 -308.543559) (xy 274.618672 -308.526107)
			(xy 274.576051 -308.5015) (xy 274.53793 -308.470375) (xy 274.505295 -308.433538) (xy 274.478992 -308.391942)
			(xy 274.459701 -308.346666) (xy 274.447924 -308.298882) (xy 274.443964 -308.249828) (xy 274.105116 -308.249828)
			(xy 274.104621 -308.274435) (xy 274.096726 -308.323012) (xy 274.081142 -308.369693) (xy 274.058271 -308.41327)
			(xy 274.028706 -308.452614) (xy 273.993213 -308.486706) (xy 273.95271 -308.514662) (xy 273.908248 -308.53576)
			(xy 273.860977 -308.549452) (xy 273.812122 -308.555384) (xy 273.762947 -308.553403) (xy 273.714728 -308.543559)
			(xy 273.668712 -308.526107) (xy 273.626091 -308.5015) (xy 273.58797 -308.470375) (xy 273.555335 -308.433538)
			(xy 273.529032 -308.391942) (xy 273.509741 -308.346666) (xy 273.497964 -308.298882) (xy 273.494004 -308.249828)
			(xy 273.155156 -308.249828) (xy 273.154661 -308.274435) (xy 273.146766 -308.323012) (xy 273.131182 -308.369693)
			(xy 273.108311 -308.41327) (xy 273.078746 -308.452614) (xy 273.043253 -308.486706) (xy 273.00275 -308.514662)
			(xy 272.958288 -308.53576) (xy 272.911017 -308.549452) (xy 272.862162 -308.555384) (xy 272.812987 -308.553403)
			(xy 272.764768 -308.543559) (xy 272.718752 -308.526107) (xy 272.676131 -308.5015) (xy 272.63801 -308.470375)
			(xy 272.605375 -308.433538) (xy 272.579072 -308.391942) (xy 272.559781 -308.346666) (xy 272.548004 -308.298882)
			(xy 272.544044 -308.249828) (xy 272.205196 -308.249828) (xy 272.204701 -308.274435) (xy 272.196806 -308.323012)
			(xy 272.181222 -308.369693) (xy 272.158351 -308.41327) (xy 272.128786 -308.452614) (xy 272.093293 -308.486706)
			(xy 272.05279 -308.514662) (xy 272.008328 -308.53576) (xy 271.961057 -308.549452) (xy 271.912202 -308.555384)
			(xy 271.863027 -308.553403) (xy 271.814808 -308.543559) (xy 271.768792 -308.526107) (xy 271.726171 -308.5015)
			(xy 271.68805 -308.470375) (xy 271.655415 -308.433538) (xy 271.629112 -308.391942) (xy 271.609821 -308.346666)
			(xy 271.598044 -308.298882) (xy 271.594084 -308.249828) (xy 271.255236 -308.249828) (xy 271.254741 -308.274435)
			(xy 271.246846 -308.323012) (xy 271.231262 -308.369693) (xy 271.208391 -308.41327) (xy 271.178826 -308.452614)
			(xy 271.143333 -308.486706) (xy 271.10283 -308.514662) (xy 271.058368 -308.53576) (xy 271.011097 -308.549452)
			(xy 270.962242 -308.555384) (xy 270.913067 -308.553403) (xy 270.864848 -308.543559) (xy 270.818832 -308.526107)
			(xy 270.776211 -308.5015) (xy 270.73809 -308.470375) (xy 270.705455 -308.433538) (xy 270.679152 -308.391942)
			(xy 270.659861 -308.346666) (xy 270.648084 -308.298882) (xy 270.644124 -308.249828) (xy 270.326866 -308.249828)
			(xy 270.326362 -308.275536) (xy 270.318319 -308.326318) (xy 270.302431 -308.375217) (xy 270.279088 -308.421029)
			(xy 270.248867 -308.462625) (xy 270.212511 -308.498981) (xy 270.170915 -308.529202) (xy 270.125103 -308.552545)
			(xy 270.076204 -308.568433) (xy 270.025422 -308.576476) (xy 269.974006 -308.576476) (xy 269.923224 -308.568433)
			(xy 269.874325 -308.552545) (xy 269.828513 -308.529202) (xy 269.786917 -308.498981) (xy 269.750561 -308.462625)
			(xy 269.72034 -308.421029) (xy 269.696997 -308.375217) (xy 269.681109 -308.326318) (xy 269.673066 -308.275536)
			(xy 269.376402 -308.275536) (xy 269.368359 -308.326318) (xy 269.352471 -308.375217) (xy 269.329128 -308.421029)
			(xy 269.298907 -308.462625) (xy 269.262551 -308.498981) (xy 269.220955 -308.529202) (xy 269.175143 -308.552545)
			(xy 269.126244 -308.568433) (xy 269.075462 -308.576476) (xy 269.024046 -308.576476) (xy 268.973264 -308.568433)
			(xy 268.924365 -308.552545) (xy 268.878553 -308.529202) (xy 268.836957 -308.498981) (xy 268.800601 -308.462625)
			(xy 268.77038 -308.421029) (xy 268.747037 -308.375217) (xy 268.731149 -308.326318) (xy 268.723106 -308.275536)
			(xy 268.404215 -308.275536) (xy 268.396458 -308.323266) (xy 268.380874 -308.369947) (xy 268.358003 -308.413524)
			(xy 268.328438 -308.452868) (xy 268.292945 -308.48696) (xy 268.252442 -308.514916) (xy 268.20798 -308.536014)
			(xy 268.160709 -308.549706) (xy 268.111854 -308.555638) (xy 268.062679 -308.553657) (xy 268.01446 -308.543813)
			(xy 267.968444 -308.526361) (xy 267.925823 -308.501754) (xy 267.887702 -308.470629) (xy 267.855067 -308.433792)
			(xy 267.828764 -308.392196) (xy 267.809473 -308.34692) (xy 267.797696 -308.299136) (xy 267.793736 -308.250082)
			(xy 260.984381 -308.250082) (xy 260.993273 -308.263522) (xy 261.016945 -308.314019) (xy 261.033013 -308.367426)
			(xy 261.041133 -308.422602) (xy 261.041642 -308.450488) (xy 261.041133 -308.478374) (xy 261.033013 -308.53355)
			(xy 261.016945 -308.586957) (xy 260.993273 -308.637454) (xy 260.978668 -308.65953) (xy 262.605518 -308.65953)
			(xy 262.609589 -308.603908) (xy 262.621715 -308.549471) (xy 262.641638 -308.49738) (xy 262.668934 -308.448745)
			(xy 262.70302 -308.404602) (xy 262.743169 -308.365893) (xy 262.788527 -308.333442) (xy 262.838127 -308.307941)
			(xy 262.890911 -308.289934) (xy 262.945754 -308.279804) (xy 263.001488 -308.277767) (xy 263.056925 -308.283867)
			(xy 263.110882 -308.297973) (xy 263.162211 -308.319785) (xy 263.209817 -308.348839) (xy 263.252685 -308.384514)
			(xy 263.289902 -308.426051) (xy 263.320675 -308.472564) (xy 263.344347 -308.523061) (xy 263.360415 -308.576468)
			(xy 263.368535 -308.631644) (xy 263.369044 -308.65953) (xy 263.368535 -308.687416) (xy 263.363032 -308.724808)
			(xy 278.719038 -308.724808) (xy 278.722998 -308.675754) (xy 278.734775 -308.62797) (xy 278.754066 -308.582694)
			(xy 278.780369 -308.541098) (xy 278.813004 -308.504261) (xy 278.851125 -308.473136) (xy 278.893746 -308.448529)
			(xy 278.939762 -308.431077) (xy 278.987981 -308.421233) (xy 279.037156 -308.419252) (xy 279.086011 -308.425184)
			(xy 279.133282 -308.438876) (xy 279.177744 -308.459974) (xy 279.218247 -308.48793) (xy 279.25374 -308.522022)
			(xy 279.283305 -308.561366) (xy 279.306176 -308.604943) (xy 279.32176 -308.651624) (xy 279.329655 -308.700201)
			(xy 279.33015 -308.724808) (xy 279.668998 -308.724808) (xy 279.672958 -308.675754) (xy 279.684735 -308.62797)
			(xy 279.704026 -308.582694) (xy 279.730329 -308.541098) (xy 279.762964 -308.504261) (xy 279.801085 -308.473136)
			(xy 279.843706 -308.448529) (xy 279.889722 -308.431077) (xy 279.937941 -308.421233) (xy 279.987116 -308.419252)
			(xy 280.035971 -308.425184) (xy 280.083242 -308.438876) (xy 280.127704 -308.459974) (xy 280.168207 -308.48793)
			(xy 280.2037 -308.522022) (xy 280.233265 -308.561366) (xy 280.256136 -308.604943) (xy 280.27172 -308.651624)
			(xy 280.279615 -308.700201) (xy 280.28011 -308.724808) (xy 280.618958 -308.724808) (xy 280.622918 -308.675754)
			(xy 280.634695 -308.62797) (xy 280.653986 -308.582694) (xy 280.680289 -308.541098) (xy 280.712924 -308.504261)
			(xy 280.751045 -308.473136) (xy 280.793666 -308.448529) (xy 280.839682 -308.431077) (xy 280.887901 -308.421233)
			(xy 280.937076 -308.419252) (xy 280.985931 -308.425184) (xy 281.033202 -308.438876) (xy 281.077664 -308.459974)
			(xy 281.118167 -308.48793) (xy 281.15366 -308.522022) (xy 281.183225 -308.561366) (xy 281.206096 -308.604943)
			(xy 281.22168 -308.651624) (xy 281.229575 -308.700201) (xy 281.23007 -308.724808) (xy 281.229903 -308.733095)
			(xy 281.568959 -308.733095) (xy 281.571645 -308.683521) (xy 281.582316 -308.635035) (xy 281.600691 -308.588914)
			(xy 281.626285 -308.546374) (xy 281.658424 -308.508534) (xy 281.696262 -308.476393) (xy 281.738802 -308.450797)
			(xy 281.784922 -308.43242) (xy 281.833407 -308.421747) (xy 281.88298 -308.419059) (xy 281.932336 -308.424427)
			(xy 281.980173 -308.437708) (xy 282.02523 -308.458554) (xy 282.066322 -308.486416) (xy 282.102364 -308.520558)
			(xy 282.132409 -308.560081) (xy 282.155663 -308.603945) (xy 282.171514 -308.650992) (xy 282.179545 -308.699985)
			(xy 282.18003 -308.724808) (xy 282.179854 -308.738991) (xy 282.177181 -308.767231) (xy 282.174696 -308.781196)
			(xy 282.172521 -308.795161) (xy 282.1751 -308.823295) (xy 282.18529 -308.849645) (xy 282.202312 -308.872194)
			(xy 282.224862 -308.889214) (xy 282.251213 -308.899402) (xy 282.279347 -308.901979) (xy 282.293314 -308.899814)
			(xy 282.30728 -308.89734) (xy 282.33552 -308.894666) (xy 282.349702 -308.89448) (xy 282.374523 -308.89498)
			(xy 282.423511 -308.903012) (xy 282.470554 -308.918863) (xy 282.514412 -308.942116) (xy 282.553932 -308.972158)
			(xy 282.58807 -309.008198) (xy 282.615927 -309.049286) (xy 282.636771 -309.09434) (xy 282.650051 -309.142173)
			(xy 282.655416 -309.191511) (xy 282.994169 -309.191511) (xy 282.999538 -309.142158) (xy 283.012821 -309.094323)
			(xy 283.033667 -309.049267) (xy 283.061529 -309.008178) (xy 283.09567 -308.972137) (xy 283.135193 -308.942095)
			(xy 283.179056 -308.918843) (xy 283.226103 -308.902994) (xy 283.275094 -308.894965) (xy 283.299916 -308.89448)
			(xy 283.314099 -308.894655) (xy 283.342339 -308.897328) (xy 283.356304 -308.899814) (xy 283.370269 -308.901986)
			(xy 283.398402 -308.899406) (xy 283.42475 -308.889215) (xy 283.447298 -308.872193) (xy 283.464318 -308.849645)
			(xy 283.474507 -308.823295) (xy 283.477085 -308.795162) (xy 283.474922 -308.781196) (xy 283.472449 -308.76723)
			(xy 283.469775 -308.73899) (xy 283.469588 -308.724808) (xy 283.470069 -308.699986) (xy 283.478099 -308.650997)
			(xy 283.49395 -308.603952) (xy 283.517202 -308.56009) (xy 283.547244 -308.520569) (xy 283.583284 -308.486429)
			(xy 283.624373 -308.458569) (xy 283.669428 -308.437723) (xy 283.717262 -308.424441) (xy 283.766614 -308.419073)
			(xy 283.816185 -308.42176) (xy 283.864668 -308.432432) (xy 283.910785 -308.450806) (xy 283.953323 -308.4764)
			(xy 283.991159 -308.508538) (xy 284.023298 -308.546374) (xy 284.048892 -308.588911) (xy 284.067267 -308.635029)
			(xy 284.077939 -308.683511) (xy 284.080178 -308.724808) (xy 284.419052 -308.724808) (xy 284.423012 -308.675754)
			(xy 284.434789 -308.62797) (xy 284.45408 -308.582694) (xy 284.480383 -308.541098) (xy 284.513018 -308.504261)
			(xy 284.551139 -308.473136) (xy 284.59376 -308.448529) (xy 284.639776 -308.431077) (xy 284.687995 -308.421233)
			(xy 284.73717 -308.419252) (xy 284.786025 -308.425184) (xy 284.833296 -308.438876) (xy 284.877758 -308.459974)
			(xy 284.918261 -308.48793) (xy 284.953754 -308.522022) (xy 284.983319 -308.561366) (xy 285.00619 -308.604943)
			(xy 285.021774 -308.651624) (xy 285.029669 -308.700201) (xy 285.030164 -308.724808) (xy 285.369012 -308.724808)
			(xy 285.372972 -308.675754) (xy 285.384749 -308.62797) (xy 285.40404 -308.582694) (xy 285.430343 -308.541098)
			(xy 285.462978 -308.504261) (xy 285.501099 -308.473136) (xy 285.54372 -308.448529) (xy 285.589736 -308.431077)
			(xy 285.637955 -308.421233) (xy 285.68713 -308.419252) (xy 285.735985 -308.425184) (xy 285.783256 -308.438876)
			(xy 285.827718 -308.459974) (xy 285.868221 -308.48793) (xy 285.903714 -308.522022) (xy 285.933279 -308.561366)
			(xy 285.95615 -308.604943) (xy 285.971734 -308.651624) (xy 285.979629 -308.700201) (xy 285.980124 -308.724808)
			(xy 286.318972 -308.724808) (xy 286.322932 -308.675754) (xy 286.334709 -308.62797) (xy 286.354 -308.582694)
			(xy 286.380303 -308.541098) (xy 286.412938 -308.504261) (xy 286.451059 -308.473136) (xy 286.49368 -308.448529)
			(xy 286.539696 -308.431077) (xy 286.587915 -308.421233) (xy 286.63709 -308.419252) (xy 286.685945 -308.425184)
			(xy 286.733216 -308.438876) (xy 286.777678 -308.459974) (xy 286.818181 -308.48793) (xy 286.853674 -308.522022)
			(xy 286.883239 -308.561366) (xy 286.90611 -308.604943) (xy 286.921694 -308.651624) (xy 286.929589 -308.700201)
			(xy 286.930084 -308.724808) (xy 286.929917 -308.733104) (xy 287.268946 -308.733104) (xy 287.27163 -308.683528)
			(xy 287.2823 -308.635039) (xy 287.300675 -308.588915) (xy 287.326269 -308.546371) (xy 287.358409 -308.508529)
			(xy 287.396249 -308.476386) (xy 287.43879 -308.450787) (xy 287.484912 -308.432409) (xy 287.5334 -308.421734)
			(xy 287.582976 -308.419045) (xy 287.632334 -308.424412) (xy 287.680174 -308.437694) (xy 287.725234 -308.458541)
			(xy 287.766328 -308.486403) (xy 287.802373 -308.520547) (xy 287.83242 -308.560072) (xy 287.855675 -308.603938)
			(xy 287.871527 -308.650988) (xy 287.879559 -308.699983) (xy 287.880044 -308.724808) (xy 287.879868 -308.738991)
			(xy 287.877195 -308.767231) (xy 287.87471 -308.781196) (xy 287.872424 -308.793642) (xy 287.87979 -308.817264)
			(xy 287.95726 -308.894734) (xy 287.980882 -308.9021) (xy 287.993328 -308.899814) (xy 288.007294 -308.897338)
			(xy 288.035533 -308.894666) (xy 288.049716 -308.89448) (xy 288.063963 -308.894645) (xy 288.092331 -308.897316)
			(xy 288.106358 -308.899814) (xy 288.11855 -308.9021) (xy 288.14268 -308.894734) (xy 288.219896 -308.817518)
			(xy 288.227262 -308.793642) (xy 288.224976 -308.781196) (xy 288.222503 -308.76723) (xy 288.219829 -308.73899)
			(xy 288.219642 -308.724808) (xy 288.220069 -308.699987) (xy 288.228099 -308.650999) (xy 288.243948 -308.603956)
			(xy 288.267198 -308.560096) (xy 288.297238 -308.520575) (xy 288.333276 -308.486435) (xy 288.374363 -308.458575)
			(xy 288.419415 -308.437728) (xy 288.467246 -308.424444) (xy 288.516596 -308.419074) (xy 288.566165 -308.421758)
			(xy 288.614647 -308.432425) (xy 288.660764 -308.450796) (xy 288.703302 -308.476385) (xy 288.74114 -308.508519)
			(xy 288.773281 -308.54635) (xy 288.798878 -308.588884) (xy 288.817258 -308.634997) (xy 288.827935 -308.683477)
			(xy 288.83018 -308.724808) (xy 290.119066 -308.724808) (xy 290.123026 -308.675754) (xy 290.134803 -308.62797)
			(xy 290.154094 -308.582694) (xy 290.180397 -308.541098) (xy 290.213032 -308.504261) (xy 290.251153 -308.473136)
			(xy 290.293774 -308.448529) (xy 290.33979 -308.431077) (xy 290.388009 -308.421233) (xy 290.437184 -308.419252)
			(xy 290.486039 -308.425184) (xy 290.53331 -308.438876) (xy 290.577772 -308.459974) (xy 290.618275 -308.48793)
			(xy 290.653768 -308.522022) (xy 290.683333 -308.561366) (xy 290.706204 -308.604943) (xy 290.721788 -308.651624)
			(xy 290.729683 -308.700201) (xy 290.730178 -308.724808) (xy 290.730012 -308.733072) (xy 292.019091 -308.733072)
			(xy 292.02178 -308.683505) (xy 292.032452 -308.635026) (xy 292.050828 -308.588912) (xy 292.076421 -308.546378)
			(xy 292.108558 -308.508546) (xy 292.146393 -308.47641) (xy 292.188928 -308.45082) (xy 292.235043 -308.432447)
			(xy 292.283523 -308.421777) (xy 292.33309 -308.419091) (xy 292.382439 -308.42446) (xy 292.430269 -308.437741)
			(xy 292.475321 -308.458586) (xy 292.516406 -308.486444) (xy 292.552444 -308.520583) (xy 292.582484 -308.560102)
			(xy 292.605734 -308.60396) (xy 292.621583 -308.651002) (xy 292.629613 -308.699988) (xy 292.630098 -308.724808)
			(xy 292.629923 -308.738991) (xy 292.62725 -308.767231) (xy 292.624764 -308.781196) (xy 292.622478 -308.793642)
			(xy 292.629844 -308.817264) (xy 292.707314 -308.894734) (xy 292.730936 -308.9021) (xy 292.743382 -308.899814)
			(xy 292.757347 -308.89733) (xy 292.785587 -308.894663) (xy 292.79977 -308.89448) (xy 292.813953 -308.894661)
			(xy 292.842193 -308.89733) (xy 292.856158 -308.899814) (xy 292.868604 -308.9021) (xy 292.892226 -308.894734)
			(xy 292.969696 -308.817264) (xy 292.977062 -308.793642) (xy 292.974776 -308.781196) (xy 292.972303 -308.76723)
			(xy 292.969629 -308.73899) (xy 292.969442 -308.724808) (xy 292.969964 -308.699553) (xy 292.978277 -308.649731)
			(xy 292.994678 -308.601957) (xy 293.018719 -308.557534) (xy 293.049743 -308.517674) (xy 293.086905 -308.483464)
			(xy 293.129191 -308.455838) (xy 293.175447 -308.435548) (xy 293.224412 -308.423148) (xy 293.27475 -308.418977)
			(xy 293.325088 -308.423148) (xy 293.374053 -308.435548) (xy 293.420309 -308.455838) (xy 293.462595 -308.483464)
			(xy 293.499757 -308.517674) (xy 293.530781 -308.557534) (xy 293.554822 -308.601957) (xy 293.571223 -308.649731)
			(xy 293.579536 -308.699553) (xy 293.580058 -308.724808) (xy 293.579883 -308.738991) (xy 293.57721 -308.767231)
			(xy 293.574724 -308.781196) (xy 293.572438 -308.793642) (xy 293.579804 -308.817264) (xy 293.657274 -308.894734)
			(xy 293.680896 -308.9021) (xy 293.693342 -308.899814) (xy 293.707308 -308.897336) (xy 293.735547 -308.894665)
			(xy 293.74973 -308.89448) (xy 293.763913 -308.894653) (xy 293.792153 -308.897327) (xy 293.806118 -308.899814)
			(xy 293.818564 -308.9021) (xy 293.842186 -308.894734) (xy 293.919656 -308.817264) (xy 293.927022 -308.793642)
			(xy 293.924736 -308.781196) (xy 293.922263 -308.76723) (xy 293.919589 -308.73899) (xy 293.919402 -308.724808)
			(xy 293.919869 -308.699987) (xy 293.927899 -308.650997) (xy 293.943749 -308.603953) (xy 293.967001 -308.560092)
			(xy 293.997043 -308.520571) (xy 294.033082 -308.48643) (xy 294.07417 -308.45857) (xy 294.119225 -308.437724)
			(xy 294.167058 -308.424442) (xy 294.216409 -308.419073) (xy 294.26598 -308.42176) (xy 294.314462 -308.43243)
			(xy 294.36058 -308.450803) (xy 294.403118 -308.476396) (xy 294.440954 -308.508533) (xy 294.473094 -308.546368)
			(xy 294.498689 -308.588904) (xy 294.517065 -308.635021) (xy 294.527738 -308.683503) (xy 294.529965 -308.724554)
			(xy 294.868866 -308.724554) (xy 294.872826 -308.6755) (xy 294.884603 -308.627716) (xy 294.903894 -308.58244)
			(xy 294.930197 -308.540844) (xy 294.962832 -308.504007) (xy 295.000953 -308.472882) (xy 295.043574 -308.448275)
			(xy 295.08959 -308.430823) (xy 295.137809 -308.420979) (xy 295.186984 -308.418998) (xy 295.235839 -308.42493)
			(xy 295.28311 -308.438622) (xy 295.327572 -308.45972) (xy 295.368075 -308.487676) (xy 295.403568 -308.521768)
			(xy 295.433133 -308.561112) (xy 295.456004 -308.604689) (xy 295.471588 -308.65137) (xy 295.479483 -308.699947)
			(xy 295.479978 -308.724554) (xy 295.479973 -308.724808) (xy 295.81908 -308.724808) (xy 295.82304 -308.675754)
			(xy 295.834817 -308.62797) (xy 295.854108 -308.582694) (xy 295.880411 -308.541098) (xy 295.913046 -308.504261)
			(xy 295.951167 -308.473136) (xy 295.993788 -308.448529) (xy 296.039804 -308.431077) (xy 296.088023 -308.421233)
			(xy 296.137198 -308.419252) (xy 296.186053 -308.425184) (xy 296.233324 -308.438876) (xy 296.277786 -308.459974)
			(xy 296.318289 -308.48793) (xy 296.353782 -308.522022) (xy 296.383347 -308.561366) (xy 296.406218 -308.604943)
			(xy 296.421802 -308.651624) (xy 296.429697 -308.700201) (xy 296.430192 -308.724808) (xy 296.76904 -308.724808)
			(xy 296.773 -308.675754) (xy 296.784777 -308.62797) (xy 296.804068 -308.582694) (xy 296.830371 -308.541098)
			(xy 296.863006 -308.504261) (xy 296.901127 -308.473136) (xy 296.943748 -308.448529) (xy 296.989764 -308.431077)
			(xy 297.037983 -308.421233) (xy 297.087158 -308.419252) (xy 297.136013 -308.425184) (xy 297.183284 -308.438876)
			(xy 297.227746 -308.459974) (xy 297.268249 -308.48793) (xy 297.303742 -308.522022) (xy 297.333307 -308.561366)
			(xy 297.356178 -308.604943) (xy 297.371762 -308.651624) (xy 297.379657 -308.700201) (xy 297.380152 -308.724808)
			(xy 297.719 -308.724808) (xy 297.72296 -308.675754) (xy 297.734737 -308.62797) (xy 297.754028 -308.582694)
			(xy 297.780331 -308.541098) (xy 297.812966 -308.504261) (xy 297.851087 -308.473136) (xy 297.893708 -308.448529)
			(xy 297.939724 -308.431077) (xy 297.987943 -308.421233) (xy 298.037118 -308.419252) (xy 298.085973 -308.425184)
			(xy 298.133244 -308.438876) (xy 298.177706 -308.459974) (xy 298.218209 -308.48793) (xy 298.253702 -308.522022)
			(xy 298.283267 -308.561366) (xy 298.306138 -308.604943) (xy 298.321722 -308.651624) (xy 298.329617 -308.700201)
			(xy 298.330112 -308.724808) (xy 298.66896 -308.724808) (xy 298.67292 -308.675754) (xy 298.684697 -308.62797)
			(xy 298.703988 -308.582694) (xy 298.730291 -308.541098) (xy 298.762926 -308.504261) (xy 298.801047 -308.473136)
			(xy 298.843668 -308.448529) (xy 298.889684 -308.431077) (xy 298.937903 -308.421233) (xy 298.987078 -308.419252)
			(xy 299.035933 -308.425184) (xy 299.083204 -308.438876) (xy 299.127666 -308.459974) (xy 299.168169 -308.48793)
			(xy 299.203662 -308.522022) (xy 299.233227 -308.561366) (xy 299.256098 -308.604943) (xy 299.271682 -308.651624)
			(xy 299.279577 -308.700201) (xy 299.280072 -308.724808) (xy 299.61892 -308.724808) (xy 299.62288 -308.675754)
			(xy 299.634657 -308.62797) (xy 299.653948 -308.582694) (xy 299.680251 -308.541098) (xy 299.712886 -308.504261)
			(xy 299.751007 -308.473136) (xy 299.793628 -308.448529) (xy 299.839644 -308.431077) (xy 299.887863 -308.421233)
			(xy 299.937038 -308.419252) (xy 299.985893 -308.425184) (xy 300.033164 -308.438876) (xy 300.077626 -308.459974)
			(xy 300.118129 -308.48793) (xy 300.153622 -308.522022) (xy 300.183187 -308.561366) (xy 300.206058 -308.604943)
			(xy 300.221642 -308.651624) (xy 300.229537 -308.700201) (xy 300.230032 -308.724808) (xy 300.229537 -308.749415)
			(xy 300.221642 -308.797992) (xy 300.206058 -308.844673) (xy 300.183187 -308.88825) (xy 300.153622 -308.927594)
			(xy 300.118129 -308.961686) (xy 300.077626 -308.989642) (xy 300.033164 -309.01074) (xy 299.985893 -309.024432)
			(xy 299.937038 -309.030364) (xy 299.887863 -309.028383) (xy 299.839644 -309.018539) (xy 299.793628 -309.001087)
			(xy 299.751007 -308.97648) (xy 299.712886 -308.945355) (xy 299.680251 -308.908518) (xy 299.653948 -308.866922)
			(xy 299.634657 -308.821646) (xy 299.62288 -308.773862) (xy 299.61892 -308.724808) (xy 299.280072 -308.724808)
			(xy 299.279577 -308.749415) (xy 299.271682 -308.797992) (xy 299.256098 -308.844673) (xy 299.233227 -308.88825)
			(xy 299.203662 -308.927594) (xy 299.168169 -308.961686) (xy 299.127666 -308.989642) (xy 299.083204 -309.01074)
			(xy 299.035933 -309.024432) (xy 298.987078 -309.030364) (xy 298.937903 -309.028383) (xy 298.889684 -309.018539)
			(xy 298.843668 -309.001087) (xy 298.801047 -308.97648) (xy 298.762926 -308.945355) (xy 298.730291 -308.908518)
			(xy 298.703988 -308.866922) (xy 298.684697 -308.821646) (xy 298.67292 -308.773862) (xy 298.66896 -308.724808)
			(xy 298.330112 -308.724808) (xy 298.329617 -308.749415) (xy 298.321722 -308.797992) (xy 298.306138 -308.844673)
			(xy 298.283267 -308.88825) (xy 298.253702 -308.927594) (xy 298.218209 -308.961686) (xy 298.177706 -308.989642)
			(xy 298.133244 -309.01074) (xy 298.085973 -309.024432) (xy 298.037118 -309.030364) (xy 297.987943 -309.028383)
			(xy 297.939724 -309.018539) (xy 297.893708 -309.001087) (xy 297.851087 -308.97648) (xy 297.812966 -308.945355)
			(xy 297.780331 -308.908518) (xy 297.754028 -308.866922) (xy 297.734737 -308.821646) (xy 297.72296 -308.773862)
			(xy 297.719 -308.724808) (xy 297.380152 -308.724808) (xy 297.379657 -308.749415) (xy 297.371762 -308.797992)
			(xy 297.356178 -308.844673) (xy 297.333307 -308.88825) (xy 297.303742 -308.927594) (xy 297.268249 -308.961686)
			(xy 297.227746 -308.989642) (xy 297.183284 -309.01074) (xy 297.136013 -309.024432) (xy 297.087158 -309.030364)
			(xy 297.037983 -309.028383) (xy 296.989764 -309.018539) (xy 296.943748 -309.001087) (xy 296.901127 -308.97648)
			(xy 296.863006 -308.945355) (xy 296.830371 -308.908518) (xy 296.804068 -308.866922) (xy 296.784777 -308.821646)
			(xy 296.773 -308.773862) (xy 296.76904 -308.724808) (xy 296.430192 -308.724808) (xy 296.429697 -308.749415)
			(xy 296.421802 -308.797992) (xy 296.406218 -308.844673) (xy 296.383347 -308.88825) (xy 296.353782 -308.927594)
			(xy 296.318289 -308.961686) (xy 296.277786 -308.989642) (xy 296.233324 -309.01074) (xy 296.186053 -309.024432)
			(xy 296.137198 -309.030364) (xy 296.088023 -309.028383) (xy 296.039804 -309.018539) (xy 295.993788 -309.001087)
			(xy 295.951167 -308.97648) (xy 295.913046 -308.945355) (xy 295.880411 -308.908518) (xy 295.854108 -308.866922)
			(xy 295.834817 -308.821646) (xy 295.82304 -308.773862) (xy 295.81908 -308.724808) (xy 295.479973 -308.724808)
			(xy 295.479483 -308.749161) (xy 295.471588 -308.797738) (xy 295.456004 -308.844419) (xy 295.433133 -308.887996)
			(xy 295.403568 -308.92734) (xy 295.368075 -308.961432) (xy 295.327572 -308.989388) (xy 295.28311 -309.010486)
			(xy 295.235839 -309.024178) (xy 295.186984 -309.03011) (xy 295.137809 -309.028129) (xy 295.08959 -309.018285)
			(xy 295.043574 -309.000833) (xy 295.000953 -308.976226) (xy 294.962832 -308.945101) (xy 294.930197 -308.908264)
			(xy 294.903894 -308.866668) (xy 294.884603 -308.821392) (xy 294.872826 -308.773608) (xy 294.868866 -308.724554)
			(xy 294.529965 -308.724554) (xy 294.530427 -308.733073) (xy 294.525061 -308.782425) (xy 294.511782 -308.830259)
			(xy 294.490939 -308.875314) (xy 294.463081 -308.916404) (xy 294.428943 -308.952445) (xy 294.389423 -308.982489)
			(xy 294.345564 -309.005744) (xy 294.29852 -309.021596) (xy 294.249531 -309.029629) (xy 294.22471 -309.030116)
			(xy 294.210527 -309.029938) (xy 294.182287 -309.027267) (xy 294.168322 -309.024782) (xy 294.155876 -309.022496)
			(xy 294.132254 -309.029862) (xy 294.054784 -309.107332) (xy 294.047418 -309.130954) (xy 294.049704 -309.1434)
			(xy 294.052177 -309.157367) (xy 294.054851 -309.185606) (xy 294.055038 -309.199788) (xy 294.054516 -309.225043)
			(xy 294.046203 -309.274865) (xy 294.029802 -309.322639) (xy 294.005761 -309.367062) (xy 293.974737 -309.406922)
			(xy 293.937575 -309.441132) (xy 293.895289 -309.468758) (xy 293.849033 -309.489048) (xy 293.800068 -309.501448)
			(xy 293.74973 -309.505619) (xy 293.699392 -309.501448) (xy 293.650427 -309.489048) (xy 293.604171 -309.468758)
			(xy 293.561885 -309.441132) (xy 293.524723 -309.406922) (xy 293.493699 -309.367062) (xy 293.469658 -309.322639)
			(xy 293.453257 -309.274865) (xy 293.444944 -309.225043) (xy 293.444422 -309.199788) (xy 293.444596 -309.185605)
			(xy 293.44727 -309.157365) (xy 293.449756 -309.1434) (xy 293.452042 -309.130954) (xy 293.444676 -309.107332)
			(xy 293.367206 -309.029862) (xy 293.343584 -309.022496) (xy 293.331138 -309.024782) (xy 293.317173 -309.027263)
			(xy 293.288933 -309.029932) (xy 293.27475 -309.030116) (xy 293.260567 -309.029932) (xy 293.232327 -309.027265)
			(xy 293.218362 -309.024782) (xy 293.205916 -309.022496) (xy 293.182294 -309.029862) (xy 293.104824 -309.107332)
			(xy 293.097458 -309.130954) (xy 293.099744 -309.1434) (xy 293.102216 -309.157367) (xy 293.104891 -309.185606)
			(xy 293.105078 -309.199788) (xy 293.104556 -309.225043) (xy 293.096243 -309.274865) (xy 293.079842 -309.322639)
			(xy 293.055801 -309.367062) (xy 293.024777 -309.406922) (xy 292.987615 -309.441132) (xy 292.945329 -309.468758)
			(xy 292.899073 -309.489048) (xy 292.850108 -309.501448) (xy 292.79977 -309.505619) (xy 292.749432 -309.501448)
			(xy 292.700467 -309.489048) (xy 292.654211 -309.468758) (xy 292.611925 -309.441132) (xy 292.574763 -309.406922)
			(xy 292.543739 -309.367062) (xy 292.519698 -309.322639) (xy 292.503297 -309.274865) (xy 292.494984 -309.225043)
			(xy 292.494462 -309.199788) (xy 292.494637 -309.185605) (xy 292.49731 -309.157365) (xy 292.499796 -309.1434)
			(xy 292.502082 -309.130954) (xy 292.494716 -309.107332) (xy 292.417246 -309.029862) (xy 292.393624 -309.022496)
			(xy 292.381178 -309.024782) (xy 292.367212 -309.027257) (xy 292.338972 -309.02993) (xy 292.32479 -309.030116)
			(xy 292.29997 -309.029611) (xy 292.250984 -309.021579) (xy 292.203943 -309.005727) (xy 292.160086 -308.982474)
			(xy 292.120569 -308.952432) (xy 292.086433 -308.916392) (xy 292.058577 -308.875305) (xy 292.037735 -308.830252)
			(xy 292.024456 -308.782421) (xy 292.019091 -308.733072) (xy 290.730012 -308.733072) (xy 290.729683 -308.749415)
			(xy 290.721788 -308.797992) (xy 290.706204 -308.844673) (xy 290.683333 -308.88825) (xy 290.653768 -308.927594)
			(xy 290.618275 -308.961686) (xy 290.577772 -308.989642) (xy 290.53331 -309.01074) (xy 290.486039 -309.024432)
			(xy 290.437184 -309.030364) (xy 290.388009 -309.028383) (xy 290.33979 -309.018539) (xy 290.293774 -309.001087)
			(xy 290.251153 -308.97648) (xy 290.213032 -308.945355) (xy 290.180397 -308.908518) (xy 290.154094 -308.866922)
			(xy 290.134803 -308.821646) (xy 290.123026 -308.773862) (xy 290.119066 -308.724808) (xy 288.83018 -308.724808)
			(xy 288.830628 -308.733046) (xy 288.825267 -308.782397) (xy 288.811992 -308.830231) (xy 288.791154 -308.875287)
			(xy 288.763301 -308.916378) (xy 288.729168 -308.952423) (xy 288.689653 -308.98247) (xy 288.645798 -309.005729)
			(xy 288.598757 -309.021587) (xy 288.549771 -309.029626) (xy 288.52495 -309.030116) (xy 288.510703 -309.029949)
			(xy 288.482336 -309.027276) (xy 288.468308 -309.024782) (xy 288.456116 -309.022496) (xy 288.431986 -309.029862)
			(xy 288.35477 -309.107078) (xy 288.347404 -309.130954) (xy 288.34969 -309.1434) (xy 288.352162 -309.157367)
			(xy 288.354837 -309.185606) (xy 288.355024 -309.199788) (xy 288.354502 -309.225043) (xy 288.346189 -309.274865)
			(xy 288.329788 -309.322639) (xy 288.305747 -309.367062) (xy 288.274723 -309.406922) (xy 288.237561 -309.441132)
			(xy 288.195275 -309.468758) (xy 288.149019 -309.489048) (xy 288.100054 -309.501448) (xy 288.049716 -309.505619)
			(xy 287.999378 -309.501448) (xy 287.950413 -309.489048) (xy 287.904157 -309.468758) (xy 287.861871 -309.441132)
			(xy 287.824709 -309.406922) (xy 287.793685 -309.367062) (xy 287.769644 -309.322639) (xy 287.753243 -309.274865)
			(xy 287.74493 -309.225043) (xy 287.744408 -309.199788) (xy 287.744583 -309.185605) (xy 287.747256 -309.157365)
			(xy 287.749742 -309.1434) (xy 287.752028 -309.130954) (xy 287.744662 -309.107332) (xy 287.667192 -309.029862)
			(xy 287.64357 -309.022496) (xy 287.631124 -309.024782) (xy 287.617159 -309.027265) (xy 287.588919 -309.029932)
			(xy 287.574736 -309.030116) (xy 287.549911 -309.029661) (xy 287.500915 -309.021634) (xy 287.453864 -309.005786)
			(xy 287.409996 -308.982535) (xy 287.370468 -308.952492) (xy 287.336321 -308.91645) (xy 287.308454 -308.875359)
			(xy 287.287604 -308.8303) (xy 287.274317 -308.782462) (xy 287.268946 -308.733104) (xy 286.929917 -308.733104)
			(xy 286.929589 -308.749415) (xy 286.921694 -308.797992) (xy 286.90611 -308.844673) (xy 286.883239 -308.88825)
			(xy 286.853674 -308.927594) (xy 286.818181 -308.961686) (xy 286.777678 -308.989642) (xy 286.733216 -309.01074)
			(xy 286.685945 -309.024432) (xy 286.63709 -309.030364) (xy 286.587915 -309.028383) (xy 286.539696 -309.018539)
			(xy 286.49368 -309.001087) (xy 286.451059 -308.97648) (xy 286.412938 -308.945355) (xy 286.380303 -308.908518)
			(xy 286.354 -308.866922) (xy 286.334709 -308.821646) (xy 286.322932 -308.773862) (xy 286.318972 -308.724808)
			(xy 285.980124 -308.724808) (xy 285.979629 -308.749415) (xy 285.971734 -308.797992) (xy 285.95615 -308.844673)
			(xy 285.933279 -308.88825) (xy 285.903714 -308.927594) (xy 285.868221 -308.961686) (xy 285.827718 -308.989642)
			(xy 285.783256 -309.01074) (xy 285.735985 -309.024432) (xy 285.68713 -309.030364) (xy 285.637955 -309.028383)
			(xy 285.589736 -309.018539) (xy 285.54372 -309.001087) (xy 285.501099 -308.97648) (xy 285.462978 -308.945355)
			(xy 285.430343 -308.908518) (xy 285.40404 -308.866922) (xy 285.384749 -308.821646) (xy 285.372972 -308.773862)
			(xy 285.369012 -308.724808) (xy 285.030164 -308.724808) (xy 285.029669 -308.749415) (xy 285.021774 -308.797992)
			(xy 285.00619 -308.844673) (xy 284.983319 -308.88825) (xy 284.953754 -308.927594) (xy 284.918261 -308.961686)
			(xy 284.877758 -308.989642) (xy 284.833296 -309.01074) (xy 284.786025 -309.024432) (xy 284.73717 -309.030364)
			(xy 284.687995 -309.028383) (xy 284.639776 -309.018539) (xy 284.59376 -309.001087) (xy 284.551139 -308.97648)
			(xy 284.513018 -308.945355) (xy 284.480383 -308.908518) (xy 284.45408 -308.866922) (xy 284.434789 -308.821646)
			(xy 284.423012 -308.773862) (xy 284.419052 -308.724808) (xy 284.080178 -308.724808) (xy 284.080627 -308.733082)
			(xy 284.075259 -308.782434) (xy 284.061978 -308.830268) (xy 284.041133 -308.875323) (xy 284.013274 -308.916413)
			(xy 283.979134 -308.952453) (xy 283.939613 -308.982496) (xy 283.895752 -309.005749) (xy 283.848707 -309.0216)
			(xy 283.799718 -309.02963) (xy 283.774896 -309.030116) (xy 283.760713 -309.02994) (xy 283.732473 -309.027267)
			(xy 283.718508 -309.024782) (xy 283.704541 -309.022628) (xy 283.67641 -309.025205) (xy 283.650063 -309.035393)
			(xy 283.627516 -309.052411) (xy 283.610496 -309.074957) (xy 283.600306 -309.101304) (xy 283.597727 -309.129435)
			(xy 283.59989 -309.1434) (xy 283.602362 -309.157367) (xy 283.605037 -309.185606) (xy 283.605224 -309.199788)
			(xy 283.604735 -309.22461) (xy 283.596705 -309.273601) (xy 283.580855 -309.320648) (xy 283.557602 -309.36451)
			(xy 283.52756 -309.404033) (xy 283.491519 -309.438174) (xy 283.450429 -309.466035) (xy 283.405373 -309.486881)
			(xy 283.357538 -309.500163) (xy 283.308185 -309.505531) (xy 283.258613 -309.502843) (xy 283.210129 -309.492172)
			(xy 283.16401 -309.473796) (xy 283.121472 -309.448202) (xy 283.083635 -309.416062) (xy 283.051496 -309.378225)
			(xy 283.025902 -309.335686) (xy 283.007527 -309.289567) (xy 282.996856 -309.241083) (xy 282.994169 -309.191511)
			(xy 282.655416 -309.191511) (xy 282.655417 -309.191524) (xy 282.652729 -309.241092) (xy 282.642056 -309.289573)
			(xy 282.623681 -309.335689) (xy 282.598087 -309.378224) (xy 282.565949 -309.416059) (xy 282.528113 -309.448195)
			(xy 282.485577 -309.473787) (xy 282.43946 -309.49216) (xy 282.390979 -309.50283) (xy 282.34141 -309.505517)
			(xy 282.292059 -309.500148) (xy 282.244227 -309.486866) (xy 282.199174 -309.466021) (xy 282.158087 -309.438161)
			(xy 282.122049 -309.404021) (xy 282.092008 -309.364501) (xy 282.068757 -309.320641) (xy 282.052908 -309.273597)
			(xy 282.044879 -309.224609) (xy 282.044394 -309.199788) (xy 282.044569 -309.185605) (xy 282.047242 -309.157365)
			(xy 282.049728 -309.1434) (xy 282.051879 -309.129433) (xy 282.0493 -309.101304) (xy 282.039111 -309.074958)
			(xy 282.022094 -309.052412) (xy 281.999549 -309.035393) (xy 281.973204 -309.025202) (xy 281.945075 -309.022621)
			(xy 281.93111 -309.024782) (xy 281.917143 -309.027253) (xy 281.888904 -309.029928) (xy 281.874722 -309.030116)
			(xy 281.849899 -309.029646) (xy 281.800906 -309.021617) (xy 281.753857 -309.005768) (xy 281.709993 -308.982516)
			(xy 281.670468 -308.952474) (xy 281.636324 -308.916433) (xy 281.608461 -308.875342) (xy 281.587613 -308.830286)
			(xy 281.574329 -308.78245) (xy 281.568959 -308.733095) (xy 281.229903 -308.733095) (xy 281.229575 -308.749415)
			(xy 281.22168 -308.797992) (xy 281.206096 -308.844673) (xy 281.183225 -308.88825) (xy 281.15366 -308.927594)
			(xy 281.118167 -308.961686) (xy 281.077664 -308.989642) (xy 281.033202 -309.01074) (xy 280.985931 -309.024432)
			(xy 280.937076 -309.030364) (xy 280.887901 -309.028383) (xy 280.839682 -309.018539) (xy 280.793666 -309.001087)
			(xy 280.751045 -308.97648) (xy 280.712924 -308.945355) (xy 280.680289 -308.908518) (xy 280.653986 -308.866922)
			(xy 280.634695 -308.821646) (xy 280.622918 -308.773862) (xy 280.618958 -308.724808) (xy 280.28011 -308.724808)
			(xy 280.279615 -308.749415) (xy 280.27172 -308.797992) (xy 280.256136 -308.844673) (xy 280.233265 -308.88825)
			(xy 280.2037 -308.927594) (xy 280.168207 -308.961686) (xy 280.127704 -308.989642) (xy 280.083242 -309.01074)
			(xy 280.035971 -309.024432) (xy 279.987116 -309.030364) (xy 279.937941 -309.028383) (xy 279.889722 -309.018539)
			(xy 279.843706 -309.001087) (xy 279.801085 -308.97648) (xy 279.762964 -308.945355) (xy 279.730329 -308.908518)
			(xy 279.704026 -308.866922) (xy 279.684735 -308.821646) (xy 279.672958 -308.773862) (xy 279.668998 -308.724808)
			(xy 279.33015 -308.724808) (xy 279.329655 -308.749415) (xy 279.32176 -308.797992) (xy 279.306176 -308.844673)
			(xy 279.283305 -308.88825) (xy 279.25374 -308.927594) (xy 279.218247 -308.961686) (xy 279.177744 -308.989642)
			(xy 279.133282 -309.01074) (xy 279.086011 -309.024432) (xy 279.037156 -309.030364) (xy 278.987981 -309.028383)
			(xy 278.939762 -309.018539) (xy 278.893746 -309.001087) (xy 278.851125 -308.97648) (xy 278.813004 -308.945355)
			(xy 278.780369 -308.908518) (xy 278.754066 -308.866922) (xy 278.734775 -308.821646) (xy 278.722998 -308.773862)
			(xy 278.719038 -308.724808) (xy 263.363032 -308.724808) (xy 263.360415 -308.742592) (xy 263.344347 -308.795999)
			(xy 263.320675 -308.846496) (xy 263.289902 -308.893009) (xy 263.252685 -308.934546) (xy 263.209817 -308.970221)
			(xy 263.162211 -308.999275) (xy 263.110882 -309.021087) (xy 263.056925 -309.035193) (xy 263.001488 -309.041293)
			(xy 262.945754 -309.039256) (xy 262.890911 -309.029126) (xy 262.838127 -309.011119) (xy 262.788527 -308.985618)
			(xy 262.743169 -308.953167) (xy 262.70302 -308.914458) (xy 262.668934 -308.870315) (xy 262.641638 -308.82168)
			(xy 262.621715 -308.769589) (xy 262.609589 -308.715152) (xy 262.605518 -308.65953) (xy 260.978668 -308.65953)
			(xy 260.9625 -308.683967) (xy 260.925283 -308.725504) (xy 260.882415 -308.761179) (xy 260.834809 -308.790233)
			(xy 260.78348 -308.812045) (xy 260.729523 -308.826151) (xy 260.674086 -308.832251) (xy 260.618352 -308.830214)
			(xy 260.563509 -308.820084) (xy 260.510725 -308.802077) (xy 260.461125 -308.776576) (xy 260.415767 -308.744125)
			(xy 260.375618 -308.705416) (xy 260.341532 -308.661273) (xy 260.314236 -308.612638) (xy 260.294313 -308.560547)
			(xy 260.282187 -308.50611) (xy 260.278116 -308.450488) (xy 255.945132 -308.450488) (xy 255.945132 -309.414926)
			(xy 259.199886 -309.414926) (xy 259.203957 -309.359304) (xy 259.216083 -309.304867) (xy 259.236006 -309.252776)
			(xy 259.263302 -309.204141) (xy 259.297388 -309.159998) (xy 259.337537 -309.121289) (xy 259.382895 -309.088838)
			(xy 259.432495 -309.063337) (xy 259.485279 -309.04533) (xy 259.540122 -309.0352) (xy 259.595856 -309.033163)
			(xy 259.651293 -309.039263) (xy 259.70525 -309.053369) (xy 259.756579 -309.075181) (xy 259.804185 -309.104235)
			(xy 259.847053 -309.13991) (xy 259.88427 -309.181447) (xy 259.896404 -309.199788) (xy 268.74395 -309.199788)
			(xy 268.74791 -309.150734) (xy 268.759687 -309.10295) (xy 268.778978 -309.057674) (xy 268.805281 -309.016078)
			(xy 268.837916 -308.979241) (xy 268.876037 -308.948116) (xy 268.918658 -308.923509) (xy 268.964674 -308.906057)
			(xy 269.012893 -308.896213) (xy 269.062068 -308.894232) (xy 269.110923 -308.900164) (xy 269.158194 -308.913856)
			(xy 269.202656 -308.934954) (xy 269.243159 -308.96291) (xy 269.278652 -308.997002) (xy 269.308217 -309.036346)
			(xy 269.331088 -309.079923) (xy 269.346672 -309.126604) (xy 269.354567 -309.175181) (xy 269.355062 -309.199788)
			(xy 269.69391 -309.199788) (xy 269.69787 -309.150734) (xy 269.709647 -309.10295) (xy 269.728938 -309.057674)
			(xy 269.755241 -309.016078) (xy 269.787876 -308.979241) (xy 269.825997 -308.948116) (xy 269.868618 -308.923509)
			(xy 269.914634 -308.906057) (xy 269.962853 -308.896213) (xy 270.012028 -308.894232) (xy 270.060883 -308.900164)
			(xy 270.108154 -308.913856) (xy 270.152616 -308.934954) (xy 270.193119 -308.96291) (xy 270.228612 -308.997002)
			(xy 270.258177 -309.036346) (xy 270.281048 -309.079923) (xy 270.296632 -309.126604) (xy 270.304527 -309.175181)
			(xy 270.305022 -309.199788) (xy 270.304527 -309.224395) (xy 270.304348 -309.225496) (xy 270.62328 -309.225496)
			(xy 270.62328 -309.17408) (xy 270.631323 -309.123298) (xy 270.647211 -309.074399) (xy 270.670554 -309.028587)
			(xy 270.700775 -308.986991) (xy 270.737131 -308.950635) (xy 270.778727 -308.920414) (xy 270.824539 -308.897071)
			(xy 270.873438 -308.881183) (xy 270.92422 -308.87314) (xy 270.975636 -308.87314) (xy 271.026418 -308.881183)
			(xy 271.075317 -308.897071) (xy 271.121129 -308.920414) (xy 271.162725 -308.950635) (xy 271.199081 -308.986991)
			(xy 271.229302 -309.028587) (xy 271.252645 -309.074399) (xy 271.268533 -309.123298) (xy 271.276576 -309.17408)
			(xy 271.27708 -309.199788) (xy 271.276576 -309.225496) (xy 271.57324 -309.225496) (xy 271.57324 -309.17408)
			(xy 271.581283 -309.123298) (xy 271.597171 -309.074399) (xy 271.620514 -309.028587) (xy 271.650735 -308.986991)
			(xy 271.687091 -308.950635) (xy 271.728687 -308.920414) (xy 271.774499 -308.897071) (xy 271.823398 -308.881183)
			(xy 271.87418 -308.87314) (xy 271.925596 -308.87314) (xy 271.976378 -308.881183) (xy 272.025277 -308.897071)
			(xy 272.071089 -308.920414) (xy 272.112685 -308.950635) (xy 272.149041 -308.986991) (xy 272.179262 -309.028587)
			(xy 272.202605 -309.074399) (xy 272.218493 -309.123298) (xy 272.226536 -309.17408) (xy 272.22704 -309.199788)
			(xy 272.544044 -309.199788) (xy 272.548004 -309.150734) (xy 272.559781 -309.10295) (xy 272.579072 -309.057674)
			(xy 272.605375 -309.016078) (xy 272.63801 -308.979241) (xy 272.676131 -308.948116) (xy 272.718752 -308.923509)
			(xy 272.764768 -308.906057) (xy 272.812987 -308.896213) (xy 272.862162 -308.894232) (xy 272.911017 -308.900164)
			(xy 272.958288 -308.913856) (xy 273.00275 -308.934954) (xy 273.043253 -308.96291) (xy 273.078746 -308.997002)
			(xy 273.108311 -309.036346) (xy 273.131182 -309.079923) (xy 273.146766 -309.126604) (xy 273.154661 -309.175181)
			(xy 273.155156 -309.199788) (xy 273.154661 -309.224395) (xy 273.154482 -309.225496) (xy 273.47316 -309.225496)
			(xy 273.47316 -309.17408) (xy 273.481203 -309.123298) (xy 273.497091 -309.074399) (xy 273.520434 -309.028587)
			(xy 273.550655 -308.986991) (xy 273.587011 -308.950635) (xy 273.628607 -308.920414) (xy 273.674419 -308.897071)
			(xy 273.723318 -308.881183) (xy 273.7741 -308.87314) (xy 273.825516 -308.87314) (xy 273.876298 -308.881183)
			(xy 273.925197 -308.897071) (xy 273.971009 -308.920414) (xy 274.012605 -308.950635) (xy 274.048961 -308.986991)
			(xy 274.079182 -309.028587) (xy 274.102525 -309.074399) (xy 274.118413 -309.123298) (xy 274.126456 -309.17408)
			(xy 274.12696 -309.199788) (xy 274.126456 -309.225496) (xy 274.42312 -309.225496) (xy 274.42312 -309.17408)
			(xy 274.431163 -309.123298) (xy 274.447051 -309.074399) (xy 274.470394 -309.028587) (xy 274.500615 -308.986991)
			(xy 274.536971 -308.950635) (xy 274.578567 -308.920414) (xy 274.624379 -308.897071) (xy 274.673278 -308.881183)
			(xy 274.72406 -308.87314) (xy 274.775476 -308.87314) (xy 274.826258 -308.881183) (xy 274.875157 -308.897071)
			(xy 274.920969 -308.920414) (xy 274.962565 -308.950635) (xy 274.998921 -308.986991) (xy 275.029142 -309.028587)
			(xy 275.052485 -309.074399) (xy 275.068373 -309.123298) (xy 275.076416 -309.17408) (xy 275.07692 -309.199788)
			(xy 275.393924 -309.199788) (xy 275.397884 -309.150734) (xy 275.409661 -309.10295) (xy 275.428952 -309.057674)
			(xy 275.455255 -309.016078) (xy 275.48789 -308.979241) (xy 275.526011 -308.948116) (xy 275.568632 -308.923509)
			(xy 275.614648 -308.906057) (xy 275.662867 -308.896213) (xy 275.712042 -308.894232) (xy 275.760897 -308.900164)
			(xy 275.808168 -308.913856) (xy 275.85263 -308.934954) (xy 275.893133 -308.96291) (xy 275.928626 -308.997002)
			(xy 275.958191 -309.036346) (xy 275.981062 -309.079923) (xy 275.996646 -309.126604) (xy 276.004541 -309.175181)
			(xy 276.005036 -309.199788) (xy 276.343884 -309.199788) (xy 276.347844 -309.150734) (xy 276.359621 -309.10295)
			(xy 276.378912 -309.057674) (xy 276.405215 -309.016078) (xy 276.43785 -308.979241) (xy 276.475971 -308.948116)
			(xy 276.518592 -308.923509) (xy 276.564608 -308.906057) (xy 276.612827 -308.896213) (xy 276.662002 -308.894232)
			(xy 276.710857 -308.900164) (xy 276.758128 -308.913856) (xy 276.80259 -308.934954) (xy 276.843093 -308.96291)
			(xy 276.878586 -308.997002) (xy 276.908151 -309.036346) (xy 276.931022 -309.079923) (xy 276.946606 -309.126604)
			(xy 276.954501 -309.175181) (xy 276.954996 -309.199788) (xy 277.294098 -309.199788) (xy 277.298058 -309.150734)
			(xy 277.309835 -309.10295) (xy 277.329126 -309.057674) (xy 277.355429 -309.016078) (xy 277.388064 -308.979241)
			(xy 277.426185 -308.948116) (xy 277.468806 -308.923509) (xy 277.514822 -308.906057) (xy 277.563041 -308.896213)
			(xy 277.612216 -308.894232) (xy 277.661071 -308.900164) (xy 277.708342 -308.913856) (xy 277.752804 -308.934954)
			(xy 277.793307 -308.96291) (xy 277.8288 -308.997002) (xy 277.858365 -309.036346) (xy 277.881236 -309.079923)
			(xy 277.89682 -309.126604) (xy 277.904715 -309.175181) (xy 277.90521 -309.199788) (xy 277.904715 -309.224395)
			(xy 277.89682 -309.272972) (xy 277.881236 -309.319653) (xy 277.858365 -309.36323) (xy 277.8288 -309.402574)
			(xy 277.793307 -309.436666) (xy 277.752804 -309.464622) (xy 277.708342 -309.48572) (xy 277.661071 -309.499412)
			(xy 277.612216 -309.505344) (xy 277.563041 -309.503363) (xy 277.514822 -309.493519) (xy 277.468806 -309.476067)
			(xy 277.426185 -309.45146) (xy 277.388064 -309.420335) (xy 277.355429 -309.383498) (xy 277.329126 -309.341902)
			(xy 277.309835 -309.296626) (xy 277.298058 -309.248842) (xy 277.294098 -309.199788) (xy 276.954996 -309.199788)
			(xy 276.954501 -309.224395) (xy 276.946606 -309.272972) (xy 276.931022 -309.319653) (xy 276.908151 -309.36323)
			(xy 276.878586 -309.402574) (xy 276.843093 -309.436666) (xy 276.80259 -309.464622) (xy 276.758128 -309.48572)
			(xy 276.710857 -309.499412) (xy 276.662002 -309.505344) (xy 276.612827 -309.503363) (xy 276.564608 -309.493519)
			(xy 276.518592 -309.476067) (xy 276.475971 -309.45146) (xy 276.43785 -309.420335) (xy 276.405215 -309.383498)
			(xy 276.378912 -309.341902) (xy 276.359621 -309.296626) (xy 276.347844 -309.248842) (xy 276.343884 -309.199788)
			(xy 276.005036 -309.199788) (xy 276.004541 -309.224395) (xy 275.996646 -309.272972) (xy 275.981062 -309.319653)
			(xy 275.958191 -309.36323) (xy 275.928626 -309.402574) (xy 275.893133 -309.436666) (xy 275.85263 -309.464622)
			(xy 275.808168 -309.48572) (xy 275.760897 -309.499412) (xy 275.712042 -309.505344) (xy 275.662867 -309.503363)
			(xy 275.614648 -309.493519) (xy 275.568632 -309.476067) (xy 275.526011 -309.45146) (xy 275.48789 -309.420335)
			(xy 275.455255 -309.383498) (xy 275.428952 -309.341902) (xy 275.409661 -309.296626) (xy 275.397884 -309.248842)
			(xy 275.393924 -309.199788) (xy 275.07692 -309.199788) (xy 275.076416 -309.225496) (xy 275.068373 -309.276278)
			(xy 275.052485 -309.325177) (xy 275.029142 -309.370989) (xy 274.998921 -309.412585) (xy 274.962565 -309.448941)
			(xy 274.920969 -309.479162) (xy 274.875157 -309.502505) (xy 274.826258 -309.518393) (xy 274.775476 -309.526436)
			(xy 274.72406 -309.526436) (xy 274.673278 -309.518393) (xy 274.624379 -309.502505) (xy 274.578567 -309.479162)
			(xy 274.536971 -309.448941) (xy 274.500615 -309.412585) (xy 274.470394 -309.370989) (xy 274.447051 -309.325177)
			(xy 274.431163 -309.276278) (xy 274.42312 -309.225496) (xy 274.126456 -309.225496) (xy 274.118413 -309.276278)
			(xy 274.102525 -309.325177) (xy 274.079182 -309.370989) (xy 274.048961 -309.412585) (xy 274.012605 -309.448941)
			(xy 273.971009 -309.479162) (xy 273.925197 -309.502505) (xy 273.876298 -309.518393) (xy 273.825516 -309.526436)
			(xy 273.7741 -309.526436) (xy 273.723318 -309.518393) (xy 273.674419 -309.502505) (xy 273.628607 -309.479162)
			(xy 273.587011 -309.448941) (xy 273.550655 -309.412585) (xy 273.520434 -309.370989) (xy 273.497091 -309.325177)
			(xy 273.481203 -309.276278) (xy 273.47316 -309.225496) (xy 273.154482 -309.225496) (xy 273.146766 -309.272972)
			(xy 273.131182 -309.319653) (xy 273.108311 -309.36323) (xy 273.078746 -309.402574) (xy 273.043253 -309.436666)
			(xy 273.00275 -309.464622) (xy 272.958288 -309.48572) (xy 272.911017 -309.499412) (xy 272.862162 -309.505344)
			(xy 272.812987 -309.503363) (xy 272.764768 -309.493519) (xy 272.718752 -309.476067) (xy 272.676131 -309.45146)
			(xy 272.63801 -309.420335) (xy 272.605375 -309.383498) (xy 272.579072 -309.341902) (xy 272.559781 -309.296626)
			(xy 272.548004 -309.248842) (xy 272.544044 -309.199788) (xy 272.22704 -309.199788) (xy 272.226536 -309.225496)
			(xy 272.218493 -309.276278) (xy 272.202605 -309.325177) (xy 272.179262 -309.370989) (xy 272.149041 -309.412585)
			(xy 272.112685 -309.448941) (xy 272.071089 -309.479162) (xy 272.025277 -309.502505) (xy 271.976378 -309.518393)
			(xy 271.925596 -309.526436) (xy 271.87418 -309.526436) (xy 271.823398 -309.518393) (xy 271.774499 -309.502505)
			(xy 271.728687 -309.479162) (xy 271.687091 -309.448941) (xy 271.650735 -309.412585) (xy 271.620514 -309.370989)
			(xy 271.597171 -309.325177) (xy 271.581283 -309.276278) (xy 271.57324 -309.225496) (xy 271.276576 -309.225496)
			(xy 271.268533 -309.276278) (xy 271.252645 -309.325177) (xy 271.229302 -309.370989) (xy 271.199081 -309.412585)
			(xy 271.162725 -309.448941) (xy 271.121129 -309.479162) (xy 271.075317 -309.502505) (xy 271.026418 -309.518393)
			(xy 270.975636 -309.526436) (xy 270.92422 -309.526436) (xy 270.873438 -309.518393) (xy 270.824539 -309.502505)
			(xy 270.778727 -309.479162) (xy 270.737131 -309.448941) (xy 270.700775 -309.412585) (xy 270.670554 -309.370989)
			(xy 270.647211 -309.325177) (xy 270.631323 -309.276278) (xy 270.62328 -309.225496) (xy 270.304348 -309.225496)
			(xy 270.296632 -309.272972) (xy 270.281048 -309.319653) (xy 270.258177 -309.36323) (xy 270.228612 -309.402574)
			(xy 270.193119 -309.436666) (xy 270.152616 -309.464622) (xy 270.108154 -309.48572) (xy 270.060883 -309.499412)
			(xy 270.012028 -309.505344) (xy 269.962853 -309.503363) (xy 269.914634 -309.493519) (xy 269.868618 -309.476067)
			(xy 269.825997 -309.45146) (xy 269.787876 -309.420335) (xy 269.755241 -309.383498) (xy 269.728938 -309.341902)
			(xy 269.709647 -309.296626) (xy 269.69787 -309.248842) (xy 269.69391 -309.199788) (xy 269.355062 -309.199788)
			(xy 269.354567 -309.224395) (xy 269.346672 -309.272972) (xy 269.331088 -309.319653) (xy 269.308217 -309.36323)
			(xy 269.278652 -309.402574) (xy 269.243159 -309.436666) (xy 269.202656 -309.464622) (xy 269.158194 -309.48572)
			(xy 269.110923 -309.499412) (xy 269.062068 -309.505344) (xy 269.012893 -309.503363) (xy 268.964674 -309.493519)
			(xy 268.918658 -309.476067) (xy 268.876037 -309.45146) (xy 268.837916 -309.420335) (xy 268.805281 -309.383498)
			(xy 268.778978 -309.341902) (xy 268.759687 -309.296626) (xy 268.74791 -309.248842) (xy 268.74395 -309.199788)
			(xy 259.896404 -309.199788) (xy 259.915043 -309.22796) (xy 259.938715 -309.278457) (xy 259.954783 -309.331864)
			(xy 259.962903 -309.38704) (xy 259.963412 -309.414926) (xy 259.962903 -309.442812) (xy 259.954783 -309.497988)
			(xy 259.938715 -309.551395) (xy 259.915043 -309.601892) (xy 259.88427 -309.648405) (xy 259.847053 -309.689942)
			(xy 259.804185 -309.725617) (xy 259.756579 -309.754671) (xy 259.70525 -309.776483) (xy 259.651293 -309.790589)
			(xy 259.595856 -309.796689) (xy 259.540122 -309.794652) (xy 259.485279 -309.784522) (xy 259.432495 -309.766515)
			(xy 259.382895 -309.741014) (xy 259.337537 -309.708563) (xy 259.297388 -309.669854) (xy 259.263302 -309.625711)
			(xy 259.236006 -309.577076) (xy 259.216083 -309.524985) (xy 259.203957 -309.470548) (xy 259.199886 -309.414926)
			(xy 255.945132 -309.414926) (xy 255.945132 -310.113934) (xy 261.18642 -310.113934) (xy 261.190491 -310.058312)
			(xy 261.202617 -310.003875) (xy 261.22254 -309.951784) (xy 261.249836 -309.903149) (xy 261.283922 -309.859006)
			(xy 261.324071 -309.820297) (xy 261.369429 -309.787846) (xy 261.419029 -309.762345) (xy 261.471813 -309.744338)
			(xy 261.526656 -309.734208) (xy 261.58239 -309.732171) (xy 261.637827 -309.738271) (xy 261.691784 -309.752377)
			(xy 261.743113 -309.774189) (xy 261.790719 -309.803243) (xy 261.833587 -309.838918) (xy 261.870804 -309.880455)
			(xy 261.901577 -309.926968) (xy 261.925249 -309.977465) (xy 261.941317 -310.030872) (xy 261.949437 -310.086048)
			(xy 261.949946 -310.113934) (xy 261.949437 -310.14182) (xy 261.941317 -310.196996) (xy 261.929168 -310.237378)
			(xy 266.300712 -310.237378) (xy 266.301198 -310.210127) (xy 266.308954 -310.156179) (xy 266.324309 -310.103884)
			(xy 266.346951 -310.054307) (xy 266.376417 -310.008457) (xy 266.412108 -309.967266) (xy 266.453299 -309.931575)
			(xy 266.499149 -309.902109) (xy 266.548726 -309.879467) (xy 266.601021 -309.864112) (xy 266.654969 -309.856356)
			(xy 266.709471 -309.856356) (xy 266.763419 -309.864112) (xy 266.815714 -309.879467) (xy 266.865291 -309.902109)
			(xy 266.911141 -309.931575) (xy 266.952332 -309.967266) (xy 266.988023 -310.008457) (xy 267.017489 -310.054307)
			(xy 267.040131 -310.103884) (xy 267.053672 -310.150002) (xy 267.793736 -310.150002) (xy 267.797696 -310.100948)
			(xy 267.809473 -310.053164) (xy 267.828764 -310.007888) (xy 267.855067 -309.966292) (xy 267.887702 -309.929455)
			(xy 267.925823 -309.89833) (xy 267.968444 -309.873723) (xy 268.01446 -309.856271) (xy 268.062679 -309.846427)
			(xy 268.111854 -309.844446) (xy 268.160709 -309.850378) (xy 268.20798 -309.86407) (xy 268.252442 -309.885168)
			(xy 268.292945 -309.913124) (xy 268.328438 -309.947216) (xy 268.358003 -309.98656) (xy 268.380874 -310.030137)
			(xy 268.396458 -310.076818) (xy 268.404353 -310.125395) (xy 268.404848 -310.150002) (xy 268.404353 -310.174609)
			(xy 268.404215 -310.175456) (xy 268.723106 -310.175456) (xy 268.723106 -310.12404) (xy 268.731149 -310.073258)
			(xy 268.747037 -310.024359) (xy 268.77038 -309.978547) (xy 268.800601 -309.936951) (xy 268.836957 -309.900595)
			(xy 268.878553 -309.870374) (xy 268.924365 -309.847031) (xy 268.973264 -309.831143) (xy 269.024046 -309.8231)
			(xy 269.075462 -309.8231) (xy 269.126244 -309.831143) (xy 269.175143 -309.847031) (xy 269.220955 -309.870374)
			(xy 269.262551 -309.900595) (xy 269.298907 -309.936951) (xy 269.329128 -309.978547) (xy 269.352471 -310.024359)
			(xy 269.368359 -310.073258) (xy 269.376402 -310.12404) (xy 269.376906 -310.149748) (xy 269.376402 -310.175456)
			(xy 269.673066 -310.175456) (xy 269.673066 -310.12404) (xy 269.681109 -310.073258) (xy 269.696997 -310.024359)
			(xy 269.72034 -309.978547) (xy 269.750561 -309.936951) (xy 269.786917 -309.900595) (xy 269.828513 -309.870374)
			(xy 269.874325 -309.847031) (xy 269.923224 -309.831143) (xy 269.974006 -309.8231) (xy 270.025422 -309.8231)
			(xy 270.076204 -309.831143) (xy 270.125103 -309.847031) (xy 270.170915 -309.870374) (xy 270.212511 -309.900595)
			(xy 270.248867 -309.936951) (xy 270.279088 -309.978547) (xy 270.302431 -310.024359) (xy 270.318319 -310.073258)
			(xy 270.326362 -310.12404) (xy 270.326866 -310.149748) (xy 270.644124 -310.149748) (xy 270.648084 -310.100694)
			(xy 270.659861 -310.05291) (xy 270.679152 -310.007634) (xy 270.705455 -309.966038) (xy 270.73809 -309.929201)
			(xy 270.776211 -309.898076) (xy 270.818832 -309.873469) (xy 270.864848 -309.856017) (xy 270.913067 -309.846173)
			(xy 270.962242 -309.844192) (xy 271.011097 -309.850124) (xy 271.058368 -309.863816) (xy 271.10283 -309.884914)
			(xy 271.143333 -309.91287) (xy 271.178826 -309.946962) (xy 271.208391 -309.986306) (xy 271.231262 -310.029883)
			(xy 271.246846 -310.076564) (xy 271.254741 -310.125141) (xy 271.255236 -310.149748) (xy 271.594084 -310.149748)
			(xy 271.598044 -310.100694) (xy 271.609821 -310.05291) (xy 271.629112 -310.007634) (xy 271.655415 -309.966038)
			(xy 271.68805 -309.929201) (xy 271.726171 -309.898076) (xy 271.768792 -309.873469) (xy 271.814808 -309.856017)
			(xy 271.863027 -309.846173) (xy 271.912202 -309.844192) (xy 271.961057 -309.850124) (xy 272.008328 -309.863816)
			(xy 272.05279 -309.884914) (xy 272.093293 -309.91287) (xy 272.128786 -309.946962) (xy 272.158351 -309.986306)
			(xy 272.181222 -310.029883) (xy 272.196806 -310.076564) (xy 272.204701 -310.125141) (xy 272.205196 -310.149748)
			(xy 272.544044 -310.149748) (xy 272.548004 -310.100694) (xy 272.559781 -310.05291) (xy 272.579072 -310.007634)
			(xy 272.605375 -309.966038) (xy 272.63801 -309.929201) (xy 272.676131 -309.898076) (xy 272.718752 -309.873469)
			(xy 272.764768 -309.856017) (xy 272.812987 -309.846173) (xy 272.862162 -309.844192) (xy 272.911017 -309.850124)
			(xy 272.958288 -309.863816) (xy 273.00275 -309.884914) (xy 273.043253 -309.91287) (xy 273.078746 -309.946962)
			(xy 273.108311 -309.986306) (xy 273.131182 -310.029883) (xy 273.146766 -310.076564) (xy 273.154661 -310.125141)
			(xy 273.155156 -310.149748) (xy 273.494004 -310.149748) (xy 273.497964 -310.100694) (xy 273.509741 -310.05291)
			(xy 273.529032 -310.007634) (xy 273.555335 -309.966038) (xy 273.58797 -309.929201) (xy 273.626091 -309.898076)
			(xy 273.668712 -309.873469) (xy 273.714728 -309.856017) (xy 273.762947 -309.846173) (xy 273.812122 -309.844192)
			(xy 273.860977 -309.850124) (xy 273.908248 -309.863816) (xy 273.95271 -309.884914) (xy 273.993213 -309.91287)
			(xy 274.028706 -309.946962) (xy 274.058271 -309.986306) (xy 274.081142 -310.029883) (xy 274.096726 -310.076564)
			(xy 274.104621 -310.125141) (xy 274.105116 -310.149748) (xy 274.443964 -310.149748) (xy 274.447924 -310.100694)
			(xy 274.459701 -310.05291) (xy 274.478992 -310.007634) (xy 274.505295 -309.966038) (xy 274.53793 -309.929201)
			(xy 274.576051 -309.898076) (xy 274.618672 -309.873469) (xy 274.664688 -309.856017) (xy 274.712907 -309.846173)
			(xy 274.762082 -309.844192) (xy 274.810937 -309.850124) (xy 274.858208 -309.863816) (xy 274.90267 -309.884914)
			(xy 274.943173 -309.91287) (xy 274.978666 -309.946962) (xy 275.008231 -309.986306) (xy 275.031102 -310.029883)
			(xy 275.046686 -310.076564) (xy 275.054581 -310.125141) (xy 275.055076 -310.149748) (xy 275.393924 -310.149748)
			(xy 275.397884 -310.100694) (xy 275.409661 -310.05291) (xy 275.428952 -310.007634) (xy 275.455255 -309.966038)
			(xy 275.48789 -309.929201) (xy 275.526011 -309.898076) (xy 275.568632 -309.873469) (xy 275.614648 -309.856017)
			(xy 275.662867 -309.846173) (xy 275.712042 -309.844192) (xy 275.760897 -309.850124) (xy 275.808168 -309.863816)
			(xy 275.85263 -309.884914) (xy 275.893133 -309.91287) (xy 275.928626 -309.946962) (xy 275.958191 -309.986306)
			(xy 275.981062 -310.029883) (xy 275.996646 -310.076564) (xy 276.004541 -310.125141) (xy 276.005036 -310.149748)
			(xy 276.343884 -310.149748) (xy 276.347844 -310.100694) (xy 276.359621 -310.05291) (xy 276.378912 -310.007634)
			(xy 276.405215 -309.966038) (xy 276.43785 -309.929201) (xy 276.475971 -309.898076) (xy 276.518592 -309.873469)
			(xy 276.564608 -309.856017) (xy 276.612827 -309.846173) (xy 276.662002 -309.844192) (xy 276.710857 -309.850124)
			(xy 276.758128 -309.863816) (xy 276.80259 -309.884914) (xy 276.843093 -309.91287) (xy 276.878586 -309.946962)
			(xy 276.908151 -309.986306) (xy 276.931022 -310.029883) (xy 276.946606 -310.076564) (xy 276.954501 -310.125141)
			(xy 276.954996 -310.149748) (xy 277.294098 -310.149748) (xy 277.298058 -310.100694) (xy 277.309835 -310.05291)
			(xy 277.329126 -310.007634) (xy 277.355429 -309.966038) (xy 277.388064 -309.929201) (xy 277.426185 -309.898076)
			(xy 277.468806 -309.873469) (xy 277.514822 -309.856017) (xy 277.563041 -309.846173) (xy 277.612216 -309.844192)
			(xy 277.661071 -309.850124) (xy 277.708342 -309.863816) (xy 277.752804 -309.884914) (xy 277.793307 -309.91287)
			(xy 277.8288 -309.946962) (xy 277.858365 -309.986306) (xy 277.881236 -310.029883) (xy 277.89682 -310.076564)
			(xy 277.904715 -310.125141) (xy 277.905043 -310.141429) (xy 278.244229 -310.141429) (xy 278.249593 -310.092089)
			(xy 278.262869 -310.044267) (xy 278.283705 -309.999222) (xy 278.311555 -309.958141) (xy 278.345683 -309.922106)
			(xy 278.385192 -309.892068) (xy 278.429039 -309.868816) (xy 278.47607 -309.852964) (xy 278.525047 -309.844929)
			(xy 278.549862 -309.84444) (xy 278.564045 -309.844621) (xy 278.592285 -309.84729) (xy 278.60625 -309.849774)
			(xy 278.618696 -309.85206) (xy 278.642318 -309.844694) (xy 278.719788 -309.767224) (xy 278.727154 -309.743602)
			(xy 278.724868 -309.731156) (xy 278.722389 -309.717191) (xy 278.719719 -309.688951) (xy 278.719534 -309.674768)
			(xy 278.720056 -309.649513) (xy 278.728369 -309.599691) (xy 278.74477 -309.551917) (xy 278.768811 -309.507494)
			(xy 278.799835 -309.467634) (xy 278.836997 -309.433424) (xy 278.879283 -309.405798) (xy 278.925539 -309.385508)
			(xy 278.974504 -309.373108) (xy 279.024842 -309.368937) (xy 279.07518 -309.373108) (xy 279.124145 -309.385508)
			(xy 279.170401 -309.405798) (xy 279.212687 -309.433424) (xy 279.249849 -309.467634) (xy 279.280873 -309.507494)
			(xy 279.304914 -309.551917) (xy 279.321315 -309.599691) (xy 279.329628 -309.649513) (xy 279.33015 -309.674768)
			(xy 279.329968 -309.688951) (xy 279.327299 -309.717191) (xy 279.324816 -309.731156) (xy 279.32253 -309.743602)
			(xy 279.329896 -309.767224) (xy 279.407366 -309.844694) (xy 279.430988 -309.85206) (xy 279.443434 -309.849774)
			(xy 279.4574 -309.847297) (xy 279.485639 -309.844625) (xy 279.499822 -309.84444) (xy 279.52464 -309.844901)
			(xy 279.573621 -309.852935) (xy 279.620658 -309.868786) (xy 279.66451 -309.892038) (xy 279.704024 -309.922078)
			(xy 279.738157 -309.958114) (xy 279.766011 -309.999198) (xy 279.786852 -310.044247) (xy 279.80013 -310.092073)
			(xy 279.805497 -310.141416) (xy 280.144129 -310.141416) (xy 280.149496 -310.092075) (xy 280.162774 -310.044253)
			(xy 280.183613 -309.999208) (xy 280.211465 -309.958128) (xy 280.245596 -309.922095) (xy 280.285107 -309.892058)
			(xy 280.328956 -309.868809) (xy 280.375989 -309.852959) (xy 280.424966 -309.844927) (xy 280.449782 -309.84444)
			(xy 280.463965 -309.844618) (xy 280.492205 -309.847289) (xy 280.50617 -309.849774) (xy 280.518616 -309.85206)
			(xy 280.542238 -309.844694) (xy 280.619708 -309.767224) (xy 280.627074 -309.743602) (xy 280.624788 -309.731156)
			(xy 280.622309 -309.71719) (xy 280.619639 -309.688951) (xy 280.619454 -309.674768) (xy 280.619976 -309.649513)
			(xy 280.628289 -309.599691) (xy 280.64469 -309.551917) (xy 280.668731 -309.507494) (xy 280.699755 -309.467634)
			(xy 280.736917 -309.433424) (xy 280.779203 -309.405798) (xy 280.825459 -309.385508) (xy 280.874424 -309.373108)
			(xy 280.924762 -309.368937) (xy 280.9751 -309.373108) (xy 281.024065 -309.385508) (xy 281.070321 -309.405798)
			(xy 281.112607 -309.433424) (xy 281.149769 -309.467634) (xy 281.180793 -309.507494) (xy 281.204834 -309.551917)
			(xy 281.221235 -309.599691) (xy 281.229548 -309.649513) (xy 281.23007 -309.674768) (xy 281.22989 -309.688951)
			(xy 281.22722 -309.717191) (xy 281.224736 -309.731156) (xy 281.22245 -309.743602) (xy 281.229816 -309.767224)
			(xy 281.307286 -309.844694) (xy 281.330908 -309.85206) (xy 281.343354 -309.849774) (xy 281.357319 -309.847294)
			(xy 281.385559 -309.844625) (xy 281.399742 -309.84444) (xy 281.424558 -309.844923) (xy 281.473535 -309.852959)
			(xy 281.520567 -309.868812) (xy 281.564414 -309.892064) (xy 281.603923 -309.922104) (xy 281.638052 -309.95814)
			(xy 281.665901 -309.999221) (xy 281.686738 -310.044267) (xy 281.700013 -310.092091) (xy 281.705377 -310.141432)
			(xy 281.704926 -310.149748) (xy 282.043898 -310.149748) (xy 282.047858 -310.100694) (xy 282.059635 -310.05291)
			(xy 282.078926 -310.007634) (xy 282.105229 -309.966038) (xy 282.137864 -309.929201) (xy 282.175985 -309.898076)
			(xy 282.218606 -309.873469) (xy 282.264622 -309.856017) (xy 282.312841 -309.846173) (xy 282.362016 -309.844192)
			(xy 282.410871 -309.850124) (xy 282.458142 -309.863816) (xy 282.502604 -309.884914) (xy 282.543107 -309.91287)
			(xy 282.5786 -309.946962) (xy 282.608165 -309.986306) (xy 282.631036 -310.029883) (xy 282.64662 -310.076564)
			(xy 282.654515 -310.125141) (xy 282.65501 -310.149748) (xy 282.994112 -310.149748) (xy 282.998072 -310.100694)
			(xy 283.009849 -310.05291) (xy 283.02914 -310.007634) (xy 283.055443 -309.966038) (xy 283.088078 -309.929201)
			(xy 283.126199 -309.898076) (xy 283.16882 -309.873469) (xy 283.214836 -309.856017) (xy 283.263055 -309.846173)
			(xy 283.31223 -309.844192) (xy 283.361085 -309.850124) (xy 283.408356 -309.863816) (xy 283.452818 -309.884914)
			(xy 283.493321 -309.91287) (xy 283.528814 -309.946962) (xy 283.558379 -309.986306) (xy 283.58125 -310.029883)
			(xy 283.596834 -310.076564) (xy 283.604729 -310.125141) (xy 283.605224 -310.149748) (xy 283.944072 -310.149748)
			(xy 283.948032 -310.100694) (xy 283.959809 -310.05291) (xy 283.9791 -310.007634) (xy 284.005403 -309.966038)
			(xy 284.038038 -309.929201) (xy 284.076159 -309.898076) (xy 284.11878 -309.873469) (xy 284.164796 -309.856017)
			(xy 284.213015 -309.846173) (xy 284.26219 -309.844192) (xy 284.311045 -309.850124) (xy 284.358316 -309.863816)
			(xy 284.402778 -309.884914) (xy 284.443281 -309.91287) (xy 284.478774 -309.946962) (xy 284.508339 -309.986306)
			(xy 284.53121 -310.029883) (xy 284.546794 -310.076564) (xy 284.554689 -310.125141) (xy 284.555184 -310.149748)
			(xy 284.894032 -310.149748) (xy 284.897992 -310.100694) (xy 284.909769 -310.05291) (xy 284.92906 -310.007634)
			(xy 284.955363 -309.966038) (xy 284.987998 -309.929201) (xy 285.026119 -309.898076) (xy 285.06874 -309.873469)
			(xy 285.114756 -309.856017) (xy 285.162975 -309.846173) (xy 285.21215 -309.844192) (xy 285.261005 -309.850124)
			(xy 285.308276 -309.863816) (xy 285.352738 -309.884914) (xy 285.393241 -309.91287) (xy 285.428734 -309.946962)
			(xy 285.458299 -309.986306) (xy 285.48117 -310.029883) (xy 285.496754 -310.076564) (xy 285.504649 -310.125141)
			(xy 285.505144 -310.149748) (xy 285.843992 -310.149748) (xy 285.847952 -310.100694) (xy 285.859729 -310.05291)
			(xy 285.87902 -310.007634) (xy 285.905323 -309.966038) (xy 285.937958 -309.929201) (xy 285.976079 -309.898076)
			(xy 286.0187 -309.873469) (xy 286.064716 -309.856017) (xy 286.112935 -309.846173) (xy 286.16211 -309.844192)
			(xy 286.210965 -309.850124) (xy 286.258236 -309.863816) (xy 286.302698 -309.884914) (xy 286.343201 -309.91287)
			(xy 286.378694 -309.946962) (xy 286.408259 -309.986306) (xy 286.43113 -310.029883) (xy 286.446714 -310.076564)
			(xy 286.454609 -310.125141) (xy 286.455104 -310.149748) (xy 286.793952 -310.149748) (xy 286.797912 -310.100694)
			(xy 286.809689 -310.05291) (xy 286.82898 -310.007634) (xy 286.855283 -309.966038) (xy 286.887918 -309.929201)
			(xy 286.926039 -309.898076) (xy 286.96866 -309.873469) (xy 287.014676 -309.856017) (xy 287.062895 -309.846173)
			(xy 287.11207 -309.844192) (xy 287.160925 -309.850124) (xy 287.208196 -309.863816) (xy 287.252658 -309.884914)
			(xy 287.293161 -309.91287) (xy 287.328654 -309.946962) (xy 287.358219 -309.986306) (xy 287.38109 -310.029883)
			(xy 287.396674 -310.076564) (xy 287.404569 -310.125141) (xy 287.405064 -310.149748) (xy 287.743912 -310.149748)
			(xy 287.747872 -310.100694) (xy 287.759649 -310.05291) (xy 287.77894 -310.007634) (xy 287.805243 -309.966038)
			(xy 287.837878 -309.929201) (xy 287.875999 -309.898076) (xy 287.91862 -309.873469) (xy 287.964636 -309.856017)
			(xy 288.012855 -309.846173) (xy 288.06203 -309.844192) (xy 288.110885 -309.850124) (xy 288.158156 -309.863816)
			(xy 288.202618 -309.884914) (xy 288.243121 -309.91287) (xy 288.278614 -309.946962) (xy 288.308179 -309.986306)
			(xy 288.33105 -310.029883) (xy 288.346634 -310.076564) (xy 288.354529 -310.125141) (xy 288.355024 -310.149748)
			(xy 288.694126 -310.149748) (xy 288.698086 -310.100694) (xy 288.709863 -310.05291) (xy 288.729154 -310.007634)
			(xy 288.755457 -309.966038) (xy 288.788092 -309.929201) (xy 288.826213 -309.898076) (xy 288.868834 -309.873469)
			(xy 288.91485 -309.856017) (xy 288.963069 -309.846173) (xy 289.012244 -309.844192) (xy 289.061099 -309.850124)
			(xy 289.10837 -309.863816) (xy 289.152832 -309.884914) (xy 289.193335 -309.91287) (xy 289.228828 -309.946962)
			(xy 289.258393 -309.986306) (xy 289.281264 -310.029883) (xy 289.296848 -310.076564) (xy 289.304743 -310.125141)
			(xy 289.305238 -310.149748) (xy 289.644086 -310.149748) (xy 289.648046 -310.100694) (xy 289.659823 -310.05291)
			(xy 289.679114 -310.007634) (xy 289.705417 -309.966038) (xy 289.738052 -309.929201) (xy 289.776173 -309.898076)
			(xy 289.818794 -309.873469) (xy 289.86481 -309.856017) (xy 289.913029 -309.846173) (xy 289.962204 -309.844192)
			(xy 290.011059 -309.850124) (xy 290.05833 -309.863816) (xy 290.102792 -309.884914) (xy 290.143295 -309.91287)
			(xy 290.178788 -309.946962) (xy 290.208353 -309.986306) (xy 290.231224 -310.029883) (xy 290.246808 -310.076564)
			(xy 290.254703 -310.125141) (xy 290.255198 -310.149748) (xy 290.594046 -310.149748) (xy 290.598006 -310.100694)
			(xy 290.609783 -310.05291) (xy 290.629074 -310.007634) (xy 290.655377 -309.966038) (xy 290.688012 -309.929201)
			(xy 290.726133 -309.898076) (xy 290.768754 -309.873469) (xy 290.81477 -309.856017) (xy 290.862989 -309.846173)
			(xy 290.912164 -309.844192) (xy 290.961019 -309.850124) (xy 291.00829 -309.863816) (xy 291.052752 -309.884914)
			(xy 291.093255 -309.91287) (xy 291.128748 -309.946962) (xy 291.158313 -309.986306) (xy 291.181184 -310.029883)
			(xy 291.196768 -310.076564) (xy 291.204663 -310.125141) (xy 291.205158 -310.149748) (xy 291.544006 -310.149748)
			(xy 291.547966 -310.100694) (xy 291.559743 -310.05291) (xy 291.579034 -310.007634) (xy 291.605337 -309.966038)
			(xy 291.637972 -309.929201) (xy 291.676093 -309.898076) (xy 291.718714 -309.873469) (xy 291.76473 -309.856017)
			(xy 291.812949 -309.846173) (xy 291.862124 -309.844192) (xy 291.910979 -309.850124) (xy 291.95825 -309.863816)
			(xy 292.002712 -309.884914) (xy 292.043215 -309.91287) (xy 292.078708 -309.946962) (xy 292.108273 -309.986306)
			(xy 292.131144 -310.029883) (xy 292.146728 -310.076564) (xy 292.154623 -310.125141) (xy 292.155118 -310.149748)
			(xy 292.493966 -310.149748) (xy 292.497926 -310.100694) (xy 292.509703 -310.05291) (xy 292.528994 -310.007634)
			(xy 292.555297 -309.966038) (xy 292.587932 -309.929201) (xy 292.626053 -309.898076) (xy 292.668674 -309.873469)
			(xy 292.71469 -309.856017) (xy 292.762909 -309.846173) (xy 292.812084 -309.844192) (xy 292.860939 -309.850124)
			(xy 292.90821 -309.863816) (xy 292.952672 -309.884914) (xy 292.993175 -309.91287) (xy 293.028668 -309.946962)
			(xy 293.058233 -309.986306) (xy 293.081104 -310.029883) (xy 293.096688 -310.076564) (xy 293.104583 -310.125141)
			(xy 293.105078 -310.149748) (xy 293.443926 -310.149748) (xy 293.447886 -310.100694) (xy 293.459663 -310.05291)
			(xy 293.478954 -310.007634) (xy 293.505257 -309.966038) (xy 293.537892 -309.929201) (xy 293.576013 -309.898076)
			(xy 293.618634 -309.873469) (xy 293.66465 -309.856017) (xy 293.712869 -309.846173) (xy 293.762044 -309.844192)
			(xy 293.810899 -309.850124) (xy 293.85817 -309.863816) (xy 293.902632 -309.884914) (xy 293.943135 -309.91287)
			(xy 293.978628 -309.946962) (xy 294.008193 -309.986306) (xy 294.031064 -310.029883) (xy 294.046648 -310.076564)
			(xy 294.054543 -310.125141) (xy 294.055038 -310.149748) (xy 294.393886 -310.149748) (xy 294.397846 -310.100694)
			(xy 294.409623 -310.05291) (xy 294.428914 -310.007634) (xy 294.455217 -309.966038) (xy 294.487852 -309.929201)
			(xy 294.525973 -309.898076) (xy 294.568594 -309.873469) (xy 294.61461 -309.856017) (xy 294.662829 -309.846173)
			(xy 294.712004 -309.844192) (xy 294.760859 -309.850124) (xy 294.80813 -309.863816) (xy 294.852592 -309.884914)
			(xy 294.893095 -309.91287) (xy 294.928588 -309.946962) (xy 294.958153 -309.986306) (xy 294.981024 -310.029883)
			(xy 294.996608 -310.076564) (xy 295.004503 -310.125141) (xy 295.004998 -310.149748) (xy 295.3441 -310.149748)
			(xy 295.34806 -310.100694) (xy 295.359837 -310.05291) (xy 295.379128 -310.007634) (xy 295.405431 -309.966038)
			(xy 295.438066 -309.929201) (xy 295.476187 -309.898076) (xy 295.518808 -309.873469) (xy 295.564824 -309.856017)
			(xy 295.613043 -309.846173) (xy 295.662218 -309.844192) (xy 295.711073 -309.850124) (xy 295.758344 -309.863816)
			(xy 295.802806 -309.884914) (xy 295.843309 -309.91287) (xy 295.878802 -309.946962) (xy 295.908367 -309.986306)
			(xy 295.931238 -310.029883) (xy 295.946822 -310.076564) (xy 295.954717 -310.125141) (xy 295.955212 -310.149748)
			(xy 296.29406 -310.149748) (xy 296.29802 -310.100694) (xy 296.309797 -310.05291) (xy 296.329088 -310.007634)
			(xy 296.355391 -309.966038) (xy 296.388026 -309.929201) (xy 296.426147 -309.898076) (xy 296.468768 -309.873469)
			(xy 296.514784 -309.856017) (xy 296.563003 -309.846173) (xy 296.612178 -309.844192) (xy 296.661033 -309.850124)
			(xy 296.708304 -309.863816) (xy 296.752766 -309.884914) (xy 296.793269 -309.91287) (xy 296.828762 -309.946962)
			(xy 296.858327 -309.986306) (xy 296.881198 -310.029883) (xy 296.896782 -310.076564) (xy 296.904677 -310.125141)
			(xy 296.905172 -310.149748) (xy 297.24402 -310.149748) (xy 297.24798 -310.100694) (xy 297.259757 -310.05291)
			(xy 297.279048 -310.007634) (xy 297.305351 -309.966038) (xy 297.337986 -309.929201) (xy 297.376107 -309.898076)
			(xy 297.418728 -309.873469) (xy 297.464744 -309.856017) (xy 297.512963 -309.846173) (xy 297.562138 -309.844192)
			(xy 297.610993 -309.850124) (xy 297.658264 -309.863816) (xy 297.702726 -309.884914) (xy 297.743229 -309.91287)
			(xy 297.778722 -309.946962) (xy 297.808287 -309.986306) (xy 297.831158 -310.029883) (xy 297.846742 -310.076564)
			(xy 297.854637 -310.125141) (xy 297.855132 -310.149748) (xy 298.19398 -310.149748) (xy 298.19794 -310.100694)
			(xy 298.209717 -310.05291) (xy 298.229008 -310.007634) (xy 298.255311 -309.966038) (xy 298.287946 -309.929201)
			(xy 298.326067 -309.898076) (xy 298.368688 -309.873469) (xy 298.414704 -309.856017) (xy 298.462923 -309.846173)
			(xy 298.512098 -309.844192) (xy 298.560953 -309.850124) (xy 298.608224 -309.863816) (xy 298.652686 -309.884914)
			(xy 298.693189 -309.91287) (xy 298.728682 -309.946962) (xy 298.758247 -309.986306) (xy 298.781118 -310.029883)
			(xy 298.796702 -310.076564) (xy 298.804597 -310.125141) (xy 298.805092 -310.149748) (xy 299.14394 -310.149748)
			(xy 299.1479 -310.100694) (xy 299.159677 -310.05291) (xy 299.178968 -310.007634) (xy 299.205271 -309.966038)
			(xy 299.237906 -309.929201) (xy 299.276027 -309.898076) (xy 299.318648 -309.873469) (xy 299.364664 -309.856017)
			(xy 299.412883 -309.846173) (xy 299.462058 -309.844192) (xy 299.510913 -309.850124) (xy 299.558184 -309.863816)
			(xy 299.602646 -309.884914) (xy 299.643149 -309.91287) (xy 299.678642 -309.946962) (xy 299.708207 -309.986306)
			(xy 299.731078 -310.029883) (xy 299.746662 -310.076564) (xy 299.754557 -310.125141) (xy 299.755052 -310.149748)
			(xy 299.754557 -310.174355) (xy 299.746662 -310.222932) (xy 299.731078 -310.269613) (xy 299.708207 -310.31319)
			(xy 299.678642 -310.352534) (xy 299.643149 -310.386626) (xy 299.602646 -310.414582) (xy 299.558184 -310.43568)
			(xy 299.510913 -310.449372) (xy 299.462058 -310.455304) (xy 299.412883 -310.453323) (xy 299.364664 -310.443479)
			(xy 299.318648 -310.426027) (xy 299.276027 -310.40142) (xy 299.237906 -310.370295) (xy 299.205271 -310.333458)
			(xy 299.178968 -310.291862) (xy 299.159677 -310.246586) (xy 299.1479 -310.198802) (xy 299.14394 -310.149748)
			(xy 298.805092 -310.149748) (xy 298.804597 -310.174355) (xy 298.796702 -310.222932) (xy 298.781118 -310.269613)
			(xy 298.758247 -310.31319) (xy 298.728682 -310.352534) (xy 298.693189 -310.386626) (xy 298.652686 -310.414582)
			(xy 298.608224 -310.43568) (xy 298.560953 -310.449372) (xy 298.512098 -310.455304) (xy 298.462923 -310.453323)
			(xy 298.414704 -310.443479) (xy 298.368688 -310.426027) (xy 298.326067 -310.40142) (xy 298.287946 -310.370295)
			(xy 298.255311 -310.333458) (xy 298.229008 -310.291862) (xy 298.209717 -310.246586) (xy 298.19794 -310.198802)
			(xy 298.19398 -310.149748) (xy 297.855132 -310.149748) (xy 297.854637 -310.174355) (xy 297.846742 -310.222932)
			(xy 297.831158 -310.269613) (xy 297.808287 -310.31319) (xy 297.778722 -310.352534) (xy 297.743229 -310.386626)
			(xy 297.702726 -310.414582) (xy 297.658264 -310.43568) (xy 297.610993 -310.449372) (xy 297.562138 -310.455304)
			(xy 297.512963 -310.453323) (xy 297.464744 -310.443479) (xy 297.418728 -310.426027) (xy 297.376107 -310.40142)
			(xy 297.337986 -310.370295) (xy 297.305351 -310.333458) (xy 297.279048 -310.291862) (xy 297.259757 -310.246586)
			(xy 297.24798 -310.198802) (xy 297.24402 -310.149748) (xy 296.905172 -310.149748) (xy 296.904677 -310.174355)
			(xy 296.896782 -310.222932) (xy 296.881198 -310.269613) (xy 296.858327 -310.31319) (xy 296.828762 -310.352534)
			(xy 296.793269 -310.386626) (xy 296.752766 -310.414582) (xy 296.708304 -310.43568) (xy 296.661033 -310.449372)
			(xy 296.612178 -310.455304) (xy 296.563003 -310.453323) (xy 296.514784 -310.443479) (xy 296.468768 -310.426027)
			(xy 296.426147 -310.40142) (xy 296.388026 -310.370295) (xy 296.355391 -310.333458) (xy 296.329088 -310.291862)
			(xy 296.309797 -310.246586) (xy 296.29802 -310.198802) (xy 296.29406 -310.149748) (xy 295.955212 -310.149748)
			(xy 295.954717 -310.174355) (xy 295.946822 -310.222932) (xy 295.931238 -310.269613) (xy 295.908367 -310.31319)
			(xy 295.878802 -310.352534) (xy 295.843309 -310.386626) (xy 295.802806 -310.414582) (xy 295.758344 -310.43568)
			(xy 295.711073 -310.449372) (xy 295.662218 -310.455304) (xy 295.613043 -310.453323) (xy 295.564824 -310.443479)
			(xy 295.518808 -310.426027) (xy 295.476187 -310.40142) (xy 295.438066 -310.370295) (xy 295.405431 -310.333458)
			(xy 295.379128 -310.291862) (xy 295.359837 -310.246586) (xy 295.34806 -310.198802) (xy 295.3441 -310.149748)
			(xy 295.004998 -310.149748) (xy 295.004503 -310.174355) (xy 294.996608 -310.222932) (xy 294.981024 -310.269613)
			(xy 294.958153 -310.31319) (xy 294.928588 -310.352534) (xy 294.893095 -310.386626) (xy 294.852592 -310.414582)
			(xy 294.80813 -310.43568) (xy 294.760859 -310.449372) (xy 294.712004 -310.455304) (xy 294.662829 -310.453323)
			(xy 294.61461 -310.443479) (xy 294.568594 -310.426027) (xy 294.525973 -310.40142) (xy 294.487852 -310.370295)
			(xy 294.455217 -310.333458) (xy 294.428914 -310.291862) (xy 294.409623 -310.246586) (xy 294.397846 -310.198802)
			(xy 294.393886 -310.149748) (xy 294.055038 -310.149748) (xy 294.054543 -310.174355) (xy 294.046648 -310.222932)
			(xy 294.031064 -310.269613) (xy 294.008193 -310.31319) (xy 293.978628 -310.352534) (xy 293.943135 -310.386626)
			(xy 293.902632 -310.414582) (xy 293.85817 -310.43568) (xy 293.810899 -310.449372) (xy 293.762044 -310.455304)
			(xy 293.712869 -310.453323) (xy 293.66465 -310.443479) (xy 293.618634 -310.426027) (xy 293.576013 -310.40142)
			(xy 293.537892 -310.370295) (xy 293.505257 -310.333458) (xy 293.478954 -310.291862) (xy 293.459663 -310.246586)
			(xy 293.447886 -310.198802) (xy 293.443926 -310.149748) (xy 293.105078 -310.149748) (xy 293.104583 -310.174355)
			(xy 293.096688 -310.222932) (xy 293.081104 -310.269613) (xy 293.058233 -310.31319) (xy 293.028668 -310.352534)
			(xy 292.993175 -310.386626) (xy 292.952672 -310.414582) (xy 292.90821 -310.43568) (xy 292.860939 -310.449372)
			(xy 292.812084 -310.455304) (xy 292.762909 -310.453323) (xy 292.71469 -310.443479) (xy 292.668674 -310.426027)
			(xy 292.626053 -310.40142) (xy 292.587932 -310.370295) (xy 292.555297 -310.333458) (xy 292.528994 -310.291862)
			(xy 292.509703 -310.246586) (xy 292.497926 -310.198802) (xy 292.493966 -310.149748) (xy 292.155118 -310.149748)
			(xy 292.154623 -310.174355) (xy 292.146728 -310.222932) (xy 292.131144 -310.269613) (xy 292.108273 -310.31319)
			(xy 292.078708 -310.352534) (xy 292.043215 -310.386626) (xy 292.002712 -310.414582) (xy 291.95825 -310.43568)
			(xy 291.910979 -310.449372) (xy 291.862124 -310.455304) (xy 291.812949 -310.453323) (xy 291.76473 -310.443479)
			(xy 291.718714 -310.426027) (xy 291.676093 -310.40142) (xy 291.637972 -310.370295) (xy 291.605337 -310.333458)
			(xy 291.579034 -310.291862) (xy 291.559743 -310.246586) (xy 291.547966 -310.198802) (xy 291.544006 -310.149748)
			(xy 291.205158 -310.149748) (xy 291.204663 -310.174355) (xy 291.196768 -310.222932) (xy 291.181184 -310.269613)
			(xy 291.158313 -310.31319) (xy 291.128748 -310.352534) (xy 291.093255 -310.386626) (xy 291.052752 -310.414582)
			(xy 291.00829 -310.43568) (xy 290.961019 -310.449372) (xy 290.912164 -310.455304) (xy 290.862989 -310.453323)
			(xy 290.81477 -310.443479) (xy 290.768754 -310.426027) (xy 290.726133 -310.40142) (xy 290.688012 -310.370295)
			(xy 290.655377 -310.333458) (xy 290.629074 -310.291862) (xy 290.609783 -310.246586) (xy 290.598006 -310.198802)
			(xy 290.594046 -310.149748) (xy 290.255198 -310.149748) (xy 290.254703 -310.174355) (xy 290.246808 -310.222932)
			(xy 290.231224 -310.269613) (xy 290.208353 -310.31319) (xy 290.178788 -310.352534) (xy 290.143295 -310.386626)
			(xy 290.102792 -310.414582) (xy 290.05833 -310.43568) (xy 290.011059 -310.449372) (xy 289.962204 -310.455304)
			(xy 289.913029 -310.453323) (xy 289.86481 -310.443479) (xy 289.818794 -310.426027) (xy 289.776173 -310.40142)
			(xy 289.738052 -310.370295) (xy 289.705417 -310.333458) (xy 289.679114 -310.291862) (xy 289.659823 -310.246586)
			(xy 289.648046 -310.198802) (xy 289.644086 -310.149748) (xy 289.305238 -310.149748) (xy 289.304743 -310.174355)
			(xy 289.296848 -310.222932) (xy 289.281264 -310.269613) (xy 289.258393 -310.31319) (xy 289.228828 -310.352534)
			(xy 289.193335 -310.386626) (xy 289.152832 -310.414582) (xy 289.10837 -310.43568) (xy 289.061099 -310.449372)
			(xy 289.012244 -310.455304) (xy 288.963069 -310.453323) (xy 288.91485 -310.443479) (xy 288.868834 -310.426027)
			(xy 288.826213 -310.40142) (xy 288.788092 -310.370295) (xy 288.755457 -310.333458) (xy 288.729154 -310.291862)
			(xy 288.709863 -310.246586) (xy 288.698086 -310.198802) (xy 288.694126 -310.149748) (xy 288.355024 -310.149748)
			(xy 288.354529 -310.174355) (xy 288.346634 -310.222932) (xy 288.33105 -310.269613) (xy 288.308179 -310.31319)
			(xy 288.278614 -310.352534) (xy 288.243121 -310.386626) (xy 288.202618 -310.414582) (xy 288.158156 -310.43568)
			(xy 288.110885 -310.449372) (xy 288.06203 -310.455304) (xy 288.012855 -310.453323) (xy 287.964636 -310.443479)
			(xy 287.91862 -310.426027) (xy 287.875999 -310.40142) (xy 287.837878 -310.370295) (xy 287.805243 -310.333458)
			(xy 287.77894 -310.291862) (xy 287.759649 -310.246586) (xy 287.747872 -310.198802) (xy 287.743912 -310.149748)
			(xy 287.405064 -310.149748) (xy 287.404569 -310.174355) (xy 287.396674 -310.222932) (xy 287.38109 -310.269613)
			(xy 287.358219 -310.31319) (xy 287.328654 -310.352534) (xy 287.293161 -310.386626) (xy 287.252658 -310.414582)
			(xy 287.208196 -310.43568) (xy 287.160925 -310.449372) (xy 287.11207 -310.455304) (xy 287.062895 -310.453323)
			(xy 287.014676 -310.443479) (xy 286.96866 -310.426027) (xy 286.926039 -310.40142) (xy 286.887918 -310.370295)
			(xy 286.855283 -310.333458) (xy 286.82898 -310.291862) (xy 286.809689 -310.246586) (xy 286.797912 -310.198802)
			(xy 286.793952 -310.149748) (xy 286.455104 -310.149748) (xy 286.454609 -310.174355) (xy 286.446714 -310.222932)
			(xy 286.43113 -310.269613) (xy 286.408259 -310.31319) (xy 286.378694 -310.352534) (xy 286.343201 -310.386626)
			(xy 286.302698 -310.414582) (xy 286.258236 -310.43568) (xy 286.210965 -310.449372) (xy 286.16211 -310.455304)
			(xy 286.112935 -310.453323) (xy 286.064716 -310.443479) (xy 286.0187 -310.426027) (xy 285.976079 -310.40142)
			(xy 285.937958 -310.370295) (xy 285.905323 -310.333458) (xy 285.87902 -310.291862) (xy 285.859729 -310.246586)
			(xy 285.847952 -310.198802) (xy 285.843992 -310.149748) (xy 285.505144 -310.149748) (xy 285.504649 -310.174355)
			(xy 285.496754 -310.222932) (xy 285.48117 -310.269613) (xy 285.458299 -310.31319) (xy 285.428734 -310.352534)
			(xy 285.393241 -310.386626) (xy 285.352738 -310.414582) (xy 285.308276 -310.43568) (xy 285.261005 -310.449372)
			(xy 285.21215 -310.455304) (xy 285.162975 -310.453323) (xy 285.114756 -310.443479) (xy 285.06874 -310.426027)
			(xy 285.026119 -310.40142) (xy 284.987998 -310.370295) (xy 284.955363 -310.333458) (xy 284.92906 -310.291862)
			(xy 284.909769 -310.246586) (xy 284.897992 -310.198802) (xy 284.894032 -310.149748) (xy 284.555184 -310.149748)
			(xy 284.554689 -310.174355) (xy 284.546794 -310.222932) (xy 284.53121 -310.269613) (xy 284.508339 -310.31319)
			(xy 284.478774 -310.352534) (xy 284.443281 -310.386626) (xy 284.402778 -310.414582) (xy 284.358316 -310.43568)
			(xy 284.311045 -310.449372) (xy 284.26219 -310.455304) (xy 284.213015 -310.453323) (xy 284.164796 -310.443479)
			(xy 284.11878 -310.426027) (xy 284.076159 -310.40142) (xy 284.038038 -310.370295) (xy 284.005403 -310.333458)
			(xy 283.9791 -310.291862) (xy 283.959809 -310.246586) (xy 283.948032 -310.198802) (xy 283.944072 -310.149748)
			(xy 283.605224 -310.149748) (xy 283.604729 -310.174355) (xy 283.596834 -310.222932) (xy 283.58125 -310.269613)
			(xy 283.558379 -310.31319) (xy 283.528814 -310.352534) (xy 283.493321 -310.386626) (xy 283.452818 -310.414582)
			(xy 283.408356 -310.43568) (xy 283.361085 -310.449372) (xy 283.31223 -310.455304) (xy 283.263055 -310.453323)
			(xy 283.214836 -310.443479) (xy 283.16882 -310.426027) (xy 283.126199 -310.40142) (xy 283.088078 -310.370295)
			(xy 283.055443 -310.333458) (xy 283.02914 -310.291862) (xy 283.009849 -310.246586) (xy 282.998072 -310.198802)
			(xy 282.994112 -310.149748) (xy 282.65501 -310.149748) (xy 282.654515 -310.174355) (xy 282.64662 -310.222932)
			(xy 282.631036 -310.269613) (xy 282.608165 -310.31319) (xy 282.5786 -310.352534) (xy 282.543107 -310.386626)
			(xy 282.502604 -310.414582) (xy 282.458142 -310.43568) (xy 282.410871 -310.449372) (xy 282.362016 -310.455304)
			(xy 282.312841 -310.453323) (xy 282.264622 -310.443479) (xy 282.218606 -310.426027) (xy 282.175985 -310.40142)
			(xy 282.137864 -310.370295) (xy 282.105229 -310.333458) (xy 282.078926 -310.291862) (xy 282.059635 -310.246586)
			(xy 282.047858 -310.198802) (xy 282.043898 -310.149748) (xy 281.704926 -310.149748) (xy 281.702688 -310.190991)
			(xy 281.692018 -310.239462) (xy 281.673646 -310.285569) (xy 281.648058 -310.328096) (xy 281.615928 -310.365923)
			(xy 281.578101 -310.398055) (xy 281.535574 -310.423644) (xy 281.489468 -310.442016) (xy 281.440997 -310.452688)
			(xy 281.391438 -310.455377) (xy 281.342097 -310.450014) (xy 281.294273 -310.43674) (xy 281.249227 -310.415904)
			(xy 281.208144 -310.388055) (xy 281.172108 -310.353928) (xy 281.142068 -310.31442) (xy 281.118814 -310.270572)
			(xy 281.10296 -310.223541) (xy 281.094924 -310.174564) (xy 281.094434 -310.149748) (xy 281.094617 -310.135565)
			(xy 281.097285 -310.107325) (xy 281.099768 -310.09336) (xy 281.102054 -310.080914) (xy 281.094688 -310.057292)
			(xy 281.017218 -309.979822) (xy 280.993596 -309.972456) (xy 280.98115 -309.974742) (xy 280.967184 -309.977221)
			(xy 280.938945 -309.979891) (xy 280.924762 -309.980076) (xy 280.910579 -309.979905) (xy 280.882339 -309.977229)
			(xy 280.868374 -309.974742) (xy 280.855928 -309.972456) (xy 280.832306 -309.979822) (xy 280.754836 -310.057292)
			(xy 280.74747 -310.080914) (xy 280.749756 -310.09336) (xy 280.752236 -310.107325) (xy 280.754906 -310.135565)
			(xy 280.75509 -310.149748) (xy 280.75457 -310.174564) (xy 280.746534 -310.22354) (xy 280.730679 -310.270572)
			(xy 280.707426 -310.314419) (xy 280.677385 -310.353926) (xy 280.641348 -310.388054) (xy 280.600266 -310.415902)
			(xy 280.555219 -310.436737) (xy 280.507395 -310.45001) (xy 280.458054 -310.455372) (xy 280.408495 -310.45268)
			(xy 280.360025 -310.442007) (xy 280.313919 -310.423634) (xy 280.271394 -310.398043) (xy 280.233568 -310.365911)
			(xy 280.201439 -310.328082) (xy 280.175853 -310.285554) (xy 280.157484 -310.239446) (xy 280.146815 -310.190975)
			(xy 280.144129 -310.141416) (xy 279.805497 -310.141416) (xy 279.805497 -310.141418) (xy 279.80281 -310.190981)
			(xy 279.79214 -310.239456) (xy 279.773769 -310.285567) (xy 279.748181 -310.328099) (xy 279.716049 -310.36593)
			(xy 279.67822 -310.398066) (xy 279.635691 -310.423658) (xy 279.589581 -310.442033) (xy 279.541107 -310.452706)
			(xy 279.491544 -310.455398) (xy 279.442199 -310.450035) (xy 279.394371 -310.436761) (xy 279.349321 -310.415924)
			(xy 279.308235 -310.388073) (xy 279.272195 -310.353943) (xy 279.242152 -310.314432) (xy 279.218897 -310.270582)
			(xy 279.203041 -310.223546) (xy 279.195004 -310.174566) (xy 279.194514 -310.149748) (xy 279.194697 -310.135565)
			(xy 279.197365 -310.107325) (xy 279.199848 -310.09336) (xy 279.202134 -310.080914) (xy 279.194768 -310.057292)
			(xy 279.117298 -309.979822) (xy 279.093676 -309.972456) (xy 279.08123 -309.974742) (xy 279.067265 -309.977224)
			(xy 279.039025 -309.979892) (xy 279.024842 -309.980076) (xy 279.010659 -309.979894) (xy 278.982419 -309.977226)
			(xy 278.968454 -309.974742) (xy 278.956008 -309.972456) (xy 278.932386 -309.979822) (xy 278.854916 -310.057292)
			(xy 278.84755 -310.080914) (xy 278.849836 -310.09336) (xy 278.852316 -310.107325) (xy 278.854986 -310.135565)
			(xy 278.85517 -310.149748) (xy 278.85467 -310.174563) (xy 278.846634 -310.223539) (xy 278.83078 -310.27057)
			(xy 278.807527 -310.314417) (xy 278.777487 -310.353924) (xy 278.741451 -310.388051) (xy 278.70037 -310.415899)
			(xy 278.655324 -310.436735) (xy 278.607501 -310.450009) (xy 278.558161 -310.455371) (xy 278.508603 -310.452681)
			(xy 278.460132 -310.44201) (xy 278.414027 -310.423638) (xy 278.371501 -310.398049) (xy 278.333675 -310.365918)
			(xy 278.301545 -310.32809) (xy 278.275958 -310.285564) (xy 278.257587 -310.239458) (xy 278.246917 -310.190988)
			(xy 278.244229 -310.141429) (xy 277.905043 -310.141429) (xy 277.90521 -310.149748) (xy 277.904715 -310.174355)
			(xy 277.89682 -310.222932) (xy 277.881236 -310.269613) (xy 277.858365 -310.31319) (xy 277.8288 -310.352534)
			(xy 277.793307 -310.386626) (xy 277.752804 -310.414582) (xy 277.708342 -310.43568) (xy 277.661071 -310.449372)
			(xy 277.612216 -310.455304) (xy 277.563041 -310.453323) (xy 277.514822 -310.443479) (xy 277.468806 -310.426027)
			(xy 277.426185 -310.40142) (xy 277.388064 -310.370295) (xy 277.355429 -310.333458) (xy 277.329126 -310.291862)
			(xy 277.309835 -310.246586) (xy 277.298058 -310.198802) (xy 277.294098 -310.149748) (xy 276.954996 -310.149748)
			(xy 276.954501 -310.174355) (xy 276.946606 -310.222932) (xy 276.931022 -310.269613) (xy 276.908151 -310.31319)
			(xy 276.878586 -310.352534) (xy 276.843093 -310.386626) (xy 276.80259 -310.414582) (xy 276.758128 -310.43568)
			(xy 276.710857 -310.449372) (xy 276.662002 -310.455304) (xy 276.612827 -310.453323) (xy 276.564608 -310.443479)
			(xy 276.518592 -310.426027) (xy 276.475971 -310.40142) (xy 276.43785 -310.370295) (xy 276.405215 -310.333458)
			(xy 276.378912 -310.291862) (xy 276.359621 -310.246586) (xy 276.347844 -310.198802) (xy 276.343884 -310.149748)
			(xy 276.005036 -310.149748) (xy 276.004541 -310.174355) (xy 275.996646 -310.222932) (xy 275.981062 -310.269613)
			(xy 275.958191 -310.31319) (xy 275.928626 -310.352534) (xy 275.893133 -310.386626) (xy 275.85263 -310.414582)
			(xy 275.808168 -310.43568) (xy 275.760897 -310.449372) (xy 275.712042 -310.455304) (xy 275.662867 -310.453323)
			(xy 275.614648 -310.443479) (xy 275.568632 -310.426027) (xy 275.526011 -310.40142) (xy 275.48789 -310.370295)
			(xy 275.455255 -310.333458) (xy 275.428952 -310.291862) (xy 275.409661 -310.246586) (xy 275.397884 -310.198802)
			(xy 275.393924 -310.149748) (xy 275.055076 -310.149748) (xy 275.054581 -310.174355) (xy 275.046686 -310.222932)
			(xy 275.031102 -310.269613) (xy 275.008231 -310.31319) (xy 274.978666 -310.352534) (xy 274.943173 -310.386626)
			(xy 274.90267 -310.414582) (xy 274.858208 -310.43568) (xy 274.810937 -310.449372) (xy 274.762082 -310.455304)
			(xy 274.712907 -310.453323) (xy 274.664688 -310.443479) (xy 274.618672 -310.426027) (xy 274.576051 -310.40142)
			(xy 274.53793 -310.370295) (xy 274.505295 -310.333458) (xy 274.478992 -310.291862) (xy 274.459701 -310.246586)
			(xy 274.447924 -310.198802) (xy 274.443964 -310.149748) (xy 274.105116 -310.149748) (xy 274.104621 -310.174355)
			(xy 274.096726 -310.222932) (xy 274.081142 -310.269613) (xy 274.058271 -310.31319) (xy 274.028706 -310.352534)
			(xy 273.993213 -310.386626) (xy 273.95271 -310.414582) (xy 273.908248 -310.43568) (xy 273.860977 -310.449372)
			(xy 273.812122 -310.455304) (xy 273.762947 -310.453323) (xy 273.714728 -310.443479) (xy 273.668712 -310.426027)
			(xy 273.626091 -310.40142) (xy 273.58797 -310.370295) (xy 273.555335 -310.333458) (xy 273.529032 -310.291862)
			(xy 273.509741 -310.246586) (xy 273.497964 -310.198802) (xy 273.494004 -310.149748) (xy 273.155156 -310.149748)
			(xy 273.154661 -310.174355) (xy 273.146766 -310.222932) (xy 273.131182 -310.269613) (xy 273.108311 -310.31319)
			(xy 273.078746 -310.352534) (xy 273.043253 -310.386626) (xy 273.00275 -310.414582) (xy 272.958288 -310.43568)
			(xy 272.911017 -310.449372) (xy 272.862162 -310.455304) (xy 272.812987 -310.453323) (xy 272.764768 -310.443479)
			(xy 272.718752 -310.426027) (xy 272.676131 -310.40142) (xy 272.63801 -310.370295) (xy 272.605375 -310.333458)
			(xy 272.579072 -310.291862) (xy 272.559781 -310.246586) (xy 272.548004 -310.198802) (xy 272.544044 -310.149748)
			(xy 272.205196 -310.149748) (xy 272.204701 -310.174355) (xy 272.196806 -310.222932) (xy 272.181222 -310.269613)
			(xy 272.158351 -310.31319) (xy 272.128786 -310.352534) (xy 272.093293 -310.386626) (xy 272.05279 -310.414582)
			(xy 272.008328 -310.43568) (xy 271.961057 -310.449372) (xy 271.912202 -310.455304) (xy 271.863027 -310.453323)
			(xy 271.814808 -310.443479) (xy 271.768792 -310.426027) (xy 271.726171 -310.40142) (xy 271.68805 -310.370295)
			(xy 271.655415 -310.333458) (xy 271.629112 -310.291862) (xy 271.609821 -310.246586) (xy 271.598044 -310.198802)
			(xy 271.594084 -310.149748) (xy 271.255236 -310.149748) (xy 271.254741 -310.174355) (xy 271.246846 -310.222932)
			(xy 271.231262 -310.269613) (xy 271.208391 -310.31319) (xy 271.178826 -310.352534) (xy 271.143333 -310.386626)
			(xy 271.10283 -310.414582) (xy 271.058368 -310.43568) (xy 271.011097 -310.449372) (xy 270.962242 -310.455304)
			(xy 270.913067 -310.453323) (xy 270.864848 -310.443479) (xy 270.818832 -310.426027) (xy 270.776211 -310.40142)
			(xy 270.73809 -310.370295) (xy 270.705455 -310.333458) (xy 270.679152 -310.291862) (xy 270.659861 -310.246586)
			(xy 270.648084 -310.198802) (xy 270.644124 -310.149748) (xy 270.326866 -310.149748) (xy 270.326362 -310.175456)
			(xy 270.318319 -310.226238) (xy 270.302431 -310.275137) (xy 270.279088 -310.320949) (xy 270.248867 -310.362545)
			(xy 270.212511 -310.398901) (xy 270.170915 -310.429122) (xy 270.125103 -310.452465) (xy 270.076204 -310.468353)
			(xy 270.025422 -310.476396) (xy 269.974006 -310.476396) (xy 269.923224 -310.468353) (xy 269.874325 -310.452465)
			(xy 269.828513 -310.429122) (xy 269.786917 -310.398901) (xy 269.750561 -310.362545) (xy 269.72034 -310.320949)
			(xy 269.696997 -310.275137) (xy 269.681109 -310.226238) (xy 269.673066 -310.175456) (xy 269.376402 -310.175456)
			(xy 269.368359 -310.226238) (xy 269.352471 -310.275137) (xy 269.329128 -310.320949) (xy 269.298907 -310.362545)
			(xy 269.262551 -310.398901) (xy 269.220955 -310.429122) (xy 269.175143 -310.452465) (xy 269.126244 -310.468353)
			(xy 269.075462 -310.476396) (xy 269.024046 -310.476396) (xy 268.973264 -310.468353) (xy 268.924365 -310.452465)
			(xy 268.878553 -310.429122) (xy 268.836957 -310.398901) (xy 268.800601 -310.362545) (xy 268.77038 -310.320949)
			(xy 268.747037 -310.275137) (xy 268.731149 -310.226238) (xy 268.723106 -310.175456) (xy 268.404215 -310.175456)
			(xy 268.396458 -310.223186) (xy 268.380874 -310.269867) (xy 268.358003 -310.313444) (xy 268.328438 -310.352788)
			(xy 268.292945 -310.38688) (xy 268.252442 -310.414836) (xy 268.20798 -310.435934) (xy 268.160709 -310.449626)
			(xy 268.111854 -310.455558) (xy 268.062679 -310.453577) (xy 268.01446 -310.443733) (xy 267.968444 -310.426281)
			(xy 267.925823 -310.401674) (xy 267.887702 -310.370549) (xy 267.855067 -310.333712) (xy 267.828764 -310.292116)
			(xy 267.809473 -310.24684) (xy 267.797696 -310.199056) (xy 267.793736 -310.150002) (xy 267.053672 -310.150002)
			(xy 267.055486 -310.156179) (xy 267.063242 -310.210127) (xy 267.063728 -310.237378) (xy 267.063203 -310.266152)
			(xy 267.054551 -310.323046) (xy 267.037455 -310.377996) (xy 267.012301 -310.429756) (xy 266.979662 -310.477153)
			(xy 266.96035 -310.49849) (xy 266.951009 -310.509061) (xy 266.93809 -310.534129) (xy 266.932524 -310.561776)
			(xy 266.934738 -310.58989) (xy 266.944561 -310.616326) (xy 266.961243 -310.639064) (xy 266.983512 -310.656368)
			(xy 266.996418 -310.662066) (xy 267.022494 -310.673139) (xy 267.071314 -310.701876) (xy 267.115349 -310.737516)
			(xy 267.153631 -310.779275) (xy 267.185318 -310.826234) (xy 267.209715 -310.877362) (xy 267.226283 -310.931535)
			(xy 267.234661 -310.987563) (xy 267.235178 -311.015888) (xy 267.234692 -311.043139) (xy 267.226936 -311.097087)
			(xy 267.226092 -311.099962) (xy 268.74395 -311.099962) (xy 268.74791 -311.050908) (xy 268.759687 -311.003124)
			(xy 268.778978 -310.957848) (xy 268.805281 -310.916252) (xy 268.837916 -310.879415) (xy 268.876037 -310.84829)
			(xy 268.918658 -310.823683) (xy 268.964674 -310.806231) (xy 269.012893 -310.796387) (xy 269.062068 -310.794406)
			(xy 269.110923 -310.800338) (xy 269.158194 -310.81403) (xy 269.202656 -310.835128) (xy 269.243159 -310.863084)
			(xy 269.278652 -310.897176) (xy 269.308217 -310.93652) (xy 269.331088 -310.980097) (xy 269.346672 -311.026778)
			(xy 269.354567 -311.075355) (xy 269.355062 -311.099962) (xy 269.69391 -311.099962) (xy 269.69787 -311.050908)
			(xy 269.709647 -311.003124) (xy 269.728938 -310.957848) (xy 269.755241 -310.916252) (xy 269.787876 -310.879415)
			(xy 269.825997 -310.84829) (xy 269.868618 -310.823683) (xy 269.914634 -310.806231) (xy 269.962853 -310.796387)
			(xy 270.012028 -310.794406) (xy 270.060883 -310.800338) (xy 270.108154 -310.81403) (xy 270.152616 -310.835128)
			(xy 270.193119 -310.863084) (xy 270.228612 -310.897176) (xy 270.258177 -310.93652) (xy 270.281048 -310.980097)
			(xy 270.296632 -311.026778) (xy 270.304527 -311.075355) (xy 270.305022 -311.099962) (xy 270.644124 -311.099962)
			(xy 270.648084 -311.050908) (xy 270.659861 -311.003124) (xy 270.679152 -310.957848) (xy 270.705455 -310.916252)
			(xy 270.73809 -310.879415) (xy 270.776211 -310.84829) (xy 270.818832 -310.823683) (xy 270.864848 -310.806231)
			(xy 270.913067 -310.796387) (xy 270.962242 -310.794406) (xy 271.011097 -310.800338) (xy 271.058368 -310.81403)
			(xy 271.10283 -310.835128) (xy 271.143333 -310.863084) (xy 271.178826 -310.897176) (xy 271.208391 -310.93652)
			(xy 271.231262 -310.980097) (xy 271.246846 -311.026778) (xy 271.254741 -311.075355) (xy 271.255236 -311.099962)
			(xy 271.254741 -311.124569) (xy 271.254562 -311.12567) (xy 271.57324 -311.12567) (xy 271.57324 -311.074254)
			(xy 271.581283 -311.023472) (xy 271.597171 -310.974573) (xy 271.620514 -310.928761) (xy 271.650735 -310.887165)
			(xy 271.687091 -310.850809) (xy 271.728687 -310.820588) (xy 271.774499 -310.797245) (xy 271.823398 -310.781357)
			(xy 271.87418 -310.773314) (xy 271.925596 -310.773314) (xy 271.976378 -310.781357) (xy 272.025277 -310.797245)
			(xy 272.071089 -310.820588) (xy 272.112685 -310.850809) (xy 272.149041 -310.887165) (xy 272.179262 -310.928761)
			(xy 272.202605 -310.974573) (xy 272.218493 -311.023472) (xy 272.226536 -311.074254) (xy 272.22704 -311.099962)
			(xy 272.544044 -311.099962) (xy 272.548004 -311.050908) (xy 272.559781 -311.003124) (xy 272.579072 -310.957848)
			(xy 272.605375 -310.916252) (xy 272.63801 -310.879415) (xy 272.676131 -310.84829) (xy 272.718752 -310.823683)
			(xy 272.764768 -310.806231) (xy 272.812987 -310.796387) (xy 272.862162 -310.794406) (xy 272.911017 -310.800338)
			(xy 272.958288 -310.81403) (xy 273.00275 -310.835128) (xy 273.043253 -310.863084) (xy 273.078746 -310.897176)
			(xy 273.108311 -310.93652) (xy 273.131182 -310.980097) (xy 273.146766 -311.026778) (xy 273.154661 -311.075355)
			(xy 273.155156 -311.099962) (xy 273.154661 -311.124569) (xy 273.154482 -311.12567) (xy 273.47316 -311.12567)
			(xy 273.47316 -311.074254) (xy 273.481203 -311.023472) (xy 273.497091 -310.974573) (xy 273.520434 -310.928761)
			(xy 273.550655 -310.887165) (xy 273.587011 -310.850809) (xy 273.628607 -310.820588) (xy 273.674419 -310.797245)
			(xy 273.723318 -310.781357) (xy 273.7741 -310.773314) (xy 273.825516 -310.773314) (xy 273.876298 -310.781357)
			(xy 273.925197 -310.797245) (xy 273.971009 -310.820588) (xy 274.012605 -310.850809) (xy 274.048961 -310.887165)
			(xy 274.079182 -310.928761) (xy 274.102525 -310.974573) (xy 274.118413 -311.023472) (xy 274.126456 -311.074254)
			(xy 274.12696 -311.099962) (xy 274.443964 -311.099962) (xy 274.447924 -311.050908) (xy 274.459701 -311.003124)
			(xy 274.478992 -310.957848) (xy 274.505295 -310.916252) (xy 274.53793 -310.879415) (xy 274.576051 -310.84829)
			(xy 274.618672 -310.823683) (xy 274.664688 -310.806231) (xy 274.712907 -310.796387) (xy 274.762082 -310.794406)
			(xy 274.810937 -310.800338) (xy 274.858208 -310.81403) (xy 274.90267 -310.835128) (xy 274.943173 -310.863084)
			(xy 274.978666 -310.897176) (xy 275.008231 -310.93652) (xy 275.031102 -310.980097) (xy 275.046686 -311.026778)
			(xy 275.054581 -311.075355) (xy 275.055076 -311.099962) (xy 275.054581 -311.124569) (xy 275.054402 -311.12567)
			(xy 275.37308 -311.12567) (xy 275.37308 -311.074254) (xy 275.381123 -311.023472) (xy 275.397011 -310.974573)
			(xy 275.420354 -310.928761) (xy 275.450575 -310.887165) (xy 275.486931 -310.850809) (xy 275.528527 -310.820588)
			(xy 275.574339 -310.797245) (xy 275.623238 -310.781357) (xy 275.67402 -310.773314) (xy 275.725436 -310.773314)
			(xy 275.776218 -310.781357) (xy 275.825117 -310.797245) (xy 275.870929 -310.820588) (xy 275.912525 -310.850809)
			(xy 275.948881 -310.887165) (xy 275.979102 -310.928761) (xy 276.002445 -310.974573) (xy 276.018333 -311.023472)
			(xy 276.026376 -311.074254) (xy 276.02688 -311.099962) (xy 276.343884 -311.099962) (xy 276.347844 -311.050908)
			(xy 276.359621 -311.003124) (xy 276.378912 -310.957848) (xy 276.405215 -310.916252) (xy 276.43785 -310.879415)
			(xy 276.475971 -310.84829) (xy 276.518592 -310.823683) (xy 276.564608 -310.806231) (xy 276.612827 -310.796387)
			(xy 276.662002 -310.794406) (xy 276.710857 -310.800338) (xy 276.758128 -310.81403) (xy 276.80259 -310.835128)
			(xy 276.843093 -310.863084) (xy 276.878586 -310.897176) (xy 276.908151 -310.93652) (xy 276.931022 -310.980097)
			(xy 276.946606 -311.026778) (xy 276.954501 -311.075355) (xy 276.954996 -311.099962) (xy 276.954501 -311.124569)
			(xy 276.954322 -311.12567) (xy 277.273254 -311.12567) (xy 277.273254 -311.074254) (xy 277.281297 -311.023472)
			(xy 277.297185 -310.974573) (xy 277.320528 -310.928761) (xy 277.350749 -310.887165) (xy 277.387105 -310.850809)
			(xy 277.428701 -310.820588) (xy 277.474513 -310.797245) (xy 277.523412 -310.781357) (xy 277.574194 -310.773314)
			(xy 277.62561 -310.773314) (xy 277.676392 -310.781357) (xy 277.725291 -310.797245) (xy 277.771103 -310.820588)
			(xy 277.812699 -310.850809) (xy 277.849055 -310.887165) (xy 277.879276 -310.928761) (xy 277.902619 -310.974573)
			(xy 277.918507 -311.023472) (xy 277.92655 -311.074254) (xy 277.927054 -311.099962) (xy 278.244058 -311.099962)
			(xy 278.248018 -311.050908) (xy 278.259795 -311.003124) (xy 278.279086 -310.957848) (xy 278.305389 -310.916252)
			(xy 278.338024 -310.879415) (xy 278.376145 -310.84829) (xy 278.418766 -310.823683) (xy 278.464782 -310.806231)
			(xy 278.513001 -310.796387) (xy 278.562176 -310.794406) (xy 278.611031 -310.800338) (xy 278.658302 -310.81403)
			(xy 278.702764 -310.835128) (xy 278.743267 -310.863084) (xy 278.77876 -310.897176) (xy 278.808325 -310.93652)
			(xy 278.831196 -310.980097) (xy 278.84678 -311.026778) (xy 278.854675 -311.075355) (xy 278.85517 -311.099962)
			(xy 278.854675 -311.124569) (xy 278.854496 -311.12567) (xy 279.173174 -311.12567) (xy 279.173174 -311.074254)
			(xy 279.181217 -311.023472) (xy 279.197105 -310.974573) (xy 279.220448 -310.928761) (xy 279.250669 -310.887165)
			(xy 279.287025 -310.850809) (xy 279.328621 -310.820588) (xy 279.374433 -310.797245) (xy 279.423332 -310.781357)
			(xy 279.474114 -310.773314) (xy 279.52553 -310.773314) (xy 279.576312 -310.781357) (xy 279.625211 -310.797245)
			(xy 279.671023 -310.820588) (xy 279.712619 -310.850809) (xy 279.748975 -310.887165) (xy 279.779196 -310.928761)
			(xy 279.802539 -310.974573) (xy 279.818427 -311.023472) (xy 279.82647 -311.074254) (xy 279.826974 -311.099962)
			(xy 280.143978 -311.099962) (xy 280.147938 -311.050908) (xy 280.159715 -311.003124) (xy 280.179006 -310.957848)
			(xy 280.205309 -310.916252) (xy 280.237944 -310.879415) (xy 280.276065 -310.84829) (xy 280.318686 -310.823683)
			(xy 280.364702 -310.806231) (xy 280.412921 -310.796387) (xy 280.462096 -310.794406) (xy 280.510951 -310.800338)
			(xy 280.558222 -310.81403) (xy 280.602684 -310.835128) (xy 280.643187 -310.863084) (xy 280.67868 -310.897176)
			(xy 280.708245 -310.93652) (xy 280.731116 -310.980097) (xy 280.7467 -311.026778) (xy 280.754595 -311.075355)
			(xy 280.75509 -311.099962) (xy 280.754595 -311.124569) (xy 280.754416 -311.12567) (xy 281.073094 -311.12567)
			(xy 281.073094 -311.074254) (xy 281.081137 -311.023472) (xy 281.097025 -310.974573) (xy 281.120368 -310.928761)
			(xy 281.150589 -310.887165) (xy 281.186945 -310.850809) (xy 281.228541 -310.820588) (xy 281.274353 -310.797245)
			(xy 281.323252 -310.781357) (xy 281.374034 -310.773314) (xy 281.42545 -310.773314) (xy 281.476232 -310.781357)
			(xy 281.525131 -310.797245) (xy 281.570943 -310.820588) (xy 281.612539 -310.850809) (xy 281.648895 -310.887165)
			(xy 281.679116 -310.928761) (xy 281.702459 -310.974573) (xy 281.718347 -311.023472) (xy 281.72639 -311.074254)
			(xy 281.726894 -311.099962) (xy 282.043898 -311.099962) (xy 282.047858 -311.050908) (xy 282.059635 -311.003124)
			(xy 282.078926 -310.957848) (xy 282.105229 -310.916252) (xy 282.137864 -310.879415) (xy 282.175985 -310.84829)
			(xy 282.218606 -310.823683) (xy 282.264622 -310.806231) (xy 282.312841 -310.796387) (xy 282.362016 -310.794406)
			(xy 282.410871 -310.800338) (xy 282.458142 -310.81403) (xy 282.502604 -310.835128) (xy 282.543107 -310.863084)
			(xy 282.5786 -310.897176) (xy 282.608165 -310.93652) (xy 282.631036 -310.980097) (xy 282.64662 -311.026778)
			(xy 282.654515 -311.075355) (xy 282.65501 -311.099962) (xy 282.654515 -311.124569) (xy 282.654336 -311.12567)
			(xy 282.973268 -311.12567) (xy 282.973268 -311.074254) (xy 282.981311 -311.023472) (xy 282.997199 -310.974573)
			(xy 283.020542 -310.928761) (xy 283.050763 -310.887165) (xy 283.087119 -310.850809) (xy 283.128715 -310.820588)
			(xy 283.174527 -310.797245) (xy 283.223426 -310.781357) (xy 283.274208 -310.773314) (xy 283.325624 -310.773314)
			(xy 283.376406 -310.781357) (xy 283.425305 -310.797245) (xy 283.471117 -310.820588) (xy 283.512713 -310.850809)
			(xy 283.549069 -310.887165) (xy 283.57929 -310.928761) (xy 283.602633 -310.974573) (xy 283.618521 -311.023472)
			(xy 283.626564 -311.074254) (xy 283.627068 -311.099962) (xy 283.944072 -311.099962) (xy 283.948032 -311.050908)
			(xy 283.959809 -311.003124) (xy 283.9791 -310.957848) (xy 284.005403 -310.916252) (xy 284.038038 -310.879415)
			(xy 284.076159 -310.84829) (xy 284.11878 -310.823683) (xy 284.164796 -310.806231) (xy 284.213015 -310.796387)
			(xy 284.26219 -310.794406) (xy 284.311045 -310.800338) (xy 284.358316 -310.81403) (xy 284.402778 -310.835128)
			(xy 284.443281 -310.863084) (xy 284.478774 -310.897176) (xy 284.508339 -310.93652) (xy 284.53121 -310.980097)
			(xy 284.546794 -311.026778) (xy 284.554689 -311.075355) (xy 284.555184 -311.099962) (xy 284.554689 -311.124569)
			(xy 284.55451 -311.12567) (xy 284.873188 -311.12567) (xy 284.873188 -311.074254) (xy 284.881231 -311.023472)
			(xy 284.897119 -310.974573) (xy 284.920462 -310.928761) (xy 284.950683 -310.887165) (xy 284.987039 -310.850809)
			(xy 285.028635 -310.820588) (xy 285.074447 -310.797245) (xy 285.123346 -310.781357) (xy 285.174128 -310.773314)
			(xy 285.225544 -310.773314) (xy 285.276326 -310.781357) (xy 285.325225 -310.797245) (xy 285.371037 -310.820588)
			(xy 285.412633 -310.850809) (xy 285.448989 -310.887165) (xy 285.47921 -310.928761) (xy 285.502553 -310.974573)
			(xy 285.518441 -311.023472) (xy 285.526484 -311.074254) (xy 285.526988 -311.099962) (xy 285.843992 -311.099962)
			(xy 285.847952 -311.050908) (xy 285.859729 -311.003124) (xy 285.87902 -310.957848) (xy 285.905323 -310.916252)
			(xy 285.937958 -310.879415) (xy 285.976079 -310.84829) (xy 286.0187 -310.823683) (xy 286.064716 -310.806231)
			(xy 286.112935 -310.796387) (xy 286.16211 -310.794406) (xy 286.210965 -310.800338) (xy 286.258236 -310.81403)
			(xy 286.302698 -310.835128) (xy 286.343201 -310.863084) (xy 286.378694 -310.897176) (xy 286.408259 -310.93652)
			(xy 286.43113 -310.980097) (xy 286.446714 -311.026778) (xy 286.454609 -311.075355) (xy 286.455104 -311.099962)
			(xy 286.454609 -311.124569) (xy 286.45443 -311.12567) (xy 286.773108 -311.12567) (xy 286.773108 -311.074254)
			(xy 286.781151 -311.023472) (xy 286.797039 -310.974573) (xy 286.820382 -310.928761) (xy 286.850603 -310.887165)
			(xy 286.886959 -310.850809) (xy 286.928555 -310.820588) (xy 286.974367 -310.797245) (xy 287.023266 -310.781357)
			(xy 287.074048 -310.773314) (xy 287.125464 -310.773314) (xy 287.176246 -310.781357) (xy 287.225145 -310.797245)
			(xy 287.270957 -310.820588) (xy 287.312553 -310.850809) (xy 287.348909 -310.887165) (xy 287.37913 -310.928761)
			(xy 287.402473 -310.974573) (xy 287.418361 -311.023472) (xy 287.426404 -311.074254) (xy 287.426908 -311.099962)
			(xy 287.743912 -311.099962) (xy 287.747872 -311.050908) (xy 287.759649 -311.003124) (xy 287.77894 -310.957848)
			(xy 287.805243 -310.916252) (xy 287.837878 -310.879415) (xy 287.875999 -310.84829) (xy 287.91862 -310.823683)
			(xy 287.964636 -310.806231) (xy 288.012855 -310.796387) (xy 288.06203 -310.794406) (xy 288.110885 -310.800338)
			(xy 288.158156 -310.81403) (xy 288.202618 -310.835128) (xy 288.243121 -310.863084) (xy 288.278614 -310.897176)
			(xy 288.308179 -310.93652) (xy 288.33105 -310.980097) (xy 288.346634 -311.026778) (xy 288.354529 -311.075355)
			(xy 288.355024 -311.099962) (xy 288.354529 -311.124569) (xy 288.35435 -311.12567) (xy 288.673282 -311.12567)
			(xy 288.673282 -311.074254) (xy 288.681325 -311.023472) (xy 288.697213 -310.974573) (xy 288.720556 -310.928761)
			(xy 288.750777 -310.887165) (xy 288.787133 -310.850809) (xy 288.828729 -310.820588) (xy 288.874541 -310.797245)
			(xy 288.92344 -310.781357) (xy 288.974222 -310.773314) (xy 289.025638 -310.773314) (xy 289.07642 -310.781357)
			(xy 289.125319 -310.797245) (xy 289.171131 -310.820588) (xy 289.212727 -310.850809) (xy 289.249083 -310.887165)
			(xy 289.279304 -310.928761) (xy 289.302647 -310.974573) (xy 289.318535 -311.023472) (xy 289.326578 -311.074254)
			(xy 289.327082 -311.099962) (xy 289.644086 -311.099962) (xy 289.648046 -311.050908) (xy 289.659823 -311.003124)
			(xy 289.679114 -310.957848) (xy 289.705417 -310.916252) (xy 289.738052 -310.879415) (xy 289.776173 -310.84829)
			(xy 289.818794 -310.823683) (xy 289.86481 -310.806231) (xy 289.913029 -310.796387) (xy 289.962204 -310.794406)
			(xy 290.011059 -310.800338) (xy 290.05833 -310.81403) (xy 290.102792 -310.835128) (xy 290.143295 -310.863084)
			(xy 290.178788 -310.897176) (xy 290.208353 -310.93652) (xy 290.231224 -310.980097) (xy 290.246808 -311.026778)
			(xy 290.254703 -311.075355) (xy 290.255198 -311.099962) (xy 290.254703 -311.124569) (xy 290.254524 -311.12567)
			(xy 290.573202 -311.12567) (xy 290.573202 -311.074254) (xy 290.581245 -311.023472) (xy 290.597133 -310.974573)
			(xy 290.620476 -310.928761) (xy 290.650697 -310.887165) (xy 290.687053 -310.850809) (xy 290.728649 -310.820588)
			(xy 290.774461 -310.797245) (xy 290.82336 -310.781357) (xy 290.874142 -310.773314) (xy 290.925558 -310.773314)
			(xy 290.97634 -310.781357) (xy 291.025239 -310.797245) (xy 291.071051 -310.820588) (xy 291.112647 -310.850809)
			(xy 291.149003 -310.887165) (xy 291.179224 -310.928761) (xy 291.202567 -310.974573) (xy 291.218455 -311.023472)
			(xy 291.226498 -311.074254) (xy 291.227002 -311.099962) (xy 291.544006 -311.099962) (xy 291.547966 -311.050908)
			(xy 291.559743 -311.003124) (xy 291.579034 -310.957848) (xy 291.605337 -310.916252) (xy 291.637972 -310.879415)
			(xy 291.676093 -310.84829) (xy 291.718714 -310.823683) (xy 291.76473 -310.806231) (xy 291.812949 -310.796387)
			(xy 291.862124 -310.794406) (xy 291.910979 -310.800338) (xy 291.95825 -310.81403) (xy 292.002712 -310.835128)
			(xy 292.043215 -310.863084) (xy 292.078708 -310.897176) (xy 292.108273 -310.93652) (xy 292.131144 -310.980097)
			(xy 292.146728 -311.026778) (xy 292.154623 -311.075355) (xy 292.155118 -311.099962) (xy 292.154623 -311.124569)
			(xy 292.154444 -311.12567) (xy 292.473122 -311.12567) (xy 292.473122 -311.074254) (xy 292.481165 -311.023472)
			(xy 292.497053 -310.974573) (xy 292.520396 -310.928761) (xy 292.550617 -310.887165) (xy 292.586973 -310.850809)
			(xy 292.628569 -310.820588) (xy 292.674381 -310.797245) (xy 292.72328 -310.781357) (xy 292.774062 -310.773314)
			(xy 292.825478 -310.773314) (xy 292.87626 -310.781357) (xy 292.925159 -310.797245) (xy 292.970971 -310.820588)
			(xy 293.012567 -310.850809) (xy 293.048923 -310.887165) (xy 293.079144 -310.928761) (xy 293.102487 -310.974573)
			(xy 293.118375 -311.023472) (xy 293.126418 -311.074254) (xy 293.126922 -311.099962) (xy 293.443926 -311.099962)
			(xy 293.447886 -311.050908) (xy 293.459663 -311.003124) (xy 293.478954 -310.957848) (xy 293.505257 -310.916252)
			(xy 293.537892 -310.879415) (xy 293.576013 -310.84829) (xy 293.618634 -310.823683) (xy 293.66465 -310.806231)
			(xy 293.712869 -310.796387) (xy 293.762044 -310.794406) (xy 293.810899 -310.800338) (xy 293.85817 -310.81403)
			(xy 293.902632 -310.835128) (xy 293.943135 -310.863084) (xy 293.978628 -310.897176) (xy 294.008193 -310.93652)
			(xy 294.031064 -310.980097) (xy 294.046648 -311.026778) (xy 294.054543 -311.075355) (xy 294.055038 -311.099962)
			(xy 294.054543 -311.124569) (xy 294.054364 -311.12567) (xy 294.373042 -311.12567) (xy 294.373042 -311.074254)
			(xy 294.381085 -311.023472) (xy 294.396973 -310.974573) (xy 294.420316 -310.928761) (xy 294.450537 -310.887165)
			(xy 294.486893 -310.850809) (xy 294.528489 -310.820588) (xy 294.574301 -310.797245) (xy 294.6232 -310.781357)
			(xy 294.673982 -310.773314) (xy 294.725398 -310.773314) (xy 294.77618 -310.781357) (xy 294.825079 -310.797245)
			(xy 294.870891 -310.820588) (xy 294.912487 -310.850809) (xy 294.948843 -310.887165) (xy 294.979064 -310.928761)
			(xy 295.002407 -310.974573) (xy 295.018295 -311.023472) (xy 295.026338 -311.074254) (xy 295.026842 -311.099962)
			(xy 295.3441 -311.099962) (xy 295.34806 -311.050908) (xy 295.359837 -311.003124) (xy 295.379128 -310.957848)
			(xy 295.405431 -310.916252) (xy 295.438066 -310.879415) (xy 295.476187 -310.84829) (xy 295.518808 -310.823683)
			(xy 295.564824 -310.806231) (xy 295.613043 -310.796387) (xy 295.662218 -310.794406) (xy 295.711073 -310.800338)
			(xy 295.758344 -310.81403) (xy 295.802806 -310.835128) (xy 295.843309 -310.863084) (xy 295.878802 -310.897176)
			(xy 295.908367 -310.93652) (xy 295.931238 -310.980097) (xy 295.946822 -311.026778) (xy 295.954717 -311.075355)
			(xy 295.955212 -311.099962) (xy 295.954717 -311.124569) (xy 295.954538 -311.12567) (xy 296.273216 -311.12567)
			(xy 296.273216 -311.074254) (xy 296.281259 -311.023472) (xy 296.297147 -310.974573) (xy 296.32049 -310.928761)
			(xy 296.350711 -310.887165) (xy 296.387067 -310.850809) (xy 296.428663 -310.820588) (xy 296.474475 -310.797245)
			(xy 296.523374 -310.781357) (xy 296.574156 -310.773314) (xy 296.625572 -310.773314) (xy 296.676354 -310.781357)
			(xy 296.725253 -310.797245) (xy 296.771065 -310.820588) (xy 296.812661 -310.850809) (xy 296.849017 -310.887165)
			(xy 296.879238 -310.928761) (xy 296.902581 -310.974573) (xy 296.918469 -311.023472) (xy 296.926512 -311.074254)
			(xy 296.927016 -311.099962) (xy 297.24402 -311.099962) (xy 297.24798 -311.050908) (xy 297.259757 -311.003124)
			(xy 297.279048 -310.957848) (xy 297.305351 -310.916252) (xy 297.337986 -310.879415) (xy 297.376107 -310.84829)
			(xy 297.418728 -310.823683) (xy 297.464744 -310.806231) (xy 297.512963 -310.796387) (xy 297.562138 -310.794406)
			(xy 297.610993 -310.800338) (xy 297.658264 -310.81403) (xy 297.702726 -310.835128) (xy 297.743229 -310.863084)
			(xy 297.778722 -310.897176) (xy 297.808287 -310.93652) (xy 297.831158 -310.980097) (xy 297.846742 -311.026778)
			(xy 297.854637 -311.075355) (xy 297.855132 -311.099962) (xy 297.854637 -311.124569) (xy 297.854458 -311.12567)
			(xy 298.173136 -311.12567) (xy 298.173136 -311.074254) (xy 298.181179 -311.023472) (xy 298.197067 -310.974573)
			(xy 298.22041 -310.928761) (xy 298.250631 -310.887165) (xy 298.286987 -310.850809) (xy 298.328583 -310.820588)
			(xy 298.374395 -310.797245) (xy 298.423294 -310.781357) (xy 298.474076 -310.773314) (xy 298.525492 -310.773314)
			(xy 298.576274 -310.781357) (xy 298.625173 -310.797245) (xy 298.670985 -310.820588) (xy 298.712581 -310.850809)
			(xy 298.748937 -310.887165) (xy 298.779158 -310.928761) (xy 298.802501 -310.974573) (xy 298.818389 -311.023472)
			(xy 298.826432 -311.074254) (xy 298.826936 -311.099962) (xy 299.14394 -311.099962) (xy 299.1479 -311.050908)
			(xy 299.159677 -311.003124) (xy 299.178968 -310.957848) (xy 299.205271 -310.916252) (xy 299.237906 -310.879415)
			(xy 299.276027 -310.84829) (xy 299.318648 -310.823683) (xy 299.364664 -310.806231) (xy 299.412883 -310.796387)
			(xy 299.462058 -310.794406) (xy 299.510913 -310.800338) (xy 299.558184 -310.81403) (xy 299.602646 -310.835128)
			(xy 299.643149 -310.863084) (xy 299.678642 -310.897176) (xy 299.708207 -310.93652) (xy 299.731078 -310.980097)
			(xy 299.746662 -311.026778) (xy 299.754557 -311.075355) (xy 299.755052 -311.099962) (xy 299.754557 -311.124569)
			(xy 299.746662 -311.173146) (xy 299.731078 -311.219827) (xy 299.708207 -311.263404) (xy 299.678642 -311.302748)
			(xy 299.643149 -311.33684) (xy 299.602646 -311.364796) (xy 299.558184 -311.385894) (xy 299.510913 -311.399586)
			(xy 299.462058 -311.405518) (xy 299.412883 -311.403537) (xy 299.364664 -311.393693) (xy 299.318648 -311.376241)
			(xy 299.276027 -311.351634) (xy 299.237906 -311.320509) (xy 299.205271 -311.283672) (xy 299.178968 -311.242076)
			(xy 299.159677 -311.1968) (xy 299.1479 -311.149016) (xy 299.14394 -311.099962) (xy 298.826936 -311.099962)
			(xy 298.826432 -311.12567) (xy 298.818389 -311.176452) (xy 298.802501 -311.225351) (xy 298.779158 -311.271163)
			(xy 298.748937 -311.312759) (xy 298.712581 -311.349115) (xy 298.670985 -311.379336) (xy 298.625173 -311.402679)
			(xy 298.576274 -311.418567) (xy 298.525492 -311.42661) (xy 298.474076 -311.42661) (xy 298.423294 -311.418567)
			(xy 298.374395 -311.402679) (xy 298.328583 -311.379336) (xy 298.286987 -311.349115) (xy 298.250631 -311.312759)
			(xy 298.22041 -311.271163) (xy 298.197067 -311.225351) (xy 298.181179 -311.176452) (xy 298.173136 -311.12567)
			(xy 297.854458 -311.12567) (xy 297.846742 -311.173146) (xy 297.831158 -311.219827) (xy 297.808287 -311.263404)
			(xy 297.778722 -311.302748) (xy 297.743229 -311.33684) (xy 297.702726 -311.364796) (xy 297.658264 -311.385894)
			(xy 297.610993 -311.399586) (xy 297.562138 -311.405518) (xy 297.512963 -311.403537) (xy 297.464744 -311.393693)
			(xy 297.418728 -311.376241) (xy 297.376107 -311.351634) (xy 297.337986 -311.320509) (xy 297.305351 -311.283672)
			(xy 297.279048 -311.242076) (xy 297.259757 -311.1968) (xy 297.24798 -311.149016) (xy 297.24402 -311.099962)
			(xy 296.927016 -311.099962) (xy 296.926512 -311.12567) (xy 296.918469 -311.176452) (xy 296.902581 -311.225351)
			(xy 296.879238 -311.271163) (xy 296.849017 -311.312759) (xy 296.812661 -311.349115) (xy 296.771065 -311.379336)
			(xy 296.725253 -311.402679) (xy 296.676354 -311.418567) (xy 296.625572 -311.42661) (xy 296.574156 -311.42661)
			(xy 296.523374 -311.418567) (xy 296.474475 -311.402679) (xy 296.428663 -311.379336) (xy 296.387067 -311.349115)
			(xy 296.350711 -311.312759) (xy 296.32049 -311.271163) (xy 296.297147 -311.225351) (xy 296.281259 -311.176452)
			(xy 296.273216 -311.12567) (xy 295.954538 -311.12567) (xy 295.946822 -311.173146) (xy 295.931238 -311.219827)
			(xy 295.908367 -311.263404) (xy 295.878802 -311.302748) (xy 295.843309 -311.33684) (xy 295.802806 -311.364796)
			(xy 295.758344 -311.385894) (xy 295.711073 -311.399586) (xy 295.662218 -311.405518) (xy 295.613043 -311.403537)
			(xy 295.564824 -311.393693) (xy 295.518808 -311.376241) (xy 295.476187 -311.351634) (xy 295.438066 -311.320509)
			(xy 295.405431 -311.283672) (xy 295.379128 -311.242076) (xy 295.359837 -311.1968) (xy 295.34806 -311.149016)
			(xy 295.3441 -311.099962) (xy 295.026842 -311.099962) (xy 295.026338 -311.12567) (xy 295.018295 -311.176452)
			(xy 295.002407 -311.225351) (xy 294.979064 -311.271163) (xy 294.948843 -311.312759) (xy 294.912487 -311.349115)
			(xy 294.870891 -311.379336) (xy 294.825079 -311.402679) (xy 294.77618 -311.418567) (xy 294.725398 -311.42661)
			(xy 294.673982 -311.42661) (xy 294.6232 -311.418567) (xy 294.574301 -311.402679) (xy 294.528489 -311.379336)
			(xy 294.486893 -311.349115) (xy 294.450537 -311.312759) (xy 294.420316 -311.271163) (xy 294.396973 -311.225351)
			(xy 294.381085 -311.176452) (xy 294.373042 -311.12567) (xy 294.054364 -311.12567) (xy 294.046648 -311.173146)
			(xy 294.031064 -311.219827) (xy 294.008193 -311.263404) (xy 293.978628 -311.302748) (xy 293.943135 -311.33684)
			(xy 293.902632 -311.364796) (xy 293.85817 -311.385894) (xy 293.810899 -311.399586) (xy 293.762044 -311.405518)
			(xy 293.712869 -311.403537) (xy 293.66465 -311.393693) (xy 293.618634 -311.376241) (xy 293.576013 -311.351634)
			(xy 293.537892 -311.320509) (xy 293.505257 -311.283672) (xy 293.478954 -311.242076) (xy 293.459663 -311.1968)
			(xy 293.447886 -311.149016) (xy 293.443926 -311.099962) (xy 293.126922 -311.099962) (xy 293.126418 -311.12567)
			(xy 293.118375 -311.176452) (xy 293.102487 -311.225351) (xy 293.079144 -311.271163) (xy 293.048923 -311.312759)
			(xy 293.012567 -311.349115) (xy 292.970971 -311.379336) (xy 292.925159 -311.402679) (xy 292.87626 -311.418567)
			(xy 292.825478 -311.42661) (xy 292.774062 -311.42661) (xy 292.72328 -311.418567) (xy 292.674381 -311.402679)
			(xy 292.628569 -311.379336) (xy 292.586973 -311.349115) (xy 292.550617 -311.312759) (xy 292.520396 -311.271163)
			(xy 292.497053 -311.225351) (xy 292.481165 -311.176452) (xy 292.473122 -311.12567) (xy 292.154444 -311.12567)
			(xy 292.146728 -311.173146) (xy 292.131144 -311.219827) (xy 292.108273 -311.263404) (xy 292.078708 -311.302748)
			(xy 292.043215 -311.33684) (xy 292.002712 -311.364796) (xy 291.95825 -311.385894) (xy 291.910979 -311.399586)
			(xy 291.862124 -311.405518) (xy 291.812949 -311.403537) (xy 291.76473 -311.393693) (xy 291.718714 -311.376241)
			(xy 291.676093 -311.351634) (xy 291.637972 -311.320509) (xy 291.605337 -311.283672) (xy 291.579034 -311.242076)
			(xy 291.559743 -311.1968) (xy 291.547966 -311.149016) (xy 291.544006 -311.099962) (xy 291.227002 -311.099962)
			(xy 291.226498 -311.12567) (xy 291.218455 -311.176452) (xy 291.202567 -311.225351) (xy 291.179224 -311.271163)
			(xy 291.149003 -311.312759) (xy 291.112647 -311.349115) (xy 291.071051 -311.379336) (xy 291.025239 -311.402679)
			(xy 290.97634 -311.418567) (xy 290.925558 -311.42661) (xy 290.874142 -311.42661) (xy 290.82336 -311.418567)
			(xy 290.774461 -311.402679) (xy 290.728649 -311.379336) (xy 290.687053 -311.349115) (xy 290.650697 -311.312759)
			(xy 290.620476 -311.271163) (xy 290.597133 -311.225351) (xy 290.581245 -311.176452) (xy 290.573202 -311.12567)
			(xy 290.254524 -311.12567) (xy 290.246808 -311.173146) (xy 290.231224 -311.219827) (xy 290.208353 -311.263404)
			(xy 290.178788 -311.302748) (xy 290.143295 -311.33684) (xy 290.102792 -311.364796) (xy 290.05833 -311.385894)
			(xy 290.011059 -311.399586) (xy 289.962204 -311.405518) (xy 289.913029 -311.403537) (xy 289.86481 -311.393693)
			(xy 289.818794 -311.376241) (xy 289.776173 -311.351634) (xy 289.738052 -311.320509) (xy 289.705417 -311.283672)
			(xy 289.679114 -311.242076) (xy 289.659823 -311.1968) (xy 289.648046 -311.149016) (xy 289.644086 -311.099962)
			(xy 289.327082 -311.099962) (xy 289.326578 -311.12567) (xy 289.318535 -311.176452) (xy 289.302647 -311.225351)
			(xy 289.279304 -311.271163) (xy 289.249083 -311.312759) (xy 289.212727 -311.349115) (xy 289.171131 -311.379336)
			(xy 289.125319 -311.402679) (xy 289.07642 -311.418567) (xy 289.025638 -311.42661) (xy 288.974222 -311.42661)
			(xy 288.92344 -311.418567) (xy 288.874541 -311.402679) (xy 288.828729 -311.379336) (xy 288.787133 -311.349115)
			(xy 288.750777 -311.312759) (xy 288.720556 -311.271163) (xy 288.697213 -311.225351) (xy 288.681325 -311.176452)
			(xy 288.673282 -311.12567) (xy 288.35435 -311.12567) (xy 288.346634 -311.173146) (xy 288.33105 -311.219827)
			(xy 288.308179 -311.263404) (xy 288.278614 -311.302748) (xy 288.243121 -311.33684) (xy 288.202618 -311.364796)
			(xy 288.158156 -311.385894) (xy 288.110885 -311.399586) (xy 288.06203 -311.405518) (xy 288.012855 -311.403537)
			(xy 287.964636 -311.393693) (xy 287.91862 -311.376241) (xy 287.875999 -311.351634) (xy 287.837878 -311.320509)
			(xy 287.805243 -311.283672) (xy 287.77894 -311.242076) (xy 287.759649 -311.1968) (xy 287.747872 -311.149016)
			(xy 287.743912 -311.099962) (xy 287.426908 -311.099962) (xy 287.426404 -311.12567) (xy 287.418361 -311.176452)
			(xy 287.402473 -311.225351) (xy 287.37913 -311.271163) (xy 287.348909 -311.312759) (xy 287.312553 -311.349115)
			(xy 287.270957 -311.379336) (xy 287.225145 -311.402679) (xy 287.176246 -311.418567) (xy 287.125464 -311.42661)
			(xy 287.074048 -311.42661) (xy 287.023266 -311.418567) (xy 286.974367 -311.402679) (xy 286.928555 -311.379336)
			(xy 286.886959 -311.349115) (xy 286.850603 -311.312759) (xy 286.820382 -311.271163) (xy 286.797039 -311.225351)
			(xy 286.781151 -311.176452) (xy 286.773108 -311.12567) (xy 286.45443 -311.12567) (xy 286.446714 -311.173146)
			(xy 286.43113 -311.219827) (xy 286.408259 -311.263404) (xy 286.378694 -311.302748) (xy 286.343201 -311.33684)
			(xy 286.302698 -311.364796) (xy 286.258236 -311.385894) (xy 286.210965 -311.399586) (xy 286.16211 -311.405518)
			(xy 286.112935 -311.403537) (xy 286.064716 -311.393693) (xy 286.0187 -311.376241) (xy 285.976079 -311.351634)
			(xy 285.937958 -311.320509) (xy 285.905323 -311.283672) (xy 285.87902 -311.242076) (xy 285.859729 -311.1968)
			(xy 285.847952 -311.149016) (xy 285.843992 -311.099962) (xy 285.526988 -311.099962) (xy 285.526484 -311.12567)
			(xy 285.518441 -311.176452) (xy 285.502553 -311.225351) (xy 285.47921 -311.271163) (xy 285.448989 -311.312759)
			(xy 285.412633 -311.349115) (xy 285.371037 -311.379336) (xy 285.325225 -311.402679) (xy 285.276326 -311.418567)
			(xy 285.225544 -311.42661) (xy 285.174128 -311.42661) (xy 285.123346 -311.418567) (xy 285.074447 -311.402679)
			(xy 285.028635 -311.379336) (xy 284.987039 -311.349115) (xy 284.950683 -311.312759) (xy 284.920462 -311.271163)
			(xy 284.897119 -311.225351) (xy 284.881231 -311.176452) (xy 284.873188 -311.12567) (xy 284.55451 -311.12567)
			(xy 284.546794 -311.173146) (xy 284.53121 -311.219827) (xy 284.508339 -311.263404) (xy 284.478774 -311.302748)
			(xy 284.443281 -311.33684) (xy 284.402778 -311.364796) (xy 284.358316 -311.385894) (xy 284.311045 -311.399586)
			(xy 284.26219 -311.405518) (xy 284.213015 -311.403537) (xy 284.164796 -311.393693) (xy 284.11878 -311.376241)
			(xy 284.076159 -311.351634) (xy 284.038038 -311.320509) (xy 284.005403 -311.283672) (xy 283.9791 -311.242076)
			(xy 283.959809 -311.1968) (xy 283.948032 -311.149016) (xy 283.944072 -311.099962) (xy 283.627068 -311.099962)
			(xy 283.626564 -311.12567) (xy 283.618521 -311.176452) (xy 283.602633 -311.225351) (xy 283.57929 -311.271163)
			(xy 283.549069 -311.312759) (xy 283.512713 -311.349115) (xy 283.471117 -311.379336) (xy 283.425305 -311.402679)
			(xy 283.376406 -311.418567) (xy 283.325624 -311.42661) (xy 283.274208 -311.42661) (xy 283.223426 -311.418567)
			(xy 283.174527 -311.402679) (xy 283.128715 -311.379336) (xy 283.087119 -311.349115) (xy 283.050763 -311.312759)
			(xy 283.020542 -311.271163) (xy 282.997199 -311.225351) (xy 282.981311 -311.176452) (xy 282.973268 -311.12567)
			(xy 282.654336 -311.12567) (xy 282.64662 -311.173146) (xy 282.631036 -311.219827) (xy 282.608165 -311.263404)
			(xy 282.5786 -311.302748) (xy 282.543107 -311.33684) (xy 282.502604 -311.364796) (xy 282.458142 -311.385894)
			(xy 282.410871 -311.399586) (xy 282.362016 -311.405518) (xy 282.312841 -311.403537) (xy 282.264622 -311.393693)
			(xy 282.218606 -311.376241) (xy 282.175985 -311.351634) (xy 282.137864 -311.320509) (xy 282.105229 -311.283672)
			(xy 282.078926 -311.242076) (xy 282.059635 -311.1968) (xy 282.047858 -311.149016) (xy 282.043898 -311.099962)
			(xy 281.726894 -311.099962) (xy 281.72639 -311.12567) (xy 281.718347 -311.176452) (xy 281.702459 -311.225351)
			(xy 281.679116 -311.271163) (xy 281.648895 -311.312759) (xy 281.612539 -311.349115) (xy 281.570943 -311.379336)
			(xy 281.525131 -311.402679) (xy 281.476232 -311.418567) (xy 281.42545 -311.42661) (xy 281.374034 -311.42661)
			(xy 281.323252 -311.418567) (xy 281.274353 -311.402679) (xy 281.228541 -311.379336) (xy 281.186945 -311.349115)
			(xy 281.150589 -311.312759) (xy 281.120368 -311.271163) (xy 281.097025 -311.225351) (xy 281.081137 -311.176452)
			(xy 281.073094 -311.12567) (xy 280.754416 -311.12567) (xy 280.7467 -311.173146) (xy 280.731116 -311.219827)
			(xy 280.708245 -311.263404) (xy 280.67868 -311.302748) (xy 280.643187 -311.33684) (xy 280.602684 -311.364796)
			(xy 280.558222 -311.385894) (xy 280.510951 -311.399586) (xy 280.462096 -311.405518) (xy 280.412921 -311.403537)
			(xy 280.364702 -311.393693) (xy 280.318686 -311.376241) (xy 280.276065 -311.351634) (xy 280.237944 -311.320509)
			(xy 280.205309 -311.283672) (xy 280.179006 -311.242076) (xy 280.159715 -311.1968) (xy 280.147938 -311.149016)
			(xy 280.143978 -311.099962) (xy 279.826974 -311.099962) (xy 279.82647 -311.12567) (xy 279.818427 -311.176452)
			(xy 279.802539 -311.225351) (xy 279.779196 -311.271163) (xy 279.748975 -311.312759) (xy 279.712619 -311.349115)
			(xy 279.671023 -311.379336) (xy 279.625211 -311.402679) (xy 279.576312 -311.418567) (xy 279.52553 -311.42661)
			(xy 279.474114 -311.42661) (xy 279.423332 -311.418567) (xy 279.374433 -311.402679) (xy 279.328621 -311.379336)
			(xy 279.287025 -311.349115) (xy 279.250669 -311.312759) (xy 279.220448 -311.271163) (xy 279.197105 -311.225351)
			(xy 279.181217 -311.176452) (xy 279.173174 -311.12567) (xy 278.854496 -311.12567) (xy 278.84678 -311.173146)
			(xy 278.831196 -311.219827) (xy 278.808325 -311.263404) (xy 278.77876 -311.302748) (xy 278.743267 -311.33684)
			(xy 278.702764 -311.364796) (xy 278.658302 -311.385894) (xy 278.611031 -311.399586) (xy 278.562176 -311.405518)
			(xy 278.513001 -311.403537) (xy 278.464782 -311.393693) (xy 278.418766 -311.376241) (xy 278.376145 -311.351634)
			(xy 278.338024 -311.320509) (xy 278.305389 -311.283672) (xy 278.279086 -311.242076) (xy 278.259795 -311.1968)
			(xy 278.248018 -311.149016) (xy 278.244058 -311.099962) (xy 277.927054 -311.099962) (xy 277.92655 -311.12567)
			(xy 277.918507 -311.176452) (xy 277.902619 -311.225351) (xy 277.879276 -311.271163) (xy 277.849055 -311.312759)
			(xy 277.812699 -311.349115) (xy 277.771103 -311.379336) (xy 277.725291 -311.402679) (xy 277.676392 -311.418567)
			(xy 277.62561 -311.42661) (xy 277.574194 -311.42661) (xy 277.523412 -311.418567) (xy 277.474513 -311.402679)
			(xy 277.428701 -311.379336) (xy 277.387105 -311.349115) (xy 277.350749 -311.312759) (xy 277.320528 -311.271163)
			(xy 277.297185 -311.225351) (xy 277.281297 -311.176452) (xy 277.273254 -311.12567) (xy 276.954322 -311.12567)
			(xy 276.946606 -311.173146) (xy 276.931022 -311.219827) (xy 276.908151 -311.263404) (xy 276.878586 -311.302748)
			(xy 276.843093 -311.33684) (xy 276.80259 -311.364796) (xy 276.758128 -311.385894) (xy 276.710857 -311.399586)
			(xy 276.662002 -311.405518) (xy 276.612827 -311.403537) (xy 276.564608 -311.393693) (xy 276.518592 -311.376241)
			(xy 276.475971 -311.351634) (xy 276.43785 -311.320509) (xy 276.405215 -311.283672) (xy 276.378912 -311.242076)
			(xy 276.359621 -311.1968) (xy 276.347844 -311.149016) (xy 276.343884 -311.099962) (xy 276.02688 -311.099962)
			(xy 276.026376 -311.12567) (xy 276.018333 -311.176452) (xy 276.002445 -311.225351) (xy 275.979102 -311.271163)
			(xy 275.948881 -311.312759) (xy 275.912525 -311.349115) (xy 275.870929 -311.379336) (xy 275.825117 -311.402679)
			(xy 275.776218 -311.418567) (xy 275.725436 -311.42661) (xy 275.67402 -311.42661) (xy 275.623238 -311.418567)
			(xy 275.574339 -311.402679) (xy 275.528527 -311.379336) (xy 275.486931 -311.349115) (xy 275.450575 -311.312759)
			(xy 275.420354 -311.271163) (xy 275.397011 -311.225351) (xy 275.381123 -311.176452) (xy 275.37308 -311.12567)
			(xy 275.054402 -311.12567) (xy 275.046686 -311.173146) (xy 275.031102 -311.219827) (xy 275.008231 -311.263404)
			(xy 274.978666 -311.302748) (xy 274.943173 -311.33684) (xy 274.90267 -311.364796) (xy 274.858208 -311.385894)
			(xy 274.810937 -311.399586) (xy 274.762082 -311.405518) (xy 274.712907 -311.403537) (xy 274.664688 -311.393693)
			(xy 274.618672 -311.376241) (xy 274.576051 -311.351634) (xy 274.53793 -311.320509) (xy 274.505295 -311.283672)
			(xy 274.478992 -311.242076) (xy 274.459701 -311.1968) (xy 274.447924 -311.149016) (xy 274.443964 -311.099962)
			(xy 274.12696 -311.099962) (xy 274.126456 -311.12567) (xy 274.118413 -311.176452) (xy 274.102525 -311.225351)
			(xy 274.079182 -311.271163) (xy 274.048961 -311.312759) (xy 274.012605 -311.349115) (xy 273.971009 -311.379336)
			(xy 273.925197 -311.402679) (xy 273.876298 -311.418567) (xy 273.825516 -311.42661) (xy 273.7741 -311.42661)
			(xy 273.723318 -311.418567) (xy 273.674419 -311.402679) (xy 273.628607 -311.379336) (xy 273.587011 -311.349115)
			(xy 273.550655 -311.312759) (xy 273.520434 -311.271163) (xy 273.497091 -311.225351) (xy 273.481203 -311.176452)
			(xy 273.47316 -311.12567) (xy 273.154482 -311.12567) (xy 273.146766 -311.173146) (xy 273.131182 -311.219827)
			(xy 273.108311 -311.263404) (xy 273.078746 -311.302748) (xy 273.043253 -311.33684) (xy 273.00275 -311.364796)
			(xy 272.958288 -311.385894) (xy 272.911017 -311.399586) (xy 272.862162 -311.405518) (xy 272.812987 -311.403537)
			(xy 272.764768 -311.393693) (xy 272.718752 -311.376241) (xy 272.676131 -311.351634) (xy 272.63801 -311.320509)
			(xy 272.605375 -311.283672) (xy 272.579072 -311.242076) (xy 272.559781 -311.1968) (xy 272.548004 -311.149016)
			(xy 272.544044 -311.099962) (xy 272.22704 -311.099962) (xy 272.226536 -311.12567) (xy 272.218493 -311.176452)
			(xy 272.202605 -311.225351) (xy 272.179262 -311.271163) (xy 272.149041 -311.312759) (xy 272.112685 -311.349115)
			(xy 272.071089 -311.379336) (xy 272.025277 -311.402679) (xy 271.976378 -311.418567) (xy 271.925596 -311.42661)
			(xy 271.87418 -311.42661) (xy 271.823398 -311.418567) (xy 271.774499 -311.402679) (xy 271.728687 -311.379336)
			(xy 271.687091 -311.349115) (xy 271.650735 -311.312759) (xy 271.620514 -311.271163) (xy 271.597171 -311.225351)
			(xy 271.581283 -311.176452) (xy 271.57324 -311.12567) (xy 271.254562 -311.12567) (xy 271.246846 -311.173146)
			(xy 271.231262 -311.219827) (xy 271.208391 -311.263404) (xy 271.178826 -311.302748) (xy 271.143333 -311.33684)
			(xy 271.10283 -311.364796) (xy 271.058368 -311.385894) (xy 271.011097 -311.399586) (xy 270.962242 -311.405518)
			(xy 270.913067 -311.403537) (xy 270.864848 -311.393693) (xy 270.818832 -311.376241) (xy 270.776211 -311.351634)
			(xy 270.73809 -311.320509) (xy 270.705455 -311.283672) (xy 270.679152 -311.242076) (xy 270.659861 -311.1968)
			(xy 270.648084 -311.149016) (xy 270.644124 -311.099962) (xy 270.305022 -311.099962) (xy 270.304527 -311.124569)
			(xy 270.296632 -311.173146) (xy 270.281048 -311.219827) (xy 270.258177 -311.263404) (xy 270.228612 -311.302748)
			(xy 270.193119 -311.33684) (xy 270.152616 -311.364796) (xy 270.108154 -311.385894) (xy 270.060883 -311.399586)
			(xy 270.012028 -311.405518) (xy 269.962853 -311.403537) (xy 269.914634 -311.393693) (xy 269.868618 -311.376241)
			(xy 269.825997 -311.351634) (xy 269.787876 -311.320509) (xy 269.755241 -311.283672) (xy 269.728938 -311.242076)
			(xy 269.709647 -311.1968) (xy 269.69787 -311.149016) (xy 269.69391 -311.099962) (xy 269.355062 -311.099962)
			(xy 269.354567 -311.124569) (xy 269.346672 -311.173146) (xy 269.331088 -311.219827) (xy 269.308217 -311.263404)
			(xy 269.278652 -311.302748) (xy 269.243159 -311.33684) (xy 269.202656 -311.364796) (xy 269.158194 -311.385894)
			(xy 269.110923 -311.399586) (xy 269.062068 -311.405518) (xy 269.012893 -311.403537) (xy 268.964674 -311.393693)
			(xy 268.918658 -311.376241) (xy 268.876037 -311.351634) (xy 268.837916 -311.320509) (xy 268.805281 -311.283672)
			(xy 268.778978 -311.242076) (xy 268.759687 -311.1968) (xy 268.74791 -311.149016) (xy 268.74395 -311.099962)
			(xy 267.226092 -311.099962) (xy 267.211581 -311.149382) (xy 267.188939 -311.198959) (xy 267.159473 -311.244809)
			(xy 267.123782 -311.286) (xy 267.082591 -311.321691) (xy 267.036741 -311.351157) (xy 266.987164 -311.373799)
			(xy 266.934869 -311.389154) (xy 266.880921 -311.39691) (xy 266.826419 -311.39691) (xy 266.772471 -311.389154)
			(xy 266.720176 -311.373799) (xy 266.670599 -311.351157) (xy 266.624749 -311.321691) (xy 266.583558 -311.286)
			(xy 266.547867 -311.244809) (xy 266.518401 -311.198959) (xy 266.495759 -311.149382) (xy 266.480404 -311.097087)
			(xy 266.472648 -311.043139) (xy 266.472162 -311.015888) (xy 266.472669 -310.987113) (xy 266.481326 -310.930219)
			(xy 266.498427 -310.875269) (xy 266.523584 -310.823509) (xy 266.556227 -310.776113) (xy 266.57554 -310.754776)
			(xy 266.584808 -310.744144) (xy 266.597733 -310.719093) (xy 266.603308 -310.691461) (xy 266.601106 -310.663358)
			(xy 266.591296 -310.636931) (xy 266.574626 -310.614199) (xy 266.552371 -310.596898) (xy 266.539472 -310.5912)
			(xy 266.513381 -310.58016) (xy 266.46456 -310.551418) (xy 266.420525 -310.515774) (xy 266.382244 -310.47401)
			(xy 266.350559 -310.427046) (xy 266.326165 -310.375913) (xy 266.3096 -310.321736) (xy 266.301227 -310.265705)
			(xy 266.300712 -310.237378) (xy 261.929168 -310.237378) (xy 261.925249 -310.250403) (xy 261.901577 -310.3009)
			(xy 261.870804 -310.347413) (xy 261.833587 -310.38895) (xy 261.790719 -310.424625) (xy 261.743113 -310.453679)
			(xy 261.691784 -310.475491) (xy 261.637827 -310.489597) (xy 261.58239 -310.495697) (xy 261.526656 -310.49366)
			(xy 261.471813 -310.48353) (xy 261.419029 -310.465523) (xy 261.369429 -310.440022) (xy 261.324071 -310.407571)
			(xy 261.283922 -310.368862) (xy 261.249836 -310.324719) (xy 261.22254 -310.276084) (xy 261.202617 -310.223993)
			(xy 261.190491 -310.169556) (xy 261.18642 -310.113934) (xy 255.945132 -310.113934) (xy 255.945132 -310.832246)
			(xy 260.467854 -310.832246) (xy 260.471925 -310.776624) (xy 260.484051 -310.722187) (xy 260.503974 -310.670096)
			(xy 260.53127 -310.621461) (xy 260.565356 -310.577318) (xy 260.605505 -310.538609) (xy 260.650863 -310.506158)
			(xy 260.700463 -310.480657) (xy 260.753247 -310.46265) (xy 260.80809 -310.45252) (xy 260.863824 -310.450483)
			(xy 260.919261 -310.456583) (xy 260.973218 -310.470689) (xy 261.024547 -310.492501) (xy 261.072153 -310.521555)
			(xy 261.115021 -310.55723) (xy 261.152238 -310.598767) (xy 261.183011 -310.64528) (xy 261.206683 -310.695777)
			(xy 261.222751 -310.749184) (xy 261.230871 -310.80436) (xy 261.23138 -310.832246) (xy 261.230871 -310.860132)
			(xy 261.222751 -310.915308) (xy 261.206683 -310.968715) (xy 261.183011 -311.019212) (xy 261.152238 -311.065725)
			(xy 261.115021 -311.107262) (xy 261.072153 -311.142937) (xy 261.024547 -311.171991) (xy 260.973218 -311.193803)
			(xy 260.919261 -311.207909) (xy 260.863824 -311.214009) (xy 260.80809 -311.211972) (xy 260.753247 -311.201842)
			(xy 260.700463 -311.183835) (xy 260.650863 -311.158334) (xy 260.605505 -311.125883) (xy 260.565356 -311.087174)
			(xy 260.53127 -311.043031) (xy 260.503974 -310.994396) (xy 260.484051 -310.942305) (xy 260.471925 -310.887868)
			(xy 260.467854 -310.832246) (xy 255.945132 -310.832246) (xy 255.945132 -311.7342) (xy 264.689334 -311.7342)
			(xy 264.693405 -311.678578) (xy 264.705531 -311.624141) (xy 264.725454 -311.57205) (xy 264.75275 -311.523415)
			(xy 264.786836 -311.479272) (xy 264.826985 -311.440563) (xy 264.872343 -311.408112) (xy 264.921943 -311.382611)
			(xy 264.974727 -311.364604) (xy 265.02957 -311.354474) (xy 265.085304 -311.352437) (xy 265.140741 -311.358537)
			(xy 265.194698 -311.372643) (xy 265.246027 -311.394455) (xy 265.293633 -311.423509) (xy 265.336501 -311.459184)
			(xy 265.373718 -311.500721) (xy 265.404491 -311.547234) (xy 265.428163 -311.597731) (xy 265.444231 -311.651138)
			(xy 265.452351 -311.706314) (xy 265.45286 -311.7342) (xy 265.452351 -311.762086) (xy 265.444231 -311.817262)
			(xy 265.428163 -311.870669) (xy 265.404491 -311.921166) (xy 265.373718 -311.967679) (xy 265.336501 -312.009216)
			(xy 265.293633 -312.044891) (xy 265.246027 -312.073945) (xy 265.194698 -312.095757) (xy 265.140741 -312.109863)
			(xy 265.085304 -312.115963) (xy 265.02957 -312.113926) (xy 264.974727 -312.103796) (xy 264.921943 -312.085789)
			(xy 264.872343 -312.060288) (xy 264.826985 -312.027837) (xy 264.786836 -311.989128) (xy 264.75275 -311.944985)
			(xy 264.725454 -311.89635) (xy 264.705531 -311.844259) (xy 264.693405 -311.789822) (xy 264.689334 -311.7342)
			(xy 255.945132 -311.7342) (xy 255.945132 -312.523378) (xy 263.931906 -312.523378) (xy 263.935977 -312.467756)
			(xy 263.948103 -312.413319) (xy 263.968026 -312.361228) (xy 263.995322 -312.312593) (xy 264.029408 -312.26845)
			(xy 264.069557 -312.229741) (xy 264.114915 -312.19729) (xy 264.164515 -312.171789) (xy 264.217299 -312.153782)
			(xy 264.272142 -312.143652) (xy 264.327876 -312.141615) (xy 264.383313 -312.147715) (xy 264.43727 -312.161821)
			(xy 264.488599 -312.183633) (xy 264.536205 -312.212687) (xy 264.579073 -312.248362) (xy 264.596765 -312.268108)
			(xy 266.259562 -312.268108) (xy 266.263633 -312.212486) (xy 266.275759 -312.158049) (xy 266.295682 -312.105958)
			(xy 266.322978 -312.057323) (xy 266.357064 -312.01318) (xy 266.397213 -311.974471) (xy 266.442571 -311.94202)
			(xy 266.492171 -311.916519) (xy 266.544955 -311.898512) (xy 266.599798 -311.888382) (xy 266.655532 -311.886345)
			(xy 266.710969 -311.892445) (xy 266.764926 -311.906551) (xy 266.816255 -311.928363) (xy 266.863861 -311.957417)
			(xy 266.906729 -311.993092) (xy 266.943946 -312.034629) (xy 266.953896 -312.049668) (xy 267.793736 -312.049668)
			(xy 267.797696 -312.000614) (xy 267.809473 -311.95283) (xy 267.828764 -311.907554) (xy 267.855067 -311.865958)
			(xy 267.887702 -311.829121) (xy 267.925823 -311.797996) (xy 267.968444 -311.773389) (xy 268.01446 -311.755937)
			(xy 268.062679 -311.746093) (xy 268.111854 -311.744112) (xy 268.160709 -311.750044) (xy 268.20798 -311.763736)
			(xy 268.252442 -311.784834) (xy 268.292945 -311.81279) (xy 268.328438 -311.846882) (xy 268.358003 -311.886226)
			(xy 268.380874 -311.929803) (xy 268.396458 -311.976484) (xy 268.404353 -312.025061) (xy 268.404848 -312.049668)
			(xy 268.404353 -312.074275) (xy 268.404133 -312.07563) (xy 268.723106 -312.07563) (xy 268.723106 -312.024214)
			(xy 268.731149 -311.973432) (xy 268.747037 -311.924533) (xy 268.77038 -311.878721) (xy 268.800601 -311.837125)
			(xy 268.836957 -311.800769) (xy 268.878553 -311.770548) (xy 268.924365 -311.747205) (xy 268.973264 -311.731317)
			(xy 269.024046 -311.723274) (xy 269.075462 -311.723274) (xy 269.126244 -311.731317) (xy 269.175143 -311.747205)
			(xy 269.220955 -311.770548) (xy 269.262551 -311.800769) (xy 269.298907 -311.837125) (xy 269.329128 -311.878721)
			(xy 269.352471 -311.924533) (xy 269.368359 -311.973432) (xy 269.376402 -312.024214) (xy 269.376906 -312.049922)
			(xy 269.376402 -312.07563) (xy 269.673066 -312.07563) (xy 269.673066 -312.024214) (xy 269.681109 -311.973432)
			(xy 269.696997 -311.924533) (xy 269.72034 -311.878721) (xy 269.750561 -311.837125) (xy 269.786917 -311.800769)
			(xy 269.828513 -311.770548) (xy 269.874325 -311.747205) (xy 269.923224 -311.731317) (xy 269.974006 -311.723274)
			(xy 270.025422 -311.723274) (xy 270.076204 -311.731317) (xy 270.125103 -311.747205) (xy 270.170915 -311.770548)
			(xy 270.212511 -311.800769) (xy 270.248867 -311.837125) (xy 270.279088 -311.878721) (xy 270.302431 -311.924533)
			(xy 270.318319 -311.973432) (xy 270.326362 -312.024214) (xy 270.326866 -312.049922) (xy 270.644124 -312.049922)
			(xy 270.648084 -312.000868) (xy 270.659861 -311.953084) (xy 270.679152 -311.907808) (xy 270.705455 -311.866212)
			(xy 270.73809 -311.829375) (xy 270.776211 -311.79825) (xy 270.818832 -311.773643) (xy 270.864848 -311.756191)
			(xy 270.913067 -311.746347) (xy 270.962242 -311.744366) (xy 271.011097 -311.750298) (xy 271.058368 -311.76399)
			(xy 271.10283 -311.785088) (xy 271.143333 -311.813044) (xy 271.178826 -311.847136) (xy 271.208391 -311.88648)
			(xy 271.231262 -311.930057) (xy 271.246846 -311.976738) (xy 271.254741 -312.025315) (xy 271.255236 -312.049922)
			(xy 271.254741 -312.074529) (xy 271.254562 -312.07563) (xy 271.57324 -312.07563) (xy 271.57324 -312.024214)
			(xy 271.581283 -311.973432) (xy 271.597171 -311.924533) (xy 271.620514 -311.878721) (xy 271.650735 -311.837125)
			(xy 271.687091 -311.800769) (xy 271.728687 -311.770548) (xy 271.774499 -311.747205) (xy 271.823398 -311.731317)
			(xy 271.87418 -311.723274) (xy 271.925596 -311.723274) (xy 271.976378 -311.731317) (xy 272.025277 -311.747205)
			(xy 272.071089 -311.770548) (xy 272.112685 -311.800769) (xy 272.149041 -311.837125) (xy 272.179262 -311.878721)
			(xy 272.202605 -311.924533) (xy 272.218493 -311.973432) (xy 272.226536 -312.024214) (xy 272.22704 -312.049922)
			(xy 272.544044 -312.049922) (xy 272.548004 -312.000868) (xy 272.559781 -311.953084) (xy 272.579072 -311.907808)
			(xy 272.605375 -311.866212) (xy 272.63801 -311.829375) (xy 272.676131 -311.79825) (xy 272.718752 -311.773643)
			(xy 272.764768 -311.756191) (xy 272.812987 -311.746347) (xy 272.862162 -311.744366) (xy 272.911017 -311.750298)
			(xy 272.958288 -311.76399) (xy 273.00275 -311.785088) (xy 273.043253 -311.813044) (xy 273.078746 -311.847136)
			(xy 273.108311 -311.88648) (xy 273.131182 -311.930057) (xy 273.146766 -311.976738) (xy 273.154661 -312.025315)
			(xy 273.155156 -312.049922) (xy 273.154661 -312.074529) (xy 273.154482 -312.07563) (xy 273.47316 -312.07563)
			(xy 273.47316 -312.024214) (xy 273.481203 -311.973432) (xy 273.497091 -311.924533) (xy 273.520434 -311.878721)
			(xy 273.550655 -311.837125) (xy 273.587011 -311.800769) (xy 273.628607 -311.770548) (xy 273.674419 -311.747205)
			(xy 273.723318 -311.731317) (xy 273.7741 -311.723274) (xy 273.825516 -311.723274) (xy 273.876298 -311.731317)
			(xy 273.925197 -311.747205) (xy 273.971009 -311.770548) (xy 274.012605 -311.800769) (xy 274.048961 -311.837125)
			(xy 274.079182 -311.878721) (xy 274.102525 -311.924533) (xy 274.118413 -311.973432) (xy 274.126456 -312.024214)
			(xy 274.12696 -312.049922) (xy 274.443964 -312.049922) (xy 274.447924 -312.000868) (xy 274.459701 -311.953084)
			(xy 274.478992 -311.907808) (xy 274.505295 -311.866212) (xy 274.53793 -311.829375) (xy 274.576051 -311.79825)
			(xy 274.618672 -311.773643) (xy 274.664688 -311.756191) (xy 274.712907 -311.746347) (xy 274.762082 -311.744366)
			(xy 274.810937 -311.750298) (xy 274.858208 -311.76399) (xy 274.90267 -311.785088) (xy 274.943173 -311.813044)
			(xy 274.978666 -311.847136) (xy 275.008231 -311.88648) (xy 275.031102 -311.930057) (xy 275.046686 -311.976738)
			(xy 275.054581 -312.025315) (xy 275.055076 -312.049922) (xy 275.054581 -312.074529) (xy 275.054402 -312.07563)
			(xy 275.37308 -312.07563) (xy 275.37308 -312.024214) (xy 275.381123 -311.973432) (xy 275.397011 -311.924533)
			(xy 275.420354 -311.878721) (xy 275.450575 -311.837125) (xy 275.486931 -311.800769) (xy 275.528527 -311.770548)
			(xy 275.574339 -311.747205) (xy 275.623238 -311.731317) (xy 275.67402 -311.723274) (xy 275.725436 -311.723274)
			(xy 275.776218 -311.731317) (xy 275.825117 -311.747205) (xy 275.870929 -311.770548) (xy 275.912525 -311.800769)
			(xy 275.948881 -311.837125) (xy 275.979102 -311.878721) (xy 276.002445 -311.924533) (xy 276.018333 -311.973432)
			(xy 276.026376 -312.024214) (xy 276.02688 -312.049922) (xy 276.343884 -312.049922) (xy 276.347844 -312.000868)
			(xy 276.359621 -311.953084) (xy 276.378912 -311.907808) (xy 276.405215 -311.866212) (xy 276.43785 -311.829375)
			(xy 276.475971 -311.79825) (xy 276.518592 -311.773643) (xy 276.564608 -311.756191) (xy 276.612827 -311.746347)
			(xy 276.662002 -311.744366) (xy 276.710857 -311.750298) (xy 276.758128 -311.76399) (xy 276.80259 -311.785088)
			(xy 276.843093 -311.813044) (xy 276.878586 -311.847136) (xy 276.908151 -311.88648) (xy 276.931022 -311.930057)
			(xy 276.946606 -311.976738) (xy 276.954501 -312.025315) (xy 276.954996 -312.049922) (xy 276.954501 -312.074529)
			(xy 276.954322 -312.07563) (xy 277.273254 -312.07563) (xy 277.273254 -312.024214) (xy 277.281297 -311.973432)
			(xy 277.297185 -311.924533) (xy 277.320528 -311.878721) (xy 277.350749 -311.837125) (xy 277.387105 -311.800769)
			(xy 277.428701 -311.770548) (xy 277.474513 -311.747205) (xy 277.523412 -311.731317) (xy 277.574194 -311.723274)
			(xy 277.62561 -311.723274) (xy 277.676392 -311.731317) (xy 277.725291 -311.747205) (xy 277.771103 -311.770548)
			(xy 277.812699 -311.800769) (xy 277.849055 -311.837125) (xy 277.879276 -311.878721) (xy 277.902619 -311.924533)
			(xy 277.918507 -311.973432) (xy 277.92655 -312.024214) (xy 277.927054 -312.049922) (xy 278.244058 -312.049922)
			(xy 278.248018 -312.000868) (xy 278.259795 -311.953084) (xy 278.279086 -311.907808) (xy 278.305389 -311.866212)
			(xy 278.338024 -311.829375) (xy 278.376145 -311.79825) (xy 278.418766 -311.773643) (xy 278.464782 -311.756191)
			(xy 278.513001 -311.746347) (xy 278.562176 -311.744366) (xy 278.611031 -311.750298) (xy 278.658302 -311.76399)
			(xy 278.702764 -311.785088) (xy 278.743267 -311.813044) (xy 278.77876 -311.847136) (xy 278.808325 -311.88648)
			(xy 278.831196 -311.930057) (xy 278.84678 -311.976738) (xy 278.854675 -312.025315) (xy 278.85517 -312.049922)
			(xy 278.854675 -312.074529) (xy 278.854496 -312.07563) (xy 279.173174 -312.07563) (xy 279.173174 -312.024214)
			(xy 279.181217 -311.973432) (xy 279.197105 -311.924533) (xy 279.220448 -311.878721) (xy 279.250669 -311.837125)
			(xy 279.287025 -311.800769) (xy 279.328621 -311.770548) (xy 279.374433 -311.747205) (xy 279.423332 -311.731317)
			(xy 279.474114 -311.723274) (xy 279.52553 -311.723274) (xy 279.576312 -311.731317) (xy 279.625211 -311.747205)
			(xy 279.671023 -311.770548) (xy 279.712619 -311.800769) (xy 279.748975 -311.837125) (xy 279.779196 -311.878721)
			(xy 279.802539 -311.924533) (xy 279.818427 -311.973432) (xy 279.82647 -312.024214) (xy 279.826974 -312.049922)
			(xy 280.143978 -312.049922) (xy 280.147938 -312.000868) (xy 280.159715 -311.953084) (xy 280.179006 -311.907808)
			(xy 280.205309 -311.866212) (xy 280.237944 -311.829375) (xy 280.276065 -311.79825) (xy 280.318686 -311.773643)
			(xy 280.364702 -311.756191) (xy 280.412921 -311.746347) (xy 280.462096 -311.744366) (xy 280.510951 -311.750298)
			(xy 280.558222 -311.76399) (xy 280.602684 -311.785088) (xy 280.643187 -311.813044) (xy 280.67868 -311.847136)
			(xy 280.708245 -311.88648) (xy 280.731116 -311.930057) (xy 280.7467 -311.976738) (xy 280.754595 -312.025315)
			(xy 280.75509 -312.049922) (xy 280.754595 -312.074529) (xy 280.754416 -312.07563) (xy 281.073094 -312.07563)
			(xy 281.073094 -312.024214) (xy 281.081137 -311.973432) (xy 281.097025 -311.924533) (xy 281.120368 -311.878721)
			(xy 281.150589 -311.837125) (xy 281.186945 -311.800769) (xy 281.228541 -311.770548) (xy 281.274353 -311.747205)
			(xy 281.323252 -311.731317) (xy 281.374034 -311.723274) (xy 281.42545 -311.723274) (xy 281.476232 -311.731317)
			(xy 281.525131 -311.747205) (xy 281.570943 -311.770548) (xy 281.612539 -311.800769) (xy 281.648895 -311.837125)
			(xy 281.679116 -311.878721) (xy 281.702459 -311.924533) (xy 281.718347 -311.973432) (xy 281.72639 -312.024214)
			(xy 281.726894 -312.049922) (xy 282.043898 -312.049922) (xy 282.047858 -312.000868) (xy 282.059635 -311.953084)
			(xy 282.078926 -311.907808) (xy 282.105229 -311.866212) (xy 282.137864 -311.829375) (xy 282.175985 -311.79825)
			(xy 282.218606 -311.773643) (xy 282.264622 -311.756191) (xy 282.312841 -311.746347) (xy 282.362016 -311.744366)
			(xy 282.410871 -311.750298) (xy 282.458142 -311.76399) (xy 282.502604 -311.785088) (xy 282.543107 -311.813044)
			(xy 282.5786 -311.847136) (xy 282.608165 -311.88648) (xy 282.631036 -311.930057) (xy 282.64662 -311.976738)
			(xy 282.654515 -312.025315) (xy 282.65501 -312.049922) (xy 282.654515 -312.074529) (xy 282.654336 -312.07563)
			(xy 282.973268 -312.07563) (xy 282.973268 -312.024214) (xy 282.981311 -311.973432) (xy 282.997199 -311.924533)
			(xy 283.020542 -311.878721) (xy 283.050763 -311.837125) (xy 283.087119 -311.800769) (xy 283.128715 -311.770548)
			(xy 283.174527 -311.747205) (xy 283.223426 -311.731317) (xy 283.274208 -311.723274) (xy 283.325624 -311.723274)
			(xy 283.376406 -311.731317) (xy 283.425305 -311.747205) (xy 283.471117 -311.770548) (xy 283.512713 -311.800769)
			(xy 283.549069 -311.837125) (xy 283.57929 -311.878721) (xy 283.602633 -311.924533) (xy 283.618521 -311.973432)
			(xy 283.626564 -312.024214) (xy 283.627068 -312.049922) (xy 283.944072 -312.049922) (xy 283.948032 -312.000868)
			(xy 283.959809 -311.953084) (xy 283.9791 -311.907808) (xy 284.005403 -311.866212) (xy 284.038038 -311.829375)
			(xy 284.076159 -311.79825) (xy 284.11878 -311.773643) (xy 284.164796 -311.756191) (xy 284.213015 -311.746347)
			(xy 284.26219 -311.744366) (xy 284.311045 -311.750298) (xy 284.358316 -311.76399) (xy 284.402778 -311.785088)
			(xy 284.443281 -311.813044) (xy 284.478774 -311.847136) (xy 284.508339 -311.88648) (xy 284.53121 -311.930057)
			(xy 284.546794 -311.976738) (xy 284.554689 -312.025315) (xy 284.555184 -312.049922) (xy 284.554689 -312.074529)
			(xy 284.55451 -312.07563) (xy 284.873188 -312.07563) (xy 284.873188 -312.024214) (xy 284.881231 -311.973432)
			(xy 284.897119 -311.924533) (xy 284.920462 -311.878721) (xy 284.950683 -311.837125) (xy 284.987039 -311.800769)
			(xy 285.028635 -311.770548) (xy 285.074447 -311.747205) (xy 285.123346 -311.731317) (xy 285.174128 -311.723274)
			(xy 285.225544 -311.723274) (xy 285.276326 -311.731317) (xy 285.325225 -311.747205) (xy 285.371037 -311.770548)
			(xy 285.412633 -311.800769) (xy 285.448989 -311.837125) (xy 285.47921 -311.878721) (xy 285.502553 -311.924533)
			(xy 285.518441 -311.973432) (xy 285.526484 -312.024214) (xy 285.526988 -312.049922) (xy 285.843992 -312.049922)
			(xy 285.847952 -312.000868) (xy 285.859729 -311.953084) (xy 285.87902 -311.907808) (xy 285.905323 -311.866212)
			(xy 285.937958 -311.829375) (xy 285.976079 -311.79825) (xy 286.0187 -311.773643) (xy 286.064716 -311.756191)
			(xy 286.112935 -311.746347) (xy 286.16211 -311.744366) (xy 286.210965 -311.750298) (xy 286.258236 -311.76399)
			(xy 286.302698 -311.785088) (xy 286.343201 -311.813044) (xy 286.378694 -311.847136) (xy 286.408259 -311.88648)
			(xy 286.43113 -311.930057) (xy 286.446714 -311.976738) (xy 286.454609 -312.025315) (xy 286.455104 -312.049922)
			(xy 286.454609 -312.074529) (xy 286.45443 -312.07563) (xy 286.773108 -312.07563) (xy 286.773108 -312.024214)
			(xy 286.781151 -311.973432) (xy 286.797039 -311.924533) (xy 286.820382 -311.878721) (xy 286.850603 -311.837125)
			(xy 286.886959 -311.800769) (xy 286.928555 -311.770548) (xy 286.974367 -311.747205) (xy 287.023266 -311.731317)
			(xy 287.074048 -311.723274) (xy 287.125464 -311.723274) (xy 287.176246 -311.731317) (xy 287.225145 -311.747205)
			(xy 287.270957 -311.770548) (xy 287.312553 -311.800769) (xy 287.348909 -311.837125) (xy 287.37913 -311.878721)
			(xy 287.402473 -311.924533) (xy 287.418361 -311.973432) (xy 287.426404 -312.024214) (xy 287.426908 -312.049922)
			(xy 287.743912 -312.049922) (xy 287.747872 -312.000868) (xy 287.759649 -311.953084) (xy 287.77894 -311.907808)
			(xy 287.805243 -311.866212) (xy 287.837878 -311.829375) (xy 287.875999 -311.79825) (xy 287.91862 -311.773643)
			(xy 287.964636 -311.756191) (xy 288.012855 -311.746347) (xy 288.06203 -311.744366) (xy 288.110885 -311.750298)
			(xy 288.158156 -311.76399) (xy 288.202618 -311.785088) (xy 288.243121 -311.813044) (xy 288.278614 -311.847136)
			(xy 288.308179 -311.88648) (xy 288.33105 -311.930057) (xy 288.346634 -311.976738) (xy 288.354529 -312.025315)
			(xy 288.355024 -312.049922) (xy 288.354529 -312.074529) (xy 288.35435 -312.07563) (xy 288.673282 -312.07563)
			(xy 288.673282 -312.024214) (xy 288.681325 -311.973432) (xy 288.697213 -311.924533) (xy 288.720556 -311.878721)
			(xy 288.750777 -311.837125) (xy 288.787133 -311.800769) (xy 288.828729 -311.770548) (xy 288.874541 -311.747205)
			(xy 288.92344 -311.731317) (xy 288.974222 -311.723274) (xy 289.025638 -311.723274) (xy 289.07642 -311.731317)
			(xy 289.125319 -311.747205) (xy 289.171131 -311.770548) (xy 289.212727 -311.800769) (xy 289.249083 -311.837125)
			(xy 289.279304 -311.878721) (xy 289.302647 -311.924533) (xy 289.318535 -311.973432) (xy 289.326578 -312.024214)
			(xy 289.327082 -312.049922) (xy 289.644086 -312.049922) (xy 289.648046 -312.000868) (xy 289.659823 -311.953084)
			(xy 289.679114 -311.907808) (xy 289.705417 -311.866212) (xy 289.738052 -311.829375) (xy 289.776173 -311.79825)
			(xy 289.818794 -311.773643) (xy 289.86481 -311.756191) (xy 289.913029 -311.746347) (xy 289.962204 -311.744366)
			(xy 290.011059 -311.750298) (xy 290.05833 -311.76399) (xy 290.102792 -311.785088) (xy 290.143295 -311.813044)
			(xy 290.178788 -311.847136) (xy 290.208353 -311.88648) (xy 290.231224 -311.930057) (xy 290.246808 -311.976738)
			(xy 290.254703 -312.025315) (xy 290.255198 -312.049922) (xy 290.254703 -312.074529) (xy 290.254524 -312.07563)
			(xy 290.573202 -312.07563) (xy 290.573202 -312.024214) (xy 290.581245 -311.973432) (xy 290.597133 -311.924533)
			(xy 290.620476 -311.878721) (xy 290.650697 -311.837125) (xy 290.687053 -311.800769) (xy 290.728649 -311.770548)
			(xy 290.774461 -311.747205) (xy 290.82336 -311.731317) (xy 290.874142 -311.723274) (xy 290.925558 -311.723274)
			(xy 290.97634 -311.731317) (xy 291.025239 -311.747205) (xy 291.071051 -311.770548) (xy 291.112647 -311.800769)
			(xy 291.149003 -311.837125) (xy 291.179224 -311.878721) (xy 291.202567 -311.924533) (xy 291.218455 -311.973432)
			(xy 291.226498 -312.024214) (xy 291.227002 -312.049922) (xy 291.544006 -312.049922) (xy 291.547966 -312.000868)
			(xy 291.559743 -311.953084) (xy 291.579034 -311.907808) (xy 291.605337 -311.866212) (xy 291.637972 -311.829375)
			(xy 291.676093 -311.79825) (xy 291.718714 -311.773643) (xy 291.76473 -311.756191) (xy 291.812949 -311.746347)
			(xy 291.862124 -311.744366) (xy 291.910979 -311.750298) (xy 291.95825 -311.76399) (xy 292.002712 -311.785088)
			(xy 292.043215 -311.813044) (xy 292.078708 -311.847136) (xy 292.108273 -311.88648) (xy 292.131144 -311.930057)
			(xy 292.146728 -311.976738) (xy 292.154623 -312.025315) (xy 292.155118 -312.049922) (xy 292.154623 -312.074529)
			(xy 292.154444 -312.07563) (xy 292.473122 -312.07563) (xy 292.473122 -312.024214) (xy 292.481165 -311.973432)
			(xy 292.497053 -311.924533) (xy 292.520396 -311.878721) (xy 292.550617 -311.837125) (xy 292.586973 -311.800769)
			(xy 292.628569 -311.770548) (xy 292.674381 -311.747205) (xy 292.72328 -311.731317) (xy 292.774062 -311.723274)
			(xy 292.825478 -311.723274) (xy 292.87626 -311.731317) (xy 292.925159 -311.747205) (xy 292.970971 -311.770548)
			(xy 293.012567 -311.800769) (xy 293.048923 -311.837125) (xy 293.079144 -311.878721) (xy 293.102487 -311.924533)
			(xy 293.118375 -311.973432) (xy 293.126418 -312.024214) (xy 293.126922 -312.049922) (xy 293.443926 -312.049922)
			(xy 293.447886 -312.000868) (xy 293.459663 -311.953084) (xy 293.478954 -311.907808) (xy 293.505257 -311.866212)
			(xy 293.537892 -311.829375) (xy 293.576013 -311.79825) (xy 293.618634 -311.773643) (xy 293.66465 -311.756191)
			(xy 293.712869 -311.746347) (xy 293.762044 -311.744366) (xy 293.810899 -311.750298) (xy 293.85817 -311.76399)
			(xy 293.902632 -311.785088) (xy 293.943135 -311.813044) (xy 293.978628 -311.847136) (xy 294.008193 -311.88648)
			(xy 294.031064 -311.930057) (xy 294.046648 -311.976738) (xy 294.054543 -312.025315) (xy 294.055038 -312.049922)
			(xy 294.054543 -312.074529) (xy 294.054364 -312.07563) (xy 294.373042 -312.07563) (xy 294.373042 -312.024214)
			(xy 294.381085 -311.973432) (xy 294.396973 -311.924533) (xy 294.420316 -311.878721) (xy 294.450537 -311.837125)
			(xy 294.486893 -311.800769) (xy 294.528489 -311.770548) (xy 294.574301 -311.747205) (xy 294.6232 -311.731317)
			(xy 294.673982 -311.723274) (xy 294.725398 -311.723274) (xy 294.77618 -311.731317) (xy 294.825079 -311.747205)
			(xy 294.870891 -311.770548) (xy 294.912487 -311.800769) (xy 294.948843 -311.837125) (xy 294.979064 -311.878721)
			(xy 295.002407 -311.924533) (xy 295.018295 -311.973432) (xy 295.026338 -312.024214) (xy 295.026842 -312.049922)
			(xy 295.3441 -312.049922) (xy 295.34806 -312.000868) (xy 295.359837 -311.953084) (xy 295.379128 -311.907808)
			(xy 295.405431 -311.866212) (xy 295.438066 -311.829375) (xy 295.476187 -311.79825) (xy 295.518808 -311.773643)
			(xy 295.564824 -311.756191) (xy 295.613043 -311.746347) (xy 295.662218 -311.744366) (xy 295.711073 -311.750298)
			(xy 295.758344 -311.76399) (xy 295.802806 -311.785088) (xy 295.843309 -311.813044) (xy 295.878802 -311.847136)
			(xy 295.908367 -311.88648) (xy 295.931238 -311.930057) (xy 295.946822 -311.976738) (xy 295.954717 -312.025315)
			(xy 295.955212 -312.049922) (xy 295.954717 -312.074529) (xy 295.954538 -312.07563) (xy 296.273216 -312.07563)
			(xy 296.273216 -312.024214) (xy 296.281259 -311.973432) (xy 296.297147 -311.924533) (xy 296.32049 -311.878721)
			(xy 296.350711 -311.837125) (xy 296.387067 -311.800769) (xy 296.428663 -311.770548) (xy 296.474475 -311.747205)
			(xy 296.523374 -311.731317) (xy 296.574156 -311.723274) (xy 296.625572 -311.723274) (xy 296.676354 -311.731317)
			(xy 296.725253 -311.747205) (xy 296.771065 -311.770548) (xy 296.812661 -311.800769) (xy 296.849017 -311.837125)
			(xy 296.879238 -311.878721) (xy 296.902581 -311.924533) (xy 296.918469 -311.973432) (xy 296.926512 -312.024214)
			(xy 296.927016 -312.049922) (xy 297.24402 -312.049922) (xy 297.24798 -312.000868) (xy 297.259757 -311.953084)
			(xy 297.279048 -311.907808) (xy 297.305351 -311.866212) (xy 297.337986 -311.829375) (xy 297.376107 -311.79825)
			(xy 297.418728 -311.773643) (xy 297.464744 -311.756191) (xy 297.512963 -311.746347) (xy 297.562138 -311.744366)
			(xy 297.610993 -311.750298) (xy 297.658264 -311.76399) (xy 297.702726 -311.785088) (xy 297.743229 -311.813044)
			(xy 297.778722 -311.847136) (xy 297.808287 -311.88648) (xy 297.831158 -311.930057) (xy 297.846742 -311.976738)
			(xy 297.854637 -312.025315) (xy 297.855132 -312.049922) (xy 297.854637 -312.074529) (xy 297.854458 -312.07563)
			(xy 298.173136 -312.07563) (xy 298.173136 -312.024214) (xy 298.181179 -311.973432) (xy 298.197067 -311.924533)
			(xy 298.22041 -311.878721) (xy 298.250631 -311.837125) (xy 298.286987 -311.800769) (xy 298.328583 -311.770548)
			(xy 298.374395 -311.747205) (xy 298.423294 -311.731317) (xy 298.474076 -311.723274) (xy 298.525492 -311.723274)
			(xy 298.576274 -311.731317) (xy 298.625173 -311.747205) (xy 298.670985 -311.770548) (xy 298.712581 -311.800769)
			(xy 298.748937 -311.837125) (xy 298.779158 -311.878721) (xy 298.802501 -311.924533) (xy 298.818389 -311.973432)
			(xy 298.826432 -312.024214) (xy 298.826936 -312.049922) (xy 299.14394 -312.049922) (xy 299.1479 -312.000868)
			(xy 299.159677 -311.953084) (xy 299.178968 -311.907808) (xy 299.205271 -311.866212) (xy 299.237906 -311.829375)
			(xy 299.276027 -311.79825) (xy 299.318648 -311.773643) (xy 299.364664 -311.756191) (xy 299.412883 -311.746347)
			(xy 299.462058 -311.744366) (xy 299.510913 -311.750298) (xy 299.558184 -311.76399) (xy 299.602646 -311.785088)
			(xy 299.643149 -311.813044) (xy 299.678642 -311.847136) (xy 299.708207 -311.88648) (xy 299.731078 -311.930057)
			(xy 299.746662 -311.976738) (xy 299.754557 -312.025315) (xy 299.755052 -312.049922) (xy 299.754557 -312.074529)
			(xy 299.746662 -312.123106) (xy 299.731078 -312.169787) (xy 299.708207 -312.213364) (xy 299.678642 -312.252708)
			(xy 299.643149 -312.2868) (xy 299.602646 -312.314756) (xy 299.558184 -312.335854) (xy 299.510913 -312.349546)
			(xy 299.462058 -312.355478) (xy 299.412883 -312.353497) (xy 299.364664 -312.343653) (xy 299.318648 -312.326201)
			(xy 299.276027 -312.301594) (xy 299.237906 -312.270469) (xy 299.205271 -312.233632) (xy 299.178968 -312.192036)
			(xy 299.159677 -312.14676) (xy 299.1479 -312.098976) (xy 299.14394 -312.049922) (xy 298.826936 -312.049922)
			(xy 298.826432 -312.07563) (xy 298.818389 -312.126412) (xy 298.802501 -312.175311) (xy 298.779158 -312.221123)
			(xy 298.748937 -312.262719) (xy 298.712581 -312.299075) (xy 298.670985 -312.329296) (xy 298.625173 -312.352639)
			(xy 298.576274 -312.368527) (xy 298.525492 -312.37657) (xy 298.474076 -312.37657) (xy 298.423294 -312.368527)
			(xy 298.374395 -312.352639) (xy 298.328583 -312.329296) (xy 298.286987 -312.299075) (xy 298.250631 -312.262719)
			(xy 298.22041 -312.221123) (xy 298.197067 -312.175311) (xy 298.181179 -312.126412) (xy 298.173136 -312.07563)
			(xy 297.854458 -312.07563) (xy 297.846742 -312.123106) (xy 297.831158 -312.169787) (xy 297.808287 -312.213364)
			(xy 297.778722 -312.252708) (xy 297.743229 -312.2868) (xy 297.702726 -312.314756) (xy 297.658264 -312.335854)
			(xy 297.610993 -312.349546) (xy 297.562138 -312.355478) (xy 297.512963 -312.353497) (xy 297.464744 -312.343653)
			(xy 297.418728 -312.326201) (xy 297.376107 -312.301594) (xy 297.337986 -312.270469) (xy 297.305351 -312.233632)
			(xy 297.279048 -312.192036) (xy 297.259757 -312.14676) (xy 297.24798 -312.098976) (xy 297.24402 -312.049922)
			(xy 296.927016 -312.049922) (xy 296.926512 -312.07563) (xy 296.918469 -312.126412) (xy 296.902581 -312.175311)
			(xy 296.879238 -312.221123) (xy 296.849017 -312.262719) (xy 296.812661 -312.299075) (xy 296.771065 -312.329296)
			(xy 296.725253 -312.352639) (xy 296.676354 -312.368527) (xy 296.625572 -312.37657) (xy 296.574156 -312.37657)
			(xy 296.523374 -312.368527) (xy 296.474475 -312.352639) (xy 296.428663 -312.329296) (xy 296.387067 -312.299075)
			(xy 296.350711 -312.262719) (xy 296.32049 -312.221123) (xy 296.297147 -312.175311) (xy 296.281259 -312.126412)
			(xy 296.273216 -312.07563) (xy 295.954538 -312.07563) (xy 295.946822 -312.123106) (xy 295.931238 -312.169787)
			(xy 295.908367 -312.213364) (xy 295.878802 -312.252708) (xy 295.843309 -312.2868) (xy 295.802806 -312.314756)
			(xy 295.758344 -312.335854) (xy 295.711073 -312.349546) (xy 295.662218 -312.355478) (xy 295.613043 -312.353497)
			(xy 295.564824 -312.343653) (xy 295.518808 -312.326201) (xy 295.476187 -312.301594) (xy 295.438066 -312.270469)
			(xy 295.405431 -312.233632) (xy 295.379128 -312.192036) (xy 295.359837 -312.14676) (xy 295.34806 -312.098976)
			(xy 295.3441 -312.049922) (xy 295.026842 -312.049922) (xy 295.026338 -312.07563) (xy 295.018295 -312.126412)
			(xy 295.002407 -312.175311) (xy 294.979064 -312.221123) (xy 294.948843 -312.262719) (xy 294.912487 -312.299075)
			(xy 294.870891 -312.329296) (xy 294.825079 -312.352639) (xy 294.77618 -312.368527) (xy 294.725398 -312.37657)
			(xy 294.673982 -312.37657) (xy 294.6232 -312.368527) (xy 294.574301 -312.352639) (xy 294.528489 -312.329296)
			(xy 294.486893 -312.299075) (xy 294.450537 -312.262719) (xy 294.420316 -312.221123) (xy 294.396973 -312.175311)
			(xy 294.381085 -312.126412) (xy 294.373042 -312.07563) (xy 294.054364 -312.07563) (xy 294.046648 -312.123106)
			(xy 294.031064 -312.169787) (xy 294.008193 -312.213364) (xy 293.978628 -312.252708) (xy 293.943135 -312.2868)
			(xy 293.902632 -312.314756) (xy 293.85817 -312.335854) (xy 293.810899 -312.349546) (xy 293.762044 -312.355478)
			(xy 293.712869 -312.353497) (xy 293.66465 -312.343653) (xy 293.618634 -312.326201) (xy 293.576013 -312.301594)
			(xy 293.537892 -312.270469) (xy 293.505257 -312.233632) (xy 293.478954 -312.192036) (xy 293.459663 -312.14676)
			(xy 293.447886 -312.098976) (xy 293.443926 -312.049922) (xy 293.126922 -312.049922) (xy 293.126418 -312.07563)
			(xy 293.118375 -312.126412) (xy 293.102487 -312.175311) (xy 293.079144 -312.221123) (xy 293.048923 -312.262719)
			(xy 293.012567 -312.299075) (xy 292.970971 -312.329296) (xy 292.925159 -312.352639) (xy 292.87626 -312.368527)
			(xy 292.825478 -312.37657) (xy 292.774062 -312.37657) (xy 292.72328 -312.368527) (xy 292.674381 -312.352639)
			(xy 292.628569 -312.329296) (xy 292.586973 -312.299075) (xy 292.550617 -312.262719) (xy 292.520396 -312.221123)
			(xy 292.497053 -312.175311) (xy 292.481165 -312.126412) (xy 292.473122 -312.07563) (xy 292.154444 -312.07563)
			(xy 292.146728 -312.123106) (xy 292.131144 -312.169787) (xy 292.108273 -312.213364) (xy 292.078708 -312.252708)
			(xy 292.043215 -312.2868) (xy 292.002712 -312.314756) (xy 291.95825 -312.335854) (xy 291.910979 -312.349546)
			(xy 291.862124 -312.355478) (xy 291.812949 -312.353497) (xy 291.76473 -312.343653) (xy 291.718714 -312.326201)
			(xy 291.676093 -312.301594) (xy 291.637972 -312.270469) (xy 291.605337 -312.233632) (xy 291.579034 -312.192036)
			(xy 291.559743 -312.14676) (xy 291.547966 -312.098976) (xy 291.544006 -312.049922) (xy 291.227002 -312.049922)
			(xy 291.226498 -312.07563) (xy 291.218455 -312.126412) (xy 291.202567 -312.175311) (xy 291.179224 -312.221123)
			(xy 291.149003 -312.262719) (xy 291.112647 -312.299075) (xy 291.071051 -312.329296) (xy 291.025239 -312.352639)
			(xy 290.97634 -312.368527) (xy 290.925558 -312.37657) (xy 290.874142 -312.37657) (xy 290.82336 -312.368527)
			(xy 290.774461 -312.352639) (xy 290.728649 -312.329296) (xy 290.687053 -312.299075) (xy 290.650697 -312.262719)
			(xy 290.620476 -312.221123) (xy 290.597133 -312.175311) (xy 290.581245 -312.126412) (xy 290.573202 -312.07563)
			(xy 290.254524 -312.07563) (xy 290.246808 -312.123106) (xy 290.231224 -312.169787) (xy 290.208353 -312.213364)
			(xy 290.178788 -312.252708) (xy 290.143295 -312.2868) (xy 290.102792 -312.314756) (xy 290.05833 -312.335854)
			(xy 290.011059 -312.349546) (xy 289.962204 -312.355478) (xy 289.913029 -312.353497) (xy 289.86481 -312.343653)
			(xy 289.818794 -312.326201) (xy 289.776173 -312.301594) (xy 289.738052 -312.270469) (xy 289.705417 -312.233632)
			(xy 289.679114 -312.192036) (xy 289.659823 -312.14676) (xy 289.648046 -312.098976) (xy 289.644086 -312.049922)
			(xy 289.327082 -312.049922) (xy 289.326578 -312.07563) (xy 289.318535 -312.126412) (xy 289.302647 -312.175311)
			(xy 289.279304 -312.221123) (xy 289.249083 -312.262719) (xy 289.212727 -312.299075) (xy 289.171131 -312.329296)
			(xy 289.125319 -312.352639) (xy 289.07642 -312.368527) (xy 289.025638 -312.37657) (xy 288.974222 -312.37657)
			(xy 288.92344 -312.368527) (xy 288.874541 -312.352639) (xy 288.828729 -312.329296) (xy 288.787133 -312.299075)
			(xy 288.750777 -312.262719) (xy 288.720556 -312.221123) (xy 288.697213 -312.175311) (xy 288.681325 -312.126412)
			(xy 288.673282 -312.07563) (xy 288.35435 -312.07563) (xy 288.346634 -312.123106) (xy 288.33105 -312.169787)
			(xy 288.308179 -312.213364) (xy 288.278614 -312.252708) (xy 288.243121 -312.2868) (xy 288.202618 -312.314756)
			(xy 288.158156 -312.335854) (xy 288.110885 -312.349546) (xy 288.06203 -312.355478) (xy 288.012855 -312.353497)
			(xy 287.964636 -312.343653) (xy 287.91862 -312.326201) (xy 287.875999 -312.301594) (xy 287.837878 -312.270469)
			(xy 287.805243 -312.233632) (xy 287.77894 -312.192036) (xy 287.759649 -312.14676) (xy 287.747872 -312.098976)
			(xy 287.743912 -312.049922) (xy 287.426908 -312.049922) (xy 287.426404 -312.07563) (xy 287.418361 -312.126412)
			(xy 287.402473 -312.175311) (xy 287.37913 -312.221123) (xy 287.348909 -312.262719) (xy 287.312553 -312.299075)
			(xy 287.270957 -312.329296) (xy 287.225145 -312.352639) (xy 287.176246 -312.368527) (xy 287.125464 -312.37657)
			(xy 287.074048 -312.37657) (xy 287.023266 -312.368527) (xy 286.974367 -312.352639) (xy 286.928555 -312.329296)
			(xy 286.886959 -312.299075) (xy 286.850603 -312.262719) (xy 286.820382 -312.221123) (xy 286.797039 -312.175311)
			(xy 286.781151 -312.126412) (xy 286.773108 -312.07563) (xy 286.45443 -312.07563) (xy 286.446714 -312.123106)
			(xy 286.43113 -312.169787) (xy 286.408259 -312.213364) (xy 286.378694 -312.252708) (xy 286.343201 -312.2868)
			(xy 286.302698 -312.314756) (xy 286.258236 -312.335854) (xy 286.210965 -312.349546) (xy 286.16211 -312.355478)
			(xy 286.112935 -312.353497) (xy 286.064716 -312.343653) (xy 286.0187 -312.326201) (xy 285.976079 -312.301594)
			(xy 285.937958 -312.270469) (xy 285.905323 -312.233632) (xy 285.87902 -312.192036) (xy 285.859729 -312.14676)
			(xy 285.847952 -312.098976) (xy 285.843992 -312.049922) (xy 285.526988 -312.049922) (xy 285.526484 -312.07563)
			(xy 285.518441 -312.126412) (xy 285.502553 -312.175311) (xy 285.47921 -312.221123) (xy 285.448989 -312.262719)
			(xy 285.412633 -312.299075) (xy 285.371037 -312.329296) (xy 285.325225 -312.352639) (xy 285.276326 -312.368527)
			(xy 285.225544 -312.37657) (xy 285.174128 -312.37657) (xy 285.123346 -312.368527) (xy 285.074447 -312.352639)
			(xy 285.028635 -312.329296) (xy 284.987039 -312.299075) (xy 284.950683 -312.262719) (xy 284.920462 -312.221123)
			(xy 284.897119 -312.175311) (xy 284.881231 -312.126412) (xy 284.873188 -312.07563) (xy 284.55451 -312.07563)
			(xy 284.546794 -312.123106) (xy 284.53121 -312.169787) (xy 284.508339 -312.213364) (xy 284.478774 -312.252708)
			(xy 284.443281 -312.2868) (xy 284.402778 -312.314756) (xy 284.358316 -312.335854) (xy 284.311045 -312.349546)
			(xy 284.26219 -312.355478) (xy 284.213015 -312.353497) (xy 284.164796 -312.343653) (xy 284.11878 -312.326201)
			(xy 284.076159 -312.301594) (xy 284.038038 -312.270469) (xy 284.005403 -312.233632) (xy 283.9791 -312.192036)
			(xy 283.959809 -312.14676) (xy 283.948032 -312.098976) (xy 283.944072 -312.049922) (xy 283.627068 -312.049922)
			(xy 283.626564 -312.07563) (xy 283.618521 -312.126412) (xy 283.602633 -312.175311) (xy 283.57929 -312.221123)
			(xy 283.549069 -312.262719) (xy 283.512713 -312.299075) (xy 283.471117 -312.329296) (xy 283.425305 -312.352639)
			(xy 283.376406 -312.368527) (xy 283.325624 -312.37657) (xy 283.274208 -312.37657) (xy 283.223426 -312.368527)
			(xy 283.174527 -312.352639) (xy 283.128715 -312.329296) (xy 283.087119 -312.299075) (xy 283.050763 -312.262719)
			(xy 283.020542 -312.221123) (xy 282.997199 -312.175311) (xy 282.981311 -312.126412) (xy 282.973268 -312.07563)
			(xy 282.654336 -312.07563) (xy 282.64662 -312.123106) (xy 282.631036 -312.169787) (xy 282.608165 -312.213364)
			(xy 282.5786 -312.252708) (xy 282.543107 -312.2868) (xy 282.502604 -312.314756) (xy 282.458142 -312.335854)
			(xy 282.410871 -312.349546) (xy 282.362016 -312.355478) (xy 282.312841 -312.353497) (xy 282.264622 -312.343653)
			(xy 282.218606 -312.326201) (xy 282.175985 -312.301594) (xy 282.137864 -312.270469) (xy 282.105229 -312.233632)
			(xy 282.078926 -312.192036) (xy 282.059635 -312.14676) (xy 282.047858 -312.098976) (xy 282.043898 -312.049922)
			(xy 281.726894 -312.049922) (xy 281.72639 -312.07563) (xy 281.718347 -312.126412) (xy 281.702459 -312.175311)
			(xy 281.679116 -312.221123) (xy 281.648895 -312.262719) (xy 281.612539 -312.299075) (xy 281.570943 -312.329296)
			(xy 281.525131 -312.352639) (xy 281.476232 -312.368527) (xy 281.42545 -312.37657) (xy 281.374034 -312.37657)
			(xy 281.323252 -312.368527) (xy 281.274353 -312.352639) (xy 281.228541 -312.329296) (xy 281.186945 -312.299075)
			(xy 281.150589 -312.262719) (xy 281.120368 -312.221123) (xy 281.097025 -312.175311) (xy 281.081137 -312.126412)
			(xy 281.073094 -312.07563) (xy 280.754416 -312.07563) (xy 280.7467 -312.123106) (xy 280.731116 -312.169787)
			(xy 280.708245 -312.213364) (xy 280.67868 -312.252708) (xy 280.643187 -312.2868) (xy 280.602684 -312.314756)
			(xy 280.558222 -312.335854) (xy 280.510951 -312.349546) (xy 280.462096 -312.355478) (xy 280.412921 -312.353497)
			(xy 280.364702 -312.343653) (xy 280.318686 -312.326201) (xy 280.276065 -312.301594) (xy 280.237944 -312.270469)
			(xy 280.205309 -312.233632) (xy 280.179006 -312.192036) (xy 280.159715 -312.14676) (xy 280.147938 -312.098976)
			(xy 280.143978 -312.049922) (xy 279.826974 -312.049922) (xy 279.82647 -312.07563) (xy 279.818427 -312.126412)
			(xy 279.802539 -312.175311) (xy 279.779196 -312.221123) (xy 279.748975 -312.262719) (xy 279.712619 -312.299075)
			(xy 279.671023 -312.329296) (xy 279.625211 -312.352639) (xy 279.576312 -312.368527) (xy 279.52553 -312.37657)
			(xy 279.474114 -312.37657) (xy 279.423332 -312.368527) (xy 279.374433 -312.352639) (xy 279.328621 -312.329296)
			(xy 279.287025 -312.299075) (xy 279.250669 -312.262719) (xy 279.220448 -312.221123) (xy 279.197105 -312.175311)
			(xy 279.181217 -312.126412) (xy 279.173174 -312.07563) (xy 278.854496 -312.07563) (xy 278.84678 -312.123106)
			(xy 278.831196 -312.169787) (xy 278.808325 -312.213364) (xy 278.77876 -312.252708) (xy 278.743267 -312.2868)
			(xy 278.702764 -312.314756) (xy 278.658302 -312.335854) (xy 278.611031 -312.349546) (xy 278.562176 -312.355478)
			(xy 278.513001 -312.353497) (xy 278.464782 -312.343653) (xy 278.418766 -312.326201) (xy 278.376145 -312.301594)
			(xy 278.338024 -312.270469) (xy 278.305389 -312.233632) (xy 278.279086 -312.192036) (xy 278.259795 -312.14676)
			(xy 278.248018 -312.098976) (xy 278.244058 -312.049922) (xy 277.927054 -312.049922) (xy 277.92655 -312.07563)
			(xy 277.918507 -312.126412) (xy 277.902619 -312.175311) (xy 277.879276 -312.221123) (xy 277.849055 -312.262719)
			(xy 277.812699 -312.299075) (xy 277.771103 -312.329296) (xy 277.725291 -312.352639) (xy 277.676392 -312.368527)
			(xy 277.62561 -312.37657) (xy 277.574194 -312.37657) (xy 277.523412 -312.368527) (xy 277.474513 -312.352639)
			(xy 277.428701 -312.329296) (xy 277.387105 -312.299075) (xy 277.350749 -312.262719) (xy 277.320528 -312.221123)
			(xy 277.297185 -312.175311) (xy 277.281297 -312.126412) (xy 277.273254 -312.07563) (xy 276.954322 -312.07563)
			(xy 276.946606 -312.123106) (xy 276.931022 -312.169787) (xy 276.908151 -312.213364) (xy 276.878586 -312.252708)
			(xy 276.843093 -312.2868) (xy 276.80259 -312.314756) (xy 276.758128 -312.335854) (xy 276.710857 -312.349546)
			(xy 276.662002 -312.355478) (xy 276.612827 -312.353497) (xy 276.564608 -312.343653) (xy 276.518592 -312.326201)
			(xy 276.475971 -312.301594) (xy 276.43785 -312.270469) (xy 276.405215 -312.233632) (xy 276.378912 -312.192036)
			(xy 276.359621 -312.14676) (xy 276.347844 -312.098976) (xy 276.343884 -312.049922) (xy 276.02688 -312.049922)
			(xy 276.026376 -312.07563) (xy 276.018333 -312.126412) (xy 276.002445 -312.175311) (xy 275.979102 -312.221123)
			(xy 275.948881 -312.262719) (xy 275.912525 -312.299075) (xy 275.870929 -312.329296) (xy 275.825117 -312.352639)
			(xy 275.776218 -312.368527) (xy 275.725436 -312.37657) (xy 275.67402 -312.37657) (xy 275.623238 -312.368527)
			(xy 275.574339 -312.352639) (xy 275.528527 -312.329296) (xy 275.486931 -312.299075) (xy 275.450575 -312.262719)
			(xy 275.420354 -312.221123) (xy 275.397011 -312.175311) (xy 275.381123 -312.126412) (xy 275.37308 -312.07563)
			(xy 275.054402 -312.07563) (xy 275.046686 -312.123106) (xy 275.031102 -312.169787) (xy 275.008231 -312.213364)
			(xy 274.978666 -312.252708) (xy 274.943173 -312.2868) (xy 274.90267 -312.314756) (xy 274.858208 -312.335854)
			(xy 274.810937 -312.349546) (xy 274.762082 -312.355478) (xy 274.712907 -312.353497) (xy 274.664688 -312.343653)
			(xy 274.618672 -312.326201) (xy 274.576051 -312.301594) (xy 274.53793 -312.270469) (xy 274.505295 -312.233632)
			(xy 274.478992 -312.192036) (xy 274.459701 -312.14676) (xy 274.447924 -312.098976) (xy 274.443964 -312.049922)
			(xy 274.12696 -312.049922) (xy 274.126456 -312.07563) (xy 274.118413 -312.126412) (xy 274.102525 -312.175311)
			(xy 274.079182 -312.221123) (xy 274.048961 -312.262719) (xy 274.012605 -312.299075) (xy 273.971009 -312.329296)
			(xy 273.925197 -312.352639) (xy 273.876298 -312.368527) (xy 273.825516 -312.37657) (xy 273.7741 -312.37657)
			(xy 273.723318 -312.368527) (xy 273.674419 -312.352639) (xy 273.628607 -312.329296) (xy 273.587011 -312.299075)
			(xy 273.550655 -312.262719) (xy 273.520434 -312.221123) (xy 273.497091 -312.175311) (xy 273.481203 -312.126412)
			(xy 273.47316 -312.07563) (xy 273.154482 -312.07563) (xy 273.146766 -312.123106) (xy 273.131182 -312.169787)
			(xy 273.108311 -312.213364) (xy 273.078746 -312.252708) (xy 273.043253 -312.2868) (xy 273.00275 -312.314756)
			(xy 272.958288 -312.335854) (xy 272.911017 -312.349546) (xy 272.862162 -312.355478) (xy 272.812987 -312.353497)
			(xy 272.764768 -312.343653) (xy 272.718752 -312.326201) (xy 272.676131 -312.301594) (xy 272.63801 -312.270469)
			(xy 272.605375 -312.233632) (xy 272.579072 -312.192036) (xy 272.559781 -312.14676) (xy 272.548004 -312.098976)
			(xy 272.544044 -312.049922) (xy 272.22704 -312.049922) (xy 272.226536 -312.07563) (xy 272.218493 -312.126412)
			(xy 272.202605 -312.175311) (xy 272.179262 -312.221123) (xy 272.149041 -312.262719) (xy 272.112685 -312.299075)
			(xy 272.071089 -312.329296) (xy 272.025277 -312.352639) (xy 271.976378 -312.368527) (xy 271.925596 -312.37657)
			(xy 271.87418 -312.37657) (xy 271.823398 -312.368527) (xy 271.774499 -312.352639) (xy 271.728687 -312.329296)
			(xy 271.687091 -312.299075) (xy 271.650735 -312.262719) (xy 271.620514 -312.221123) (xy 271.597171 -312.175311)
			(xy 271.581283 -312.126412) (xy 271.57324 -312.07563) (xy 271.254562 -312.07563) (xy 271.246846 -312.123106)
			(xy 271.231262 -312.169787) (xy 271.208391 -312.213364) (xy 271.178826 -312.252708) (xy 271.143333 -312.2868)
			(xy 271.10283 -312.314756) (xy 271.058368 -312.335854) (xy 271.011097 -312.349546) (xy 270.962242 -312.355478)
			(xy 270.913067 -312.353497) (xy 270.864848 -312.343653) (xy 270.818832 -312.326201) (xy 270.776211 -312.301594)
			(xy 270.73809 -312.270469) (xy 270.705455 -312.233632) (xy 270.679152 -312.192036) (xy 270.659861 -312.14676)
			(xy 270.648084 -312.098976) (xy 270.644124 -312.049922) (xy 270.326866 -312.049922) (xy 270.326362 -312.07563)
			(xy 270.318319 -312.126412) (xy 270.302431 -312.175311) (xy 270.279088 -312.221123) (xy 270.248867 -312.262719)
			(xy 270.212511 -312.299075) (xy 270.170915 -312.329296) (xy 270.125103 -312.352639) (xy 270.076204 -312.368527)
			(xy 270.025422 -312.37657) (xy 269.974006 -312.37657) (xy 269.923224 -312.368527) (xy 269.874325 -312.352639)
			(xy 269.828513 -312.329296) (xy 269.786917 -312.299075) (xy 269.750561 -312.262719) (xy 269.72034 -312.221123)
			(xy 269.696997 -312.175311) (xy 269.681109 -312.126412) (xy 269.673066 -312.07563) (xy 269.376402 -312.07563)
			(xy 269.368359 -312.126412) (xy 269.352471 -312.175311) (xy 269.329128 -312.221123) (xy 269.298907 -312.262719)
			(xy 269.262551 -312.299075) (xy 269.220955 -312.329296) (xy 269.175143 -312.352639) (xy 269.126244 -312.368527)
			(xy 269.075462 -312.37657) (xy 269.024046 -312.37657) (xy 268.973264 -312.368527) (xy 268.924365 -312.352639)
			(xy 268.878553 -312.329296) (xy 268.836957 -312.299075) (xy 268.800601 -312.262719) (xy 268.77038 -312.221123)
			(xy 268.747037 -312.175311) (xy 268.731149 -312.126412) (xy 268.723106 -312.07563) (xy 268.404133 -312.07563)
			(xy 268.396458 -312.122852) (xy 268.380874 -312.169533) (xy 268.358003 -312.21311) (xy 268.328438 -312.252454)
			(xy 268.292945 -312.286546) (xy 268.252442 -312.314502) (xy 268.20798 -312.3356) (xy 268.160709 -312.349292)
			(xy 268.111854 -312.355224) (xy 268.062679 -312.353243) (xy 268.01446 -312.343399) (xy 267.968444 -312.325947)
			(xy 267.925823 -312.30134) (xy 267.887702 -312.270215) (xy 267.855067 -312.233378) (xy 267.828764 -312.191782)
			(xy 267.809473 -312.146506) (xy 267.797696 -312.098722) (xy 267.793736 -312.049668) (xy 266.953896 -312.049668)
			(xy 266.974719 -312.081142) (xy 266.998391 -312.131639) (xy 267.014459 -312.185046) (xy 267.022579 -312.240222)
			(xy 267.023088 -312.268108) (xy 267.022579 -312.295994) (xy 267.014459 -312.35117) (xy 266.998391 -312.404577)
			(xy 266.974719 -312.455074) (xy 266.943946 -312.501587) (xy 266.906729 -312.543124) (xy 266.863861 -312.578799)
			(xy 266.816255 -312.607853) (xy 266.764926 -312.629665) (xy 266.710969 -312.643771) (xy 266.655532 -312.649871)
			(xy 266.599798 -312.647834) (xy 266.544955 -312.637704) (xy 266.492171 -312.619697) (xy 266.442571 -312.594196)
			(xy 266.397213 -312.561745) (xy 266.357064 -312.523036) (xy 266.322978 -312.478893) (xy 266.295682 -312.430258)
			(xy 266.275759 -312.378167) (xy 266.263633 -312.32373) (xy 266.259562 -312.268108) (xy 264.596765 -312.268108)
			(xy 264.61629 -312.289899) (xy 264.647063 -312.336412) (xy 264.670735 -312.386909) (xy 264.686803 -312.440316)
			(xy 264.694923 -312.495492) (xy 264.695432 -312.523378) (xy 264.694923 -312.551264) (xy 264.686803 -312.60644)
			(xy 264.670735 -312.659847) (xy 264.647063 -312.710344) (xy 264.61629 -312.756857) (xy 264.579073 -312.798394)
			(xy 264.536205 -312.834069) (xy 264.488599 -312.863123) (xy 264.43727 -312.884935) (xy 264.383313 -312.899041)
			(xy 264.327876 -312.905141) (xy 264.272142 -312.903104) (xy 264.217299 -312.892974) (xy 264.164515 -312.874967)
			(xy 264.114915 -312.849466) (xy 264.069557 -312.817015) (xy 264.029408 -312.778306) (xy 263.995322 -312.734163)
			(xy 263.968026 -312.685528) (xy 263.948103 -312.633437) (xy 263.935977 -312.579) (xy 263.931906 -312.523378)
			(xy 255.945132 -312.523378) (xy 255.945132 -312.999882) (xy 268.74395 -312.999882) (xy 268.74791 -312.950828)
			(xy 268.759687 -312.903044) (xy 268.778978 -312.857768) (xy 268.805281 -312.816172) (xy 268.837916 -312.779335)
			(xy 268.876037 -312.74821) (xy 268.918658 -312.723603) (xy 268.964674 -312.706151) (xy 269.012893 -312.696307)
			(xy 269.062068 -312.694326) (xy 269.110923 -312.700258) (xy 269.158194 -312.71395) (xy 269.202656 -312.735048)
			(xy 269.243159 -312.763004) (xy 269.278652 -312.797096) (xy 269.308217 -312.83644) (xy 269.331088 -312.880017)
			(xy 269.346672 -312.926698) (xy 269.354567 -312.975275) (xy 269.355062 -312.999882) (xy 269.69391 -312.999882)
			(xy 269.69787 -312.950828) (xy 269.709647 -312.903044) (xy 269.728938 -312.857768) (xy 269.755241 -312.816172)
			(xy 269.787876 -312.779335) (xy 269.825997 -312.74821) (xy 269.868618 -312.723603) (xy 269.914634 -312.706151)
			(xy 269.962853 -312.696307) (xy 270.012028 -312.694326) (xy 270.060883 -312.700258) (xy 270.108154 -312.71395)
			(xy 270.152616 -312.735048) (xy 270.193119 -312.763004) (xy 270.228612 -312.797096) (xy 270.258177 -312.83644)
			(xy 270.281048 -312.880017) (xy 270.296632 -312.926698) (xy 270.304527 -312.975275) (xy 270.305022 -312.999882)
			(xy 270.304527 -313.024489) (xy 270.304348 -313.02559) (xy 270.62328 -313.02559) (xy 270.62328 -312.974174)
			(xy 270.631323 -312.923392) (xy 270.647211 -312.874493) (xy 270.670554 -312.828681) (xy 270.700775 -312.787085)
			(xy 270.737131 -312.750729) (xy 270.778727 -312.720508) (xy 270.824539 -312.697165) (xy 270.873438 -312.681277)
			(xy 270.92422 -312.673234) (xy 270.975636 -312.673234) (xy 271.026418 -312.681277) (xy 271.075317 -312.697165)
			(xy 271.121129 -312.720508) (xy 271.162725 -312.750729) (xy 271.199081 -312.787085) (xy 271.229302 -312.828681)
			(xy 271.252645 -312.874493) (xy 271.268533 -312.923392) (xy 271.276576 -312.974174) (xy 271.27708 -312.999882)
			(xy 271.594084 -312.999882) (xy 271.598044 -312.950828) (xy 271.609821 -312.903044) (xy 271.629112 -312.857768)
			(xy 271.655415 -312.816172) (xy 271.68805 -312.779335) (xy 271.726171 -312.74821) (xy 271.768792 -312.723603)
			(xy 271.814808 -312.706151) (xy 271.863027 -312.696307) (xy 271.912202 -312.694326) (xy 271.961057 -312.700258)
			(xy 272.008328 -312.71395) (xy 272.05279 -312.735048) (xy 272.093293 -312.763004) (xy 272.128786 -312.797096)
			(xy 272.158351 -312.83644) (xy 272.181222 -312.880017) (xy 272.196806 -312.926698) (xy 272.204701 -312.975275)
			(xy 272.205196 -312.999882) (xy 272.204701 -313.024489) (xy 272.204522 -313.02559) (xy 272.5232 -313.02559)
			(xy 272.5232 -312.974174) (xy 272.531243 -312.923392) (xy 272.547131 -312.874493) (xy 272.570474 -312.828681)
			(xy 272.600695 -312.787085) (xy 272.637051 -312.750729) (xy 272.678647 -312.720508) (xy 272.724459 -312.697165)
			(xy 272.773358 -312.681277) (xy 272.82414 -312.673234) (xy 272.875556 -312.673234) (xy 272.926338 -312.681277)
			(xy 272.975237 -312.697165) (xy 273.021049 -312.720508) (xy 273.062645 -312.750729) (xy 273.099001 -312.787085)
			(xy 273.129222 -312.828681) (xy 273.152565 -312.874493) (xy 273.168453 -312.923392) (xy 273.176496 -312.974174)
			(xy 273.177 -312.999882) (xy 273.494004 -312.999882) (xy 273.497964 -312.950828) (xy 273.509741 -312.903044)
			(xy 273.529032 -312.857768) (xy 273.555335 -312.816172) (xy 273.58797 -312.779335) (xy 273.626091 -312.74821)
			(xy 273.668712 -312.723603) (xy 273.714728 -312.706151) (xy 273.762947 -312.696307) (xy 273.812122 -312.694326)
			(xy 273.860977 -312.700258) (xy 273.908248 -312.71395) (xy 273.95271 -312.735048) (xy 273.993213 -312.763004)
			(xy 274.028706 -312.797096) (xy 274.058271 -312.83644) (xy 274.081142 -312.880017) (xy 274.096726 -312.926698)
			(xy 274.104621 -312.975275) (xy 274.105116 -312.999882) (xy 274.104621 -313.024489) (xy 274.104442 -313.02559)
			(xy 274.42312 -313.02559) (xy 274.42312 -312.974174) (xy 274.431163 -312.923392) (xy 274.447051 -312.874493)
			(xy 274.470394 -312.828681) (xy 274.500615 -312.787085) (xy 274.536971 -312.750729) (xy 274.578567 -312.720508)
			(xy 274.624379 -312.697165) (xy 274.673278 -312.681277) (xy 274.72406 -312.673234) (xy 274.775476 -312.673234)
			(xy 274.826258 -312.681277) (xy 274.875157 -312.697165) (xy 274.920969 -312.720508) (xy 274.962565 -312.750729)
			(xy 274.998921 -312.787085) (xy 275.029142 -312.828681) (xy 275.052485 -312.874493) (xy 275.068373 -312.923392)
			(xy 275.076416 -312.974174) (xy 275.07692 -312.999882) (xy 275.393924 -312.999882) (xy 275.397884 -312.950828)
			(xy 275.409661 -312.903044) (xy 275.428952 -312.857768) (xy 275.455255 -312.816172) (xy 275.48789 -312.779335)
			(xy 275.526011 -312.74821) (xy 275.568632 -312.723603) (xy 275.614648 -312.706151) (xy 275.662867 -312.696307)
			(xy 275.712042 -312.694326) (xy 275.760897 -312.700258) (xy 275.808168 -312.71395) (xy 275.85263 -312.735048)
			(xy 275.893133 -312.763004) (xy 275.928626 -312.797096) (xy 275.958191 -312.83644) (xy 275.981062 -312.880017)
			(xy 275.996646 -312.926698) (xy 276.004541 -312.975275) (xy 276.005036 -312.999882) (xy 276.004541 -313.024489)
			(xy 276.004362 -313.02559) (xy 276.32304 -313.02559) (xy 276.32304 -312.974174) (xy 276.331083 -312.923392)
			(xy 276.346971 -312.874493) (xy 276.370314 -312.828681) (xy 276.400535 -312.787085) (xy 276.436891 -312.750729)
			(xy 276.478487 -312.720508) (xy 276.524299 -312.697165) (xy 276.573198 -312.681277) (xy 276.62398 -312.673234)
			(xy 276.675396 -312.673234) (xy 276.726178 -312.681277) (xy 276.775077 -312.697165) (xy 276.820889 -312.720508)
			(xy 276.862485 -312.750729) (xy 276.898841 -312.787085) (xy 276.929062 -312.828681) (xy 276.952405 -312.874493)
			(xy 276.968293 -312.923392) (xy 276.976336 -312.974174) (xy 276.97684 -312.999882) (xy 277.294098 -312.999882)
			(xy 277.298058 -312.950828) (xy 277.309835 -312.903044) (xy 277.329126 -312.857768) (xy 277.355429 -312.816172)
			(xy 277.388064 -312.779335) (xy 277.426185 -312.74821) (xy 277.468806 -312.723603) (xy 277.514822 -312.706151)
			(xy 277.563041 -312.696307) (xy 277.612216 -312.694326) (xy 277.661071 -312.700258) (xy 277.708342 -312.71395)
			(xy 277.752804 -312.735048) (xy 277.793307 -312.763004) (xy 277.8288 -312.797096) (xy 277.858365 -312.83644)
			(xy 277.881236 -312.880017) (xy 277.89682 -312.926698) (xy 277.904715 -312.975275) (xy 277.90521 -312.999882)
			(xy 277.904715 -313.024489) (xy 277.904536 -313.02559) (xy 278.223214 -313.02559) (xy 278.223214 -312.974174)
			(xy 278.231257 -312.923392) (xy 278.247145 -312.874493) (xy 278.270488 -312.828681) (xy 278.300709 -312.787085)
			(xy 278.337065 -312.750729) (xy 278.378661 -312.720508) (xy 278.424473 -312.697165) (xy 278.473372 -312.681277)
			(xy 278.524154 -312.673234) (xy 278.57557 -312.673234) (xy 278.626352 -312.681277) (xy 278.675251 -312.697165)
			(xy 278.721063 -312.720508) (xy 278.762659 -312.750729) (xy 278.799015 -312.787085) (xy 278.829236 -312.828681)
			(xy 278.852579 -312.874493) (xy 278.868467 -312.923392) (xy 278.87651 -312.974174) (xy 278.877014 -312.999882)
			(xy 279.194018 -312.999882) (xy 279.197978 -312.950828) (xy 279.209755 -312.903044) (xy 279.229046 -312.857768)
			(xy 279.255349 -312.816172) (xy 279.287984 -312.779335) (xy 279.326105 -312.74821) (xy 279.368726 -312.723603)
			(xy 279.414742 -312.706151) (xy 279.462961 -312.696307) (xy 279.512136 -312.694326) (xy 279.560991 -312.700258)
			(xy 279.608262 -312.71395) (xy 279.652724 -312.735048) (xy 279.693227 -312.763004) (xy 279.72872 -312.797096)
			(xy 279.758285 -312.83644) (xy 279.781156 -312.880017) (xy 279.79674 -312.926698) (xy 279.804635 -312.975275)
			(xy 279.80513 -312.999882) (xy 279.804635 -313.024489) (xy 279.804456 -313.02559) (xy 280.123134 -313.02559)
			(xy 280.123134 -312.974174) (xy 280.131177 -312.923392) (xy 280.147065 -312.874493) (xy 280.170408 -312.828681)
			(xy 280.200629 -312.787085) (xy 280.236985 -312.750729) (xy 280.278581 -312.720508) (xy 280.324393 -312.697165)
			(xy 280.373292 -312.681277) (xy 280.424074 -312.673234) (xy 280.47549 -312.673234) (xy 280.526272 -312.681277)
			(xy 280.575171 -312.697165) (xy 280.620983 -312.720508) (xy 280.662579 -312.750729) (xy 280.698935 -312.787085)
			(xy 280.729156 -312.828681) (xy 280.752499 -312.874493) (xy 280.768387 -312.923392) (xy 280.77643 -312.974174)
			(xy 280.776934 -312.999882) (xy 281.093938 -312.999882) (xy 281.097898 -312.950828) (xy 281.109675 -312.903044)
			(xy 281.128966 -312.857768) (xy 281.155269 -312.816172) (xy 281.187904 -312.779335) (xy 281.226025 -312.74821)
			(xy 281.268646 -312.723603) (xy 281.314662 -312.706151) (xy 281.362881 -312.696307) (xy 281.412056 -312.694326)
			(xy 281.460911 -312.700258) (xy 281.508182 -312.71395) (xy 281.552644 -312.735048) (xy 281.593147 -312.763004)
			(xy 281.62864 -312.797096) (xy 281.658205 -312.83644) (xy 281.681076 -312.880017) (xy 281.69666 -312.926698)
			(xy 281.704555 -312.975275) (xy 281.70505 -312.999882) (xy 281.704555 -313.024489) (xy 281.704376 -313.02559)
			(xy 282.023054 -313.02559) (xy 282.023054 -312.974174) (xy 282.031097 -312.923392) (xy 282.046985 -312.874493)
			(xy 282.070328 -312.828681) (xy 282.100549 -312.787085) (xy 282.136905 -312.750729) (xy 282.178501 -312.720508)
			(xy 282.224313 -312.697165) (xy 282.273212 -312.681277) (xy 282.323994 -312.673234) (xy 282.37541 -312.673234)
			(xy 282.426192 -312.681277) (xy 282.475091 -312.697165) (xy 282.520903 -312.720508) (xy 282.562499 -312.750729)
			(xy 282.598855 -312.787085) (xy 282.629076 -312.828681) (xy 282.652419 -312.874493) (xy 282.668307 -312.923392)
			(xy 282.67635 -312.974174) (xy 282.676854 -312.999882) (xy 282.994112 -312.999882) (xy 282.998072 -312.950828)
			(xy 283.009849 -312.903044) (xy 283.02914 -312.857768) (xy 283.055443 -312.816172) (xy 283.088078 -312.779335)
			(xy 283.126199 -312.74821) (xy 283.16882 -312.723603) (xy 283.214836 -312.706151) (xy 283.263055 -312.696307)
			(xy 283.31223 -312.694326) (xy 283.361085 -312.700258) (xy 283.408356 -312.71395) (xy 283.452818 -312.735048)
			(xy 283.493321 -312.763004) (xy 283.528814 -312.797096) (xy 283.558379 -312.83644) (xy 283.58125 -312.880017)
			(xy 283.596834 -312.926698) (xy 283.604729 -312.975275) (xy 283.605224 -312.999882) (xy 283.604729 -313.024489)
			(xy 283.60455 -313.02559) (xy 283.923228 -313.02559) (xy 283.923228 -312.974174) (xy 283.931271 -312.923392)
			(xy 283.947159 -312.874493) (xy 283.970502 -312.828681) (xy 284.000723 -312.787085) (xy 284.037079 -312.750729)
			(xy 284.078675 -312.720508) (xy 284.124487 -312.697165) (xy 284.173386 -312.681277) (xy 284.224168 -312.673234)
			(xy 284.275584 -312.673234) (xy 284.326366 -312.681277) (xy 284.375265 -312.697165) (xy 284.421077 -312.720508)
			(xy 284.462673 -312.750729) (xy 284.499029 -312.787085) (xy 284.52925 -312.828681) (xy 284.552593 -312.874493)
			(xy 284.568481 -312.923392) (xy 284.576524 -312.974174) (xy 284.577028 -312.999882) (xy 284.894032 -312.999882)
			(xy 284.897992 -312.950828) (xy 284.909769 -312.903044) (xy 284.92906 -312.857768) (xy 284.955363 -312.816172)
			(xy 284.987998 -312.779335) (xy 285.026119 -312.74821) (xy 285.06874 -312.723603) (xy 285.114756 -312.706151)
			(xy 285.162975 -312.696307) (xy 285.21215 -312.694326) (xy 285.261005 -312.700258) (xy 285.308276 -312.71395)
			(xy 285.352738 -312.735048) (xy 285.393241 -312.763004) (xy 285.428734 -312.797096) (xy 285.458299 -312.83644)
			(xy 285.48117 -312.880017) (xy 285.496754 -312.926698) (xy 285.504649 -312.975275) (xy 285.505144 -312.999882)
			(xy 285.504649 -313.024489) (xy 285.50447 -313.02559) (xy 285.823148 -313.02559) (xy 285.823148 -312.974174)
			(xy 285.831191 -312.923392) (xy 285.847079 -312.874493) (xy 285.870422 -312.828681) (xy 285.900643 -312.787085)
			(xy 285.936999 -312.750729) (xy 285.978595 -312.720508) (xy 286.024407 -312.697165) (xy 286.073306 -312.681277)
			(xy 286.124088 -312.673234) (xy 286.175504 -312.673234) (xy 286.226286 -312.681277) (xy 286.275185 -312.697165)
			(xy 286.320997 -312.720508) (xy 286.362593 -312.750729) (xy 286.398949 -312.787085) (xy 286.42917 -312.828681)
			(xy 286.452513 -312.874493) (xy 286.468401 -312.923392) (xy 286.476444 -312.974174) (xy 286.476948 -312.999882)
			(xy 286.793952 -312.999882) (xy 286.797912 -312.950828) (xy 286.809689 -312.903044) (xy 286.82898 -312.857768)
			(xy 286.855283 -312.816172) (xy 286.887918 -312.779335) (xy 286.926039 -312.74821) (xy 286.96866 -312.723603)
			(xy 287.014676 -312.706151) (xy 287.062895 -312.696307) (xy 287.11207 -312.694326) (xy 287.160925 -312.700258)
			(xy 287.208196 -312.71395) (xy 287.252658 -312.735048) (xy 287.293161 -312.763004) (xy 287.328654 -312.797096)
			(xy 287.358219 -312.83644) (xy 287.38109 -312.880017) (xy 287.396674 -312.926698) (xy 287.404569 -312.975275)
			(xy 287.405064 -312.999882) (xy 287.404569 -313.024489) (xy 287.40439 -313.02559) (xy 287.723068 -313.02559)
			(xy 287.723068 -312.974174) (xy 287.731111 -312.923392) (xy 287.746999 -312.874493) (xy 287.770342 -312.828681)
			(xy 287.800563 -312.787085) (xy 287.836919 -312.750729) (xy 287.878515 -312.720508) (xy 287.924327 -312.697165)
			(xy 287.973226 -312.681277) (xy 288.024008 -312.673234) (xy 288.075424 -312.673234) (xy 288.126206 -312.681277)
			(xy 288.175105 -312.697165) (xy 288.220917 -312.720508) (xy 288.262513 -312.750729) (xy 288.298869 -312.787085)
			(xy 288.32909 -312.828681) (xy 288.352433 -312.874493) (xy 288.368321 -312.923392) (xy 288.376364 -312.974174)
			(xy 288.376868 -312.999882) (xy 288.694126 -312.999882) (xy 288.698086 -312.950828) (xy 288.709863 -312.903044)
			(xy 288.729154 -312.857768) (xy 288.755457 -312.816172) (xy 288.788092 -312.779335) (xy 288.826213 -312.74821)
			(xy 288.868834 -312.723603) (xy 288.91485 -312.706151) (xy 288.963069 -312.696307) (xy 289.012244 -312.694326)
			(xy 289.061099 -312.700258) (xy 289.10837 -312.71395) (xy 289.152832 -312.735048) (xy 289.193335 -312.763004)
			(xy 289.228828 -312.797096) (xy 289.258393 -312.83644) (xy 289.281264 -312.880017) (xy 289.296848 -312.926698)
			(xy 289.304743 -312.975275) (xy 289.305238 -312.999882) (xy 289.304743 -313.024489) (xy 289.304564 -313.02559)
			(xy 289.623242 -313.02559) (xy 289.623242 -312.974174) (xy 289.631285 -312.923392) (xy 289.647173 -312.874493)
			(xy 289.670516 -312.828681) (xy 289.700737 -312.787085) (xy 289.737093 -312.750729) (xy 289.778689 -312.720508)
			(xy 289.824501 -312.697165) (xy 289.8734 -312.681277) (xy 289.924182 -312.673234) (xy 289.975598 -312.673234)
			(xy 290.02638 -312.681277) (xy 290.075279 -312.697165) (xy 290.121091 -312.720508) (xy 290.162687 -312.750729)
			(xy 290.199043 -312.787085) (xy 290.229264 -312.828681) (xy 290.252607 -312.874493) (xy 290.268495 -312.923392)
			(xy 290.276538 -312.974174) (xy 290.277042 -312.999882) (xy 290.594046 -312.999882) (xy 290.598006 -312.950828)
			(xy 290.609783 -312.903044) (xy 290.629074 -312.857768) (xy 290.655377 -312.816172) (xy 290.688012 -312.779335)
			(xy 290.726133 -312.74821) (xy 290.768754 -312.723603) (xy 290.81477 -312.706151) (xy 290.862989 -312.696307)
			(xy 290.912164 -312.694326) (xy 290.961019 -312.700258) (xy 291.00829 -312.71395) (xy 291.052752 -312.735048)
			(xy 291.093255 -312.763004) (xy 291.128748 -312.797096) (xy 291.158313 -312.83644) (xy 291.181184 -312.880017)
			(xy 291.196768 -312.926698) (xy 291.204663 -312.975275) (xy 291.205158 -312.999882) (xy 291.204663 -313.024489)
			(xy 291.204484 -313.02559) (xy 291.523162 -313.02559) (xy 291.523162 -312.974174) (xy 291.531205 -312.923392)
			(xy 291.547093 -312.874493) (xy 291.570436 -312.828681) (xy 291.600657 -312.787085) (xy 291.637013 -312.750729)
			(xy 291.678609 -312.720508) (xy 291.724421 -312.697165) (xy 291.77332 -312.681277) (xy 291.824102 -312.673234)
			(xy 291.875518 -312.673234) (xy 291.9263 -312.681277) (xy 291.975199 -312.697165) (xy 292.021011 -312.720508)
			(xy 292.062607 -312.750729) (xy 292.098963 -312.787085) (xy 292.129184 -312.828681) (xy 292.152527 -312.874493)
			(xy 292.168415 -312.923392) (xy 292.176458 -312.974174) (xy 292.176962 -312.999882) (xy 292.493966 -312.999882)
			(xy 292.497926 -312.950828) (xy 292.509703 -312.903044) (xy 292.528994 -312.857768) (xy 292.555297 -312.816172)
			(xy 292.587932 -312.779335) (xy 292.626053 -312.74821) (xy 292.668674 -312.723603) (xy 292.71469 -312.706151)
			(xy 292.762909 -312.696307) (xy 292.812084 -312.694326) (xy 292.860939 -312.700258) (xy 292.90821 -312.71395)
			(xy 292.952672 -312.735048) (xy 292.993175 -312.763004) (xy 293.028668 -312.797096) (xy 293.058233 -312.83644)
			(xy 293.081104 -312.880017) (xy 293.096688 -312.926698) (xy 293.104583 -312.975275) (xy 293.105078 -312.999882)
			(xy 293.104583 -313.024489) (xy 293.104404 -313.02559) (xy 293.423082 -313.02559) (xy 293.423082 -312.974174)
			(xy 293.431125 -312.923392) (xy 293.447013 -312.874493) (xy 293.470356 -312.828681) (xy 293.500577 -312.787085)
			(xy 293.536933 -312.750729) (xy 293.578529 -312.720508) (xy 293.624341 -312.697165) (xy 293.67324 -312.681277)
			(xy 293.724022 -312.673234) (xy 293.775438 -312.673234) (xy 293.82622 -312.681277) (xy 293.875119 -312.697165)
			(xy 293.920931 -312.720508) (xy 293.962527 -312.750729) (xy 293.998883 -312.787085) (xy 294.029104 -312.828681)
			(xy 294.052447 -312.874493) (xy 294.068335 -312.923392) (xy 294.076378 -312.974174) (xy 294.076882 -312.999882)
			(xy 294.393886 -312.999882) (xy 294.397846 -312.950828) (xy 294.409623 -312.903044) (xy 294.428914 -312.857768)
			(xy 294.455217 -312.816172) (xy 294.487852 -312.779335) (xy 294.525973 -312.74821) (xy 294.568594 -312.723603)
			(xy 294.61461 -312.706151) (xy 294.662829 -312.696307) (xy 294.712004 -312.694326) (xy 294.760859 -312.700258)
			(xy 294.80813 -312.71395) (xy 294.852592 -312.735048) (xy 294.893095 -312.763004) (xy 294.928588 -312.797096)
			(xy 294.958153 -312.83644) (xy 294.981024 -312.880017) (xy 294.996608 -312.926698) (xy 295.004503 -312.975275)
			(xy 295.004998 -312.999882) (xy 295.004503 -313.024489) (xy 295.004324 -313.02559) (xy 295.323256 -313.02559)
			(xy 295.323256 -312.974174) (xy 295.331299 -312.923392) (xy 295.347187 -312.874493) (xy 295.37053 -312.828681)
			(xy 295.400751 -312.787085) (xy 295.437107 -312.750729) (xy 295.478703 -312.720508) (xy 295.524515 -312.697165)
			(xy 295.573414 -312.681277) (xy 295.624196 -312.673234) (xy 295.675612 -312.673234) (xy 295.726394 -312.681277)
			(xy 295.775293 -312.697165) (xy 295.821105 -312.720508) (xy 295.862701 -312.750729) (xy 295.899057 -312.787085)
			(xy 295.929278 -312.828681) (xy 295.952621 -312.874493) (xy 295.968509 -312.923392) (xy 295.976552 -312.974174)
			(xy 295.977056 -312.999882) (xy 296.29406 -312.999882) (xy 296.29802 -312.950828) (xy 296.309797 -312.903044)
			(xy 296.329088 -312.857768) (xy 296.355391 -312.816172) (xy 296.388026 -312.779335) (xy 296.426147 -312.74821)
			(xy 296.468768 -312.723603) (xy 296.514784 -312.706151) (xy 296.563003 -312.696307) (xy 296.612178 -312.694326)
			(xy 296.661033 -312.700258) (xy 296.708304 -312.71395) (xy 296.752766 -312.735048) (xy 296.793269 -312.763004)
			(xy 296.828762 -312.797096) (xy 296.858327 -312.83644) (xy 296.881198 -312.880017) (xy 296.896782 -312.926698)
			(xy 296.904677 -312.975275) (xy 296.905172 -312.999882) (xy 296.904677 -313.024489) (xy 296.904498 -313.02559)
			(xy 297.223176 -313.02559) (xy 297.223176 -312.974174) (xy 297.231219 -312.923392) (xy 297.247107 -312.874493)
			(xy 297.27045 -312.828681) (xy 297.300671 -312.787085) (xy 297.337027 -312.750729) (xy 297.378623 -312.720508)
			(xy 297.424435 -312.697165) (xy 297.473334 -312.681277) (xy 297.524116 -312.673234) (xy 297.575532 -312.673234)
			(xy 297.626314 -312.681277) (xy 297.675213 -312.697165) (xy 297.721025 -312.720508) (xy 297.762621 -312.750729)
			(xy 297.798977 -312.787085) (xy 297.829198 -312.828681) (xy 297.852541 -312.874493) (xy 297.868429 -312.923392)
			(xy 297.876472 -312.974174) (xy 297.876976 -312.999882) (xy 298.19398 -312.999882) (xy 298.19794 -312.950828)
			(xy 298.209717 -312.903044) (xy 298.229008 -312.857768) (xy 298.255311 -312.816172) (xy 298.287946 -312.779335)
			(xy 298.326067 -312.74821) (xy 298.368688 -312.723603) (xy 298.414704 -312.706151) (xy 298.462923 -312.696307)
			(xy 298.512098 -312.694326) (xy 298.560953 -312.700258) (xy 298.608224 -312.71395) (xy 298.652686 -312.735048)
			(xy 298.693189 -312.763004) (xy 298.728682 -312.797096) (xy 298.758247 -312.83644) (xy 298.781118 -312.880017)
			(xy 298.796702 -312.926698) (xy 298.804597 -312.975275) (xy 298.805092 -312.999882) (xy 298.804597 -313.024489)
			(xy 298.804418 -313.02559) (xy 299.123096 -313.02559) (xy 299.123096 -312.974174) (xy 299.131139 -312.923392)
			(xy 299.147027 -312.874493) (xy 299.17037 -312.828681) (xy 299.200591 -312.787085) (xy 299.236947 -312.750729)
			(xy 299.278543 -312.720508) (xy 299.324355 -312.697165) (xy 299.373254 -312.681277) (xy 299.424036 -312.673234)
			(xy 299.475452 -312.673234) (xy 299.526234 -312.681277) (xy 299.575133 -312.697165) (xy 299.620945 -312.720508)
			(xy 299.662541 -312.750729) (xy 299.698897 -312.787085) (xy 299.729118 -312.828681) (xy 299.752461 -312.874493)
			(xy 299.768349 -312.923392) (xy 299.776392 -312.974174) (xy 299.776896 -312.999882) (xy 299.776392 -313.02559)
			(xy 299.768349 -313.076372) (xy 299.752461 -313.125271) (xy 299.729118 -313.171083) (xy 299.698897 -313.212679)
			(xy 299.662541 -313.249035) (xy 299.620945 -313.279256) (xy 299.575133 -313.302599) (xy 299.526234 -313.318487)
			(xy 299.475452 -313.32653) (xy 299.424036 -313.32653) (xy 299.373254 -313.318487) (xy 299.324355 -313.302599)
			(xy 299.278543 -313.279256) (xy 299.236947 -313.249035) (xy 299.200591 -313.212679) (xy 299.17037 -313.171083)
			(xy 299.147027 -313.125271) (xy 299.131139 -313.076372) (xy 299.123096 -313.02559) (xy 298.804418 -313.02559)
			(xy 298.796702 -313.073066) (xy 298.781118 -313.119747) (xy 298.758247 -313.163324) (xy 298.728682 -313.202668)
			(xy 298.693189 -313.23676) (xy 298.652686 -313.264716) (xy 298.608224 -313.285814) (xy 298.560953 -313.299506)
			(xy 298.512098 -313.305438) (xy 298.462923 -313.303457) (xy 298.414704 -313.293613) (xy 298.368688 -313.276161)
			(xy 298.326067 -313.251554) (xy 298.287946 -313.220429) (xy 298.255311 -313.183592) (xy 298.229008 -313.141996)
			(xy 298.209717 -313.09672) (xy 298.19794 -313.048936) (xy 298.19398 -312.999882) (xy 297.876976 -312.999882)
			(xy 297.876472 -313.02559) (xy 297.868429 -313.076372) (xy 297.852541 -313.125271) (xy 297.829198 -313.171083)
			(xy 297.798977 -313.212679) (xy 297.762621 -313.249035) (xy 297.721025 -313.279256) (xy 297.675213 -313.302599)
			(xy 297.626314 -313.318487) (xy 297.575532 -313.32653) (xy 297.524116 -313.32653) (xy 297.473334 -313.318487)
			(xy 297.424435 -313.302599) (xy 297.378623 -313.279256) (xy 297.337027 -313.249035) (xy 297.300671 -313.212679)
			(xy 297.27045 -313.171083) (xy 297.247107 -313.125271) (xy 297.231219 -313.076372) (xy 297.223176 -313.02559)
			(xy 296.904498 -313.02559) (xy 296.896782 -313.073066) (xy 296.881198 -313.119747) (xy 296.858327 -313.163324)
			(xy 296.828762 -313.202668) (xy 296.793269 -313.23676) (xy 296.752766 -313.264716) (xy 296.708304 -313.285814)
			(xy 296.661033 -313.299506) (xy 296.612178 -313.305438) (xy 296.563003 -313.303457) (xy 296.514784 -313.293613)
			(xy 296.468768 -313.276161) (xy 296.426147 -313.251554) (xy 296.388026 -313.220429) (xy 296.355391 -313.183592)
			(xy 296.329088 -313.141996) (xy 296.309797 -313.09672) (xy 296.29802 -313.048936) (xy 296.29406 -312.999882)
			(xy 295.977056 -312.999882) (xy 295.976552 -313.02559) (xy 295.968509 -313.076372) (xy 295.952621 -313.125271)
			(xy 295.929278 -313.171083) (xy 295.899057 -313.212679) (xy 295.862701 -313.249035) (xy 295.821105 -313.279256)
			(xy 295.775293 -313.302599) (xy 295.726394 -313.318487) (xy 295.675612 -313.32653) (xy 295.624196 -313.32653)
			(xy 295.573414 -313.318487) (xy 295.524515 -313.302599) (xy 295.478703 -313.279256) (xy 295.437107 -313.249035)
			(xy 295.400751 -313.212679) (xy 295.37053 -313.171083) (xy 295.347187 -313.125271) (xy 295.331299 -313.076372)
			(xy 295.323256 -313.02559) (xy 295.004324 -313.02559) (xy 294.996608 -313.073066) (xy 294.981024 -313.119747)
			(xy 294.958153 -313.163324) (xy 294.928588 -313.202668) (xy 294.893095 -313.23676) (xy 294.852592 -313.264716)
			(xy 294.80813 -313.285814) (xy 294.760859 -313.299506) (xy 294.712004 -313.305438) (xy 294.662829 -313.303457)
			(xy 294.61461 -313.293613) (xy 294.568594 -313.276161) (xy 294.525973 -313.251554) (xy 294.487852 -313.220429)
			(xy 294.455217 -313.183592) (xy 294.428914 -313.141996) (xy 294.409623 -313.09672) (xy 294.397846 -313.048936)
			(xy 294.393886 -312.999882) (xy 294.076882 -312.999882) (xy 294.076378 -313.02559) (xy 294.068335 -313.076372)
			(xy 294.052447 -313.125271) (xy 294.029104 -313.171083) (xy 293.998883 -313.212679) (xy 293.962527 -313.249035)
			(xy 293.920931 -313.279256) (xy 293.875119 -313.302599) (xy 293.82622 -313.318487) (xy 293.775438 -313.32653)
			(xy 293.724022 -313.32653) (xy 293.67324 -313.318487) (xy 293.624341 -313.302599) (xy 293.578529 -313.279256)
			(xy 293.536933 -313.249035) (xy 293.500577 -313.212679) (xy 293.470356 -313.171083) (xy 293.447013 -313.125271)
			(xy 293.431125 -313.076372) (xy 293.423082 -313.02559) (xy 293.104404 -313.02559) (xy 293.096688 -313.073066)
			(xy 293.081104 -313.119747) (xy 293.058233 -313.163324) (xy 293.028668 -313.202668) (xy 292.993175 -313.23676)
			(xy 292.952672 -313.264716) (xy 292.90821 -313.285814) (xy 292.860939 -313.299506) (xy 292.812084 -313.305438)
			(xy 292.762909 -313.303457) (xy 292.71469 -313.293613) (xy 292.668674 -313.276161) (xy 292.626053 -313.251554)
			(xy 292.587932 -313.220429) (xy 292.555297 -313.183592) (xy 292.528994 -313.141996) (xy 292.509703 -313.09672)
			(xy 292.497926 -313.048936) (xy 292.493966 -312.999882) (xy 292.176962 -312.999882) (xy 292.176458 -313.02559)
			(xy 292.168415 -313.076372) (xy 292.152527 -313.125271) (xy 292.129184 -313.171083) (xy 292.098963 -313.212679)
			(xy 292.062607 -313.249035) (xy 292.021011 -313.279256) (xy 291.975199 -313.302599) (xy 291.9263 -313.318487)
			(xy 291.875518 -313.32653) (xy 291.824102 -313.32653) (xy 291.77332 -313.318487) (xy 291.724421 -313.302599)
			(xy 291.678609 -313.279256) (xy 291.637013 -313.249035) (xy 291.600657 -313.212679) (xy 291.570436 -313.171083)
			(xy 291.547093 -313.125271) (xy 291.531205 -313.076372) (xy 291.523162 -313.02559) (xy 291.204484 -313.02559)
			(xy 291.196768 -313.073066) (xy 291.181184 -313.119747) (xy 291.158313 -313.163324) (xy 291.128748 -313.202668)
			(xy 291.093255 -313.23676) (xy 291.052752 -313.264716) (xy 291.00829 -313.285814) (xy 290.961019 -313.299506)
			(xy 290.912164 -313.305438) (xy 290.862989 -313.303457) (xy 290.81477 -313.293613) (xy 290.768754 -313.276161)
			(xy 290.726133 -313.251554) (xy 290.688012 -313.220429) (xy 290.655377 -313.183592) (xy 290.629074 -313.141996)
			(xy 290.609783 -313.09672) (xy 290.598006 -313.048936) (xy 290.594046 -312.999882) (xy 290.277042 -312.999882)
			(xy 290.276538 -313.02559) (xy 290.268495 -313.076372) (xy 290.252607 -313.125271) (xy 290.229264 -313.171083)
			(xy 290.199043 -313.212679) (xy 290.162687 -313.249035) (xy 290.121091 -313.279256) (xy 290.075279 -313.302599)
			(xy 290.02638 -313.318487) (xy 289.975598 -313.32653) (xy 289.924182 -313.32653) (xy 289.8734 -313.318487)
			(xy 289.824501 -313.302599) (xy 289.778689 -313.279256) (xy 289.737093 -313.249035) (xy 289.700737 -313.212679)
			(xy 289.670516 -313.171083) (xy 289.647173 -313.125271) (xy 289.631285 -313.076372) (xy 289.623242 -313.02559)
			(xy 289.304564 -313.02559) (xy 289.296848 -313.073066) (xy 289.281264 -313.119747) (xy 289.258393 -313.163324)
			(xy 289.228828 -313.202668) (xy 289.193335 -313.23676) (xy 289.152832 -313.264716) (xy 289.10837 -313.285814)
			(xy 289.061099 -313.299506) (xy 289.012244 -313.305438) (xy 288.963069 -313.303457) (xy 288.91485 -313.293613)
			(xy 288.868834 -313.276161) (xy 288.826213 -313.251554) (xy 288.788092 -313.220429) (xy 288.755457 -313.183592)
			(xy 288.729154 -313.141996) (xy 288.709863 -313.09672) (xy 288.698086 -313.048936) (xy 288.694126 -312.999882)
			(xy 288.376868 -312.999882) (xy 288.376364 -313.02559) (xy 288.368321 -313.076372) (xy 288.352433 -313.125271)
			(xy 288.32909 -313.171083) (xy 288.298869 -313.212679) (xy 288.262513 -313.249035) (xy 288.220917 -313.279256)
			(xy 288.175105 -313.302599) (xy 288.126206 -313.318487) (xy 288.075424 -313.32653) (xy 288.024008 -313.32653)
			(xy 287.973226 -313.318487) (xy 287.924327 -313.302599) (xy 287.878515 -313.279256) (xy 287.836919 -313.249035)
			(xy 287.800563 -313.212679) (xy 287.770342 -313.171083) (xy 287.746999 -313.125271) (xy 287.731111 -313.076372)
			(xy 287.723068 -313.02559) (xy 287.40439 -313.02559) (xy 287.396674 -313.073066) (xy 287.38109 -313.119747)
			(xy 287.358219 -313.163324) (xy 287.328654 -313.202668) (xy 287.293161 -313.23676) (xy 287.252658 -313.264716)
			(xy 287.208196 -313.285814) (xy 287.160925 -313.299506) (xy 287.11207 -313.305438) (xy 287.062895 -313.303457)
			(xy 287.014676 -313.293613) (xy 286.96866 -313.276161) (xy 286.926039 -313.251554) (xy 286.887918 -313.220429)
			(xy 286.855283 -313.183592) (xy 286.82898 -313.141996) (xy 286.809689 -313.09672) (xy 286.797912 -313.048936)
			(xy 286.793952 -312.999882) (xy 286.476948 -312.999882) (xy 286.476444 -313.02559) (xy 286.468401 -313.076372)
			(xy 286.452513 -313.125271) (xy 286.42917 -313.171083) (xy 286.398949 -313.212679) (xy 286.362593 -313.249035)
			(xy 286.320997 -313.279256) (xy 286.275185 -313.302599) (xy 286.226286 -313.318487) (xy 286.175504 -313.32653)
			(xy 286.124088 -313.32653) (xy 286.073306 -313.318487) (xy 286.024407 -313.302599) (xy 285.978595 -313.279256)
			(xy 285.936999 -313.249035) (xy 285.900643 -313.212679) (xy 285.870422 -313.171083) (xy 285.847079 -313.125271)
			(xy 285.831191 -313.076372) (xy 285.823148 -313.02559) (xy 285.50447 -313.02559) (xy 285.496754 -313.073066)
			(xy 285.48117 -313.119747) (xy 285.458299 -313.163324) (xy 285.428734 -313.202668) (xy 285.393241 -313.23676)
			(xy 285.352738 -313.264716) (xy 285.308276 -313.285814) (xy 285.261005 -313.299506) (xy 285.21215 -313.305438)
			(xy 285.162975 -313.303457) (xy 285.114756 -313.293613) (xy 285.06874 -313.276161) (xy 285.026119 -313.251554)
			(xy 284.987998 -313.220429) (xy 284.955363 -313.183592) (xy 284.92906 -313.141996) (xy 284.909769 -313.09672)
			(xy 284.897992 -313.048936) (xy 284.894032 -312.999882) (xy 284.577028 -312.999882) (xy 284.576524 -313.02559)
			(xy 284.568481 -313.076372) (xy 284.552593 -313.125271) (xy 284.52925 -313.171083) (xy 284.499029 -313.212679)
			(xy 284.462673 -313.249035) (xy 284.421077 -313.279256) (xy 284.375265 -313.302599) (xy 284.326366 -313.318487)
			(xy 284.275584 -313.32653) (xy 284.224168 -313.32653) (xy 284.173386 -313.318487) (xy 284.124487 -313.302599)
			(xy 284.078675 -313.279256) (xy 284.037079 -313.249035) (xy 284.000723 -313.212679) (xy 283.970502 -313.171083)
			(xy 283.947159 -313.125271) (xy 283.931271 -313.076372) (xy 283.923228 -313.02559) (xy 283.60455 -313.02559)
			(xy 283.596834 -313.073066) (xy 283.58125 -313.119747) (xy 283.558379 -313.163324) (xy 283.528814 -313.202668)
			(xy 283.493321 -313.23676) (xy 283.452818 -313.264716) (xy 283.408356 -313.285814) (xy 283.361085 -313.299506)
			(xy 283.31223 -313.305438) (xy 283.263055 -313.303457) (xy 283.214836 -313.293613) (xy 283.16882 -313.276161)
			(xy 283.126199 -313.251554) (xy 283.088078 -313.220429) (xy 283.055443 -313.183592) (xy 283.02914 -313.141996)
			(xy 283.009849 -313.09672) (xy 282.998072 -313.048936) (xy 282.994112 -312.999882) (xy 282.676854 -312.999882)
			(xy 282.67635 -313.02559) (xy 282.668307 -313.076372) (xy 282.652419 -313.125271) (xy 282.629076 -313.171083)
			(xy 282.598855 -313.212679) (xy 282.562499 -313.249035) (xy 282.520903 -313.279256) (xy 282.475091 -313.302599)
			(xy 282.426192 -313.318487) (xy 282.37541 -313.32653) (xy 282.323994 -313.32653) (xy 282.273212 -313.318487)
			(xy 282.224313 -313.302599) (xy 282.178501 -313.279256) (xy 282.136905 -313.249035) (xy 282.100549 -313.212679)
			(xy 282.070328 -313.171083) (xy 282.046985 -313.125271) (xy 282.031097 -313.076372) (xy 282.023054 -313.02559)
			(xy 281.704376 -313.02559) (xy 281.69666 -313.073066) (xy 281.681076 -313.119747) (xy 281.658205 -313.163324)
			(xy 281.62864 -313.202668) (xy 281.593147 -313.23676) (xy 281.552644 -313.264716) (xy 281.508182 -313.285814)
			(xy 281.460911 -313.299506) (xy 281.412056 -313.305438) (xy 281.362881 -313.303457) (xy 281.314662 -313.293613)
			(xy 281.268646 -313.276161) (xy 281.226025 -313.251554) (xy 281.187904 -313.220429) (xy 281.155269 -313.183592)
			(xy 281.128966 -313.141996) (xy 281.109675 -313.09672) (xy 281.097898 -313.048936) (xy 281.093938 -312.999882)
			(xy 280.776934 -312.999882) (xy 280.77643 -313.02559) (xy 280.768387 -313.076372) (xy 280.752499 -313.125271)
			(xy 280.729156 -313.171083) (xy 280.698935 -313.212679) (xy 280.662579 -313.249035) (xy 280.620983 -313.279256)
			(xy 280.575171 -313.302599) (xy 280.526272 -313.318487) (xy 280.47549 -313.32653) (xy 280.424074 -313.32653)
			(xy 280.373292 -313.318487) (xy 280.324393 -313.302599) (xy 280.278581 -313.279256) (xy 280.236985 -313.249035)
			(xy 280.200629 -313.212679) (xy 280.170408 -313.171083) (xy 280.147065 -313.125271) (xy 280.131177 -313.076372)
			(xy 280.123134 -313.02559) (xy 279.804456 -313.02559) (xy 279.79674 -313.073066) (xy 279.781156 -313.119747)
			(xy 279.758285 -313.163324) (xy 279.72872 -313.202668) (xy 279.693227 -313.23676) (xy 279.652724 -313.264716)
			(xy 279.608262 -313.285814) (xy 279.560991 -313.299506) (xy 279.512136 -313.305438) (xy 279.462961 -313.303457)
			(xy 279.414742 -313.293613) (xy 279.368726 -313.276161) (xy 279.326105 -313.251554) (xy 279.287984 -313.220429)
			(xy 279.255349 -313.183592) (xy 279.229046 -313.141996) (xy 279.209755 -313.09672) (xy 279.197978 -313.048936)
			(xy 279.194018 -312.999882) (xy 278.877014 -312.999882) (xy 278.87651 -313.02559) (xy 278.868467 -313.076372)
			(xy 278.852579 -313.125271) (xy 278.829236 -313.171083) (xy 278.799015 -313.212679) (xy 278.762659 -313.249035)
			(xy 278.721063 -313.279256) (xy 278.675251 -313.302599) (xy 278.626352 -313.318487) (xy 278.57557 -313.32653)
			(xy 278.524154 -313.32653) (xy 278.473372 -313.318487) (xy 278.424473 -313.302599) (xy 278.378661 -313.279256)
			(xy 278.337065 -313.249035) (xy 278.300709 -313.212679) (xy 278.270488 -313.171083) (xy 278.247145 -313.125271)
			(xy 278.231257 -313.076372) (xy 278.223214 -313.02559) (xy 277.904536 -313.02559) (xy 277.89682 -313.073066)
			(xy 277.881236 -313.119747) (xy 277.858365 -313.163324) (xy 277.8288 -313.202668) (xy 277.793307 -313.23676)
			(xy 277.752804 -313.264716) (xy 277.708342 -313.285814) (xy 277.661071 -313.299506) (xy 277.612216 -313.305438)
			(xy 277.563041 -313.303457) (xy 277.514822 -313.293613) (xy 277.468806 -313.276161) (xy 277.426185 -313.251554)
			(xy 277.388064 -313.220429) (xy 277.355429 -313.183592) (xy 277.329126 -313.141996) (xy 277.309835 -313.09672)
			(xy 277.298058 -313.048936) (xy 277.294098 -312.999882) (xy 276.97684 -312.999882) (xy 276.976336 -313.02559)
			(xy 276.968293 -313.076372) (xy 276.952405 -313.125271) (xy 276.929062 -313.171083) (xy 276.898841 -313.212679)
			(xy 276.862485 -313.249035) (xy 276.820889 -313.279256) (xy 276.775077 -313.302599) (xy 276.726178 -313.318487)
			(xy 276.675396 -313.32653) (xy 276.62398 -313.32653) (xy 276.573198 -313.318487) (xy 276.524299 -313.302599)
			(xy 276.478487 -313.279256) (xy 276.436891 -313.249035) (xy 276.400535 -313.212679) (xy 276.370314 -313.171083)
			(xy 276.346971 -313.125271) (xy 276.331083 -313.076372) (xy 276.32304 -313.02559) (xy 276.004362 -313.02559)
			(xy 275.996646 -313.073066) (xy 275.981062 -313.119747) (xy 275.958191 -313.163324) (xy 275.928626 -313.202668)
			(xy 275.893133 -313.23676) (xy 275.85263 -313.264716) (xy 275.808168 -313.285814) (xy 275.760897 -313.299506)
			(xy 275.712042 -313.305438) (xy 275.662867 -313.303457) (xy 275.614648 -313.293613) (xy 275.568632 -313.276161)
			(xy 275.526011 -313.251554) (xy 275.48789 -313.220429) (xy 275.455255 -313.183592) (xy 275.428952 -313.141996)
			(xy 275.409661 -313.09672) (xy 275.397884 -313.048936) (xy 275.393924 -312.999882) (xy 275.07692 -312.999882)
			(xy 275.076416 -313.02559) (xy 275.068373 -313.076372) (xy 275.052485 -313.125271) (xy 275.029142 -313.171083)
			(xy 274.998921 -313.212679) (xy 274.962565 -313.249035) (xy 274.920969 -313.279256) (xy 274.875157 -313.302599)
			(xy 274.826258 -313.318487) (xy 274.775476 -313.32653) (xy 274.72406 -313.32653) (xy 274.673278 -313.318487)
			(xy 274.624379 -313.302599) (xy 274.578567 -313.279256) (xy 274.536971 -313.249035) (xy 274.500615 -313.212679)
			(xy 274.470394 -313.171083) (xy 274.447051 -313.125271) (xy 274.431163 -313.076372) (xy 274.42312 -313.02559)
			(xy 274.104442 -313.02559) (xy 274.096726 -313.073066) (xy 274.081142 -313.119747) (xy 274.058271 -313.163324)
			(xy 274.028706 -313.202668) (xy 273.993213 -313.23676) (xy 273.95271 -313.264716) (xy 273.908248 -313.285814)
			(xy 273.860977 -313.299506) (xy 273.812122 -313.305438) (xy 273.762947 -313.303457) (xy 273.714728 -313.293613)
			(xy 273.668712 -313.276161) (xy 273.626091 -313.251554) (xy 273.58797 -313.220429) (xy 273.555335 -313.183592)
			(xy 273.529032 -313.141996) (xy 273.509741 -313.09672) (xy 273.497964 -313.048936) (xy 273.494004 -312.999882)
			(xy 273.177 -312.999882) (xy 273.176496 -313.02559) (xy 273.168453 -313.076372) (xy 273.152565 -313.125271)
			(xy 273.129222 -313.171083) (xy 273.099001 -313.212679) (xy 273.062645 -313.249035) (xy 273.021049 -313.279256)
			(xy 272.975237 -313.302599) (xy 272.926338 -313.318487) (xy 272.875556 -313.32653) (xy 272.82414 -313.32653)
			(xy 272.773358 -313.318487) (xy 272.724459 -313.302599) (xy 272.678647 -313.279256) (xy 272.637051 -313.249035)
			(xy 272.600695 -313.212679) (xy 272.570474 -313.171083) (xy 272.547131 -313.125271) (xy 272.531243 -313.076372)
			(xy 272.5232 -313.02559) (xy 272.204522 -313.02559) (xy 272.196806 -313.073066) (xy 272.181222 -313.119747)
			(xy 272.158351 -313.163324) (xy 272.128786 -313.202668) (xy 272.093293 -313.23676) (xy 272.05279 -313.264716)
			(xy 272.008328 -313.285814) (xy 271.961057 -313.299506) (xy 271.912202 -313.305438) (xy 271.863027 -313.303457)
			(xy 271.814808 -313.293613) (xy 271.768792 -313.276161) (xy 271.726171 -313.251554) (xy 271.68805 -313.220429)
			(xy 271.655415 -313.183592) (xy 271.629112 -313.141996) (xy 271.609821 -313.09672) (xy 271.598044 -313.048936)
			(xy 271.594084 -312.999882) (xy 271.27708 -312.999882) (xy 271.276576 -313.02559) (xy 271.268533 -313.076372)
			(xy 271.252645 -313.125271) (xy 271.229302 -313.171083) (xy 271.199081 -313.212679) (xy 271.162725 -313.249035)
			(xy 271.121129 -313.279256) (xy 271.075317 -313.302599) (xy 271.026418 -313.318487) (xy 270.975636 -313.32653)
			(xy 270.92422 -313.32653) (xy 270.873438 -313.318487) (xy 270.824539 -313.302599) (xy 270.778727 -313.279256)
			(xy 270.737131 -313.249035) (xy 270.700775 -313.212679) (xy 270.670554 -313.171083) (xy 270.647211 -313.125271)
			(xy 270.631323 -313.076372) (xy 270.62328 -313.02559) (xy 270.304348 -313.02559) (xy 270.296632 -313.073066)
			(xy 270.281048 -313.119747) (xy 270.258177 -313.163324) (xy 270.228612 -313.202668) (xy 270.193119 -313.23676)
			(xy 270.152616 -313.264716) (xy 270.108154 -313.285814) (xy 270.060883 -313.299506) (xy 270.012028 -313.305438)
			(xy 269.962853 -313.303457) (xy 269.914634 -313.293613) (xy 269.868618 -313.276161) (xy 269.825997 -313.251554)
			(xy 269.787876 -313.220429) (xy 269.755241 -313.183592) (xy 269.728938 -313.141996) (xy 269.709647 -313.09672)
			(xy 269.69787 -313.048936) (xy 269.69391 -312.999882) (xy 269.355062 -312.999882) (xy 269.354567 -313.024489)
			(xy 269.346672 -313.073066) (xy 269.331088 -313.119747) (xy 269.308217 -313.163324) (xy 269.278652 -313.202668)
			(xy 269.243159 -313.23676) (xy 269.202656 -313.264716) (xy 269.158194 -313.285814) (xy 269.110923 -313.299506)
			(xy 269.062068 -313.305438) (xy 269.012893 -313.303457) (xy 268.964674 -313.293613) (xy 268.918658 -313.276161)
			(xy 268.876037 -313.251554) (xy 268.837916 -313.220429) (xy 268.805281 -313.183592) (xy 268.778978 -313.141996)
			(xy 268.759687 -313.09672) (xy 268.74791 -313.048936) (xy 268.74395 -312.999882) (xy 255.945132 -312.999882)
			(xy 255.945132 -313.669934) (xy 266.246862 -313.669934) (xy 266.250933 -313.614312) (xy 266.263059 -313.559875)
			(xy 266.282982 -313.507784) (xy 266.310278 -313.459149) (xy 266.344364 -313.415006) (xy 266.384513 -313.376297)
			(xy 266.429871 -313.343846) (xy 266.479471 -313.318345) (xy 266.532255 -313.300338) (xy 266.587098 -313.290208)
			(xy 266.642832 -313.288171) (xy 266.698269 -313.294271) (xy 266.752226 -313.308377) (xy 266.803555 -313.330189)
			(xy 266.851161 -313.359243) (xy 266.894029 -313.394918) (xy 266.931246 -313.436455) (xy 266.962019 -313.482968)
			(xy 266.985691 -313.533465) (xy 267.001759 -313.586872) (xy 267.009879 -313.642048) (xy 267.010388 -313.669934)
			(xy 267.009879 -313.69782) (xy 267.001759 -313.752996) (xy 266.985691 -313.806403) (xy 266.962019 -313.8569)
			(xy 266.931246 -313.903413) (xy 266.894029 -313.94495) (xy 266.888151 -313.949842) (xy 268.74395 -313.949842)
			(xy 268.74791 -313.900788) (xy 268.759687 -313.853004) (xy 268.778978 -313.807728) (xy 268.805281 -313.766132)
			(xy 268.837916 -313.729295) (xy 268.876037 -313.69817) (xy 268.918658 -313.673563) (xy 268.964674 -313.656111)
			(xy 269.012893 -313.646267) (xy 269.062068 -313.644286) (xy 269.110923 -313.650218) (xy 269.158194 -313.66391)
			(xy 269.202656 -313.685008) (xy 269.243159 -313.712964) (xy 269.278652 -313.747056) (xy 269.308217 -313.7864)
			(xy 269.331088 -313.829977) (xy 269.346672 -313.876658) (xy 269.354567 -313.925235) (xy 269.355062 -313.949842)
			(xy 269.69391 -313.949842) (xy 269.69787 -313.900788) (xy 269.709647 -313.853004) (xy 269.728938 -313.807728)
			(xy 269.755241 -313.766132) (xy 269.787876 -313.729295) (xy 269.825997 -313.69817) (xy 269.868618 -313.673563)
			(xy 269.914634 -313.656111) (xy 269.962853 -313.646267) (xy 270.012028 -313.644286) (xy 270.060883 -313.650218)
			(xy 270.108154 -313.66391) (xy 270.152616 -313.685008) (xy 270.193119 -313.712964) (xy 270.228612 -313.747056)
			(xy 270.258177 -313.7864) (xy 270.281048 -313.829977) (xy 270.296632 -313.876658) (xy 270.304527 -313.925235)
			(xy 270.305022 -313.949842) (xy 270.304527 -313.974449) (xy 270.304348 -313.97555) (xy 270.62328 -313.97555)
			(xy 270.62328 -313.924134) (xy 270.631323 -313.873352) (xy 270.647211 -313.824453) (xy 270.670554 -313.778641)
			(xy 270.700775 -313.737045) (xy 270.737131 -313.700689) (xy 270.778727 -313.670468) (xy 270.824539 -313.647125)
			(xy 270.873438 -313.631237) (xy 270.92422 -313.623194) (xy 270.975636 -313.623194) (xy 271.026418 -313.631237)
			(xy 271.075317 -313.647125) (xy 271.121129 -313.670468) (xy 271.162725 -313.700689) (xy 271.199081 -313.737045)
			(xy 271.229302 -313.778641) (xy 271.252645 -313.824453) (xy 271.268533 -313.873352) (xy 271.276576 -313.924134)
			(xy 271.27708 -313.949842) (xy 271.594084 -313.949842) (xy 271.598044 -313.900788) (xy 271.609821 -313.853004)
			(xy 271.629112 -313.807728) (xy 271.655415 -313.766132) (xy 271.68805 -313.729295) (xy 271.726171 -313.69817)
			(xy 271.768792 -313.673563) (xy 271.814808 -313.656111) (xy 271.863027 -313.646267) (xy 271.912202 -313.644286)
			(xy 271.961057 -313.650218) (xy 272.008328 -313.66391) (xy 272.05279 -313.685008) (xy 272.093293 -313.712964)
			(xy 272.128786 -313.747056) (xy 272.158351 -313.7864) (xy 272.181222 -313.829977) (xy 272.196806 -313.876658)
			(xy 272.204701 -313.925235) (xy 272.205196 -313.949842) (xy 272.204701 -313.974449) (xy 272.204522 -313.97555)
			(xy 272.5232 -313.97555) (xy 272.5232 -313.924134) (xy 272.531243 -313.873352) (xy 272.547131 -313.824453)
			(xy 272.570474 -313.778641) (xy 272.600695 -313.737045) (xy 272.637051 -313.700689) (xy 272.678647 -313.670468)
			(xy 272.724459 -313.647125) (xy 272.773358 -313.631237) (xy 272.82414 -313.623194) (xy 272.875556 -313.623194)
			(xy 272.926338 -313.631237) (xy 272.975237 -313.647125) (xy 273.021049 -313.670468) (xy 273.062645 -313.700689)
			(xy 273.099001 -313.737045) (xy 273.129222 -313.778641) (xy 273.152565 -313.824453) (xy 273.168453 -313.873352)
			(xy 273.176496 -313.924134) (xy 273.177 -313.949842) (xy 273.494004 -313.949842) (xy 273.497964 -313.900788)
			(xy 273.509741 -313.853004) (xy 273.529032 -313.807728) (xy 273.555335 -313.766132) (xy 273.58797 -313.729295)
			(xy 273.626091 -313.69817) (xy 273.668712 -313.673563) (xy 273.714728 -313.656111) (xy 273.762947 -313.646267)
			(xy 273.812122 -313.644286) (xy 273.860977 -313.650218) (xy 273.908248 -313.66391) (xy 273.95271 -313.685008)
			(xy 273.993213 -313.712964) (xy 274.028706 -313.747056) (xy 274.058271 -313.7864) (xy 274.081142 -313.829977)
			(xy 274.096726 -313.876658) (xy 274.104621 -313.925235) (xy 274.105116 -313.949842) (xy 274.104621 -313.974449)
			(xy 274.104442 -313.97555) (xy 274.42312 -313.97555) (xy 274.42312 -313.924134) (xy 274.431163 -313.873352)
			(xy 274.447051 -313.824453) (xy 274.470394 -313.778641) (xy 274.500615 -313.737045) (xy 274.536971 -313.700689)
			(xy 274.578567 -313.670468) (xy 274.624379 -313.647125) (xy 274.673278 -313.631237) (xy 274.72406 -313.623194)
			(xy 274.775476 -313.623194) (xy 274.826258 -313.631237) (xy 274.875157 -313.647125) (xy 274.920969 -313.670468)
			(xy 274.962565 -313.700689) (xy 274.998921 -313.737045) (xy 275.029142 -313.778641) (xy 275.052485 -313.824453)
			(xy 275.068373 -313.873352) (xy 275.076416 -313.924134) (xy 275.07692 -313.949842) (xy 275.393924 -313.949842)
			(xy 275.397884 -313.900788) (xy 275.409661 -313.853004) (xy 275.428952 -313.807728) (xy 275.455255 -313.766132)
			(xy 275.48789 -313.729295) (xy 275.526011 -313.69817) (xy 275.568632 -313.673563) (xy 275.614648 -313.656111)
			(xy 275.662867 -313.646267) (xy 275.712042 -313.644286) (xy 275.760897 -313.650218) (xy 275.808168 -313.66391)
			(xy 275.85263 -313.685008) (xy 275.893133 -313.712964) (xy 275.928626 -313.747056) (xy 275.958191 -313.7864)
			(xy 275.981062 -313.829977) (xy 275.996646 -313.876658) (xy 276.004541 -313.925235) (xy 276.005036 -313.949842)
			(xy 276.004541 -313.974449) (xy 276.004362 -313.97555) (xy 276.32304 -313.97555) (xy 276.32304 -313.924134)
			(xy 276.331083 -313.873352) (xy 276.346971 -313.824453) (xy 276.370314 -313.778641) (xy 276.400535 -313.737045)
			(xy 276.436891 -313.700689) (xy 276.478487 -313.670468) (xy 276.524299 -313.647125) (xy 276.573198 -313.631237)
			(xy 276.62398 -313.623194) (xy 276.675396 -313.623194) (xy 276.726178 -313.631237) (xy 276.775077 -313.647125)
			(xy 276.820889 -313.670468) (xy 276.862485 -313.700689) (xy 276.898841 -313.737045) (xy 276.929062 -313.778641)
			(xy 276.952405 -313.824453) (xy 276.968293 -313.873352) (xy 276.976336 -313.924134) (xy 276.97684 -313.949842)
			(xy 277.294098 -313.949842) (xy 277.298058 -313.900788) (xy 277.309835 -313.853004) (xy 277.329126 -313.807728)
			(xy 277.355429 -313.766132) (xy 277.388064 -313.729295) (xy 277.426185 -313.69817) (xy 277.468806 -313.673563)
			(xy 277.514822 -313.656111) (xy 277.563041 -313.646267) (xy 277.612216 -313.644286) (xy 277.661071 -313.650218)
			(xy 277.708342 -313.66391) (xy 277.752804 -313.685008) (xy 277.793307 -313.712964) (xy 277.8288 -313.747056)
			(xy 277.858365 -313.7864) (xy 277.881236 -313.829977) (xy 277.89682 -313.876658) (xy 277.904715 -313.925235)
			(xy 277.90521 -313.949842) (xy 277.904715 -313.974449) (xy 277.904536 -313.97555) (xy 278.223214 -313.97555)
			(xy 278.223214 -313.924134) (xy 278.231257 -313.873352) (xy 278.247145 -313.824453) (xy 278.270488 -313.778641)
			(xy 278.300709 -313.737045) (xy 278.337065 -313.700689) (xy 278.378661 -313.670468) (xy 278.424473 -313.647125)
			(xy 278.473372 -313.631237) (xy 278.524154 -313.623194) (xy 278.57557 -313.623194) (xy 278.626352 -313.631237)
			(xy 278.675251 -313.647125) (xy 278.721063 -313.670468) (xy 278.762659 -313.700689) (xy 278.799015 -313.737045)
			(xy 278.829236 -313.778641) (xy 278.852579 -313.824453) (xy 278.868467 -313.873352) (xy 278.87651 -313.924134)
			(xy 278.877014 -313.949842) (xy 279.194018 -313.949842) (xy 279.197978 -313.900788) (xy 279.209755 -313.853004)
			(xy 279.229046 -313.807728) (xy 279.255349 -313.766132) (xy 279.287984 -313.729295) (xy 279.326105 -313.69817)
			(xy 279.368726 -313.673563) (xy 279.414742 -313.656111) (xy 279.462961 -313.646267) (xy 279.512136 -313.644286)
			(xy 279.560991 -313.650218) (xy 279.608262 -313.66391) (xy 279.652724 -313.685008) (xy 279.693227 -313.712964)
			(xy 279.72872 -313.747056) (xy 279.758285 -313.7864) (xy 279.781156 -313.829977) (xy 279.79674 -313.876658)
			(xy 279.804635 -313.925235) (xy 279.80513 -313.949842) (xy 279.804635 -313.974449) (xy 279.804456 -313.97555)
			(xy 280.123134 -313.97555) (xy 280.123134 -313.924134) (xy 280.131177 -313.873352) (xy 280.147065 -313.824453)
			(xy 280.170408 -313.778641) (xy 280.200629 -313.737045) (xy 280.236985 -313.700689) (xy 280.278581 -313.670468)
			(xy 280.324393 -313.647125) (xy 280.373292 -313.631237) (xy 280.424074 -313.623194) (xy 280.47549 -313.623194)
			(xy 280.526272 -313.631237) (xy 280.575171 -313.647125) (xy 280.620983 -313.670468) (xy 280.662579 -313.700689)
			(xy 280.698935 -313.737045) (xy 280.729156 -313.778641) (xy 280.752499 -313.824453) (xy 280.768387 -313.873352)
			(xy 280.77643 -313.924134) (xy 280.776934 -313.949842) (xy 281.093938 -313.949842) (xy 281.097898 -313.900788)
			(xy 281.109675 -313.853004) (xy 281.128966 -313.807728) (xy 281.155269 -313.766132) (xy 281.187904 -313.729295)
			(xy 281.226025 -313.69817) (xy 281.268646 -313.673563) (xy 281.314662 -313.656111) (xy 281.362881 -313.646267)
			(xy 281.412056 -313.644286) (xy 281.460911 -313.650218) (xy 281.508182 -313.66391) (xy 281.552644 -313.685008)
			(xy 281.593147 -313.712964) (xy 281.62864 -313.747056) (xy 281.658205 -313.7864) (xy 281.681076 -313.829977)
			(xy 281.69666 -313.876658) (xy 281.704555 -313.925235) (xy 281.70505 -313.949842) (xy 281.704555 -313.974449)
			(xy 281.704376 -313.97555) (xy 282.023054 -313.97555) (xy 282.023054 -313.924134) (xy 282.031097 -313.873352)
			(xy 282.046985 -313.824453) (xy 282.070328 -313.778641) (xy 282.100549 -313.737045) (xy 282.136905 -313.700689)
			(xy 282.178501 -313.670468) (xy 282.224313 -313.647125) (xy 282.273212 -313.631237) (xy 282.323994 -313.623194)
			(xy 282.37541 -313.623194) (xy 282.426192 -313.631237) (xy 282.475091 -313.647125) (xy 282.520903 -313.670468)
			(xy 282.562499 -313.700689) (xy 282.598855 -313.737045) (xy 282.629076 -313.778641) (xy 282.652419 -313.824453)
			(xy 282.668307 -313.873352) (xy 282.67635 -313.924134) (xy 282.676854 -313.949842) (xy 282.994112 -313.949842)
			(xy 282.998072 -313.900788) (xy 283.009849 -313.853004) (xy 283.02914 -313.807728) (xy 283.055443 -313.766132)
			(xy 283.088078 -313.729295) (xy 283.126199 -313.69817) (xy 283.16882 -313.673563) (xy 283.214836 -313.656111)
			(xy 283.263055 -313.646267) (xy 283.31223 -313.644286) (xy 283.361085 -313.650218) (xy 283.408356 -313.66391)
			(xy 283.452818 -313.685008) (xy 283.493321 -313.712964) (xy 283.528814 -313.747056) (xy 283.558379 -313.7864)
			(xy 283.58125 -313.829977) (xy 283.596834 -313.876658) (xy 283.604729 -313.925235) (xy 283.605224 -313.949842)
			(xy 283.604729 -313.974449) (xy 283.60455 -313.97555) (xy 283.923228 -313.97555) (xy 283.923228 -313.924134)
			(xy 283.931271 -313.873352) (xy 283.947159 -313.824453) (xy 283.970502 -313.778641) (xy 284.000723 -313.737045)
			(xy 284.037079 -313.700689) (xy 284.078675 -313.670468) (xy 284.124487 -313.647125) (xy 284.173386 -313.631237)
			(xy 284.224168 -313.623194) (xy 284.275584 -313.623194) (xy 284.326366 -313.631237) (xy 284.375265 -313.647125)
			(xy 284.421077 -313.670468) (xy 284.462673 -313.700689) (xy 284.499029 -313.737045) (xy 284.52925 -313.778641)
			(xy 284.552593 -313.824453) (xy 284.568481 -313.873352) (xy 284.576524 -313.924134) (xy 284.577028 -313.949842)
			(xy 284.894032 -313.949842) (xy 284.897992 -313.900788) (xy 284.909769 -313.853004) (xy 284.92906 -313.807728)
			(xy 284.955363 -313.766132) (xy 284.987998 -313.729295) (xy 285.026119 -313.69817) (xy 285.06874 -313.673563)
			(xy 285.114756 -313.656111) (xy 285.162975 -313.646267) (xy 285.21215 -313.644286) (xy 285.261005 -313.650218)
			(xy 285.308276 -313.66391) (xy 285.352738 -313.685008) (xy 285.393241 -313.712964) (xy 285.428734 -313.747056)
			(xy 285.458299 -313.7864) (xy 285.48117 -313.829977) (xy 285.496754 -313.876658) (xy 285.504649 -313.925235)
			(xy 285.505144 -313.949842) (xy 285.504649 -313.974449) (xy 285.50447 -313.97555) (xy 285.823148 -313.97555)
			(xy 285.823148 -313.924134) (xy 285.831191 -313.873352) (xy 285.847079 -313.824453) (xy 285.870422 -313.778641)
			(xy 285.900643 -313.737045) (xy 285.936999 -313.700689) (xy 285.978595 -313.670468) (xy 286.024407 -313.647125)
			(xy 286.073306 -313.631237) (xy 286.124088 -313.623194) (xy 286.175504 -313.623194) (xy 286.226286 -313.631237)
			(xy 286.275185 -313.647125) (xy 286.320997 -313.670468) (xy 286.362593 -313.700689) (xy 286.398949 -313.737045)
			(xy 286.42917 -313.778641) (xy 286.452513 -313.824453) (xy 286.468401 -313.873352) (xy 286.476444 -313.924134)
			(xy 286.476948 -313.949842) (xy 286.793952 -313.949842) (xy 286.797912 -313.900788) (xy 286.809689 -313.853004)
			(xy 286.82898 -313.807728) (xy 286.855283 -313.766132) (xy 286.887918 -313.729295) (xy 286.926039 -313.69817)
			(xy 286.96866 -313.673563) (xy 287.014676 -313.656111) (xy 287.062895 -313.646267) (xy 287.11207 -313.644286)
			(xy 287.160925 -313.650218) (xy 287.208196 -313.66391) (xy 287.252658 -313.685008) (xy 287.293161 -313.712964)
			(xy 287.328654 -313.747056) (xy 287.358219 -313.7864) (xy 287.38109 -313.829977) (xy 287.396674 -313.876658)
			(xy 287.404569 -313.925235) (xy 287.405064 -313.949842) (xy 287.404569 -313.974449) (xy 287.40439 -313.97555)
			(xy 287.723068 -313.97555) (xy 287.723068 -313.924134) (xy 287.731111 -313.873352) (xy 287.746999 -313.824453)
			(xy 287.770342 -313.778641) (xy 287.800563 -313.737045) (xy 287.836919 -313.700689) (xy 287.878515 -313.670468)
			(xy 287.924327 -313.647125) (xy 287.973226 -313.631237) (xy 288.024008 -313.623194) (xy 288.075424 -313.623194)
			(xy 288.126206 -313.631237) (xy 288.175105 -313.647125) (xy 288.220917 -313.670468) (xy 288.262513 -313.700689)
			(xy 288.298869 -313.737045) (xy 288.32909 -313.778641) (xy 288.352433 -313.824453) (xy 288.368321 -313.873352)
			(xy 288.376364 -313.924134) (xy 288.376868 -313.949842) (xy 288.694126 -313.949842) (xy 288.698086 -313.900788)
			(xy 288.709863 -313.853004) (xy 288.729154 -313.807728) (xy 288.755457 -313.766132) (xy 288.788092 -313.729295)
			(xy 288.826213 -313.69817) (xy 288.868834 -313.673563) (xy 288.91485 -313.656111) (xy 288.963069 -313.646267)
			(xy 289.012244 -313.644286) (xy 289.061099 -313.650218) (xy 289.10837 -313.66391) (xy 289.152832 -313.685008)
			(xy 289.193335 -313.712964) (xy 289.228828 -313.747056) (xy 289.258393 -313.7864) (xy 289.281264 -313.829977)
			(xy 289.296848 -313.876658) (xy 289.304743 -313.925235) (xy 289.305238 -313.949842) (xy 289.304743 -313.974449)
			(xy 289.304564 -313.97555) (xy 289.623242 -313.97555) (xy 289.623242 -313.924134) (xy 289.631285 -313.873352)
			(xy 289.647173 -313.824453) (xy 289.670516 -313.778641) (xy 289.700737 -313.737045) (xy 289.737093 -313.700689)
			(xy 289.778689 -313.670468) (xy 289.824501 -313.647125) (xy 289.8734 -313.631237) (xy 289.924182 -313.623194)
			(xy 289.975598 -313.623194) (xy 290.02638 -313.631237) (xy 290.075279 -313.647125) (xy 290.121091 -313.670468)
			(xy 290.162687 -313.700689) (xy 290.199043 -313.737045) (xy 290.229264 -313.778641) (xy 290.252607 -313.824453)
			(xy 290.268495 -313.873352) (xy 290.276538 -313.924134) (xy 290.277042 -313.949842) (xy 290.594046 -313.949842)
			(xy 290.598006 -313.900788) (xy 290.609783 -313.853004) (xy 290.629074 -313.807728) (xy 290.655377 -313.766132)
			(xy 290.688012 -313.729295) (xy 290.726133 -313.69817) (xy 290.768754 -313.673563) (xy 290.81477 -313.656111)
			(xy 290.862989 -313.646267) (xy 290.912164 -313.644286) (xy 290.961019 -313.650218) (xy 291.00829 -313.66391)
			(xy 291.052752 -313.685008) (xy 291.093255 -313.712964) (xy 291.128748 -313.747056) (xy 291.158313 -313.7864)
			(xy 291.181184 -313.829977) (xy 291.196768 -313.876658) (xy 291.204663 -313.925235) (xy 291.205158 -313.949842)
			(xy 291.204663 -313.974449) (xy 291.204484 -313.97555) (xy 291.523162 -313.97555) (xy 291.523162 -313.924134)
			(xy 291.531205 -313.873352) (xy 291.547093 -313.824453) (xy 291.570436 -313.778641) (xy 291.600657 -313.737045)
			(xy 291.637013 -313.700689) (xy 291.678609 -313.670468) (xy 291.724421 -313.647125) (xy 291.77332 -313.631237)
			(xy 291.824102 -313.623194) (xy 291.875518 -313.623194) (xy 291.9263 -313.631237) (xy 291.975199 -313.647125)
			(xy 292.021011 -313.670468) (xy 292.062607 -313.700689) (xy 292.098963 -313.737045) (xy 292.129184 -313.778641)
			(xy 292.152527 -313.824453) (xy 292.168415 -313.873352) (xy 292.176458 -313.924134) (xy 292.176962 -313.949842)
			(xy 292.493966 -313.949842) (xy 292.497926 -313.900788) (xy 292.509703 -313.853004) (xy 292.528994 -313.807728)
			(xy 292.555297 -313.766132) (xy 292.587932 -313.729295) (xy 292.626053 -313.69817) (xy 292.668674 -313.673563)
			(xy 292.71469 -313.656111) (xy 292.762909 -313.646267) (xy 292.812084 -313.644286) (xy 292.860939 -313.650218)
			(xy 292.90821 -313.66391) (xy 292.952672 -313.685008) (xy 292.993175 -313.712964) (xy 293.028668 -313.747056)
			(xy 293.058233 -313.7864) (xy 293.081104 -313.829977) (xy 293.096688 -313.876658) (xy 293.104583 -313.925235)
			(xy 293.105078 -313.949842) (xy 293.104583 -313.974449) (xy 293.104404 -313.97555) (xy 293.423082 -313.97555)
			(xy 293.423082 -313.924134) (xy 293.431125 -313.873352) (xy 293.447013 -313.824453) (xy 293.470356 -313.778641)
			(xy 293.500577 -313.737045) (xy 293.536933 -313.700689) (xy 293.578529 -313.670468) (xy 293.624341 -313.647125)
			(xy 293.67324 -313.631237) (xy 293.724022 -313.623194) (xy 293.775438 -313.623194) (xy 293.82622 -313.631237)
			(xy 293.875119 -313.647125) (xy 293.920931 -313.670468) (xy 293.962527 -313.700689) (xy 293.998883 -313.737045)
			(xy 294.029104 -313.778641) (xy 294.052447 -313.824453) (xy 294.068335 -313.873352) (xy 294.076378 -313.924134)
			(xy 294.076882 -313.949842) (xy 294.393886 -313.949842) (xy 294.397846 -313.900788) (xy 294.409623 -313.853004)
			(xy 294.428914 -313.807728) (xy 294.455217 -313.766132) (xy 294.487852 -313.729295) (xy 294.525973 -313.69817)
			(xy 294.568594 -313.673563) (xy 294.61461 -313.656111) (xy 294.662829 -313.646267) (xy 294.712004 -313.644286)
			(xy 294.760859 -313.650218) (xy 294.80813 -313.66391) (xy 294.852592 -313.685008) (xy 294.893095 -313.712964)
			(xy 294.928588 -313.747056) (xy 294.958153 -313.7864) (xy 294.981024 -313.829977) (xy 294.996608 -313.876658)
			(xy 295.004503 -313.925235) (xy 295.004998 -313.949842) (xy 295.004503 -313.974449) (xy 295.004324 -313.97555)
			(xy 295.323256 -313.97555) (xy 295.323256 -313.924134) (xy 295.331299 -313.873352) (xy 295.347187 -313.824453)
			(xy 295.37053 -313.778641) (xy 295.400751 -313.737045) (xy 295.437107 -313.700689) (xy 295.478703 -313.670468)
			(xy 295.524515 -313.647125) (xy 295.573414 -313.631237) (xy 295.624196 -313.623194) (xy 295.675612 -313.623194)
			(xy 295.726394 -313.631237) (xy 295.775293 -313.647125) (xy 295.821105 -313.670468) (xy 295.862701 -313.700689)
			(xy 295.899057 -313.737045) (xy 295.929278 -313.778641) (xy 295.952621 -313.824453) (xy 295.968509 -313.873352)
			(xy 295.976552 -313.924134) (xy 295.977056 -313.949842) (xy 296.29406 -313.949842) (xy 296.29802 -313.900788)
			(xy 296.309797 -313.853004) (xy 296.329088 -313.807728) (xy 296.355391 -313.766132) (xy 296.388026 -313.729295)
			(xy 296.426147 -313.69817) (xy 296.468768 -313.673563) (xy 296.514784 -313.656111) (xy 296.563003 -313.646267)
			(xy 296.612178 -313.644286) (xy 296.661033 -313.650218) (xy 296.708304 -313.66391) (xy 296.752766 -313.685008)
			(xy 296.793269 -313.712964) (xy 296.828762 -313.747056) (xy 296.858327 -313.7864) (xy 296.881198 -313.829977)
			(xy 296.896782 -313.876658) (xy 296.904677 -313.925235) (xy 296.905172 -313.949842) (xy 296.904677 -313.974449)
			(xy 296.904498 -313.97555) (xy 297.223176 -313.97555) (xy 297.223176 -313.924134) (xy 297.231219 -313.873352)
			(xy 297.247107 -313.824453) (xy 297.27045 -313.778641) (xy 297.300671 -313.737045) (xy 297.337027 -313.700689)
			(xy 297.378623 -313.670468) (xy 297.424435 -313.647125) (xy 297.473334 -313.631237) (xy 297.524116 -313.623194)
			(xy 297.575532 -313.623194) (xy 297.626314 -313.631237) (xy 297.675213 -313.647125) (xy 297.721025 -313.670468)
			(xy 297.762621 -313.700689) (xy 297.798977 -313.737045) (xy 297.829198 -313.778641) (xy 297.852541 -313.824453)
			(xy 297.868429 -313.873352) (xy 297.876472 -313.924134) (xy 297.876976 -313.949842) (xy 298.19398 -313.949842)
			(xy 298.19794 -313.900788) (xy 298.209717 -313.853004) (xy 298.229008 -313.807728) (xy 298.255311 -313.766132)
			(xy 298.287946 -313.729295) (xy 298.326067 -313.69817) (xy 298.368688 -313.673563) (xy 298.414704 -313.656111)
			(xy 298.462923 -313.646267) (xy 298.512098 -313.644286) (xy 298.560953 -313.650218) (xy 298.608224 -313.66391)
			(xy 298.652686 -313.685008) (xy 298.693189 -313.712964) (xy 298.728682 -313.747056) (xy 298.758247 -313.7864)
			(xy 298.781118 -313.829977) (xy 298.796702 -313.876658) (xy 298.804597 -313.925235) (xy 298.805092 -313.949842)
			(xy 298.804597 -313.974449) (xy 298.804418 -313.97555) (xy 299.123096 -313.97555) (xy 299.123096 -313.924134)
			(xy 299.131139 -313.873352) (xy 299.147027 -313.824453) (xy 299.17037 -313.778641) (xy 299.200591 -313.737045)
			(xy 299.236947 -313.700689) (xy 299.278543 -313.670468) (xy 299.324355 -313.647125) (xy 299.373254 -313.631237)
			(xy 299.424036 -313.623194) (xy 299.475452 -313.623194) (xy 299.526234 -313.631237) (xy 299.575133 -313.647125)
			(xy 299.620945 -313.670468) (xy 299.662541 -313.700689) (xy 299.698897 -313.737045) (xy 299.729118 -313.778641)
			(xy 299.752461 -313.824453) (xy 299.768349 -313.873352) (xy 299.776392 -313.924134) (xy 299.776896 -313.949842)
			(xy 299.776392 -313.97555) (xy 299.768349 -314.026332) (xy 299.752461 -314.075231) (xy 299.729118 -314.121043)
			(xy 299.698897 -314.162639) (xy 299.662541 -314.198995) (xy 299.620945 -314.229216) (xy 299.575133 -314.252559)
			(xy 299.526234 -314.268447) (xy 299.475452 -314.27649) (xy 299.424036 -314.27649) (xy 299.373254 -314.268447)
			(xy 299.324355 -314.252559) (xy 299.278543 -314.229216) (xy 299.236947 -314.198995) (xy 299.200591 -314.162639)
			(xy 299.17037 -314.121043) (xy 299.147027 -314.075231) (xy 299.131139 -314.026332) (xy 299.123096 -313.97555)
			(xy 298.804418 -313.97555) (xy 298.796702 -314.023026) (xy 298.781118 -314.069707) (xy 298.758247 -314.113284)
			(xy 298.728682 -314.152628) (xy 298.693189 -314.18672) (xy 298.652686 -314.214676) (xy 298.608224 -314.235774)
			(xy 298.560953 -314.249466) (xy 298.512098 -314.255398) (xy 298.462923 -314.253417) (xy 298.414704 -314.243573)
			(xy 298.368688 -314.226121) (xy 298.326067 -314.201514) (xy 298.287946 -314.170389) (xy 298.255311 -314.133552)
			(xy 298.229008 -314.091956) (xy 298.209717 -314.04668) (xy 298.19794 -313.998896) (xy 298.19398 -313.949842)
			(xy 297.876976 -313.949842) (xy 297.876472 -313.97555) (xy 297.868429 -314.026332) (xy 297.852541 -314.075231)
			(xy 297.829198 -314.121043) (xy 297.798977 -314.162639) (xy 297.762621 -314.198995) (xy 297.721025 -314.229216)
			(xy 297.675213 -314.252559) (xy 297.626314 -314.268447) (xy 297.575532 -314.27649) (xy 297.524116 -314.27649)
			(xy 297.473334 -314.268447) (xy 297.424435 -314.252559) (xy 297.378623 -314.229216) (xy 297.337027 -314.198995)
			(xy 297.300671 -314.162639) (xy 297.27045 -314.121043) (xy 297.247107 -314.075231) (xy 297.231219 -314.026332)
			(xy 297.223176 -313.97555) (xy 296.904498 -313.97555) (xy 296.896782 -314.023026) (xy 296.881198 -314.069707)
			(xy 296.858327 -314.113284) (xy 296.828762 -314.152628) (xy 296.793269 -314.18672) (xy 296.752766 -314.214676)
			(xy 296.708304 -314.235774) (xy 296.661033 -314.249466) (xy 296.612178 -314.255398) (xy 296.563003 -314.253417)
			(xy 296.514784 -314.243573) (xy 296.468768 -314.226121) (xy 296.426147 -314.201514) (xy 296.388026 -314.170389)
			(xy 296.355391 -314.133552) (xy 296.329088 -314.091956) (xy 296.309797 -314.04668) (xy 296.29802 -313.998896)
			(xy 296.29406 -313.949842) (xy 295.977056 -313.949842) (xy 295.976552 -313.97555) (xy 295.968509 -314.026332)
			(xy 295.952621 -314.075231) (xy 295.929278 -314.121043) (xy 295.899057 -314.162639) (xy 295.862701 -314.198995)
			(xy 295.821105 -314.229216) (xy 295.775293 -314.252559) (xy 295.726394 -314.268447) (xy 295.675612 -314.27649)
			(xy 295.624196 -314.27649) (xy 295.573414 -314.268447) (xy 295.524515 -314.252559) (xy 295.478703 -314.229216)
			(xy 295.437107 -314.198995) (xy 295.400751 -314.162639) (xy 295.37053 -314.121043) (xy 295.347187 -314.075231)
			(xy 295.331299 -314.026332) (xy 295.323256 -313.97555) (xy 295.004324 -313.97555) (xy 294.996608 -314.023026)
			(xy 294.981024 -314.069707) (xy 294.958153 -314.113284) (xy 294.928588 -314.152628) (xy 294.893095 -314.18672)
			(xy 294.852592 -314.214676) (xy 294.80813 -314.235774) (xy 294.760859 -314.249466) (xy 294.712004 -314.255398)
			(xy 294.662829 -314.253417) (xy 294.61461 -314.243573) (xy 294.568594 -314.226121) (xy 294.525973 -314.201514)
			(xy 294.487852 -314.170389) (xy 294.455217 -314.133552) (xy 294.428914 -314.091956) (xy 294.409623 -314.04668)
			(xy 294.397846 -313.998896) (xy 294.393886 -313.949842) (xy 294.076882 -313.949842) (xy 294.076378 -313.97555)
			(xy 294.068335 -314.026332) (xy 294.052447 -314.075231) (xy 294.029104 -314.121043) (xy 293.998883 -314.162639)
			(xy 293.962527 -314.198995) (xy 293.920931 -314.229216) (xy 293.875119 -314.252559) (xy 293.82622 -314.268447)
			(xy 293.775438 -314.27649) (xy 293.724022 -314.27649) (xy 293.67324 -314.268447) (xy 293.624341 -314.252559)
			(xy 293.578529 -314.229216) (xy 293.536933 -314.198995) (xy 293.500577 -314.162639) (xy 293.470356 -314.121043)
			(xy 293.447013 -314.075231) (xy 293.431125 -314.026332) (xy 293.423082 -313.97555) (xy 293.104404 -313.97555)
			(xy 293.096688 -314.023026) (xy 293.081104 -314.069707) (xy 293.058233 -314.113284) (xy 293.028668 -314.152628)
			(xy 292.993175 -314.18672) (xy 292.952672 -314.214676) (xy 292.90821 -314.235774) (xy 292.860939 -314.249466)
			(xy 292.812084 -314.255398) (xy 292.762909 -314.253417) (xy 292.71469 -314.243573) (xy 292.668674 -314.226121)
			(xy 292.626053 -314.201514) (xy 292.587932 -314.170389) (xy 292.555297 -314.133552) (xy 292.528994 -314.091956)
			(xy 292.509703 -314.04668) (xy 292.497926 -313.998896) (xy 292.493966 -313.949842) (xy 292.176962 -313.949842)
			(xy 292.176458 -313.97555) (xy 292.168415 -314.026332) (xy 292.152527 -314.075231) (xy 292.129184 -314.121043)
			(xy 292.098963 -314.162639) (xy 292.062607 -314.198995) (xy 292.021011 -314.229216) (xy 291.975199 -314.252559)
			(xy 291.9263 -314.268447) (xy 291.875518 -314.27649) (xy 291.824102 -314.27649) (xy 291.77332 -314.268447)
			(xy 291.724421 -314.252559) (xy 291.678609 -314.229216) (xy 291.637013 -314.198995) (xy 291.600657 -314.162639)
			(xy 291.570436 -314.121043) (xy 291.547093 -314.075231) (xy 291.531205 -314.026332) (xy 291.523162 -313.97555)
			(xy 291.204484 -313.97555) (xy 291.196768 -314.023026) (xy 291.181184 -314.069707) (xy 291.158313 -314.113284)
			(xy 291.128748 -314.152628) (xy 291.093255 -314.18672) (xy 291.052752 -314.214676) (xy 291.00829 -314.235774)
			(xy 290.961019 -314.249466) (xy 290.912164 -314.255398) (xy 290.862989 -314.253417) (xy 290.81477 -314.243573)
			(xy 290.768754 -314.226121) (xy 290.726133 -314.201514) (xy 290.688012 -314.170389) (xy 290.655377 -314.133552)
			(xy 290.629074 -314.091956) (xy 290.609783 -314.04668) (xy 290.598006 -313.998896) (xy 290.594046 -313.949842)
			(xy 290.277042 -313.949842) (xy 290.276538 -313.97555) (xy 290.268495 -314.026332) (xy 290.252607 -314.075231)
			(xy 290.229264 -314.121043) (xy 290.199043 -314.162639) (xy 290.162687 -314.198995) (xy 290.121091 -314.229216)
			(xy 290.075279 -314.252559) (xy 290.02638 -314.268447) (xy 289.975598 -314.27649) (xy 289.924182 -314.27649)
			(xy 289.8734 -314.268447) (xy 289.824501 -314.252559) (xy 289.778689 -314.229216) (xy 289.737093 -314.198995)
			(xy 289.700737 -314.162639) (xy 289.670516 -314.121043) (xy 289.647173 -314.075231) (xy 289.631285 -314.026332)
			(xy 289.623242 -313.97555) (xy 289.304564 -313.97555) (xy 289.296848 -314.023026) (xy 289.281264 -314.069707)
			(xy 289.258393 -314.113284) (xy 289.228828 -314.152628) (xy 289.193335 -314.18672) (xy 289.152832 -314.214676)
			(xy 289.10837 -314.235774) (xy 289.061099 -314.249466) (xy 289.012244 -314.255398) (xy 288.963069 -314.253417)
			(xy 288.91485 -314.243573) (xy 288.868834 -314.226121) (xy 288.826213 -314.201514) (xy 288.788092 -314.170389)
			(xy 288.755457 -314.133552) (xy 288.729154 -314.091956) (xy 288.709863 -314.04668) (xy 288.698086 -313.998896)
			(xy 288.694126 -313.949842) (xy 288.376868 -313.949842) (xy 288.376364 -313.97555) (xy 288.368321 -314.026332)
			(xy 288.352433 -314.075231) (xy 288.32909 -314.121043) (xy 288.298869 -314.162639) (xy 288.262513 -314.198995)
			(xy 288.220917 -314.229216) (xy 288.175105 -314.252559) (xy 288.126206 -314.268447) (xy 288.075424 -314.27649)
			(xy 288.024008 -314.27649) (xy 287.973226 -314.268447) (xy 287.924327 -314.252559) (xy 287.878515 -314.229216)
			(xy 287.836919 -314.198995) (xy 287.800563 -314.162639) (xy 287.770342 -314.121043) (xy 287.746999 -314.075231)
			(xy 287.731111 -314.026332) (xy 287.723068 -313.97555) (xy 287.40439 -313.97555) (xy 287.396674 -314.023026)
			(xy 287.38109 -314.069707) (xy 287.358219 -314.113284) (xy 287.328654 -314.152628) (xy 287.293161 -314.18672)
			(xy 287.252658 -314.214676) (xy 287.208196 -314.235774) (xy 287.160925 -314.249466) (xy 287.11207 -314.255398)
			(xy 287.062895 -314.253417) (xy 287.014676 -314.243573) (xy 286.96866 -314.226121) (xy 286.926039 -314.201514)
			(xy 286.887918 -314.170389) (xy 286.855283 -314.133552) (xy 286.82898 -314.091956) (xy 286.809689 -314.04668)
			(xy 286.797912 -313.998896) (xy 286.793952 -313.949842) (xy 286.476948 -313.949842) (xy 286.476444 -313.97555)
			(xy 286.468401 -314.026332) (xy 286.452513 -314.075231) (xy 286.42917 -314.121043) (xy 286.398949 -314.162639)
			(xy 286.362593 -314.198995) (xy 286.320997 -314.229216) (xy 286.275185 -314.252559) (xy 286.226286 -314.268447)
			(xy 286.175504 -314.27649) (xy 286.124088 -314.27649) (xy 286.073306 -314.268447) (xy 286.024407 -314.252559)
			(xy 285.978595 -314.229216) (xy 285.936999 -314.198995) (xy 285.900643 -314.162639) (xy 285.870422 -314.121043)
			(xy 285.847079 -314.075231) (xy 285.831191 -314.026332) (xy 285.823148 -313.97555) (xy 285.50447 -313.97555)
			(xy 285.496754 -314.023026) (xy 285.48117 -314.069707) (xy 285.458299 -314.113284) (xy 285.428734 -314.152628)
			(xy 285.393241 -314.18672) (xy 285.352738 -314.214676) (xy 285.308276 -314.235774) (xy 285.261005 -314.249466)
			(xy 285.21215 -314.255398) (xy 285.162975 -314.253417) (xy 285.114756 -314.243573) (xy 285.06874 -314.226121)
			(xy 285.026119 -314.201514) (xy 284.987998 -314.170389) (xy 284.955363 -314.133552) (xy 284.92906 -314.091956)
			(xy 284.909769 -314.04668) (xy 284.897992 -313.998896) (xy 284.894032 -313.949842) (xy 284.577028 -313.949842)
			(xy 284.576524 -313.97555) (xy 284.568481 -314.026332) (xy 284.552593 -314.075231) (xy 284.52925 -314.121043)
			(xy 284.499029 -314.162639) (xy 284.462673 -314.198995) (xy 284.421077 -314.229216) (xy 284.375265 -314.252559)
			(xy 284.326366 -314.268447) (xy 284.275584 -314.27649) (xy 284.224168 -314.27649) (xy 284.173386 -314.268447)
			(xy 284.124487 -314.252559) (xy 284.078675 -314.229216) (xy 284.037079 -314.198995) (xy 284.000723 -314.162639)
			(xy 283.970502 -314.121043) (xy 283.947159 -314.075231) (xy 283.931271 -314.026332) (xy 283.923228 -313.97555)
			(xy 283.60455 -313.97555) (xy 283.596834 -314.023026) (xy 283.58125 -314.069707) (xy 283.558379 -314.113284)
			(xy 283.528814 -314.152628) (xy 283.493321 -314.18672) (xy 283.452818 -314.214676) (xy 283.408356 -314.235774)
			(xy 283.361085 -314.249466) (xy 283.31223 -314.255398) (xy 283.263055 -314.253417) (xy 283.214836 -314.243573)
			(xy 283.16882 -314.226121) (xy 283.126199 -314.201514) (xy 283.088078 -314.170389) (xy 283.055443 -314.133552)
			(xy 283.02914 -314.091956) (xy 283.009849 -314.04668) (xy 282.998072 -313.998896) (xy 282.994112 -313.949842)
			(xy 282.676854 -313.949842) (xy 282.67635 -313.97555) (xy 282.668307 -314.026332) (xy 282.652419 -314.075231)
			(xy 282.629076 -314.121043) (xy 282.598855 -314.162639) (xy 282.562499 -314.198995) (xy 282.520903 -314.229216)
			(xy 282.475091 -314.252559) (xy 282.426192 -314.268447) (xy 282.37541 -314.27649) (xy 282.323994 -314.27649)
			(xy 282.273212 -314.268447) (xy 282.224313 -314.252559) (xy 282.178501 -314.229216) (xy 282.136905 -314.198995)
			(xy 282.100549 -314.162639) (xy 282.070328 -314.121043) (xy 282.046985 -314.075231) (xy 282.031097 -314.026332)
			(xy 282.023054 -313.97555) (xy 281.704376 -313.97555) (xy 281.69666 -314.023026) (xy 281.681076 -314.069707)
			(xy 281.658205 -314.113284) (xy 281.62864 -314.152628) (xy 281.593147 -314.18672) (xy 281.552644 -314.214676)
			(xy 281.508182 -314.235774) (xy 281.460911 -314.249466) (xy 281.412056 -314.255398) (xy 281.362881 -314.253417)
			(xy 281.314662 -314.243573) (xy 281.268646 -314.226121) (xy 281.226025 -314.201514) (xy 281.187904 -314.170389)
			(xy 281.155269 -314.133552) (xy 281.128966 -314.091956) (xy 281.109675 -314.04668) (xy 281.097898 -313.998896)
			(xy 281.093938 -313.949842) (xy 280.776934 -313.949842) (xy 280.77643 -313.97555) (xy 280.768387 -314.026332)
			(xy 280.752499 -314.075231) (xy 280.729156 -314.121043) (xy 280.698935 -314.162639) (xy 280.662579 -314.198995)
			(xy 280.620983 -314.229216) (xy 280.575171 -314.252559) (xy 280.526272 -314.268447) (xy 280.47549 -314.27649)
			(xy 280.424074 -314.27649) (xy 280.373292 -314.268447) (xy 280.324393 -314.252559) (xy 280.278581 -314.229216)
			(xy 280.236985 -314.198995) (xy 280.200629 -314.162639) (xy 280.170408 -314.121043) (xy 280.147065 -314.075231)
			(xy 280.131177 -314.026332) (xy 280.123134 -313.97555) (xy 279.804456 -313.97555) (xy 279.79674 -314.023026)
			(xy 279.781156 -314.069707) (xy 279.758285 -314.113284) (xy 279.72872 -314.152628) (xy 279.693227 -314.18672)
			(xy 279.652724 -314.214676) (xy 279.608262 -314.235774) (xy 279.560991 -314.249466) (xy 279.512136 -314.255398)
			(xy 279.462961 -314.253417) (xy 279.414742 -314.243573) (xy 279.368726 -314.226121) (xy 279.326105 -314.201514)
			(xy 279.287984 -314.170389) (xy 279.255349 -314.133552) (xy 279.229046 -314.091956) (xy 279.209755 -314.04668)
			(xy 279.197978 -313.998896) (xy 279.194018 -313.949842) (xy 278.877014 -313.949842) (xy 278.87651 -313.97555)
			(xy 278.868467 -314.026332) (xy 278.852579 -314.075231) (xy 278.829236 -314.121043) (xy 278.799015 -314.162639)
			(xy 278.762659 -314.198995) (xy 278.721063 -314.229216) (xy 278.675251 -314.252559) (xy 278.626352 -314.268447)
			(xy 278.57557 -314.27649) (xy 278.524154 -314.27649) (xy 278.473372 -314.268447) (xy 278.424473 -314.252559)
			(xy 278.378661 -314.229216) (xy 278.337065 -314.198995) (xy 278.300709 -314.162639) (xy 278.270488 -314.121043)
			(xy 278.247145 -314.075231) (xy 278.231257 -314.026332) (xy 278.223214 -313.97555) (xy 277.904536 -313.97555)
			(xy 277.89682 -314.023026) (xy 277.881236 -314.069707) (xy 277.858365 -314.113284) (xy 277.8288 -314.152628)
			(xy 277.793307 -314.18672) (xy 277.752804 -314.214676) (xy 277.708342 -314.235774) (xy 277.661071 -314.249466)
			(xy 277.612216 -314.255398) (xy 277.563041 -314.253417) (xy 277.514822 -314.243573) (xy 277.468806 -314.226121)
			(xy 277.426185 -314.201514) (xy 277.388064 -314.170389) (xy 277.355429 -314.133552) (xy 277.329126 -314.091956)
			(xy 277.309835 -314.04668) (xy 277.298058 -313.998896) (xy 277.294098 -313.949842) (xy 276.97684 -313.949842)
			(xy 276.976336 -313.97555) (xy 276.968293 -314.026332) (xy 276.952405 -314.075231) (xy 276.929062 -314.121043)
			(xy 276.898841 -314.162639) (xy 276.862485 -314.198995) (xy 276.820889 -314.229216) (xy 276.775077 -314.252559)
			(xy 276.726178 -314.268447) (xy 276.675396 -314.27649) (xy 276.62398 -314.27649) (xy 276.573198 -314.268447)
			(xy 276.524299 -314.252559) (xy 276.478487 -314.229216) (xy 276.436891 -314.198995) (xy 276.400535 -314.162639)
			(xy 276.370314 -314.121043) (xy 276.346971 -314.075231) (xy 276.331083 -314.026332) (xy 276.32304 -313.97555)
			(xy 276.004362 -313.97555) (xy 275.996646 -314.023026) (xy 275.981062 -314.069707) (xy 275.958191 -314.113284)
			(xy 275.928626 -314.152628) (xy 275.893133 -314.18672) (xy 275.85263 -314.214676) (xy 275.808168 -314.235774)
			(xy 275.760897 -314.249466) (xy 275.712042 -314.255398) (xy 275.662867 -314.253417) (xy 275.614648 -314.243573)
			(xy 275.568632 -314.226121) (xy 275.526011 -314.201514) (xy 275.48789 -314.170389) (xy 275.455255 -314.133552)
			(xy 275.428952 -314.091956) (xy 275.409661 -314.04668) (xy 275.397884 -313.998896) (xy 275.393924 -313.949842)
			(xy 275.07692 -313.949842) (xy 275.076416 -313.97555) (xy 275.068373 -314.026332) (xy 275.052485 -314.075231)
			(xy 275.029142 -314.121043) (xy 274.998921 -314.162639) (xy 274.962565 -314.198995) (xy 274.920969 -314.229216)
			(xy 274.875157 -314.252559) (xy 274.826258 -314.268447) (xy 274.775476 -314.27649) (xy 274.72406 -314.27649)
			(xy 274.673278 -314.268447) (xy 274.624379 -314.252559) (xy 274.578567 -314.229216) (xy 274.536971 -314.198995)
			(xy 274.500615 -314.162639) (xy 274.470394 -314.121043) (xy 274.447051 -314.075231) (xy 274.431163 -314.026332)
			(xy 274.42312 -313.97555) (xy 274.104442 -313.97555) (xy 274.096726 -314.023026) (xy 274.081142 -314.069707)
			(xy 274.058271 -314.113284) (xy 274.028706 -314.152628) (xy 273.993213 -314.18672) (xy 273.95271 -314.214676)
			(xy 273.908248 -314.235774) (xy 273.860977 -314.249466) (xy 273.812122 -314.255398) (xy 273.762947 -314.253417)
			(xy 273.714728 -314.243573) (xy 273.668712 -314.226121) (xy 273.626091 -314.201514) (xy 273.58797 -314.170389)
			(xy 273.555335 -314.133552) (xy 273.529032 -314.091956) (xy 273.509741 -314.04668) (xy 273.497964 -313.998896)
			(xy 273.494004 -313.949842) (xy 273.177 -313.949842) (xy 273.176496 -313.97555) (xy 273.168453 -314.026332)
			(xy 273.152565 -314.075231) (xy 273.129222 -314.121043) (xy 273.099001 -314.162639) (xy 273.062645 -314.198995)
			(xy 273.021049 -314.229216) (xy 272.975237 -314.252559) (xy 272.926338 -314.268447) (xy 272.875556 -314.27649)
			(xy 272.82414 -314.27649) (xy 272.773358 -314.268447) (xy 272.724459 -314.252559) (xy 272.678647 -314.229216)
			(xy 272.637051 -314.198995) (xy 272.600695 -314.162639) (xy 272.570474 -314.121043) (xy 272.547131 -314.075231)
			(xy 272.531243 -314.026332) (xy 272.5232 -313.97555) (xy 272.204522 -313.97555) (xy 272.196806 -314.023026)
			(xy 272.181222 -314.069707) (xy 272.158351 -314.113284) (xy 272.128786 -314.152628) (xy 272.093293 -314.18672)
			(xy 272.05279 -314.214676) (xy 272.008328 -314.235774) (xy 271.961057 -314.249466) (xy 271.912202 -314.255398)
			(xy 271.863027 -314.253417) (xy 271.814808 -314.243573) (xy 271.768792 -314.226121) (xy 271.726171 -314.201514)
			(xy 271.68805 -314.170389) (xy 271.655415 -314.133552) (xy 271.629112 -314.091956) (xy 271.609821 -314.04668)
			(xy 271.598044 -313.998896) (xy 271.594084 -313.949842) (xy 271.27708 -313.949842) (xy 271.276576 -313.97555)
			(xy 271.268533 -314.026332) (xy 271.252645 -314.075231) (xy 271.229302 -314.121043) (xy 271.199081 -314.162639)
			(xy 271.162725 -314.198995) (xy 271.121129 -314.229216) (xy 271.075317 -314.252559) (xy 271.026418 -314.268447)
			(xy 270.975636 -314.27649) (xy 270.92422 -314.27649) (xy 270.873438 -314.268447) (xy 270.824539 -314.252559)
			(xy 270.778727 -314.229216) (xy 270.737131 -314.198995) (xy 270.700775 -314.162639) (xy 270.670554 -314.121043)
			(xy 270.647211 -314.075231) (xy 270.631323 -314.026332) (xy 270.62328 -313.97555) (xy 270.304348 -313.97555)
			(xy 270.296632 -314.023026) (xy 270.281048 -314.069707) (xy 270.258177 -314.113284) (xy 270.228612 -314.152628)
			(xy 270.193119 -314.18672) (xy 270.152616 -314.214676) (xy 270.108154 -314.235774) (xy 270.060883 -314.249466)
			(xy 270.012028 -314.255398) (xy 269.962853 -314.253417) (xy 269.914634 -314.243573) (xy 269.868618 -314.226121)
			(xy 269.825997 -314.201514) (xy 269.787876 -314.170389) (xy 269.755241 -314.133552) (xy 269.728938 -314.091956)
			(xy 269.709647 -314.04668) (xy 269.69787 -313.998896) (xy 269.69391 -313.949842) (xy 269.355062 -313.949842)
			(xy 269.354567 -313.974449) (xy 269.346672 -314.023026) (xy 269.331088 -314.069707) (xy 269.308217 -314.113284)
			(xy 269.278652 -314.152628) (xy 269.243159 -314.18672) (xy 269.202656 -314.214676) (xy 269.158194 -314.235774)
			(xy 269.110923 -314.249466) (xy 269.062068 -314.255398) (xy 269.012893 -314.253417) (xy 268.964674 -314.243573)
			(xy 268.918658 -314.226121) (xy 268.876037 -314.201514) (xy 268.837916 -314.170389) (xy 268.805281 -314.133552)
			(xy 268.778978 -314.091956) (xy 268.759687 -314.04668) (xy 268.74791 -313.998896) (xy 268.74395 -313.949842)
			(xy 266.888151 -313.949842) (xy 266.851161 -313.980625) (xy 266.803555 -314.009679) (xy 266.752226 -314.031491)
			(xy 266.698269 -314.045597) (xy 266.642832 -314.051697) (xy 266.587098 -314.04966) (xy 266.532255 -314.03953)
			(xy 266.479471 -314.021523) (xy 266.429871 -313.996022) (xy 266.384513 -313.963571) (xy 266.344364 -313.924862)
			(xy 266.310278 -313.880719) (xy 266.282982 -313.832084) (xy 266.263059 -313.779993) (xy 266.250933 -313.725556)
			(xy 266.246862 -313.669934) (xy 255.945132 -313.669934) (xy 255.945132 -314.899548) (xy 267.793482 -314.899548)
			(xy 267.797442 -314.850494) (xy 267.809219 -314.80271) (xy 267.82851 -314.757434) (xy 267.854813 -314.715838)
			(xy 267.887448 -314.679001) (xy 267.925569 -314.647876) (xy 267.96819 -314.623269) (xy 268.014206 -314.605817)
			(xy 268.062425 -314.595973) (xy 268.1116 -314.593992) (xy 268.160455 -314.599924) (xy 268.207726 -314.613616)
			(xy 268.252188 -314.634714) (xy 268.292691 -314.66267) (xy 268.328184 -314.696762) (xy 268.357749 -314.736106)
			(xy 268.38062 -314.779683) (xy 268.396204 -314.826364) (xy 268.404099 -314.874941) (xy 268.404594 -314.899548)
			(xy 268.404099 -314.924155) (xy 268.403879 -314.92551) (xy 268.723106 -314.92551) (xy 268.723106 -314.874094)
			(xy 268.731149 -314.823312) (xy 268.747037 -314.774413) (xy 268.77038 -314.728601) (xy 268.800601 -314.687005)
			(xy 268.836957 -314.650649) (xy 268.878553 -314.620428) (xy 268.924365 -314.597085) (xy 268.973264 -314.581197)
			(xy 269.024046 -314.573154) (xy 269.075462 -314.573154) (xy 269.126244 -314.581197) (xy 269.175143 -314.597085)
			(xy 269.220955 -314.620428) (xy 269.262551 -314.650649) (xy 269.298907 -314.687005) (xy 269.329128 -314.728601)
			(xy 269.352471 -314.774413) (xy 269.368359 -314.823312) (xy 269.376402 -314.874094) (xy 269.376906 -314.899802)
			(xy 269.376402 -314.92551) (xy 269.673066 -314.92551) (xy 269.673066 -314.874094) (xy 269.681109 -314.823312)
			(xy 269.696997 -314.774413) (xy 269.72034 -314.728601) (xy 269.750561 -314.687005) (xy 269.786917 -314.650649)
			(xy 269.828513 -314.620428) (xy 269.874325 -314.597085) (xy 269.923224 -314.581197) (xy 269.974006 -314.573154)
			(xy 270.025422 -314.573154) (xy 270.076204 -314.581197) (xy 270.125103 -314.597085) (xy 270.170915 -314.620428)
			(xy 270.212511 -314.650649) (xy 270.248867 -314.687005) (xy 270.279088 -314.728601) (xy 270.302431 -314.774413)
			(xy 270.318319 -314.823312) (xy 270.326362 -314.874094) (xy 270.326866 -314.899802) (xy 270.644124 -314.899802)
			(xy 270.648084 -314.850748) (xy 270.659861 -314.802964) (xy 270.679152 -314.757688) (xy 270.705455 -314.716092)
			(xy 270.73809 -314.679255) (xy 270.776211 -314.64813) (xy 270.818832 -314.623523) (xy 270.864848 -314.606071)
			(xy 270.913067 -314.596227) (xy 270.962242 -314.594246) (xy 271.011097 -314.600178) (xy 271.058368 -314.61387)
			(xy 271.10283 -314.634968) (xy 271.143333 -314.662924) (xy 271.178826 -314.697016) (xy 271.208391 -314.73636)
			(xy 271.231262 -314.779937) (xy 271.246846 -314.826618) (xy 271.254741 -314.875195) (xy 271.255236 -314.899802)
			(xy 271.594084 -314.899802) (xy 271.598044 -314.850748) (xy 271.609821 -314.802964) (xy 271.629112 -314.757688)
			(xy 271.655415 -314.716092) (xy 271.68805 -314.679255) (xy 271.726171 -314.64813) (xy 271.768792 -314.623523)
			(xy 271.814808 -314.606071) (xy 271.863027 -314.596227) (xy 271.912202 -314.594246) (xy 271.961057 -314.600178)
			(xy 272.008328 -314.61387) (xy 272.05279 -314.634968) (xy 272.093293 -314.662924) (xy 272.128786 -314.697016)
			(xy 272.158351 -314.73636) (xy 272.181222 -314.779937) (xy 272.196806 -314.826618) (xy 272.204701 -314.875195)
			(xy 272.205196 -314.899802) (xy 272.544044 -314.899802) (xy 272.548004 -314.850748) (xy 272.559781 -314.802964)
			(xy 272.579072 -314.757688) (xy 272.605375 -314.716092) (xy 272.63801 -314.679255) (xy 272.676131 -314.64813)
			(xy 272.718752 -314.623523) (xy 272.764768 -314.606071) (xy 272.812987 -314.596227) (xy 272.862162 -314.594246)
			(xy 272.911017 -314.600178) (xy 272.958288 -314.61387) (xy 273.00275 -314.634968) (xy 273.043253 -314.662924)
			(xy 273.078746 -314.697016) (xy 273.108311 -314.73636) (xy 273.131182 -314.779937) (xy 273.146766 -314.826618)
			(xy 273.154661 -314.875195) (xy 273.155156 -314.899802) (xy 273.494004 -314.899802) (xy 273.497964 -314.850748)
			(xy 273.509741 -314.802964) (xy 273.529032 -314.757688) (xy 273.555335 -314.716092) (xy 273.58797 -314.679255)
			(xy 273.626091 -314.64813) (xy 273.668712 -314.623523) (xy 273.714728 -314.606071) (xy 273.762947 -314.596227)
			(xy 273.812122 -314.594246) (xy 273.860977 -314.600178) (xy 273.908248 -314.61387) (xy 273.95271 -314.634968)
			(xy 273.993213 -314.662924) (xy 274.028706 -314.697016) (xy 274.058271 -314.73636) (xy 274.081142 -314.779937)
			(xy 274.096726 -314.826618) (xy 274.104621 -314.875195) (xy 274.105116 -314.899802) (xy 274.443964 -314.899802)
			(xy 274.447924 -314.850748) (xy 274.459701 -314.802964) (xy 274.478992 -314.757688) (xy 274.505295 -314.716092)
			(xy 274.53793 -314.679255) (xy 274.576051 -314.64813) (xy 274.618672 -314.623523) (xy 274.664688 -314.606071)
			(xy 274.712907 -314.596227) (xy 274.762082 -314.594246) (xy 274.810937 -314.600178) (xy 274.858208 -314.61387)
			(xy 274.90267 -314.634968) (xy 274.943173 -314.662924) (xy 274.978666 -314.697016) (xy 275.008231 -314.73636)
			(xy 275.031102 -314.779937) (xy 275.046686 -314.826618) (xy 275.054581 -314.875195) (xy 275.055076 -314.899802)
			(xy 275.393924 -314.899802) (xy 275.397884 -314.850748) (xy 275.409661 -314.802964) (xy 275.428952 -314.757688)
			(xy 275.455255 -314.716092) (xy 275.48789 -314.679255) (xy 275.526011 -314.64813) (xy 275.568632 -314.623523)
			(xy 275.614648 -314.606071) (xy 275.662867 -314.596227) (xy 275.712042 -314.594246) (xy 275.760897 -314.600178)
			(xy 275.808168 -314.61387) (xy 275.85263 -314.634968) (xy 275.893133 -314.662924) (xy 275.928626 -314.697016)
			(xy 275.958191 -314.73636) (xy 275.981062 -314.779937) (xy 275.996646 -314.826618) (xy 276.004541 -314.875195)
			(xy 276.005036 -314.899802) (xy 276.343884 -314.899802) (xy 276.347844 -314.850748) (xy 276.359621 -314.802964)
			(xy 276.378912 -314.757688) (xy 276.405215 -314.716092) (xy 276.43785 -314.679255) (xy 276.475971 -314.64813)
			(xy 276.518592 -314.623523) (xy 276.564608 -314.606071) (xy 276.612827 -314.596227) (xy 276.662002 -314.594246)
			(xy 276.710857 -314.600178) (xy 276.758128 -314.61387) (xy 276.80259 -314.634968) (xy 276.843093 -314.662924)
			(xy 276.878586 -314.697016) (xy 276.908151 -314.73636) (xy 276.931022 -314.779937) (xy 276.946606 -314.826618)
			(xy 276.954501 -314.875195) (xy 276.954996 -314.899802) (xy 277.294098 -314.899802) (xy 277.298058 -314.850748)
			(xy 277.309835 -314.802964) (xy 277.329126 -314.757688) (xy 277.355429 -314.716092) (xy 277.388064 -314.679255)
			(xy 277.426185 -314.64813) (xy 277.468806 -314.623523) (xy 277.514822 -314.606071) (xy 277.563041 -314.596227)
			(xy 277.612216 -314.594246) (xy 277.661071 -314.600178) (xy 277.708342 -314.61387) (xy 277.752804 -314.634968)
			(xy 277.793307 -314.662924) (xy 277.8288 -314.697016) (xy 277.858365 -314.73636) (xy 277.881236 -314.779937)
			(xy 277.89682 -314.826618) (xy 277.904715 -314.875195) (xy 277.90521 -314.899802) (xy 278.244058 -314.899802)
			(xy 278.248018 -314.850748) (xy 278.259795 -314.802964) (xy 278.279086 -314.757688) (xy 278.305389 -314.716092)
			(xy 278.338024 -314.679255) (xy 278.376145 -314.64813) (xy 278.418766 -314.623523) (xy 278.464782 -314.606071)
			(xy 278.513001 -314.596227) (xy 278.562176 -314.594246) (xy 278.611031 -314.600178) (xy 278.658302 -314.61387)
			(xy 278.702764 -314.634968) (xy 278.743267 -314.662924) (xy 278.77876 -314.697016) (xy 278.808325 -314.73636)
			(xy 278.831196 -314.779937) (xy 278.84678 -314.826618) (xy 278.854675 -314.875195) (xy 278.85517 -314.899802)
			(xy 279.194018 -314.899802) (xy 279.197978 -314.850748) (xy 279.209755 -314.802964) (xy 279.229046 -314.757688)
			(xy 279.255349 -314.716092) (xy 279.287984 -314.679255) (xy 279.326105 -314.64813) (xy 279.368726 -314.623523)
			(xy 279.414742 -314.606071) (xy 279.462961 -314.596227) (xy 279.512136 -314.594246) (xy 279.560991 -314.600178)
			(xy 279.608262 -314.61387) (xy 279.652724 -314.634968) (xy 279.693227 -314.662924) (xy 279.72872 -314.697016)
			(xy 279.758285 -314.73636) (xy 279.781156 -314.779937) (xy 279.79674 -314.826618) (xy 279.804635 -314.875195)
			(xy 279.80513 -314.899802) (xy 280.143978 -314.899802) (xy 280.147938 -314.850748) (xy 280.159715 -314.802964)
			(xy 280.179006 -314.757688) (xy 280.205309 -314.716092) (xy 280.237944 -314.679255) (xy 280.276065 -314.64813)
			(xy 280.318686 -314.623523) (xy 280.364702 -314.606071) (xy 280.412921 -314.596227) (xy 280.462096 -314.594246)
			(xy 280.510951 -314.600178) (xy 280.558222 -314.61387) (xy 280.602684 -314.634968) (xy 280.643187 -314.662924)
			(xy 280.67868 -314.697016) (xy 280.708245 -314.73636) (xy 280.731116 -314.779937) (xy 280.7467 -314.826618)
			(xy 280.754595 -314.875195) (xy 280.75509 -314.899802) (xy 281.093938 -314.899802) (xy 281.097898 -314.850748)
			(xy 281.109675 -314.802964) (xy 281.128966 -314.757688) (xy 281.155269 -314.716092) (xy 281.187904 -314.679255)
			(xy 281.226025 -314.64813) (xy 281.268646 -314.623523) (xy 281.314662 -314.606071) (xy 281.362881 -314.596227)
			(xy 281.412056 -314.594246) (xy 281.460911 -314.600178) (xy 281.508182 -314.61387) (xy 281.552644 -314.634968)
			(xy 281.593147 -314.662924) (xy 281.62864 -314.697016) (xy 281.658205 -314.73636) (xy 281.681076 -314.779937)
			(xy 281.69666 -314.826618) (xy 281.704555 -314.875195) (xy 281.70505 -314.899802) (xy 282.043898 -314.899802)
			(xy 282.047858 -314.850748) (xy 282.059635 -314.802964) (xy 282.078926 -314.757688) (xy 282.105229 -314.716092)
			(xy 282.137864 -314.679255) (xy 282.175985 -314.64813) (xy 282.218606 -314.623523) (xy 282.264622 -314.606071)
			(xy 282.312841 -314.596227) (xy 282.362016 -314.594246) (xy 282.410871 -314.600178) (xy 282.458142 -314.61387)
			(xy 282.502604 -314.634968) (xy 282.543107 -314.662924) (xy 282.5786 -314.697016) (xy 282.608165 -314.73636)
			(xy 282.631036 -314.779937) (xy 282.64662 -314.826618) (xy 282.654515 -314.875195) (xy 282.65501 -314.899802)
			(xy 282.994112 -314.899802) (xy 282.998072 -314.850748) (xy 283.009849 -314.802964) (xy 283.02914 -314.757688)
			(xy 283.055443 -314.716092) (xy 283.088078 -314.679255) (xy 283.126199 -314.64813) (xy 283.16882 -314.623523)
			(xy 283.214836 -314.606071) (xy 283.263055 -314.596227) (xy 283.31223 -314.594246) (xy 283.361085 -314.600178)
			(xy 283.408356 -314.61387) (xy 283.452818 -314.634968) (xy 283.493321 -314.662924) (xy 283.528814 -314.697016)
			(xy 283.558379 -314.73636) (xy 283.58125 -314.779937) (xy 283.596834 -314.826618) (xy 283.604729 -314.875195)
			(xy 283.605224 -314.899802) (xy 283.944072 -314.899802) (xy 283.948032 -314.850748) (xy 283.959809 -314.802964)
			(xy 283.9791 -314.757688) (xy 284.005403 -314.716092) (xy 284.038038 -314.679255) (xy 284.076159 -314.64813)
			(xy 284.11878 -314.623523) (xy 284.164796 -314.606071) (xy 284.213015 -314.596227) (xy 284.26219 -314.594246)
			(xy 284.311045 -314.600178) (xy 284.358316 -314.61387) (xy 284.402778 -314.634968) (xy 284.443281 -314.662924)
			(xy 284.478774 -314.697016) (xy 284.508339 -314.73636) (xy 284.53121 -314.779937) (xy 284.546794 -314.826618)
			(xy 284.554689 -314.875195) (xy 284.555184 -314.899802) (xy 284.894032 -314.899802) (xy 284.897992 -314.850748)
			(xy 284.909769 -314.802964) (xy 284.92906 -314.757688) (xy 284.955363 -314.716092) (xy 284.987998 -314.679255)
			(xy 285.026119 -314.64813) (xy 285.06874 -314.623523) (xy 285.114756 -314.606071) (xy 285.162975 -314.596227)
			(xy 285.21215 -314.594246) (xy 285.261005 -314.600178) (xy 285.308276 -314.61387) (xy 285.352738 -314.634968)
			(xy 285.393241 -314.662924) (xy 285.428734 -314.697016) (xy 285.458299 -314.73636) (xy 285.48117 -314.779937)
			(xy 285.496754 -314.826618) (xy 285.504649 -314.875195) (xy 285.505144 -314.899802) (xy 285.843992 -314.899802)
			(xy 285.847952 -314.850748) (xy 285.859729 -314.802964) (xy 285.87902 -314.757688) (xy 285.905323 -314.716092)
			(xy 285.937958 -314.679255) (xy 285.976079 -314.64813) (xy 286.0187 -314.623523) (xy 286.064716 -314.606071)
			(xy 286.112935 -314.596227) (xy 286.16211 -314.594246) (xy 286.210965 -314.600178) (xy 286.258236 -314.61387)
			(xy 286.302698 -314.634968) (xy 286.343201 -314.662924) (xy 286.378694 -314.697016) (xy 286.408259 -314.73636)
			(xy 286.43113 -314.779937) (xy 286.446714 -314.826618) (xy 286.454609 -314.875195) (xy 286.455104 -314.899802)
			(xy 286.793952 -314.899802) (xy 286.797912 -314.850748) (xy 286.809689 -314.802964) (xy 286.82898 -314.757688)
			(xy 286.855283 -314.716092) (xy 286.887918 -314.679255) (xy 286.926039 -314.64813) (xy 286.96866 -314.623523)
			(xy 287.014676 -314.606071) (xy 287.062895 -314.596227) (xy 287.11207 -314.594246) (xy 287.160925 -314.600178)
			(xy 287.208196 -314.61387) (xy 287.252658 -314.634968) (xy 287.293161 -314.662924) (xy 287.328654 -314.697016)
			(xy 287.358219 -314.73636) (xy 287.38109 -314.779937) (xy 287.396674 -314.826618) (xy 287.404569 -314.875195)
			(xy 287.405064 -314.899802) (xy 287.743912 -314.899802) (xy 287.747872 -314.850748) (xy 287.759649 -314.802964)
			(xy 287.77894 -314.757688) (xy 287.805243 -314.716092) (xy 287.837878 -314.679255) (xy 287.875999 -314.64813)
			(xy 287.91862 -314.623523) (xy 287.964636 -314.606071) (xy 288.012855 -314.596227) (xy 288.06203 -314.594246)
			(xy 288.110885 -314.600178) (xy 288.158156 -314.61387) (xy 288.202618 -314.634968) (xy 288.243121 -314.662924)
			(xy 288.278614 -314.697016) (xy 288.308179 -314.73636) (xy 288.33105 -314.779937) (xy 288.346634 -314.826618)
			(xy 288.354529 -314.875195) (xy 288.355024 -314.899802) (xy 288.694126 -314.899802) (xy 288.698086 -314.850748)
			(xy 288.709863 -314.802964) (xy 288.729154 -314.757688) (xy 288.755457 -314.716092) (xy 288.788092 -314.679255)
			(xy 288.826213 -314.64813) (xy 288.868834 -314.623523) (xy 288.91485 -314.606071) (xy 288.963069 -314.596227)
			(xy 289.012244 -314.594246) (xy 289.061099 -314.600178) (xy 289.10837 -314.61387) (xy 289.152832 -314.634968)
			(xy 289.193335 -314.662924) (xy 289.228828 -314.697016) (xy 289.258393 -314.73636) (xy 289.281264 -314.779937)
			(xy 289.296848 -314.826618) (xy 289.304743 -314.875195) (xy 289.305238 -314.899802) (xy 289.644086 -314.899802)
			(xy 289.648046 -314.850748) (xy 289.659823 -314.802964) (xy 289.679114 -314.757688) (xy 289.705417 -314.716092)
			(xy 289.738052 -314.679255) (xy 289.776173 -314.64813) (xy 289.818794 -314.623523) (xy 289.86481 -314.606071)
			(xy 289.913029 -314.596227) (xy 289.962204 -314.594246) (xy 290.011059 -314.600178) (xy 290.05833 -314.61387)
			(xy 290.102792 -314.634968) (xy 290.143295 -314.662924) (xy 290.178788 -314.697016) (xy 290.208353 -314.73636)
			(xy 290.231224 -314.779937) (xy 290.246808 -314.826618) (xy 290.254703 -314.875195) (xy 290.255198 -314.899802)
			(xy 290.594046 -314.899802) (xy 290.598006 -314.850748) (xy 290.609783 -314.802964) (xy 290.629074 -314.757688)
			(xy 290.655377 -314.716092) (xy 290.688012 -314.679255) (xy 290.726133 -314.64813) (xy 290.768754 -314.623523)
			(xy 290.81477 -314.606071) (xy 290.862989 -314.596227) (xy 290.912164 -314.594246) (xy 290.961019 -314.600178)
			(xy 291.00829 -314.61387) (xy 291.052752 -314.634968) (xy 291.093255 -314.662924) (xy 291.128748 -314.697016)
			(xy 291.158313 -314.73636) (xy 291.181184 -314.779937) (xy 291.196768 -314.826618) (xy 291.204663 -314.875195)
			(xy 291.205158 -314.899802) (xy 291.544006 -314.899802) (xy 291.547966 -314.850748) (xy 291.559743 -314.802964)
			(xy 291.579034 -314.757688) (xy 291.605337 -314.716092) (xy 291.637972 -314.679255) (xy 291.676093 -314.64813)
			(xy 291.718714 -314.623523) (xy 291.76473 -314.606071) (xy 291.812949 -314.596227) (xy 291.862124 -314.594246)
			(xy 291.910979 -314.600178) (xy 291.95825 -314.61387) (xy 292.002712 -314.634968) (xy 292.043215 -314.662924)
			(xy 292.078708 -314.697016) (xy 292.108273 -314.73636) (xy 292.131144 -314.779937) (xy 292.146728 -314.826618)
			(xy 292.154623 -314.875195) (xy 292.155118 -314.899802) (xy 292.493966 -314.899802) (xy 292.497926 -314.850748)
			(xy 292.509703 -314.802964) (xy 292.528994 -314.757688) (xy 292.555297 -314.716092) (xy 292.587932 -314.679255)
			(xy 292.626053 -314.64813) (xy 292.668674 -314.623523) (xy 292.71469 -314.606071) (xy 292.762909 -314.596227)
			(xy 292.812084 -314.594246) (xy 292.860939 -314.600178) (xy 292.90821 -314.61387) (xy 292.952672 -314.634968)
			(xy 292.993175 -314.662924) (xy 293.028668 -314.697016) (xy 293.058233 -314.73636) (xy 293.081104 -314.779937)
			(xy 293.096688 -314.826618) (xy 293.104583 -314.875195) (xy 293.105078 -314.899802) (xy 293.443926 -314.899802)
			(xy 293.447886 -314.850748) (xy 293.459663 -314.802964) (xy 293.478954 -314.757688) (xy 293.505257 -314.716092)
			(xy 293.537892 -314.679255) (xy 293.576013 -314.64813) (xy 293.618634 -314.623523) (xy 293.66465 -314.606071)
			(xy 293.712869 -314.596227) (xy 293.762044 -314.594246) (xy 293.810899 -314.600178) (xy 293.85817 -314.61387)
			(xy 293.902632 -314.634968) (xy 293.943135 -314.662924) (xy 293.978628 -314.697016) (xy 294.008193 -314.73636)
			(xy 294.031064 -314.779937) (xy 294.046648 -314.826618) (xy 294.054543 -314.875195) (xy 294.055038 -314.899802)
			(xy 294.393886 -314.899802) (xy 294.397846 -314.850748) (xy 294.409623 -314.802964) (xy 294.428914 -314.757688)
			(xy 294.455217 -314.716092) (xy 294.487852 -314.679255) (xy 294.525973 -314.64813) (xy 294.568594 -314.623523)
			(xy 294.61461 -314.606071) (xy 294.662829 -314.596227) (xy 294.712004 -314.594246) (xy 294.760859 -314.600178)
			(xy 294.80813 -314.61387) (xy 294.852592 -314.634968) (xy 294.893095 -314.662924) (xy 294.928588 -314.697016)
			(xy 294.958153 -314.73636) (xy 294.981024 -314.779937) (xy 294.996608 -314.826618) (xy 295.004503 -314.875195)
			(xy 295.004998 -314.899802) (xy 295.3441 -314.899802) (xy 295.34806 -314.850748) (xy 295.359837 -314.802964)
			(xy 295.379128 -314.757688) (xy 295.405431 -314.716092) (xy 295.438066 -314.679255) (xy 295.476187 -314.64813)
			(xy 295.518808 -314.623523) (xy 295.564824 -314.606071) (xy 295.613043 -314.596227) (xy 295.662218 -314.594246)
			(xy 295.711073 -314.600178) (xy 295.758344 -314.61387) (xy 295.802806 -314.634968) (xy 295.843309 -314.662924)
			(xy 295.878802 -314.697016) (xy 295.908367 -314.73636) (xy 295.931238 -314.779937) (xy 295.946822 -314.826618)
			(xy 295.954717 -314.875195) (xy 295.955212 -314.899802) (xy 296.29406 -314.899802) (xy 296.29802 -314.850748)
			(xy 296.309797 -314.802964) (xy 296.329088 -314.757688) (xy 296.355391 -314.716092) (xy 296.388026 -314.679255)
			(xy 296.426147 -314.64813) (xy 296.468768 -314.623523) (xy 296.514784 -314.606071) (xy 296.563003 -314.596227)
			(xy 296.612178 -314.594246) (xy 296.661033 -314.600178) (xy 296.708304 -314.61387) (xy 296.752766 -314.634968)
			(xy 296.793269 -314.662924) (xy 296.828762 -314.697016) (xy 296.858327 -314.73636) (xy 296.881198 -314.779937)
			(xy 296.896782 -314.826618) (xy 296.904677 -314.875195) (xy 296.905172 -314.899802) (xy 297.24402 -314.899802)
			(xy 297.24798 -314.850748) (xy 297.259757 -314.802964) (xy 297.279048 -314.757688) (xy 297.305351 -314.716092)
			(xy 297.337986 -314.679255) (xy 297.376107 -314.64813) (xy 297.418728 -314.623523) (xy 297.464744 -314.606071)
			(xy 297.512963 -314.596227) (xy 297.562138 -314.594246) (xy 297.610993 -314.600178) (xy 297.658264 -314.61387)
			(xy 297.702726 -314.634968) (xy 297.743229 -314.662924) (xy 297.778722 -314.697016) (xy 297.808287 -314.73636)
			(xy 297.831158 -314.779937) (xy 297.846742 -314.826618) (xy 297.854637 -314.875195) (xy 297.855132 -314.899802)
			(xy 298.19398 -314.899802) (xy 298.19794 -314.850748) (xy 298.209717 -314.802964) (xy 298.229008 -314.757688)
			(xy 298.255311 -314.716092) (xy 298.287946 -314.679255) (xy 298.326067 -314.64813) (xy 298.368688 -314.623523)
			(xy 298.414704 -314.606071) (xy 298.462923 -314.596227) (xy 298.512098 -314.594246) (xy 298.560953 -314.600178)
			(xy 298.608224 -314.61387) (xy 298.652686 -314.634968) (xy 298.693189 -314.662924) (xy 298.728682 -314.697016)
			(xy 298.758247 -314.73636) (xy 298.781118 -314.779937) (xy 298.796702 -314.826618) (xy 298.804597 -314.875195)
			(xy 298.805092 -314.899802) (xy 299.14394 -314.899802) (xy 299.1479 -314.850748) (xy 299.159677 -314.802964)
			(xy 299.178968 -314.757688) (xy 299.205271 -314.716092) (xy 299.237906 -314.679255) (xy 299.276027 -314.64813)
			(xy 299.318648 -314.623523) (xy 299.364664 -314.606071) (xy 299.412883 -314.596227) (xy 299.462058 -314.594246)
			(xy 299.510913 -314.600178) (xy 299.558184 -314.61387) (xy 299.602646 -314.634968) (xy 299.643149 -314.662924)
			(xy 299.678642 -314.697016) (xy 299.708207 -314.73636) (xy 299.731078 -314.779937) (xy 299.746662 -314.826618)
			(xy 299.754557 -314.875195) (xy 299.755052 -314.899802) (xy 299.754557 -314.924409) (xy 299.746662 -314.972986)
			(xy 299.731078 -315.019667) (xy 299.708207 -315.063244) (xy 299.678642 -315.102588) (xy 299.643149 -315.13668)
			(xy 299.602646 -315.164636) (xy 299.558184 -315.185734) (xy 299.510913 -315.199426) (xy 299.462058 -315.205358)
			(xy 299.412883 -315.203377) (xy 299.364664 -315.193533) (xy 299.318648 -315.176081) (xy 299.276027 -315.151474)
			(xy 299.237906 -315.120349) (xy 299.205271 -315.083512) (xy 299.178968 -315.041916) (xy 299.159677 -314.99664)
			(xy 299.1479 -314.948856) (xy 299.14394 -314.899802) (xy 298.805092 -314.899802) (xy 298.804597 -314.924409)
			(xy 298.796702 -314.972986) (xy 298.781118 -315.019667) (xy 298.758247 -315.063244) (xy 298.728682 -315.102588)
			(xy 298.693189 -315.13668) (xy 298.652686 -315.164636) (xy 298.608224 -315.185734) (xy 298.560953 -315.199426)
			(xy 298.512098 -315.205358) (xy 298.462923 -315.203377) (xy 298.414704 -315.193533) (xy 298.368688 -315.176081)
			(xy 298.326067 -315.151474) (xy 298.287946 -315.120349) (xy 298.255311 -315.083512) (xy 298.229008 -315.041916)
			(xy 298.209717 -314.99664) (xy 298.19794 -314.948856) (xy 298.19398 -314.899802) (xy 297.855132 -314.899802)
			(xy 297.854637 -314.924409) (xy 297.846742 -314.972986) (xy 297.831158 -315.019667) (xy 297.808287 -315.063244)
			(xy 297.778722 -315.102588) (xy 297.743229 -315.13668) (xy 297.702726 -315.164636) (xy 297.658264 -315.185734)
			(xy 297.610993 -315.199426) (xy 297.562138 -315.205358) (xy 297.512963 -315.203377) (xy 297.464744 -315.193533)
			(xy 297.418728 -315.176081) (xy 297.376107 -315.151474) (xy 297.337986 -315.120349) (xy 297.305351 -315.083512)
			(xy 297.279048 -315.041916) (xy 297.259757 -314.99664) (xy 297.24798 -314.948856) (xy 297.24402 -314.899802)
			(xy 296.905172 -314.899802) (xy 296.904677 -314.924409) (xy 296.896782 -314.972986) (xy 296.881198 -315.019667)
			(xy 296.858327 -315.063244) (xy 296.828762 -315.102588) (xy 296.793269 -315.13668) (xy 296.752766 -315.164636)
			(xy 296.708304 -315.185734) (xy 296.661033 -315.199426) (xy 296.612178 -315.205358) (xy 296.563003 -315.203377)
			(xy 296.514784 -315.193533) (xy 296.468768 -315.176081) (xy 296.426147 -315.151474) (xy 296.388026 -315.120349)
			(xy 296.355391 -315.083512) (xy 296.329088 -315.041916) (xy 296.309797 -314.99664) (xy 296.29802 -314.948856)
			(xy 296.29406 -314.899802) (xy 295.955212 -314.899802) (xy 295.954717 -314.924409) (xy 295.946822 -314.972986)
			(xy 295.931238 -315.019667) (xy 295.908367 -315.063244) (xy 295.878802 -315.102588) (xy 295.843309 -315.13668)
			(xy 295.802806 -315.164636) (xy 295.758344 -315.185734) (xy 295.711073 -315.199426) (xy 295.662218 -315.205358)
			(xy 295.613043 -315.203377) (xy 295.564824 -315.193533) (xy 295.518808 -315.176081) (xy 295.476187 -315.151474)
			(xy 295.438066 -315.120349) (xy 295.405431 -315.083512) (xy 295.379128 -315.041916) (xy 295.359837 -314.99664)
			(xy 295.34806 -314.948856) (xy 295.3441 -314.899802) (xy 295.004998 -314.899802) (xy 295.004503 -314.924409)
			(xy 294.996608 -314.972986) (xy 294.981024 -315.019667) (xy 294.958153 -315.063244) (xy 294.928588 -315.102588)
			(xy 294.893095 -315.13668) (xy 294.852592 -315.164636) (xy 294.80813 -315.185734) (xy 294.760859 -315.199426)
			(xy 294.712004 -315.205358) (xy 294.662829 -315.203377) (xy 294.61461 -315.193533) (xy 294.568594 -315.176081)
			(xy 294.525973 -315.151474) (xy 294.487852 -315.120349) (xy 294.455217 -315.083512) (xy 294.428914 -315.041916)
			(xy 294.409623 -314.99664) (xy 294.397846 -314.948856) (xy 294.393886 -314.899802) (xy 294.055038 -314.899802)
			(xy 294.054543 -314.924409) (xy 294.046648 -314.972986) (xy 294.031064 -315.019667) (xy 294.008193 -315.063244)
			(xy 293.978628 -315.102588) (xy 293.943135 -315.13668) (xy 293.902632 -315.164636) (xy 293.85817 -315.185734)
			(xy 293.810899 -315.199426) (xy 293.762044 -315.205358) (xy 293.712869 -315.203377) (xy 293.66465 -315.193533)
			(xy 293.618634 -315.176081) (xy 293.576013 -315.151474) (xy 293.537892 -315.120349) (xy 293.505257 -315.083512)
			(xy 293.478954 -315.041916) (xy 293.459663 -314.99664) (xy 293.447886 -314.948856) (xy 293.443926 -314.899802)
			(xy 293.105078 -314.899802) (xy 293.104583 -314.924409) (xy 293.096688 -314.972986) (xy 293.081104 -315.019667)
			(xy 293.058233 -315.063244) (xy 293.028668 -315.102588) (xy 292.993175 -315.13668) (xy 292.952672 -315.164636)
			(xy 292.90821 -315.185734) (xy 292.860939 -315.199426) (xy 292.812084 -315.205358) (xy 292.762909 -315.203377)
			(xy 292.71469 -315.193533) (xy 292.668674 -315.176081) (xy 292.626053 -315.151474) (xy 292.587932 -315.120349)
			(xy 292.555297 -315.083512) (xy 292.528994 -315.041916) (xy 292.509703 -314.99664) (xy 292.497926 -314.948856)
			(xy 292.493966 -314.899802) (xy 292.155118 -314.899802) (xy 292.154623 -314.924409) (xy 292.146728 -314.972986)
			(xy 292.131144 -315.019667) (xy 292.108273 -315.063244) (xy 292.078708 -315.102588) (xy 292.043215 -315.13668)
			(xy 292.002712 -315.164636) (xy 291.95825 -315.185734) (xy 291.910979 -315.199426) (xy 291.862124 -315.205358)
			(xy 291.812949 -315.203377) (xy 291.76473 -315.193533) (xy 291.718714 -315.176081) (xy 291.676093 -315.151474)
			(xy 291.637972 -315.120349) (xy 291.605337 -315.083512) (xy 291.579034 -315.041916) (xy 291.559743 -314.99664)
			(xy 291.547966 -314.948856) (xy 291.544006 -314.899802) (xy 291.205158 -314.899802) (xy 291.204663 -314.924409)
			(xy 291.196768 -314.972986) (xy 291.181184 -315.019667) (xy 291.158313 -315.063244) (xy 291.128748 -315.102588)
			(xy 291.093255 -315.13668) (xy 291.052752 -315.164636) (xy 291.00829 -315.185734) (xy 290.961019 -315.199426)
			(xy 290.912164 -315.205358) (xy 290.862989 -315.203377) (xy 290.81477 -315.193533) (xy 290.768754 -315.176081)
			(xy 290.726133 -315.151474) (xy 290.688012 -315.120349) (xy 290.655377 -315.083512) (xy 290.629074 -315.041916)
			(xy 290.609783 -314.99664) (xy 290.598006 -314.948856) (xy 290.594046 -314.899802) (xy 290.255198 -314.899802)
			(xy 290.254703 -314.924409) (xy 290.246808 -314.972986) (xy 290.231224 -315.019667) (xy 290.208353 -315.063244)
			(xy 290.178788 -315.102588) (xy 290.143295 -315.13668) (xy 290.102792 -315.164636) (xy 290.05833 -315.185734)
			(xy 290.011059 -315.199426) (xy 289.962204 -315.205358) (xy 289.913029 -315.203377) (xy 289.86481 -315.193533)
			(xy 289.818794 -315.176081) (xy 289.776173 -315.151474) (xy 289.738052 -315.120349) (xy 289.705417 -315.083512)
			(xy 289.679114 -315.041916) (xy 289.659823 -314.99664) (xy 289.648046 -314.948856) (xy 289.644086 -314.899802)
			(xy 289.305238 -314.899802) (xy 289.304743 -314.924409) (xy 289.296848 -314.972986) (xy 289.281264 -315.019667)
			(xy 289.258393 -315.063244) (xy 289.228828 -315.102588) (xy 289.193335 -315.13668) (xy 289.152832 -315.164636)
			(xy 289.10837 -315.185734) (xy 289.061099 -315.199426) (xy 289.012244 -315.205358) (xy 288.963069 -315.203377)
			(xy 288.91485 -315.193533) (xy 288.868834 -315.176081) (xy 288.826213 -315.151474) (xy 288.788092 -315.120349)
			(xy 288.755457 -315.083512) (xy 288.729154 -315.041916) (xy 288.709863 -314.99664) (xy 288.698086 -314.948856)
			(xy 288.694126 -314.899802) (xy 288.355024 -314.899802) (xy 288.354529 -314.924409) (xy 288.346634 -314.972986)
			(xy 288.33105 -315.019667) (xy 288.308179 -315.063244) (xy 288.278614 -315.102588) (xy 288.243121 -315.13668)
			(xy 288.202618 -315.164636) (xy 288.158156 -315.185734) (xy 288.110885 -315.199426) (xy 288.06203 -315.205358)
			(xy 288.012855 -315.203377) (xy 287.964636 -315.193533) (xy 287.91862 -315.176081) (xy 287.875999 -315.151474)
			(xy 287.837878 -315.120349) (xy 287.805243 -315.083512) (xy 287.77894 -315.041916) (xy 287.759649 -314.99664)
			(xy 287.747872 -314.948856) (xy 287.743912 -314.899802) (xy 287.405064 -314.899802) (xy 287.404569 -314.924409)
			(xy 287.396674 -314.972986) (xy 287.38109 -315.019667) (xy 287.358219 -315.063244) (xy 287.328654 -315.102588)
			(xy 287.293161 -315.13668) (xy 287.252658 -315.164636) (xy 287.208196 -315.185734) (xy 287.160925 -315.199426)
			(xy 287.11207 -315.205358) (xy 287.062895 -315.203377) (xy 287.014676 -315.193533) (xy 286.96866 -315.176081)
			(xy 286.926039 -315.151474) (xy 286.887918 -315.120349) (xy 286.855283 -315.083512) (xy 286.82898 -315.041916)
			(xy 286.809689 -314.99664) (xy 286.797912 -314.948856) (xy 286.793952 -314.899802) (xy 286.455104 -314.899802)
			(xy 286.454609 -314.924409) (xy 286.446714 -314.972986) (xy 286.43113 -315.019667) (xy 286.408259 -315.063244)
			(xy 286.378694 -315.102588) (xy 286.343201 -315.13668) (xy 286.302698 -315.164636) (xy 286.258236 -315.185734)
			(xy 286.210965 -315.199426) (xy 286.16211 -315.205358) (xy 286.112935 -315.203377) (xy 286.064716 -315.193533)
			(xy 286.0187 -315.176081) (xy 285.976079 -315.151474) (xy 285.937958 -315.120349) (xy 285.905323 -315.083512)
			(xy 285.87902 -315.041916) (xy 285.859729 -314.99664) (xy 285.847952 -314.948856) (xy 285.843992 -314.899802)
			(xy 285.505144 -314.899802) (xy 285.504649 -314.924409) (xy 285.496754 -314.972986) (xy 285.48117 -315.019667)
			(xy 285.458299 -315.063244) (xy 285.428734 -315.102588) (xy 285.393241 -315.13668) (xy 285.352738 -315.164636)
			(xy 285.308276 -315.185734) (xy 285.261005 -315.199426) (xy 285.21215 -315.205358) (xy 285.162975 -315.203377)
			(xy 285.114756 -315.193533) (xy 285.06874 -315.176081) (xy 285.026119 -315.151474) (xy 284.987998 -315.120349)
			(xy 284.955363 -315.083512) (xy 284.92906 -315.041916) (xy 284.909769 -314.99664) (xy 284.897992 -314.948856)
			(xy 284.894032 -314.899802) (xy 284.555184 -314.899802) (xy 284.554689 -314.924409) (xy 284.546794 -314.972986)
			(xy 284.53121 -315.019667) (xy 284.508339 -315.063244) (xy 284.478774 -315.102588) (xy 284.443281 -315.13668)
			(xy 284.402778 -315.164636) (xy 284.358316 -315.185734) (xy 284.311045 -315.199426) (xy 284.26219 -315.205358)
			(xy 284.213015 -315.203377) (xy 284.164796 -315.193533) (xy 284.11878 -315.176081) (xy 284.076159 -315.151474)
			(xy 284.038038 -315.120349) (xy 284.005403 -315.083512) (xy 283.9791 -315.041916) (xy 283.959809 -314.99664)
			(xy 283.948032 -314.948856) (xy 283.944072 -314.899802) (xy 283.605224 -314.899802) (xy 283.604729 -314.924409)
			(xy 283.596834 -314.972986) (xy 283.58125 -315.019667) (xy 283.558379 -315.063244) (xy 283.528814 -315.102588)
			(xy 283.493321 -315.13668) (xy 283.452818 -315.164636) (xy 283.408356 -315.185734) (xy 283.361085 -315.199426)
			(xy 283.31223 -315.205358) (xy 283.263055 -315.203377) (xy 283.214836 -315.193533) (xy 283.16882 -315.176081)
			(xy 283.126199 -315.151474) (xy 283.088078 -315.120349) (xy 283.055443 -315.083512) (xy 283.02914 -315.041916)
			(xy 283.009849 -314.99664) (xy 282.998072 -314.948856) (xy 282.994112 -314.899802) (xy 282.65501 -314.899802)
			(xy 282.654515 -314.924409) (xy 282.64662 -314.972986) (xy 282.631036 -315.019667) (xy 282.608165 -315.063244)
			(xy 282.5786 -315.102588) (xy 282.543107 -315.13668) (xy 282.502604 -315.164636) (xy 282.458142 -315.185734)
			(xy 282.410871 -315.199426) (xy 282.362016 -315.205358) (xy 282.312841 -315.203377) (xy 282.264622 -315.193533)
			(xy 282.218606 -315.176081) (xy 282.175985 -315.151474) (xy 282.137864 -315.120349) (xy 282.105229 -315.083512)
			(xy 282.078926 -315.041916) (xy 282.059635 -314.99664) (xy 282.047858 -314.948856) (xy 282.043898 -314.899802)
			(xy 281.70505 -314.899802) (xy 281.704555 -314.924409) (xy 281.69666 -314.972986) (xy 281.681076 -315.019667)
			(xy 281.658205 -315.063244) (xy 281.62864 -315.102588) (xy 281.593147 -315.13668) (xy 281.552644 -315.164636)
			(xy 281.508182 -315.185734) (xy 281.460911 -315.199426) (xy 281.412056 -315.205358) (xy 281.362881 -315.203377)
			(xy 281.314662 -315.193533) (xy 281.268646 -315.176081) (xy 281.226025 -315.151474) (xy 281.187904 -315.120349)
			(xy 281.155269 -315.083512) (xy 281.128966 -315.041916) (xy 281.109675 -314.99664) (xy 281.097898 -314.948856)
			(xy 281.093938 -314.899802) (xy 280.75509 -314.899802) (xy 280.754595 -314.924409) (xy 280.7467 -314.972986)
			(xy 280.731116 -315.019667) (xy 280.708245 -315.063244) (xy 280.67868 -315.102588) (xy 280.643187 -315.13668)
			(xy 280.602684 -315.164636) (xy 280.558222 -315.185734) (xy 280.510951 -315.199426) (xy 280.462096 -315.205358)
			(xy 280.412921 -315.203377) (xy 280.364702 -315.193533) (xy 280.318686 -315.176081) (xy 280.276065 -315.151474)
			(xy 280.237944 -315.120349) (xy 280.205309 -315.083512) (xy 280.179006 -315.041916) (xy 280.159715 -314.99664)
			(xy 280.147938 -314.948856) (xy 280.143978 -314.899802) (xy 279.80513 -314.899802) (xy 279.804635 -314.924409)
			(xy 279.79674 -314.972986) (xy 279.781156 -315.019667) (xy 279.758285 -315.063244) (xy 279.72872 -315.102588)
			(xy 279.693227 -315.13668) (xy 279.652724 -315.164636) (xy 279.608262 -315.185734) (xy 279.560991 -315.199426)
			(xy 279.512136 -315.205358) (xy 279.462961 -315.203377) (xy 279.414742 -315.193533) (xy 279.368726 -315.176081)
			(xy 279.326105 -315.151474) (xy 279.287984 -315.120349) (xy 279.255349 -315.083512) (xy 279.229046 -315.041916)
			(xy 279.209755 -314.99664) (xy 279.197978 -314.948856) (xy 279.194018 -314.899802) (xy 278.85517 -314.899802)
			(xy 278.854675 -314.924409) (xy 278.84678 -314.972986) (xy 278.831196 -315.019667) (xy 278.808325 -315.063244)
			(xy 278.77876 -315.102588) (xy 278.743267 -315.13668) (xy 278.702764 -315.164636) (xy 278.658302 -315.185734)
			(xy 278.611031 -315.199426) (xy 278.562176 -315.205358) (xy 278.513001 -315.203377) (xy 278.464782 -315.193533)
			(xy 278.418766 -315.176081) (xy 278.376145 -315.151474) (xy 278.338024 -315.120349) (xy 278.305389 -315.083512)
			(xy 278.279086 -315.041916) (xy 278.259795 -314.99664) (xy 278.248018 -314.948856) (xy 278.244058 -314.899802)
			(xy 277.90521 -314.899802) (xy 277.904715 -314.924409) (xy 277.89682 -314.972986) (xy 277.881236 -315.019667)
			(xy 277.858365 -315.063244) (xy 277.8288 -315.102588) (xy 277.793307 -315.13668) (xy 277.752804 -315.164636)
			(xy 277.708342 -315.185734) (xy 277.661071 -315.199426) (xy 277.612216 -315.205358) (xy 277.563041 -315.203377)
			(xy 277.514822 -315.193533) (xy 277.468806 -315.176081) (xy 277.426185 -315.151474) (xy 277.388064 -315.120349)
			(xy 277.355429 -315.083512) (xy 277.329126 -315.041916) (xy 277.309835 -314.99664) (xy 277.298058 -314.948856)
			(xy 277.294098 -314.899802) (xy 276.954996 -314.899802) (xy 276.954501 -314.924409) (xy 276.946606 -314.972986)
			(xy 276.931022 -315.019667) (xy 276.908151 -315.063244) (xy 276.878586 -315.102588) (xy 276.843093 -315.13668)
			(xy 276.80259 -315.164636) (xy 276.758128 -315.185734) (xy 276.710857 -315.199426) (xy 276.662002 -315.205358)
			(xy 276.612827 -315.203377) (xy 276.564608 -315.193533) (xy 276.518592 -315.176081) (xy 276.475971 -315.151474)
			(xy 276.43785 -315.120349) (xy 276.405215 -315.083512) (xy 276.378912 -315.041916) (xy 276.359621 -314.99664)
			(xy 276.347844 -314.948856) (xy 276.343884 -314.899802) (xy 276.005036 -314.899802) (xy 276.004541 -314.924409)
			(xy 275.996646 -314.972986) (xy 275.981062 -315.019667) (xy 275.958191 -315.063244) (xy 275.928626 -315.102588)
			(xy 275.893133 -315.13668) (xy 275.85263 -315.164636) (xy 275.808168 -315.185734) (xy 275.760897 -315.199426)
			(xy 275.712042 -315.205358) (xy 275.662867 -315.203377) (xy 275.614648 -315.193533) (xy 275.568632 -315.176081)
			(xy 275.526011 -315.151474) (xy 275.48789 -315.120349) (xy 275.455255 -315.083512) (xy 275.428952 -315.041916)
			(xy 275.409661 -314.99664) (xy 275.397884 -314.948856) (xy 275.393924 -314.899802) (xy 275.055076 -314.899802)
			(xy 275.054581 -314.924409) (xy 275.046686 -314.972986) (xy 275.031102 -315.019667) (xy 275.008231 -315.063244)
			(xy 274.978666 -315.102588) (xy 274.943173 -315.13668) (xy 274.90267 -315.164636) (xy 274.858208 -315.185734)
			(xy 274.810937 -315.199426) (xy 274.762082 -315.205358) (xy 274.712907 -315.203377) (xy 274.664688 -315.193533)
			(xy 274.618672 -315.176081) (xy 274.576051 -315.151474) (xy 274.53793 -315.120349) (xy 274.505295 -315.083512)
			(xy 274.478992 -315.041916) (xy 274.459701 -314.99664) (xy 274.447924 -314.948856) (xy 274.443964 -314.899802)
			(xy 274.105116 -314.899802) (xy 274.104621 -314.924409) (xy 274.096726 -314.972986) (xy 274.081142 -315.019667)
			(xy 274.058271 -315.063244) (xy 274.028706 -315.102588) (xy 273.993213 -315.13668) (xy 273.95271 -315.164636)
			(xy 273.908248 -315.185734) (xy 273.860977 -315.199426) (xy 273.812122 -315.205358) (xy 273.762947 -315.203377)
			(xy 273.714728 -315.193533) (xy 273.668712 -315.176081) (xy 273.626091 -315.151474) (xy 273.58797 -315.120349)
			(xy 273.555335 -315.083512) (xy 273.529032 -315.041916) (xy 273.509741 -314.99664) (xy 273.497964 -314.948856)
			(xy 273.494004 -314.899802) (xy 273.155156 -314.899802) (xy 273.154661 -314.924409) (xy 273.146766 -314.972986)
			(xy 273.131182 -315.019667) (xy 273.108311 -315.063244) (xy 273.078746 -315.102588) (xy 273.043253 -315.13668)
			(xy 273.00275 -315.164636) (xy 272.958288 -315.185734) (xy 272.911017 -315.199426) (xy 272.862162 -315.205358)
			(xy 272.812987 -315.203377) (xy 272.764768 -315.193533) (xy 272.718752 -315.176081) (xy 272.676131 -315.151474)
			(xy 272.63801 -315.120349) (xy 272.605375 -315.083512) (xy 272.579072 -315.041916) (xy 272.559781 -314.99664)
			(xy 272.548004 -314.948856) (xy 272.544044 -314.899802) (xy 272.205196 -314.899802) (xy 272.204701 -314.924409)
			(xy 272.196806 -314.972986) (xy 272.181222 -315.019667) (xy 272.158351 -315.063244) (xy 272.128786 -315.102588)
			(xy 272.093293 -315.13668) (xy 272.05279 -315.164636) (xy 272.008328 -315.185734) (xy 271.961057 -315.199426)
			(xy 271.912202 -315.205358) (xy 271.863027 -315.203377) (xy 271.814808 -315.193533) (xy 271.768792 -315.176081)
			(xy 271.726171 -315.151474) (xy 271.68805 -315.120349) (xy 271.655415 -315.083512) (xy 271.629112 -315.041916)
			(xy 271.609821 -314.99664) (xy 271.598044 -314.948856) (xy 271.594084 -314.899802) (xy 271.255236 -314.899802)
			(xy 271.254741 -314.924409) (xy 271.246846 -314.972986) (xy 271.231262 -315.019667) (xy 271.208391 -315.063244)
			(xy 271.178826 -315.102588) (xy 271.143333 -315.13668) (xy 271.10283 -315.164636) (xy 271.058368 -315.185734)
			(xy 271.011097 -315.199426) (xy 270.962242 -315.205358) (xy 270.913067 -315.203377) (xy 270.864848 -315.193533)
			(xy 270.818832 -315.176081) (xy 270.776211 -315.151474) (xy 270.73809 -315.120349) (xy 270.705455 -315.083512)
			(xy 270.679152 -315.041916) (xy 270.659861 -314.99664) (xy 270.648084 -314.948856) (xy 270.644124 -314.899802)
			(xy 270.326866 -314.899802) (xy 270.326362 -314.92551) (xy 270.318319 -314.976292) (xy 270.302431 -315.025191)
			(xy 270.279088 -315.071003) (xy 270.248867 -315.112599) (xy 270.212511 -315.148955) (xy 270.170915 -315.179176)
			(xy 270.125103 -315.202519) (xy 270.076204 -315.218407) (xy 270.025422 -315.22645) (xy 269.974006 -315.22645)
			(xy 269.923224 -315.218407) (xy 269.874325 -315.202519) (xy 269.828513 -315.179176) (xy 269.786917 -315.148955)
			(xy 269.750561 -315.112599) (xy 269.72034 -315.071003) (xy 269.696997 -315.025191) (xy 269.681109 -314.976292)
			(xy 269.673066 -314.92551) (xy 269.376402 -314.92551) (xy 269.368359 -314.976292) (xy 269.352471 -315.025191)
			(xy 269.329128 -315.071003) (xy 269.298907 -315.112599) (xy 269.262551 -315.148955) (xy 269.220955 -315.179176)
			(xy 269.175143 -315.202519) (xy 269.126244 -315.218407) (xy 269.075462 -315.22645) (xy 269.024046 -315.22645)
			(xy 268.973264 -315.218407) (xy 268.924365 -315.202519) (xy 268.878553 -315.179176) (xy 268.836957 -315.148955)
			(xy 268.800601 -315.112599) (xy 268.77038 -315.071003) (xy 268.747037 -315.025191) (xy 268.731149 -314.976292)
			(xy 268.723106 -314.92551) (xy 268.403879 -314.92551) (xy 268.396204 -314.972732) (xy 268.38062 -315.019413)
			(xy 268.357749 -315.06299) (xy 268.328184 -315.102334) (xy 268.292691 -315.136426) (xy 268.252188 -315.164382)
			(xy 268.207726 -315.18548) (xy 268.160455 -315.199172) (xy 268.1116 -315.205104) (xy 268.062425 -315.203123)
			(xy 268.014206 -315.193279) (xy 267.96819 -315.175827) (xy 267.925569 -315.15122) (xy 267.887448 -315.120095)
			(xy 267.854813 -315.083258) (xy 267.82851 -315.041662) (xy 267.809219 -314.996386) (xy 267.797442 -314.948602)
			(xy 267.793482 -314.899548) (xy 255.945132 -314.899548) (xy 255.945132 -314.991242) (xy 255.945563 -315.001308)
			(xy 255.953292 -315.019899) (xy 255.960118 -315.02731) (xy 256.878328 -315.94552) (xy 256.885724 -315.952371)
			(xy 256.904323 -315.960108) (xy 256.914396 -315.960506)
		)
		(stroke
			(width 0)
			(type solid)
		)
		(fill yes)
		(layer "In15.Cu")
		(net "P1V25_SERDES_VDDPLL_PEX2")
	)
	(gr_poly
		(pts
			(xy 446.781174 -417.053776) (xy 446.790892 -417.053352) (xy 446.808942 -417.046141) (xy 446.82302 -417.03274)
			(xy 446.827402 -417.024058) (xy 446.872106 -416.926522) (xy 446.868042 -416.897312) (xy 446.858136 -416.885882)
			(xy 446.84078 -416.865018) (xy 446.811531 -416.819305) (xy 446.789062 -416.769906) (xy 446.773827 -416.717818)
			(xy 446.766134 -416.664097) (xy 446.76568 -416.636962) (xy 446.766166 -416.609711) (xy 446.773922 -416.555763)
			(xy 446.789277 -416.503468) (xy 446.811919 -416.453891) (xy 446.841385 -416.408041) (xy 446.877076 -416.36685)
			(xy 446.918267 -416.331159) (xy 446.964117 -416.301693) (xy 447.013694 -416.279051) (xy 447.065989 -416.263696)
			(xy 447.119937 -416.25594) (xy 447.174439 -416.25594) (xy 447.228387 -416.263696) (xy 447.280682 -416.279051)
			(xy 447.330259 -416.301693) (xy 447.376109 -416.331159) (xy 447.4173 -416.36685) (xy 447.452991 -416.408041)
			(xy 447.482457 -416.453891) (xy 447.505099 -416.503468) (xy 447.520454 -416.555763) (xy 447.52821 -416.609711)
			(xy 447.528696 -416.636962) (xy 447.528214 -416.664094) (xy 447.520513 -416.71781) (xy 447.505277 -416.769892)
			(xy 447.482813 -416.819289) (xy 447.453574 -416.865003) (xy 447.43624 -416.885882) (xy 447.426334 -416.897312)
			(xy 447.42227 -416.926522) (xy 447.466974 -417.024058) (xy 447.471394 -417.032721) (xy 447.485449 -417.046139)
			(xy 447.503486 -417.053366) (xy 447.513202 -417.053776) (xy 448.813174 -417.053776) (xy 448.822892 -417.053352)
			(xy 448.840942 -417.046141) (xy 448.85502 -417.03274) (xy 448.859402 -417.024058) (xy 448.904106 -416.926522)
			(xy 448.900042 -416.897312) (xy 448.890136 -416.885882) (xy 448.87278 -416.865018) (xy 448.843531 -416.819305)
			(xy 448.821062 -416.769906) (xy 448.805827 -416.717818) (xy 448.798134 -416.664097) (xy 448.79768 -416.636962)
			(xy 448.798166 -416.609711) (xy 448.805922 -416.555763) (xy 448.821277 -416.503468) (xy 448.843919 -416.453891)
			(xy 448.873385 -416.408041) (xy 448.909076 -416.36685) (xy 448.950267 -416.331159) (xy 448.996117 -416.301693)
			(xy 449.045694 -416.279051) (xy 449.097989 -416.263696) (xy 449.151937 -416.25594) (xy 449.206439 -416.25594)
			(xy 449.260387 -416.263696) (xy 449.312682 -416.279051) (xy 449.362259 -416.301693) (xy 449.408109 -416.331159)
			(xy 449.4493 -416.36685) (xy 449.484991 -416.408041) (xy 449.514457 -416.453891) (xy 449.537099 -416.503468)
			(xy 449.552454 -416.555763) (xy 449.56021 -416.609711) (xy 449.560696 -416.636962) (xy 449.560214 -416.664094)
			(xy 449.552513 -416.71781) (xy 449.537277 -416.769892) (xy 449.514813 -416.819289) (xy 449.485574 -416.865003)
			(xy 449.46824 -416.885882) (xy 449.458334 -416.897312) (xy 449.45427 -416.926522) (xy 449.498974 -417.024058)
			(xy 449.503394 -417.032721) (xy 449.517449 -417.046139) (xy 449.535486 -417.053366) (xy 449.545202 -417.053776)
			(xy 449.829174 -417.053776) (xy 449.838892 -417.053352) (xy 449.856942 -417.046141) (xy 449.87102 -417.03274)
			(xy 449.875402 -417.024058) (xy 449.920106 -416.926522) (xy 449.916042 -416.897312) (xy 449.906136 -416.885882)
			(xy 449.88878 -416.865018) (xy 449.859531 -416.819305) (xy 449.837062 -416.769906) (xy 449.821827 -416.717818)
			(xy 449.814134 -416.664097) (xy 449.81368 -416.636962) (xy 449.814166 -416.609711) (xy 449.821922 -416.555763)
			(xy 449.837277 -416.503468) (xy 449.859919 -416.453891) (xy 449.889385 -416.408041) (xy 449.925076 -416.36685)
			(xy 449.966267 -416.331159) (xy 450.012117 -416.301693) (xy 450.061694 -416.279051) (xy 450.113989 -416.263696)
			(xy 450.167937 -416.25594) (xy 450.222439 -416.25594) (xy 450.276387 -416.263696) (xy 450.328682 -416.279051)
			(xy 450.378259 -416.301693) (xy 450.424109 -416.331159) (xy 450.4653 -416.36685) (xy 450.500991 -416.408041)
			(xy 450.530457 -416.453891) (xy 450.553099 -416.503468) (xy 450.568454 -416.555763) (xy 450.57621 -416.609711)
			(xy 450.576696 -416.636962) (xy 450.576214 -416.664094) (xy 450.568513 -416.71781) (xy 450.553277 -416.769892)
			(xy 450.530813 -416.819289) (xy 450.501574 -416.865003) (xy 450.48424 -416.885882) (xy 450.474334 -416.897312)
			(xy 450.47027 -416.926522) (xy 450.514974 -417.024058) (xy 450.519394 -417.032721) (xy 450.533449 -417.046139)
			(xy 450.551486 -417.053366) (xy 450.561202 -417.053776) (xy 465.6074 -417.053776) (xy 465.61747 -417.053352)
			(xy 465.636072 -417.045635) (xy 465.643468 -417.03879) (xy 466.152484 -416.529774) (xy 466.159328 -416.522375)
			(xy 466.167056 -416.503777) (xy 466.16747 -416.493706) (xy 466.16747 -323.556122) (xy 466.167032 -323.546059)
			(xy 466.159294 -323.527478) (xy 466.152484 -323.520054) (xy 465.105242 -322.472812) (xy 465.097841 -322.465973)
			(xy 465.079243 -322.458258) (xy 465.069174 -322.457826) (xy 448.192398 -322.457826) (xy 448.182327 -322.457403)
			(xy 448.163721 -322.449691) (xy 448.15633 -322.44284) (xy 446.438274 -320.724784) (xy 446.431422 -320.717388)
			(xy 446.423682 -320.698789) (xy 446.423288 -320.688716) (xy 446.423288 -311.865772) (xy 446.42274 -311.855141)
			(xy 446.414134 -311.835699) (xy 446.398401 -311.821396) (xy 446.38849 -311.817512) (xy 446.309955 -311.790986)
			(xy 446.15531 -311.731242) (xy 446.003781 -311.663985) (xy 445.855733 -311.589377) (xy 445.711522 -311.507598)
			(xy 445.571497 -311.418843) (xy 445.435993 -311.323328) (xy 445.305336 -311.221282) (xy 445.179842 -311.11295)
			(xy 445.059813 -310.998594) (xy 444.945536 -310.878488) (xy 444.837288 -310.752922) (xy 444.735329 -310.622197)
			(xy 444.639904 -310.486629) (xy 444.551243 -310.346545) (xy 444.46956 -310.20228) (xy 444.395051 -310.054182)
			(xy 444.327895 -309.902608) (xy 444.268254 -309.747923) (xy 444.216272 -309.590499) (xy 444.172073 -309.430715)
			(xy 444.135765 -309.268955) (xy 444.107434 -309.105609) (xy 444.087149 -308.94107) (xy 444.074958 -308.775735)
			(xy 444.070891 -308.61) (xy 444.074958 -308.444265) (xy 444.087149 -308.27893) (xy 444.107434 -308.114391)
			(xy 444.135765 -307.951045) (xy 444.172073 -307.789285) (xy 444.216272 -307.629501) (xy 444.268254 -307.472077)
			(xy 444.327895 -307.317392) (xy 444.395051 -307.165818) (xy 444.46956 -307.01772) (xy 444.551243 -306.873455)
			(xy 444.639904 -306.733371) (xy 444.735329 -306.597803) (xy 444.837288 -306.467078) (xy 444.945536 -306.341512)
			(xy 445.059813 -306.221406) (xy 445.179842 -306.10705) (xy 445.305336 -305.998718) (xy 445.435993 -305.896672)
			(xy 445.571497 -305.801157) (xy 445.711522 -305.712402) (xy 445.855733 -305.630623) (xy 446.003781 -305.556015)
			(xy 446.15531 -305.488758) (xy 446.309955 -305.429014) (xy 446.38849 -305.402488) (xy 446.398426 -305.398634)
			(xy 446.414195 -305.384338) (xy 446.422806 -305.364871) (xy 446.423288 -305.354228) (xy 446.423288 -292.158928)
			(xy 446.422851 -292.148864) (xy 446.415117 -292.13028) (xy 446.408302 -292.12286) (xy 445.444372 -291.15893)
			(xy 445.436973 -291.152085) (xy 445.418375 -291.144356) (xy 445.408304 -291.143944) (xy 440.055254 -291.143944)
			(xy 440.045189 -291.144377) (xy 440.0266 -291.152108) (xy 440.019186 -291.15893) (xy 439.056109 -292.122098)
			(xy 441.5569 -292.122098) (xy 441.560971 -292.066476) (xy 441.573097 -292.012039) (xy 441.59302 -291.959948)
			(xy 441.620316 -291.911313) (xy 441.654402 -291.86717) (xy 441.694551 -291.828461) (xy 441.739909 -291.79601)
			(xy 441.789509 -291.770509) (xy 441.842293 -291.752502) (xy 441.897136 -291.742372) (xy 441.95287 -291.740335)
			(xy 442.008307 -291.746435) (xy 442.062264 -291.760541) (xy 442.113593 -291.782353) (xy 442.161199 -291.811407)
			(xy 442.204067 -291.847082) (xy 442.241284 -291.888619) (xy 442.272057 -291.935132) (xy 442.295729 -291.985629)
			(xy 442.311797 -292.039036) (xy 442.319917 -292.094212) (xy 442.320426 -292.122098) (xy 442.319917 -292.149984)
			(xy 442.311797 -292.20516) (xy 442.295729 -292.258567) (xy 442.272057 -292.309064) (xy 442.241284 -292.355577)
			(xy 442.204067 -292.397114) (xy 442.161199 -292.432789) (xy 442.113593 -292.461843) (xy 442.062264 -292.483655)
			(xy 442.008307 -292.497761) (xy 441.95287 -292.503861) (xy 441.897136 -292.501824) (xy 441.842293 -292.491694)
			(xy 441.789509 -292.473687) (xy 441.739909 -292.448186) (xy 441.694551 -292.415735) (xy 441.654402 -292.377026)
			(xy 441.620316 -292.332883) (xy 441.59302 -292.284248) (xy 441.573097 -292.232157) (xy 441.560971 -292.17772)
			(xy 441.5569 -292.122098) (xy 439.056109 -292.122098) (xy 437.34228 -293.83609) (xy 437.320703 -293.856822)
			(xy 437.272284 -293.891979) (xy 437.218965 -293.919133) (xy 437.162057 -293.937618) (xy 437.102958 -293.946979)
			(xy 437.07304 -293.947596) (xy 436.803038 -293.947596) (xy 436.792973 -293.948031) (xy 436.774384 -293.95576)
			(xy 436.76697 -293.962582) (xy 436.713376 -294.016176) (xy 437.940702 -294.016176) (xy 437.944773 -293.960554)
			(xy 437.956899 -293.906117) (xy 437.976822 -293.854026) (xy 438.004118 -293.805391) (xy 438.038204 -293.761248)
			(xy 438.078353 -293.722539) (xy 438.123711 -293.690088) (xy 438.173311 -293.664587) (xy 438.226095 -293.64658)
			(xy 438.280938 -293.63645) (xy 438.336672 -293.634413) (xy 438.392109 -293.640513) (xy 438.446066 -293.654619)
			(xy 438.497395 -293.676431) (xy 438.545001 -293.705485) (xy 438.587869 -293.74116) (xy 438.625086 -293.782697)
			(xy 438.655859 -293.82921) (xy 438.679531 -293.879707) (xy 438.695599 -293.933114) (xy 438.70259 -293.980616)
			(xy 439.58078 -293.980616) (xy 439.584851 -293.924994) (xy 439.596977 -293.870557) (xy 439.6169 -293.818466)
			(xy 439.644196 -293.769831) (xy 439.678282 -293.725688) (xy 439.718431 -293.686979) (xy 439.763789 -293.654528)
			(xy 439.813389 -293.629027) (xy 439.866173 -293.61102) (xy 439.921016 -293.60089) (xy 439.97675 -293.598853)
			(xy 440.032187 -293.604953) (xy 440.086144 -293.619059) (xy 440.137473 -293.640871) (xy 440.185079 -293.669925)
			(xy 440.227947 -293.7056) (xy 440.265164 -293.747137) (xy 440.295937 -293.79365) (xy 440.319609 -293.844147)
			(xy 440.335677 -293.897554) (xy 440.343797 -293.95273) (xy 440.344306 -293.980616) (xy 440.343797 -294.008502)
			(xy 440.335677 -294.063678) (xy 440.319609 -294.117085) (xy 440.295937 -294.167582) (xy 440.265164 -294.214095)
			(xy 440.227947 -294.255632) (xy 440.185079 -294.291307) (xy 440.137473 -294.320361) (xy 440.086144 -294.342173)
			(xy 440.032187 -294.356279) (xy 439.97675 -294.362379) (xy 439.921016 -294.360342) (xy 439.866173 -294.350212)
			(xy 439.813389 -294.332205) (xy 439.763789 -294.306704) (xy 439.718431 -294.274253) (xy 439.678282 -294.235544)
			(xy 439.644196 -294.191401) (xy 439.6169 -294.142766) (xy 439.596977 -294.090675) (xy 439.584851 -294.036238)
			(xy 439.58078 -293.980616) (xy 438.70259 -293.980616) (xy 438.703719 -293.98829) (xy 438.704228 -294.016176)
			(xy 438.703719 -294.044062) (xy 438.695599 -294.099238) (xy 438.679531 -294.152645) (xy 438.655859 -294.203142)
			(xy 438.625086 -294.249655) (xy 438.587869 -294.291192) (xy 438.545001 -294.326867) (xy 438.497395 -294.355921)
			(xy 438.446066 -294.377733) (xy 438.392109 -294.391839) (xy 438.336672 -294.397939) (xy 438.280938 -294.395902)
			(xy 438.226095 -294.385772) (xy 438.173311 -294.367765) (xy 438.123711 -294.342264) (xy 438.078353 -294.309813)
			(xy 438.038204 -294.271104) (xy 438.004118 -294.226961) (xy 437.976822 -294.178326) (xy 437.956899 -294.126235)
			(xy 437.944773 -294.071798) (xy 437.940702 -294.016176) (xy 436.713376 -294.016176) (xy 434.11648 -296.613072)
			(xy 437.562496 -296.613072) (xy 437.566567 -296.55745) (xy 437.578693 -296.503013) (xy 437.598616 -296.450922)
			(xy 437.625912 -296.402287) (xy 437.659998 -296.358144) (xy 437.700147 -296.319435) (xy 437.745505 -296.286984)
			(xy 437.795105 -296.261483) (xy 437.847889 -296.243476) (xy 437.902732 -296.233346) (xy 437.958466 -296.231309)
			(xy 438.013903 -296.237409) (xy 438.06786 -296.251515) (xy 438.119189 -296.273327) (xy 438.166795 -296.302381)
			(xy 438.209663 -296.338056) (xy 438.24688 -296.379593) (xy 438.277653 -296.426106) (xy 438.301325 -296.476603)
			(xy 438.317393 -296.53001) (xy 438.325513 -296.585186) (xy 438.326022 -296.613072) (xy 438.837322 -296.613072)
			(xy 438.841393 -296.55745) (xy 438.853519 -296.503013) (xy 438.873442 -296.450922) (xy 438.900738 -296.402287)
			(xy 438.934824 -296.358144) (xy 438.974973 -296.319435) (xy 439.020331 -296.286984) (xy 439.069931 -296.261483)
			(xy 439.122715 -296.243476) (xy 439.177558 -296.233346) (xy 439.233292 -296.231309) (xy 439.288729 -296.237409)
			(xy 439.342686 -296.251515) (xy 439.394015 -296.273327) (xy 439.441621 -296.302381) (xy 439.484489 -296.338056)
			(xy 439.521706 -296.379593) (xy 439.552479 -296.426106) (xy 439.576151 -296.476603) (xy 439.592219 -296.53001)
			(xy 439.600339 -296.585186) (xy 439.600848 -296.613072) (xy 439.600339 -296.640958) (xy 439.592219 -296.696134)
			(xy 439.576151 -296.749541) (xy 439.552479 -296.800038) (xy 439.521706 -296.846551) (xy 439.484489 -296.888088)
			(xy 439.441621 -296.923763) (xy 439.394015 -296.952817) (xy 439.342686 -296.974629) (xy 439.288729 -296.988735)
			(xy 439.233292 -296.994835) (xy 439.177558 -296.992798) (xy 439.122715 -296.982668) (xy 439.069931 -296.964661)
			(xy 439.020331 -296.93916) (xy 438.974973 -296.906709) (xy 438.934824 -296.868) (xy 438.900738 -296.823857)
			(xy 438.873442 -296.775222) (xy 438.853519 -296.723131) (xy 438.841393 -296.668694) (xy 438.837322 -296.613072)
			(xy 438.326022 -296.613072) (xy 438.325513 -296.640958) (xy 438.317393 -296.696134) (xy 438.301325 -296.749541)
			(xy 438.277653 -296.800038) (xy 438.24688 -296.846551) (xy 438.209663 -296.888088) (xy 438.166795 -296.923763)
			(xy 438.119189 -296.952817) (xy 438.06786 -296.974629) (xy 438.013903 -296.988735) (xy 437.958466 -296.994835)
			(xy 437.902732 -296.992798) (xy 437.847889 -296.982668) (xy 437.795105 -296.964661) (xy 437.745505 -296.93916)
			(xy 437.700147 -296.906709) (xy 437.659998 -296.868) (xy 437.625912 -296.823857) (xy 437.598616 -296.775222)
			(xy 437.578693 -296.723131) (xy 437.566567 -296.668694) (xy 437.562496 -296.613072) (xy 434.11648 -296.613072)
			(xy 433.995068 -296.734484) (xy 433.987669 -296.741327) (xy 433.96907 -296.749052) (xy 433.959 -296.74947)
			(xy 419.900862 -296.74947) (xy 419.891972 -296.750232) (xy 419.87535 -296.753045) (xy 419.841773 -296.756097)
			(xy 419.824916 -296.756328) (xy 419.808058 -296.756114) (xy 419.774481 -296.753058) (xy 419.75786 -296.750232)
			(xy 419.74897 -296.74947) (xy 418.94633 -296.74947) (xy 418.942012 -296.750232) (xy 418.925453 -296.753038)
			(xy 418.892004 -296.756093) (xy 418.87521 -296.756328) (xy 418.874702 -296.756328) (xy 418.857908 -296.756107)
			(xy 418.824457 -296.753055) (xy 418.8079 -296.750232) (xy 418.803582 -296.74947) (xy 418.377878 -296.74947)
			(xy 418.367809 -296.749896) (xy 418.349207 -296.757613) (xy 418.34181 -296.764456) (xy 417.815268 -297.290998)
			(xy 417.808414 -297.298393) (xy 417.800668 -297.316992) (xy 417.80037 -297.32478) (xy 418.569152 -297.32478)
			(xy 418.573112 -297.275726) (xy 418.584889 -297.227942) (xy 418.60418 -297.182666) (xy 418.630483 -297.14107)
			(xy 418.663118 -297.104233) (xy 418.701239 -297.073108) (xy 418.74386 -297.048501) (xy 418.789876 -297.031049)
			(xy 418.838095 -297.021205) (xy 418.88727 -297.019224) (xy 418.936125 -297.025156) (xy 418.983396 -297.038848)
			(xy 419.027858 -297.059946) (xy 419.068361 -297.087902) (xy 419.103854 -297.121994) (xy 419.133419 -297.161338)
			(xy 419.15629 -297.204915) (xy 419.171874 -297.251596) (xy 419.179769 -297.300173) (xy 419.180264 -297.32478)
			(xy 420.469072 -297.32478) (xy 420.473032 -297.275726) (xy 420.484809 -297.227942) (xy 420.5041 -297.182666)
			(xy 420.530403 -297.14107) (xy 420.563038 -297.104233) (xy 420.601159 -297.073108) (xy 420.64378 -297.048501)
			(xy 420.689796 -297.031049) (xy 420.738015 -297.021205) (xy 420.78719 -297.019224) (xy 420.836045 -297.025156)
			(xy 420.883316 -297.038848) (xy 420.927778 -297.059946) (xy 420.968281 -297.087902) (xy 421.003774 -297.121994)
			(xy 421.033339 -297.161338) (xy 421.05621 -297.204915) (xy 421.071794 -297.251596) (xy 421.079689 -297.300173)
			(xy 421.080184 -297.32478) (xy 422.369246 -297.32478) (xy 422.373206 -297.275726) (xy 422.384983 -297.227942)
			(xy 422.404274 -297.182666) (xy 422.430577 -297.14107) (xy 422.463212 -297.104233) (xy 422.501333 -297.073108)
			(xy 422.543954 -297.048501) (xy 422.58997 -297.031049) (xy 422.638189 -297.021205) (xy 422.687364 -297.019224)
			(xy 422.736219 -297.025156) (xy 422.78349 -297.038848) (xy 422.827952 -297.059946) (xy 422.868455 -297.087902)
			(xy 422.903948 -297.121994) (xy 422.933513 -297.161338) (xy 422.956384 -297.204915) (xy 422.971968 -297.251596)
			(xy 422.979863 -297.300173) (xy 422.980358 -297.32478) (xy 423.319206 -297.32478) (xy 423.323166 -297.275726)
			(xy 423.334943 -297.227942) (xy 423.354234 -297.182666) (xy 423.380537 -297.14107) (xy 423.413172 -297.104233)
			(xy 423.451293 -297.073108) (xy 423.493914 -297.048501) (xy 423.53993 -297.031049) (xy 423.588149 -297.021205)
			(xy 423.637324 -297.019224) (xy 423.686179 -297.025156) (xy 423.73345 -297.038848) (xy 423.777912 -297.059946)
			(xy 423.818415 -297.087902) (xy 423.853908 -297.121994) (xy 423.883473 -297.161338) (xy 423.906344 -297.204915)
			(xy 423.921928 -297.251596) (xy 423.929823 -297.300173) (xy 423.930318 -297.32478) (xy 427.119046 -297.32478)
			(xy 427.123006 -297.275726) (xy 427.134783 -297.227942) (xy 427.154074 -297.182666) (xy 427.180377 -297.14107)
			(xy 427.213012 -297.104233) (xy 427.251133 -297.073108) (xy 427.293754 -297.048501) (xy 427.33977 -297.031049)
			(xy 427.387989 -297.021205) (xy 427.437164 -297.019224) (xy 427.486019 -297.025156) (xy 427.53329 -297.038848)
			(xy 427.577752 -297.059946) (xy 427.618255 -297.087902) (xy 427.653748 -297.121994) (xy 427.683313 -297.161338)
			(xy 427.706184 -297.204915) (xy 427.721768 -297.251596) (xy 427.729663 -297.300173) (xy 427.730158 -297.32478)
			(xy 428.069006 -297.32478) (xy 428.072966 -297.275726) (xy 428.084743 -297.227942) (xy 428.104034 -297.182666)
			(xy 428.130337 -297.14107) (xy 428.162972 -297.104233) (xy 428.201093 -297.073108) (xy 428.243714 -297.048501)
			(xy 428.28973 -297.031049) (xy 428.337949 -297.021205) (xy 428.387124 -297.019224) (xy 428.435979 -297.025156)
			(xy 428.48325 -297.038848) (xy 428.527712 -297.059946) (xy 428.568215 -297.087902) (xy 428.603708 -297.121994)
			(xy 428.633273 -297.161338) (xy 428.656144 -297.204915) (xy 428.671728 -297.251596) (xy 428.679623 -297.300173)
			(xy 428.680118 -297.32478) (xy 428.679623 -297.349387) (xy 428.671728 -297.397964) (xy 428.656144 -297.444645)
			(xy 428.633273 -297.488222) (xy 428.603708 -297.527566) (xy 428.568215 -297.561658) (xy 428.527712 -297.589614)
			(xy 428.48325 -297.610712) (xy 428.435979 -297.624404) (xy 428.387124 -297.630336) (xy 428.337949 -297.628355)
			(xy 428.28973 -297.618511) (xy 428.243714 -297.601059) (xy 428.201093 -297.576452) (xy 428.162972 -297.545327)
			(xy 428.130337 -297.50849) (xy 428.104034 -297.466894) (xy 428.084743 -297.421618) (xy 428.072966 -297.373834)
			(xy 428.069006 -297.32478) (xy 427.730158 -297.32478) (xy 427.729663 -297.349387) (xy 427.721768 -297.397964)
			(xy 427.706184 -297.444645) (xy 427.683313 -297.488222) (xy 427.653748 -297.527566) (xy 427.618255 -297.561658)
			(xy 427.577752 -297.589614) (xy 427.53329 -297.610712) (xy 427.486019 -297.624404) (xy 427.437164 -297.630336)
			(xy 427.387989 -297.628355) (xy 427.33977 -297.618511) (xy 427.293754 -297.601059) (xy 427.251133 -297.576452)
			(xy 427.213012 -297.545327) (xy 427.180377 -297.50849) (xy 427.154074 -297.466894) (xy 427.134783 -297.421618)
			(xy 427.123006 -297.373834) (xy 427.119046 -297.32478) (xy 423.930318 -297.32478) (xy 423.929823 -297.349387)
			(xy 423.921928 -297.397964) (xy 423.906344 -297.444645) (xy 423.883473 -297.488222) (xy 423.853908 -297.527566)
			(xy 423.818415 -297.561658) (xy 423.777912 -297.589614) (xy 423.73345 -297.610712) (xy 423.686179 -297.624404)
			(xy 423.637324 -297.630336) (xy 423.588149 -297.628355) (xy 423.53993 -297.618511) (xy 423.493914 -297.601059)
			(xy 423.451293 -297.576452) (xy 423.413172 -297.545327) (xy 423.380537 -297.50849) (xy 423.354234 -297.466894)
			(xy 423.334943 -297.421618) (xy 423.323166 -297.373834) (xy 423.319206 -297.32478) (xy 422.980358 -297.32478)
			(xy 422.979863 -297.349387) (xy 422.971968 -297.397964) (xy 422.956384 -297.444645) (xy 422.933513 -297.488222)
			(xy 422.903948 -297.527566) (xy 422.868455 -297.561658) (xy 422.827952 -297.589614) (xy 422.78349 -297.610712)
			(xy 422.736219 -297.624404) (xy 422.687364 -297.630336) (xy 422.638189 -297.628355) (xy 422.58997 -297.618511)
			(xy 422.543954 -297.601059) (xy 422.501333 -297.576452) (xy 422.463212 -297.545327) (xy 422.430577 -297.50849)
			(xy 422.404274 -297.466894) (xy 422.384983 -297.421618) (xy 422.373206 -297.373834) (xy 422.369246 -297.32478)
			(xy 421.080184 -297.32478) (xy 421.079689 -297.349387) (xy 421.071794 -297.397964) (xy 421.05621 -297.444645)
			(xy 421.033339 -297.488222) (xy 421.003774 -297.527566) (xy 420.968281 -297.561658) (xy 420.927778 -297.589614)
			(xy 420.883316 -297.610712) (xy 420.836045 -297.624404) (xy 420.78719 -297.630336) (xy 420.738015 -297.628355)
			(xy 420.689796 -297.618511) (xy 420.64378 -297.601059) (xy 420.601159 -297.576452) (xy 420.563038 -297.545327)
			(xy 420.530403 -297.50849) (xy 420.5041 -297.466894) (xy 420.484809 -297.421618) (xy 420.473032 -297.373834)
			(xy 420.469072 -297.32478) (xy 419.180264 -297.32478) (xy 419.179769 -297.349387) (xy 419.171874 -297.397964)
			(xy 419.15629 -297.444645) (xy 419.133419 -297.488222) (xy 419.103854 -297.527566) (xy 419.068361 -297.561658)
			(xy 419.027858 -297.589614) (xy 418.983396 -297.610712) (xy 418.936125 -297.624404) (xy 418.88727 -297.630336)
			(xy 418.838095 -297.628355) (xy 418.789876 -297.618511) (xy 418.74386 -297.601059) (xy 418.701239 -297.576452)
			(xy 418.663118 -297.545327) (xy 418.630483 -297.50849) (xy 418.60418 -297.466894) (xy 418.584889 -297.421618)
			(xy 418.573112 -297.373834) (xy 418.569152 -297.32478) (xy 417.80037 -297.32478) (xy 417.800282 -297.327066)
			(xy 417.800282 -298.27474) (xy 418.569152 -298.27474) (xy 418.573112 -298.225686) (xy 418.584889 -298.177902)
			(xy 418.60418 -298.132626) (xy 418.630483 -298.09103) (xy 418.663118 -298.054193) (xy 418.701239 -298.023068)
			(xy 418.74386 -297.998461) (xy 418.789876 -297.981009) (xy 418.838095 -297.971165) (xy 418.88727 -297.969184)
			(xy 418.936125 -297.975116) (xy 418.983396 -297.988808) (xy 419.027858 -298.009906) (xy 419.068361 -298.037862)
			(xy 419.103854 -298.071954) (xy 419.133419 -298.111298) (xy 419.15629 -298.154875) (xy 419.171874 -298.201556)
			(xy 419.179769 -298.250133) (xy 419.180264 -298.27474) (xy 420.469072 -298.27474) (xy 420.473032 -298.225686)
			(xy 420.484809 -298.177902) (xy 420.5041 -298.132626) (xy 420.530403 -298.09103) (xy 420.563038 -298.054193)
			(xy 420.601159 -298.023068) (xy 420.64378 -297.998461) (xy 420.689796 -297.981009) (xy 420.738015 -297.971165)
			(xy 420.78719 -297.969184) (xy 420.836045 -297.975116) (xy 420.883316 -297.988808) (xy 420.927778 -298.009906)
			(xy 420.968281 -298.037862) (xy 421.003774 -298.071954) (xy 421.033339 -298.111298) (xy 421.05621 -298.154875)
			(xy 421.071794 -298.201556) (xy 421.079689 -298.250133) (xy 421.080184 -298.27474) (xy 425.219126 -298.27474)
			(xy 425.223086 -298.225686) (xy 425.234863 -298.177902) (xy 425.254154 -298.132626) (xy 425.280457 -298.09103)
			(xy 425.313092 -298.054193) (xy 425.351213 -298.023068) (xy 425.393834 -297.998461) (xy 425.43985 -297.981009)
			(xy 425.488069 -297.971165) (xy 425.537244 -297.969184) (xy 425.586099 -297.975116) (xy 425.63337 -297.988808)
			(xy 425.677832 -298.009906) (xy 425.718335 -298.037862) (xy 425.753828 -298.071954) (xy 425.783393 -298.111298)
			(xy 425.806264 -298.154875) (xy 425.821848 -298.201556) (xy 425.829743 -298.250133) (xy 425.830238 -298.27474)
			(xy 426.169086 -298.27474) (xy 426.173046 -298.225686) (xy 426.184823 -298.177902) (xy 426.204114 -298.132626)
			(xy 426.230417 -298.09103) (xy 426.263052 -298.054193) (xy 426.301173 -298.023068) (xy 426.343794 -297.998461)
			(xy 426.38981 -297.981009) (xy 426.438029 -297.971165) (xy 426.487204 -297.969184) (xy 426.536059 -297.975116)
			(xy 426.58333 -297.988808) (xy 426.627792 -298.009906) (xy 426.668295 -298.037862) (xy 426.703788 -298.071954)
			(xy 426.733353 -298.111298) (xy 426.756224 -298.154875) (xy 426.771808 -298.201556) (xy 426.779703 -298.250133)
			(xy 426.780198 -298.27474) (xy 429.96918 -298.27474) (xy 429.97314 -298.225686) (xy 429.984917 -298.177902)
			(xy 430.004208 -298.132626) (xy 430.030511 -298.09103) (xy 430.063146 -298.054193) (xy 430.101267 -298.023068)
			(xy 430.143888 -297.998461) (xy 430.189904 -297.981009) (xy 430.238123 -297.971165) (xy 430.287298 -297.969184)
			(xy 430.336153 -297.975116) (xy 430.383424 -297.988808) (xy 430.427886 -298.009906) (xy 430.468389 -298.037862)
			(xy 430.503882 -298.071954) (xy 430.533447 -298.111298) (xy 430.556318 -298.154875) (xy 430.571902 -298.201556)
			(xy 430.579797 -298.250133) (xy 430.580292 -298.27474) (xy 430.91914 -298.27474) (xy 430.9231 -298.225686)
			(xy 430.934877 -298.177902) (xy 430.954168 -298.132626) (xy 430.980471 -298.09103) (xy 431.013106 -298.054193)
			(xy 431.051227 -298.023068) (xy 431.093848 -297.998461) (xy 431.139864 -297.981009) (xy 431.188083 -297.971165)
			(xy 431.237258 -297.969184) (xy 431.286113 -297.975116) (xy 431.333384 -297.988808) (xy 431.377846 -298.009906)
			(xy 431.418349 -298.037862) (xy 431.453842 -298.071954) (xy 431.483407 -298.111298) (xy 431.506278 -298.154875)
			(xy 431.521862 -298.201556) (xy 431.529757 -298.250133) (xy 431.530252 -298.27474) (xy 431.529757 -298.299347)
			(xy 431.525612 -298.324851) (xy 432.282578 -298.324851) (xy 432.282578 -298.270349) (xy 432.290334 -298.216401)
			(xy 432.305689 -298.164106) (xy 432.328331 -298.114529) (xy 432.357797 -298.068679) (xy 432.393488 -298.027488)
			(xy 432.434679 -297.991797) (xy 432.480529 -297.962331) (xy 432.530106 -297.939689) (xy 432.582401 -297.924334)
			(xy 432.636349 -297.916578) (xy 432.6636 -297.916092) (xy 432.688532 -297.916503) (xy 432.737972 -297.922985)
			(xy 432.786146 -297.935851) (xy 432.832235 -297.954882) (xy 432.875452 -297.979755) (xy 432.895502 -297.994578)
			(xy 432.906521 -298.002476) (xy 432.931603 -298.012733) (xy 432.958502 -298.016018) (xy 432.985316 -298.012099)
			(xy 433.01015 -298.001253) (xy 433.031248 -297.984246) (xy 433.047119 -297.962281) (xy 433.05664 -297.93691)
			(xy 433.058316 -297.923458) (xy 433.061444 -297.895404) (xy 433.074876 -297.84058) (xy 433.096235 -297.788332)
			(xy 433.125056 -297.739799) (xy 433.16071 -297.696039) (xy 433.20242 -297.658008) (xy 433.249276 -297.626534)
			(xy 433.300257 -297.602303) (xy 433.354249 -297.585845) (xy 433.410077 -297.577518) (xy 433.4383 -297.577002)
			(xy 433.465552 -297.577468) (xy 433.519501 -297.585225) (xy 433.571797 -297.60058) (xy 433.621376 -297.623222)
			(xy 433.667227 -297.652689) (xy 433.693322 -297.6753) (xy 434.599586 -297.6753) (xy 434.603657 -297.619678)
			(xy 434.615783 -297.565241) (xy 434.635706 -297.51315) (xy 434.663002 -297.464515) (xy 434.697088 -297.420372)
			(xy 434.737237 -297.381663) (xy 434.782595 -297.349212) (xy 434.832195 -297.323711) (xy 434.884979 -297.305704)
			(xy 434.939822 -297.295574) (xy 434.995556 -297.293537) (xy 435.050993 -297.299637) (xy 435.10495 -297.313743)
			(xy 435.156279 -297.335555) (xy 435.203885 -297.364609) (xy 435.216152 -297.374818) (xy 440.915804 -297.374818)
			(xy 440.919875 -297.319196) (xy 440.932001 -297.264759) (xy 440.951924 -297.212668) (xy 440.97922 -297.164033)
			(xy 441.013306 -297.11989) (xy 441.053455 -297.081181) (xy 441.098813 -297.04873) (xy 441.148413 -297.023229)
			(xy 441.201197 -297.005222) (xy 441.25604 -296.995092) (xy 441.311774 -296.993055) (xy 441.367211 -296.999155)
			(xy 441.421168 -297.013261) (xy 441.472497 -297.035073) (xy 441.520103 -297.064127) (xy 441.562971 -297.099802)
			(xy 441.600188 -297.141339) (xy 441.630961 -297.187852) (xy 441.654633 -297.238349) (xy 441.670701 -297.291756)
			(xy 441.678821 -297.346932) (xy 441.67933 -297.374818) (xy 441.678821 -297.402704) (xy 441.670701 -297.45788)
			(xy 441.654633 -297.511287) (xy 441.630961 -297.561784) (xy 441.600188 -297.608297) (xy 441.562971 -297.649834)
			(xy 441.520103 -297.685509) (xy 441.472497 -297.714563) (xy 441.421168 -297.736375) (xy 441.367211 -297.750481)
			(xy 441.311774 -297.756581) (xy 441.25604 -297.754544) (xy 441.201197 -297.744414) (xy 441.148413 -297.726407)
			(xy 441.098813 -297.700906) (xy 441.053455 -297.668455) (xy 441.013306 -297.629746) (xy 440.97922 -297.585603)
			(xy 440.951924 -297.536968) (xy 440.932001 -297.484877) (xy 440.919875 -297.43044) (xy 440.915804 -297.374818)
			(xy 435.216152 -297.374818) (xy 435.246753 -297.400284) (xy 435.28397 -297.441821) (xy 435.314743 -297.488334)
			(xy 435.338415 -297.538831) (xy 435.354483 -297.592238) (xy 435.362603 -297.647414) (xy 435.363112 -297.6753)
			(xy 435.362603 -297.703186) (xy 435.354483 -297.758362) (xy 435.338415 -297.811769) (xy 435.314743 -297.862266)
			(xy 435.28397 -297.908779) (xy 435.246753 -297.950316) (xy 435.203885 -297.985991) (xy 435.156279 -298.015045)
			(xy 435.10495 -298.036857) (xy 435.050993 -298.050963) (xy 434.995556 -298.057063) (xy 434.939822 -298.055026)
			(xy 434.884979 -298.044896) (xy 434.832195 -298.026889) (xy 434.782595 -298.001388) (xy 434.737237 -297.968937)
			(xy 434.697088 -297.930228) (xy 434.663002 -297.886085) (xy 434.635706 -297.83745) (xy 434.615783 -297.785359)
			(xy 434.603657 -297.730922) (xy 434.599586 -297.6753) (xy 433.693322 -297.6753) (xy 433.708419 -297.688381)
			(xy 433.744111 -297.729573) (xy 433.773578 -297.775424) (xy 433.79622 -297.825003) (xy 433.811575 -297.877299)
			(xy 433.819332 -297.931248) (xy 433.819332 -297.985752) (xy 433.811575 -298.039701) (xy 433.79622 -298.091997)
			(xy 433.773578 -298.141576) (xy 433.744111 -298.187427) (xy 433.708419 -298.228619) (xy 433.667227 -298.264311)
			(xy 433.621376 -298.293778) (xy 433.571797 -298.31642) (xy 433.519501 -298.331775) (xy 433.465552 -298.339532)
			(xy 433.4383 -298.340018) (xy 433.413368 -298.339605) (xy 433.363929 -298.333123) (xy 433.315754 -298.320258)
			(xy 433.269666 -298.301227) (xy 433.226449 -298.276355) (xy 433.206398 -298.261532) (xy 433.195383 -298.253628)
			(xy 433.170299 -298.243369) (xy 433.143399 -298.240082) (xy 433.116583 -298.244002) (xy 433.091748 -298.254849)
			(xy 433.070649 -298.271858) (xy 433.054779 -298.293825) (xy 433.045259 -298.319199) (xy 433.043584 -298.332652)
			(xy 433.040464 -298.360707) (xy 433.027031 -298.415531) (xy 433.00567 -298.467779) (xy 432.976848 -298.516312)
			(xy 432.941193 -298.560071) (xy 432.899482 -298.598103) (xy 432.852626 -298.629577) (xy 432.801645 -298.653807)
			(xy 432.747651 -298.670265) (xy 432.691823 -298.678592) (xy 432.6636 -298.679108) (xy 432.636349 -298.678622)
			(xy 432.582401 -298.670866) (xy 432.530106 -298.655511) (xy 432.480529 -298.632869) (xy 432.434679 -298.603403)
			(xy 432.393488 -298.567712) (xy 432.357797 -298.526521) (xy 432.328331 -298.480671) (xy 432.305689 -298.431094)
			(xy 432.290334 -298.378799) (xy 432.282578 -298.324851) (xy 431.525612 -298.324851) (xy 431.521862 -298.347924)
			(xy 431.506278 -298.394605) (xy 431.483407 -298.438182) (xy 431.453842 -298.477526) (xy 431.418349 -298.511618)
			(xy 431.377846 -298.539574) (xy 431.333384 -298.560672) (xy 431.286113 -298.574364) (xy 431.237258 -298.580296)
			(xy 431.188083 -298.578315) (xy 431.139864 -298.568471) (xy 431.093848 -298.551019) (xy 431.051227 -298.526412)
			(xy 431.013106 -298.495287) (xy 430.980471 -298.45845) (xy 430.954168 -298.416854) (xy 430.934877 -298.371578)
			(xy 430.9231 -298.323794) (xy 430.91914 -298.27474) (xy 430.580292 -298.27474) (xy 430.579797 -298.299347)
			(xy 430.571902 -298.347924) (xy 430.556318 -298.394605) (xy 430.533447 -298.438182) (xy 430.503882 -298.477526)
			(xy 430.468389 -298.511618) (xy 430.427886 -298.539574) (xy 430.383424 -298.560672) (xy 430.336153 -298.574364)
			(xy 430.287298 -298.580296) (xy 430.238123 -298.578315) (xy 430.189904 -298.568471) (xy 430.143888 -298.551019)
			(xy 430.101267 -298.526412) (xy 430.063146 -298.495287) (xy 430.030511 -298.45845) (xy 430.004208 -298.416854)
			(xy 429.984917 -298.371578) (xy 429.97314 -298.323794) (xy 429.96918 -298.27474) (xy 426.780198 -298.27474)
			(xy 426.779703 -298.299347) (xy 426.771808 -298.347924) (xy 426.756224 -298.394605) (xy 426.733353 -298.438182)
			(xy 426.703788 -298.477526) (xy 426.668295 -298.511618) (xy 426.627792 -298.539574) (xy 426.58333 -298.560672)
			(xy 426.536059 -298.574364) (xy 426.487204 -298.580296) (xy 426.438029 -298.578315) (xy 426.38981 -298.568471)
			(xy 426.343794 -298.551019) (xy 426.301173 -298.526412) (xy 426.263052 -298.495287) (xy 426.230417 -298.45845)
			(xy 426.204114 -298.416854) (xy 426.184823 -298.371578) (xy 426.173046 -298.323794) (xy 426.169086 -298.27474)
			(xy 425.830238 -298.27474) (xy 425.829743 -298.299347) (xy 425.821848 -298.347924) (xy 425.806264 -298.394605)
			(xy 425.783393 -298.438182) (xy 425.753828 -298.477526) (xy 425.718335 -298.511618) (xy 425.677832 -298.539574)
			(xy 425.63337 -298.560672) (xy 425.586099 -298.574364) (xy 425.537244 -298.580296) (xy 425.488069 -298.578315)
			(xy 425.43985 -298.568471) (xy 425.393834 -298.551019) (xy 425.351213 -298.526412) (xy 425.313092 -298.495287)
			(xy 425.280457 -298.45845) (xy 425.254154 -298.416854) (xy 425.234863 -298.371578) (xy 425.223086 -298.323794)
			(xy 425.219126 -298.27474) (xy 421.080184 -298.27474) (xy 421.079689 -298.299347) (xy 421.071794 -298.347924)
			(xy 421.05621 -298.394605) (xy 421.033339 -298.438182) (xy 421.003774 -298.477526) (xy 420.968281 -298.511618)
			(xy 420.927778 -298.539574) (xy 420.883316 -298.560672) (xy 420.836045 -298.574364) (xy 420.78719 -298.580296)
			(xy 420.738015 -298.578315) (xy 420.689796 -298.568471) (xy 420.64378 -298.551019) (xy 420.601159 -298.526412)
			(xy 420.563038 -298.495287) (xy 420.530403 -298.45845) (xy 420.5041 -298.416854) (xy 420.484809 -298.371578)
			(xy 420.473032 -298.323794) (xy 420.469072 -298.27474) (xy 419.180264 -298.27474) (xy 419.179769 -298.299347)
			(xy 419.171874 -298.347924) (xy 419.15629 -298.394605) (xy 419.133419 -298.438182) (xy 419.103854 -298.477526)
			(xy 419.068361 -298.511618) (xy 419.027858 -298.539574) (xy 418.983396 -298.560672) (xy 418.936125 -298.574364)
			(xy 418.88727 -298.580296) (xy 418.838095 -298.578315) (xy 418.789876 -298.568471) (xy 418.74386 -298.551019)
			(xy 418.701239 -298.526412) (xy 418.663118 -298.495287) (xy 418.630483 -298.45845) (xy 418.60418 -298.416854)
			(xy 418.584889 -298.371578) (xy 418.573112 -298.323794) (xy 418.569152 -298.27474) (xy 417.800282 -298.27474)
			(xy 417.800282 -298.713652) (xy 434.780688 -298.713652) (xy 434.784759 -298.65803) (xy 434.796885 -298.603593)
			(xy 434.816808 -298.551502) (xy 434.844104 -298.502867) (xy 434.87819 -298.458724) (xy 434.918339 -298.420015)
			(xy 434.963697 -298.387564) (xy 435.013297 -298.362063) (xy 435.066081 -298.344056) (xy 435.120924 -298.333926)
			(xy 435.176658 -298.331889) (xy 435.232095 -298.337989) (xy 435.286052 -298.352095) (xy 435.337381 -298.373907)
			(xy 435.384987 -298.402961) (xy 435.427855 -298.438636) (xy 435.465072 -298.480173) (xy 435.495845 -298.526686)
			(xy 435.519517 -298.577183) (xy 435.535585 -298.63059) (xy 435.543705 -298.685766) (xy 435.544214 -298.713652)
			(xy 435.543705 -298.741538) (xy 435.535585 -298.796714) (xy 435.519517 -298.850121) (xy 435.495845 -298.900618)
			(xy 435.465072 -298.947131) (xy 435.427855 -298.988668) (xy 435.384987 -299.024343) (xy 435.337381 -299.053397)
			(xy 435.286052 -299.075209) (xy 435.232095 -299.089315) (xy 435.176658 -299.095415) (xy 435.120924 -299.093378)
			(xy 435.066081 -299.083248) (xy 435.013297 -299.065241) (xy 434.963697 -299.03974) (xy 434.918339 -299.007289)
			(xy 434.87819 -298.96858) (xy 434.844104 -298.924437) (xy 434.816808 -298.875802) (xy 434.796885 -298.823711)
			(xy 434.784759 -298.769274) (xy 434.780688 -298.713652) (xy 417.800282 -298.713652) (xy 417.800282 -298.818808)
			(xy 417.800823 -298.829167) (xy 417.809078 -298.848177) (xy 417.816284 -298.855638) (xy 417.877752 -298.913804)
			(xy 417.897056 -298.920662) (xy 417.907724 -298.920154) (xy 417.924996 -298.919646) (xy 417.950258 -298.920139)
			(xy 418.000092 -298.928454) (xy 418.047878 -298.944858) (xy 418.092313 -298.968904) (xy 418.132183 -298.999936)
			(xy 418.166402 -299.037107) (xy 418.194036 -299.079404) (xy 418.214331 -299.125672) (xy 418.226734 -299.174649)
			(xy 418.230902 -299.224954) (xy 420.469072 -299.224954) (xy 420.473032 -299.1759) (xy 420.484809 -299.128116)
			(xy 420.5041 -299.08284) (xy 420.530403 -299.041244) (xy 420.563038 -299.004407) (xy 420.601159 -298.973282)
			(xy 420.64378 -298.948675) (xy 420.689796 -298.931223) (xy 420.738015 -298.921379) (xy 420.78719 -298.919398)
			(xy 420.836045 -298.92533) (xy 420.883316 -298.939022) (xy 420.927778 -298.96012) (xy 420.968281 -298.988076)
			(xy 421.003774 -299.022168) (xy 421.033339 -299.061512) (xy 421.05621 -299.105089) (xy 421.071794 -299.15177)
			(xy 421.079689 -299.200347) (xy 421.080184 -299.224954) (xy 427.119046 -299.224954) (xy 427.123006 -299.1759)
			(xy 427.134783 -299.128116) (xy 427.154074 -299.08284) (xy 427.180377 -299.041244) (xy 427.213012 -299.004407)
			(xy 427.251133 -298.973282) (xy 427.293754 -298.948675) (xy 427.33977 -298.931223) (xy 427.387989 -298.921379)
			(xy 427.437164 -298.919398) (xy 427.486019 -298.92533) (xy 427.53329 -298.939022) (xy 427.577752 -298.96012)
			(xy 427.618255 -298.988076) (xy 427.653748 -299.022168) (xy 427.683313 -299.061512) (xy 427.706184 -299.105089)
			(xy 427.721768 -299.15177) (xy 427.729663 -299.200347) (xy 427.730158 -299.224954) (xy 428.069006 -299.224954)
			(xy 428.072966 -299.1759) (xy 428.084743 -299.128116) (xy 428.104034 -299.08284) (xy 428.130337 -299.041244)
			(xy 428.162972 -299.004407) (xy 428.201093 -298.973282) (xy 428.243714 -298.948675) (xy 428.28973 -298.931223)
			(xy 428.337949 -298.921379) (xy 428.387124 -298.919398) (xy 428.435979 -298.92533) (xy 428.48325 -298.939022)
			(xy 428.527712 -298.96012) (xy 428.568215 -298.988076) (xy 428.603708 -299.022168) (xy 428.633273 -299.061512)
			(xy 428.656144 -299.105089) (xy 428.671728 -299.15177) (xy 428.679623 -299.200347) (xy 428.680118 -299.224954)
			(xy 428.679623 -299.249561) (xy 428.67582 -299.27296) (xy 438.614564 -299.27296) (xy 438.618635 -299.217338)
			(xy 438.630761 -299.162901) (xy 438.650684 -299.11081) (xy 438.67798 -299.062175) (xy 438.712066 -299.018032)
			(xy 438.752215 -298.979323) (xy 438.797573 -298.946872) (xy 438.847173 -298.921371) (xy 438.899957 -298.903364)
			(xy 438.9548 -298.893234) (xy 439.010534 -298.891197) (xy 439.065971 -298.897297) (xy 439.119928 -298.911403)
			(xy 439.171257 -298.933215) (xy 439.218863 -298.962269) (xy 439.261731 -298.997944) (xy 439.298948 -299.039481)
			(xy 439.329721 -299.085994) (xy 439.353393 -299.136491) (xy 439.369461 -299.189898) (xy 439.377581 -299.245074)
			(xy 439.37809 -299.27296) (xy 439.377581 -299.300846) (xy 439.369461 -299.356022) (xy 439.353393 -299.409429)
			(xy 439.329721 -299.459926) (xy 439.298948 -299.506439) (xy 439.261731 -299.547976) (xy 439.218863 -299.583651)
			(xy 439.171257 -299.612705) (xy 439.119928 -299.634517) (xy 439.065971 -299.648623) (xy 439.010534 -299.654723)
			(xy 438.9548 -299.652686) (xy 438.899957 -299.642556) (xy 438.847173 -299.624549) (xy 438.797573 -299.599048)
			(xy 438.752215 -299.566597) (xy 438.712066 -299.527888) (xy 438.67798 -299.483745) (xy 438.650684 -299.43511)
			(xy 438.630761 -299.383019) (xy 438.618635 -299.328582) (xy 438.614564 -299.27296) (xy 428.67582 -299.27296)
			(xy 428.671728 -299.298138) (xy 428.656144 -299.344819) (xy 428.633273 -299.388396) (xy 428.603708 -299.42774)
			(xy 428.568215 -299.461832) (xy 428.527712 -299.489788) (xy 428.48325 -299.510886) (xy 428.435979 -299.524578)
			(xy 428.387124 -299.53051) (xy 428.337949 -299.528529) (xy 428.28973 -299.518685) (xy 428.243714 -299.501233)
			(xy 428.201093 -299.476626) (xy 428.162972 -299.445501) (xy 428.130337 -299.408664) (xy 428.104034 -299.367068)
			(xy 428.084743 -299.321792) (xy 428.072966 -299.274008) (xy 428.069006 -299.224954) (xy 427.730158 -299.224954)
			(xy 427.729663 -299.249561) (xy 427.721768 -299.298138) (xy 427.706184 -299.344819) (xy 427.683313 -299.388396)
			(xy 427.653748 -299.42774) (xy 427.618255 -299.461832) (xy 427.577752 -299.489788) (xy 427.53329 -299.510886)
			(xy 427.486019 -299.524578) (xy 427.437164 -299.53051) (xy 427.387989 -299.528529) (xy 427.33977 -299.518685)
			(xy 427.293754 -299.501233) (xy 427.251133 -299.476626) (xy 427.213012 -299.445501) (xy 427.180377 -299.408664)
			(xy 427.154074 -299.367068) (xy 427.134783 -299.321792) (xy 427.123006 -299.274008) (xy 427.119046 -299.224954)
			(xy 421.080184 -299.224954) (xy 421.079689 -299.249561) (xy 421.071794 -299.298138) (xy 421.05621 -299.344819)
			(xy 421.033339 -299.388396) (xy 421.003774 -299.42774) (xy 420.968281 -299.461832) (xy 420.927778 -299.489788)
			(xy 420.883316 -299.510886) (xy 420.836045 -299.524578) (xy 420.78719 -299.53051) (xy 420.738015 -299.528529)
			(xy 420.689796 -299.518685) (xy 420.64378 -299.501233) (xy 420.601159 -299.476626) (xy 420.563038 -299.445501)
			(xy 420.530403 -299.408664) (xy 420.5041 -299.367068) (xy 420.484809 -299.321792) (xy 420.473032 -299.274008)
			(xy 420.469072 -299.224954) (xy 418.230902 -299.224954) (xy 418.230906 -299.225) (xy 418.226734 -299.275351)
			(xy 418.214331 -299.324328) (xy 418.194036 -299.370596) (xy 418.166402 -299.412893) (xy 418.132183 -299.450064)
			(xy 418.092313 -299.481096) (xy 418.047878 -299.505142) (xy 418.000092 -299.521546) (xy 417.950258 -299.529861)
			(xy 417.924996 -299.530262) (xy 417.907724 -299.529754) (xy 417.897056 -299.529246) (xy 417.877752 -299.536104)
			(xy 417.816284 -299.59427) (xy 417.809048 -299.601715) (xy 417.80077 -299.620731) (xy 417.800282 -299.6311)
			(xy 417.800282 -299.76445) (xy 436.341772 -299.76445) (xy 436.345843 -299.708828) (xy 436.357969 -299.654391)
			(xy 436.377892 -299.6023) (xy 436.405188 -299.553665) (xy 436.439274 -299.509522) (xy 436.479423 -299.470813)
			(xy 436.524781 -299.438362) (xy 436.574381 -299.412861) (xy 436.627165 -299.394854) (xy 436.682008 -299.384724)
			(xy 436.737742 -299.382687) (xy 436.793179 -299.388787) (xy 436.847136 -299.402893) (xy 436.898465 -299.424705)
			(xy 436.946071 -299.453759) (xy 436.988939 -299.489434) (xy 437.026156 -299.530971) (xy 437.056929 -299.577484)
			(xy 437.080601 -299.627981) (xy 437.096669 -299.681388) (xy 437.104789 -299.736564) (xy 437.105298 -299.76445)
			(xy 437.10502 -299.77969) (xy 440.93841 -299.77969) (xy 440.942481 -299.724068) (xy 440.954607 -299.669631)
			(xy 440.97453 -299.61754) (xy 441.001826 -299.568905) (xy 441.035912 -299.524762) (xy 441.076061 -299.486053)
			(xy 441.121419 -299.453602) (xy 441.171019 -299.428101) (xy 441.223803 -299.410094) (xy 441.278646 -299.399964)
			(xy 441.33438 -299.397927) (xy 441.389817 -299.404027) (xy 441.443774 -299.418133) (xy 441.495103 -299.439945)
			(xy 441.542709 -299.468999) (xy 441.585577 -299.504674) (xy 441.622794 -299.546211) (xy 441.653567 -299.592724)
			(xy 441.677239 -299.643221) (xy 441.693307 -299.696628) (xy 441.701427 -299.751804) (xy 441.701936 -299.77969)
			(xy 441.701427 -299.807576) (xy 441.693307 -299.862752) (xy 441.677239 -299.916159) (xy 441.653567 -299.966656)
			(xy 441.622794 -300.013169) (xy 441.585577 -300.054706) (xy 441.542709 -300.090381) (xy 441.495103 -300.119435)
			(xy 441.443774 -300.141247) (xy 441.389817 -300.155353) (xy 441.33438 -300.161453) (xy 441.278646 -300.159416)
			(xy 441.223803 -300.149286) (xy 441.171019 -300.131279) (xy 441.121419 -300.105778) (xy 441.076061 -300.073327)
			(xy 441.035912 -300.034618) (xy 441.001826 -299.990475) (xy 440.97453 -299.94184) (xy 440.954607 -299.889749)
			(xy 440.942481 -299.835312) (xy 440.93841 -299.77969) (xy 437.10502 -299.77969) (xy 437.104789 -299.792336)
			(xy 437.096669 -299.847512) (xy 437.080601 -299.900919) (xy 437.056929 -299.951416) (xy 437.026156 -299.997929)
			(xy 436.988939 -300.039466) (xy 436.946071 -300.075141) (xy 436.898465 -300.104195) (xy 436.847136 -300.126007)
			(xy 436.793179 -300.140113) (xy 436.737742 -300.146213) (xy 436.682008 -300.144176) (xy 436.627165 -300.134046)
			(xy 436.574381 -300.116039) (xy 436.524781 -300.090538) (xy 436.479423 -300.058087) (xy 436.439274 -300.019378)
			(xy 436.405188 -299.975235) (xy 436.377892 -299.9266) (xy 436.357969 -299.874509) (xy 436.345843 -299.820072)
			(xy 436.341772 -299.76445) (xy 417.800282 -299.76445) (xy 417.800282 -300.174914) (xy 419.519112 -300.174914)
			(xy 419.523072 -300.12586) (xy 419.534849 -300.078076) (xy 419.55414 -300.0328) (xy 419.580443 -299.991204)
			(xy 419.613078 -299.954367) (xy 419.651199 -299.923242) (xy 419.69382 -299.898635) (xy 419.739836 -299.881183)
			(xy 419.788055 -299.871339) (xy 419.83723 -299.869358) (xy 419.886085 -299.87529) (xy 419.933356 -299.888982)
			(xy 419.977818 -299.91008) (xy 420.018321 -299.938036) (xy 420.053814 -299.972128) (xy 420.083379 -300.011472)
			(xy 420.10625 -300.055049) (xy 420.121834 -300.10173) (xy 420.129729 -300.150307) (xy 420.130224 -300.174914)
			(xy 421.419032 -300.174914) (xy 421.422992 -300.12586) (xy 421.434769 -300.078076) (xy 421.45406 -300.0328)
			(xy 421.480363 -299.991204) (xy 421.512998 -299.954367) (xy 421.551119 -299.923242) (xy 421.59374 -299.898635)
			(xy 421.639756 -299.881183) (xy 421.687975 -299.871339) (xy 421.73715 -299.869358) (xy 421.786005 -299.87529)
			(xy 421.833276 -299.888982) (xy 421.877738 -299.91008) (xy 421.918241 -299.938036) (xy 421.953734 -299.972128)
			(xy 421.983299 -300.011472) (xy 422.00617 -300.055049) (xy 422.021754 -300.10173) (xy 422.029649 -300.150307)
			(xy 422.030144 -300.174914) (xy 425.219126 -300.174914) (xy 425.223086 -300.12586) (xy 425.234863 -300.078076)
			(xy 425.254154 -300.0328) (xy 425.280457 -299.991204) (xy 425.313092 -299.954367) (xy 425.351213 -299.923242)
			(xy 425.393834 -299.898635) (xy 425.43985 -299.881183) (xy 425.488069 -299.871339) (xy 425.537244 -299.869358)
			(xy 425.586099 -299.87529) (xy 425.63337 -299.888982) (xy 425.677832 -299.91008) (xy 425.718335 -299.938036)
			(xy 425.753828 -299.972128) (xy 425.783393 -300.011472) (xy 425.806264 -300.055049) (xy 425.821848 -300.10173)
			(xy 425.829743 -300.150307) (xy 425.830238 -300.174914) (xy 426.169086 -300.174914) (xy 426.173046 -300.12586)
			(xy 426.184823 -300.078076) (xy 426.204114 -300.0328) (xy 426.230417 -299.991204) (xy 426.263052 -299.954367)
			(xy 426.301173 -299.923242) (xy 426.343794 -299.898635) (xy 426.38981 -299.881183) (xy 426.438029 -299.871339)
			(xy 426.487204 -299.869358) (xy 426.536059 -299.87529) (xy 426.58333 -299.888982) (xy 426.627792 -299.91008)
			(xy 426.668295 -299.938036) (xy 426.703788 -299.972128) (xy 426.733353 -300.011472) (xy 426.756224 -300.055049)
			(xy 426.771808 -300.10173) (xy 426.779703 -300.150307) (xy 426.780198 -300.174914) (xy 429.96918 -300.174914)
			(xy 429.97314 -300.12586) (xy 429.984917 -300.078076) (xy 430.004208 -300.0328) (xy 430.030511 -299.991204)
			(xy 430.063146 -299.954367) (xy 430.101267 -299.923242) (xy 430.143888 -299.898635) (xy 430.189904 -299.881183)
			(xy 430.238123 -299.871339) (xy 430.287298 -299.869358) (xy 430.336153 -299.87529) (xy 430.383424 -299.888982)
			(xy 430.427886 -299.91008) (xy 430.468389 -299.938036) (xy 430.503882 -299.972128) (xy 430.533447 -300.011472)
			(xy 430.556318 -300.055049) (xy 430.571902 -300.10173) (xy 430.579797 -300.150307) (xy 430.580292 -300.174914)
			(xy 430.91914 -300.174914) (xy 430.9231 -300.12586) (xy 430.934877 -300.078076) (xy 430.954168 -300.0328)
			(xy 430.980471 -299.991204) (xy 431.013106 -299.954367) (xy 431.051227 -299.923242) (xy 431.093848 -299.898635)
			(xy 431.139864 -299.881183) (xy 431.188083 -299.871339) (xy 431.237258 -299.869358) (xy 431.286113 -299.87529)
			(xy 431.333384 -299.888982) (xy 431.377846 -299.91008) (xy 431.418349 -299.938036) (xy 431.453842 -299.972128)
			(xy 431.483407 -300.011472) (xy 431.506278 -300.055049) (xy 431.521862 -300.10173) (xy 431.529757 -300.150307)
			(xy 431.530252 -300.174914) (xy 431.529757 -300.199521) (xy 431.521862 -300.248098) (xy 431.506278 -300.294779)
			(xy 431.483407 -300.338356) (xy 431.453842 -300.3777) (xy 431.418349 -300.411792) (xy 431.377846 -300.439748)
			(xy 431.333384 -300.460846) (xy 431.286113 -300.474538) (xy 431.237258 -300.48047) (xy 431.188083 -300.478489)
			(xy 431.139864 -300.468645) (xy 431.093848 -300.451193) (xy 431.051227 -300.426586) (xy 431.013106 -300.395461)
			(xy 430.980471 -300.358624) (xy 430.954168 -300.317028) (xy 430.934877 -300.271752) (xy 430.9231 -300.223968)
			(xy 430.91914 -300.174914) (xy 430.580292 -300.174914) (xy 430.579797 -300.199521) (xy 430.571902 -300.248098)
			(xy 430.556318 -300.294779) (xy 430.533447 -300.338356) (xy 430.503882 -300.3777) (xy 430.468389 -300.411792)
			(xy 430.427886 -300.439748) (xy 430.383424 -300.460846) (xy 430.336153 -300.474538) (xy 430.287298 -300.48047)
			(xy 430.238123 -300.478489) (xy 430.189904 -300.468645) (xy 430.143888 -300.451193) (xy 430.101267 -300.426586)
			(xy 430.063146 -300.395461) (xy 430.030511 -300.358624) (xy 430.004208 -300.317028) (xy 429.984917 -300.271752)
			(xy 429.97314 -300.223968) (xy 429.96918 -300.174914) (xy 426.780198 -300.174914) (xy 426.779703 -300.199521)
			(xy 426.771808 -300.248098) (xy 426.756224 -300.294779) (xy 426.733353 -300.338356) (xy 426.703788 -300.3777)
			(xy 426.668295 -300.411792) (xy 426.627792 -300.439748) (xy 426.58333 -300.460846) (xy 426.536059 -300.474538)
			(xy 426.487204 -300.48047) (xy 426.438029 -300.478489) (xy 426.38981 -300.468645) (xy 426.343794 -300.451193)
			(xy 426.301173 -300.426586) (xy 426.263052 -300.395461) (xy 426.230417 -300.358624) (xy 426.204114 -300.317028)
			(xy 426.184823 -300.271752) (xy 426.173046 -300.223968) (xy 426.169086 -300.174914) (xy 425.830238 -300.174914)
			(xy 425.829743 -300.199521) (xy 425.821848 -300.248098) (xy 425.806264 -300.294779) (xy 425.783393 -300.338356)
			(xy 425.753828 -300.3777) (xy 425.718335 -300.411792) (xy 425.677832 -300.439748) (xy 425.63337 -300.460846)
			(xy 425.586099 -300.474538) (xy 425.537244 -300.48047) (xy 425.488069 -300.478489) (xy 425.43985 -300.468645)
			(xy 425.393834 -300.451193) (xy 425.351213 -300.426586) (xy 425.313092 -300.395461) (xy 425.280457 -300.358624)
			(xy 425.254154 -300.317028) (xy 425.234863 -300.271752) (xy 425.223086 -300.223968) (xy 425.219126 -300.174914)
			(xy 422.030144 -300.174914) (xy 422.029649 -300.199521) (xy 422.021754 -300.248098) (xy 422.00617 -300.294779)
			(xy 421.983299 -300.338356) (xy 421.953734 -300.3777) (xy 421.918241 -300.411792) (xy 421.877738 -300.439748)
			(xy 421.833276 -300.460846) (xy 421.786005 -300.474538) (xy 421.73715 -300.48047) (xy 421.687975 -300.478489)
			(xy 421.639756 -300.468645) (xy 421.59374 -300.451193) (xy 421.551119 -300.426586) (xy 421.512998 -300.395461)
			(xy 421.480363 -300.358624) (xy 421.45406 -300.317028) (xy 421.434769 -300.271752) (xy 421.422992 -300.223968)
			(xy 421.419032 -300.174914) (xy 420.130224 -300.174914) (xy 420.129729 -300.199521) (xy 420.121834 -300.248098)
			(xy 420.10625 -300.294779) (xy 420.083379 -300.338356) (xy 420.053814 -300.3777) (xy 420.018321 -300.411792)
			(xy 419.977818 -300.439748) (xy 419.933356 -300.460846) (xy 419.886085 -300.474538) (xy 419.83723 -300.48047)
			(xy 419.788055 -300.478489) (xy 419.739836 -300.468645) (xy 419.69382 -300.451193) (xy 419.651199 -300.426586)
			(xy 419.613078 -300.395461) (xy 419.580443 -300.358624) (xy 419.55414 -300.317028) (xy 419.534849 -300.271752)
			(xy 419.523072 -300.223968) (xy 419.519112 -300.174914) (xy 417.800282 -300.174914) (xy 417.800282 -300.718728)
			(xy 417.800826 -300.729085) (xy 417.809087 -300.748089) (xy 417.816284 -300.755558) (xy 417.877752 -300.813724)
			(xy 417.897056 -300.820582) (xy 417.907724 -300.820074) (xy 417.924996 -300.819566) (xy 417.950256 -300.820058)
			(xy 418.000087 -300.828373) (xy 418.04787 -300.844777) (xy 418.092302 -300.868821) (xy 418.132169 -300.899851)
			(xy 418.166386 -300.93702) (xy 418.194018 -300.979313) (xy 418.214312 -301.025578) (xy 418.226714 -301.074552)
			(xy 418.230884 -301.124874) (xy 427.119046 -301.124874) (xy 427.123006 -301.07582) (xy 427.134783 -301.028036)
			(xy 427.154074 -300.98276) (xy 427.180377 -300.941164) (xy 427.213012 -300.904327) (xy 427.251133 -300.873202)
			(xy 427.293754 -300.848595) (xy 427.33977 -300.831143) (xy 427.387989 -300.821299) (xy 427.437164 -300.819318)
			(xy 427.486019 -300.82525) (xy 427.53329 -300.838942) (xy 427.577752 -300.86004) (xy 427.618255 -300.887996)
			(xy 427.653748 -300.922088) (xy 427.683313 -300.961432) (xy 427.706184 -301.005009) (xy 427.721768 -301.05169)
			(xy 427.729663 -301.100267) (xy 427.730158 -301.124874) (xy 428.069006 -301.124874) (xy 428.072966 -301.07582)
			(xy 428.084743 -301.028036) (xy 428.104034 -300.98276) (xy 428.130337 -300.941164) (xy 428.162972 -300.904327)
			(xy 428.201093 -300.873202) (xy 428.243714 -300.848595) (xy 428.28973 -300.831143) (xy 428.337949 -300.821299)
			(xy 428.387124 -300.819318) (xy 428.435979 -300.82525) (xy 428.48325 -300.838942) (xy 428.527712 -300.86004)
			(xy 428.568215 -300.887996) (xy 428.603708 -300.922088) (xy 428.633273 -300.961432) (xy 428.656144 -301.005009)
			(xy 428.668516 -301.04207) (xy 438.617104 -301.04207) (xy 438.621175 -300.986448) (xy 438.633301 -300.932011)
			(xy 438.653224 -300.87992) (xy 438.68052 -300.831285) (xy 438.714606 -300.787142) (xy 438.754755 -300.748433)
			(xy 438.800113 -300.715982) (xy 438.849713 -300.690481) (xy 438.902497 -300.672474) (xy 438.95734 -300.662344)
			(xy 439.013074 -300.660307) (xy 439.068511 -300.666407) (xy 439.122468 -300.680513) (xy 439.173797 -300.702325)
			(xy 439.221403 -300.731379) (xy 439.264271 -300.767054) (xy 439.301488 -300.808591) (xy 439.332261 -300.855104)
			(xy 439.355933 -300.905601) (xy 439.372001 -300.959008) (xy 439.380121 -301.014184) (xy 439.38063 -301.04207)
			(xy 439.380477 -301.050452) (xy 440.990988 -301.050452) (xy 440.995059 -300.99483) (xy 441.007185 -300.940393)
			(xy 441.027108 -300.888302) (xy 441.054404 -300.839667) (xy 441.08849 -300.795524) (xy 441.128639 -300.756815)
			(xy 441.173997 -300.724364) (xy 441.223597 -300.698863) (xy 441.276381 -300.680856) (xy 441.331224 -300.670726)
			(xy 441.386958 -300.668689) (xy 441.442395 -300.674789) (xy 441.496352 -300.688895) (xy 441.547681 -300.710707)
			(xy 441.595287 -300.739761) (xy 441.638155 -300.775436) (xy 441.675372 -300.816973) (xy 441.706145 -300.863486)
			(xy 441.729817 -300.913983) (xy 441.745885 -300.96739) (xy 441.754005 -301.022566) (xy 441.754514 -301.050452)
			(xy 441.754005 -301.078338) (xy 441.745885 -301.133514) (xy 441.729817 -301.186921) (xy 441.706145 -301.237418)
			(xy 441.675372 -301.283931) (xy 441.638155 -301.325468) (xy 441.595287 -301.361143) (xy 441.547681 -301.390197)
			(xy 441.496352 -301.412009) (xy 441.442395 -301.426115) (xy 441.386958 -301.432215) (xy 441.331224 -301.430178)
			(xy 441.276381 -301.420048) (xy 441.223597 -301.402041) (xy 441.173997 -301.37654) (xy 441.128639 -301.344089)
			(xy 441.08849 -301.30538) (xy 441.054404 -301.261237) (xy 441.027108 -301.212602) (xy 441.007185 -301.160511)
			(xy 440.995059 -301.106074) (xy 440.990988 -301.050452) (xy 439.380477 -301.050452) (xy 439.380121 -301.069956)
			(xy 439.372001 -301.125132) (xy 439.355933 -301.178539) (xy 439.332261 -301.229036) (xy 439.301488 -301.275549)
			(xy 439.264271 -301.317086) (xy 439.221403 -301.352761) (xy 439.173797 -301.381815) (xy 439.122468 -301.403627)
			(xy 439.068511 -301.417733) (xy 439.013074 -301.423833) (xy 438.95734 -301.421796) (xy 438.902497 -301.411666)
			(xy 438.849713 -301.393659) (xy 438.800113 -301.368158) (xy 438.754755 -301.335707) (xy 438.714606 -301.296998)
			(xy 438.68052 -301.252855) (xy 438.653224 -301.20422) (xy 438.633301 -301.152129) (xy 438.621175 -301.097692)
			(xy 438.617104 -301.04207) (xy 428.668516 -301.04207) (xy 428.671728 -301.05169) (xy 428.679623 -301.100267)
			(xy 428.680118 -301.124874) (xy 428.679623 -301.149481) (xy 428.671728 -301.198058) (xy 428.656144 -301.244739)
			(xy 428.633273 -301.288316) (xy 428.603708 -301.32766) (xy 428.568215 -301.361752) (xy 428.527712 -301.389708)
			(xy 428.48325 -301.410806) (xy 428.435979 -301.424498) (xy 428.387124 -301.43043) (xy 428.337949 -301.428449)
			(xy 428.28973 -301.418605) (xy 428.243714 -301.401153) (xy 428.201093 -301.376546) (xy 428.162972 -301.345421)
			(xy 428.130337 -301.308584) (xy 428.104034 -301.266988) (xy 428.084743 -301.221712) (xy 428.072966 -301.173928)
			(xy 428.069006 -301.124874) (xy 427.730158 -301.124874) (xy 427.729663 -301.149481) (xy 427.721768 -301.198058)
			(xy 427.706184 -301.244739) (xy 427.683313 -301.288316) (xy 427.653748 -301.32766) (xy 427.618255 -301.361752)
			(xy 427.577752 -301.389708) (xy 427.53329 -301.410806) (xy 427.486019 -301.424498) (xy 427.437164 -301.43043)
			(xy 427.387989 -301.428449) (xy 427.33977 -301.418605) (xy 427.293754 -301.401153) (xy 427.251133 -301.376546)
			(xy 427.213012 -301.345421) (xy 427.180377 -301.308584) (xy 427.154074 -301.266988) (xy 427.134783 -301.221712)
			(xy 427.123006 -301.173928) (xy 427.119046 -301.124874) (xy 418.230884 -301.124874) (xy 418.230886 -301.1249)
			(xy 418.226714 -301.175248) (xy 418.214312 -301.224222) (xy 418.194018 -301.270487) (xy 418.166386 -301.31278)
			(xy 418.132169 -301.349949) (xy 418.092302 -301.380979) (xy 418.04787 -301.405023) (xy 418.000087 -301.421427)
			(xy 417.950256 -301.429742) (xy 417.924996 -301.430182) (xy 417.907724 -301.429674) (xy 417.897056 -301.429166)
			(xy 417.877752 -301.436024) (xy 417.816284 -301.49419) (xy 417.809051 -301.501636) (xy 417.800781 -301.520652)
			(xy 417.800282 -301.53102) (xy 417.800282 -301.668688) (xy 417.800819 -301.679049) (xy 417.809069 -301.698064)
			(xy 417.816284 -301.705518) (xy 417.877752 -301.763684) (xy 417.897056 -301.770542) (xy 417.907724 -301.770034)
			(xy 417.924996 -301.769526) (xy 417.950251 -301.770018) (xy 418.000073 -301.778331) (xy 418.047846 -301.794732)
			(xy 418.092269 -301.818771) (xy 418.132129 -301.849795) (xy 418.166339 -301.886956) (xy 418.193965 -301.929242)
			(xy 418.214255 -301.975498) (xy 418.226655 -302.024462) (xy 418.230826 -302.0748) (xy 418.230823 -302.074834)
			(xy 420.469072 -302.074834) (xy 420.473032 -302.02578) (xy 420.484809 -301.977996) (xy 420.5041 -301.93272)
			(xy 420.530403 -301.891124) (xy 420.563038 -301.854287) (xy 420.601159 -301.823162) (xy 420.64378 -301.798555)
			(xy 420.689796 -301.781103) (xy 420.738015 -301.771259) (xy 420.78719 -301.769278) (xy 420.836045 -301.77521)
			(xy 420.883316 -301.788902) (xy 420.927778 -301.81) (xy 420.968281 -301.837956) (xy 421.003774 -301.872048)
			(xy 421.033339 -301.911392) (xy 421.05621 -301.954969) (xy 421.071794 -302.00165) (xy 421.079689 -302.050227)
			(xy 421.080184 -302.074834) (xy 421.419032 -302.074834) (xy 421.422992 -302.02578) (xy 421.434769 -301.977996)
			(xy 421.45406 -301.93272) (xy 421.480363 -301.891124) (xy 421.512998 -301.854287) (xy 421.551119 -301.823162)
			(xy 421.59374 -301.798555) (xy 421.639756 -301.781103) (xy 421.687975 -301.771259) (xy 421.73715 -301.769278)
			(xy 421.786005 -301.77521) (xy 421.833276 -301.788902) (xy 421.877738 -301.81) (xy 421.918241 -301.837956)
			(xy 421.953734 -301.872048) (xy 421.983299 -301.911392) (xy 422.00617 -301.954969) (xy 422.021754 -302.00165)
			(xy 422.029649 -302.050227) (xy 422.030144 -302.074834) (xy 425.219126 -302.074834) (xy 425.223086 -302.02578)
			(xy 425.234863 -301.977996) (xy 425.254154 -301.93272) (xy 425.280457 -301.891124) (xy 425.313092 -301.854287)
			(xy 425.351213 -301.823162) (xy 425.393834 -301.798555) (xy 425.43985 -301.781103) (xy 425.488069 -301.771259)
			(xy 425.537244 -301.769278) (xy 425.586099 -301.77521) (xy 425.63337 -301.788902) (xy 425.677832 -301.81)
			(xy 425.718335 -301.837956) (xy 425.753828 -301.872048) (xy 425.783393 -301.911392) (xy 425.806264 -301.954969)
			(xy 425.821848 -302.00165) (xy 425.829743 -302.050227) (xy 425.830238 -302.074834) (xy 426.169086 -302.074834)
			(xy 426.173046 -302.02578) (xy 426.184823 -301.977996) (xy 426.204114 -301.93272) (xy 426.230417 -301.891124)
			(xy 426.263052 -301.854287) (xy 426.301173 -301.823162) (xy 426.343794 -301.798555) (xy 426.38981 -301.781103)
			(xy 426.438029 -301.771259) (xy 426.487204 -301.769278) (xy 426.536059 -301.77521) (xy 426.58333 -301.788902)
			(xy 426.627792 -301.81) (xy 426.668295 -301.837956) (xy 426.703788 -301.872048) (xy 426.733353 -301.911392)
			(xy 426.756224 -301.954969) (xy 426.771808 -302.00165) (xy 426.779703 -302.050227) (xy 426.780198 -302.074834)
			(xy 429.96918 -302.074834) (xy 429.97314 -302.02578) (xy 429.984917 -301.977996) (xy 430.004208 -301.93272)
			(xy 430.030511 -301.891124) (xy 430.063146 -301.854287) (xy 430.101267 -301.823162) (xy 430.143888 -301.798555)
			(xy 430.189904 -301.781103) (xy 430.238123 -301.771259) (xy 430.287298 -301.769278) (xy 430.336153 -301.77521)
			(xy 430.383424 -301.788902) (xy 430.427886 -301.81) (xy 430.468389 -301.837956) (xy 430.503882 -301.872048)
			(xy 430.533447 -301.911392) (xy 430.556318 -301.954969) (xy 430.571902 -302.00165) (xy 430.579797 -302.050227)
			(xy 430.580292 -302.074834) (xy 430.91914 -302.074834) (xy 430.9231 -302.02578) (xy 430.934877 -301.977996)
			(xy 430.954168 -301.93272) (xy 430.980471 -301.891124) (xy 431.013106 -301.854287) (xy 431.051227 -301.823162)
			(xy 431.093848 -301.798555) (xy 431.139864 -301.781103) (xy 431.188083 -301.771259) (xy 431.237258 -301.769278)
			(xy 431.286113 -301.77521) (xy 431.333384 -301.788902) (xy 431.377846 -301.81) (xy 431.418349 -301.837956)
			(xy 431.453842 -301.872048) (xy 431.459066 -301.879) (xy 434.647592 -301.879) (xy 434.651663 -301.823378)
			(xy 434.663789 -301.768941) (xy 434.683712 -301.71685) (xy 434.711008 -301.668215) (xy 434.745094 -301.624072)
			(xy 434.785243 -301.585363) (xy 434.830601 -301.552912) (xy 434.880201 -301.527411) (xy 434.932985 -301.509404)
			(xy 434.987828 -301.499274) (xy 435.043562 -301.497237) (xy 435.098999 -301.503337) (xy 435.152956 -301.517443)
			(xy 435.204285 -301.539255) (xy 435.226168 -301.55261) (xy 436.41975 -301.55261) (xy 436.423821 -301.496988)
			(xy 436.435947 -301.442551) (xy 436.45587 -301.39046) (xy 436.483166 -301.341825) (xy 436.517252 -301.297682)
			(xy 436.557401 -301.258973) (xy 436.602759 -301.226522) (xy 436.652359 -301.201021) (xy 436.705143 -301.183014)
			(xy 436.759986 -301.172884) (xy 436.81572 -301.170847) (xy 436.871157 -301.176947) (xy 436.925114 -301.191053)
			(xy 436.976443 -301.212865) (xy 437.024049 -301.241919) (xy 437.066917 -301.277594) (xy 437.104134 -301.319131)
			(xy 437.134907 -301.365644) (xy 437.158579 -301.416141) (xy 437.174647 -301.469548) (xy 437.182767 -301.524724)
			(xy 437.183276 -301.55261) (xy 437.182836 -301.57674) (xy 439.81319 -301.57674) (xy 439.817261 -301.521118)
			(xy 439.829387 -301.466681) (xy 439.84931 -301.41459) (xy 439.876606 -301.365955) (xy 439.910692 -301.321812)
			(xy 439.950841 -301.283103) (xy 439.996199 -301.250652) (xy 440.045799 -301.225151) (xy 440.098583 -301.207144)
			(xy 440.153426 -301.197014) (xy 440.20916 -301.194977) (xy 440.264597 -301.201077) (xy 440.318554 -301.215183)
			(xy 440.369883 -301.236995) (xy 440.417489 -301.266049) (xy 440.460357 -301.301724) (xy 440.497574 -301.343261)
			(xy 440.528347 -301.389774) (xy 440.552019 -301.440271) (xy 440.568087 -301.493678) (xy 440.576207 -301.548854)
			(xy 440.576716 -301.57674) (xy 440.576207 -301.604626) (xy 440.568087 -301.659802) (xy 440.552019 -301.713209)
			(xy 440.528347 -301.763706) (xy 440.497574 -301.810219) (xy 440.460357 -301.851756) (xy 440.417489 -301.887431)
			(xy 440.369883 -301.916485) (xy 440.318554 -301.938297) (xy 440.264597 -301.952403) (xy 440.20916 -301.958503)
			(xy 440.153426 -301.956466) (xy 440.098583 -301.946336) (xy 440.045799 -301.928329) (xy 439.996199 -301.902828)
			(xy 439.950841 -301.870377) (xy 439.910692 -301.831668) (xy 439.876606 -301.787525) (xy 439.84931 -301.73889)
			(xy 439.829387 -301.686799) (xy 439.817261 -301.632362) (xy 439.81319 -301.57674) (xy 437.182836 -301.57674)
			(xy 437.182767 -301.580496) (xy 437.174647 -301.635672) (xy 437.158579 -301.689079) (xy 437.134907 -301.739576)
			(xy 437.104134 -301.786089) (xy 437.066917 -301.827626) (xy 437.024049 -301.863301) (xy 436.976443 -301.892355)
			(xy 436.925114 -301.914167) (xy 436.871157 -301.928273) (xy 436.81572 -301.934373) (xy 436.759986 -301.932336)
			(xy 436.705143 -301.922206) (xy 436.652359 -301.904199) (xy 436.602759 -301.878698) (xy 436.557401 -301.846247)
			(xy 436.517252 -301.807538) (xy 436.483166 -301.763395) (xy 436.45587 -301.71476) (xy 436.435947 -301.662669)
			(xy 436.423821 -301.608232) (xy 436.41975 -301.55261) (xy 435.226168 -301.55261) (xy 435.251891 -301.568309)
			(xy 435.294759 -301.603984) (xy 435.331976 -301.645521) (xy 435.362749 -301.692034) (xy 435.386421 -301.742531)
			(xy 435.402489 -301.795938) (xy 435.410609 -301.851114) (xy 435.411118 -301.879) (xy 435.410609 -301.906886)
			(xy 435.402489 -301.962062) (xy 435.386421 -302.015469) (xy 435.362749 -302.065966) (xy 435.331976 -302.112479)
			(xy 435.294759 -302.154016) (xy 435.251891 -302.189691) (xy 435.204285 -302.218745) (xy 435.152956 -302.240557)
			(xy 435.098999 -302.254663) (xy 435.043562 -302.260763) (xy 434.987828 -302.258726) (xy 434.932985 -302.248596)
			(xy 434.880201 -302.230589) (xy 434.830601 -302.205088) (xy 434.785243 -302.172637) (xy 434.745094 -302.133928)
			(xy 434.711008 -302.089785) (xy 434.683712 -302.04115) (xy 434.663789 -301.989059) (xy 434.651663 -301.934622)
			(xy 434.647592 -301.879) (xy 431.459066 -301.879) (xy 431.483407 -301.911392) (xy 431.506278 -301.954969)
			(xy 431.521862 -302.00165) (xy 431.529757 -302.050227) (xy 431.530252 -302.074834) (xy 431.529757 -302.099441)
			(xy 431.521862 -302.148018) (xy 431.506278 -302.194699) (xy 431.483407 -302.238276) (xy 431.453842 -302.27762)
			(xy 431.418349 -302.311712) (xy 431.377846 -302.339668) (xy 431.333384 -302.360766) (xy 431.286113 -302.374458)
			(xy 431.237258 -302.38039) (xy 431.188083 -302.378409) (xy 431.139864 -302.368565) (xy 431.093848 -302.351113)
			(xy 431.051227 -302.326506) (xy 431.013106 -302.295381) (xy 430.980471 -302.258544) (xy 430.954168 -302.216948)
			(xy 430.934877 -302.171672) (xy 430.9231 -302.123888) (xy 430.91914 -302.074834) (xy 430.580292 -302.074834)
			(xy 430.579797 -302.099441) (xy 430.571902 -302.148018) (xy 430.556318 -302.194699) (xy 430.533447 -302.238276)
			(xy 430.503882 -302.27762) (xy 430.468389 -302.311712) (xy 430.427886 -302.339668) (xy 430.383424 -302.360766)
			(xy 430.336153 -302.374458) (xy 430.287298 -302.38039) (xy 430.238123 -302.378409) (xy 430.189904 -302.368565)
			(xy 430.143888 -302.351113) (xy 430.101267 -302.326506) (xy 430.063146 -302.295381) (xy 430.030511 -302.258544)
			(xy 430.004208 -302.216948) (xy 429.984917 -302.171672) (xy 429.97314 -302.123888) (xy 429.96918 -302.074834)
			(xy 426.780198 -302.074834) (xy 426.779703 -302.099441) (xy 426.771808 -302.148018) (xy 426.756224 -302.194699)
			(xy 426.733353 -302.238276) (xy 426.703788 -302.27762) (xy 426.668295 -302.311712) (xy 426.627792 -302.339668)
			(xy 426.58333 -302.360766) (xy 426.536059 -302.374458) (xy 426.487204 -302.38039) (xy 426.438029 -302.378409)
			(xy 426.38981 -302.368565) (xy 426.343794 -302.351113) (xy 426.301173 -302.326506) (xy 426.263052 -302.295381)
			(xy 426.230417 -302.258544) (xy 426.204114 -302.216948) (xy 426.184823 -302.171672) (xy 426.173046 -302.123888)
			(xy 426.169086 -302.074834) (xy 425.830238 -302.074834) (xy 425.829743 -302.099441) (xy 425.821848 -302.148018)
			(xy 425.806264 -302.194699) (xy 425.783393 -302.238276) (xy 425.753828 -302.27762) (xy 425.718335 -302.311712)
			(xy 425.677832 -302.339668) (xy 425.63337 -302.360766) (xy 425.586099 -302.374458) (xy 425.537244 -302.38039)
			(xy 425.488069 -302.378409) (xy 425.43985 -302.368565) (xy 425.393834 -302.351113) (xy 425.351213 -302.326506)
			(xy 425.313092 -302.295381) (xy 425.280457 -302.258544) (xy 425.254154 -302.216948) (xy 425.234863 -302.171672)
			(xy 425.223086 -302.123888) (xy 425.219126 -302.074834) (xy 422.030144 -302.074834) (xy 422.029649 -302.099441)
			(xy 422.021754 -302.148018) (xy 422.00617 -302.194699) (xy 421.983299 -302.238276) (xy 421.953734 -302.27762)
			(xy 421.918241 -302.311712) (xy 421.877738 -302.339668) (xy 421.833276 -302.360766) (xy 421.786005 -302.374458)
			(xy 421.73715 -302.38039) (xy 421.687975 -302.378409) (xy 421.639756 -302.368565) (xy 421.59374 -302.351113)
			(xy 421.551119 -302.326506) (xy 421.512998 -302.295381) (xy 421.480363 -302.258544) (xy 421.45406 -302.216948)
			(xy 421.434769 -302.171672) (xy 421.422992 -302.123888) (xy 421.419032 -302.074834) (xy 421.080184 -302.074834)
			(xy 421.079689 -302.099441) (xy 421.071794 -302.148018) (xy 421.05621 -302.194699) (xy 421.033339 -302.238276)
			(xy 421.003774 -302.27762) (xy 420.968281 -302.311712) (xy 420.927778 -302.339668) (xy 420.883316 -302.360766)
			(xy 420.836045 -302.374458) (xy 420.78719 -302.38039) (xy 420.738015 -302.378409) (xy 420.689796 -302.368565)
			(xy 420.64378 -302.351113) (xy 420.601159 -302.326506) (xy 420.563038 -302.295381) (xy 420.530403 -302.258544)
			(xy 420.5041 -302.216948) (xy 420.484809 -302.171672) (xy 420.473032 -302.123888) (xy 420.469072 -302.074834)
			(xy 418.230823 -302.074834) (xy 418.226655 -302.125138) (xy 418.214255 -302.174102) (xy 418.193965 -302.220358)
			(xy 418.166339 -302.262644) (xy 418.132129 -302.299805) (xy 418.092269 -302.330829) (xy 418.047846 -302.354868)
			(xy 418.000073 -302.371269) (xy 417.950251 -302.379582) (xy 417.924996 -302.380142) (xy 417.907724 -302.379634)
			(xy 417.897056 -302.379126) (xy 417.877752 -302.385984) (xy 417.816284 -302.44415) (xy 417.809061 -302.451599)
			(xy 417.800813 -302.470616) (xy 417.800282 -302.48098) (xy 417.800282 -302.618648) (xy 417.80083 -302.629004)
			(xy 417.809096 -302.648002) (xy 417.816284 -302.655478) (xy 417.877752 -302.713644) (xy 417.897056 -302.720502)
			(xy 417.907724 -302.719994) (xy 417.924996 -302.719486) (xy 417.950254 -302.719978) (xy 418.000082 -302.728293)
			(xy 418.047862 -302.744695) (xy 418.092291 -302.768738) (xy 418.132156 -302.799766) (xy 418.16637 -302.836932)
			(xy 418.194001 -302.879223) (xy 418.214293 -302.925485) (xy 418.226694 -302.974456) (xy 418.230866 -303.024794)
			(xy 427.119046 -303.024794) (xy 427.123006 -302.97574) (xy 427.134783 -302.927956) (xy 427.154074 -302.88268)
			(xy 427.180377 -302.841084) (xy 427.213012 -302.804247) (xy 427.251133 -302.773122) (xy 427.293754 -302.748515)
			(xy 427.33977 -302.731063) (xy 427.387989 -302.721219) (xy 427.437164 -302.719238) (xy 427.486019 -302.72517)
			(xy 427.53329 -302.738862) (xy 427.577752 -302.75996) (xy 427.618255 -302.787916) (xy 427.653748 -302.822008)
			(xy 427.683313 -302.861352) (xy 427.706184 -302.904929) (xy 427.721768 -302.95161) (xy 427.729663 -303.000187)
			(xy 427.730158 -303.024794) (xy 428.069006 -303.024794) (xy 428.072966 -302.97574) (xy 428.084743 -302.927956)
			(xy 428.104034 -302.88268) (xy 428.130337 -302.841084) (xy 428.162972 -302.804247) (xy 428.201093 -302.773122)
			(xy 428.243714 -302.748515) (xy 428.28973 -302.731063) (xy 428.337949 -302.721219) (xy 428.387124 -302.719238)
			(xy 428.435979 -302.72517) (xy 428.48325 -302.738862) (xy 428.527712 -302.75996) (xy 428.568215 -302.787916)
			(xy 428.603708 -302.822008) (xy 428.633273 -302.861352) (xy 428.656144 -302.904929) (xy 428.671728 -302.95161)
			(xy 428.679623 -303.000187) (xy 428.680118 -303.024794) (xy 428.679623 -303.049401) (xy 428.671728 -303.097978)
			(xy 428.656144 -303.144659) (xy 428.633273 -303.188236) (xy 428.603708 -303.22758) (xy 428.568215 -303.261672)
			(xy 428.527712 -303.289628) (xy 428.48325 -303.310726) (xy 428.435979 -303.324418) (xy 428.387124 -303.33035)
			(xy 428.337949 -303.328369) (xy 428.28973 -303.318525) (xy 428.243714 -303.301073) (xy 428.201093 -303.276466)
			(xy 428.162972 -303.245341) (xy 428.130337 -303.208504) (xy 428.104034 -303.166908) (xy 428.084743 -303.121632)
			(xy 428.072966 -303.073848) (xy 428.069006 -303.024794) (xy 427.730158 -303.024794) (xy 427.729663 -303.049401)
			(xy 427.721768 -303.097978) (xy 427.706184 -303.144659) (xy 427.683313 -303.188236) (xy 427.653748 -303.22758)
			(xy 427.618255 -303.261672) (xy 427.577752 -303.289628) (xy 427.53329 -303.310726) (xy 427.486019 -303.324418)
			(xy 427.437164 -303.33035) (xy 427.387989 -303.328369) (xy 427.33977 -303.318525) (xy 427.293754 -303.301073)
			(xy 427.251133 -303.276466) (xy 427.213012 -303.245341) (xy 427.180377 -303.208504) (xy 427.154074 -303.166908)
			(xy 427.134783 -303.121632) (xy 427.123006 -303.073848) (xy 427.119046 -303.024794) (xy 418.230866 -303.024794)
			(xy 418.230866 -303.0248) (xy 418.226694 -303.075144) (xy 418.214293 -303.124115) (xy 418.194001 -303.170377)
			(xy 418.16637 -303.212668) (xy 418.132156 -303.249834) (xy 418.092291 -303.280862) (xy 418.047862 -303.304905)
			(xy 418.000082 -303.321307) (xy 417.950254 -303.329622) (xy 417.924996 -303.330102) (xy 417.907724 -303.329594)
			(xy 417.897056 -303.329086) (xy 417.877752 -303.335944) (xy 417.816284 -303.39411) (xy 417.809054 -303.401557)
			(xy 417.800791 -303.420574) (xy 417.800282 -303.43094) (xy 417.800282 -303.974754) (xy 418.569152 -303.974754)
			(xy 418.573112 -303.9257) (xy 418.584889 -303.877916) (xy 418.60418 -303.83264) (xy 418.630483 -303.791044)
			(xy 418.663118 -303.754207) (xy 418.701239 -303.723082) (xy 418.74386 -303.698475) (xy 418.789876 -303.681023)
			(xy 418.838095 -303.671179) (xy 418.88727 -303.669198) (xy 418.936125 -303.67513) (xy 418.983396 -303.688822)
			(xy 419.027858 -303.70992) (xy 419.068361 -303.737876) (xy 419.103854 -303.771968) (xy 419.133419 -303.811312)
			(xy 419.15629 -303.854889) (xy 419.171874 -303.90157) (xy 419.179769 -303.950147) (xy 419.180264 -303.974754)
			(xy 420.469072 -303.974754) (xy 420.473032 -303.9257) (xy 420.484809 -303.877916) (xy 420.5041 -303.83264)
			(xy 420.530403 -303.791044) (xy 420.563038 -303.754207) (xy 420.601159 -303.723082) (xy 420.64378 -303.698475)
			(xy 420.689796 -303.681023) (xy 420.738015 -303.671179) (xy 420.78719 -303.669198) (xy 420.836045 -303.67513)
			(xy 420.883316 -303.688822) (xy 420.927778 -303.70992) (xy 420.968281 -303.737876) (xy 421.003774 -303.771968)
			(xy 421.033339 -303.811312) (xy 421.05621 -303.854889) (xy 421.071794 -303.90157) (xy 421.077455 -303.9364)
			(xy 434.60365 -303.9364) (xy 434.607721 -303.880778) (xy 434.619847 -303.826341) (xy 434.63977 -303.77425)
			(xy 434.667066 -303.725615) (xy 434.701152 -303.681472) (xy 434.741301 -303.642763) (xy 434.786659 -303.610312)
			(xy 434.836259 -303.584811) (xy 434.889043 -303.566804) (xy 434.943886 -303.556674) (xy 434.99962 -303.554637)
			(xy 435.055057 -303.560737) (xy 435.109014 -303.574843) (xy 435.160343 -303.596655) (xy 435.207949 -303.625709)
			(xy 435.250817 -303.661384) (xy 435.288034 -303.702921) (xy 435.318807 -303.749434) (xy 435.342479 -303.799931)
			(xy 435.358547 -303.853338) (xy 435.366667 -303.908514) (xy 435.367176 -303.9364) (xy 435.366667 -303.964286)
			(xy 435.358547 -304.019462) (xy 435.342479 -304.072869) (xy 435.318807 -304.123366) (xy 435.288034 -304.169879)
			(xy 435.250817 -304.211416) (xy 435.207949 -304.247091) (xy 435.160343 -304.276145) (xy 435.109014 -304.297957)
			(xy 435.055057 -304.312063) (xy 434.99962 -304.318163) (xy 434.943886 -304.316126) (xy 434.889043 -304.305996)
			(xy 434.836259 -304.287989) (xy 434.786659 -304.262488) (xy 434.741301 -304.230037) (xy 434.701152 -304.191328)
			(xy 434.667066 -304.147185) (xy 434.63977 -304.09855) (xy 434.619847 -304.046459) (xy 434.607721 -303.992022)
			(xy 434.60365 -303.9364) (xy 421.077455 -303.9364) (xy 421.079689 -303.950147) (xy 421.080184 -303.974754)
			(xy 421.079689 -303.999361) (xy 421.071794 -304.047938) (xy 421.05621 -304.094619) (xy 421.033339 -304.138196)
			(xy 421.003774 -304.17754) (xy 420.968281 -304.211632) (xy 420.927778 -304.239588) (xy 420.883316 -304.260686)
			(xy 420.836045 -304.274378) (xy 420.78719 -304.28031) (xy 420.738015 -304.278329) (xy 420.689796 -304.268485)
			(xy 420.64378 -304.251033) (xy 420.601159 -304.226426) (xy 420.563038 -304.195301) (xy 420.530403 -304.158464)
			(xy 420.5041 -304.116868) (xy 420.484809 -304.071592) (xy 420.473032 -304.023808) (xy 420.469072 -303.974754)
			(xy 419.180264 -303.974754) (xy 419.179769 -303.999361) (xy 419.171874 -304.047938) (xy 419.15629 -304.094619)
			(xy 419.133419 -304.138196) (xy 419.103854 -304.17754) (xy 419.068361 -304.211632) (xy 419.027858 -304.239588)
			(xy 418.983396 -304.260686) (xy 418.936125 -304.274378) (xy 418.88727 -304.28031) (xy 418.838095 -304.278329)
			(xy 418.789876 -304.268485) (xy 418.74386 -304.251033) (xy 418.701239 -304.226426) (xy 418.663118 -304.195301)
			(xy 418.630483 -304.158464) (xy 418.60418 -304.116868) (xy 418.584889 -304.071592) (xy 418.573112 -304.023808)
			(xy 418.569152 -303.974754) (xy 417.800282 -303.974754) (xy 417.800282 -304.475442) (xy 422.823382 -304.475442)
			(xy 422.823382 -304.424026) (xy 422.831425 -304.373244) (xy 422.847313 -304.324345) (xy 422.870656 -304.278533)
			(xy 422.900877 -304.236937) (xy 422.937233 -304.200581) (xy 422.978829 -304.17036) (xy 423.024641 -304.147017)
			(xy 423.07354 -304.131129) (xy 423.124322 -304.123086) (xy 423.175738 -304.123086) (xy 423.22652 -304.131129)
			(xy 423.275419 -304.147017) (xy 423.321231 -304.17036) (xy 423.362827 -304.200581) (xy 423.399183 -304.236937)
			(xy 423.429404 -304.278533) (xy 423.452747 -304.324345) (xy 423.468635 -304.373244) (xy 423.476678 -304.424026)
			(xy 423.477182 -304.449734) (xy 423.476678 -304.475442) (xy 423.773342 -304.475442) (xy 423.773342 -304.424026)
			(xy 423.781385 -304.373244) (xy 423.797273 -304.324345) (xy 423.820616 -304.278533) (xy 423.850837 -304.236937)
			(xy 423.887193 -304.200581) (xy 423.928789 -304.17036) (xy 423.974601 -304.147017) (xy 424.0235 -304.131129)
			(xy 424.074282 -304.123086) (xy 424.125698 -304.123086) (xy 424.17648 -304.131129) (xy 424.225379 -304.147017)
			(xy 424.271191 -304.17036) (xy 424.312787 -304.200581) (xy 424.349143 -304.236937) (xy 424.379364 -304.278533)
			(xy 424.402707 -304.324345) (xy 424.418595 -304.373244) (xy 424.426638 -304.424026) (xy 424.427142 -304.449734)
			(xy 424.426638 -304.475442) (xy 429.473356 -304.475442) (xy 429.473356 -304.424026) (xy 429.481399 -304.373244)
			(xy 429.497287 -304.324345) (xy 429.52063 -304.278533) (xy 429.550851 -304.236937) (xy 429.587207 -304.200581)
			(xy 429.628803 -304.17036) (xy 429.674615 -304.147017) (xy 429.723514 -304.131129) (xy 429.774296 -304.123086)
			(xy 429.825712 -304.123086) (xy 429.876494 -304.131129) (xy 429.925393 -304.147017) (xy 429.971205 -304.17036)
			(xy 430.012801 -304.200581) (xy 430.049157 -304.236937) (xy 430.079378 -304.278533) (xy 430.102721 -304.324345)
			(xy 430.118609 -304.373244) (xy 430.126652 -304.424026) (xy 430.127156 -304.449734) (xy 430.126652 -304.475442)
			(xy 430.423316 -304.475442) (xy 430.423316 -304.424026) (xy 430.431359 -304.373244) (xy 430.447247 -304.324345)
			(xy 430.47059 -304.278533) (xy 430.500811 -304.236937) (xy 430.537167 -304.200581) (xy 430.578763 -304.17036)
			(xy 430.624575 -304.147017) (xy 430.673474 -304.131129) (xy 430.724256 -304.123086) (xy 430.775672 -304.123086)
			(xy 430.826454 -304.131129) (xy 430.875353 -304.147017) (xy 430.921165 -304.17036) (xy 430.962761 -304.200581)
			(xy 430.999117 -304.236937) (xy 431.029338 -304.278533) (xy 431.052681 -304.324345) (xy 431.068569 -304.373244)
			(xy 431.076612 -304.424026) (xy 431.077116 -304.449734) (xy 431.076612 -304.475442) (xy 431.068569 -304.526224)
			(xy 431.052681 -304.575123) (xy 431.029338 -304.620935) (xy 430.999117 -304.662531) (xy 430.962761 -304.698887)
			(xy 430.921165 -304.729108) (xy 430.875353 -304.752451) (xy 430.826454 -304.768339) (xy 430.775672 -304.776382)
			(xy 430.724256 -304.776382) (xy 430.673474 -304.768339) (xy 430.624575 -304.752451) (xy 430.578763 -304.729108)
			(xy 430.537167 -304.698887) (xy 430.500811 -304.662531) (xy 430.47059 -304.620935) (xy 430.447247 -304.575123)
			(xy 430.431359 -304.526224) (xy 430.423316 -304.475442) (xy 430.126652 -304.475442) (xy 430.118609 -304.526224)
			(xy 430.102721 -304.575123) (xy 430.079378 -304.620935) (xy 430.049157 -304.662531) (xy 430.012801 -304.698887)
			(xy 429.971205 -304.729108) (xy 429.925393 -304.752451) (xy 429.876494 -304.768339) (xy 429.825712 -304.776382)
			(xy 429.774296 -304.776382) (xy 429.723514 -304.768339) (xy 429.674615 -304.752451) (xy 429.628803 -304.729108)
			(xy 429.587207 -304.698887) (xy 429.550851 -304.662531) (xy 429.52063 -304.620935) (xy 429.497287 -304.575123)
			(xy 429.481399 -304.526224) (xy 429.473356 -304.475442) (xy 424.426638 -304.475442) (xy 424.418595 -304.526224)
			(xy 424.402707 -304.575123) (xy 424.379364 -304.620935) (xy 424.349143 -304.662531) (xy 424.312787 -304.698887)
			(xy 424.271191 -304.729108) (xy 424.225379 -304.752451) (xy 424.17648 -304.768339) (xy 424.125698 -304.776382)
			(xy 424.074282 -304.776382) (xy 424.0235 -304.768339) (xy 423.974601 -304.752451) (xy 423.928789 -304.729108)
			(xy 423.887193 -304.698887) (xy 423.850837 -304.662531) (xy 423.820616 -304.620935) (xy 423.797273 -304.575123)
			(xy 423.781385 -304.526224) (xy 423.773342 -304.475442) (xy 423.476678 -304.475442) (xy 423.468635 -304.526224)
			(xy 423.452747 -304.575123) (xy 423.429404 -304.620935) (xy 423.399183 -304.662531) (xy 423.362827 -304.698887)
			(xy 423.321231 -304.729108) (xy 423.275419 -304.752451) (xy 423.22652 -304.768339) (xy 423.175738 -304.776382)
			(xy 423.124322 -304.776382) (xy 423.07354 -304.768339) (xy 423.024641 -304.752451) (xy 422.978829 -304.729108)
			(xy 422.937233 -304.698887) (xy 422.900877 -304.662531) (xy 422.870656 -304.620935) (xy 422.847313 -304.575123)
			(xy 422.831425 -304.526224) (xy 422.823382 -304.475442) (xy 417.800282 -304.475442) (xy 417.800282 -304.518568)
			(xy 417.800834 -304.528922) (xy 417.809104 -304.547915) (xy 417.816284 -304.555398) (xy 417.877752 -304.613564)
			(xy 417.897056 -304.620422) (xy 417.907724 -304.619914) (xy 417.924996 -304.619406) (xy 417.950253 -304.619898)
			(xy 418.000077 -304.628212) (xy 418.047854 -304.644613) (xy 418.09228 -304.668655) (xy 418.132142 -304.69968)
			(xy 418.166354 -304.736844) (xy 418.193983 -304.779132) (xy 418.214274 -304.825391) (xy 418.226675 -304.874359)
			(xy 418.230846 -304.9247) (xy 418.230845 -304.924714) (xy 418.569152 -304.924714) (xy 418.573112 -304.87566)
			(xy 418.584889 -304.827876) (xy 418.60418 -304.7826) (xy 418.630483 -304.741004) (xy 418.663118 -304.704167)
			(xy 418.701239 -304.673042) (xy 418.74386 -304.648435) (xy 418.789876 -304.630983) (xy 418.838095 -304.621139)
			(xy 418.88727 -304.619158) (xy 418.936125 -304.62509) (xy 418.983396 -304.638782) (xy 419.027858 -304.65988)
			(xy 419.068361 -304.687836) (xy 419.103854 -304.721928) (xy 419.133419 -304.761272) (xy 419.15629 -304.804849)
			(xy 419.171874 -304.85153) (xy 419.179769 -304.900107) (xy 419.180264 -304.924714) (xy 419.519112 -304.924714)
			(xy 419.523072 -304.87566) (xy 419.534849 -304.827876) (xy 419.55414 -304.7826) (xy 419.580443 -304.741004)
			(xy 419.613078 -304.704167) (xy 419.651199 -304.673042) (xy 419.69382 -304.648435) (xy 419.739836 -304.630983)
			(xy 419.788055 -304.621139) (xy 419.83723 -304.619158) (xy 419.886085 -304.62509) (xy 419.933356 -304.638782)
			(xy 419.977818 -304.65988) (xy 420.018321 -304.687836) (xy 420.053814 -304.721928) (xy 420.083379 -304.761272)
			(xy 420.10625 -304.804849) (xy 420.121834 -304.85153) (xy 420.129729 -304.900107) (xy 420.130224 -304.924714)
			(xy 420.469072 -304.924714) (xy 420.473032 -304.87566) (xy 420.484809 -304.827876) (xy 420.5041 -304.7826)
			(xy 420.530403 -304.741004) (xy 420.563038 -304.704167) (xy 420.601159 -304.673042) (xy 420.64378 -304.648435)
			(xy 420.689796 -304.630983) (xy 420.738015 -304.621139) (xy 420.78719 -304.619158) (xy 420.836045 -304.62509)
			(xy 420.883316 -304.638782) (xy 420.927778 -304.65988) (xy 420.968281 -304.687836) (xy 421.003774 -304.721928)
			(xy 421.033339 -304.761272) (xy 421.043196 -304.780052) (xy 436.149734 -304.780052) (xy 436.149734 -304.725548)
			(xy 436.15749 -304.671598) (xy 436.172844 -304.619302) (xy 436.195484 -304.569722) (xy 436.224949 -304.523869)
			(xy 436.26064 -304.482675) (xy 436.301829 -304.446979) (xy 436.347678 -304.417508) (xy 436.397255 -304.394862)
			(xy 436.449549 -304.3795) (xy 436.503498 -304.371737) (xy 436.53075 -304.371248) (xy 436.557895 -304.371688)
			(xy 436.61164 -304.37937) (xy 436.663751 -304.3946) (xy 436.713173 -304.417069) (xy 436.758908 -304.446324)
			(xy 436.800029 -304.481771) (xy 436.835704 -304.522695) (xy 436.865213 -304.568266) (xy 436.887956 -304.617563)
			(xy 436.903475 -304.669588) (xy 436.90794 -304.696368) (xy 436.910763 -304.711197) (xy 436.923798 -304.738405)
			(xy 436.944204 -304.760626) (xy 436.970207 -304.775926) (xy 436.999542 -304.782973) (xy 437.029656 -304.781154)
			(xy 437.05793 -304.770627) (xy 437.070246 -304.7619) (xy 437.090311 -304.747097) (xy 437.133526 -304.722227)
			(xy 437.179611 -304.703192) (xy 437.227781 -304.690318) (xy 437.277218 -304.683822) (xy 437.302148 -304.683414)
			(xy 437.329399 -304.683859) (xy 437.383344 -304.691622) (xy 437.435636 -304.706982) (xy 437.48521 -304.729627)
			(xy 437.531057 -304.759096) (xy 437.572244 -304.79479) (xy 437.607933 -304.835981) (xy 437.637396 -304.881832)
			(xy 437.660035 -304.931409) (xy 437.675389 -304.983703) (xy 437.683144 -305.037649) (xy 437.683144 -305.064922)
			(xy 437.935114 -305.064922) (xy 437.939185 -305.0093) (xy 437.951311 -304.954863) (xy 437.971234 -304.902772)
			(xy 437.99853 -304.854137) (xy 438.032616 -304.809994) (xy 438.072765 -304.771285) (xy 438.118123 -304.738834)
			(xy 438.167723 -304.713333) (xy 438.220507 -304.695326) (xy 438.27535 -304.685196) (xy 438.331084 -304.683159)
			(xy 438.386521 -304.689259) (xy 438.440478 -304.703365) (xy 438.491807 -304.725177) (xy 438.539413 -304.754231)
			(xy 438.582281 -304.789906) (xy 438.619498 -304.831443) (xy 438.650271 -304.877956) (xy 438.673943 -304.928453)
			(xy 438.690011 -304.98186) (xy 438.698131 -305.037036) (xy 438.69864 -305.064922) (xy 438.943494 -305.064922)
			(xy 438.947565 -305.0093) (xy 438.959691 -304.954863) (xy 438.979614 -304.902772) (xy 439.00691 -304.854137)
			(xy 439.040996 -304.809994) (xy 439.081145 -304.771285) (xy 439.126503 -304.738834) (xy 439.176103 -304.713333)
			(xy 439.228887 -304.695326) (xy 439.28373 -304.685196) (xy 439.339464 -304.683159) (xy 439.394901 -304.689259)
			(xy 439.448858 -304.703365) (xy 439.500187 -304.725177) (xy 439.547793 -304.754231) (xy 439.590661 -304.789906)
			(xy 439.627878 -304.831443) (xy 439.658651 -304.877956) (xy 439.682323 -304.928453) (xy 439.698391 -304.98186)
			(xy 439.706511 -305.037036) (xy 439.707001 -305.063906) (xy 439.96813 -305.063906) (xy 439.972201 -305.008284)
			(xy 439.984327 -304.953847) (xy 440.00425 -304.901756) (xy 440.031546 -304.853121) (xy 440.065632 -304.808978)
			(xy 440.105781 -304.770269) (xy 440.151139 -304.737818) (xy 440.200739 -304.712317) (xy 440.253523 -304.69431)
			(xy 440.308366 -304.68418) (xy 440.3641 -304.682143) (xy 440.419537 -304.688243) (xy 440.473494 -304.702349)
			(xy 440.524823 -304.724161) (xy 440.572429 -304.753215) (xy 440.615297 -304.78889) (xy 440.652514 -304.830427)
			(xy 440.683287 -304.87694) (xy 440.706959 -304.927437) (xy 440.723027 -304.980844) (xy 440.731147 -305.03602)
			(xy 440.731331 -305.046126) (xy 440.98413 -305.046126) (xy 440.988201 -304.990504) (xy 441.000327 -304.936067)
			(xy 441.02025 -304.883976) (xy 441.047546 -304.835341) (xy 441.081632 -304.791198) (xy 441.121781 -304.752489)
			(xy 441.167139 -304.720038) (xy 441.216739 -304.694537) (xy 441.269523 -304.67653) (xy 441.324366 -304.6664)
			(xy 441.3801 -304.664363) (xy 441.435537 -304.670463) (xy 441.489494 -304.684569) (xy 441.540823 -304.706381)
			(xy 441.588429 -304.735435) (xy 441.631297 -304.77111) (xy 441.668514 -304.812647) (xy 441.699287 -304.85916)
			(xy 441.722959 -304.909657) (xy 441.739027 -304.963064) (xy 441.747147 -305.01824) (xy 441.747656 -305.046126)
			(xy 441.747147 -305.074012) (xy 441.739027 -305.129188) (xy 441.722959 -305.182595) (xy 441.699287 -305.233092)
			(xy 441.668514 -305.279605) (xy 441.631297 -305.321142) (xy 441.588429 -305.356817) (xy 441.540823 -305.385871)
			(xy 441.489494 -305.407683) (xy 441.435537 -305.421789) (xy 441.3801 -305.427889) (xy 441.324366 -305.425852)
			(xy 441.269523 -305.415722) (xy 441.216739 -305.397715) (xy 441.167139 -305.372214) (xy 441.121781 -305.339763)
			(xy 441.081632 -305.301054) (xy 441.047546 -305.256911) (xy 441.02025 -305.208276) (xy 441.000327 -305.156185)
			(xy 440.988201 -305.101748) (xy 440.98413 -305.046126) (xy 440.731331 -305.046126) (xy 440.731656 -305.063906)
			(xy 440.731147 -305.091792) (xy 440.723027 -305.146968) (xy 440.706959 -305.200375) (xy 440.683287 -305.250872)
			(xy 440.652514 -305.297385) (xy 440.615297 -305.338922) (xy 440.572429 -305.374597) (xy 440.524823 -305.403651)
			(xy 440.473494 -305.425463) (xy 440.419537 -305.439569) (xy 440.3641 -305.445669) (xy 440.308366 -305.443632)
			(xy 440.253523 -305.433502) (xy 440.200739 -305.415495) (xy 440.151139 -305.389994) (xy 440.105781 -305.357543)
			(xy 440.065632 -305.318834) (xy 440.031546 -305.274691) (xy 440.00425 -305.226056) (xy 439.984327 -305.173965)
			(xy 439.972201 -305.119528) (xy 439.96813 -305.063906) (xy 439.707001 -305.063906) (xy 439.70702 -305.064922)
			(xy 439.706511 -305.092808) (xy 439.698391 -305.147984) (xy 439.682323 -305.201391) (xy 439.658651 -305.251888)
			(xy 439.627878 -305.298401) (xy 439.590661 -305.339938) (xy 439.547793 -305.375613) (xy 439.500187 -305.404667)
			(xy 439.448858 -305.426479) (xy 439.394901 -305.440585) (xy 439.339464 -305.446685) (xy 439.28373 -305.444648)
			(xy 439.228887 -305.434518) (xy 439.176103 -305.416511) (xy 439.126503 -305.39101) (xy 439.081145 -305.358559)
			(xy 439.040996 -305.31985) (xy 439.00691 -305.275707) (xy 438.979614 -305.227072) (xy 438.959691 -305.174981)
			(xy 438.947565 -305.120544) (xy 438.943494 -305.064922) (xy 438.69864 -305.064922) (xy 438.698131 -305.092808)
			(xy 438.690011 -305.147984) (xy 438.673943 -305.201391) (xy 438.650271 -305.251888) (xy 438.619498 -305.298401)
			(xy 438.582281 -305.339938) (xy 438.539413 -305.375613) (xy 438.491807 -305.404667) (xy 438.440478 -305.426479)
			(xy 438.386521 -305.440585) (xy 438.331084 -305.446685) (xy 438.27535 -305.444648) (xy 438.220507 -305.434518)
			(xy 438.167723 -305.416511) (xy 438.118123 -305.39101) (xy 438.072765 -305.358559) (xy 438.032616 -305.31985)
			(xy 437.99853 -305.275707) (xy 437.971234 -305.227072) (xy 437.951311 -305.174981) (xy 437.939185 -305.120544)
			(xy 437.935114 -305.064922) (xy 437.683144 -305.064922) (xy 437.683144 -305.092151) (xy 437.675389 -305.146097)
			(xy 437.660035 -305.198391) (xy 437.637396 -305.247968) (xy 437.607933 -305.293819) (xy 437.572244 -305.33501)
			(xy 437.531057 -305.370704) (xy 437.48521 -305.400173) (xy 437.435636 -305.422818) (xy 437.383344 -305.438178)
			(xy 437.329399 -305.445941) (xy 437.302148 -305.44643) (xy 437.275002 -305.44601) (xy 437.221256 -305.438328)
			(xy 437.169143 -305.423097) (xy 437.119719 -305.400625) (xy 437.073984 -305.371369) (xy 437.032863 -305.335919)
			(xy 436.997188 -305.294993) (xy 436.96768 -305.249419) (xy 436.944938 -305.200119) (xy 436.929421 -305.148091)
			(xy 436.924958 -305.12131) (xy 436.922149 -305.106479) (xy 436.909109 -305.079272) (xy 436.8887 -305.057053)
			(xy 436.862695 -305.041755) (xy 436.83336 -305.034708) (xy 436.803244 -305.036527) (xy 436.774969 -305.047052)
			(xy 436.762652 -305.055778) (xy 436.742596 -305.070592) (xy 436.699377 -305.095459) (xy 436.65329 -305.11449)
			(xy 436.605118 -305.127362) (xy 436.555681 -305.133857) (xy 436.53075 -305.134264) (xy 436.503498 -305.133863)
			(xy 436.449549 -305.1261) (xy 436.397255 -305.110738) (xy 436.347678 -305.088092) (xy 436.301829 -305.058621)
			(xy 436.26064 -305.022925) (xy 436.224949 -304.981731) (xy 436.195484 -304.935878) (xy 436.172844 -304.886298)
			(xy 436.15749 -304.834002) (xy 436.149734 -304.780052) (xy 421.043196 -304.780052) (xy 421.05621 -304.804849)
			(xy 421.071794 -304.85153) (xy 421.079689 -304.900107) (xy 421.080184 -304.924714) (xy 421.079689 -304.949321)
			(xy 421.071794 -304.997898) (xy 421.05621 -305.044579) (xy 421.033339 -305.088156) (xy 421.003774 -305.1275)
			(xy 420.968281 -305.161592) (xy 420.927778 -305.189548) (xy 420.883316 -305.210646) (xy 420.836045 -305.224338)
			(xy 420.78719 -305.23027) (xy 420.738015 -305.228289) (xy 420.689796 -305.218445) (xy 420.64378 -305.200993)
			(xy 420.601159 -305.176386) (xy 420.563038 -305.145261) (xy 420.530403 -305.108424) (xy 420.5041 -305.066828)
			(xy 420.484809 -305.021552) (xy 420.473032 -304.973768) (xy 420.469072 -304.924714) (xy 420.130224 -304.924714)
			(xy 420.129729 -304.949321) (xy 420.121834 -304.997898) (xy 420.10625 -305.044579) (xy 420.083379 -305.088156)
			(xy 420.053814 -305.1275) (xy 420.018321 -305.161592) (xy 419.977818 -305.189548) (xy 419.933356 -305.210646)
			(xy 419.886085 -305.224338) (xy 419.83723 -305.23027) (xy 419.788055 -305.228289) (xy 419.739836 -305.218445)
			(xy 419.69382 -305.200993) (xy 419.651199 -305.176386) (xy 419.613078 -305.145261) (xy 419.580443 -305.108424)
			(xy 419.55414 -305.066828) (xy 419.534849 -305.021552) (xy 419.523072 -304.973768) (xy 419.519112 -304.924714)
			(xy 419.180264 -304.924714) (xy 419.179769 -304.949321) (xy 419.171874 -304.997898) (xy 419.15629 -305.044579)
			(xy 419.133419 -305.088156) (xy 419.103854 -305.1275) (xy 419.068361 -305.161592) (xy 419.027858 -305.189548)
			(xy 418.983396 -305.210646) (xy 418.936125 -305.224338) (xy 418.88727 -305.23027) (xy 418.838095 -305.228289)
			(xy 418.789876 -305.218445) (xy 418.74386 -305.200993) (xy 418.701239 -305.176386) (xy 418.663118 -305.145261)
			(xy 418.630483 -305.108424) (xy 418.60418 -305.066828) (xy 418.584889 -305.021552) (xy 418.573112 -304.973768)
			(xy 418.569152 -304.924714) (xy 418.230845 -304.924714) (xy 418.226675 -304.975041) (xy 418.214274 -305.024009)
			(xy 418.193983 -305.070268) (xy 418.166354 -305.112556) (xy 418.132142 -305.14972) (xy 418.09228 -305.180745)
			(xy 418.047854 -305.204787) (xy 418.000077 -305.221188) (xy 417.950253 -305.229502) (xy 417.924996 -305.230022)
			(xy 417.907724 -305.229514) (xy 417.897056 -305.229006) (xy 417.877752 -305.235864) (xy 417.816284 -305.29403)
			(xy 417.809058 -305.301478) (xy 417.800802 -305.320495) (xy 417.800282 -305.33086) (xy 417.800282 -305.425656)
			(xy 424.723302 -305.425656) (xy 424.723302 -305.37424) (xy 424.731345 -305.323458) (xy 424.747233 -305.274559)
			(xy 424.770576 -305.228747) (xy 424.800797 -305.187151) (xy 424.837153 -305.150795) (xy 424.878749 -305.120574)
			(xy 424.924561 -305.097231) (xy 424.97346 -305.081343) (xy 425.024242 -305.0733) (xy 425.075658 -305.0733)
			(xy 425.12644 -305.081343) (xy 425.175339 -305.097231) (xy 425.221151 -305.120574) (xy 425.262747 -305.150795)
			(xy 425.299103 -305.187151) (xy 425.329324 -305.228747) (xy 425.352667 -305.274559) (xy 425.368555 -305.323458)
			(xy 425.376598 -305.37424) (xy 425.377102 -305.399948) (xy 425.376598 -305.425656) (xy 425.673262 -305.425656)
			(xy 425.673262 -305.37424) (xy 425.681305 -305.323458) (xy 425.697193 -305.274559) (xy 425.720536 -305.228747)
			(xy 425.750757 -305.187151) (xy 425.787113 -305.150795) (xy 425.828709 -305.120574) (xy 425.874521 -305.097231)
			(xy 425.92342 -305.081343) (xy 425.974202 -305.0733) (xy 426.025618 -305.0733) (xy 426.0764 -305.081343)
			(xy 426.125299 -305.097231) (xy 426.171111 -305.120574) (xy 426.212707 -305.150795) (xy 426.249063 -305.187151)
			(xy 426.279284 -305.228747) (xy 426.302627 -305.274559) (xy 426.318515 -305.323458) (xy 426.326558 -305.37424)
			(xy 426.327062 -305.399948) (xy 426.326558 -305.425656) (xy 427.573182 -305.425656) (xy 427.573182 -305.37424)
			(xy 427.581225 -305.323458) (xy 427.597113 -305.274559) (xy 427.620456 -305.228747) (xy 427.650677 -305.187151)
			(xy 427.687033 -305.150795) (xy 427.728629 -305.120574) (xy 427.774441 -305.097231) (xy 427.82334 -305.081343)
			(xy 427.874122 -305.0733) (xy 427.925538 -305.0733) (xy 427.97632 -305.081343) (xy 428.025219 -305.097231)
			(xy 428.071031 -305.120574) (xy 428.112627 -305.150795) (xy 428.148983 -305.187151) (xy 428.179204 -305.228747)
			(xy 428.202547 -305.274559) (xy 428.218435 -305.323458) (xy 428.226478 -305.37424) (xy 428.226982 -305.399948)
			(xy 428.226478 -305.425656) (xy 428.523142 -305.425656) (xy 428.523142 -305.37424) (xy 428.531185 -305.323458)
			(xy 428.547073 -305.274559) (xy 428.570416 -305.228747) (xy 428.600637 -305.187151) (xy 428.636993 -305.150795)
			(xy 428.678589 -305.120574) (xy 428.724401 -305.097231) (xy 428.7733 -305.081343) (xy 428.824082 -305.0733)
			(xy 428.875498 -305.0733) (xy 428.92628 -305.081343) (xy 428.975179 -305.097231) (xy 429.020991 -305.120574)
			(xy 429.062587 -305.150795) (xy 429.098943 -305.187151) (xy 429.129164 -305.228747) (xy 429.152507 -305.274559)
			(xy 429.168395 -305.323458) (xy 429.176438 -305.37424) (xy 429.176942 -305.399948) (xy 429.176438 -305.425656)
			(xy 429.168395 -305.476438) (xy 429.152507 -305.525337) (xy 429.129164 -305.571149) (xy 429.098943 -305.612745)
			(xy 429.062587 -305.649101) (xy 429.020991 -305.679322) (xy 428.975179 -305.702665) (xy 428.92628 -305.718553)
			(xy 428.875498 -305.726596) (xy 428.824082 -305.726596) (xy 428.7733 -305.718553) (xy 428.724401 -305.702665)
			(xy 428.678589 -305.679322) (xy 428.636993 -305.649101) (xy 428.600637 -305.612745) (xy 428.570416 -305.571149)
			(xy 428.547073 -305.525337) (xy 428.531185 -305.476438) (xy 428.523142 -305.425656) (xy 428.226478 -305.425656)
			(xy 428.218435 -305.476438) (xy 428.202547 -305.525337) (xy 428.179204 -305.571149) (xy 428.148983 -305.612745)
			(xy 428.112627 -305.649101) (xy 428.071031 -305.679322) (xy 428.025219 -305.702665) (xy 427.97632 -305.718553)
			(xy 427.925538 -305.726596) (xy 427.874122 -305.726596) (xy 427.82334 -305.718553) (xy 427.774441 -305.702665)
			(xy 427.728629 -305.679322) (xy 427.687033 -305.649101) (xy 427.650677 -305.612745) (xy 427.620456 -305.571149)
			(xy 427.597113 -305.525337) (xy 427.581225 -305.476438) (xy 427.573182 -305.425656) (xy 426.326558 -305.425656)
			(xy 426.318515 -305.476438) (xy 426.302627 -305.525337) (xy 426.279284 -305.571149) (xy 426.249063 -305.612745)
			(xy 426.212707 -305.649101) (xy 426.171111 -305.679322) (xy 426.125299 -305.702665) (xy 426.0764 -305.718553)
			(xy 426.025618 -305.726596) (xy 425.974202 -305.726596) (xy 425.92342 -305.718553) (xy 425.874521 -305.702665)
			(xy 425.828709 -305.679322) (xy 425.787113 -305.649101) (xy 425.750757 -305.612745) (xy 425.720536 -305.571149)
			(xy 425.697193 -305.525337) (xy 425.681305 -305.476438) (xy 425.673262 -305.425656) (xy 425.376598 -305.425656)
			(xy 425.368555 -305.476438) (xy 425.352667 -305.525337) (xy 425.329324 -305.571149) (xy 425.299103 -305.612745)
			(xy 425.262747 -305.649101) (xy 425.221151 -305.679322) (xy 425.175339 -305.702665) (xy 425.12644 -305.718553)
			(xy 425.075658 -305.726596) (xy 425.024242 -305.726596) (xy 424.97346 -305.718553) (xy 424.924561 -305.702665)
			(xy 424.878749 -305.679322) (xy 424.837153 -305.649101) (xy 424.800797 -305.612745) (xy 424.770576 -305.571149)
			(xy 424.747233 -305.525337) (xy 424.731345 -305.476438) (xy 424.723302 -305.425656) (xy 417.800282 -305.425656)
			(xy 417.800282 -305.874928) (xy 418.569152 -305.874928) (xy 418.573112 -305.825874) (xy 418.584889 -305.77809)
			(xy 418.60418 -305.732814) (xy 418.630483 -305.691218) (xy 418.663118 -305.654381) (xy 418.701239 -305.623256)
			(xy 418.74386 -305.598649) (xy 418.789876 -305.581197) (xy 418.838095 -305.571353) (xy 418.88727 -305.569372)
			(xy 418.936125 -305.575304) (xy 418.983396 -305.588996) (xy 419.027858 -305.610094) (xy 419.068361 -305.63805)
			(xy 419.103854 -305.672142) (xy 419.133419 -305.711486) (xy 419.15629 -305.755063) (xy 419.171874 -305.801744)
			(xy 419.179769 -305.850321) (xy 419.180264 -305.874928) (xy 420.469072 -305.874928) (xy 420.473032 -305.825874)
			(xy 420.484809 -305.77809) (xy 420.5041 -305.732814) (xy 420.530403 -305.691218) (xy 420.563038 -305.654381)
			(xy 420.601159 -305.623256) (xy 420.64378 -305.598649) (xy 420.689796 -305.581197) (xy 420.738015 -305.571353)
			(xy 420.78719 -305.569372) (xy 420.836045 -305.575304) (xy 420.883316 -305.588996) (xy 420.927778 -305.610094)
			(xy 420.968281 -305.63805) (xy 421.003774 -305.672142) (xy 421.033339 -305.711486) (xy 421.05621 -305.755063)
			(xy 421.071794 -305.801744) (xy 421.079689 -305.850321) (xy 421.080184 -305.874928) (xy 421.079689 -305.899535)
			(xy 421.071794 -305.948112) (xy 421.05621 -305.994793) (xy 421.033339 -306.03837) (xy 421.003774 -306.077714)
			(xy 420.968281 -306.111806) (xy 420.927778 -306.139762) (xy 420.883316 -306.16086) (xy 420.836045 -306.174552)
			(xy 420.78719 -306.180484) (xy 420.738015 -306.178503) (xy 420.689796 -306.168659) (xy 420.64378 -306.151207)
			(xy 420.601159 -306.1266) (xy 420.563038 -306.095475) (xy 420.530403 -306.058638) (xy 420.5041 -306.017042)
			(xy 420.484809 -305.971766) (xy 420.473032 -305.923982) (xy 420.469072 -305.874928) (xy 419.180264 -305.874928)
			(xy 419.179769 -305.899535) (xy 419.171874 -305.948112) (xy 419.15629 -305.994793) (xy 419.133419 -306.03837)
			(xy 419.103854 -306.077714) (xy 419.068361 -306.111806) (xy 419.027858 -306.139762) (xy 418.983396 -306.16086)
			(xy 418.936125 -306.174552) (xy 418.88727 -306.180484) (xy 418.838095 -306.178503) (xy 418.789876 -306.168659)
			(xy 418.74386 -306.151207) (xy 418.701239 -306.1266) (xy 418.663118 -306.095475) (xy 418.630483 -306.058638)
			(xy 418.60418 -306.017042) (xy 418.584889 -305.971766) (xy 418.573112 -305.923982) (xy 418.569152 -305.874928)
			(xy 417.800282 -305.874928) (xy 417.800282 -306.375616) (xy 422.823382 -306.375616) (xy 422.823382 -306.3242)
			(xy 422.831425 -306.273418) (xy 422.847313 -306.224519) (xy 422.870656 -306.178707) (xy 422.900877 -306.137111)
			(xy 422.937233 -306.100755) (xy 422.978829 -306.070534) (xy 423.024641 -306.047191) (xy 423.07354 -306.031303)
			(xy 423.124322 -306.02326) (xy 423.175738 -306.02326) (xy 423.22652 -306.031303) (xy 423.275419 -306.047191)
			(xy 423.321231 -306.070534) (xy 423.362827 -306.100755) (xy 423.399183 -306.137111) (xy 423.429404 -306.178707)
			(xy 423.452747 -306.224519) (xy 423.468635 -306.273418) (xy 423.476678 -306.3242) (xy 423.477182 -306.349908)
			(xy 423.476678 -306.375616) (xy 423.773342 -306.375616) (xy 423.773342 -306.3242) (xy 423.781385 -306.273418)
			(xy 423.797273 -306.224519) (xy 423.820616 -306.178707) (xy 423.850837 -306.137111) (xy 423.887193 -306.100755)
			(xy 423.928789 -306.070534) (xy 423.974601 -306.047191) (xy 424.0235 -306.031303) (xy 424.074282 -306.02326)
			(xy 424.125698 -306.02326) (xy 424.17648 -306.031303) (xy 424.225379 -306.047191) (xy 424.271191 -306.070534)
			(xy 424.312787 -306.100755) (xy 424.349143 -306.137111) (xy 424.379364 -306.178707) (xy 424.402707 -306.224519)
			(xy 424.418595 -306.273418) (xy 424.426638 -306.3242) (xy 424.427142 -306.349908) (xy 424.426638 -306.375616)
			(xy 429.473356 -306.375616) (xy 429.473356 -306.3242) (xy 429.481399 -306.273418) (xy 429.497287 -306.224519)
			(xy 429.52063 -306.178707) (xy 429.550851 -306.137111) (xy 429.587207 -306.100755) (xy 429.628803 -306.070534)
			(xy 429.674615 -306.047191) (xy 429.723514 -306.031303) (xy 429.774296 -306.02326) (xy 429.825712 -306.02326)
			(xy 429.876494 -306.031303) (xy 429.925393 -306.047191) (xy 429.971205 -306.070534) (xy 430.012801 -306.100755)
			(xy 430.049157 -306.137111) (xy 430.079378 -306.178707) (xy 430.102721 -306.224519) (xy 430.118609 -306.273418)
			(xy 430.126652 -306.3242) (xy 430.127156 -306.349908) (xy 430.126652 -306.375616) (xy 430.423316 -306.375616)
			(xy 430.423316 -306.3242) (xy 430.431359 -306.273418) (xy 430.447247 -306.224519) (xy 430.47059 -306.178707)
			(xy 430.500811 -306.137111) (xy 430.537167 -306.100755) (xy 430.578763 -306.070534) (xy 430.624575 -306.047191)
			(xy 430.673474 -306.031303) (xy 430.724256 -306.02326) (xy 430.775672 -306.02326) (xy 430.826454 -306.031303)
			(xy 430.875353 -306.047191) (xy 430.921165 -306.070534) (xy 430.962761 -306.100755) (xy 430.999117 -306.137111)
			(xy 431.029338 -306.178707) (xy 431.052681 -306.224519) (xy 431.068569 -306.273418) (xy 431.076612 -306.3242)
			(xy 431.077116 -306.349908) (xy 431.076612 -306.375616) (xy 431.068569 -306.426398) (xy 431.052681 -306.475297)
			(xy 431.029338 -306.521109) (xy 430.999117 -306.562705) (xy 430.962761 -306.599061) (xy 430.921165 -306.629282)
			(xy 430.875353 -306.652625) (xy 430.826454 -306.668513) (xy 430.775672 -306.676556) (xy 430.724256 -306.676556)
			(xy 430.673474 -306.668513) (xy 430.624575 -306.652625) (xy 430.578763 -306.629282) (xy 430.537167 -306.599061)
			(xy 430.500811 -306.562705) (xy 430.47059 -306.521109) (xy 430.447247 -306.475297) (xy 430.431359 -306.426398)
			(xy 430.423316 -306.375616) (xy 430.126652 -306.375616) (xy 430.118609 -306.426398) (xy 430.102721 -306.475297)
			(xy 430.079378 -306.521109) (xy 430.049157 -306.562705) (xy 430.012801 -306.599061) (xy 429.971205 -306.629282)
			(xy 429.925393 -306.652625) (xy 429.876494 -306.668513) (xy 429.825712 -306.676556) (xy 429.774296 -306.676556)
			(xy 429.723514 -306.668513) (xy 429.674615 -306.652625) (xy 429.628803 -306.629282) (xy 429.587207 -306.599061)
			(xy 429.550851 -306.562705) (xy 429.52063 -306.521109) (xy 429.497287 -306.475297) (xy 429.481399 -306.426398)
			(xy 429.473356 -306.375616) (xy 424.426638 -306.375616) (xy 424.418595 -306.426398) (xy 424.402707 -306.475297)
			(xy 424.379364 -306.521109) (xy 424.349143 -306.562705) (xy 424.312787 -306.599061) (xy 424.271191 -306.629282)
			(xy 424.225379 -306.652625) (xy 424.17648 -306.668513) (xy 424.125698 -306.676556) (xy 424.074282 -306.676556)
			(xy 424.0235 -306.668513) (xy 423.974601 -306.652625) (xy 423.928789 -306.629282) (xy 423.887193 -306.599061)
			(xy 423.850837 -306.562705) (xy 423.820616 -306.521109) (xy 423.797273 -306.475297) (xy 423.781385 -306.426398)
			(xy 423.773342 -306.375616) (xy 423.476678 -306.375616) (xy 423.468635 -306.426398) (xy 423.452747 -306.475297)
			(xy 423.429404 -306.521109) (xy 423.399183 -306.562705) (xy 423.362827 -306.599061) (xy 423.321231 -306.629282)
			(xy 423.275419 -306.652625) (xy 423.22652 -306.668513) (xy 423.175738 -306.676556) (xy 423.124322 -306.676556)
			(xy 423.07354 -306.668513) (xy 423.024641 -306.652625) (xy 422.978829 -306.629282) (xy 422.937233 -306.599061)
			(xy 422.900877 -306.562705) (xy 422.870656 -306.521109) (xy 422.847313 -306.475297) (xy 422.831425 -306.426398)
			(xy 422.823382 -306.375616) (xy 417.800282 -306.375616) (xy 417.800282 -306.824888) (xy 418.569152 -306.824888)
			(xy 418.573112 -306.775834) (xy 418.584889 -306.72805) (xy 418.60418 -306.682774) (xy 418.630483 -306.641178)
			(xy 418.663118 -306.604341) (xy 418.701239 -306.573216) (xy 418.74386 -306.548609) (xy 418.789876 -306.531157)
			(xy 418.838095 -306.521313) (xy 418.88727 -306.519332) (xy 418.936125 -306.525264) (xy 418.983396 -306.538956)
			(xy 419.027858 -306.560054) (xy 419.068361 -306.58801) (xy 419.103854 -306.622102) (xy 419.133419 -306.661446)
			(xy 419.15629 -306.705023) (xy 419.171874 -306.751704) (xy 419.179769 -306.800281) (xy 419.180264 -306.824888)
			(xy 419.519112 -306.824888) (xy 419.523072 -306.775834) (xy 419.534849 -306.72805) (xy 419.55414 -306.682774)
			(xy 419.580443 -306.641178) (xy 419.613078 -306.604341) (xy 419.651199 -306.573216) (xy 419.69382 -306.548609)
			(xy 419.739836 -306.531157) (xy 419.788055 -306.521313) (xy 419.83723 -306.519332) (xy 419.886085 -306.525264)
			(xy 419.933356 -306.538956) (xy 419.977818 -306.560054) (xy 420.018321 -306.58801) (xy 420.053814 -306.622102)
			(xy 420.083379 -306.661446) (xy 420.10625 -306.705023) (xy 420.121834 -306.751704) (xy 420.129729 -306.800281)
			(xy 420.130224 -306.824888) (xy 420.469072 -306.824888) (xy 420.473032 -306.775834) (xy 420.484809 -306.72805)
			(xy 420.5041 -306.682774) (xy 420.530403 -306.641178) (xy 420.563038 -306.604341) (xy 420.601159 -306.573216)
			(xy 420.64378 -306.548609) (xy 420.689796 -306.531157) (xy 420.738015 -306.521313) (xy 420.78719 -306.519332)
			(xy 420.836045 -306.525264) (xy 420.883316 -306.538956) (xy 420.927778 -306.560054) (xy 420.968281 -306.58801)
			(xy 421.003774 -306.622102) (xy 421.033339 -306.661446) (xy 421.05621 -306.705023) (xy 421.071794 -306.751704)
			(xy 421.079689 -306.800281) (xy 421.080184 -306.824888) (xy 421.079689 -306.849495) (xy 421.071794 -306.898072)
			(xy 421.05621 -306.944753) (xy 421.033339 -306.98833) (xy 421.003774 -307.027674) (xy 420.968281 -307.061766)
			(xy 420.927778 -307.089722) (xy 420.883316 -307.11082) (xy 420.836045 -307.124512) (xy 420.78719 -307.130444)
			(xy 420.738015 -307.128463) (xy 420.689796 -307.118619) (xy 420.64378 -307.101167) (xy 420.601159 -307.07656)
			(xy 420.563038 -307.045435) (xy 420.530403 -307.008598) (xy 420.5041 -306.967002) (xy 420.484809 -306.921726)
			(xy 420.473032 -306.873942) (xy 420.469072 -306.824888) (xy 420.130224 -306.824888) (xy 420.129729 -306.849495)
			(xy 420.121834 -306.898072) (xy 420.10625 -306.944753) (xy 420.083379 -306.98833) (xy 420.053814 -307.027674)
			(xy 420.018321 -307.061766) (xy 419.977818 -307.089722) (xy 419.933356 -307.11082) (xy 419.886085 -307.124512)
			(xy 419.83723 -307.130444) (xy 419.788055 -307.128463) (xy 419.739836 -307.118619) (xy 419.69382 -307.101167)
			(xy 419.651199 -307.07656) (xy 419.613078 -307.045435) (xy 419.580443 -307.008598) (xy 419.55414 -306.967002)
			(xy 419.534849 -306.921726) (xy 419.523072 -306.873942) (xy 419.519112 -306.824888) (xy 419.180264 -306.824888)
			(xy 419.179769 -306.849495) (xy 419.171874 -306.898072) (xy 419.15629 -306.944753) (xy 419.133419 -306.98833)
			(xy 419.103854 -307.027674) (xy 419.068361 -307.061766) (xy 419.027858 -307.089722) (xy 418.983396 -307.11082)
			(xy 418.936125 -307.124512) (xy 418.88727 -307.130444) (xy 418.838095 -307.128463) (xy 418.789876 -307.118619)
			(xy 418.74386 -307.101167) (xy 418.701239 -307.07656) (xy 418.663118 -307.045435) (xy 418.630483 -307.008598)
			(xy 418.60418 -306.967002) (xy 418.584889 -306.921726) (xy 418.573112 -306.873942) (xy 418.569152 -306.824888)
			(xy 417.800282 -306.824888) (xy 417.800282 -307.325576) (xy 424.723302 -307.325576) (xy 424.723302 -307.27416)
			(xy 424.731345 -307.223378) (xy 424.747233 -307.174479) (xy 424.770576 -307.128667) (xy 424.800797 -307.087071)
			(xy 424.837153 -307.050715) (xy 424.878749 -307.020494) (xy 424.924561 -306.997151) (xy 424.97346 -306.981263)
			(xy 425.024242 -306.97322) (xy 425.075658 -306.97322) (xy 425.12644 -306.981263) (xy 425.175339 -306.997151)
			(xy 425.221151 -307.020494) (xy 425.262747 -307.050715) (xy 425.299103 -307.087071) (xy 425.329324 -307.128667)
			(xy 425.352667 -307.174479) (xy 425.368555 -307.223378) (xy 425.376598 -307.27416) (xy 425.377102 -307.299868)
			(xy 425.376598 -307.325576) (xy 425.673262 -307.325576) (xy 425.673262 -307.27416) (xy 425.681305 -307.223378)
			(xy 425.697193 -307.174479) (xy 425.720536 -307.128667) (xy 425.750757 -307.087071) (xy 425.787113 -307.050715)
			(xy 425.828709 -307.020494) (xy 425.874521 -306.997151) (xy 425.92342 -306.981263) (xy 425.974202 -306.97322)
			(xy 426.025618 -306.97322) (xy 426.0764 -306.981263) (xy 426.125299 -306.997151) (xy 426.171111 -307.020494)
			(xy 426.212707 -307.050715) (xy 426.249063 -307.087071) (xy 426.279284 -307.128667) (xy 426.302627 -307.174479)
			(xy 426.318515 -307.223378) (xy 426.326558 -307.27416) (xy 426.327062 -307.299868) (xy 426.326558 -307.325576)
			(xy 427.573182 -307.325576) (xy 427.573182 -307.27416) (xy 427.581225 -307.223378) (xy 427.597113 -307.174479)
			(xy 427.620456 -307.128667) (xy 427.650677 -307.087071) (xy 427.687033 -307.050715) (xy 427.728629 -307.020494)
			(xy 427.774441 -306.997151) (xy 427.82334 -306.981263) (xy 427.874122 -306.97322) (xy 427.925538 -306.97322)
			(xy 427.97632 -306.981263) (xy 428.025219 -306.997151) (xy 428.071031 -307.020494) (xy 428.112627 -307.050715)
			(xy 428.148983 -307.087071) (xy 428.179204 -307.128667) (xy 428.202547 -307.174479) (xy 428.218435 -307.223378)
			(xy 428.226478 -307.27416) (xy 428.226982 -307.299868) (xy 428.226478 -307.325576) (xy 428.523142 -307.325576)
			(xy 428.523142 -307.27416) (xy 428.531185 -307.223378) (xy 428.547073 -307.174479) (xy 428.570416 -307.128667)
			(xy 428.600637 -307.087071) (xy 428.636993 -307.050715) (xy 428.678589 -307.020494) (xy 428.724401 -306.997151)
			(xy 428.7733 -306.981263) (xy 428.824082 -306.97322) (xy 428.875498 -306.97322) (xy 428.92628 -306.981263)
			(xy 428.975179 -306.997151) (xy 429.020991 -307.020494) (xy 429.062587 -307.050715) (xy 429.096094 -307.084222)
			(xy 441.014356 -307.084222) (xy 441.018427 -307.0286) (xy 441.030553 -306.974163) (xy 441.050476 -306.922072)
			(xy 441.077772 -306.873437) (xy 441.111858 -306.829294) (xy 441.152007 -306.790585) (xy 441.197365 -306.758134)
			(xy 441.246965 -306.732633) (xy 441.299749 -306.714626) (xy 441.354592 -306.704496) (xy 441.410326 -306.702459)
			(xy 441.465763 -306.708559) (xy 441.51972 -306.722665) (xy 441.571049 -306.744477) (xy 441.618655 -306.773531)
			(xy 441.661523 -306.809206) (xy 441.69874 -306.850743) (xy 441.729513 -306.897256) (xy 441.753185 -306.947753)
			(xy 441.769253 -307.00116) (xy 441.777373 -307.056336) (xy 441.777882 -307.084222) (xy 441.777373 -307.112108)
			(xy 441.769253 -307.167284) (xy 441.753185 -307.220691) (xy 441.729513 -307.271188) (xy 441.69874 -307.317701)
			(xy 441.661523 -307.359238) (xy 441.618655 -307.394913) (xy 441.571049 -307.423967) (xy 441.51972 -307.445779)
			(xy 441.465763 -307.459885) (xy 441.410326 -307.465985) (xy 441.354592 -307.463948) (xy 441.299749 -307.453818)
			(xy 441.246965 -307.435811) (xy 441.197365 -307.41031) (xy 441.152007 -307.377859) (xy 441.111858 -307.33915)
			(xy 441.077772 -307.295007) (xy 441.050476 -307.246372) (xy 441.030553 -307.194281) (xy 441.018427 -307.139844)
			(xy 441.014356 -307.084222) (xy 429.096094 -307.084222) (xy 429.098943 -307.087071) (xy 429.129164 -307.128667)
			(xy 429.152507 -307.174479) (xy 429.168395 -307.223378) (xy 429.176438 -307.27416) (xy 429.176942 -307.299868)
			(xy 429.176438 -307.325576) (xy 429.168395 -307.376358) (xy 429.152507 -307.425257) (xy 429.129164 -307.471069)
			(xy 429.098943 -307.512665) (xy 429.062587 -307.549021) (xy 429.020991 -307.579242) (xy 428.975179 -307.602585)
			(xy 428.92628 -307.618473) (xy 428.875498 -307.626516) (xy 428.824082 -307.626516) (xy 428.7733 -307.618473)
			(xy 428.724401 -307.602585) (xy 428.678589 -307.579242) (xy 428.636993 -307.549021) (xy 428.600637 -307.512665)
			(xy 428.570416 -307.471069) (xy 428.547073 -307.425257) (xy 428.531185 -307.376358) (xy 428.523142 -307.325576)
			(xy 428.226478 -307.325576) (xy 428.218435 -307.376358) (xy 428.202547 -307.425257) (xy 428.179204 -307.471069)
			(xy 428.148983 -307.512665) (xy 428.112627 -307.549021) (xy 428.071031 -307.579242) (xy 428.025219 -307.602585)
			(xy 427.97632 -307.618473) (xy 427.925538 -307.626516) (xy 427.874122 -307.626516) (xy 427.82334 -307.618473)
			(xy 427.774441 -307.602585) (xy 427.728629 -307.579242) (xy 427.687033 -307.549021) (xy 427.650677 -307.512665)
			(xy 427.620456 -307.471069) (xy 427.597113 -307.425257) (xy 427.581225 -307.376358) (xy 427.573182 -307.325576)
			(xy 426.326558 -307.325576) (xy 426.318515 -307.376358) (xy 426.302627 -307.425257) (xy 426.279284 -307.471069)
			(xy 426.249063 -307.512665) (xy 426.212707 -307.549021) (xy 426.171111 -307.579242) (xy 426.125299 -307.602585)
			(xy 426.0764 -307.618473) (xy 426.025618 -307.626516) (xy 425.974202 -307.626516) (xy 425.92342 -307.618473)
			(xy 425.874521 -307.602585) (xy 425.828709 -307.579242) (xy 425.787113 -307.549021) (xy 425.750757 -307.512665)
			(xy 425.720536 -307.471069) (xy 425.697193 -307.425257) (xy 425.681305 -307.376358) (xy 425.673262 -307.325576)
			(xy 425.376598 -307.325576) (xy 425.368555 -307.376358) (xy 425.352667 -307.425257) (xy 425.329324 -307.471069)
			(xy 425.299103 -307.512665) (xy 425.262747 -307.549021) (xy 425.221151 -307.579242) (xy 425.175339 -307.602585)
			(xy 425.12644 -307.618473) (xy 425.075658 -307.626516) (xy 425.024242 -307.626516) (xy 424.97346 -307.618473)
			(xy 424.924561 -307.602585) (xy 424.878749 -307.579242) (xy 424.837153 -307.549021) (xy 424.800797 -307.512665)
			(xy 424.770576 -307.471069) (xy 424.747233 -307.425257) (xy 424.731345 -307.376358) (xy 424.723302 -307.325576)
			(xy 417.800282 -307.325576) (xy 417.800282 -307.368702) (xy 417.800822 -307.379062) (xy 417.809075 -307.398073)
			(xy 417.816284 -307.405532) (xy 417.877752 -307.463698) (xy 417.897056 -307.470556) (xy 417.907724 -307.470048)
			(xy 417.924996 -307.46954) (xy 417.95025 -307.470032) (xy 418.000069 -307.478345) (xy 418.047841 -307.494744)
			(xy 418.092261 -307.518783) (xy 418.132119 -307.549805) (xy 418.166328 -307.586965) (xy 418.193953 -307.629248)
			(xy 418.214242 -307.675502) (xy 418.226641 -307.724465) (xy 418.230812 -307.7748) (xy 418.230808 -307.774848)
			(xy 419.519112 -307.774848) (xy 419.523072 -307.725794) (xy 419.534849 -307.67801) (xy 419.55414 -307.632734)
			(xy 419.580443 -307.591138) (xy 419.613078 -307.554301) (xy 419.651199 -307.523176) (xy 419.69382 -307.498569)
			(xy 419.739836 -307.481117) (xy 419.788055 -307.471273) (xy 419.83723 -307.469292) (xy 419.886085 -307.475224)
			(xy 419.933356 -307.488916) (xy 419.977818 -307.510014) (xy 420.018321 -307.53797) (xy 420.053814 -307.572062)
			(xy 420.083379 -307.611406) (xy 420.10625 -307.654983) (xy 420.121834 -307.701664) (xy 420.129729 -307.750241)
			(xy 420.130224 -307.774848) (xy 420.469072 -307.774848) (xy 420.473032 -307.725794) (xy 420.484809 -307.67801)
			(xy 420.5041 -307.632734) (xy 420.530403 -307.591138) (xy 420.563038 -307.554301) (xy 420.601159 -307.523176)
			(xy 420.64378 -307.498569) (xy 420.689796 -307.481117) (xy 420.738015 -307.471273) (xy 420.78719 -307.469292)
			(xy 420.836045 -307.475224) (xy 420.883316 -307.488916) (xy 420.927778 -307.510014) (xy 420.968281 -307.53797)
			(xy 421.003774 -307.572062) (xy 421.033339 -307.611406) (xy 421.05621 -307.654983) (xy 421.071794 -307.701664)
			(xy 421.079689 -307.750241) (xy 421.080184 -307.774848) (xy 421.079689 -307.799455) (xy 421.071794 -307.848032)
			(xy 421.05621 -307.894713) (xy 421.033339 -307.93829) (xy 421.003774 -307.977634) (xy 420.968281 -308.011726)
			(xy 420.927778 -308.039682) (xy 420.883316 -308.06078) (xy 420.836045 -308.074472) (xy 420.78719 -308.080404)
			(xy 420.738015 -308.078423) (xy 420.689796 -308.068579) (xy 420.64378 -308.051127) (xy 420.601159 -308.02652)
			(xy 420.563038 -307.995395) (xy 420.530403 -307.958558) (xy 420.5041 -307.916962) (xy 420.484809 -307.871686)
			(xy 420.473032 -307.823902) (xy 420.469072 -307.774848) (xy 420.130224 -307.774848) (xy 420.129729 -307.799455)
			(xy 420.121834 -307.848032) (xy 420.10625 -307.894713) (xy 420.083379 -307.93829) (xy 420.053814 -307.977634)
			(xy 420.018321 -308.011726) (xy 419.977818 -308.039682) (xy 419.933356 -308.06078) (xy 419.886085 -308.074472)
			(xy 419.83723 -308.080404) (xy 419.788055 -308.078423) (xy 419.739836 -308.068579) (xy 419.69382 -308.051127)
			(xy 419.651199 -308.02652) (xy 419.613078 -307.995395) (xy 419.580443 -307.958558) (xy 419.55414 -307.916962)
			(xy 419.534849 -307.871686) (xy 419.523072 -307.823902) (xy 419.519112 -307.774848) (xy 418.230808 -307.774848)
			(xy 418.226641 -307.825135) (xy 418.214242 -307.874098) (xy 418.193953 -307.920352) (xy 418.166328 -307.962635)
			(xy 418.132119 -307.999795) (xy 418.092261 -308.030817) (xy 418.047841 -308.054856) (xy 418.000069 -308.071255)
			(xy 417.95025 -308.079568) (xy 417.924996 -308.080156) (xy 417.907724 -308.079648) (xy 417.897056 -308.07914)
			(xy 417.877752 -308.085998) (xy 417.816284 -308.144164) (xy 417.809047 -308.151609) (xy 417.800767 -308.170625)
			(xy 417.800282 -308.180994) (xy 417.800282 -308.275536) (xy 422.823382 -308.275536) (xy 422.823382 -308.22412)
			(xy 422.831425 -308.173338) (xy 422.847313 -308.124439) (xy 422.870656 -308.078627) (xy 422.900877 -308.037031)
			(xy 422.937233 -308.000675) (xy 422.978829 -307.970454) (xy 423.024641 -307.947111) (xy 423.07354 -307.931223)
			(xy 423.124322 -307.92318) (xy 423.175738 -307.92318) (xy 423.22652 -307.931223) (xy 423.275419 -307.947111)
			(xy 423.321231 -307.970454) (xy 423.362827 -308.000675) (xy 423.399183 -308.037031) (xy 423.429404 -308.078627)
			(xy 423.452747 -308.124439) (xy 423.468635 -308.173338) (xy 423.476678 -308.22412) (xy 423.477182 -308.249828)
			(xy 423.476678 -308.275536) (xy 423.773342 -308.275536) (xy 423.773342 -308.22412) (xy 423.781385 -308.173338)
			(xy 423.797273 -308.124439) (xy 423.820616 -308.078627) (xy 423.850837 -308.037031) (xy 423.887193 -308.000675)
			(xy 423.928789 -307.970454) (xy 423.974601 -307.947111) (xy 424.0235 -307.931223) (xy 424.074282 -307.92318)
			(xy 424.125698 -307.92318) (xy 424.17648 -307.931223) (xy 424.225379 -307.947111) (xy 424.271191 -307.970454)
			(xy 424.312787 -308.000675) (xy 424.349143 -308.037031) (xy 424.379364 -308.078627) (xy 424.402707 -308.124439)
			(xy 424.418595 -308.173338) (xy 424.426638 -308.22412) (xy 424.427142 -308.249828) (xy 424.426638 -308.275536)
			(xy 429.473356 -308.275536) (xy 429.473356 -308.22412) (xy 429.481399 -308.173338) (xy 429.497287 -308.124439)
			(xy 429.52063 -308.078627) (xy 429.550851 -308.037031) (xy 429.587207 -308.000675) (xy 429.628803 -307.970454)
			(xy 429.674615 -307.947111) (xy 429.723514 -307.931223) (xy 429.774296 -307.92318) (xy 429.825712 -307.92318)
			(xy 429.876494 -307.931223) (xy 429.925393 -307.947111) (xy 429.971205 -307.970454) (xy 430.012801 -308.000675)
			(xy 430.049157 -308.037031) (xy 430.079378 -308.078627) (xy 430.102721 -308.124439) (xy 430.118609 -308.173338)
			(xy 430.126652 -308.22412) (xy 430.127156 -308.249828) (xy 430.126652 -308.275536) (xy 430.423316 -308.275536)
			(xy 430.423316 -308.22412) (xy 430.431359 -308.173338) (xy 430.447247 -308.124439) (xy 430.47059 -308.078627)
			(xy 430.500811 -308.037031) (xy 430.537167 -308.000675) (xy 430.578763 -307.970454) (xy 430.624575 -307.947111)
			(xy 430.673474 -307.931223) (xy 430.724256 -307.92318) (xy 430.775672 -307.92318) (xy 430.826454 -307.931223)
			(xy 430.875353 -307.947111) (xy 430.921165 -307.970454) (xy 430.962761 -308.000675) (xy 430.999117 -308.037031)
			(xy 431.029338 -308.078627) (xy 431.052681 -308.124439) (xy 431.068569 -308.173338) (xy 431.076612 -308.22412)
			(xy 431.077116 -308.249828) (xy 431.076612 -308.275536) (xy 431.068569 -308.326318) (xy 431.052681 -308.375217)
			(xy 431.029338 -308.421029) (xy 430.999117 -308.462625) (xy 430.962761 -308.498981) (xy 430.921165 -308.529202)
			(xy 430.875353 -308.552545) (xy 430.826454 -308.568433) (xy 430.775672 -308.576476) (xy 430.724256 -308.576476)
			(xy 430.673474 -308.568433) (xy 430.624575 -308.552545) (xy 430.578763 -308.529202) (xy 430.537167 -308.498981)
			(xy 430.500811 -308.462625) (xy 430.47059 -308.421029) (xy 430.447247 -308.375217) (xy 430.431359 -308.326318)
			(xy 430.423316 -308.275536) (xy 430.126652 -308.275536) (xy 430.118609 -308.326318) (xy 430.102721 -308.375217)
			(xy 430.079378 -308.421029) (xy 430.049157 -308.462625) (xy 430.012801 -308.498981) (xy 429.971205 -308.529202)
			(xy 429.925393 -308.552545) (xy 429.876494 -308.568433) (xy 429.825712 -308.576476) (xy 429.774296 -308.576476)
			(xy 429.723514 -308.568433) (xy 429.674615 -308.552545) (xy 429.628803 -308.529202) (xy 429.587207 -308.498981)
			(xy 429.550851 -308.462625) (xy 429.52063 -308.421029) (xy 429.497287 -308.375217) (xy 429.481399 -308.326318)
			(xy 429.473356 -308.275536) (xy 424.426638 -308.275536) (xy 424.418595 -308.326318) (xy 424.402707 -308.375217)
			(xy 424.379364 -308.421029) (xy 424.349143 -308.462625) (xy 424.312787 -308.498981) (xy 424.271191 -308.529202)
			(xy 424.225379 -308.552545) (xy 424.17648 -308.568433) (xy 424.125698 -308.576476) (xy 424.074282 -308.576476)
			(xy 424.0235 -308.568433) (xy 423.974601 -308.552545) (xy 423.928789 -308.529202) (xy 423.887193 -308.498981)
			(xy 423.850837 -308.462625) (xy 423.820616 -308.421029) (xy 423.797273 -308.375217) (xy 423.781385 -308.326318)
			(xy 423.773342 -308.275536) (xy 423.476678 -308.275536) (xy 423.468635 -308.326318) (xy 423.452747 -308.375217)
			(xy 423.429404 -308.421029) (xy 423.399183 -308.462625) (xy 423.362827 -308.498981) (xy 423.321231 -308.529202)
			(xy 423.275419 -308.552545) (xy 423.22652 -308.568433) (xy 423.175738 -308.576476) (xy 423.124322 -308.576476)
			(xy 423.07354 -308.568433) (xy 423.024641 -308.552545) (xy 422.978829 -308.529202) (xy 422.937233 -308.498981)
			(xy 422.900877 -308.462625) (xy 422.870656 -308.421029) (xy 422.847313 -308.375217) (xy 422.831425 -308.326318)
			(xy 422.823382 -308.275536) (xy 417.800282 -308.275536) (xy 417.800282 -308.318662) (xy 417.800833 -308.329017)
			(xy 417.809102 -308.348011) (xy 417.816284 -308.355492) (xy 417.877752 -308.413658) (xy 417.897056 -308.420516)
			(xy 417.907724 -308.420008) (xy 417.924996 -308.4195) (xy 417.950253 -308.419992) (xy 418.000079 -308.428306)
			(xy 418.047857 -308.444708) (xy 418.092283 -308.46875) (xy 418.132146 -308.499776) (xy 418.166359 -308.53694)
			(xy 418.193988 -308.579229) (xy 418.21428 -308.625489) (xy 418.226681 -308.674458) (xy 418.230852 -308.7248)
			(xy 418.230851 -308.724808) (xy 418.569152 -308.724808) (xy 418.573112 -308.675754) (xy 418.584889 -308.62797)
			(xy 418.60418 -308.582694) (xy 418.630483 -308.541098) (xy 418.663118 -308.504261) (xy 418.701239 -308.473136)
			(xy 418.74386 -308.448529) (xy 418.789876 -308.431077) (xy 418.838095 -308.421233) (xy 418.88727 -308.419252)
			(xy 418.936125 -308.425184) (xy 418.983396 -308.438876) (xy 419.027858 -308.459974) (xy 419.068361 -308.48793)
			(xy 419.103854 -308.522022) (xy 419.133419 -308.561366) (xy 419.15629 -308.604943) (xy 419.171874 -308.651624)
			(xy 419.179769 -308.700201) (xy 419.180264 -308.724808) (xy 419.519112 -308.724808) (xy 419.523072 -308.675754)
			(xy 419.534849 -308.62797) (xy 419.55414 -308.582694) (xy 419.580443 -308.541098) (xy 419.613078 -308.504261)
			(xy 419.651199 -308.473136) (xy 419.69382 -308.448529) (xy 419.739836 -308.431077) (xy 419.788055 -308.421233)
			(xy 419.83723 -308.419252) (xy 419.886085 -308.425184) (xy 419.933356 -308.438876) (xy 419.977818 -308.459974)
			(xy 420.018321 -308.48793) (xy 420.053814 -308.522022) (xy 420.083379 -308.561366) (xy 420.10625 -308.604943)
			(xy 420.121834 -308.651624) (xy 420.129729 -308.700201) (xy 420.130224 -308.724808) (xy 420.469072 -308.724808)
			(xy 420.473032 -308.675754) (xy 420.484809 -308.62797) (xy 420.5041 -308.582694) (xy 420.530403 -308.541098)
			(xy 420.563038 -308.504261) (xy 420.601159 -308.473136) (xy 420.64378 -308.448529) (xy 420.689796 -308.431077)
			(xy 420.738015 -308.421233) (xy 420.78719 -308.419252) (xy 420.836045 -308.425184) (xy 420.883316 -308.438876)
			(xy 420.927778 -308.459974) (xy 420.968281 -308.48793) (xy 421.003774 -308.522022) (xy 421.033339 -308.561366)
			(xy 421.05621 -308.604943) (xy 421.071794 -308.651624) (xy 421.079689 -308.700201) (xy 421.080184 -308.724808)
			(xy 421.079689 -308.749415) (xy 421.071794 -308.797992) (xy 421.05621 -308.844673) (xy 421.033339 -308.88825)
			(xy 421.003774 -308.927594) (xy 420.968281 -308.961686) (xy 420.927778 -308.989642) (xy 420.883316 -309.01074)
			(xy 420.836045 -309.024432) (xy 420.78719 -309.030364) (xy 420.738015 -309.028383) (xy 420.689796 -309.018539)
			(xy 420.64378 -309.001087) (xy 420.601159 -308.97648) (xy 420.563038 -308.945355) (xy 420.530403 -308.908518)
			(xy 420.5041 -308.866922) (xy 420.484809 -308.821646) (xy 420.473032 -308.773862) (xy 420.469072 -308.724808)
			(xy 420.130224 -308.724808) (xy 420.129729 -308.749415) (xy 420.121834 -308.797992) (xy 420.10625 -308.844673)
			(xy 420.083379 -308.88825) (xy 420.053814 -308.927594) (xy 420.018321 -308.961686) (xy 419.977818 -308.989642)
			(xy 419.933356 -309.01074) (xy 419.886085 -309.024432) (xy 419.83723 -309.030364) (xy 419.788055 -309.028383)
			(xy 419.739836 -309.018539) (xy 419.69382 -309.001087) (xy 419.651199 -308.97648) (xy 419.613078 -308.945355)
			(xy 419.580443 -308.908518) (xy 419.55414 -308.866922) (xy 419.534849 -308.821646) (xy 419.523072 -308.773862)
			(xy 419.519112 -308.724808) (xy 419.180264 -308.724808) (xy 419.179769 -308.749415) (xy 419.171874 -308.797992)
			(xy 419.15629 -308.844673) (xy 419.133419 -308.88825) (xy 419.103854 -308.927594) (xy 419.068361 -308.961686)
			(xy 419.027858 -308.989642) (xy 418.983396 -309.01074) (xy 418.936125 -309.024432) (xy 418.88727 -309.030364)
			(xy 418.838095 -309.028383) (xy 418.789876 -309.018539) (xy 418.74386 -309.001087) (xy 418.701239 -308.97648)
			(xy 418.663118 -308.945355) (xy 418.630483 -308.908518) (xy 418.60418 -308.866922) (xy 418.584889 -308.821646)
			(xy 418.573112 -308.773862) (xy 418.569152 -308.724808) (xy 418.230851 -308.724808) (xy 418.226681 -308.775142)
			(xy 418.21428 -308.824111) (xy 418.193988 -308.870371) (xy 418.166359 -308.91266) (xy 418.132146 -308.949824)
			(xy 418.092283 -308.98085) (xy 418.047857 -309.004892) (xy 418.000079 -309.021294) (xy 417.950253 -309.029608)
			(xy 417.924996 -309.030116) (xy 417.907724 -309.029608) (xy 417.897056 -309.0291) (xy 417.877752 -309.035958)
			(xy 417.816284 -309.094124) (xy 417.809057 -309.101572) (xy 417.800799 -309.120588) (xy 417.800282 -309.130954)
			(xy 417.800282 -309.225496) (xy 424.723302 -309.225496) (xy 424.723302 -309.17408) (xy 424.731345 -309.123298)
			(xy 424.747233 -309.074399) (xy 424.770576 -309.028587) (xy 424.800797 -308.986991) (xy 424.837153 -308.950635)
			(xy 424.878749 -308.920414) (xy 424.924561 -308.897071) (xy 424.97346 -308.881183) (xy 425.024242 -308.87314)
			(xy 425.075658 -308.87314) (xy 425.12644 -308.881183) (xy 425.175339 -308.897071) (xy 425.221151 -308.920414)
			(xy 425.262747 -308.950635) (xy 425.299103 -308.986991) (xy 425.329324 -309.028587) (xy 425.352667 -309.074399)
			(xy 425.368555 -309.123298) (xy 425.376598 -309.17408) (xy 425.377102 -309.199788) (xy 425.376598 -309.225496)
			(xy 425.673262 -309.225496) (xy 425.673262 -309.17408) (xy 425.681305 -309.123298) (xy 425.697193 -309.074399)
			(xy 425.720536 -309.028587) (xy 425.750757 -308.986991) (xy 425.787113 -308.950635) (xy 425.828709 -308.920414)
			(xy 425.874521 -308.897071) (xy 425.92342 -308.881183) (xy 425.974202 -308.87314) (xy 426.025618 -308.87314)
			(xy 426.0764 -308.881183) (xy 426.125299 -308.897071) (xy 426.171111 -308.920414) (xy 426.212707 -308.950635)
			(xy 426.249063 -308.986991) (xy 426.279284 -309.028587) (xy 426.302627 -309.074399) (xy 426.318515 -309.123298)
			(xy 426.326558 -309.17408) (xy 426.327062 -309.199788) (xy 426.326558 -309.225496) (xy 427.573182 -309.225496)
			(xy 427.573182 -309.17408) (xy 427.581225 -309.123298) (xy 427.597113 -309.074399) (xy 427.620456 -309.028587)
			(xy 427.650677 -308.986991) (xy 427.687033 -308.950635) (xy 427.728629 -308.920414) (xy 427.774441 -308.897071)
			(xy 427.82334 -308.881183) (xy 427.874122 -308.87314) (xy 427.925538 -308.87314) (xy 427.97632 -308.881183)
			(xy 428.025219 -308.897071) (xy 428.071031 -308.920414) (xy 428.112627 -308.950635) (xy 428.148983 -308.986991)
			(xy 428.179204 -309.028587) (xy 428.202547 -309.074399) (xy 428.218435 -309.123298) (xy 428.226478 -309.17408)
			(xy 428.226982 -309.199788) (xy 428.226478 -309.225496) (xy 428.523142 -309.225496) (xy 428.523142 -309.17408)
			(xy 428.531185 -309.123298) (xy 428.547073 -309.074399) (xy 428.570416 -309.028587) (xy 428.600637 -308.986991)
			(xy 428.636993 -308.950635) (xy 428.678589 -308.920414) (xy 428.724401 -308.897071) (xy 428.7733 -308.881183)
			(xy 428.824082 -308.87314) (xy 428.875498 -308.87314) (xy 428.92628 -308.881183) (xy 428.975179 -308.897071)
			(xy 429.020991 -308.920414) (xy 429.062587 -308.950635) (xy 429.098943 -308.986991) (xy 429.129164 -309.028587)
			(xy 429.152507 -309.074399) (xy 429.168395 -309.123298) (xy 429.176438 -309.17408) (xy 429.176474 -309.175912)
			(xy 436.634126 -309.175912) (xy 436.638197 -309.12029) (xy 436.650323 -309.065853) (xy 436.670246 -309.013762)
			(xy 436.697542 -308.965127) (xy 436.731628 -308.920984) (xy 436.771777 -308.882275) (xy 436.817135 -308.849824)
			(xy 436.866735 -308.824323) (xy 436.919519 -308.806316) (xy 436.974362 -308.796186) (xy 437.030096 -308.794149)
			(xy 437.085533 -308.800249) (xy 437.13949 -308.814355) (xy 437.190819 -308.836167) (xy 437.238425 -308.865221)
			(xy 437.281293 -308.900896) (xy 437.31851 -308.942433) (xy 437.349283 -308.988946) (xy 437.372955 -309.039443)
			(xy 437.389023 -309.09285) (xy 437.397143 -309.148026) (xy 437.397652 -309.175912) (xy 437.397143 -309.203798)
			(xy 437.389023 -309.258974) (xy 437.372955 -309.312381) (xy 437.349283 -309.362878) (xy 437.31851 -309.409391)
			(xy 437.281293 -309.450928) (xy 437.238425 -309.486603) (xy 437.190819 -309.515657) (xy 437.13949 -309.537469)
			(xy 437.085533 -309.551575) (xy 437.030096 -309.557675) (xy 436.974362 -309.555638) (xy 436.919519 -309.545508)
			(xy 436.866735 -309.527501) (xy 436.817135 -309.502) (xy 436.771777 -309.469549) (xy 436.731628 -309.43084)
			(xy 436.697542 -309.386697) (xy 436.670246 -309.338062) (xy 436.650323 -309.285971) (xy 436.638197 -309.231534)
			(xy 436.634126 -309.175912) (xy 429.176474 -309.175912) (xy 429.176942 -309.199788) (xy 429.176438 -309.225496)
			(xy 429.168395 -309.276278) (xy 429.152507 -309.325177) (xy 429.129164 -309.370989) (xy 429.098943 -309.412585)
			(xy 429.062587 -309.448941) (xy 429.020991 -309.479162) (xy 428.975179 -309.502505) (xy 428.92628 -309.518393)
			(xy 428.875498 -309.526436) (xy 428.824082 -309.526436) (xy 428.7733 -309.518393) (xy 428.724401 -309.502505)
			(xy 428.678589 -309.479162) (xy 428.636993 -309.448941) (xy 428.600637 -309.412585) (xy 428.570416 -309.370989)
			(xy 428.547073 -309.325177) (xy 428.531185 -309.276278) (xy 428.523142 -309.225496) (xy 428.226478 -309.225496)
			(xy 428.218435 -309.276278) (xy 428.202547 -309.325177) (xy 428.179204 -309.370989) (xy 428.148983 -309.412585)
			(xy 428.112627 -309.448941) (xy 428.071031 -309.479162) (xy 428.025219 -309.502505) (xy 427.97632 -309.518393)
			(xy 427.925538 -309.526436) (xy 427.874122 -309.526436) (xy 427.82334 -309.518393) (xy 427.774441 -309.502505)
			(xy 427.728629 -309.479162) (xy 427.687033 -309.448941) (xy 427.650677 -309.412585) (xy 427.620456 -309.370989)
			(xy 427.597113 -309.325177) (xy 427.581225 -309.276278) (xy 427.573182 -309.225496) (xy 426.326558 -309.225496)
			(xy 426.318515 -309.276278) (xy 426.302627 -309.325177) (xy 426.279284 -309.370989) (xy 426.249063 -309.412585)
			(xy 426.212707 -309.448941) (xy 426.171111 -309.479162) (xy 426.125299 -309.502505) (xy 426.0764 -309.518393)
			(xy 426.025618 -309.526436) (xy 425.974202 -309.526436) (xy 425.92342 -309.518393) (xy 425.874521 -309.502505)
			(xy 425.828709 -309.479162) (xy 425.787113 -309.448941) (xy 425.750757 -309.412585) (xy 425.720536 -309.370989)
			(xy 425.697193 -309.325177) (xy 425.681305 -309.276278) (xy 425.673262 -309.225496) (xy 425.376598 -309.225496)
			(xy 425.368555 -309.276278) (xy 425.352667 -309.325177) (xy 425.329324 -309.370989) (xy 425.299103 -309.412585)
			(xy 425.262747 -309.448941) (xy 425.221151 -309.479162) (xy 425.175339 -309.502505) (xy 425.12644 -309.518393)
			(xy 425.075658 -309.526436) (xy 425.024242 -309.526436) (xy 424.97346 -309.518393) (xy 424.924561 -309.502505)
			(xy 424.878749 -309.479162) (xy 424.837153 -309.448941) (xy 424.800797 -309.412585) (xy 424.770576 -309.370989)
			(xy 424.747233 -309.325177) (xy 424.731345 -309.276278) (xy 424.723302 -309.225496) (xy 417.800282 -309.225496)
			(xy 417.800282 -310.175456) (xy 429.473356 -310.175456) (xy 429.473356 -310.12404) (xy 429.481399 -310.073258)
			(xy 429.497287 -310.024359) (xy 429.52063 -309.978547) (xy 429.550851 -309.936951) (xy 429.587207 -309.900595)
			(xy 429.628803 -309.870374) (xy 429.674615 -309.847031) (xy 429.723514 -309.831143) (xy 429.774296 -309.8231)
			(xy 429.825712 -309.8231) (xy 429.876494 -309.831143) (xy 429.925393 -309.847031) (xy 429.971205 -309.870374)
			(xy 430.012801 -309.900595) (xy 430.049157 -309.936951) (xy 430.079378 -309.978547) (xy 430.102721 -310.024359)
			(xy 430.118609 -310.073258) (xy 430.126652 -310.12404) (xy 430.127156 -310.149748) (xy 430.126652 -310.175456)
			(xy 430.423316 -310.175456) (xy 430.423316 -310.12404) (xy 430.431359 -310.073258) (xy 430.447247 -310.024359)
			(xy 430.47059 -309.978547) (xy 430.500811 -309.936951) (xy 430.537167 -309.900595) (xy 430.578763 -309.870374)
			(xy 430.624575 -309.847031) (xy 430.673474 -309.831143) (xy 430.724256 -309.8231) (xy 430.775672 -309.8231)
			(xy 430.826454 -309.831143) (xy 430.875353 -309.847031) (xy 430.887715 -309.85333) (xy 437.310782 -309.85333)
			(xy 437.314853 -309.797708) (xy 437.326979 -309.743271) (xy 437.346902 -309.69118) (xy 437.374198 -309.642545)
			(xy 437.408284 -309.598402) (xy 437.448433 -309.559693) (xy 437.493791 -309.527242) (xy 437.543391 -309.501741)
			(xy 437.596175 -309.483734) (xy 437.651018 -309.473604) (xy 437.706752 -309.471567) (xy 437.762189 -309.477667)
			(xy 437.816146 -309.491773) (xy 437.867475 -309.513585) (xy 437.915081 -309.542639) (xy 437.957949 -309.578314)
			(xy 437.995166 -309.619851) (xy 438.025939 -309.666364) (xy 438.049611 -309.716861) (xy 438.065679 -309.770268)
			(xy 438.073799 -309.825444) (xy 438.074308 -309.85333) (xy 438.073799 -309.881216) (xy 438.065679 -309.936392)
			(xy 438.049611 -309.989799) (xy 438.025939 -310.040296) (xy 437.995166 -310.086809) (xy 437.957949 -310.128346)
			(xy 437.915081 -310.164021) (xy 437.867475 -310.193075) (xy 437.816146 -310.214887) (xy 437.762189 -310.228993)
			(xy 437.706752 -310.235093) (xy 437.651018 -310.233056) (xy 437.596175 -310.222926) (xy 437.543391 -310.204919)
			(xy 437.493791 -310.179418) (xy 437.448433 -310.146967) (xy 437.408284 -310.108258) (xy 437.374198 -310.064115)
			(xy 437.346902 -310.01548) (xy 437.326979 -309.963389) (xy 437.314853 -309.908952) (xy 437.310782 -309.85333)
			(xy 430.887715 -309.85333) (xy 430.921165 -309.870374) (xy 430.962761 -309.900595) (xy 430.999117 -309.936951)
			(xy 431.029338 -309.978547) (xy 431.052681 -310.024359) (xy 431.068569 -310.073258) (xy 431.076612 -310.12404)
			(xy 431.077116 -310.149748) (xy 431.076612 -310.175456) (xy 431.068569 -310.226238) (xy 431.052681 -310.275137)
			(xy 431.029338 -310.320949) (xy 430.999117 -310.362545) (xy 430.962761 -310.398901) (xy 430.921165 -310.429122)
			(xy 430.875353 -310.452465) (xy 430.826454 -310.468353) (xy 430.775672 -310.476396) (xy 430.724256 -310.476396)
			(xy 430.673474 -310.468353) (xy 430.624575 -310.452465) (xy 430.578763 -310.429122) (xy 430.537167 -310.398901)
			(xy 430.500811 -310.362545) (xy 430.47059 -310.320949) (xy 430.447247 -310.275137) (xy 430.431359 -310.226238)
			(xy 430.423316 -310.175456) (xy 430.126652 -310.175456) (xy 430.118609 -310.226238) (xy 430.102721 -310.275137)
			(xy 430.079378 -310.320949) (xy 430.049157 -310.362545) (xy 430.012801 -310.398901) (xy 429.971205 -310.429122)
			(xy 429.925393 -310.452465) (xy 429.876494 -310.468353) (xy 429.825712 -310.476396) (xy 429.774296 -310.476396)
			(xy 429.723514 -310.468353) (xy 429.674615 -310.452465) (xy 429.628803 -310.429122) (xy 429.587207 -310.398901)
			(xy 429.550851 -310.362545) (xy 429.52063 -310.320949) (xy 429.497287 -310.275137) (xy 429.481399 -310.226238)
			(xy 429.473356 -310.175456) (xy 417.800282 -310.175456) (xy 417.800282 -310.632938) (xy 427.11923 -310.632938)
			(xy 427.121924 -310.583378) (xy 427.1326 -310.534907) (xy 427.150977 -310.488802) (xy 427.176571 -310.446277)
			(xy 427.208708 -310.408453) (xy 427.24654 -310.376326) (xy 427.289072 -310.350743) (xy 427.335182 -310.332377)
			(xy 427.383655 -310.321713) (xy 427.433216 -310.319032) (xy 427.482557 -310.324404) (xy 427.530379 -310.337687)
			(xy 427.575422 -310.358533) (xy 427.6165 -310.38639) (xy 427.65253 -310.420527) (xy 427.682562 -310.460042)
			(xy 427.705806 -310.503896) (xy 427.72165 -310.550932) (xy 427.729675 -310.599912) (xy 427.730158 -310.624728)
			(xy 427.730158 -310.624982) (xy 427.730082 -310.634789) (xy 427.728808 -310.654363) (xy 427.727618 -310.664098)
			(xy 427.726186 -310.677618) (xy 427.727225 -310.68518) (xy 438.142632 -310.68518) (xy 438.146703 -310.629558)
			(xy 438.158829 -310.575121) (xy 438.178752 -310.52303) (xy 438.206048 -310.474395) (xy 438.240134 -310.430252)
			(xy 438.280283 -310.391543) (xy 438.325641 -310.359092) (xy 438.375241 -310.333591) (xy 438.428025 -310.315584)
			(xy 438.482868 -310.305454) (xy 438.538602 -310.303417) (xy 438.594039 -310.309517) (xy 438.647996 -310.323623)
			(xy 438.699325 -310.345435) (xy 438.746931 -310.374489) (xy 438.789799 -310.410164) (xy 438.827016 -310.451701)
			(xy 438.857789 -310.498214) (xy 438.881461 -310.548711) (xy 438.897529 -310.602118) (xy 438.905649 -310.657294)
			(xy 438.906158 -310.68518) (xy 438.905649 -310.713066) (xy 438.897529 -310.768242) (xy 438.881461 -310.821649)
			(xy 438.857789 -310.872146) (xy 438.827016 -310.918659) (xy 438.789799 -310.960196) (xy 438.746931 -310.995871)
			(xy 438.699325 -311.024925) (xy 438.647996 -311.046737) (xy 438.594039 -311.060843) (xy 438.538602 -311.066943)
			(xy 438.482868 -311.064906) (xy 438.428025 -311.054776) (xy 438.375241 -311.036769) (xy 438.325641 -311.011268)
			(xy 438.280283 -310.978817) (xy 438.240134 -310.940108) (xy 438.206048 -310.895965) (xy 438.178752 -310.84733)
			(xy 438.158829 -310.795239) (xy 438.146703 -310.740802) (xy 438.142632 -310.68518) (xy 427.727225 -310.68518)
			(xy 427.729885 -310.704549) (xy 427.740551 -310.729552) (xy 427.75743 -310.75086) (xy 427.779329 -310.766965)
			(xy 427.804699 -310.776728) (xy 427.831744 -310.779459) (xy 427.84522 -310.777636) (xy 427.858707 -310.775496)
			(xy 427.885921 -310.773203) (xy 427.899576 -310.773064) (xy 427.89983 -310.773064) (xy 427.925518 -310.773612)
			(xy 427.976259 -310.781654) (xy 428.025119 -310.797534) (xy 428.070892 -310.820862) (xy 428.112453 -310.851064)
			(xy 428.148777 -310.887395) (xy 428.178971 -310.928961) (xy 428.20229 -310.974739) (xy 428.218161 -311.023602)
			(xy 428.226193 -311.074345) (xy 428.226188 -311.12572) (xy 428.218146 -311.176462) (xy 428.202265 -311.225321)
			(xy 428.178936 -311.271094) (xy 428.148735 -311.312655) (xy 428.112403 -311.348979) (xy 428.070836 -311.379172)
			(xy 428.025058 -311.402491) (xy 427.976196 -311.418362) (xy 427.925452 -311.426393) (xy 427.874077 -311.426387)
			(xy 427.823335 -311.418345) (xy 427.774476 -311.402464) (xy 427.728703 -311.379135) (xy 427.687143 -311.348933)
			(xy 427.65082 -311.312601) (xy 427.620627 -311.271034) (xy 427.597308 -311.225256) (xy 427.581438 -311.176393)
			(xy 427.573407 -311.12565) (xy 427.572932 -311.099962) (xy 427.572932 -311.099708) (xy 427.573084 -311.086053)
			(xy 427.575374 -311.05884) (xy 427.577504 -311.045352) (xy 427.579384 -311.031877) (xy 427.576757 -311.004807)
			(xy 427.567068 -310.979395) (xy 427.551005 -310.957449) (xy 427.529711 -310.94053) (xy 427.504703 -310.929842)
			(xy 427.477758 -310.926147) (xy 427.46422 -310.927496) (xy 427.454484 -310.928679) (xy 427.434911 -310.929949)
			(xy 427.425104 -310.930036) (xy 427.42485 -310.930036) (xy 427.400034 -310.929468) (xy 427.351056 -310.921431)
			(xy 427.304024 -310.905575) (xy 427.260176 -310.88232) (xy 427.220668 -310.852277) (xy 427.186541 -310.816239)
			(xy 427.158694 -310.775154) (xy 427.137861 -310.730106) (xy 427.124589 -310.68228) (xy 427.11923 -310.632938)
			(xy 417.800282 -310.632938) (xy 417.800282 -311.12567) (xy 418.073328 -311.12567) (xy 418.073328 -311.074254)
			(xy 418.081371 -311.023472) (xy 418.097259 -310.974573) (xy 418.120602 -310.928761) (xy 418.150823 -310.887165)
			(xy 418.187179 -310.850809) (xy 418.228775 -310.820588) (xy 418.274587 -310.797245) (xy 418.323486 -310.781357)
			(xy 418.374268 -310.773314) (xy 418.425684 -310.773314) (xy 418.476466 -310.781357) (xy 418.525365 -310.797245)
			(xy 418.571177 -310.820588) (xy 418.612773 -310.850809) (xy 418.649129 -310.887165) (xy 418.67935 -310.928761)
			(xy 418.702693 -310.974573) (xy 418.718581 -311.023472) (xy 418.726624 -311.074254) (xy 418.727128 -311.099962)
			(xy 418.726624 -311.12567) (xy 419.973248 -311.12567) (xy 419.973248 -311.074254) (xy 419.981291 -311.023472)
			(xy 419.997179 -310.974573) (xy 420.020522 -310.928761) (xy 420.050743 -310.887165) (xy 420.087099 -310.850809)
			(xy 420.128695 -310.820588) (xy 420.174507 -310.797245) (xy 420.223406 -310.781357) (xy 420.274188 -310.773314)
			(xy 420.325604 -310.773314) (xy 420.376386 -310.781357) (xy 420.425285 -310.797245) (xy 420.471097 -310.820588)
			(xy 420.512693 -310.850809) (xy 420.549049 -310.887165) (xy 420.57927 -310.928761) (xy 420.602613 -310.974573)
			(xy 420.618501 -311.023472) (xy 420.626544 -311.074254) (xy 420.627048 -311.099962) (xy 420.626544 -311.12567)
			(xy 421.873168 -311.12567) (xy 421.873168 -311.074254) (xy 421.881211 -311.023472) (xy 421.897099 -310.974573)
			(xy 421.920442 -310.928761) (xy 421.950663 -310.887165) (xy 421.987019 -310.850809) (xy 422.028615 -310.820588)
			(xy 422.074427 -310.797245) (xy 422.123326 -310.781357) (xy 422.174108 -310.773314) (xy 422.225524 -310.773314)
			(xy 422.276306 -310.781357) (xy 422.325205 -310.797245) (xy 422.371017 -310.820588) (xy 422.412613 -310.850809)
			(xy 422.448969 -310.887165) (xy 422.47919 -310.928761) (xy 422.502533 -310.974573) (xy 422.518421 -311.023472)
			(xy 422.526464 -311.074254) (xy 422.526968 -311.099962) (xy 422.526464 -311.12567) (xy 423.773342 -311.12567)
			(xy 423.773342 -311.074254) (xy 423.781385 -311.023472) (xy 423.797273 -310.974573) (xy 423.820616 -310.928761)
			(xy 423.850837 -310.887165) (xy 423.887193 -310.850809) (xy 423.928789 -310.820588) (xy 423.974601 -310.797245)
			(xy 424.0235 -310.781357) (xy 424.074282 -310.773314) (xy 424.125698 -310.773314) (xy 424.17648 -310.781357)
			(xy 424.225379 -310.797245) (xy 424.271191 -310.820588) (xy 424.312787 -310.850809) (xy 424.349143 -310.887165)
			(xy 424.379364 -310.928761) (xy 424.402707 -310.974573) (xy 424.418595 -311.023472) (xy 424.426638 -311.074254)
			(xy 424.427142 -311.099962) (xy 424.426638 -311.12567) (xy 425.673262 -311.12567) (xy 425.673262 -311.074254)
			(xy 425.681305 -311.023472) (xy 425.697193 -310.974573) (xy 425.720536 -310.928761) (xy 425.750757 -310.887165)
			(xy 425.787113 -310.850809) (xy 425.828709 -310.820588) (xy 425.874521 -310.797245) (xy 425.92342 -310.781357)
			(xy 425.974202 -310.773314) (xy 426.025618 -310.773314) (xy 426.0764 -310.781357) (xy 426.125299 -310.797245)
			(xy 426.171111 -310.820588) (xy 426.212707 -310.850809) (xy 426.249063 -310.887165) (xy 426.279284 -310.928761)
			(xy 426.302627 -310.974573) (xy 426.318515 -311.023472) (xy 426.326558 -311.074254) (xy 426.327062 -311.099962)
			(xy 426.326558 -311.12567) (xy 426.318515 -311.176452) (xy 426.302627 -311.225351) (xy 426.279284 -311.271163)
			(xy 426.249063 -311.312759) (xy 426.212707 -311.349115) (xy 426.171111 -311.379336) (xy 426.125299 -311.402679)
			(xy 426.0764 -311.418567) (xy 426.025618 -311.42661) (xy 425.974202 -311.42661) (xy 425.92342 -311.418567)
			(xy 425.874521 -311.402679) (xy 425.828709 -311.379336) (xy 425.787113 -311.349115) (xy 425.750757 -311.312759)
			(xy 425.720536 -311.271163) (xy 425.697193 -311.225351) (xy 425.681305 -311.176452) (xy 425.673262 -311.12567)
			(xy 424.426638 -311.12567) (xy 424.418595 -311.176452) (xy 424.402707 -311.225351) (xy 424.379364 -311.271163)
			(xy 424.349143 -311.312759) (xy 424.312787 -311.349115) (xy 424.271191 -311.379336) (xy 424.225379 -311.402679)
			(xy 424.17648 -311.418567) (xy 424.125698 -311.42661) (xy 424.074282 -311.42661) (xy 424.0235 -311.418567)
			(xy 423.974601 -311.402679) (xy 423.928789 -311.379336) (xy 423.887193 -311.349115) (xy 423.850837 -311.312759)
			(xy 423.820616 -311.271163) (xy 423.797273 -311.225351) (xy 423.781385 -311.176452) (xy 423.773342 -311.12567)
			(xy 422.526464 -311.12567) (xy 422.518421 -311.176452) (xy 422.502533 -311.225351) (xy 422.47919 -311.271163)
			(xy 422.448969 -311.312759) (xy 422.412613 -311.349115) (xy 422.371017 -311.379336) (xy 422.325205 -311.402679)
			(xy 422.276306 -311.418567) (xy 422.225524 -311.42661) (xy 422.174108 -311.42661) (xy 422.123326 -311.418567)
			(xy 422.074427 -311.402679) (xy 422.028615 -311.379336) (xy 421.987019 -311.349115) (xy 421.950663 -311.312759)
			(xy 421.920442 -311.271163) (xy 421.897099 -311.225351) (xy 421.881211 -311.176452) (xy 421.873168 -311.12567)
			(xy 420.626544 -311.12567) (xy 420.618501 -311.176452) (xy 420.602613 -311.225351) (xy 420.57927 -311.271163)
			(xy 420.549049 -311.312759) (xy 420.512693 -311.349115) (xy 420.471097 -311.379336) (xy 420.425285 -311.402679)
			(xy 420.376386 -311.418567) (xy 420.325604 -311.42661) (xy 420.274188 -311.42661) (xy 420.223406 -311.418567)
			(xy 420.174507 -311.402679) (xy 420.128695 -311.379336) (xy 420.087099 -311.349115) (xy 420.050743 -311.312759)
			(xy 420.020522 -311.271163) (xy 419.997179 -311.225351) (xy 419.981291 -311.176452) (xy 419.973248 -311.12567)
			(xy 418.726624 -311.12567) (xy 418.718581 -311.176452) (xy 418.702693 -311.225351) (xy 418.67935 -311.271163)
			(xy 418.649129 -311.312759) (xy 418.612773 -311.349115) (xy 418.571177 -311.379336) (xy 418.525365 -311.402679)
			(xy 418.476466 -311.418567) (xy 418.425684 -311.42661) (xy 418.374268 -311.42661) (xy 418.323486 -311.418567)
			(xy 418.274587 -311.402679) (xy 418.228775 -311.379336) (xy 418.187179 -311.349115) (xy 418.150823 -311.312759)
			(xy 418.120602 -311.271163) (xy 418.097259 -311.225351) (xy 418.081371 -311.176452) (xy 418.073328 -311.12567)
			(xy 417.800282 -311.12567) (xy 417.800282 -311.435354) (xy 438.86679 -311.435354) (xy 438.86679 -311.380854)
			(xy 438.874545 -311.32691) (xy 438.889898 -311.274618) (xy 438.912537 -311.225043) (xy 438.942001 -311.179195)
			(xy 438.977689 -311.138006) (xy 439.018875 -311.102315) (xy 439.064722 -311.072849) (xy 439.114295 -311.050207)
			(xy 439.166586 -311.03485) (xy 439.22053 -311.027092) (xy 439.27503 -311.027089) (xy 439.328975 -311.034842)
			(xy 439.381267 -311.050193) (xy 439.430843 -311.07283) (xy 439.476693 -311.102291) (xy 439.517883 -311.137977)
			(xy 439.553575 -311.179163) (xy 439.583044 -311.225008) (xy 439.605688 -311.27458) (xy 439.621046 -311.326871)
			(xy 439.628807 -311.380814) (xy 439.629296 -311.408064) (xy 439.6291 -311.425112) (xy 439.626045 -311.459072)
			(xy 439.6232 -311.475882) (xy 439.621161 -311.489766) (xy 439.623883 -311.517684) (xy 439.634091 -311.543811)
			(xy 439.651016 -311.56618) (xy 439.673383 -311.583106) (xy 439.69951 -311.593316) (xy 439.727428 -311.596039)
			(xy 439.74131 -311.593992) (xy 439.758118 -311.591129) (xy 439.792079 -311.588077) (xy 439.809128 -311.587896)
			(xy 439.809382 -311.587896) (xy 439.836636 -311.588336) (xy 439.890591 -311.596091) (xy 439.942892 -311.611445)
			(xy 439.992476 -311.634087) (xy 440.038333 -311.663554) (xy 440.07953 -311.699248) (xy 440.115227 -311.740442)
			(xy 440.144698 -311.786296) (xy 440.167344 -311.835878) (xy 440.182703 -311.888179) (xy 440.190462 -311.942132)
			(xy 440.190464 -311.996641) (xy 440.182708 -312.050595) (xy 440.167353 -312.102897) (xy 440.144711 -312.15248)
			(xy 440.115243 -312.198337) (xy 440.079548 -312.239533) (xy 440.038354 -312.27523) (xy 439.9925 -312.304701)
			(xy 439.942917 -312.327346) (xy 439.890617 -312.342704) (xy 439.836663 -312.350462) (xy 439.782154 -312.350464)
			(xy 439.7282 -312.342707) (xy 439.675899 -312.327352) (xy 439.626316 -312.304709) (xy 439.580459 -312.27524)
			(xy 439.539264 -312.239545) (xy 439.503568 -312.198351) (xy 439.474097 -312.152495) (xy 439.451453 -312.102913)
			(xy 439.436095 -312.050612) (xy 439.428337 -311.996658) (xy 439.427874 -311.969404) (xy 439.428079 -311.952356)
			(xy 439.431128 -311.918397) (xy 439.43397 -311.901586) (xy 439.436077 -311.88771) (xy 439.433347 -311.859783)
			(xy 439.423129 -311.833649) (xy 439.406193 -311.811276) (xy 439.383813 -311.794349) (xy 439.357675 -311.784143)
			(xy 439.329746 -311.781425) (xy 439.31586 -311.783476) (xy 439.299053 -311.786343) (xy 439.265091 -311.789392)
			(xy 439.248042 -311.789572) (xy 439.247788 -311.789572) (xy 439.220538 -311.789109) (xy 439.166594 -311.781351)
			(xy 439.114303 -311.765996) (xy 439.064729 -311.743355) (xy 439.018882 -311.71389) (xy 438.977694 -311.6782)
			(xy 438.942005 -311.637012) (xy 438.912541 -311.591164) (xy 438.889901 -311.54159) (xy 438.874547 -311.489298)
			(xy 438.86679 -311.435354) (xy 417.800282 -311.435354) (xy 417.800282 -312.07563) (xy 418.073328 -312.07563)
			(xy 418.073328 -312.024214) (xy 418.081371 -311.973432) (xy 418.097259 -311.924533) (xy 418.120602 -311.878721)
			(xy 418.150823 -311.837125) (xy 418.187179 -311.800769) (xy 418.228775 -311.770548) (xy 418.274587 -311.747205)
			(xy 418.323486 -311.731317) (xy 418.374268 -311.723274) (xy 418.425684 -311.723274) (xy 418.476466 -311.731317)
			(xy 418.525365 -311.747205) (xy 418.571177 -311.770548) (xy 418.612773 -311.800769) (xy 418.649129 -311.837125)
			(xy 418.67935 -311.878721) (xy 418.702693 -311.924533) (xy 418.718581 -311.973432) (xy 418.726624 -312.024214)
			(xy 418.727128 -312.049922) (xy 418.726624 -312.07563) (xy 419.973248 -312.07563) (xy 419.973248 -312.024214)
			(xy 419.981291 -311.973432) (xy 419.997179 -311.924533) (xy 420.020522 -311.878721) (xy 420.050743 -311.837125)
			(xy 420.087099 -311.800769) (xy 420.128695 -311.770548) (xy 420.174507 -311.747205) (xy 420.223406 -311.731317)
			(xy 420.274188 -311.723274) (xy 420.325604 -311.723274) (xy 420.376386 -311.731317) (xy 420.425285 -311.747205)
			(xy 420.471097 -311.770548) (xy 420.512693 -311.800769) (xy 420.549049 -311.837125) (xy 420.57927 -311.878721)
			(xy 420.602613 -311.924533) (xy 420.618501 -311.973432) (xy 420.626544 -312.024214) (xy 420.627048 -312.049922)
			(xy 420.626544 -312.07563) (xy 421.873168 -312.07563) (xy 421.873168 -312.024214) (xy 421.881211 -311.973432)
			(xy 421.897099 -311.924533) (xy 421.920442 -311.878721) (xy 421.950663 -311.837125) (xy 421.987019 -311.800769)
			(xy 422.028615 -311.770548) (xy 422.074427 -311.747205) (xy 422.123326 -311.731317) (xy 422.174108 -311.723274)
			(xy 422.225524 -311.723274) (xy 422.276306 -311.731317) (xy 422.325205 -311.747205) (xy 422.371017 -311.770548)
			(xy 422.412613 -311.800769) (xy 422.448969 -311.837125) (xy 422.47919 -311.878721) (xy 422.502533 -311.924533)
			(xy 422.518421 -311.973432) (xy 422.526464 -312.024214) (xy 422.526968 -312.049922) (xy 422.526464 -312.07563)
			(xy 423.773342 -312.07563) (xy 423.773342 -312.024214) (xy 423.781385 -311.973432) (xy 423.797273 -311.924533)
			(xy 423.820616 -311.878721) (xy 423.850837 -311.837125) (xy 423.887193 -311.800769) (xy 423.928789 -311.770548)
			(xy 423.974601 -311.747205) (xy 424.0235 -311.731317) (xy 424.074282 -311.723274) (xy 424.125698 -311.723274)
			(xy 424.17648 -311.731317) (xy 424.225379 -311.747205) (xy 424.271191 -311.770548) (xy 424.312787 -311.800769)
			(xy 424.349143 -311.837125) (xy 424.379364 -311.878721) (xy 424.402707 -311.924533) (xy 424.418595 -311.973432)
			(xy 424.426638 -312.024214) (xy 424.427142 -312.049922) (xy 424.426638 -312.07563) (xy 425.673262 -312.07563)
			(xy 425.673262 -312.024214) (xy 425.681305 -311.973432) (xy 425.697193 -311.924533) (xy 425.720536 -311.878721)
			(xy 425.750757 -311.837125) (xy 425.787113 -311.800769) (xy 425.828709 -311.770548) (xy 425.874521 -311.747205)
			(xy 425.92342 -311.731317) (xy 425.974202 -311.723274) (xy 426.025618 -311.723274) (xy 426.0764 -311.731317)
			(xy 426.125299 -311.747205) (xy 426.171111 -311.770548) (xy 426.212707 -311.800769) (xy 426.249063 -311.837125)
			(xy 426.279284 -311.878721) (xy 426.302627 -311.924533) (xy 426.318515 -311.973432) (xy 426.326558 -312.024214)
			(xy 426.327062 -312.049922) (xy 426.326558 -312.07563) (xy 427.573182 -312.07563) (xy 427.573182 -312.024214)
			(xy 427.581225 -311.973432) (xy 427.597113 -311.924533) (xy 427.620456 -311.878721) (xy 427.650677 -311.837125)
			(xy 427.687033 -311.800769) (xy 427.728629 -311.770548) (xy 427.774441 -311.747205) (xy 427.82334 -311.731317)
			(xy 427.874122 -311.723274) (xy 427.925538 -311.723274) (xy 427.97632 -311.731317) (xy 428.025219 -311.747205)
			(xy 428.071031 -311.770548) (xy 428.112627 -311.800769) (xy 428.148983 -311.837125) (xy 428.179204 -311.878721)
			(xy 428.202547 -311.924533) (xy 428.218435 -311.973432) (xy 428.226478 -312.024214) (xy 428.226982 -312.049922)
			(xy 428.226478 -312.07563) (xy 429.473356 -312.07563) (xy 429.473356 -312.024214) (xy 429.481399 -311.973432)
			(xy 429.497287 -311.924533) (xy 429.52063 -311.878721) (xy 429.550851 -311.837125) (xy 429.587207 -311.800769)
			(xy 429.628803 -311.770548) (xy 429.674615 -311.747205) (xy 429.723514 -311.731317) (xy 429.774296 -311.723274)
			(xy 429.825712 -311.723274) (xy 429.876494 -311.731317) (xy 429.925393 -311.747205) (xy 429.971205 -311.770548)
			(xy 430.012801 -311.800769) (xy 430.049157 -311.837125) (xy 430.079378 -311.878721) (xy 430.102721 -311.924533)
			(xy 430.118609 -311.973432) (xy 430.126652 -312.024214) (xy 430.127156 -312.049922) (xy 430.126652 -312.07563)
			(xy 430.423316 -312.07563) (xy 430.423316 -312.024214) (xy 430.431359 -311.973432) (xy 430.447247 -311.924533)
			(xy 430.47059 -311.878721) (xy 430.500811 -311.837125) (xy 430.537167 -311.800769) (xy 430.578763 -311.770548)
			(xy 430.624575 -311.747205) (xy 430.673474 -311.731317) (xy 430.724256 -311.723274) (xy 430.775672 -311.723274)
			(xy 430.826454 -311.731317) (xy 430.875353 -311.747205) (xy 430.921165 -311.770548) (xy 430.962761 -311.800769)
			(xy 430.999117 -311.837125) (xy 431.029338 -311.878721) (xy 431.052681 -311.924533) (xy 431.068569 -311.973432)
			(xy 431.076612 -312.024214) (xy 431.077116 -312.049922) (xy 431.076612 -312.07563) (xy 431.068569 -312.126412)
			(xy 431.052681 -312.175311) (xy 431.029338 -312.221123) (xy 430.999117 -312.262719) (xy 430.962761 -312.299075)
			(xy 430.921165 -312.329296) (xy 430.875353 -312.352639) (xy 430.826454 -312.368527) (xy 430.775672 -312.37657)
			(xy 430.724256 -312.37657) (xy 430.673474 -312.368527) (xy 430.624575 -312.352639) (xy 430.578763 -312.329296)
			(xy 430.537167 -312.299075) (xy 430.500811 -312.262719) (xy 430.47059 -312.221123) (xy 430.447247 -312.175311)
			(xy 430.431359 -312.126412) (xy 430.423316 -312.07563) (xy 430.126652 -312.07563) (xy 430.118609 -312.126412)
			(xy 430.102721 -312.175311) (xy 430.079378 -312.221123) (xy 430.049157 -312.262719) (xy 430.012801 -312.299075)
			(xy 429.971205 -312.329296) (xy 429.925393 -312.352639) (xy 429.876494 -312.368527) (xy 429.825712 -312.37657)
			(xy 429.774296 -312.37657) (xy 429.723514 -312.368527) (xy 429.674615 -312.352639) (xy 429.628803 -312.329296)
			(xy 429.587207 -312.299075) (xy 429.550851 -312.262719) (xy 429.52063 -312.221123) (xy 429.497287 -312.175311)
			(xy 429.481399 -312.126412) (xy 429.473356 -312.07563) (xy 428.226478 -312.07563) (xy 428.218435 -312.126412)
			(xy 428.202547 -312.175311) (xy 428.179204 -312.221123) (xy 428.148983 -312.262719) (xy 428.112627 -312.299075)
			(xy 428.071031 -312.329296) (xy 428.025219 -312.352639) (xy 427.97632 -312.368527) (xy 427.925538 -312.37657)
			(xy 427.874122 -312.37657) (xy 427.82334 -312.368527) (xy 427.774441 -312.352639) (xy 427.728629 -312.329296)
			(xy 427.687033 -312.299075) (xy 427.650677 -312.262719) (xy 427.620456 -312.221123) (xy 427.597113 -312.175311)
			(xy 427.581225 -312.126412) (xy 427.573182 -312.07563) (xy 426.326558 -312.07563) (xy 426.318515 -312.126412)
			(xy 426.302627 -312.175311) (xy 426.279284 -312.221123) (xy 426.249063 -312.262719) (xy 426.212707 -312.299075)
			(xy 426.171111 -312.329296) (xy 426.125299 -312.352639) (xy 426.0764 -312.368527) (xy 426.025618 -312.37657)
			(xy 425.974202 -312.37657) (xy 425.92342 -312.368527) (xy 425.874521 -312.352639) (xy 425.828709 -312.329296)
			(xy 425.787113 -312.299075) (xy 425.750757 -312.262719) (xy 425.720536 -312.221123) (xy 425.697193 -312.175311)
			(xy 425.681305 -312.126412) (xy 425.673262 -312.07563) (xy 424.426638 -312.07563) (xy 424.418595 -312.126412)
			(xy 424.402707 -312.175311) (xy 424.379364 -312.221123) (xy 424.349143 -312.262719) (xy 424.312787 -312.299075)
			(xy 424.271191 -312.329296) (xy 424.225379 -312.352639) (xy 424.17648 -312.368527) (xy 424.125698 -312.37657)
			(xy 424.074282 -312.37657) (xy 424.0235 -312.368527) (xy 423.974601 -312.352639) (xy 423.928789 -312.329296)
			(xy 423.887193 -312.299075) (xy 423.850837 -312.262719) (xy 423.820616 -312.221123) (xy 423.797273 -312.175311)
			(xy 423.781385 -312.126412) (xy 423.773342 -312.07563) (xy 422.526464 -312.07563) (xy 422.518421 -312.126412)
			(xy 422.502533 -312.175311) (xy 422.47919 -312.221123) (xy 422.448969 -312.262719) (xy 422.412613 -312.299075)
			(xy 422.371017 -312.329296) (xy 422.325205 -312.352639) (xy 422.276306 -312.368527) (xy 422.225524 -312.37657)
			(xy 422.174108 -312.37657) (xy 422.123326 -312.368527) (xy 422.074427 -312.352639) (xy 422.028615 -312.329296)
			(xy 421.987019 -312.299075) (xy 421.950663 -312.262719) (xy 421.920442 -312.221123) (xy 421.897099 -312.175311)
			(xy 421.881211 -312.126412) (xy 421.873168 -312.07563) (xy 420.626544 -312.07563) (xy 420.618501 -312.126412)
			(xy 420.602613 -312.175311) (xy 420.57927 -312.221123) (xy 420.549049 -312.262719) (xy 420.512693 -312.299075)
			(xy 420.471097 -312.329296) (xy 420.425285 -312.352639) (xy 420.376386 -312.368527) (xy 420.325604 -312.37657)
			(xy 420.274188 -312.37657) (xy 420.223406 -312.368527) (xy 420.174507 -312.352639) (xy 420.128695 -312.329296)
			(xy 420.087099 -312.299075) (xy 420.050743 -312.262719) (xy 420.020522 -312.221123) (xy 419.997179 -312.175311)
			(xy 419.981291 -312.126412) (xy 419.973248 -312.07563) (xy 418.726624 -312.07563) (xy 418.718581 -312.126412)
			(xy 418.702693 -312.175311) (xy 418.67935 -312.221123) (xy 418.649129 -312.262719) (xy 418.612773 -312.299075)
			(xy 418.571177 -312.329296) (xy 418.525365 -312.352639) (xy 418.476466 -312.368527) (xy 418.425684 -312.37657)
			(xy 418.374268 -312.37657) (xy 418.323486 -312.368527) (xy 418.274587 -312.352639) (xy 418.228775 -312.329296)
			(xy 418.187179 -312.299075) (xy 418.150823 -312.262719) (xy 418.120602 -312.221123) (xy 418.097259 -312.175311)
			(xy 418.081371 -312.126412) (xy 418.073328 -312.07563) (xy 417.800282 -312.07563) (xy 417.800282 -313.02559)
			(xy 419.023288 -313.02559) (xy 419.023288 -312.974174) (xy 419.031331 -312.923392) (xy 419.047219 -312.874493)
			(xy 419.070562 -312.828681) (xy 419.100783 -312.787085) (xy 419.137139 -312.750729) (xy 419.178735 -312.720508)
			(xy 419.224547 -312.697165) (xy 419.273446 -312.681277) (xy 419.324228 -312.673234) (xy 419.375644 -312.673234)
			(xy 419.426426 -312.681277) (xy 419.475325 -312.697165) (xy 419.521137 -312.720508) (xy 419.562733 -312.750729)
			(xy 419.599089 -312.787085) (xy 419.62931 -312.828681) (xy 419.652653 -312.874493) (xy 419.668541 -312.923392)
			(xy 419.676584 -312.974174) (xy 419.677088 -312.999882) (xy 419.676584 -313.02559) (xy 420.923208 -313.02559)
			(xy 420.923208 -312.974174) (xy 420.931251 -312.923392) (xy 420.947139 -312.874493) (xy 420.970482 -312.828681)
			(xy 421.000703 -312.787085) (xy 421.037059 -312.750729) (xy 421.078655 -312.720508) (xy 421.124467 -312.697165)
			(xy 421.173366 -312.681277) (xy 421.224148 -312.673234) (xy 421.275564 -312.673234) (xy 421.326346 -312.681277)
			(xy 421.375245 -312.697165) (xy 421.421057 -312.720508) (xy 421.462653 -312.750729) (xy 421.499009 -312.787085)
			(xy 421.52923 -312.828681) (xy 421.552573 -312.874493) (xy 421.568461 -312.923392) (xy 421.576504 -312.974174)
			(xy 421.577008 -312.999882) (xy 421.576504 -313.02559) (xy 422.823382 -313.02559) (xy 422.823382 -312.974174)
			(xy 422.831425 -312.923392) (xy 422.847313 -312.874493) (xy 422.870656 -312.828681) (xy 422.900877 -312.787085)
			(xy 422.937233 -312.750729) (xy 422.978829 -312.720508) (xy 423.024641 -312.697165) (xy 423.07354 -312.681277)
			(xy 423.124322 -312.673234) (xy 423.175738 -312.673234) (xy 423.22652 -312.681277) (xy 423.275419 -312.697165)
			(xy 423.321231 -312.720508) (xy 423.362827 -312.750729) (xy 423.399183 -312.787085) (xy 423.429404 -312.828681)
			(xy 423.452747 -312.874493) (xy 423.468635 -312.923392) (xy 423.476678 -312.974174) (xy 423.477182 -312.999882)
			(xy 423.476678 -313.02559) (xy 424.723302 -313.02559) (xy 424.723302 -312.974174) (xy 424.731345 -312.923392)
			(xy 424.747233 -312.874493) (xy 424.770576 -312.828681) (xy 424.800797 -312.787085) (xy 424.837153 -312.750729)
			(xy 424.878749 -312.720508) (xy 424.924561 -312.697165) (xy 424.97346 -312.681277) (xy 425.024242 -312.673234)
			(xy 425.075658 -312.673234) (xy 425.12644 -312.681277) (xy 425.175339 -312.697165) (xy 425.221151 -312.720508)
			(xy 425.262747 -312.750729) (xy 425.299103 -312.787085) (xy 425.329324 -312.828681) (xy 425.352667 -312.874493)
			(xy 425.368555 -312.923392) (xy 425.376598 -312.974174) (xy 425.377102 -312.999882) (xy 425.376598 -313.02559)
			(xy 426.623222 -313.02559) (xy 426.623222 -312.974174) (xy 426.631265 -312.923392) (xy 426.647153 -312.874493)
			(xy 426.670496 -312.828681) (xy 426.700717 -312.787085) (xy 426.737073 -312.750729) (xy 426.778669 -312.720508)
			(xy 426.824481 -312.697165) (xy 426.87338 -312.681277) (xy 426.924162 -312.673234) (xy 426.975578 -312.673234)
			(xy 427.02636 -312.681277) (xy 427.075259 -312.697165) (xy 427.121071 -312.720508) (xy 427.162667 -312.750729)
			(xy 427.199023 -312.787085) (xy 427.229244 -312.828681) (xy 427.252587 -312.874493) (xy 427.268475 -312.923392)
			(xy 427.276518 -312.974174) (xy 427.277022 -312.999882) (xy 427.276518 -313.02559) (xy 428.523142 -313.02559)
			(xy 428.523142 -312.974174) (xy 428.531185 -312.923392) (xy 428.547073 -312.874493) (xy 428.570416 -312.828681)
			(xy 428.600637 -312.787085) (xy 428.636993 -312.750729) (xy 428.678589 -312.720508) (xy 428.724401 -312.697165)
			(xy 428.7733 -312.681277) (xy 428.824082 -312.673234) (xy 428.875498 -312.673234) (xy 428.92628 -312.681277)
			(xy 428.975179 -312.697165) (xy 429.020991 -312.720508) (xy 429.062587 -312.750729) (xy 429.098943 -312.787085)
			(xy 429.129164 -312.828681) (xy 429.152507 -312.874493) (xy 429.153014 -312.876052) (xy 434.16853 -312.876052)
			(xy 434.16853 -312.821548) (xy 434.176286 -312.767597) (xy 434.19164 -312.7153) (xy 434.214281 -312.66572)
			(xy 434.243746 -312.619866) (xy 434.279437 -312.578672) (xy 434.320626 -312.542976) (xy 434.366476 -312.513505)
			(xy 434.416053 -312.490858) (xy 434.468349 -312.475497) (xy 434.522298 -312.467733) (xy 434.54955 -312.467244)
			(xy 434.561584 -312.467349) (xy 434.585605 -312.468874) (xy 434.597556 -312.470292) (xy 434.611702 -312.471595)
			(xy 434.639763 -312.467237) (xy 434.665541 -312.455327) (xy 434.687048 -312.436783) (xy 434.702622 -312.413038)
			(xy 434.711061 -312.385924) (xy 434.711856 -312.37174) (xy 434.712819 -312.344857) (xy 434.721495 -312.291768)
			(xy 434.73754 -312.240423) (xy 434.760634 -312.191838) (xy 434.790321 -312.146978) (xy 434.826013 -312.106731)
			(xy 434.867002 -312.071893) (xy 434.912477 -312.043156) (xy 434.961536 -312.021088) (xy 435.013207 -312.006127)
			(xy 435.066467 -311.998569) (xy 435.093364 -311.998106) (xy 435.12062 -311.998538) (xy 435.174576 -312.006292)
			(xy 435.226881 -312.021645) (xy 435.276467 -312.044286) (xy 435.322326 -312.073754) (xy 435.363525 -312.109449)
			(xy 435.399224 -312.150645) (xy 435.428696 -312.196501) (xy 435.451342 -312.246086) (xy 435.466701 -312.298388)
			(xy 435.474459 -312.352344) (xy 435.474459 -312.406856) (xy 435.466701 -312.460812) (xy 435.451342 -312.513114)
			(xy 435.428696 -312.562699) (xy 435.399224 -312.608555) (xy 435.363525 -312.649751) (xy 435.322326 -312.685446)
			(xy 435.276467 -312.714914) (xy 435.226881 -312.737555) (xy 435.174576 -312.752908) (xy 435.12062 -312.760662)
			(xy 435.093364 -312.761122) (xy 435.08133 -312.761016) (xy 435.057309 -312.759492) (xy 435.045358 -312.758074)
			(xy 435.031213 -312.756721) (xy 435.003142 -312.761078) (xy 434.977355 -312.772995) (xy 434.955845 -312.791549)
			(xy 434.940274 -312.815309) (xy 434.931845 -312.842437) (xy 434.931058 -312.856626) (xy 434.93005 -312.883506)
			(xy 434.921379 -312.936593) (xy 434.90534 -312.987937) (xy 434.88225 -313.036521) (xy 434.852568 -313.08138)
			(xy 434.816881 -313.121628) (xy 434.775896 -313.156466) (xy 434.730425 -313.185205) (xy 434.68137 -313.207274)
			(xy 434.629702 -313.222237) (xy 434.576445 -313.229796) (xy 434.54955 -313.23026) (xy 434.522298 -313.229867)
			(xy 434.468349 -313.222103) (xy 434.416053 -313.206742) (xy 434.366476 -313.184095) (xy 434.320626 -313.154624)
			(xy 434.279437 -313.118928) (xy 434.243746 -313.077734) (xy 434.214281 -313.03188) (xy 434.19164 -312.9823)
			(xy 434.176286 -312.930003) (xy 434.16853 -312.876052) (xy 429.153014 -312.876052) (xy 429.168395 -312.923392)
			(xy 429.176438 -312.974174) (xy 429.176942 -312.999882) (xy 429.176438 -313.02559) (xy 429.168395 -313.076372)
			(xy 429.152507 -313.125271) (xy 429.129164 -313.171083) (xy 429.098943 -313.212679) (xy 429.062587 -313.249035)
			(xy 429.020991 -313.279256) (xy 428.975179 -313.302599) (xy 428.92628 -313.318487) (xy 428.875498 -313.32653)
			(xy 428.824082 -313.32653) (xy 428.7733 -313.318487) (xy 428.724401 -313.302599) (xy 428.678589 -313.279256)
			(xy 428.636993 -313.249035) (xy 428.600637 -313.212679) (xy 428.570416 -313.171083) (xy 428.547073 -313.125271)
			(xy 428.531185 -313.076372) (xy 428.523142 -313.02559) (xy 427.276518 -313.02559) (xy 427.268475 -313.076372)
			(xy 427.252587 -313.125271) (xy 427.229244 -313.171083) (xy 427.199023 -313.212679) (xy 427.162667 -313.249035)
			(xy 427.121071 -313.279256) (xy 427.075259 -313.302599) (xy 427.02636 -313.318487) (xy 426.975578 -313.32653)
			(xy 426.924162 -313.32653) (xy 426.87338 -313.318487) (xy 426.824481 -313.302599) (xy 426.778669 -313.279256)
			(xy 426.737073 -313.249035) (xy 426.700717 -313.212679) (xy 426.670496 -313.171083) (xy 426.647153 -313.125271)
			(xy 426.631265 -313.076372) (xy 426.623222 -313.02559) (xy 425.376598 -313.02559) (xy 425.368555 -313.076372)
			(xy 425.352667 -313.125271) (xy 425.329324 -313.171083) (xy 425.299103 -313.212679) (xy 425.262747 -313.249035)
			(xy 425.221151 -313.279256) (xy 425.175339 -313.302599) (xy 425.12644 -313.318487) (xy 425.075658 -313.32653)
			(xy 425.024242 -313.32653) (xy 424.97346 -313.318487) (xy 424.924561 -313.302599) (xy 424.878749 -313.279256)
			(xy 424.837153 -313.249035) (xy 424.800797 -313.212679) (xy 424.770576 -313.171083) (xy 424.747233 -313.125271)
			(xy 424.731345 -313.076372) (xy 424.723302 -313.02559) (xy 423.476678 -313.02559) (xy 423.468635 -313.076372)
			(xy 423.452747 -313.125271) (xy 423.429404 -313.171083) (xy 423.399183 -313.212679) (xy 423.362827 -313.249035)
			(xy 423.321231 -313.279256) (xy 423.275419 -313.302599) (xy 423.22652 -313.318487) (xy 423.175738 -313.32653)
			(xy 423.124322 -313.32653) (xy 423.07354 -313.318487) (xy 423.024641 -313.302599) (xy 422.978829 -313.279256)
			(xy 422.937233 -313.249035) (xy 422.900877 -313.212679) (xy 422.870656 -313.171083) (xy 422.847313 -313.125271)
			(xy 422.831425 -313.076372) (xy 422.823382 -313.02559) (xy 421.576504 -313.02559) (xy 421.568461 -313.076372)
			(xy 421.552573 -313.125271) (xy 421.52923 -313.171083) (xy 421.499009 -313.212679) (xy 421.462653 -313.249035)
			(xy 421.421057 -313.279256) (xy 421.375245 -313.302599) (xy 421.326346 -313.318487) (xy 421.275564 -313.32653)
			(xy 421.224148 -313.32653) (xy 421.173366 -313.318487) (xy 421.124467 -313.302599) (xy 421.078655 -313.279256)
			(xy 421.037059 -313.249035) (xy 421.000703 -313.212679) (xy 420.970482 -313.171083) (xy 420.947139 -313.125271)
			(xy 420.931251 -313.076372) (xy 420.923208 -313.02559) (xy 419.676584 -313.02559) (xy 419.668541 -313.076372)
			(xy 419.652653 -313.125271) (xy 419.62931 -313.171083) (xy 419.599089 -313.212679) (xy 419.562733 -313.249035)
			(xy 419.521137 -313.279256) (xy 419.475325 -313.302599) (xy 419.426426 -313.318487) (xy 419.375644 -313.32653)
			(xy 419.324228 -313.32653) (xy 419.273446 -313.318487) (xy 419.224547 -313.302599) (xy 419.178735 -313.279256)
			(xy 419.137139 -313.249035) (xy 419.100783 -313.212679) (xy 419.070562 -313.171083) (xy 419.047219 -313.125271)
			(xy 419.031331 -313.076372) (xy 419.023288 -313.02559) (xy 417.800282 -313.02559) (xy 417.800282 -313.97555)
			(xy 419.023288 -313.97555) (xy 419.023288 -313.924134) (xy 419.031331 -313.873352) (xy 419.047219 -313.824453)
			(xy 419.070562 -313.778641) (xy 419.100783 -313.737045) (xy 419.137139 -313.700689) (xy 419.178735 -313.670468)
			(xy 419.224547 -313.647125) (xy 419.273446 -313.631237) (xy 419.324228 -313.623194) (xy 419.375644 -313.623194)
			(xy 419.426426 -313.631237) (xy 419.475325 -313.647125) (xy 419.521137 -313.670468) (xy 419.562733 -313.700689)
			(xy 419.599089 -313.737045) (xy 419.62931 -313.778641) (xy 419.652653 -313.824453) (xy 419.668541 -313.873352)
			(xy 419.676584 -313.924134) (xy 419.677088 -313.949842) (xy 419.676584 -313.97555) (xy 420.923208 -313.97555)
			(xy 420.923208 -313.924134) (xy 420.931251 -313.873352) (xy 420.947139 -313.824453) (xy 420.970482 -313.778641)
			(xy 421.000703 -313.737045) (xy 421.037059 -313.700689) (xy 421.078655 -313.670468) (xy 421.124467 -313.647125)
			(xy 421.173366 -313.631237) (xy 421.224148 -313.623194) (xy 421.275564 -313.623194) (xy 421.326346 -313.631237)
			(xy 421.375245 -313.647125) (xy 421.421057 -313.670468) (xy 421.462653 -313.700689) (xy 421.499009 -313.737045)
			(xy 421.52923 -313.778641) (xy 421.552573 -313.824453) (xy 421.568461 -313.873352) (xy 421.576504 -313.924134)
			(xy 421.577008 -313.949842) (xy 421.576504 -313.97555) (xy 422.823382 -313.97555) (xy 422.823382 -313.924134)
			(xy 422.831425 -313.873352) (xy 422.847313 -313.824453) (xy 422.870656 -313.778641) (xy 422.900877 -313.737045)
			(xy 422.937233 -313.700689) (xy 422.978829 -313.670468) (xy 423.024641 -313.647125) (xy 423.07354 -313.631237)
			(xy 423.124322 -313.623194) (xy 423.175738 -313.623194) (xy 423.22652 -313.631237) (xy 423.275419 -313.647125)
			(xy 423.321231 -313.670468) (xy 423.362827 -313.700689) (xy 423.399183 -313.737045) (xy 423.429404 -313.778641)
			(xy 423.452747 -313.824453) (xy 423.468635 -313.873352) (xy 423.476678 -313.924134) (xy 423.477182 -313.949842)
			(xy 423.476678 -313.97555) (xy 424.723302 -313.97555) (xy 424.723302 -313.924134) (xy 424.731345 -313.873352)
			(xy 424.747233 -313.824453) (xy 424.770576 -313.778641) (xy 424.800797 -313.737045) (xy 424.837153 -313.700689)
			(xy 424.878749 -313.670468) (xy 424.924561 -313.647125) (xy 424.97346 -313.631237) (xy 425.024242 -313.623194)
			(xy 425.075658 -313.623194) (xy 425.12644 -313.631237) (xy 425.175339 -313.647125) (xy 425.221151 -313.670468)
			(xy 425.262747 -313.700689) (xy 425.299103 -313.737045) (xy 425.329324 -313.778641) (xy 425.352667 -313.824453)
			(xy 425.368555 -313.873352) (xy 425.376598 -313.924134) (xy 425.377102 -313.949842) (xy 425.376598 -313.97555)
			(xy 426.623222 -313.97555) (xy 426.623222 -313.924134) (xy 426.631265 -313.873352) (xy 426.647153 -313.824453)
			(xy 426.670496 -313.778641) (xy 426.700717 -313.737045) (xy 426.737073 -313.700689) (xy 426.778669 -313.670468)
			(xy 426.824481 -313.647125) (xy 426.87338 -313.631237) (xy 426.924162 -313.623194) (xy 426.975578 -313.623194)
			(xy 427.02636 -313.631237) (xy 427.075259 -313.647125) (xy 427.121071 -313.670468) (xy 427.162667 -313.700689)
			(xy 427.199023 -313.737045) (xy 427.229244 -313.778641) (xy 427.252587 -313.824453) (xy 427.268475 -313.873352)
			(xy 427.276518 -313.924134) (xy 427.277022 -313.949842) (xy 427.276518 -313.97555) (xy 428.523142 -313.97555)
			(xy 428.523142 -313.924134) (xy 428.531185 -313.873352) (xy 428.547073 -313.824453) (xy 428.570416 -313.778641)
			(xy 428.600637 -313.737045) (xy 428.636993 -313.700689) (xy 428.678589 -313.670468) (xy 428.724401 -313.647125)
			(xy 428.7733 -313.631237) (xy 428.824082 -313.623194) (xy 428.875498 -313.623194) (xy 428.92628 -313.631237)
			(xy 428.975179 -313.647125) (xy 429.020991 -313.670468) (xy 429.062587 -313.700689) (xy 429.098943 -313.737045)
			(xy 429.129164 -313.778641) (xy 429.152507 -313.824453) (xy 429.168395 -313.873352) (xy 429.176438 -313.924134)
			(xy 429.176942 -313.949842) (xy 429.176438 -313.97555) (xy 429.168395 -314.026332) (xy 429.152507 -314.075231)
			(xy 429.129164 -314.121043) (xy 429.098943 -314.162639) (xy 429.062587 -314.198995) (xy 429.020991 -314.229216)
			(xy 428.975179 -314.252559) (xy 428.92628 -314.268447) (xy 428.875498 -314.27649) (xy 428.824082 -314.27649)
			(xy 428.7733 -314.268447) (xy 428.724401 -314.252559) (xy 428.678589 -314.229216) (xy 428.636993 -314.198995)
			(xy 428.600637 -314.162639) (xy 428.570416 -314.121043) (xy 428.547073 -314.075231) (xy 428.531185 -314.026332)
			(xy 428.523142 -313.97555) (xy 427.276518 -313.97555) (xy 427.268475 -314.026332) (xy 427.252587 -314.075231)
			(xy 427.229244 -314.121043) (xy 427.199023 -314.162639) (xy 427.162667 -314.198995) (xy 427.121071 -314.229216)
			(xy 427.075259 -314.252559) (xy 427.02636 -314.268447) (xy 426.975578 -314.27649) (xy 426.924162 -314.27649)
			(xy 426.87338 -314.268447) (xy 426.824481 -314.252559) (xy 426.778669 -314.229216) (xy 426.737073 -314.198995)
			(xy 426.700717 -314.162639) (xy 426.670496 -314.121043) (xy 426.647153 -314.075231) (xy 426.631265 -314.026332)
			(xy 426.623222 -313.97555) (xy 425.376598 -313.97555) (xy 425.368555 -314.026332) (xy 425.352667 -314.075231)
			(xy 425.329324 -314.121043) (xy 425.299103 -314.162639) (xy 425.262747 -314.198995) (xy 425.221151 -314.229216)
			(xy 425.175339 -314.252559) (xy 425.12644 -314.268447) (xy 425.075658 -314.27649) (xy 425.024242 -314.27649)
			(xy 424.97346 -314.268447) (xy 424.924561 -314.252559) (xy 424.878749 -314.229216) (xy 424.837153 -314.198995)
			(xy 424.800797 -314.162639) (xy 424.770576 -314.121043) (xy 424.747233 -314.075231) (xy 424.731345 -314.026332)
			(xy 424.723302 -313.97555) (xy 423.476678 -313.97555) (xy 423.468635 -314.026332) (xy 423.452747 -314.075231)
			(xy 423.429404 -314.121043) (xy 423.399183 -314.162639) (xy 423.362827 -314.198995) (xy 423.321231 -314.229216)
			(xy 423.275419 -314.252559) (xy 423.22652 -314.268447) (xy 423.175738 -314.27649) (xy 423.124322 -314.27649)
			(xy 423.07354 -314.268447) (xy 423.024641 -314.252559) (xy 422.978829 -314.229216) (xy 422.937233 -314.198995)
			(xy 422.900877 -314.162639) (xy 422.870656 -314.121043) (xy 422.847313 -314.075231) (xy 422.831425 -314.026332)
			(xy 422.823382 -313.97555) (xy 421.576504 -313.97555) (xy 421.568461 -314.026332) (xy 421.552573 -314.075231)
			(xy 421.52923 -314.121043) (xy 421.499009 -314.162639) (xy 421.462653 -314.198995) (xy 421.421057 -314.229216)
			(xy 421.375245 -314.252559) (xy 421.326346 -314.268447) (xy 421.275564 -314.27649) (xy 421.224148 -314.27649)
			(xy 421.173366 -314.268447) (xy 421.124467 -314.252559) (xy 421.078655 -314.229216) (xy 421.037059 -314.198995)
			(xy 421.000703 -314.162639) (xy 420.970482 -314.121043) (xy 420.947139 -314.075231) (xy 420.931251 -314.026332)
			(xy 420.923208 -313.97555) (xy 419.676584 -313.97555) (xy 419.668541 -314.026332) (xy 419.652653 -314.075231)
			(xy 419.62931 -314.121043) (xy 419.599089 -314.162639) (xy 419.562733 -314.198995) (xy 419.521137 -314.229216)
			(xy 419.475325 -314.252559) (xy 419.426426 -314.268447) (xy 419.375644 -314.27649) (xy 419.324228 -314.27649)
			(xy 419.273446 -314.268447) (xy 419.224547 -314.252559) (xy 419.178735 -314.229216) (xy 419.137139 -314.198995)
			(xy 419.100783 -314.162639) (xy 419.070562 -314.121043) (xy 419.047219 -314.075231) (xy 419.031331 -314.026332)
			(xy 419.023288 -313.97555) (xy 417.800282 -313.97555) (xy 417.800282 -314.898786) (xy 417.800646 -314.90748)
			(xy 417.806481 -314.92386) (xy 417.817452 -314.93735) (xy 417.824666 -314.94222) (xy 417.910772 -314.99429)
			(xy 417.937188 -314.995052) (xy 417.949126 -314.988702) (xy 417.970764 -314.977511) (xy 418.01498 -314.957053)
			(xy 418.037518 -314.947808) (xy 418.069268 -314.900818) (xy 418.069268 -314.899802) (xy 418.069778 -314.873815)
			(xy 418.077908 -314.82248) (xy 418.093969 -314.77305) (xy 418.117565 -314.72674) (xy 418.148115 -314.684692)
			(xy 418.184866 -314.647941) (xy 418.226914 -314.617391) (xy 418.273224 -314.593795) (xy 418.322654 -314.577734)
			(xy 418.373989 -314.569604) (xy 418.425963 -314.569604) (xy 418.477298 -314.577734) (xy 418.526728 -314.593795)
			(xy 418.573038 -314.617391) (xy 418.615086 -314.647941) (xy 418.651837 -314.684692) (xy 418.682387 -314.72674)
			(xy 418.705983 -314.77305) (xy 418.722044 -314.82248) (xy 418.730174 -314.873815) (xy 418.730684 -314.899802)
			(xy 418.730684 -314.900818) (xy 418.762434 -314.947808) (xy 418.801357 -314.963937) (xy 418.876526 -315.002009)
			(xy 418.948117 -315.046446) (xy 419.015591 -315.096915) (xy 419.078443 -315.153035) (xy 419.1362 -315.214386)
			(xy 419.188429 -315.280507) (xy 419.234738 -315.350902) (xy 419.255194 -315.387736) (xy 419.260274 -315.397134)
			(xy 419.277292 -315.410342) (xy 419.371272 -315.433456) (xy 419.392354 -315.429646) (xy 419.401244 -315.423804)
			(xy 419.426898 -315.40704) (xy 419.432347 -315.403402) (xy 419.44135 -315.393888) (xy 419.444678 -315.388244)
			(xy 419.465083 -315.351356) (xy 419.511375 -315.280897) (xy 419.563597 -315.214712) (xy 419.621354 -315.153299)
			(xy 419.684213 -315.097119) (xy 419.751703 -315.046594) (xy 419.823314 -315.002105) (xy 419.89851 -314.963986)
			(xy 419.937438 -314.947808) (xy 419.969188 -314.900818) (xy 419.969188 -314.899802) (xy 419.969698 -314.873815)
			(xy 419.977828 -314.82248) (xy 419.993889 -314.77305) (xy 420.017485 -314.72674) (xy 420.048035 -314.684692)
			(xy 420.084786 -314.647941) (xy 420.126834 -314.617391) (xy 420.173144 -314.593795) (xy 420.222574 -314.577734)
			(xy 420.273909 -314.569604) (xy 420.325883 -314.569604) (xy 420.377218 -314.577734) (xy 420.426648 -314.593795)
			(xy 420.472958 -314.617391) (xy 420.515006 -314.647941) (xy 420.551757 -314.684692) (xy 420.582307 -314.72674)
			(xy 420.605903 -314.77305) (xy 420.621964 -314.82248) (xy 420.630094 -314.873815) (xy 420.630604 -314.899802)
			(xy 420.630604 -314.900818) (xy 420.647288 -314.92551) (xy 429.473356 -314.92551) (xy 429.473356 -314.874094)
			(xy 429.481399 -314.823312) (xy 429.497287 -314.774413) (xy 429.52063 -314.728601) (xy 429.550851 -314.687005)
			(xy 429.587207 -314.650649) (xy 429.628803 -314.620428) (xy 429.674615 -314.597085) (xy 429.723514 -314.581197)
			(xy 429.774296 -314.573154) (xy 429.825712 -314.573154) (xy 429.876494 -314.581197) (xy 429.925393 -314.597085)
			(xy 429.971205 -314.620428) (xy 430.012801 -314.650649) (xy 430.049157 -314.687005) (xy 430.079378 -314.728601)
			(xy 430.102721 -314.774413) (xy 430.118609 -314.823312) (xy 430.126652 -314.874094) (xy 430.127156 -314.899802)
			(xy 430.126652 -314.92551) (xy 430.423316 -314.92551) (xy 430.423316 -314.874094) (xy 430.431359 -314.823312)
			(xy 430.447247 -314.774413) (xy 430.47059 -314.728601) (xy 430.500811 -314.687005) (xy 430.537167 -314.650649)
			(xy 430.578763 -314.620428) (xy 430.624575 -314.597085) (xy 430.673474 -314.581197) (xy 430.724256 -314.573154)
			(xy 430.775672 -314.573154) (xy 430.826454 -314.581197) (xy 430.875353 -314.597085) (xy 430.921165 -314.620428)
			(xy 430.962761 -314.650649) (xy 430.999117 -314.687005) (xy 431.029338 -314.728601) (xy 431.052681 -314.774413)
			(xy 431.068569 -314.823312) (xy 431.076612 -314.874094) (xy 431.077116 -314.899802) (xy 431.076612 -314.92551)
			(xy 431.068569 -314.976292) (xy 431.052681 -315.025191) (xy 431.029338 -315.071003) (xy 430.999117 -315.112599)
			(xy 430.962761 -315.148955) (xy 430.921165 -315.179176) (xy 430.875353 -315.202519) (xy 430.826454 -315.218407)
			(xy 430.775672 -315.22645) (xy 430.724256 -315.22645) (xy 430.673474 -315.218407) (xy 430.624575 -315.202519)
			(xy 430.578763 -315.179176) (xy 430.537167 -315.148955) (xy 430.500811 -315.112599) (xy 430.47059 -315.071003)
			(xy 430.447247 -315.025191) (xy 430.431359 -314.976292) (xy 430.423316 -314.92551) (xy 430.126652 -314.92551)
			(xy 430.118609 -314.976292) (xy 430.102721 -315.025191) (xy 430.079378 -315.071003) (xy 430.049157 -315.112599)
			(xy 430.012801 -315.148955) (xy 429.971205 -315.179176) (xy 429.925393 -315.202519) (xy 429.876494 -315.218407)
			(xy 429.825712 -315.22645) (xy 429.774296 -315.22645) (xy 429.723514 -315.218407) (xy 429.674615 -315.202519)
			(xy 429.628803 -315.179176) (xy 429.587207 -315.148955) (xy 429.550851 -315.112599) (xy 429.52063 -315.071003)
			(xy 429.497287 -315.025191) (xy 429.481399 -314.976292) (xy 429.473356 -314.92551) (xy 420.647288 -314.92551)
			(xy 420.662354 -314.947808) (xy 420.702597 -314.964501) (xy 420.780215 -315.00409) (xy 420.853976 -315.05047)
			(xy 420.923289 -315.103267) (xy 420.987596 -315.162057) (xy 421.046382 -315.226369) (xy 421.099173 -315.295686)
			(xy 421.145547 -315.369451) (xy 421.185131 -315.447071) (xy 421.20185 -315.487304) (xy 421.24884 -315.519054)
			(xy 421.249856 -315.519054) (xy 421.275849 -315.519534) (xy 421.327195 -315.527659) (xy 421.376638 -315.543717)
			(xy 421.42296 -315.567312) (xy 421.46502 -315.597863) (xy 421.501784 -315.634617) (xy 421.532345 -315.67667)
			(xy 421.555951 -315.722987) (xy 421.572021 -315.772425) (xy 421.58016 -315.82377) (xy 421.580564 -315.849762)
			(xy 421.580077 -315.8754) (xy 421.580066 -315.87547) (xy 421.873168 -315.87547) (xy 421.873168 -315.824054)
			(xy 421.881211 -315.773272) (xy 421.897099 -315.724373) (xy 421.920442 -315.678561) (xy 421.950663 -315.636965)
			(xy 421.987019 -315.600609) (xy 422.028615 -315.570388) (xy 422.074427 -315.547045) (xy 422.123326 -315.531157)
			(xy 422.174108 -315.523114) (xy 422.225524 -315.523114) (xy 422.276306 -315.531157) (xy 422.325205 -315.547045)
			(xy 422.371017 -315.570388) (xy 422.412613 -315.600609) (xy 422.448969 -315.636965) (xy 422.47919 -315.678561)
			(xy 422.502533 -315.724373) (xy 422.518421 -315.773272) (xy 422.526464 -315.824054) (xy 422.526968 -315.849762)
			(xy 422.526464 -315.87547) (xy 423.773342 -315.87547) (xy 423.773342 -315.824054) (xy 423.781385 -315.773272)
			(xy 423.797273 -315.724373) (xy 423.820616 -315.678561) (xy 423.850837 -315.636965) (xy 423.887193 -315.600609)
			(xy 423.928789 -315.570388) (xy 423.974601 -315.547045) (xy 424.0235 -315.531157) (xy 424.074282 -315.523114)
			(xy 424.125698 -315.523114) (xy 424.17648 -315.531157) (xy 424.225379 -315.547045) (xy 424.271191 -315.570388)
			(xy 424.312787 -315.600609) (xy 424.349143 -315.636965) (xy 424.379364 -315.678561) (xy 424.402707 -315.724373)
			(xy 424.418595 -315.773272) (xy 424.426638 -315.824054) (xy 424.427142 -315.849762) (xy 424.426638 -315.87547)
			(xy 425.673262 -315.87547) (xy 425.673262 -315.824054) (xy 425.681305 -315.773272) (xy 425.697193 -315.724373)
			(xy 425.720536 -315.678561) (xy 425.750757 -315.636965) (xy 425.787113 -315.600609) (xy 425.828709 -315.570388)
			(xy 425.874521 -315.547045) (xy 425.92342 -315.531157) (xy 425.974202 -315.523114) (xy 426.025618 -315.523114)
			(xy 426.0764 -315.531157) (xy 426.125299 -315.547045) (xy 426.171111 -315.570388) (xy 426.212707 -315.600609)
			(xy 426.249063 -315.636965) (xy 426.279284 -315.678561) (xy 426.302627 -315.724373) (xy 426.318515 -315.773272)
			(xy 426.326558 -315.824054) (xy 426.327062 -315.849762) (xy 426.326558 -315.87547) (xy 427.573182 -315.87547)
			(xy 427.573182 -315.824054) (xy 427.581225 -315.773272) (xy 427.597113 -315.724373) (xy 427.620456 -315.678561)
			(xy 427.650677 -315.636965) (xy 427.687033 -315.600609) (xy 427.728629 -315.570388) (xy 427.774441 -315.547045)
			(xy 427.82334 -315.531157) (xy 427.874122 -315.523114) (xy 427.925538 -315.523114) (xy 427.97632 -315.531157)
			(xy 428.025219 -315.547045) (xy 428.071031 -315.570388) (xy 428.112627 -315.600609) (xy 428.148983 -315.636965)
			(xy 428.179204 -315.678561) (xy 428.202547 -315.724373) (xy 428.218435 -315.773272) (xy 428.226478 -315.824054)
			(xy 428.226982 -315.849762) (xy 428.226478 -315.87547) (xy 428.218435 -315.926252) (xy 428.202547 -315.975151)
			(xy 428.179204 -316.020963) (xy 428.148983 -316.062559) (xy 428.112627 -316.098915) (xy 428.071031 -316.129136)
			(xy 428.025219 -316.152479) (xy 427.97632 -316.168367) (xy 427.925538 -316.17641) (xy 427.874122 -316.17641)
			(xy 427.82334 -316.168367) (xy 427.774441 -316.152479) (xy 427.728629 -316.129136) (xy 427.687033 -316.098915)
			(xy 427.650677 -316.062559) (xy 427.620456 -316.020963) (xy 427.597113 -315.975151) (xy 427.581225 -315.926252)
			(xy 427.573182 -315.87547) (xy 426.326558 -315.87547) (xy 426.318515 -315.926252) (xy 426.302627 -315.975151)
			(xy 426.279284 -316.020963) (xy 426.249063 -316.062559) (xy 426.212707 -316.098915) (xy 426.171111 -316.129136)
			(xy 426.125299 -316.152479) (xy 426.0764 -316.168367) (xy 426.025618 -316.17641) (xy 425.974202 -316.17641)
			(xy 425.92342 -316.168367) (xy 425.874521 -316.152479) (xy 425.828709 -316.129136) (xy 425.787113 -316.098915)
			(xy 425.750757 -316.062559) (xy 425.720536 -316.020963) (xy 425.697193 -315.975151) (xy 425.681305 -315.926252)
			(xy 425.673262 -315.87547) (xy 424.426638 -315.87547) (xy 424.418595 -315.926252) (xy 424.402707 -315.975151)
			(xy 424.379364 -316.020963) (xy 424.349143 -316.062559) (xy 424.312787 -316.098915) (xy 424.271191 -316.129136)
			(xy 424.225379 -316.152479) (xy 424.17648 -316.168367) (xy 424.125698 -316.17641) (xy 424.074282 -316.17641)
			(xy 424.0235 -316.168367) (xy 423.974601 -316.152479) (xy 423.928789 -316.129136) (xy 423.887193 -316.098915)
			(xy 423.850837 -316.062559) (xy 423.820616 -316.020963) (xy 423.797273 -315.975151) (xy 423.781385 -315.926252)
			(xy 423.773342 -315.87547) (xy 422.526464 -315.87547) (xy 422.518421 -315.926252) (xy 422.502533 -315.975151)
			(xy 422.47919 -316.020963) (xy 422.448969 -316.062559) (xy 422.412613 -316.098915) (xy 422.371017 -316.129136)
			(xy 422.325205 -316.152479) (xy 422.276306 -316.168367) (xy 422.225524 -316.17641) (xy 422.174108 -316.17641)
			(xy 422.123326 -316.168367) (xy 422.074427 -316.152479) (xy 422.028615 -316.129136) (xy 421.987019 -316.098915)
			(xy 421.950663 -316.062559) (xy 421.920442 -316.020963) (xy 421.897099 -315.975151) (xy 421.881211 -315.926252)
			(xy 421.873168 -315.87547) (xy 421.580066 -315.87547) (xy 421.572154 -315.926061) (xy 421.556509 -315.974893)
			(xy 421.533515 -316.020725) (xy 421.503723 -316.06246) (xy 421.467848 -316.099097) (xy 421.426748 -316.129759)
			(xy 421.381409 -316.153711) (xy 421.332917 -316.170379) (xy 421.307768 -316.17539) (xy 421.297058 -316.177842)
			(xy 421.279026 -316.190354) (xy 421.267848 -316.209242) (xy 421.266112 -316.220094) (xy 421.26344 -316.2438)
			(xy 421.25607 -316.290938) (xy 421.25138 -316.314328) (xy 421.250364 -316.324742) (xy 421.25138 -316.335156)
			(xy 421.256077 -316.358545) (xy 421.263446 -316.405683) (xy 421.266112 -316.42939) (xy 421.267788 -316.440257)
			(xy 421.278985 -316.459154) (xy 421.297046 -316.471654) (xy 421.307768 -316.474094) (xy 421.332931 -316.479056)
			(xy 421.381436 -316.495718) (xy 421.426787 -316.519669) (xy 421.467897 -316.550333) (xy 421.50378 -316.586976)
			(xy 421.533576 -316.62872) (xy 421.556571 -316.674563) (xy 421.572213 -316.723406) (xy 421.580127 -316.774079)
			(xy 421.580564 -316.799722) (xy 421.580564 -316.800738) (xy 421.580964 -316.810892) (xy 421.588709 -316.829662)
			(xy 421.603072 -316.844015) (xy 421.612314 -316.848236) (xy 421.640441 -316.859738) (xy 421.695345 -316.885792)
			(xy 421.722042 -316.900306) (xy 421.73398 -316.907164) (xy 421.761158 -316.906656) (xy 421.848534 -316.85357)
			(xy 421.85579 -316.848749) (xy 421.866776 -316.835246) (xy 421.872595 -316.81884) (xy 421.872918 -316.810136)
			(xy 421.872918 -316.808866) (xy 421.872664 -316.80023) (xy 421.872664 -316.799214) (xy 421.873205 -316.773536)
			(xy 421.881311 -316.722821) (xy 421.897247 -316.673998) (xy 421.920622 -316.628267) (xy 421.950859 -316.586754)
			(xy 421.987216 -316.550479) (xy 422.028797 -316.520335) (xy 422.074581 -316.497064) (xy 422.12344 -316.481238)
			(xy 422.174173 -316.473247) (xy 422.225531 -316.473287) (xy 422.276251 -316.481356) (xy 422.325086 -316.497257)
			(xy 422.370833 -316.520599) (xy 422.412368 -316.550807) (xy 422.448669 -316.587137) (xy 422.478842 -316.628697)
			(xy 422.502146 -316.674464) (xy 422.518007 -316.723312) (xy 422.526035 -316.774039) (xy 422.526032 -316.825397)
			(xy 422.526027 -316.82543) (xy 423.773342 -316.82543) (xy 423.773342 -316.774014) (xy 423.781385 -316.723232)
			(xy 423.797273 -316.674333) (xy 423.820616 -316.628521) (xy 423.850837 -316.586925) (xy 423.887193 -316.550569)
			(xy 423.928789 -316.520348) (xy 423.974601 -316.497005) (xy 424.0235 -316.481117) (xy 424.074282 -316.473074)
			(xy 424.125698 -316.473074) (xy 424.17648 -316.481117) (xy 424.225379 -316.497005) (xy 424.271191 -316.520348)
			(xy 424.312787 -316.550569) (xy 424.349143 -316.586925) (xy 424.379364 -316.628521) (xy 424.402707 -316.674333)
			(xy 424.418595 -316.723232) (xy 424.426638 -316.774014) (xy 424.427142 -316.799722) (xy 424.426638 -316.82543)
			(xy 425.673262 -316.82543) (xy 425.673262 -316.774014) (xy 425.681305 -316.723232) (xy 425.697193 -316.674333)
			(xy 425.720536 -316.628521) (xy 425.750757 -316.586925) (xy 425.787113 -316.550569) (xy 425.828709 -316.520348)
			(xy 425.874521 -316.497005) (xy 425.92342 -316.481117) (xy 425.974202 -316.473074) (xy 426.025618 -316.473074)
			(xy 426.0764 -316.481117) (xy 426.125299 -316.497005) (xy 426.171111 -316.520348) (xy 426.212707 -316.550569)
			(xy 426.249063 -316.586925) (xy 426.279284 -316.628521) (xy 426.302627 -316.674333) (xy 426.318515 -316.723232)
			(xy 426.326558 -316.774014) (xy 426.327062 -316.799722) (xy 426.326558 -316.82543) (xy 427.573182 -316.82543)
			(xy 427.573182 -316.774014) (xy 427.581225 -316.723232) (xy 427.597113 -316.674333) (xy 427.620456 -316.628521)
			(xy 427.650677 -316.586925) (xy 427.687033 -316.550569) (xy 427.728629 -316.520348) (xy 427.774441 -316.497005)
			(xy 427.82334 -316.481117) (xy 427.874122 -316.473074) (xy 427.925538 -316.473074) (xy 427.97632 -316.481117)
			(xy 428.025219 -316.497005) (xy 428.071031 -316.520348) (xy 428.112627 -316.550569) (xy 428.148983 -316.586925)
			(xy 428.179204 -316.628521) (xy 428.202547 -316.674333) (xy 428.218435 -316.723232) (xy 428.226478 -316.774014)
			(xy 428.226982 -316.799722) (xy 428.226478 -316.82543) (xy 429.473356 -316.82543) (xy 429.473356 -316.774014)
			(xy 429.481399 -316.723232) (xy 429.497287 -316.674333) (xy 429.52063 -316.628521) (xy 429.550851 -316.586925)
			(xy 429.587207 -316.550569) (xy 429.628803 -316.520348) (xy 429.674615 -316.497005) (xy 429.723514 -316.481117)
			(xy 429.774296 -316.473074) (xy 429.825712 -316.473074) (xy 429.876494 -316.481117) (xy 429.925393 -316.497005)
			(xy 429.971205 -316.520348) (xy 430.012801 -316.550569) (xy 430.049157 -316.586925) (xy 430.079378 -316.628521)
			(xy 430.102721 -316.674333) (xy 430.118609 -316.723232) (xy 430.126652 -316.774014) (xy 430.127156 -316.799722)
			(xy 430.126652 -316.82543) (xy 430.423316 -316.82543) (xy 430.423316 -316.774014) (xy 430.431359 -316.723232)
			(xy 430.447247 -316.674333) (xy 430.47059 -316.628521) (xy 430.500811 -316.586925) (xy 430.537167 -316.550569)
			(xy 430.578763 -316.520348) (xy 430.624575 -316.497005) (xy 430.673474 -316.481117) (xy 430.724256 -316.473074)
			(xy 430.775672 -316.473074) (xy 430.826454 -316.481117) (xy 430.875353 -316.497005) (xy 430.921165 -316.520348)
			(xy 430.962761 -316.550569) (xy 430.999117 -316.586925) (xy 431.029338 -316.628521) (xy 431.052681 -316.674333)
			(xy 431.068569 -316.723232) (xy 431.076612 -316.774014) (xy 431.077116 -316.799722) (xy 431.076612 -316.82543)
			(xy 431.068569 -316.876212) (xy 431.052681 -316.925111) (xy 431.029338 -316.970923) (xy 430.999117 -317.012519)
			(xy 430.962761 -317.048875) (xy 430.921165 -317.079096) (xy 430.875353 -317.102439) (xy 430.826454 -317.118327)
			(xy 430.775672 -317.12637) (xy 430.724256 -317.12637) (xy 430.673474 -317.118327) (xy 430.624575 -317.102439)
			(xy 430.578763 -317.079096) (xy 430.537167 -317.048875) (xy 430.500811 -317.012519) (xy 430.47059 -316.970923)
			(xy 430.447247 -316.925111) (xy 430.431359 -316.876212) (xy 430.423316 -316.82543) (xy 430.126652 -316.82543)
			(xy 430.118609 -316.876212) (xy 430.102721 -316.925111) (xy 430.079378 -316.970923) (xy 430.049157 -317.012519)
			(xy 430.012801 -317.048875) (xy 429.971205 -317.079096) (xy 429.925393 -317.102439) (xy 429.876494 -317.118327)
			(xy 429.825712 -317.12637) (xy 429.774296 -317.12637) (xy 429.723514 -317.118327) (xy 429.674615 -317.102439)
			(xy 429.628803 -317.079096) (xy 429.587207 -317.048875) (xy 429.550851 -317.012519) (xy 429.52063 -316.970923)
			(xy 429.497287 -316.925111) (xy 429.481399 -316.876212) (xy 429.473356 -316.82543) (xy 428.226478 -316.82543)
			(xy 428.218435 -316.876212) (xy 428.202547 -316.925111) (xy 428.179204 -316.970923) (xy 428.148983 -317.012519)
			(xy 428.112627 -317.048875) (xy 428.071031 -317.079096) (xy 428.025219 -317.102439) (xy 427.97632 -317.118327)
			(xy 427.925538 -317.12637) (xy 427.874122 -317.12637) (xy 427.82334 -317.118327) (xy 427.774441 -317.102439)
			(xy 427.728629 -317.079096) (xy 427.687033 -317.048875) (xy 427.650677 -317.012519) (xy 427.620456 -316.970923)
			(xy 427.597113 -316.925111) (xy 427.581225 -316.876212) (xy 427.573182 -316.82543) (xy 426.326558 -316.82543)
			(xy 426.318515 -316.876212) (xy 426.302627 -316.925111) (xy 426.279284 -316.970923) (xy 426.249063 -317.012519)
			(xy 426.212707 -317.048875) (xy 426.171111 -317.079096) (xy 426.125299 -317.102439) (xy 426.0764 -317.118327)
			(xy 426.025618 -317.12637) (xy 425.974202 -317.12637) (xy 425.92342 -317.118327) (xy 425.874521 -317.102439)
			(xy 425.828709 -317.079096) (xy 425.787113 -317.048875) (xy 425.750757 -317.012519) (xy 425.720536 -316.970923)
			(xy 425.697193 -316.925111) (xy 425.681305 -316.876212) (xy 425.673262 -316.82543) (xy 424.426638 -316.82543)
			(xy 424.418595 -316.876212) (xy 424.402707 -316.925111) (xy 424.379364 -316.970923) (xy 424.349143 -317.012519)
			(xy 424.312787 -317.048875) (xy 424.271191 -317.079096) (xy 424.225379 -317.102439) (xy 424.17648 -317.118327)
			(xy 424.125698 -317.12637) (xy 424.074282 -317.12637) (xy 424.0235 -317.118327) (xy 423.974601 -317.102439)
			(xy 423.928789 -317.079096) (xy 423.887193 -317.048875) (xy 423.850837 -317.012519) (xy 423.820616 -316.970923)
			(xy 423.797273 -316.925111) (xy 423.781385 -316.876212) (xy 423.773342 -316.82543) (xy 422.526027 -316.82543)
			(xy 422.517999 -316.876123) (xy 422.502132 -316.924969) (xy 422.478824 -316.970733) (xy 422.448646 -317.01229)
			(xy 422.412341 -317.048617) (xy 422.370802 -317.07882) (xy 422.325052 -317.102156) (xy 422.276216 -317.118052)
			(xy 422.225495 -317.126116) (xy 422.199816 -317.12662) (xy 422.190672 -317.12662) (xy 422.181745 -317.126737)
			(xy 422.164832 -317.132423) (xy 422.150888 -317.143555) (xy 422.145968 -317.151004) (xy 422.093136 -317.23838)
			(xy 422.092628 -317.265558) (xy 422.099232 -317.277496) (xy 422.113884 -317.304245) (xy 422.140193 -317.359277)
			(xy 422.15181 -317.387478) (xy 422.1988 -317.419228) (xy 422.199816 -317.419228) (xy 422.225803 -317.419712)
			(xy 422.277138 -317.427846) (xy 422.326568 -317.44391) (xy 422.372876 -317.467509) (xy 422.414923 -317.498062)
			(xy 422.451672 -317.534817) (xy 422.482218 -317.576868) (xy 422.50581 -317.62318) (xy 422.521866 -317.672613)
			(xy 422.529992 -317.723949) (xy 422.530524 -317.749936) (xy 422.530039 -317.775575) (xy 422.530028 -317.775644)
			(xy 422.823382 -317.775644) (xy 422.823382 -317.724228) (xy 422.831425 -317.673446) (xy 422.847313 -317.624547)
			(xy 422.870656 -317.578735) (xy 422.900877 -317.537139) (xy 422.937233 -317.500783) (xy 422.978829 -317.470562)
			(xy 423.024641 -317.447219) (xy 423.07354 -317.431331) (xy 423.124322 -317.423288) (xy 423.175738 -317.423288)
			(xy 423.22652 -317.431331) (xy 423.275419 -317.447219) (xy 423.321231 -317.470562) (xy 423.362827 -317.500783)
			(xy 423.399183 -317.537139) (xy 423.429404 -317.578735) (xy 423.452747 -317.624547) (xy 423.468635 -317.673446)
			(xy 423.476678 -317.724228) (xy 423.477182 -317.749936) (xy 423.476678 -317.775644) (xy 424.723302 -317.775644)
			(xy 424.723302 -317.724228) (xy 424.731345 -317.673446) (xy 424.747233 -317.624547) (xy 424.770576 -317.578735)
			(xy 424.800797 -317.537139) (xy 424.837153 -317.500783) (xy 424.878749 -317.470562) (xy 424.924561 -317.447219)
			(xy 424.97346 -317.431331) (xy 425.024242 -317.423288) (xy 425.075658 -317.423288) (xy 425.12644 -317.431331)
			(xy 425.175339 -317.447219) (xy 425.221151 -317.470562) (xy 425.262747 -317.500783) (xy 425.299103 -317.537139)
			(xy 425.329324 -317.578735) (xy 425.352667 -317.624547) (xy 425.368555 -317.673446) (xy 425.376598 -317.724228)
			(xy 425.377102 -317.749936) (xy 425.376598 -317.775644) (xy 426.623222 -317.775644) (xy 426.623222 -317.724228)
			(xy 426.631265 -317.673446) (xy 426.647153 -317.624547) (xy 426.670496 -317.578735) (xy 426.700717 -317.537139)
			(xy 426.737073 -317.500783) (xy 426.778669 -317.470562) (xy 426.824481 -317.447219) (xy 426.87338 -317.431331)
			(xy 426.924162 -317.423288) (xy 426.975578 -317.423288) (xy 427.02636 -317.431331) (xy 427.075259 -317.447219)
			(xy 427.121071 -317.470562) (xy 427.162667 -317.500783) (xy 427.199023 -317.537139) (xy 427.229244 -317.578735)
			(xy 427.252587 -317.624547) (xy 427.268475 -317.673446) (xy 427.276518 -317.724228) (xy 427.277022 -317.749936)
			(xy 427.276518 -317.775644) (xy 428.523142 -317.775644) (xy 428.523142 -317.724228) (xy 428.531185 -317.673446)
			(xy 428.547073 -317.624547) (xy 428.570416 -317.578735) (xy 428.600637 -317.537139) (xy 428.636993 -317.500783)
			(xy 428.678589 -317.470562) (xy 428.724401 -317.447219) (xy 428.7733 -317.431331) (xy 428.824082 -317.423288)
			(xy 428.875498 -317.423288) (xy 428.92628 -317.431331) (xy 428.975179 -317.447219) (xy 429.020991 -317.470562)
			(xy 429.062587 -317.500783) (xy 429.098943 -317.537139) (xy 429.129164 -317.578735) (xy 429.152507 -317.624547)
			(xy 429.168395 -317.673446) (xy 429.176438 -317.724228) (xy 429.176942 -317.749936) (xy 429.176438 -317.775644)
			(xy 429.168395 -317.826426) (xy 429.152507 -317.875325) (xy 429.129164 -317.921137) (xy 429.098943 -317.962733)
			(xy 429.062587 -317.999089) (xy 429.020991 -318.02931) (xy 428.975179 -318.052653) (xy 428.92628 -318.068541)
			(xy 428.875498 -318.076584) (xy 428.824082 -318.076584) (xy 428.7733 -318.068541) (xy 428.724401 -318.052653)
			(xy 428.678589 -318.02931) (xy 428.636993 -317.999089) (xy 428.600637 -317.962733) (xy 428.570416 -317.921137)
			(xy 428.547073 -317.875325) (xy 428.531185 -317.826426) (xy 428.523142 -317.775644) (xy 427.276518 -317.775644)
			(xy 427.268475 -317.826426) (xy 427.252587 -317.875325) (xy 427.229244 -317.921137) (xy 427.199023 -317.962733)
			(xy 427.162667 -317.999089) (xy 427.121071 -318.02931) (xy 427.075259 -318.052653) (xy 427.02636 -318.068541)
			(xy 426.975578 -318.076584) (xy 426.924162 -318.076584) (xy 426.87338 -318.068541) (xy 426.824481 -318.052653)
			(xy 426.778669 -318.02931) (xy 426.737073 -317.999089) (xy 426.700717 -317.962733) (xy 426.670496 -317.921137)
			(xy 426.647153 -317.875325) (xy 426.631265 -317.826426) (xy 426.623222 -317.775644) (xy 425.376598 -317.775644)
			(xy 425.368555 -317.826426) (xy 425.352667 -317.875325) (xy 425.329324 -317.921137) (xy 425.299103 -317.962733)
			(xy 425.262747 -317.999089) (xy 425.221151 -318.02931) (xy 425.175339 -318.052653) (xy 425.12644 -318.068541)
			(xy 425.075658 -318.076584) (xy 425.024242 -318.076584) (xy 424.97346 -318.068541) (xy 424.924561 -318.052653)
			(xy 424.878749 -318.02931) (xy 424.837153 -317.999089) (xy 424.800797 -317.962733) (xy 424.770576 -317.921137)
			(xy 424.747233 -317.875325) (xy 424.731345 -317.826426) (xy 424.723302 -317.775644) (xy 423.476678 -317.775644)
			(xy 423.468635 -317.826426) (xy 423.452747 -317.875325) (xy 423.429404 -317.921137) (xy 423.399183 -317.962733)
			(xy 423.362827 -317.999089) (xy 423.321231 -318.02931) (xy 423.275419 -318.052653) (xy 423.22652 -318.068541)
			(xy 423.175738 -318.076584) (xy 423.124322 -318.076584) (xy 423.07354 -318.068541) (xy 423.024641 -318.052653)
			(xy 422.978829 -318.02931) (xy 422.937233 -317.999089) (xy 422.900877 -317.962733) (xy 422.870656 -317.921137)
			(xy 422.847313 -317.875325) (xy 422.831425 -317.826426) (xy 422.823382 -317.775644) (xy 422.530028 -317.775644)
			(xy 422.522119 -317.826237) (xy 422.506475 -317.875069) (xy 422.483481 -317.920902) (xy 422.453689 -317.962637)
			(xy 422.417813 -317.999274) (xy 422.376712 -318.029934) (xy 422.331371 -318.053884) (xy 422.282877 -318.070548)
			(xy 422.257728 -318.075564) (xy 422.247007 -318.078005) (xy 422.228948 -318.090508) (xy 422.217746 -318.109401)
			(xy 422.216072 -318.120268) (xy 422.213401 -318.143974) (xy 422.206031 -318.191112) (xy 422.20134 -318.214502)
			(xy 422.200324 -318.224916) (xy 422.20134 -318.23533) (xy 422.206037 -318.258719) (xy 422.213407 -318.305857)
			(xy 422.216072 -318.329564) (xy 422.217759 -318.340424) (xy 422.228964 -318.359303) (xy 422.247018 -318.371795)
			(xy 422.257728 -318.374268) (xy 422.282885 -318.379235) (xy 422.331378 -318.395905) (xy 422.376715 -318.419861)
			(xy 422.417811 -318.450528) (xy 422.453679 -318.487173) (xy 422.483461 -318.528915) (xy 422.506441 -318.574755)
			(xy 422.522069 -318.623592) (xy 422.52997 -318.674257) (xy 422.530524 -318.699896) (xy 422.53002 -318.725604)
			(xy 422.823382 -318.725604) (xy 422.823382 -318.674188) (xy 422.831425 -318.623406) (xy 422.847313 -318.574507)
			(xy 422.870656 -318.528695) (xy 422.900877 -318.487099) (xy 422.937233 -318.450743) (xy 422.978829 -318.420522)
			(xy 423.024641 -318.397179) (xy 423.07354 -318.381291) (xy 423.124322 -318.373248) (xy 423.175738 -318.373248)
			(xy 423.22652 -318.381291) (xy 423.275419 -318.397179) (xy 423.321231 -318.420522) (xy 423.362827 -318.450743)
			(xy 423.399183 -318.487099) (xy 423.429404 -318.528695) (xy 423.452747 -318.574507) (xy 423.468635 -318.623406)
			(xy 423.476678 -318.674188) (xy 423.477182 -318.699896) (xy 423.476678 -318.725604) (xy 424.723302 -318.725604)
			(xy 424.723302 -318.674188) (xy 424.731345 -318.623406) (xy 424.747233 -318.574507) (xy 424.770576 -318.528695)
			(xy 424.800797 -318.487099) (xy 424.837153 -318.450743) (xy 424.878749 -318.420522) (xy 424.924561 -318.397179)
			(xy 424.97346 -318.381291) (xy 425.024242 -318.373248) (xy 425.075658 -318.373248) (xy 425.12644 -318.381291)
			(xy 425.175339 -318.397179) (xy 425.221151 -318.420522) (xy 425.262747 -318.450743) (xy 425.299103 -318.487099)
			(xy 425.329324 -318.528695) (xy 425.352667 -318.574507) (xy 425.368555 -318.623406) (xy 425.376598 -318.674188)
			(xy 425.377102 -318.699896) (xy 425.376598 -318.725604) (xy 426.623222 -318.725604) (xy 426.623222 -318.674188)
			(xy 426.631265 -318.623406) (xy 426.647153 -318.574507) (xy 426.670496 -318.528695) (xy 426.700717 -318.487099)
			(xy 426.737073 -318.450743) (xy 426.778669 -318.420522) (xy 426.824481 -318.397179) (xy 426.87338 -318.381291)
			(xy 426.924162 -318.373248) (xy 426.975578 -318.373248) (xy 427.02636 -318.381291) (xy 427.075259 -318.397179)
			(xy 427.121071 -318.420522) (xy 427.162667 -318.450743) (xy 427.199023 -318.487099) (xy 427.229244 -318.528695)
			(xy 427.252587 -318.574507) (xy 427.268475 -318.623406) (xy 427.276518 -318.674188) (xy 427.277022 -318.699896)
			(xy 427.276518 -318.725604) (xy 428.523142 -318.725604) (xy 428.523142 -318.674188) (xy 428.531185 -318.623406)
			(xy 428.547073 -318.574507) (xy 428.570416 -318.528695) (xy 428.600637 -318.487099) (xy 428.636993 -318.450743)
			(xy 428.678589 -318.420522) (xy 428.724401 -318.397179) (xy 428.7733 -318.381291) (xy 428.824082 -318.373248)
			(xy 428.875498 -318.373248) (xy 428.92628 -318.381291) (xy 428.975179 -318.397179) (xy 429.020991 -318.420522)
			(xy 429.062587 -318.450743) (xy 429.098943 -318.487099) (xy 429.129164 -318.528695) (xy 429.152507 -318.574507)
			(xy 429.168395 -318.623406) (xy 429.176438 -318.674188) (xy 429.176942 -318.699896) (xy 429.176438 -318.725604)
			(xy 429.168395 -318.776386) (xy 429.152507 -318.825285) (xy 429.129164 -318.871097) (xy 429.098943 -318.912693)
			(xy 429.062587 -318.949049) (xy 429.020991 -318.97927) (xy 428.975179 -319.002613) (xy 428.92628 -319.018501)
			(xy 428.875498 -319.026544) (xy 428.824082 -319.026544) (xy 428.7733 -319.018501) (xy 428.724401 -319.002613)
			(xy 428.678589 -318.97927) (xy 428.636993 -318.949049) (xy 428.600637 -318.912693) (xy 428.570416 -318.871097)
			(xy 428.547073 -318.825285) (xy 428.531185 -318.776386) (xy 428.523142 -318.725604) (xy 427.276518 -318.725604)
			(xy 427.268475 -318.776386) (xy 427.252587 -318.825285) (xy 427.229244 -318.871097) (xy 427.199023 -318.912693)
			(xy 427.162667 -318.949049) (xy 427.121071 -318.97927) (xy 427.075259 -319.002613) (xy 427.02636 -319.018501)
			(xy 426.975578 -319.026544) (xy 426.924162 -319.026544) (xy 426.87338 -319.018501) (xy 426.824481 -319.002613)
			(xy 426.778669 -318.97927) (xy 426.737073 -318.949049) (xy 426.700717 -318.912693) (xy 426.670496 -318.871097)
			(xy 426.647153 -318.825285) (xy 426.631265 -318.776386) (xy 426.623222 -318.725604) (xy 425.376598 -318.725604)
			(xy 425.368555 -318.776386) (xy 425.352667 -318.825285) (xy 425.329324 -318.871097) (xy 425.299103 -318.912693)
			(xy 425.262747 -318.949049) (xy 425.221151 -318.97927) (xy 425.175339 -319.002613) (xy 425.12644 -319.018501)
			(xy 425.075658 -319.026544) (xy 425.024242 -319.026544) (xy 424.97346 -319.018501) (xy 424.924561 -319.002613)
			(xy 424.878749 -318.97927) (xy 424.837153 -318.949049) (xy 424.800797 -318.912693) (xy 424.770576 -318.871097)
			(xy 424.747233 -318.825285) (xy 424.731345 -318.776386) (xy 424.723302 -318.725604) (xy 423.476678 -318.725604)
			(xy 423.468635 -318.776386) (xy 423.452747 -318.825285) (xy 423.429404 -318.871097) (xy 423.399183 -318.912693)
			(xy 423.362827 -318.949049) (xy 423.321231 -318.97927) (xy 423.275419 -319.002613) (xy 423.22652 -319.018501)
			(xy 423.175738 -319.026544) (xy 423.124322 -319.026544) (xy 423.07354 -319.018501) (xy 423.024641 -319.002613)
			(xy 422.978829 -318.97927) (xy 422.937233 -318.949049) (xy 422.900877 -318.912693) (xy 422.870656 -318.871097)
			(xy 422.847313 -318.825285) (xy 422.831425 -318.776386) (xy 422.823382 -318.725604) (xy 422.53002 -318.725604)
			(xy 422.530015 -318.725884) (xy 422.521885 -318.77722) (xy 422.505824 -318.826652) (xy 422.482229 -318.872963)
			(xy 422.45168 -318.915013) (xy 422.414928 -318.951767) (xy 422.37288 -318.982319) (xy 422.32657 -319.005917)
			(xy 422.277139 -319.02198) (xy 422.225804 -319.030113) (xy 422.199816 -319.030604) (xy 422.1988 -319.030604)
			(xy 422.15181 -319.062354) (xy 422.136031 -319.10042) (xy 422.098913 -319.173997) (xy 422.055696 -319.244164)
			(xy 422.006689 -319.310418) (xy 421.952245 -319.372282) (xy 421.892756 -319.42931) (xy 421.86098 -319.455546)
			(xy 421.85258 -319.463162) (xy 421.842825 -319.483596) (xy 421.842184 -319.494916) (xy 421.842184 -319.74917)
			(xy 421.845486 -319.75806) (xy 421.861742 -319.801319) (xy 421.887119 -319.890186) (xy 421.904173 -319.981019)
			(xy 421.912758 -320.073039) (xy 421.913304 -320.119248) (xy 421.913304 -320.996459) (xy 433.285636 -320.996459)
			(xy 433.285636 -320.803629) (xy 433.293605 -320.610963) (xy 433.309528 -320.41879) (xy 433.33338 -320.22744)
			(xy 433.365119 -320.037239) (xy 433.404691 -319.848513) (xy 433.452028 -319.661583) (xy 433.50705 -319.476768)
			(xy 433.569662 -319.294385) (xy 433.639757 -319.114746) (xy 433.717217 -318.938157) (xy 433.801907 -318.764919)
			(xy 433.893685 -318.59533) (xy 433.992392 -318.429678) (xy 434.09786 -318.268246) (xy 434.20991 -318.111311)
			(xy 434.328349 -317.95914) (xy 434.452975 -317.811994) (xy 434.583576 -317.670124) (xy 434.719928 -317.533772)
			(xy 434.861798 -317.403171) (xy 435.008944 -317.278545) (xy 435.161115 -317.160106) (xy 435.31805 -317.048056)
			(xy 435.479482 -316.942588) (xy 435.645134 -316.843881) (xy 435.814723 -316.752103) (xy 435.987961 -316.667413)
			(xy 436.16455 -316.589953) (xy 436.344189 -316.519858) (xy 436.526572 -316.457246) (xy 436.711387 -316.402224)
			(xy 436.898317 -316.354887) (xy 437.087043 -316.315315) (xy 437.277244 -316.283576) (xy 437.468594 -316.259724)
			(xy 437.660767 -316.243801) (xy 437.853433 -316.235832) (xy 438.046263 -316.235832) (xy 438.238929 -316.243801)
			(xy 438.431102 -316.259724) (xy 438.622452 -316.283576) (xy 438.812653 -316.315315) (xy 439.001379 -316.354887)
			(xy 439.188309 -316.402224) (xy 439.373124 -316.457246) (xy 439.555507 -316.519858) (xy 439.735146 -316.589953)
			(xy 439.911735 -316.667413) (xy 440.084973 -316.752103) (xy 440.254562 -316.843881) (xy 440.420214 -316.942588)
			(xy 440.581646 -317.048056) (xy 440.738581 -317.160106) (xy 440.890752 -317.278545) (xy 441.037898 -317.403171)
			(xy 441.179768 -317.533772) (xy 441.31612 -317.670124) (xy 441.446721 -317.811994) (xy 441.571347 -317.95914)
			(xy 441.689786 -318.111311) (xy 441.801836 -318.268246) (xy 441.907304 -318.429678) (xy 442.006011 -318.59533)
			(xy 442.097789 -318.764919) (xy 442.182479 -318.938157) (xy 442.259939 -319.114746) (xy 442.330034 -319.294385)
			(xy 442.392646 -319.476768) (xy 442.447668 -319.661583) (xy 442.495005 -319.848513) (xy 442.534577 -320.037239)
			(xy 442.566316 -320.22744) (xy 442.590168 -320.41879) (xy 442.606091 -320.610963) (xy 442.61406 -320.803629)
			(xy 442.614558 -320.900044) (xy 442.61406 -320.996459) (xy 442.606091 -321.189125) (xy 442.590168 -321.381298)
			(xy 442.566316 -321.572648) (xy 442.534577 -321.762849) (xy 442.495005 -321.951575) (xy 442.447668 -322.138505)
			(xy 442.392646 -322.32332) (xy 442.330034 -322.505703) (xy 442.259939 -322.685342) (xy 442.182479 -322.861931)
			(xy 442.097789 -323.035169) (xy 442.006011 -323.204758) (xy 441.907304 -323.37041) (xy 441.801836 -323.531842)
			(xy 441.689786 -323.688777) (xy 441.571347 -323.840948) (xy 441.446721 -323.988094) (xy 441.31612 -324.129964)
			(xy 441.179768 -324.266316) (xy 441.037898 -324.396917) (xy 440.890752 -324.521543) (xy 440.738581 -324.639982)
			(xy 440.581646 -324.752032) (xy 440.420214 -324.8575) (xy 440.254562 -324.956207) (xy 440.084973 -325.047985)
			(xy 439.911735 -325.132675) (xy 439.735146 -325.210135) (xy 439.555507 -325.28023) (xy 439.373124 -325.342842)
			(xy 439.188309 -325.397864) (xy 439.001379 -325.445201) (xy 438.812653 -325.484773) (xy 438.622452 -325.516512)
			(xy 438.431102 -325.540364) (xy 438.238929 -325.556287) (xy 438.046263 -325.564256) (xy 437.853433 -325.564256)
			(xy 437.660767 -325.556287) (xy 437.468594 -325.540364) (xy 437.277244 -325.516512) (xy 437.087043 -325.484773)
			(xy 436.898317 -325.445201) (xy 436.711387 -325.397864) (xy 436.526572 -325.342842) (xy 436.344189 -325.28023)
			(xy 436.16455 -325.210135) (xy 435.987961 -325.132675) (xy 435.814723 -325.047985) (xy 435.645134 -324.956207)
			(xy 435.479482 -324.8575) (xy 435.31805 -324.752032) (xy 435.161115 -324.639982) (xy 435.008944 -324.521543)
			(xy 434.861798 -324.396917) (xy 434.719928 -324.266316) (xy 434.583576 -324.129964) (xy 434.452975 -323.988094)
			(xy 434.328349 -323.840948) (xy 434.20991 -323.688777) (xy 434.09786 -323.531842) (xy 433.992392 -323.37041)
			(xy 433.893685 -323.204758) (xy 433.801907 -323.035169) (xy 433.717217 -322.861931) (xy 433.639757 -322.685342)
			(xy 433.569662 -322.505703) (xy 433.50705 -322.32332) (xy 433.452028 -322.138505) (xy 433.404691 -321.951575)
			(xy 433.365119 -321.762849) (xy 433.33338 -321.572648) (xy 433.309528 -321.381298) (xy 433.293605 -321.189125)
			(xy 433.285636 -320.996459) (xy 421.913304 -320.996459) (xy 421.913304 -323.587872) (xy 421.912861 -323.630251)
			(xy 421.905655 -323.714702) (xy 421.891301 -323.798236) (xy 421.869903 -323.880249) (xy 421.841615 -323.960147)
			(xy 421.806643 -324.037354) (xy 421.786304 -324.074536) (xy 419.76421 -327.690988) (xy 419.7498 -327.716415)
			(xy 419.718411 -327.765723) (xy 419.701472 -327.78954) (xy 418.186053 -329.880976) (xy 459.363064 -329.880976)
			(xy 459.363527 -329.854662) (xy 459.370764 -329.802534) (xy 459.385085 -329.751891) (xy 459.406218 -329.703693)
			(xy 459.433765 -329.658849) (xy 459.467203 -329.618209) (xy 459.486254 -329.600052) (xy 459.493672 -329.592544)
			(xy 459.502188 -329.573254) (xy 459.502764 -329.562714) (xy 459.502764 -329.488038) (xy 459.502238 -329.477488)
			(xy 459.493702 -329.458192) (xy 459.486254 -329.4507) (xy 459.467197 -329.432546) (xy 459.433741 -329.391915)
			(xy 459.406184 -329.347074) (xy 459.385046 -329.298873) (xy 459.370729 -329.248226) (xy 459.363503 -329.196092)
			(xy 459.363064 -329.169776) (xy 459.363555 -329.142525) (xy 459.371314 -329.088579) (xy 459.386671 -329.036286)
			(xy 459.409313 -328.986711) (xy 459.438779 -328.940862) (xy 459.47447 -328.899673) (xy 459.515659 -328.863982)
			(xy 459.561507 -328.834515) (xy 459.611083 -328.811873) (xy 459.663375 -328.796515) (xy 459.717321 -328.788756)
			(xy 459.744572 -328.788268) (xy 459.770887 -328.788698) (xy 459.823017 -328.795942) (xy 459.87366 -328.810269)
			(xy 459.921858 -328.831408) (xy 459.966701 -328.858961) (xy 460.00734 -328.892404) (xy 460.025496 -328.911458)
			(xy 460.033023 -328.918853) (xy 460.052299 -328.927383) (xy 460.062834 -328.927968) (xy 460.13751 -328.927968)
			(xy 460.148063 -328.927467) (xy 460.167359 -328.918913) (xy 460.174848 -328.911458) (xy 460.194668 -328.89067)
			(xy 460.23944 -328.854695) (xy 460.289098 -328.825835) (xy 460.34252 -328.804742) (xy 460.398499 -328.791893)
			(xy 460.455772 -328.787578) (xy 460.513045 -328.791893) (xy 460.569024 -328.804742) (xy 460.622446 -328.825835)
			(xy 460.672104 -328.854695) (xy 460.716876 -328.89067) (xy 460.736696 -328.911458) (xy 460.744223 -328.918853)
			(xy 460.763499 -328.927383) (xy 460.774034 -328.927968) (xy 460.84871 -328.927968) (xy 460.859263 -328.927467)
			(xy 460.878559 -328.918913) (xy 460.886048 -328.911458) (xy 460.904179 -328.892378) (xy 460.944815 -328.858925)
			(xy 460.989661 -328.83137) (xy 461.037866 -328.810236) (xy 461.088517 -328.795924) (xy 461.140655 -328.788704)
			(xy 461.166972 -328.788268) (xy 461.194223 -328.788781) (xy 461.248171 -328.796534) (xy 461.300466 -328.811885)
			(xy 461.350045 -328.834523) (xy 461.395897 -328.863985) (xy 461.437089 -328.899674) (xy 461.472783 -328.940861)
			(xy 461.502252 -328.986709) (xy 461.524897 -329.036285) (xy 461.540255 -329.088578) (xy 461.548015 -329.142525)
			(xy 461.54848 -329.169776) (xy 461.548003 -329.19609) (xy 461.540771 -329.248218) (xy 461.526454 -329.298861)
			(xy 461.505324 -329.34706) (xy 461.477779 -329.391904) (xy 461.444341 -329.432543) (xy 461.42529 -329.4507)
			(xy 461.417885 -329.458218) (xy 461.409363 -329.477501) (xy 461.40878 -329.488038) (xy 461.40878 -329.562714)
			(xy 461.409294 -329.573265) (xy 461.41784 -329.59256) (xy 461.42529 -329.600052) (xy 461.444362 -329.618191)
			(xy 461.477818 -329.658824) (xy 461.505375 -329.703668) (xy 461.526511 -329.751872) (xy 461.540824 -329.802522)
			(xy 461.548044 -329.854659) (xy 461.54848 -329.880976) (xy 461.548022 -329.90823) (xy 461.540268 -329.962182)
			(xy 461.524913 -330.014482) (xy 461.502272 -330.064064) (xy 461.472804 -330.109918) (xy 461.437109 -330.151112)
			(xy 461.395915 -330.186806) (xy 461.35006 -330.216274) (xy 461.300478 -330.238915) (xy 461.248178 -330.254269)
			(xy 461.194226 -330.262023) (xy 461.166972 -330.262484) (xy 461.140657 -330.26204) (xy 461.088527 -330.254801)
			(xy 461.037884 -330.240478) (xy 460.989685 -330.219341) (xy 460.944842 -330.191791) (xy 460.904204 -330.158348)
			(xy 460.886048 -330.139294) (xy 460.878548 -330.131867) (xy 460.859252 -330.123357) (xy 460.84871 -330.122784)
			(xy 460.774034 -330.122784) (xy 460.763486 -330.123323) (xy 460.74419 -330.131852) (xy 460.736696 -330.139294)
			(xy 460.716876 -330.160082) (xy 460.672104 -330.196057) (xy 460.622446 -330.224917) (xy 460.569024 -330.24601)
			(xy 460.513045 -330.258859) (xy 460.455772 -330.263174) (xy 460.398499 -330.258859) (xy 460.34252 -330.24601)
			(xy 460.289098 -330.224917) (xy 460.23944 -330.196057) (xy 460.194668 -330.160082) (xy 460.174848 -330.139294)
			(xy 460.167348 -330.131867) (xy 460.148052 -330.123357) (xy 460.13751 -330.122784) (xy 460.062834 -330.122784)
			(xy 460.052286 -330.123323) (xy 460.03299 -330.131852) (xy 460.025496 -330.139294) (xy 460.007334 -330.158343)
			(xy 459.966706 -330.191801) (xy 459.921867 -330.219361) (xy 459.873667 -330.240501) (xy 459.823021 -330.254819)
			(xy 459.770888 -330.262045) (xy 459.744572 -330.262484) (xy 459.717319 -330.262048) (xy 459.663368 -330.254287)
			(xy 459.611071 -330.238927) (xy 459.561492 -330.216281) (xy 459.515641 -330.18681) (xy 459.47445 -330.151113)
			(xy 459.438759 -330.109918) (xy 459.409294 -330.064062) (xy 459.386654 -330.01448) (xy 459.371302 -329.962181)
			(xy 459.363548 -329.908229) (xy 459.363064 -329.880976) (xy 418.186053 -329.880976) (xy 415.253678 -333.927958)
			(xy 415.249238 -333.934644) (xy 415.244313 -333.94991) (xy 415.244026 -333.95793) (xy 415.244026 -335.695544)
			(xy 415.243596 -335.705611) (xy 415.235873 -335.724207) (xy 415.22904 -335.731612) (xy 412.220156 -338.740496)
			(xy 412.213303 -338.747892) (xy 412.205558 -338.76649) (xy 412.20517 -338.776564) (xy 412.20517 -341.966042)
			(xy 412.20578 -341.977368) (xy 412.215551 -341.997804) (xy 412.223966 -342.005412) (xy 412.293816 -342.062562)
			(xy 412.31566 -342.067896) (xy 412.32709 -342.06561) (xy 412.346116 -342.061921) (xy 412.384673 -342.057972)
			(xy 412.404052 -342.057736) (xy 413.267652 -342.057736) (xy 413.294925 -342.058196) (xy 413.348918 -342.065953)
			(xy 413.401256 -342.081315) (xy 413.450876 -342.10397) (xy 413.496766 -342.133456) (xy 413.537992 -342.169174)
			(xy 413.573715 -342.210396) (xy 413.603207 -342.256282) (xy 413.625868 -342.305899) (xy 413.641237 -342.358235)
			(xy 413.649 -342.412227) (xy 413.649 -342.466772) (xy 415.1317 -342.466772) (xy 415.1317 -342.412228)
			(xy 415.139462 -342.35824) (xy 415.154829 -342.305906) (xy 415.177488 -342.256292) (xy 415.206976 -342.210407)
			(xy 415.242695 -342.169187) (xy 415.283917 -342.133469) (xy 415.329803 -342.103982) (xy 415.379417 -342.081325)
			(xy 415.431752 -342.065959) (xy 415.48574 -342.058199) (xy 415.513012 -342.057736) (xy 416.376612 -342.057736)
			(xy 416.403881 -342.058227) (xy 416.457863 -342.06599) (xy 416.510191 -342.081357) (xy 416.559799 -342.104013)
			(xy 416.605678 -342.133499) (xy 416.646894 -342.169214) (xy 416.682608 -342.210432) (xy 416.712092 -342.256312)
			(xy 416.734748 -342.305921) (xy 416.750112 -342.358249) (xy 416.757874 -342.412231) (xy 416.757874 -342.466768)
			(xy 418.240722 -342.466768) (xy 418.240722 -342.412232) (xy 418.248483 -342.35825) (xy 418.263847 -342.305923)
			(xy 418.286502 -342.256314) (xy 418.315985 -342.210434) (xy 418.351697 -342.169217) (xy 418.392912 -342.133502)
			(xy 418.43879 -342.104015) (xy 418.488396 -342.081357) (xy 418.540723 -342.065989) (xy 418.594704 -342.058224)
			(xy 418.621972 -342.057736) (xy 419.485572 -342.057736) (xy 419.512844 -342.058202) (xy 419.566834 -342.06596)
			(xy 419.61917 -342.081324) (xy 419.668786 -342.10398) (xy 419.714673 -342.133467) (xy 419.755896 -342.169184)
			(xy 419.791616 -342.210405) (xy 419.821107 -342.256289) (xy 419.843766 -342.305904) (xy 419.859134 -342.358239)
			(xy 419.866896 -342.412228) (xy 419.866896 -342.466772) (xy 419.866896 -342.466773) (xy 421.3496 -342.466773)
			(xy 421.3496 -342.412227) (xy 421.357363 -342.358237) (xy 421.372731 -342.305902) (xy 421.395391 -342.256286)
			(xy 421.424881 -342.210401) (xy 421.460602 -342.16918) (xy 421.501827 -342.133462) (xy 421.547715 -342.103975)
			(xy 421.597332 -342.081319) (xy 421.649669 -342.065956) (xy 421.703659 -342.058197) (xy 421.730932 -342.057736)
			(xy 422.594532 -342.057736) (xy 422.6218 -342.058229) (xy 422.67578 -342.065994) (xy 422.728105 -342.081362)
			(xy 422.777711 -342.10402) (xy 422.823588 -342.133506) (xy 422.864801 -342.169222) (xy 422.900513 -342.210438)
			(xy 422.929995 -342.256317) (xy 422.952649 -342.305925) (xy 422.968013 -342.358252) (xy 422.975774 -342.412232)
			(xy 422.975774 -342.466768) (xy 422.975774 -342.466769) (xy 424.458622 -342.466769) (xy 424.458622 -342.412231)
			(xy 424.466384 -342.358248) (xy 424.481749 -342.305918) (xy 424.504405 -342.256309) (xy 424.53389 -342.210428)
			(xy 424.569605 -342.16921) (xy 424.610821 -342.133495) (xy 424.656702 -342.104009) (xy 424.706311 -342.081352)
			(xy 424.75864 -342.065986) (xy 424.812623 -342.058223) (xy 424.839892 -342.057736) (xy 425.703492 -342.057736)
			(xy 425.730763 -342.058203) (xy 425.784751 -342.065964) (xy 425.837084 -342.08133) (xy 425.886698 -342.103987)
			(xy 425.932582 -342.133474) (xy 425.973803 -342.169191) (xy 426.009521 -342.210411) (xy 426.03901 -342.256295)
			(xy 426.061668 -342.305908) (xy 426.077034 -342.358241) (xy 426.084796 -342.412229) (xy 426.084796 -342.466767)
			(xy 427.567622 -342.466767) (xy 427.567622 -342.412233) (xy 427.575383 -342.358253) (xy 427.590746 -342.305927)
			(xy 427.613399 -342.25632) (xy 427.64288 -342.210441) (xy 427.67859 -342.169224) (xy 427.719802 -342.133509)
			(xy 427.765678 -342.104022) (xy 427.815282 -342.081363) (xy 427.867606 -342.065993) (xy 427.921585 -342.058226)
			(xy 427.948852 -342.057736) (xy 428.812452 -342.057736) (xy 428.839725 -342.0582) (xy 428.893717 -342.065957)
			(xy 428.946055 -342.081319) (xy 428.995674 -342.103974) (xy 429.041563 -342.13346) (xy 429.082789 -342.169177)
			(xy 429.118512 -342.210398) (xy 429.148003 -342.256284) (xy 429.170664 -342.3059) (xy 429.186033 -342.358236)
			(xy 429.193796 -342.412227) (xy 429.193796 -342.466772) (xy 430.6765 -342.466772) (xy 430.6765 -342.412228)
			(xy 430.684262 -342.35824) (xy 430.699629 -342.305906) (xy 430.722288 -342.256292) (xy 430.751776 -342.210407)
			(xy 430.787495 -342.169187) (xy 430.828717 -342.133469) (xy 430.874603 -342.103982) (xy 430.924217 -342.081325)
			(xy 430.976552 -342.065959) (xy 431.03054 -342.058199) (xy 431.057812 -342.057736) (xy 431.921412 -342.057736)
			(xy 431.948681 -342.058227) (xy 432.002663 -342.06599) (xy 432.054991 -342.081357) (xy 432.104599 -342.104013)
			(xy 432.150478 -342.133499) (xy 432.191694 -342.169214) (xy 432.227408 -342.210432) (xy 432.256892 -342.256312)
			(xy 432.279548 -342.305921) (xy 432.294912 -342.358249) (xy 432.302674 -342.412231) (xy 432.302674 -342.466768)
			(xy 433.785522 -342.466768) (xy 433.785522 -342.412232) (xy 433.793283 -342.35825) (xy 433.808647 -342.305923)
			(xy 433.831302 -342.256314) (xy 433.860785 -342.210434) (xy 433.896497 -342.169217) (xy 433.937712 -342.133502)
			(xy 433.98359 -342.104015) (xy 434.033196 -342.081357) (xy 434.085523 -342.065989) (xy 434.139504 -342.058224)
			(xy 434.166772 -342.057736) (xy 435.030372 -342.057736) (xy 435.057644 -342.058202) (xy 435.111634 -342.06596)
			(xy 435.16397 -342.081324) (xy 435.213586 -342.10398) (xy 435.259473 -342.133467) (xy 435.300696 -342.169184)
			(xy 435.336416 -342.210405) (xy 435.365907 -342.256289) (xy 435.388566 -342.305904) (xy 435.403934 -342.358239)
			(xy 435.411696 -342.412228) (xy 435.411696 -342.466772) (xy 435.411696 -342.466773) (xy 436.8944 -342.466773)
			(xy 436.8944 -342.412227) (xy 436.902163 -342.358237) (xy 436.917531 -342.305902) (xy 436.940191 -342.256286)
			(xy 436.969681 -342.210401) (xy 437.005402 -342.16918) (xy 437.046627 -342.133462) (xy 437.092515 -342.103975)
			(xy 437.142132 -342.081319) (xy 437.194469 -342.065956) (xy 437.248459 -342.058197) (xy 437.275732 -342.057736)
			(xy 438.139332 -342.057736) (xy 438.1666 -342.058229) (xy 438.22058 -342.065994) (xy 438.272905 -342.081362)
			(xy 438.322511 -342.10402) (xy 438.368388 -342.133506) (xy 438.409601 -342.169222) (xy 438.445313 -342.210438)
			(xy 438.474795 -342.256317) (xy 438.497449 -342.305925) (xy 438.512813 -342.358252) (xy 438.520574 -342.412232)
			(xy 438.520574 -342.466768) (xy 438.520574 -342.466769) (xy 440.003422 -342.466769) (xy 440.003422 -342.412231)
			(xy 440.011184 -342.358248) (xy 440.026549 -342.305918) (xy 440.049205 -342.256309) (xy 440.07869 -342.210428)
			(xy 440.114405 -342.16921) (xy 440.155621 -342.133495) (xy 440.201502 -342.104009) (xy 440.251111 -342.081352)
			(xy 440.30344 -342.065986) (xy 440.357423 -342.058223) (xy 440.384692 -342.057736) (xy 441.248292 -342.057736)
			(xy 441.275563 -342.058203) (xy 441.329551 -342.065964) (xy 441.381884 -342.08133) (xy 441.431498 -342.103987)
			(xy 441.477382 -342.133474) (xy 441.518603 -342.169191) (xy 441.554321 -342.210411) (xy 441.58381 -342.256295)
			(xy 441.606468 -342.305908) (xy 441.621834 -342.358241) (xy 441.629596 -342.412229) (xy 441.629596 -342.466771)
			(xy 441.621834 -342.520759) (xy 441.606468 -342.573092) (xy 441.58381 -342.622705) (xy 441.554321 -342.668589)
			(xy 441.518603 -342.709809) (xy 441.477382 -342.745526) (xy 441.431498 -342.775013) (xy 441.381884 -342.79767)
			(xy 441.329551 -342.813036) (xy 441.275563 -342.820797) (xy 441.248292 -342.82126) (xy 440.384692 -342.82126)
			(xy 440.357423 -342.820777) (xy 440.30344 -342.813014) (xy 440.251111 -342.797648) (xy 440.201502 -342.774991)
			(xy 440.155621 -342.745505) (xy 440.114405 -342.70979) (xy 440.07869 -342.668572) (xy 440.049205 -342.622691)
			(xy 440.026549 -342.573082) (xy 440.011184 -342.520752) (xy 440.003422 -342.466769) (xy 438.520574 -342.466769)
			(xy 438.512813 -342.520748) (xy 438.497449 -342.573075) (xy 438.474795 -342.622683) (xy 438.445313 -342.668562)
			(xy 438.409601 -342.709778) (xy 438.368388 -342.745494) (xy 438.322511 -342.77498) (xy 438.272905 -342.797638)
			(xy 438.22058 -342.813006) (xy 438.1666 -342.820771) (xy 438.139332 -342.82126) (xy 437.275732 -342.82126)
			(xy 437.248459 -342.820803) (xy 437.194469 -342.813044) (xy 437.142132 -342.797681) (xy 437.092515 -342.775025)
			(xy 437.046627 -342.745538) (xy 437.005402 -342.70982) (xy 436.969681 -342.668599) (xy 436.940191 -342.622714)
			(xy 436.917531 -342.573098) (xy 436.902163 -342.520763) (xy 436.8944 -342.466773) (xy 435.411696 -342.466773)
			(xy 435.403934 -342.520761) (xy 435.388566 -342.573096) (xy 435.365907 -342.622711) (xy 435.336416 -342.668595)
			(xy 435.300696 -342.709816) (xy 435.259473 -342.745533) (xy 435.213586 -342.77502) (xy 435.16397 -342.797676)
			(xy 435.111634 -342.81304) (xy 435.057644 -342.820798) (xy 435.030372 -342.82126) (xy 434.166772 -342.82126)
			(xy 434.139504 -342.820776) (xy 434.085523 -342.813011) (xy 434.033196 -342.797643) (xy 433.98359 -342.774985)
			(xy 433.937712 -342.745498) (xy 433.896497 -342.709783) (xy 433.860785 -342.668566) (xy 433.831302 -342.622686)
			(xy 433.808647 -342.573077) (xy 433.793283 -342.52075) (xy 433.785522 -342.466768) (xy 432.302674 -342.466768)
			(xy 432.302674 -342.466769) (xy 432.294912 -342.520751) (xy 432.279548 -342.573079) (xy 432.256892 -342.622688)
			(xy 432.227408 -342.668568) (xy 432.191694 -342.709786) (xy 432.150478 -342.745501) (xy 432.104599 -342.774987)
			(xy 432.054991 -342.797643) (xy 432.002663 -342.81301) (xy 431.948681 -342.820773) (xy 431.921412 -342.82126)
			(xy 431.057812 -342.82126) (xy 431.03054 -342.820801) (xy 430.976552 -342.813041) (xy 430.924217 -342.797675)
			(xy 430.874603 -342.775018) (xy 430.828717 -342.745531) (xy 430.787495 -342.709813) (xy 430.751776 -342.668593)
			(xy 430.722288 -342.622708) (xy 430.699629 -342.573094) (xy 430.684262 -342.52076) (xy 430.6765 -342.466772)
			(xy 429.193796 -342.466772) (xy 429.193796 -342.466773) (xy 429.186033 -342.520764) (xy 429.170664 -342.5731)
			(xy 429.148003 -342.622716) (xy 429.118512 -342.668602) (xy 429.082789 -342.709823) (xy 429.041563 -342.74554)
			(xy 428.995674 -342.775026) (xy 428.946055 -342.797681) (xy 428.893717 -342.813043) (xy 428.839725 -342.8208)
			(xy 428.812452 -342.82126) (xy 427.948852 -342.82126) (xy 427.921585 -342.820774) (xy 427.867606 -342.813007)
			(xy 427.815282 -342.797637) (xy 427.765678 -342.774978) (xy 427.719802 -342.745491) (xy 427.67859 -342.709776)
			(xy 427.64288 -342.668559) (xy 427.613399 -342.62268) (xy 427.590746 -342.573073) (xy 427.575383 -342.520747)
			(xy 427.567622 -342.466767) (xy 426.084796 -342.466767) (xy 426.084796 -342.466771) (xy 426.077034 -342.520759)
			(xy 426.061668 -342.573092) (xy 426.03901 -342.622705) (xy 426.009521 -342.668589) (xy 425.973803 -342.709809)
			(xy 425.932582 -342.745526) (xy 425.886698 -342.775013) (xy 425.837084 -342.79767) (xy 425.784751 -342.813036)
			(xy 425.730763 -342.820797) (xy 425.703492 -342.82126) (xy 424.839892 -342.82126) (xy 424.812623 -342.820777)
			(xy 424.75864 -342.813014) (xy 424.706311 -342.797648) (xy 424.656702 -342.774991) (xy 424.610821 -342.745505)
			(xy 424.569605 -342.70979) (xy 424.53389 -342.668572) (xy 424.504405 -342.622691) (xy 424.481749 -342.573082)
			(xy 424.466384 -342.520752) (xy 424.458622 -342.466769) (xy 422.975774 -342.466769) (xy 422.968013 -342.520748)
			(xy 422.952649 -342.573075) (xy 422.929995 -342.622683) (xy 422.900513 -342.668562) (xy 422.864801 -342.709778)
			(xy 422.823588 -342.745494) (xy 422.777711 -342.77498) (xy 422.728105 -342.797638) (xy 422.67578 -342.813006)
			(xy 422.6218 -342.820771) (xy 422.594532 -342.82126) (xy 421.730932 -342.82126) (xy 421.703659 -342.820803)
			(xy 421.649669 -342.813044) (xy 421.597332 -342.797681) (xy 421.547715 -342.775025) (xy 421.501827 -342.745538)
			(xy 421.460602 -342.70982) (xy 421.424881 -342.668599) (xy 421.395391 -342.622714) (xy 421.372731 -342.573098)
			(xy 421.357363 -342.520763) (xy 421.3496 -342.466773) (xy 419.866896 -342.466773) (xy 419.859134 -342.520761)
			(xy 419.843766 -342.573096) (xy 419.821107 -342.622711) (xy 419.791616 -342.668595) (xy 419.755896 -342.709816)
			(xy 419.714673 -342.745533) (xy 419.668786 -342.77502) (xy 419.61917 -342.797676) (xy 419.566834 -342.81304)
			(xy 419.512844 -342.820798) (xy 419.485572 -342.82126) (xy 418.621972 -342.82126) (xy 418.594704 -342.820776)
			(xy 418.540723 -342.813011) (xy 418.488396 -342.797643) (xy 418.43879 -342.774985) (xy 418.392912 -342.745498)
			(xy 418.351697 -342.709783) (xy 418.315985 -342.668566) (xy 418.286502 -342.622686) (xy 418.263847 -342.573077)
			(xy 418.248483 -342.52075) (xy 418.240722 -342.466768) (xy 416.757874 -342.466768) (xy 416.757874 -342.466769)
			(xy 416.750112 -342.520751) (xy 416.734748 -342.573079) (xy 416.712092 -342.622688) (xy 416.682608 -342.668568)
			(xy 416.646894 -342.709786) (xy 416.605678 -342.745501) (xy 416.559799 -342.774987) (xy 416.510191 -342.797643)
			(xy 416.457863 -342.81301) (xy 416.403881 -342.820773) (xy 416.376612 -342.82126) (xy 415.513012 -342.82126)
			(xy 415.48574 -342.820801) (xy 415.431752 -342.813041) (xy 415.379417 -342.797675) (xy 415.329803 -342.775018)
			(xy 415.283917 -342.745531) (xy 415.242695 -342.709813) (xy 415.206976 -342.668593) (xy 415.177488 -342.622708)
			(xy 415.154829 -342.573094) (xy 415.139462 -342.52076) (xy 415.1317 -342.466772) (xy 413.649 -342.466772)
			(xy 413.649 -342.466773) (xy 413.641237 -342.520765) (xy 413.625868 -342.573101) (xy 413.603207 -342.622718)
			(xy 413.573715 -342.668604) (xy 413.537992 -342.709826) (xy 413.496766 -342.745544) (xy 413.450876 -342.77503)
			(xy 413.401256 -342.797685) (xy 413.348918 -342.813047) (xy 413.294925 -342.820804) (xy 413.267652 -342.82126)
			(xy 412.404052 -342.82126) (xy 412.384674 -342.820999) (xy 412.34612 -342.817052) (xy 412.32709 -342.813386)
			(xy 412.31566 -342.8111) (xy 412.293816 -342.816434) (xy 412.223966 -342.873584) (xy 412.215558 -342.881197)
			(xy 412.205781 -342.901631) (xy 412.20517 -342.912954) (xy 412.20517 -344.99169) (xy 412.205769 -345.003022)
			(xy 412.215528 -345.023474) (xy 412.223966 -345.03106) (xy 412.293816 -345.08821) (xy 412.31566 -345.093544)
			(xy 412.32709 -345.091258) (xy 412.346116 -345.087568) (xy 412.384673 -345.083619) (xy 412.404052 -345.083384)
			(xy 413.267652 -345.083384) (xy 413.294922 -345.083844) (xy 413.348908 -345.0916) (xy 413.40124 -345.10696)
			(xy 413.450853 -345.129612) (xy 413.496737 -345.159095) (xy 413.537958 -345.194808) (xy 413.573676 -345.236024)
			(xy 413.603165 -345.281905) (xy 413.625823 -345.331515) (xy 413.64119 -345.383846) (xy 413.648952 -345.43783)
			(xy 413.648952 -345.492368) (xy 415.131747 -345.492368) (xy 415.131747 -345.437832) (xy 415.139509 -345.38385)
			(xy 415.154874 -345.331523) (xy 415.17753 -345.281915) (xy 415.207015 -345.236036) (xy 415.242729 -345.194821)
			(xy 415.283946 -345.159108) (xy 415.329826 -345.129624) (xy 415.379434 -345.10697) (xy 415.431762 -345.091606)
			(xy 415.485744 -345.083847) (xy 415.513012 -345.083384) (xy 416.376612 -345.083384) (xy 416.403884 -345.083779)
			(xy 416.457873 -345.091543) (xy 416.510207 -345.106912) (xy 416.559822 -345.129571) (xy 416.605707 -345.159061)
			(xy 416.646928 -345.194781) (xy 416.682646 -345.236003) (xy 416.712135 -345.281889) (xy 416.734793 -345.331504)
			(xy 416.750159 -345.383839) (xy 416.757921 -345.437828) (xy 416.757921 -345.492365) (xy 418.24077 -345.492365)
			(xy 418.24077 -345.437835) (xy 418.24853 -345.383861) (xy 418.263892 -345.33154) (xy 418.286544 -345.281937)
			(xy 418.316023 -345.236063) (xy 418.351731 -345.194851) (xy 418.392941 -345.15914) (xy 418.438813 -345.129657)
			(xy 418.488413 -345.107002) (xy 418.540733 -345.091636) (xy 418.594707 -345.083872) (xy 418.621972 -345.083384)
			(xy 419.485572 -345.083384) (xy 419.512848 -345.083754) (xy 419.566844 -345.091514) (xy 419.619186 -345.106879)
			(xy 419.668809 -345.129538) (xy 419.714702 -345.159028) (xy 419.75593 -345.19475) (xy 419.791655 -345.235976)
			(xy 419.821149 -345.281866) (xy 419.843811 -345.331487) (xy 419.859181 -345.383829) (xy 419.866944 -345.437824)
			(xy 419.866944 -345.492369) (xy 421.349647 -345.492369) (xy 421.349647 -345.437831) (xy 421.35741 -345.383848)
			(xy 421.372776 -345.331519) (xy 421.395433 -345.281909) (xy 421.42492 -345.23603) (xy 421.460636 -345.194814)
			(xy 421.501855 -345.159101) (xy 421.547738 -345.129617) (xy 421.597349 -345.106964) (xy 421.649679 -345.091603)
			(xy 421.703663 -345.083845) (xy 421.730932 -345.083384) (xy 422.594532 -345.083384) (xy 422.621803 -345.083781)
			(xy 422.67579 -345.091547) (xy 422.728122 -345.106917) (xy 422.777734 -345.129578) (xy 422.823616 -345.159068)
			(xy 422.864835 -345.194788) (xy 422.900551 -345.236009) (xy 422.930038 -345.281894) (xy 422.952694 -345.331508)
			(xy 422.96806 -345.383842) (xy 422.975822 -345.437829) (xy 422.975822 -345.492366) (xy 424.45867 -345.492366)
			(xy 424.45867 -345.437834) (xy 424.466431 -345.383858) (xy 424.481794 -345.331535) (xy 424.504447 -345.281932)
			(xy 424.533928 -345.236057) (xy 424.569638 -345.194844) (xy 424.61085 -345.159133) (xy 424.656725 -345.129651)
			(xy 424.706328 -345.106997) (xy 424.75865 -345.091633) (xy 424.812626 -345.083871) (xy 424.839892 -345.083384)
			(xy 425.703492 -345.083384) (xy 425.730767 -345.083755) (xy 425.784761 -345.091517) (xy 425.837101 -345.106885)
			(xy 425.886721 -345.129544) (xy 425.932611 -345.159035) (xy 425.973837 -345.194757) (xy 426.00956 -345.235982)
			(xy 426.039052 -345.281872) (xy 426.061713 -345.331492) (xy 426.077081 -345.383831) (xy 426.084844 -345.437825)
			(xy 426.084844 -345.492364) (xy 427.56767 -345.492364) (xy 427.56767 -345.437836) (xy 427.57543 -345.383863)
			(xy 427.590791 -345.331544) (xy 427.613441 -345.281943) (xy 427.642919 -345.23607) (xy 427.678624 -345.194858)
			(xy 427.719831 -345.159147) (xy 427.765701 -345.129664) (xy 427.815299 -345.107008) (xy 427.867616 -345.09164)
			(xy 427.921588 -345.083874) (xy 427.948852 -345.083384) (xy 428.812452 -345.083384) (xy 428.839729 -345.083752)
			(xy 428.893727 -345.09151) (xy 428.946072 -345.106874) (xy 428.995697 -345.129531) (xy 429.041592 -345.159021)
			(xy 429.082823 -345.194743) (xy 429.11855 -345.235969) (xy 429.148046 -345.281861) (xy 429.170709 -345.331483)
			(xy 429.18608 -345.383826) (xy 429.193844 -345.437824) (xy 429.193844 -345.492368) (xy 430.676547 -345.492368)
			(xy 430.676547 -345.437832) (xy 430.684309 -345.38385) (xy 430.699674 -345.331523) (xy 430.72233 -345.281915)
			(xy 430.751815 -345.236036) (xy 430.787529 -345.194821) (xy 430.828746 -345.159108) (xy 430.874626 -345.129624)
			(xy 430.924234 -345.10697) (xy 430.976562 -345.091606) (xy 431.030544 -345.083847) (xy 431.057812 -345.083384)
			(xy 431.921412 -345.083384) (xy 431.948684 -345.083779) (xy 432.002673 -345.091543) (xy 432.055007 -345.106912)
			(xy 432.104622 -345.129571) (xy 432.150507 -345.159061) (xy 432.191728 -345.194781) (xy 432.227446 -345.236003)
			(xy 432.256935 -345.281889) (xy 432.279593 -345.331504) (xy 432.294959 -345.383839) (xy 432.302721 -345.437828)
			(xy 432.302721 -345.492365) (xy 433.78557 -345.492365) (xy 433.78557 -345.437835) (xy 433.79333 -345.383861)
			(xy 433.808692 -345.33154) (xy 433.831344 -345.281937) (xy 433.860823 -345.236063) (xy 433.896531 -345.194851)
			(xy 433.937741 -345.15914) (xy 433.983613 -345.129657) (xy 434.033213 -345.107002) (xy 434.085533 -345.091636)
			(xy 434.139507 -345.083872) (xy 434.166772 -345.083384) (xy 435.030372 -345.083384) (xy 435.057648 -345.083754)
			(xy 435.111644 -345.091514) (xy 435.163986 -345.106879) (xy 435.213609 -345.129538) (xy 435.259502 -345.159028)
			(xy 435.30073 -345.19475) (xy 435.336455 -345.235976) (xy 435.365949 -345.281866) (xy 435.388611 -345.331487)
			(xy 435.403981 -345.383829) (xy 435.411744 -345.437824) (xy 435.411744 -345.492369) (xy 436.894447 -345.492369)
			(xy 436.894447 -345.437831) (xy 436.90221 -345.383848) (xy 436.917576 -345.331519) (xy 436.940233 -345.281909)
			(xy 436.96972 -345.23603) (xy 437.005436 -345.194814) (xy 437.046655 -345.159101) (xy 437.092538 -345.129617)
			(xy 437.142149 -345.106964) (xy 437.194479 -345.091603) (xy 437.248463 -345.083845) (xy 437.275732 -345.083384)
			(xy 438.139332 -345.083384) (xy 438.166603 -345.083781) (xy 438.22059 -345.091547) (xy 438.272922 -345.106917)
			(xy 438.322534 -345.129578) (xy 438.368416 -345.159068) (xy 438.409635 -345.194788) (xy 438.445351 -345.236009)
			(xy 438.474838 -345.281894) (xy 438.497494 -345.331508) (xy 438.51286 -345.383842) (xy 438.520622 -345.437829)
			(xy 438.520622 -345.492366) (xy 440.00347 -345.492366) (xy 440.00347 -345.437834) (xy 440.011231 -345.383858)
			(xy 440.026594 -345.331535) (xy 440.049247 -345.281932) (xy 440.078728 -345.236057) (xy 440.114438 -345.194844)
			(xy 440.15565 -345.159133) (xy 440.201525 -345.129651) (xy 440.251128 -345.106997) (xy 440.30345 -345.091633)
			(xy 440.357426 -345.083871) (xy 440.384692 -345.083384) (xy 441.248292 -345.083384) (xy 441.275567 -345.083755)
			(xy 441.329561 -345.091517) (xy 441.381901 -345.106885) (xy 441.431521 -345.129544) (xy 441.477411 -345.159035)
			(xy 441.518637 -345.194757) (xy 441.55436 -345.235982) (xy 441.583852 -345.281872) (xy 441.606513 -345.331492)
			(xy 441.621881 -345.383831) (xy 441.629644 -345.437825) (xy 441.629644 -345.492375) (xy 441.621881 -345.546369)
			(xy 441.606513 -345.598708) (xy 441.583852 -345.648328) (xy 441.55436 -345.694218) (xy 441.518637 -345.735443)
			(xy 441.477411 -345.771165) (xy 441.431521 -345.800656) (xy 441.381901 -345.823315) (xy 441.329561 -345.838683)
			(xy 441.275567 -345.846445) (xy 441.248292 -345.846908) (xy 440.384692 -345.846908) (xy 440.357426 -345.846329)
			(xy 440.30345 -345.838567) (xy 440.251128 -345.823203) (xy 440.201525 -345.800549) (xy 440.15565 -345.771067)
			(xy 440.114438 -345.735356) (xy 440.078728 -345.694143) (xy 440.049247 -345.648268) (xy 440.026594 -345.598665)
			(xy 440.011231 -345.546342) (xy 440.00347 -345.492366) (xy 438.520622 -345.492366) (xy 438.520622 -345.492371)
			(xy 438.51286 -345.546358) (xy 438.497494 -345.598692) (xy 438.474838 -345.648306) (xy 438.445351 -345.694191)
			(xy 438.409635 -345.735412) (xy 438.368416 -345.771132) (xy 438.322534 -345.800622) (xy 438.272922 -345.823283)
			(xy 438.22059 -345.838653) (xy 438.166603 -345.846419) (xy 438.139332 -345.846908) (xy 437.275732 -345.846908)
			(xy 437.248463 -345.846355) (xy 437.194479 -345.838597) (xy 437.142149 -345.823236) (xy 437.092538 -345.800583)
			(xy 437.046655 -345.771099) (xy 437.005436 -345.735386) (xy 436.96972 -345.69417) (xy 436.940233 -345.648291)
			(xy 436.917576 -345.598681) (xy 436.90221 -345.546352) (xy 436.894447 -345.492369) (xy 435.411744 -345.492369)
			(xy 435.411744 -345.492376) (xy 435.403981 -345.546371) (xy 435.388611 -345.598713) (xy 435.365949 -345.648334)
			(xy 435.336455 -345.694224) (xy 435.30073 -345.73545) (xy 435.259502 -345.771172) (xy 435.213609 -345.800662)
			(xy 435.163986 -345.823321) (xy 435.111644 -345.838686) (xy 435.057648 -345.846446) (xy 435.030372 -345.846908)
			(xy 434.166772 -345.846908) (xy 434.139507 -345.846328) (xy 434.085533 -345.838564) (xy 434.033213 -345.823198)
			(xy 433.983613 -345.800543) (xy 433.937741 -345.77106) (xy 433.896531 -345.735349) (xy 433.860823 -345.694137)
			(xy 433.831344 -345.648263) (xy 433.808692 -345.59866) (xy 433.79333 -345.546339) (xy 433.78557 -345.492365)
			(xy 432.302721 -345.492365) (xy 432.302721 -345.492372) (xy 432.294959 -345.546361) (xy 432.279593 -345.598696)
			(xy 432.256935 -345.648311) (xy 432.227446 -345.694197) (xy 432.191728 -345.735419) (xy 432.150507 -345.771139)
			(xy 432.104622 -345.800629) (xy 432.055007 -345.823288) (xy 432.002673 -345.838657) (xy 431.948684 -345.846421)
			(xy 431.921412 -345.846908) (xy 431.057812 -345.846908) (xy 431.030544 -345.846353) (xy 430.976562 -345.838594)
			(xy 430.924234 -345.82323) (xy 430.874626 -345.800576) (xy 430.828746 -345.771092) (xy 430.787529 -345.735379)
			(xy 430.751815 -345.694164) (xy 430.72233 -345.648285) (xy 430.699674 -345.598677) (xy 430.684309 -345.54635)
			(xy 430.676547 -345.492368) (xy 429.193844 -345.492368) (xy 429.193844 -345.492376) (xy 429.18608 -345.546374)
			(xy 429.170709 -345.598717) (xy 429.148046 -345.648339) (xy 429.11855 -345.694231) (xy 429.082823 -345.735457)
			(xy 429.041592 -345.771179) (xy 428.995697 -345.800669) (xy 428.946072 -345.823326) (xy 428.893727 -345.83869)
			(xy 428.839729 -345.846448) (xy 428.812452 -345.846908) (xy 427.948852 -345.846908) (xy 427.921588 -345.846326)
			(xy 427.867616 -345.83856) (xy 427.815299 -345.823192) (xy 427.765701 -345.800536) (xy 427.719831 -345.771053)
			(xy 427.678624 -345.735342) (xy 427.642919 -345.69413) (xy 427.613441 -345.648257) (xy 427.590791 -345.598656)
			(xy 427.57543 -345.546337) (xy 427.56767 -345.492364) (xy 426.084844 -345.492364) (xy 426.084844 -345.492375)
			(xy 426.077081 -345.546369) (xy 426.061713 -345.598708) (xy 426.039052 -345.648328) (xy 426.00956 -345.694218)
			(xy 425.973837 -345.735443) (xy 425.932611 -345.771165) (xy 425.886721 -345.800656) (xy 425.837101 -345.823315)
			(xy 425.784761 -345.838683) (xy 425.730767 -345.846445) (xy 425.703492 -345.846908) (xy 424.839892 -345.846908)
			(xy 424.812626 -345.846329) (xy 424.75865 -345.838567) (xy 424.706328 -345.823203) (xy 424.656725 -345.800549)
			(xy 424.61085 -345.771067) (xy 424.569638 -345.735356) (xy 424.533928 -345.694143) (xy 424.504447 -345.648268)
			(xy 424.481794 -345.598665) (xy 424.466431 -345.546342) (xy 424.45867 -345.492366) (xy 422.975822 -345.492366)
			(xy 422.975822 -345.492371) (xy 422.96806 -345.546358) (xy 422.952694 -345.598692) (xy 422.930038 -345.648306)
			(xy 422.900551 -345.694191) (xy 422.864835 -345.735412) (xy 422.823616 -345.771132) (xy 422.777734 -345.800622)
			(xy 422.728122 -345.823283) (xy 422.67579 -345.838653) (xy 422.621803 -345.846419) (xy 422.594532 -345.846908)
			(xy 421.730932 -345.846908) (xy 421.703663 -345.846355) (xy 421.649679 -345.838597) (xy 421.597349 -345.823236)
			(xy 421.547738 -345.800583) (xy 421.501855 -345.771099) (xy 421.460636 -345.735386) (xy 421.42492 -345.69417)
			(xy 421.395433 -345.648291) (xy 421.372776 -345.598681) (xy 421.35741 -345.546352) (xy 421.349647 -345.492369)
			(xy 419.866944 -345.492369) (xy 419.866944 -345.492376) (xy 419.859181 -345.546371) (xy 419.843811 -345.598713)
			(xy 419.821149 -345.648334) (xy 419.791655 -345.694224) (xy 419.75593 -345.73545) (xy 419.714702 -345.771172)
			(xy 419.668809 -345.800662) (xy 419.619186 -345.823321) (xy 419.566844 -345.838686) (xy 419.512848 -345.846446)
			(xy 419.485572 -345.846908) (xy 418.621972 -345.846908) (xy 418.594707 -345.846328) (xy 418.540733 -345.838564)
			(xy 418.488413 -345.823198) (xy 418.438813 -345.800543) (xy 418.392941 -345.77106) (xy 418.351731 -345.735349)
			(xy 418.316023 -345.694137) (xy 418.286544 -345.648263) (xy 418.263892 -345.59866) (xy 418.24853 -345.546339)
			(xy 418.24077 -345.492365) (xy 416.757921 -345.492365) (xy 416.757921 -345.492372) (xy 416.750159 -345.546361)
			(xy 416.734793 -345.598696) (xy 416.712135 -345.648311) (xy 416.682646 -345.694197) (xy 416.646928 -345.735419)
			(xy 416.605707 -345.771139) (xy 416.559822 -345.800629) (xy 416.510207 -345.823288) (xy 416.457873 -345.838657)
			(xy 416.403884 -345.846421) (xy 416.376612 -345.846908) (xy 415.513012 -345.846908) (xy 415.485744 -345.846353)
			(xy 415.431762 -345.838594) (xy 415.379434 -345.82323) (xy 415.329826 -345.800576) (xy 415.283946 -345.771092)
			(xy 415.242729 -345.735379) (xy 415.207015 -345.694164) (xy 415.17753 -345.648285) (xy 415.154874 -345.598677)
			(xy 415.139509 -345.54635) (xy 415.131747 -345.492368) (xy 413.648952 -345.492368) (xy 413.648952 -345.49237)
			(xy 413.64119 -345.546354) (xy 413.625823 -345.598685) (xy 413.603165 -345.648295) (xy 413.573676 -345.694176)
			(xy 413.537958 -345.735392) (xy 413.496737 -345.771105) (xy 413.450853 -345.800588) (xy 413.40124 -345.82324)
			(xy 413.348908 -345.8386) (xy 413.294922 -345.846356) (xy 413.267652 -345.846908) (xy 412.404052 -345.846908)
			(xy 412.384674 -345.846646) (xy 412.34612 -345.842699) (xy 412.32709 -345.839034) (xy 412.31566 -345.836748)
			(xy 412.293816 -345.842082) (xy 412.223966 -345.899232) (xy 412.215566 -345.906848) (xy 412.205808 -345.927282)
			(xy 412.20517 -345.938602) (xy 412.20517 -348.112334) (xy 412.205778 -348.123661) (xy 412.215548 -348.144099)
			(xy 412.223966 -348.151704) (xy 412.293816 -348.208854) (xy 412.31566 -348.214188) (xy 412.32709 -348.211902)
			(xy 412.346116 -348.208213) (xy 412.384673 -348.204265) (xy 412.404052 -348.204028) (xy 413.267652 -348.204028)
			(xy 413.294926 -348.204488) (xy 413.348919 -348.212245) (xy 413.401259 -348.227608) (xy 413.45088 -348.250263)
			(xy 413.496771 -348.27975) (xy 413.537998 -348.315468) (xy 413.573721 -348.356691) (xy 413.603214 -348.402578)
			(xy 413.625876 -348.452196) (xy 413.641245 -348.504534) (xy 413.649008 -348.558526) (xy 413.649008 -348.613072)
			(xy 415.131692 -348.613072) (xy 415.131692 -348.558528) (xy 415.139454 -348.504538) (xy 415.154821 -348.452203)
			(xy 415.177481 -348.402588) (xy 415.20697 -348.356703) (xy 415.24269 -348.315481) (xy 415.283912 -348.279763)
			(xy 415.329799 -348.250275) (xy 415.379415 -348.227617) (xy 415.43175 -348.212252) (xy 415.48574 -348.204491)
			(xy 415.513012 -348.204028) (xy 416.376612 -348.204028) (xy 416.40388 -348.204535) (xy 416.457861 -348.212298)
			(xy 416.510188 -348.227664) (xy 416.559795 -348.25032) (xy 416.605673 -348.279806) (xy 416.646888 -348.31552)
			(xy 416.682601 -348.356736) (xy 416.712085 -348.402615) (xy 416.73474 -348.452224) (xy 416.750104 -348.504551)
			(xy 416.757866 -348.558532) (xy 416.757866 -348.613068) (xy 416.757866 -348.613069) (xy 418.240714 -348.613069)
			(xy 418.240714 -348.558531) (xy 418.248476 -348.504549) (xy 418.26384 -348.45222) (xy 418.286495 -348.40261)
			(xy 418.315979 -348.35673) (xy 418.351692 -348.315512) (xy 418.392907 -348.279795) (xy 418.438786 -348.250308)
			(xy 418.488394 -348.22765) (xy 418.540721 -348.212281) (xy 418.594703 -348.204516) (xy 418.621972 -348.204028)
			(xy 419.485572 -348.204028) (xy 419.512844 -348.20451) (xy 419.566832 -348.212268) (xy 419.619167 -348.227632)
			(xy 419.668782 -348.250287) (xy 419.714668 -348.279773) (xy 419.75589 -348.31549) (xy 419.79161 -348.356709)
			(xy 419.821099 -348.402593) (xy 419.843759 -348.452207) (xy 419.859126 -348.504541) (xy 419.866888 -348.558528)
			(xy 419.866888 -348.613072) (xy 419.866888 -348.613073) (xy 421.349592 -348.613073) (xy 421.349592 -348.558527)
			(xy 421.357355 -348.504536) (xy 421.372723 -348.452199) (xy 421.395384 -348.402583) (xy 421.424875 -348.356696)
			(xy 421.460597 -348.315474) (xy 421.501822 -348.279756) (xy 421.547711 -348.250268) (xy 421.597329 -348.227612)
			(xy 421.649667 -348.212248) (xy 421.703659 -348.204489) (xy 421.730932 -348.204028) (xy 422.594532 -348.204028)
			(xy 422.621799 -348.204537) (xy 422.675778 -348.212302) (xy 422.728102 -348.227669) (xy 422.777707 -348.250327)
			(xy 422.823583 -348.279813) (xy 422.864795 -348.315527) (xy 422.900506 -348.356743) (xy 422.929988 -348.402621)
			(xy 422.952642 -348.452228) (xy 422.968005 -348.504553) (xy 422.975766 -348.558533) (xy 422.975766 -348.613067)
			(xy 422.975766 -348.61307) (xy 424.458614 -348.61307) (xy 424.458614 -348.55853) (xy 424.466376 -348.504546)
			(xy 424.481741 -348.452216) (xy 424.504398 -348.402605) (xy 424.533884 -348.356723) (xy 424.569599 -348.315505)
			(xy 424.610817 -348.279788) (xy 424.656698 -348.250301) (xy 424.706308 -348.227644) (xy 424.758638 -348.212278)
			(xy 424.812622 -348.204515) (xy 424.839892 -348.204028) (xy 425.703492 -348.204028) (xy 425.730763 -348.204511)
			(xy 425.784749 -348.212272) (xy 425.837081 -348.227637) (xy 425.886694 -348.250294) (xy 425.932578 -348.27978)
			(xy 425.973798 -348.315497) (xy 426.009515 -348.356716) (xy 426.039003 -348.402599) (xy 426.06166 -348.452211)
			(xy 426.077026 -348.504543) (xy 426.084789 -348.558529) (xy 426.084789 -348.613068) (xy 427.567614 -348.613068)
			(xy 427.567614 -348.558532) (xy 427.575375 -348.504551) (xy 427.590738 -348.452224) (xy 427.613392 -348.402616)
			(xy 427.642874 -348.356736) (xy 427.678585 -348.315519) (xy 427.719798 -348.279803) (xy 427.765674 -348.250315)
			(xy 427.815279 -348.227655) (xy 427.867604 -348.212285) (xy 427.921584 -348.204518) (xy 427.948852 -348.204028)
			(xy 428.812452 -348.204028) (xy 428.839725 -348.204508) (xy 428.893715 -348.212265) (xy 428.946052 -348.227626)
			(xy 428.99567 -348.250281) (xy 429.041559 -348.279766) (xy 429.082783 -348.315483) (xy 429.118505 -348.356703)
			(xy 429.147996 -348.402588) (xy 429.170657 -348.452203) (xy 429.186025 -348.504538) (xy 429.193788 -348.558528)
			(xy 429.193788 -348.613072) (xy 430.676492 -348.613072) (xy 430.676492 -348.558528) (xy 430.684254 -348.504538)
			(xy 430.699621 -348.452203) (xy 430.722281 -348.402588) (xy 430.75177 -348.356703) (xy 430.78749 -348.315481)
			(xy 430.828712 -348.279763) (xy 430.874599 -348.250275) (xy 430.924215 -348.227617) (xy 430.97655 -348.212252)
			(xy 431.03054 -348.204491) (xy 431.057812 -348.204028) (xy 431.921412 -348.204028) (xy 431.94868 -348.204535)
			(xy 432.002661 -348.212298) (xy 432.054988 -348.227664) (xy 432.104595 -348.25032) (xy 432.150473 -348.279806)
			(xy 432.191688 -348.31552) (xy 432.227401 -348.356736) (xy 432.256885 -348.402615) (xy 432.27954 -348.452224)
			(xy 432.294904 -348.504551) (xy 432.302666 -348.558532) (xy 432.302666 -348.613068) (xy 432.302666 -348.613069)
			(xy 433.785514 -348.613069) (xy 433.785514 -348.558531) (xy 433.793276 -348.504549) (xy 433.80864 -348.45222)
			(xy 433.831295 -348.40261) (xy 433.860779 -348.35673) (xy 433.896492 -348.315512) (xy 433.937707 -348.279795)
			(xy 433.983586 -348.250308) (xy 434.033194 -348.22765) (xy 434.085521 -348.212281) (xy 434.139503 -348.204516)
			(xy 434.166772 -348.204028) (xy 435.030372 -348.204028) (xy 435.057644 -348.20451) (xy 435.111632 -348.212268)
			(xy 435.163967 -348.227632) (xy 435.213582 -348.250287) (xy 435.259468 -348.279773) (xy 435.30069 -348.31549)
			(xy 435.33641 -348.356709) (xy 435.365899 -348.402593) (xy 435.388559 -348.452207) (xy 435.403926 -348.504541)
			(xy 435.411688 -348.558528) (xy 435.411688 -348.613072) (xy 435.411688 -348.613073) (xy 436.894392 -348.613073)
			(xy 436.894392 -348.558527) (xy 436.902155 -348.504536) (xy 436.917523 -348.452199) (xy 436.940184 -348.402583)
			(xy 436.969675 -348.356696) (xy 437.005397 -348.315474) (xy 437.046622 -348.279756) (xy 437.092511 -348.250268)
			(xy 437.142129 -348.227612) (xy 437.194467 -348.212248) (xy 437.248459 -348.204489) (xy 437.275732 -348.204028)
			(xy 438.139332 -348.204028) (xy 438.166599 -348.204537) (xy 438.220578 -348.212302) (xy 438.272902 -348.227669)
			(xy 438.322507 -348.250327) (xy 438.368383 -348.279813) (xy 438.409595 -348.315527) (xy 438.445306 -348.356743)
			(xy 438.474788 -348.402621) (xy 438.497442 -348.452228) (xy 438.512805 -348.504553) (xy 438.520566 -348.558533)
			(xy 438.520566 -348.613067) (xy 438.520566 -348.61307) (xy 440.003414 -348.61307) (xy 440.003414 -348.55853)
			(xy 440.011176 -348.504546) (xy 440.026541 -348.452216) (xy 440.049198 -348.402605) (xy 440.078684 -348.356723)
			(xy 440.114399 -348.315505) (xy 440.155617 -348.279788) (xy 440.201498 -348.250301) (xy 440.251108 -348.227644)
			(xy 440.303438 -348.212278) (xy 440.357422 -348.204515) (xy 440.384692 -348.204028) (xy 441.248292 -348.204028)
			(xy 441.275563 -348.204511) (xy 441.329549 -348.212272) (xy 441.381881 -348.227637) (xy 441.431494 -348.250294)
			(xy 441.477378 -348.27978) (xy 441.518598 -348.315497) (xy 441.554315 -348.356716) (xy 441.583803 -348.402599)
			(xy 441.60646 -348.452211) (xy 441.621826 -348.504543) (xy 441.629589 -348.558529) (xy 441.629589 -348.613071)
			(xy 441.621826 -348.667057) (xy 441.60646 -348.719389) (xy 441.583803 -348.769001) (xy 441.554315 -348.814884)
			(xy 441.518598 -348.856103) (xy 441.477378 -348.89182) (xy 441.431494 -348.921306) (xy 441.381881 -348.943963)
			(xy 441.329549 -348.959328) (xy 441.275563 -348.967089) (xy 441.248292 -348.967552) (xy 440.384692 -348.967552)
			(xy 440.357422 -348.967085) (xy 440.303438 -348.959322) (xy 440.251108 -348.943956) (xy 440.201498 -348.921299)
			(xy 440.155617 -348.891812) (xy 440.114399 -348.856095) (xy 440.078684 -348.814877) (xy 440.049198 -348.768995)
			(xy 440.026541 -348.719384) (xy 440.011176 -348.667054) (xy 440.003414 -348.61307) (xy 438.520566 -348.61307)
			(xy 438.512805 -348.667047) (xy 438.497442 -348.719372) (xy 438.474788 -348.768979) (xy 438.445306 -348.814857)
			(xy 438.409595 -348.856073) (xy 438.368383 -348.891787) (xy 438.322507 -348.921273) (xy 438.272902 -348.943931)
			(xy 438.220578 -348.959298) (xy 438.166599 -348.967063) (xy 438.139332 -348.967552) (xy 437.275732 -348.967552)
			(xy 437.248459 -348.967111) (xy 437.194467 -348.959352) (xy 437.142129 -348.943988) (xy 437.092511 -348.921332)
			(xy 437.046622 -348.891844) (xy 437.005397 -348.856126) (xy 436.969675 -348.814904) (xy 436.940184 -348.769017)
			(xy 436.917523 -348.719401) (xy 436.902155 -348.667064) (xy 436.894392 -348.613073) (xy 435.411688 -348.613073)
			(xy 435.403926 -348.667059) (xy 435.388559 -348.719393) (xy 435.365899 -348.769007) (xy 435.33641 -348.814891)
			(xy 435.30069 -348.85611) (xy 435.259468 -348.891827) (xy 435.213582 -348.921313) (xy 435.163967 -348.943968)
			(xy 435.111632 -348.959332) (xy 435.057644 -348.96709) (xy 435.030372 -348.967552) (xy 434.166772 -348.967552)
			(xy 434.139503 -348.967084) (xy 434.085521 -348.959319) (xy 434.033194 -348.94395) (xy 433.983586 -348.921292)
			(xy 433.937707 -348.891805) (xy 433.896492 -348.856088) (xy 433.860779 -348.81487) (xy 433.831295 -348.76899)
			(xy 433.80864 -348.71938) (xy 433.793276 -348.667051) (xy 433.785514 -348.613069) (xy 432.302666 -348.613069)
			(xy 432.294904 -348.667049) (xy 432.27954 -348.719376) (xy 432.256885 -348.768985) (xy 432.227401 -348.814864)
			(xy 432.191688 -348.85608) (xy 432.150473 -348.891794) (xy 432.104595 -348.92128) (xy 432.054988 -348.943936)
			(xy 432.002661 -348.959302) (xy 431.94868 -348.967065) (xy 431.921412 -348.967552) (xy 431.057812 -348.967552)
			(xy 431.03054 -348.967109) (xy 430.97655 -348.959348) (xy 430.924215 -348.943983) (xy 430.874599 -348.921325)
			(xy 430.828712 -348.891837) (xy 430.78749 -348.856119) (xy 430.75177 -348.814897) (xy 430.722281 -348.769012)
			(xy 430.699621 -348.719397) (xy 430.684254 -348.667062) (xy 430.676492 -348.613072) (xy 429.193788 -348.613072)
			(xy 429.186025 -348.667062) (xy 429.170657 -348.719397) (xy 429.147996 -348.769012) (xy 429.118505 -348.814897)
			(xy 429.082783 -348.856117) (xy 429.041559 -348.891834) (xy 428.99567 -348.921319) (xy 428.946052 -348.943974)
			(xy 428.893715 -348.959335) (xy 428.839725 -348.967092) (xy 428.812452 -348.967552) (xy 427.948852 -348.967552)
			(xy 427.921584 -348.967082) (xy 427.867604 -348.959315) (xy 427.815279 -348.943945) (xy 427.765674 -348.921285)
			(xy 427.719798 -348.891797) (xy 427.678585 -348.856081) (xy 427.642874 -348.814864) (xy 427.613392 -348.768984)
			(xy 427.590738 -348.719376) (xy 427.575375 -348.667049) (xy 427.567614 -348.613068) (xy 426.084789 -348.613068)
			(xy 426.084789 -348.613071) (xy 426.077026 -348.667057) (xy 426.06166 -348.719389) (xy 426.039003 -348.769001)
			(xy 426.009515 -348.814884) (xy 425.973798 -348.856103) (xy 425.932578 -348.89182) (xy 425.886694 -348.921306)
			(xy 425.837081 -348.943963) (xy 425.784749 -348.959328) (xy 425.730763 -348.967089) (xy 425.703492 -348.967552)
			(xy 424.839892 -348.967552) (xy 424.812622 -348.967085) (xy 424.758638 -348.959322) (xy 424.706308 -348.943956)
			(xy 424.656698 -348.921299) (xy 424.610817 -348.891812) (xy 424.569599 -348.856095) (xy 424.533884 -348.814877)
			(xy 424.504398 -348.768995) (xy 424.481741 -348.719384) (xy 424.466376 -348.667054) (xy 424.458614 -348.61307)
			(xy 422.975766 -348.61307) (xy 422.968005 -348.667047) (xy 422.952642 -348.719372) (xy 422.929988 -348.768979)
			(xy 422.900506 -348.814857) (xy 422.864795 -348.856073) (xy 422.823583 -348.891787) (xy 422.777707 -348.921273)
			(xy 422.728102 -348.943931) (xy 422.675778 -348.959298) (xy 422.621799 -348.967063) (xy 422.594532 -348.967552)
			(xy 421.730932 -348.967552) (xy 421.703659 -348.967111) (xy 421.649667 -348.959352) (xy 421.597329 -348.943988)
			(xy 421.547711 -348.921332) (xy 421.501822 -348.891844) (xy 421.460597 -348.856126) (xy 421.424875 -348.814904)
			(xy 421.395384 -348.769017) (xy 421.372723 -348.719401) (xy 421.357355 -348.667064) (xy 421.349592 -348.613073)
			(xy 419.866888 -348.613073) (xy 419.859126 -348.667059) (xy 419.843759 -348.719393) (xy 419.821099 -348.769007)
			(xy 419.79161 -348.814891) (xy 419.75589 -348.85611) (xy 419.714668 -348.891827) (xy 419.668782 -348.921313)
			(xy 419.619167 -348.943968) (xy 419.566832 -348.959332) (xy 419.512844 -348.96709) (xy 419.485572 -348.967552)
			(xy 418.621972 -348.967552) (xy 418.594703 -348.967084) (xy 418.540721 -348.959319) (xy 418.488394 -348.94395)
			(xy 418.438786 -348.921292) (xy 418.392907 -348.891805) (xy 418.351692 -348.856088) (xy 418.315979 -348.81487)
			(xy 418.286495 -348.76899) (xy 418.26384 -348.71938) (xy 418.248476 -348.667051) (xy 418.240714 -348.613069)
			(xy 416.757866 -348.613069) (xy 416.750104 -348.667049) (xy 416.73474 -348.719376) (xy 416.712085 -348.768985)
			(xy 416.682601 -348.814864) (xy 416.646888 -348.85608) (xy 416.605673 -348.891794) (xy 416.559795 -348.92128)
			(xy 416.510188 -348.943936) (xy 416.457861 -348.959302) (xy 416.40388 -348.967065) (xy 416.376612 -348.967552)
			(xy 415.513012 -348.967552) (xy 415.48574 -348.967109) (xy 415.43175 -348.959348) (xy 415.379415 -348.943983)
			(xy 415.329799 -348.921325) (xy 415.283912 -348.891837) (xy 415.24269 -348.856119) (xy 415.20697 -348.814897)
			(xy 415.177481 -348.769012) (xy 415.154821 -348.719397) (xy 415.139454 -348.667062) (xy 415.131692 -348.613072)
			(xy 413.649008 -348.613072) (xy 413.649008 -348.613074) (xy 413.641245 -348.667066) (xy 413.625876 -348.719404)
			(xy 413.603214 -348.769022) (xy 413.573721 -348.814909) (xy 413.537998 -348.856132) (xy 413.496771 -348.89185)
			(xy 413.45088 -348.921337) (xy 413.401259 -348.943992) (xy 413.348919 -348.959355) (xy 413.294926 -348.967112)
			(xy 413.267652 -348.967552) (xy 412.404052 -348.967552) (xy 412.384674 -348.967291) (xy 412.34612 -348.963344)
			(xy 412.32709 -348.959678) (xy 412.31566 -348.957392) (xy 412.293816 -348.962726) (xy 412.223966 -349.019876)
			(xy 412.215557 -349.027488) (xy 412.205776 -349.047922) (xy 412.20517 -349.059246) (xy 412.20517 -351.137982)
			(xy 412.205768 -351.149315) (xy 412.215524 -351.169769) (xy 412.223966 -351.177352) (xy 412.293816 -351.234502)
			(xy 412.31566 -351.239836) (xy 412.32709 -351.23755) (xy 412.346116 -351.23386) (xy 412.384673 -351.229912)
			(xy 412.404052 -351.229676) (xy 413.267652 -351.229676) (xy 413.294923 -351.230136) (xy 413.348909 -351.237892)
			(xy 413.401242 -351.253253) (xy 413.450857 -351.275905) (xy 413.496742 -351.305388) (xy 413.537964 -351.341102)
			(xy 413.573683 -351.38232) (xy 413.603172 -351.428201) (xy 413.625831 -351.477812) (xy 413.641198 -351.530144)
			(xy 413.64896 -351.58413) (xy 413.64896 -351.638669) (xy 415.131739 -351.638669) (xy 415.131739 -351.584131)
			(xy 415.139501 -351.530149) (xy 415.154866 -351.47782) (xy 415.177523 -351.428211) (xy 415.207008 -351.382331)
			(xy 415.242724 -351.341115) (xy 415.283941 -351.305401) (xy 415.329822 -351.275917) (xy 415.379431 -351.253262)
			(xy 415.43176 -351.237899) (xy 415.485743 -351.230139) (xy 415.513012 -351.229676) (xy 416.376612 -351.229676)
			(xy 416.403884 -351.230087) (xy 416.457871 -351.237851) (xy 416.510204 -351.253219) (xy 416.559818 -351.275878)
			(xy 416.605702 -351.305367) (xy 416.646922 -351.341086) (xy 416.68264 -351.382308) (xy 416.712128 -351.428192)
			(xy 416.734785 -351.477807) (xy 416.750151 -351.530141) (xy 416.757914 -351.584128) (xy 416.757914 -351.638665)
			(xy 418.240762 -351.638665) (xy 418.240762 -351.584135) (xy 418.248522 -351.530159) (xy 418.263885 -351.477837)
			(xy 418.286537 -351.428233) (xy 418.316017 -351.382358) (xy 418.351726 -351.341146) (xy 418.392936 -351.305434)
			(xy 418.438809 -351.27595) (xy 418.48841 -351.253295) (xy 418.540731 -351.237928) (xy 418.594707 -351.230164)
			(xy 418.621972 -351.229676) (xy 419.485572 -351.229676) (xy 419.512847 -351.230062) (xy 419.566842 -351.237821)
			(xy 419.619184 -351.253187) (xy 419.668805 -351.275845) (xy 419.714697 -351.305335) (xy 419.755924 -351.341056)
			(xy 419.791648 -351.382281) (xy 419.821142 -351.42817) (xy 419.843803 -351.47779) (xy 419.859173 -351.53013)
			(xy 419.866936 -351.584125) (xy 419.866936 -351.63867) (xy 421.349639 -351.63867) (xy 421.349639 -351.58413)
			(xy 421.357402 -351.530146) (xy 421.372768 -351.477816) (xy 421.395426 -351.428206) (xy 421.424913 -351.382325)
			(xy 421.460631 -351.341108) (xy 421.501851 -351.305394) (xy 421.547734 -351.27591) (xy 421.597346 -351.253257)
			(xy 421.649677 -351.237895) (xy 421.703662 -351.230137) (xy 421.730932 -351.229676) (xy 422.594532 -351.229676)
			(xy 422.621803 -351.230089) (xy 422.675788 -351.237855) (xy 422.728119 -351.253224) (xy 422.77773 -351.275885)
			(xy 422.823612 -351.305374) (xy 422.864829 -351.341093) (xy 422.900545 -351.382314) (xy 422.930031 -351.428198)
			(xy 422.952687 -351.477811) (xy 422.968052 -351.530143) (xy 422.975814 -351.584129) (xy 422.975814 -351.638666)
			(xy 424.458662 -351.638666) (xy 424.458662 -351.584134) (xy 424.466423 -351.530156) (xy 424.481786 -351.477832)
			(xy 424.50444 -351.428228) (xy 424.533922 -351.382352) (xy 424.569633 -351.341138) (xy 424.610845 -351.305427)
			(xy 424.656721 -351.275944) (xy 424.706325 -351.253289) (xy 424.758648 -351.237925) (xy 424.812626 -351.230163)
			(xy 424.839892 -351.229676) (xy 425.703492 -351.229676) (xy 425.730766 -351.230063) (xy 425.784759 -351.237825)
			(xy 425.837098 -351.253192) (xy 425.886717 -351.275851) (xy 425.932606 -351.305342) (xy 425.973832 -351.341063)
			(xy 426.009553 -351.382287) (xy 426.039045 -351.428176) (xy 426.061705 -351.477794) (xy 426.077073 -351.530133)
			(xy 426.084836 -351.584126) (xy 426.084836 -351.638664) (xy 427.567662 -351.638664) (xy 427.567662 -351.584136)
			(xy 427.575422 -351.530162) (xy 427.590783 -351.477841) (xy 427.613434 -351.428239) (xy 427.642912 -351.382365)
			(xy 427.678619 -351.341153) (xy 427.719826 -351.305441) (xy 427.765697 -351.275957) (xy 427.815296 -351.2533)
			(xy 427.867615 -351.237932) (xy 427.921588 -351.230166) (xy 427.948852 -351.229676) (xy 428.812452 -351.229676)
			(xy 428.839728 -351.23006) (xy 428.893725 -351.237818) (xy 428.946069 -351.253181) (xy 428.995693 -351.275838)
			(xy 429.041587 -351.305328) (xy 429.082817 -351.341049) (xy 429.118544 -351.382274) (xy 429.148039 -351.428165)
			(xy 429.170702 -351.477786) (xy 429.186072 -351.530128) (xy 429.193836 -351.584124) (xy 429.193836 -351.638669)
			(xy 430.676539 -351.638669) (xy 430.676539 -351.584131) (xy 430.684301 -351.530149) (xy 430.699666 -351.47782)
			(xy 430.722323 -351.428211) (xy 430.751808 -351.382331) (xy 430.787524 -351.341115) (xy 430.828741 -351.305401)
			(xy 430.874622 -351.275917) (xy 430.924231 -351.253262) (xy 430.97656 -351.237899) (xy 431.030543 -351.230139)
			(xy 431.057812 -351.229676) (xy 431.921412 -351.229676) (xy 431.948684 -351.230087) (xy 432.002671 -351.237851)
			(xy 432.055004 -351.253219) (xy 432.104618 -351.275878) (xy 432.150502 -351.305367) (xy 432.191722 -351.341086)
			(xy 432.22744 -351.382308) (xy 432.256928 -351.428192) (xy 432.279585 -351.477807) (xy 432.294951 -351.530141)
			(xy 432.302714 -351.584128) (xy 432.302714 -351.638665) (xy 433.785562 -351.638665) (xy 433.785562 -351.584135)
			(xy 433.793322 -351.530159) (xy 433.808685 -351.477837) (xy 433.831337 -351.428233) (xy 433.860817 -351.382358)
			(xy 433.896526 -351.341146) (xy 433.937736 -351.305434) (xy 433.983609 -351.27595) (xy 434.03321 -351.253295)
			(xy 434.085531 -351.237928) (xy 434.139507 -351.230164) (xy 434.166772 -351.229676) (xy 435.030372 -351.229676)
			(xy 435.057647 -351.230062) (xy 435.111642 -351.237821) (xy 435.163984 -351.253187) (xy 435.213605 -351.275845)
			(xy 435.259497 -351.305335) (xy 435.300724 -351.341056) (xy 435.336448 -351.382281) (xy 435.365942 -351.42817)
			(xy 435.388603 -351.47779) (xy 435.403973 -351.53013) (xy 435.411736 -351.584125) (xy 435.411736 -351.63867)
			(xy 436.894439 -351.63867) (xy 436.894439 -351.58413) (xy 436.902202 -351.530146) (xy 436.917568 -351.477816)
			(xy 436.940226 -351.428206) (xy 436.969713 -351.382325) (xy 437.005431 -351.341108) (xy 437.046651 -351.305394)
			(xy 437.092534 -351.27591) (xy 437.142146 -351.253257) (xy 437.194477 -351.237895) (xy 437.248462 -351.230137)
			(xy 437.275732 -351.229676) (xy 438.139332 -351.229676) (xy 438.166603 -351.230089) (xy 438.220588 -351.237855)
			(xy 438.272919 -351.253224) (xy 438.32253 -351.275885) (xy 438.368412 -351.305374) (xy 438.409629 -351.341093)
			(xy 438.445345 -351.382314) (xy 438.474831 -351.428198) (xy 438.497487 -351.477811) (xy 438.512852 -351.530143)
			(xy 438.520614 -351.584129) (xy 438.520614 -351.638666) (xy 440.003462 -351.638666) (xy 440.003462 -351.584134)
			(xy 440.011223 -351.530156) (xy 440.026586 -351.477832) (xy 440.04924 -351.428228) (xy 440.078722 -351.382352)
			(xy 440.114433 -351.341138) (xy 440.155645 -351.305427) (xy 440.201521 -351.275944) (xy 440.251125 -351.253289)
			(xy 440.303448 -351.237925) (xy 440.357426 -351.230163) (xy 440.384692 -351.229676) (xy 441.248292 -351.229676)
			(xy 441.275566 -351.230063) (xy 441.329559 -351.237825) (xy 441.381898 -351.253192) (xy 441.431517 -351.275851)
			(xy 441.477406 -351.305342) (xy 441.518632 -351.341063) (xy 441.554353 -351.382287) (xy 441.583845 -351.428176)
			(xy 441.606505 -351.477794) (xy 441.621873 -351.530133) (xy 441.629636 -351.584126) (xy 441.629636 -351.638674)
			(xy 441.621873 -351.692667) (xy 441.606505 -351.745006) (xy 441.583845 -351.794624) (xy 441.554353 -351.840513)
			(xy 441.518632 -351.881737) (xy 441.477406 -351.917458) (xy 441.431517 -351.946949) (xy 441.381898 -351.969608)
			(xy 441.329559 -351.984975) (xy 441.275566 -351.992737) (xy 441.248292 -351.9932) (xy 440.384692 -351.9932)
			(xy 440.357426 -351.992637) (xy 440.303448 -351.984875) (xy 440.251125 -351.969511) (xy 440.201521 -351.946856)
			(xy 440.155645 -351.917373) (xy 440.114433 -351.881662) (xy 440.078722 -351.840448) (xy 440.04924 -351.794572)
			(xy 440.026586 -351.744968) (xy 440.011223 -351.692644) (xy 440.003462 -351.638666) (xy 438.520614 -351.638666)
			(xy 438.520614 -351.638671) (xy 438.512852 -351.692657) (xy 438.497487 -351.744989) (xy 438.474831 -351.794602)
			(xy 438.445345 -351.840486) (xy 438.409629 -351.881707) (xy 438.368412 -351.917426) (xy 438.32253 -351.946915)
			(xy 438.272919 -351.969576) (xy 438.220588 -351.984945) (xy 438.166603 -351.992711) (xy 438.139332 -351.9932)
			(xy 437.275732 -351.9932) (xy 437.248462 -351.992663) (xy 437.194477 -351.984905) (xy 437.142146 -351.969543)
			(xy 437.092534 -351.94689) (xy 437.046651 -351.917406) (xy 437.005431 -351.881692) (xy 436.969713 -351.840475)
			(xy 436.940226 -351.794594) (xy 436.917568 -351.744984) (xy 436.902202 -351.692654) (xy 436.894439 -351.63867)
			(xy 435.411736 -351.63867) (xy 435.411736 -351.638675) (xy 435.403973 -351.69267) (xy 435.388603 -351.74501)
			(xy 435.365942 -351.79463) (xy 435.336448 -351.840519) (xy 435.300724 -351.881744) (xy 435.259497 -351.917465)
			(xy 435.213605 -351.946955) (xy 435.163984 -351.969613) (xy 435.111642 -351.984979) (xy 435.057647 -351.992738)
			(xy 435.030372 -351.9932) (xy 434.166772 -351.9932) (xy 434.139507 -351.992636) (xy 434.085531 -351.984872)
			(xy 434.03321 -351.969505) (xy 433.983609 -351.94685) (xy 433.937736 -351.917366) (xy 433.896526 -351.881654)
			(xy 433.860817 -351.840442) (xy 433.831337 -351.794567) (xy 433.808685 -351.744963) (xy 433.793322 -351.692641)
			(xy 433.785562 -351.638665) (xy 432.302714 -351.638665) (xy 432.302714 -351.638672) (xy 432.294951 -351.692659)
			(xy 432.279585 -351.744993) (xy 432.256928 -351.794608) (xy 432.22744 -351.840492) (xy 432.191722 -351.881714)
			(xy 432.150502 -351.917433) (xy 432.104618 -351.946922) (xy 432.055004 -351.969581) (xy 432.002671 -351.984949)
			(xy 431.948684 -351.992713) (xy 431.921412 -351.9932) (xy 431.057812 -351.9932) (xy 431.030543 -351.992661)
			(xy 430.97656 -351.984901) (xy 430.924231 -351.969538) (xy 430.874622 -351.946883) (xy 430.828741 -351.917399)
			(xy 430.787524 -351.881685) (xy 430.751808 -351.840469) (xy 430.722323 -351.794589) (xy 430.699666 -351.74498)
			(xy 430.684301 -351.692651) (xy 430.676539 -351.638669) (xy 429.193836 -351.638669) (xy 429.193836 -351.638676)
			(xy 429.186072 -351.692672) (xy 429.170702 -351.745014) (xy 429.148039 -351.794635) (xy 429.118544 -351.840526)
			(xy 429.082817 -351.881751) (xy 429.041587 -351.917472) (xy 428.995693 -351.946962) (xy 428.946069 -351.969619)
			(xy 428.893725 -351.984982) (xy 428.839728 -351.99274) (xy 428.812452 -351.9932) (xy 427.948852 -351.9932)
			(xy 427.921588 -351.992634) (xy 427.867615 -351.984868) (xy 427.815296 -351.9695) (xy 427.765697 -351.946843)
			(xy 427.719826 -351.917359) (xy 427.678619 -351.881647) (xy 427.642912 -351.840435) (xy 427.613434 -351.794561)
			(xy 427.590783 -351.744959) (xy 427.575422 -351.692639) (xy 427.567662 -351.638664) (xy 426.084836 -351.638664)
			(xy 426.084836 -351.638674) (xy 426.077073 -351.692667) (xy 426.061705 -351.745006) (xy 426.039045 -351.794624)
			(xy 426.009553 -351.840513) (xy 425.973832 -351.881737) (xy 425.932606 -351.917458) (xy 425.886717 -351.946949)
			(xy 425.837098 -351.969608) (xy 425.784759 -351.984975) (xy 425.730766 -351.992737) (xy 425.703492 -351.9932)
			(xy 424.839892 -351.9932) (xy 424.812626 -351.992637) (xy 424.758648 -351.984875) (xy 424.706325 -351.969511)
			(xy 424.656721 -351.946856) (xy 424.610845 -351.917373) (xy 424.569633 -351.881662) (xy 424.533922 -351.840448)
			(xy 424.50444 -351.794572) (xy 424.481786 -351.744968) (xy 424.466423 -351.692644) (xy 424.458662 -351.638666)
			(xy 422.975814 -351.638666) (xy 422.975814 -351.638671) (xy 422.968052 -351.692657) (xy 422.952687 -351.744989)
			(xy 422.930031 -351.794602) (xy 422.900545 -351.840486) (xy 422.864829 -351.881707) (xy 422.823612 -351.917426)
			(xy 422.77773 -351.946915) (xy 422.728119 -351.969576) (xy 422.675788 -351.984945) (xy 422.621803 -351.992711)
			(xy 422.594532 -351.9932) (xy 421.730932 -351.9932) (xy 421.703662 -351.992663) (xy 421.649677 -351.984905)
			(xy 421.597346 -351.969543) (xy 421.547734 -351.94689) (xy 421.501851 -351.917406) (xy 421.460631 -351.881692)
			(xy 421.424913 -351.840475) (xy 421.395426 -351.794594) (xy 421.372768 -351.744984) (xy 421.357402 -351.692654)
			(xy 421.349639 -351.63867) (xy 419.866936 -351.63867) (xy 419.866936 -351.638675) (xy 419.859173 -351.69267)
			(xy 419.843803 -351.74501) (xy 419.821142 -351.79463) (xy 419.791648 -351.840519) (xy 419.755924 -351.881744)
			(xy 419.714697 -351.917465) (xy 419.668805 -351.946955) (xy 419.619184 -351.969613) (xy 419.566842 -351.984979)
			(xy 419.512847 -351.992738) (xy 419.485572 -351.9932) (xy 418.621972 -351.9932) (xy 418.594707 -351.992636)
			(xy 418.540731 -351.984872) (xy 418.48841 -351.969505) (xy 418.438809 -351.94685) (xy 418.392936 -351.917366)
			(xy 418.351726 -351.881654) (xy 418.316017 -351.840442) (xy 418.286537 -351.794567) (xy 418.263885 -351.744963)
			(xy 418.248522 -351.692641) (xy 418.240762 -351.638665) (xy 416.757914 -351.638665) (xy 416.757914 -351.638672)
			(xy 416.750151 -351.692659) (xy 416.734785 -351.744993) (xy 416.712128 -351.794608) (xy 416.68264 -351.840492)
			(xy 416.646922 -351.881714) (xy 416.605702 -351.917433) (xy 416.559818 -351.946922) (xy 416.510204 -351.969581)
			(xy 416.457871 -351.984949) (xy 416.403884 -351.992713) (xy 416.376612 -351.9932) (xy 415.513012 -351.9932)
			(xy 415.485743 -351.992661) (xy 415.43176 -351.984901) (xy 415.379431 -351.969538) (xy 415.329822 -351.946883)
			(xy 415.283941 -351.917399) (xy 415.242724 -351.881685) (xy 415.207008 -351.840469) (xy 415.177523 -351.794589)
			(xy 415.154866 -351.74498) (xy 415.139501 -351.692651) (xy 415.131739 -351.638669) (xy 413.64896 -351.638669)
			(xy 413.64896 -351.63867) (xy 413.641198 -351.692656) (xy 413.625831 -351.744987) (xy 413.603172 -351.794599)
			(xy 413.573683 -351.84048) (xy 413.537964 -351.881698) (xy 413.496742 -351.917411) (xy 413.450857 -351.946895)
			(xy 413.401242 -351.969547) (xy 413.348909 -351.984908) (xy 413.294923 -351.992664) (xy 413.267652 -351.9932)
			(xy 412.404052 -351.9932) (xy 412.384674 -351.992938) (xy 412.34612 -351.988991) (xy 412.32709 -351.985326)
			(xy 412.31566 -351.98304) (xy 412.293816 -351.988374) (xy 412.223966 -352.045524) (xy 412.215565 -352.053139)
			(xy 412.205803 -352.073573) (xy 412.20517 -352.084894) (xy 412.20517 -352.67773) (xy 412.204741 -352.687797)
			(xy 412.197015 -352.706391) (xy 412.190184 -352.713798) (xy 410.144614 -354.759368) (xy 412.022806 -354.759368)
			(xy 412.022806 -354.704832) (xy 412.030567 -354.65085) (xy 412.045931 -354.598521) (xy 412.068585 -354.548912)
			(xy 412.098067 -354.503031) (xy 412.133779 -354.461813) (xy 412.174993 -354.426096) (xy 412.22087 -354.396608)
			(xy 412.270476 -354.373948) (xy 412.322803 -354.358577) (xy 412.376784 -354.35081) (xy 412.404052 -354.35032)
			(xy 413.267652 -354.35032) (xy 413.294924 -354.350816) (xy 413.348913 -354.358572) (xy 413.401249 -354.373934)
			(xy 413.450866 -354.396588) (xy 413.496754 -354.426072) (xy 413.537978 -354.461788) (xy 413.573699 -354.503008)
			(xy 413.603189 -354.548891) (xy 413.625849 -354.598506) (xy 413.641217 -354.65084) (xy 413.64898 -354.704828)
			(xy 413.64898 -354.759372) (xy 413.64898 -354.759373) (xy 415.131684 -354.759373) (xy 415.131684 -354.704827)
			(xy 415.139446 -354.650837) (xy 415.154814 -354.598501) (xy 415.177473 -354.548884) (xy 415.206964 -354.502998)
			(xy 415.242684 -354.461776) (xy 415.283908 -354.426056) (xy 415.329795 -354.396568) (xy 415.379412 -354.37391)
			(xy 415.431748 -354.358544) (xy 415.485739 -354.350783) (xy 415.513012 -354.35032) (xy 416.376612 -354.35032)
			(xy 416.40388 -354.350843) (xy 416.457859 -354.358606) (xy 416.510185 -354.373972) (xy 416.559791 -354.396627)
			(xy 416.605668 -354.426112) (xy 416.646883 -354.461826) (xy 416.682595 -354.503041) (xy 416.712078 -354.548919)
			(xy 416.734733 -354.598526) (xy 416.750097 -354.650852) (xy 416.757858 -354.704832) (xy 416.757858 -354.759368)
			(xy 416.757858 -354.759369) (xy 418.240706 -354.759369) (xy 418.240706 -354.704831) (xy 418.248468 -354.650847)
			(xy 418.263832 -354.598517) (xy 418.286488 -354.548907) (xy 418.315972 -354.503025) (xy 418.351686 -354.461806)
			(xy 418.392902 -354.426089) (xy 418.438782 -354.396601) (xy 418.488391 -354.373942) (xy 418.54072 -354.358574)
			(xy 418.594703 -354.350808) (xy 418.621972 -354.35032) (xy 419.485572 -354.35032) (xy 419.512843 -354.350818)
			(xy 419.56683 -354.358576) (xy 419.619164 -354.373939) (xy 419.668778 -354.396594) (xy 419.714663 -354.42608)
			(xy 419.755885 -354.461795) (xy 419.791604 -354.503014) (xy 419.821092 -354.548897) (xy 419.843751 -354.59851)
			(xy 419.859118 -354.650842) (xy 419.86688 -354.704829) (xy 419.86688 -354.759371) (xy 419.86688 -354.759374)
			(xy 421.349584 -354.759374) (xy 421.349584 -354.704826) (xy 421.357347 -354.650834) (xy 421.372716 -354.598496)
			(xy 421.395377 -354.548879) (xy 421.424869 -354.502991) (xy 421.460591 -354.461768) (xy 421.501817 -354.426049)
			(xy 421.547707 -354.396561) (xy 421.597326 -354.373904) (xy 421.649665 -354.35854) (xy 421.703658 -354.350781)
			(xy 421.730932 -354.35032) (xy 422.594532 -354.35032) (xy 422.621799 -354.350845) (xy 422.675776 -354.35861)
			(xy 422.728099 -354.373977) (xy 422.777703 -354.396634) (xy 422.823578 -354.426119) (xy 422.86479 -354.461833)
			(xy 422.9005 -354.503048) (xy 422.929981 -354.548925) (xy 422.952634 -354.598531) (xy 422.967997 -354.650855)
			(xy 422.975758 -354.704833) (xy 422.975758 -354.759367) (xy 422.975758 -354.75937) (xy 424.458606 -354.75937)
			(xy 424.458606 -354.70483) (xy 424.466368 -354.650844) (xy 424.481734 -354.598513) (xy 424.504391 -354.548901)
			(xy 424.533877 -354.503018) (xy 424.569593 -354.461799) (xy 424.610812 -354.426082) (xy 424.656694 -354.396594)
			(xy 424.706305 -354.373937) (xy 424.758636 -354.35857) (xy 424.812622 -354.350807) (xy 424.839892 -354.35032)
			(xy 425.703492 -354.35032) (xy 425.730762 -354.350819) (xy 425.784747 -354.35858) (xy 425.837078 -354.373945)
			(xy 425.88669 -354.396601) (xy 425.932573 -354.426087) (xy 425.973792 -354.461802) (xy 426.009509 -354.503021)
			(xy 426.038996 -354.548903) (xy 426.061653 -354.598514) (xy 426.077019 -354.650845) (xy 426.084781 -354.70483)
			(xy 426.084781 -354.759368) (xy 427.567606 -354.759368) (xy 427.567606 -354.704832) (xy 427.575367 -354.65085)
			(xy 427.590731 -354.598521) (xy 427.613385 -354.548912) (xy 427.642867 -354.503031) (xy 427.678579 -354.461813)
			(xy 427.719793 -354.426096) (xy 427.76567 -354.396608) (xy 427.815276 -354.373948) (xy 427.867603 -354.358577)
			(xy 427.921584 -354.35081) (xy 427.948852 -354.35032) (xy 428.812452 -354.35032) (xy 428.839724 -354.350816)
			(xy 428.893713 -354.358572) (xy 428.946049 -354.373934) (xy 428.995666 -354.396588) (xy 429.041554 -354.426072)
			(xy 429.082778 -354.461788) (xy 429.118499 -354.503008) (xy 429.147989 -354.548891) (xy 429.170649 -354.598506)
			(xy 429.186017 -354.65084) (xy 429.19378 -354.704828) (xy 429.19378 -354.759372) (xy 429.19378 -354.759373)
			(xy 430.676484 -354.759373) (xy 430.676484 -354.704827) (xy 430.684246 -354.650837) (xy 430.699614 -354.598501)
			(xy 430.722273 -354.548884) (xy 430.751764 -354.502998) (xy 430.787484 -354.461776) (xy 430.828708 -354.426056)
			(xy 430.874595 -354.396568) (xy 430.924212 -354.37391) (xy 430.976548 -354.358544) (xy 431.030539 -354.350783)
			(xy 431.057812 -354.35032) (xy 431.921412 -354.35032) (xy 431.94868 -354.350843) (xy 432.002659 -354.358606)
			(xy 432.054985 -354.373972) (xy 432.104591 -354.396627) (xy 432.150468 -354.426112) (xy 432.191683 -354.461826)
			(xy 432.227395 -354.503041) (xy 432.256878 -354.548919) (xy 432.279533 -354.598526) (xy 432.294897 -354.650852)
			(xy 432.302658 -354.704832) (xy 432.302658 -354.759368) (xy 432.302658 -354.759369) (xy 433.785506 -354.759369)
			(xy 433.785506 -354.704831) (xy 433.793268 -354.650847) (xy 433.808632 -354.598517) (xy 433.831288 -354.548907)
			(xy 433.860772 -354.503025) (xy 433.896486 -354.461806) (xy 433.937702 -354.426089) (xy 433.983582 -354.396601)
			(xy 434.033191 -354.373942) (xy 434.08552 -354.358574) (xy 434.139503 -354.350808) (xy 434.166772 -354.35032)
			(xy 435.030372 -354.35032) (xy 435.057643 -354.350818) (xy 435.11163 -354.358576) (xy 435.163964 -354.373939)
			(xy 435.213578 -354.396594) (xy 435.259463 -354.42608) (xy 435.300685 -354.461795) (xy 435.336404 -354.503014)
			(xy 435.365892 -354.548897) (xy 435.388551 -354.59851) (xy 435.403918 -354.650842) (xy 435.41168 -354.704829)
			(xy 435.41168 -354.759371) (xy 435.41168 -354.759374) (xy 436.894384 -354.759374) (xy 436.894384 -354.704826)
			(xy 436.902147 -354.650834) (xy 436.917516 -354.598496) (xy 436.940177 -354.548879) (xy 436.969669 -354.502991)
			(xy 437.005391 -354.461768) (xy 437.046617 -354.426049) (xy 437.092507 -354.396561) (xy 437.142126 -354.373904)
			(xy 437.194465 -354.35854) (xy 437.248458 -354.350781) (xy 437.275732 -354.35032) (xy 438.139332 -354.35032)
			(xy 438.166599 -354.350845) (xy 438.220576 -354.35861) (xy 438.272899 -354.373977) (xy 438.322503 -354.396634)
			(xy 438.368378 -354.426119) (xy 438.40959 -354.461833) (xy 438.4453 -354.503048) (xy 438.474781 -354.548925)
			(xy 438.497434 -354.598531) (xy 438.512797 -354.650855) (xy 438.520558 -354.704833) (xy 438.520558 -354.759367)
			(xy 438.520558 -354.75937) (xy 440.003406 -354.75937) (xy 440.003406 -354.70483) (xy 440.011168 -354.650844)
			(xy 440.026534 -354.598513) (xy 440.049191 -354.548901) (xy 440.078677 -354.503018) (xy 440.114393 -354.461799)
			(xy 440.155612 -354.426082) (xy 440.201494 -354.396594) (xy 440.251105 -354.373937) (xy 440.303436 -354.35857)
			(xy 440.357422 -354.350807) (xy 440.384692 -354.35032) (xy 441.248292 -354.35032) (xy 441.275562 -354.350819)
			(xy 441.329547 -354.35858) (xy 441.381878 -354.373945) (xy 441.43149 -354.396601) (xy 441.477373 -354.426087)
			(xy 441.518592 -354.461802) (xy 441.554309 -354.503021) (xy 441.583796 -354.548903) (xy 441.606453 -354.598514)
			(xy 441.621819 -354.650845) (xy 441.629581 -354.70483) (xy 441.629581 -354.75937) (xy 441.621819 -354.813355)
			(xy 441.606453 -354.865686) (xy 441.583796 -354.915297) (xy 441.554309 -354.961179) (xy 441.518592 -355.002398)
			(xy 441.477373 -355.038113) (xy 441.43149 -355.067599) (xy 441.381878 -355.090255) (xy 441.329547 -355.10562)
			(xy 441.275562 -355.113381) (xy 441.248292 -355.113844) (xy 440.384692 -355.113844) (xy 440.357422 -355.113393)
			(xy 440.303436 -355.10563) (xy 440.251105 -355.090263) (xy 440.201494 -355.067606) (xy 440.155612 -355.038118)
			(xy 440.114393 -355.002401) (xy 440.078677 -354.961182) (xy 440.049191 -354.915299) (xy 440.026534 -354.865687)
			(xy 440.011168 -354.813356) (xy 440.003406 -354.75937) (xy 438.520558 -354.75937) (xy 438.512797 -354.813345)
			(xy 438.497434 -354.865669) (xy 438.474781 -354.915275) (xy 438.4453 -354.961152) (xy 438.40959 -355.002367)
			(xy 438.368378 -355.038081) (xy 438.322503 -355.067566) (xy 438.272899 -355.090223) (xy 438.220576 -355.10559)
			(xy 438.166599 -355.113355) (xy 438.139332 -355.113844) (xy 437.275732 -355.113844) (xy 437.248458 -355.113419)
			(xy 437.194465 -355.10566) (xy 437.142126 -355.090296) (xy 437.092507 -355.067639) (xy 437.046617 -355.038151)
			(xy 437.005391 -355.002432) (xy 436.969669 -354.961209) (xy 436.940177 -354.915321) (xy 436.917516 -354.865704)
			(xy 436.902147 -354.813366) (xy 436.894384 -354.759374) (xy 435.41168 -354.759374) (xy 435.403918 -354.813358)
			(xy 435.388551 -354.86569) (xy 435.365892 -354.915303) (xy 435.336404 -354.961186) (xy 435.300685 -355.002405)
			(xy 435.259463 -355.03812) (xy 435.213578 -355.067606) (xy 435.163964 -355.090261) (xy 435.11163 -355.105624)
			(xy 435.057643 -355.113382) (xy 435.030372 -355.113844) (xy 434.166772 -355.113844) (xy 434.139503 -355.113392)
			(xy 434.08552 -355.105626) (xy 434.033191 -355.090258) (xy 433.983582 -355.067599) (xy 433.937702 -355.038111)
			(xy 433.896486 -355.002394) (xy 433.860772 -354.961175) (xy 433.831288 -354.915293) (xy 433.808632 -354.865683)
			(xy 433.793268 -354.813353) (xy 433.785506 -354.759369) (xy 432.302658 -354.759369) (xy 432.294897 -354.813348)
			(xy 432.279533 -354.865674) (xy 432.256878 -354.915281) (xy 432.227395 -354.961159) (xy 432.191683 -355.002374)
			(xy 432.150468 -355.038088) (xy 432.104591 -355.067573) (xy 432.054985 -355.090228) (xy 432.002659 -355.105594)
			(xy 431.94868 -355.113357) (xy 431.921412 -355.113844) (xy 431.057812 -355.113844) (xy 431.030539 -355.113417)
			(xy 430.976548 -355.105656) (xy 430.924212 -355.09029) (xy 430.874595 -355.067632) (xy 430.828708 -355.038144)
			(xy 430.787484 -355.002424) (xy 430.751764 -354.961202) (xy 430.722273 -354.915316) (xy 430.699614 -354.865699)
			(xy 430.684246 -354.813363) (xy 430.676484 -354.759373) (xy 429.19378 -354.759373) (xy 429.186017 -354.81336)
			(xy 429.170649 -354.865694) (xy 429.147989 -354.915309) (xy 429.118499 -354.961192) (xy 429.082778 -355.002412)
			(xy 429.041554 -355.038128) (xy 428.995666 -355.067612) (xy 428.946049 -355.090266) (xy 428.893713 -355.105628)
			(xy 428.839724 -355.113384) (xy 428.812452 -355.113844) (xy 427.948852 -355.113844) (xy 427.921584 -355.11339)
			(xy 427.867603 -355.105623) (xy 427.815276 -355.090252) (xy 427.76567 -355.067592) (xy 427.719793 -355.038104)
			(xy 427.678579 -355.002387) (xy 427.642867 -354.961169) (xy 427.613385 -354.915288) (xy 427.590731 -354.865679)
			(xy 427.575367 -354.81335) (xy 427.567606 -354.759368) (xy 426.084781 -354.759368) (xy 426.084781 -354.75937)
			(xy 426.077019 -354.813355) (xy 426.061653 -354.865686) (xy 426.038996 -354.915297) (xy 426.009509 -354.961179)
			(xy 425.973792 -355.002398) (xy 425.932573 -355.038113) (xy 425.88669 -355.067599) (xy 425.837078 -355.090255)
			(xy 425.784747 -355.10562) (xy 425.730762 -355.113381) (xy 425.703492 -355.113844) (xy 424.839892 -355.113844)
			(xy 424.812622 -355.113393) (xy 424.758636 -355.10563) (xy 424.706305 -355.090263) (xy 424.656694 -355.067606)
			(xy 424.610812 -355.038118) (xy 424.569593 -355.002401) (xy 424.533877 -354.961182) (xy 424.504391 -354.915299)
			(xy 424.481734 -354.865687) (xy 424.466368 -354.813356) (xy 424.458606 -354.75937) (xy 422.975758 -354.75937)
			(xy 422.967997 -354.813345) (xy 422.952634 -354.865669) (xy 422.929981 -354.915275) (xy 422.9005 -354.961152)
			(xy 422.86479 -355.002367) (xy 422.823578 -355.038081) (xy 422.777703 -355.067566) (xy 422.728099 -355.090223)
			(xy 422.675776 -355.10559) (xy 422.621799 -355.113355) (xy 422.594532 -355.113844) (xy 421.730932 -355.113844)
			(xy 421.703658 -355.113419) (xy 421.649665 -355.10566) (xy 421.597326 -355.090296) (xy 421.547707 -355.067639)
			(xy 421.501817 -355.038151) (xy 421.460591 -355.002432) (xy 421.424869 -354.961209) (xy 421.395377 -354.915321)
			(xy 421.372716 -354.865704) (xy 421.357347 -354.813366) (xy 421.349584 -354.759374) (xy 419.86688 -354.759374)
			(xy 419.859118 -354.813358) (xy 419.843751 -354.86569) (xy 419.821092 -354.915303) (xy 419.791604 -354.961186)
			(xy 419.755885 -355.002405) (xy 419.714663 -355.03812) (xy 419.668778 -355.067606) (xy 419.619164 -355.090261)
			(xy 419.56683 -355.105624) (xy 419.512843 -355.113382) (xy 419.485572 -355.113844) (xy 418.621972 -355.113844)
			(xy 418.594703 -355.113392) (xy 418.54072 -355.105626) (xy 418.488391 -355.090258) (xy 418.438782 -355.067599)
			(xy 418.392902 -355.038111) (xy 418.351686 -355.002394) (xy 418.315972 -354.961175) (xy 418.286488 -354.915293)
			(xy 418.263832 -354.865683) (xy 418.248468 -354.813353) (xy 418.240706 -354.759369) (xy 416.757858 -354.759369)
			(xy 416.750097 -354.813348) (xy 416.734733 -354.865674) (xy 416.712078 -354.915281) (xy 416.682595 -354.961159)
			(xy 416.646883 -355.002374) (xy 416.605668 -355.038088) (xy 416.559791 -355.067573) (xy 416.510185 -355.090228)
			(xy 416.457859 -355.105594) (xy 416.40388 -355.113357) (xy 416.376612 -355.113844) (xy 415.513012 -355.113844)
			(xy 415.485739 -355.113417) (xy 415.431748 -355.105656) (xy 415.379412 -355.09029) (xy 415.329795 -355.067632)
			(xy 415.283908 -355.038144) (xy 415.242684 -355.002424) (xy 415.206964 -354.961202) (xy 415.177473 -354.915316)
			(xy 415.154814 -354.865699) (xy 415.139446 -354.813363) (xy 415.131684 -354.759373) (xy 413.64898 -354.759373)
			(xy 413.641217 -354.81336) (xy 413.625849 -354.865694) (xy 413.603189 -354.915309) (xy 413.573699 -354.961192)
			(xy 413.537978 -355.002412) (xy 413.496754 -355.038128) (xy 413.450866 -355.067612) (xy 413.401249 -355.090266)
			(xy 413.348913 -355.105628) (xy 413.294924 -355.113384) (xy 413.267652 -355.113844) (xy 412.404052 -355.113844)
			(xy 412.376784 -355.11339) (xy 412.322803 -355.105623) (xy 412.270476 -355.090252) (xy 412.22087 -355.067592)
			(xy 412.174993 -355.038104) (xy 412.133779 -355.002387) (xy 412.098067 -354.961169) (xy 412.068585 -354.915288)
			(xy 412.045931 -354.865679) (xy 412.030567 -354.81335) (xy 412.022806 -354.759368) (xy 410.144614 -354.759368)
			(xy 407.119017 -357.784965) (xy 412.022854 -357.784965) (xy 412.022854 -357.730435) (xy 412.030614 -357.67646)
			(xy 412.045976 -357.624138) (xy 412.068627 -357.574535) (xy 412.098106 -357.52866) (xy 412.133813 -357.487447)
			(xy 412.175022 -357.451735) (xy 412.220893 -357.42225) (xy 412.270493 -357.399593) (xy 412.322813 -357.384224)
			(xy 412.376787 -357.376458) (xy 412.404052 -357.375968) (xy 413.267652 -357.375968) (xy 413.294927 -357.376368)
			(xy 413.348924 -357.384125) (xy 413.401266 -357.399489) (xy 413.450889 -357.422145) (xy 413.496783 -357.451634)
			(xy 413.538012 -357.487354) (xy 413.573737 -357.528579) (xy 413.603232 -357.574468) (xy 413.625894 -357.624089)
			(xy 413.641264 -357.676429) (xy 413.649028 -357.730425) (xy 413.649028 -357.784969) (xy 415.131731 -357.784969)
			(xy 415.131731 -357.730431) (xy 415.139493 -357.676447) (xy 415.154859 -357.624117) (xy 415.177516 -357.574507)
			(xy 415.207002 -357.528627) (xy 415.242718 -357.487409) (xy 415.283936 -357.451695) (xy 415.329818 -357.42221)
			(xy 415.379429 -357.399555) (xy 415.431759 -357.384191) (xy 415.485743 -357.376431) (xy 415.513012 -357.375968)
			(xy 416.376612 -357.375968) (xy 416.403883 -357.376395) (xy 416.457869 -357.384159) (xy 416.510202 -357.399527)
			(xy 416.559814 -357.422185) (xy 416.605697 -357.451674) (xy 416.646917 -357.487392) (xy 416.682633 -357.528612)
			(xy 416.712121 -357.574496) (xy 416.734778 -357.62411) (xy 416.750144 -357.676442) (xy 416.757906 -357.730429)
			(xy 416.757906 -357.784966) (xy 418.240754 -357.784966) (xy 418.240754 -357.730434) (xy 418.248515 -357.676457)
			(xy 418.263877 -357.624134) (xy 418.28653 -357.57453) (xy 418.316011 -357.528654) (xy 418.35172 -357.48744)
			(xy 418.392931 -357.451727) (xy 418.438805 -357.422243) (xy 418.488408 -357.399587) (xy 418.54073 -357.384221)
			(xy 418.594706 -357.376456) (xy 418.621972 -357.375968) (xy 419.485572 -357.375968) (xy 419.512846 -357.37637)
			(xy 419.566841 -357.384129) (xy 419.619181 -357.399494) (xy 419.668801 -357.422152) (xy 419.714692 -357.451641)
			(xy 419.755919 -357.487361) (xy 419.791642 -357.528585) (xy 419.821135 -357.574474) (xy 419.843796 -357.624093)
			(xy 419.859165 -357.676432) (xy 419.866928 -357.730426) (xy 419.866928 -357.78497) (xy 421.349632 -357.78497)
			(xy 421.349632 -357.73043) (xy 421.357394 -357.676444) (xy 421.372761 -357.624113) (xy 421.395419 -357.574502)
			(xy 421.424907 -357.52862) (xy 421.460625 -357.487402) (xy 421.501846 -357.451688) (xy 421.54773 -357.422203)
			(xy 421.597343 -357.399549) (xy 421.649676 -357.384187) (xy 421.703662 -357.376429) (xy 421.730932 -357.375968)
			(xy 422.594532 -357.375968) (xy 422.621802 -357.376397) (xy 422.675786 -357.384163) (xy 422.728116 -357.399532)
			(xy 422.777726 -357.422192) (xy 422.823607 -357.451681) (xy 422.864824 -357.487399) (xy 422.900538 -357.528619)
			(xy 422.930024 -357.574502) (xy 422.952679 -357.624114) (xy 422.968044 -357.676445) (xy 422.975806 -357.73043)
			(xy 422.975806 -357.784967) (xy 424.458654 -357.784967) (xy 424.458654 -357.730433) (xy 424.466415 -357.676454)
			(xy 424.481779 -357.62413) (xy 424.504433 -357.574524) (xy 424.533916 -357.528647) (xy 424.569627 -357.487433)
			(xy 424.610841 -357.45172) (xy 424.656717 -357.422237) (xy 424.706322 -357.399582) (xy 424.758647 -357.384217)
			(xy 424.812625 -357.376455) (xy 424.839892 -357.375968) (xy 425.703492 -357.375968) (xy 425.730766 -357.376371)
			(xy 425.784757 -357.384133) (xy 425.837095 -357.3995) (xy 425.886713 -357.422159) (xy 425.932602 -357.451648)
			(xy 425.973826 -357.487368) (xy 426.009547 -357.528592) (xy 426.039038 -357.57448) (xy 426.061698 -357.624097)
			(xy 426.077065 -357.676435) (xy 426.084828 -357.730426) (xy 426.084828 -357.784965) (xy 427.567654 -357.784965)
			(xy 427.567654 -357.730435) (xy 427.575414 -357.67646) (xy 427.590776 -357.624138) (xy 427.613427 -357.574535)
			(xy 427.642906 -357.52866) (xy 427.678613 -357.487447) (xy 427.719822 -357.451735) (xy 427.765693 -357.42225)
			(xy 427.815293 -357.399593) (xy 427.867613 -357.384224) (xy 427.921587 -357.376458) (xy 427.948852 -357.375968)
			(xy 428.812452 -357.375968) (xy 428.839727 -357.376368) (xy 428.893724 -357.384125) (xy 428.946066 -357.399489)
			(xy 428.995689 -357.422145) (xy 429.041583 -357.451634) (xy 429.082812 -357.487354) (xy 429.118537 -357.528579)
			(xy 429.148032 -357.574468) (xy 429.170694 -357.624089) (xy 429.186064 -357.676429) (xy 429.193828 -357.730425)
			(xy 429.193828 -357.784969) (xy 430.676531 -357.784969) (xy 430.676531 -357.730431) (xy 430.684293 -357.676447)
			(xy 430.699659 -357.624117) (xy 430.722316 -357.574507) (xy 430.751802 -357.528627) (xy 430.787518 -357.487409)
			(xy 430.828736 -357.451695) (xy 430.874618 -357.42221) (xy 430.924229 -357.399555) (xy 430.976559 -357.384191)
			(xy 431.030543 -357.376431) (xy 431.057812 -357.375968) (xy 431.921412 -357.375968) (xy 431.948683 -357.376395)
			(xy 432.002669 -357.384159) (xy 432.055002 -357.399527) (xy 432.104614 -357.422185) (xy 432.150497 -357.451674)
			(xy 432.191717 -357.487392) (xy 432.227433 -357.528612) (xy 432.256921 -357.574496) (xy 432.279578 -357.62411)
			(xy 432.294944 -357.676442) (xy 432.302706 -357.730429) (xy 432.302706 -357.784966) (xy 433.785554 -357.784966)
			(xy 433.785554 -357.730434) (xy 433.793315 -357.676457) (xy 433.808677 -357.624134) (xy 433.83133 -357.57453)
			(xy 433.860811 -357.528654) (xy 433.89652 -357.48744) (xy 433.937731 -357.451727) (xy 433.983605 -357.422243)
			(xy 434.033208 -357.399587) (xy 434.08553 -357.384221) (xy 434.139506 -357.376456) (xy 434.166772 -357.375968)
			(xy 435.030372 -357.375968) (xy 435.057646 -357.37637) (xy 435.111641 -357.384129) (xy 435.163981 -357.399494)
			(xy 435.213601 -357.422152) (xy 435.259492 -357.451641) (xy 435.300719 -357.487361) (xy 435.336442 -357.528585)
			(xy 435.365935 -357.574474) (xy 435.388596 -357.624093) (xy 435.403965 -357.676432) (xy 435.411728 -357.730426)
			(xy 435.411728 -357.78497) (xy 436.894432 -357.78497) (xy 436.894432 -357.73043) (xy 436.902194 -357.676444)
			(xy 436.917561 -357.624113) (xy 436.940219 -357.574502) (xy 436.969707 -357.52862) (xy 437.005425 -357.487402)
			(xy 437.046646 -357.451688) (xy 437.09253 -357.422203) (xy 437.142143 -357.399549) (xy 437.194476 -357.384187)
			(xy 437.248462 -357.376429) (xy 437.275732 -357.375968) (xy 438.139332 -357.375968) (xy 438.166602 -357.376397)
			(xy 438.220586 -357.384163) (xy 438.272916 -357.399532) (xy 438.322526 -357.422192) (xy 438.368407 -357.451681)
			(xy 438.409624 -357.487399) (xy 438.445338 -357.528619) (xy 438.474824 -357.574502) (xy 438.497479 -357.624114)
			(xy 438.512844 -357.676445) (xy 438.520606 -357.73043) (xy 438.520606 -357.784967) (xy 440.003454 -357.784967)
			(xy 440.003454 -357.730433) (xy 440.011215 -357.676454) (xy 440.026579 -357.62413) (xy 440.049233 -357.574524)
			(xy 440.078716 -357.528647) (xy 440.114427 -357.487433) (xy 440.155641 -357.45172) (xy 440.201517 -357.422237)
			(xy 440.251122 -357.399582) (xy 440.303447 -357.384217) (xy 440.357425 -357.376455) (xy 440.384692 -357.375968)
			(xy 441.248292 -357.375968) (xy 441.275566 -357.376371) (xy 441.329557 -357.384133) (xy 441.381895 -357.3995)
			(xy 441.431513 -357.422159) (xy 441.477402 -357.451648) (xy 441.518626 -357.487368) (xy 441.554347 -357.528592)
			(xy 441.583838 -357.57448) (xy 441.606498 -357.624097) (xy 441.621865 -357.676435) (xy 441.629628 -357.730426)
			(xy 441.629628 -357.784974) (xy 441.621865 -357.838965) (xy 441.606498 -357.891303) (xy 441.583838 -357.94092)
			(xy 441.554347 -357.986808) (xy 441.518626 -358.028032) (xy 441.477402 -358.063752) (xy 441.431513 -358.093241)
			(xy 441.381895 -358.1159) (xy 441.329557 -358.131267) (xy 441.275566 -358.139029) (xy 441.248292 -358.139492)
			(xy 440.384692 -358.139492) (xy 440.357425 -358.138945) (xy 440.303447 -358.131183) (xy 440.251122 -358.115818)
			(xy 440.201517 -358.093163) (xy 440.155641 -358.06368) (xy 440.114427 -358.027967) (xy 440.078716 -357.986753)
			(xy 440.049233 -357.940876) (xy 440.026579 -357.89127) (xy 440.011215 -357.838946) (xy 440.003454 -357.784967)
			(xy 438.520606 -357.784967) (xy 438.520606 -357.78497) (xy 438.512844 -357.838955) (xy 438.497479 -357.891286)
			(xy 438.474824 -357.940898) (xy 438.445338 -357.986781) (xy 438.409624 -358.028001) (xy 438.368407 -358.063719)
			(xy 438.322526 -358.093208) (xy 438.272916 -358.115868) (xy 438.220586 -358.131237) (xy 438.166602 -358.139003)
			(xy 438.139332 -358.139492) (xy 437.275732 -358.139492) (xy 437.248462 -358.138971) (xy 437.194476 -358.131213)
			(xy 437.142143 -358.115851) (xy 437.09253 -358.093197) (xy 437.046646 -358.063712) (xy 437.005425 -358.027998)
			(xy 436.969707 -357.98678) (xy 436.940219 -357.940898) (xy 436.917561 -357.891287) (xy 436.902194 -357.838956)
			(xy 436.894432 -357.78497) (xy 435.411728 -357.78497) (xy 435.411728 -357.784974) (xy 435.403965 -357.838968)
			(xy 435.388596 -357.891307) (xy 435.365935 -357.940926) (xy 435.336442 -357.986815) (xy 435.300719 -358.028039)
			(xy 435.259492 -358.063759) (xy 435.213601 -358.093248) (xy 435.163981 -358.115906) (xy 435.111641 -358.131271)
			(xy 435.057646 -358.13903) (xy 435.030372 -358.139492) (xy 434.166772 -358.139492) (xy 434.139506 -358.138944)
			(xy 434.08553 -358.131179) (xy 434.033208 -358.115813) (xy 433.983605 -358.093157) (xy 433.937731 -358.063673)
			(xy 433.89652 -358.02796) (xy 433.860811 -357.986746) (xy 433.83133 -357.94087) (xy 433.808677 -357.891266)
			(xy 433.793315 -357.838943) (xy 433.785554 -357.784966) (xy 432.302706 -357.784966) (xy 432.302706 -357.784971)
			(xy 432.294944 -357.838958) (xy 432.279578 -357.89129) (xy 432.256921 -357.940904) (xy 432.227433 -357.986788)
			(xy 432.191717 -358.028008) (xy 432.150497 -358.063726) (xy 432.104614 -358.093215) (xy 432.055002 -358.115873)
			(xy 432.002669 -358.131241) (xy 431.948683 -358.139005) (xy 431.921412 -358.139492) (xy 431.057812 -358.139492)
			(xy 431.030543 -358.138969) (xy 430.976559 -358.131209) (xy 430.924229 -358.115845) (xy 430.874618 -358.09319)
			(xy 430.828736 -358.063705) (xy 430.787518 -358.027991) (xy 430.751802 -357.986773) (xy 430.722316 -357.940893)
			(xy 430.699659 -357.891283) (xy 430.684293 -357.838953) (xy 430.676531 -357.784969) (xy 429.193828 -357.784969)
			(xy 429.193828 -357.784975) (xy 429.186064 -357.838971) (xy 429.170694 -357.891311) (xy 429.148032 -357.940932)
			(xy 429.118537 -357.986821) (xy 429.082812 -358.028046) (xy 429.041583 -358.063766) (xy 428.995689 -358.093255)
			(xy 428.946066 -358.115911) (xy 428.893724 -358.131275) (xy 428.839727 -358.139032) (xy 428.812452 -358.139492)
			(xy 427.948852 -358.139492) (xy 427.921587 -358.138942) (xy 427.867613 -358.131176) (xy 427.815293 -358.115807)
			(xy 427.765693 -358.09315) (xy 427.719822 -358.063665) (xy 427.678613 -358.027953) (xy 427.642906 -357.98674)
			(xy 427.613427 -357.940865) (xy 427.590776 -357.891262) (xy 427.575414 -357.83894) (xy 427.567654 -357.784965)
			(xy 426.084828 -357.784965) (xy 426.084828 -357.784974) (xy 426.077065 -357.838965) (xy 426.061698 -357.891303)
			(xy 426.039038 -357.94092) (xy 426.009547 -357.986808) (xy 425.973826 -358.028032) (xy 425.932602 -358.063752)
			(xy 425.886713 -358.093241) (xy 425.837095 -358.1159) (xy 425.784757 -358.131267) (xy 425.730766 -358.139029)
			(xy 425.703492 -358.139492) (xy 424.839892 -358.139492) (xy 424.812625 -358.138945) (xy 424.758647 -358.131183)
			(xy 424.706322 -358.115818) (xy 424.656717 -358.093163) (xy 424.610841 -358.06368) (xy 424.569627 -358.027967)
			(xy 424.533916 -357.986753) (xy 424.504433 -357.940876) (xy 424.481779 -357.89127) (xy 424.466415 -357.838946)
			(xy 424.458654 -357.784967) (xy 422.975806 -357.784967) (xy 422.975806 -357.78497) (xy 422.968044 -357.838955)
			(xy 422.952679 -357.891286) (xy 422.930024 -357.940898) (xy 422.900538 -357.986781) (xy 422.864824 -358.028001)
			(xy 422.823607 -358.063719) (xy 422.777726 -358.093208) (xy 422.728116 -358.115868) (xy 422.675786 -358.131237)
			(xy 422.621802 -358.139003) (xy 422.594532 -358.139492) (xy 421.730932 -358.139492) (xy 421.703662 -358.138971)
			(xy 421.649676 -358.131213) (xy 421.597343 -358.115851) (xy 421.54773 -358.093197) (xy 421.501846 -358.063712)
			(xy 421.460625 -358.027998) (xy 421.424907 -357.98678) (xy 421.395419 -357.940898) (xy 421.372761 -357.891287)
			(xy 421.357394 -357.838956) (xy 421.349632 -357.78497) (xy 419.866928 -357.78497) (xy 419.866928 -357.784974)
			(xy 419.859165 -357.838968) (xy 419.843796 -357.891307) (xy 419.821135 -357.940926) (xy 419.791642 -357.986815)
			(xy 419.755919 -358.028039) (xy 419.714692 -358.063759) (xy 419.668801 -358.093248) (xy 419.619181 -358.115906)
			(xy 419.566841 -358.131271) (xy 419.512846 -358.13903) (xy 419.485572 -358.139492) (xy 418.621972 -358.139492)
			(xy 418.594706 -358.138944) (xy 418.54073 -358.131179) (xy 418.488408 -358.115813) (xy 418.438805 -358.093157)
			(xy 418.392931 -358.063673) (xy 418.35172 -358.02796) (xy 418.316011 -357.986746) (xy 418.28653 -357.94087)
			(xy 418.263877 -357.891266) (xy 418.248515 -357.838943) (xy 418.240754 -357.784966) (xy 416.757906 -357.784966)
			(xy 416.757906 -357.784971) (xy 416.750144 -357.838958) (xy 416.734778 -357.89129) (xy 416.712121 -357.940904)
			(xy 416.682633 -357.986788) (xy 416.646917 -358.028008) (xy 416.605697 -358.063726) (xy 416.559814 -358.093215)
			(xy 416.510202 -358.115873) (xy 416.457869 -358.131241) (xy 416.403883 -358.139005) (xy 416.376612 -358.139492)
			(xy 415.513012 -358.139492) (xy 415.485743 -358.138969) (xy 415.431759 -358.131209) (xy 415.379429 -358.115845)
			(xy 415.329818 -358.09319) (xy 415.283936 -358.063705) (xy 415.242718 -358.027991) (xy 415.207002 -357.986773)
			(xy 415.177516 -357.940893) (xy 415.154859 -357.891283) (xy 415.139493 -357.838953) (xy 415.131731 -357.784969)
			(xy 413.649028 -357.784969) (xy 413.649028 -357.784975) (xy 413.641264 -357.838971) (xy 413.625894 -357.891311)
			(xy 413.603232 -357.940932) (xy 413.573737 -357.986821) (xy 413.538012 -358.028046) (xy 413.496783 -358.063766)
			(xy 413.450889 -358.093255) (xy 413.401266 -358.115911) (xy 413.348924 -358.131275) (xy 413.294927 -358.139032)
			(xy 413.267652 -358.139492) (xy 412.404052 -358.139492) (xy 412.376787 -358.138942) (xy 412.322813 -358.131176)
			(xy 412.270493 -358.115807) (xy 412.220893 -358.09315) (xy 412.175022 -358.063665) (xy 412.133813 -358.027953)
			(xy 412.098106 -357.98674) (xy 412.068627 -357.940865) (xy 412.045976 -357.891262) (xy 412.030614 -357.83894)
			(xy 412.022854 -357.784965) (xy 407.119017 -357.784965) (xy 406.470358 -358.433624) (xy 406.467168 -358.436928)
			(xy 406.461928 -358.444468) (xy 406.459944 -358.44861) (xy 405.79929 -359.917238) (xy 405.781184 -359.956338)
			(xy 405.739156 -360.031565) (xy 405.690793 -360.102885) (xy 405.636456 -360.169766) (xy 405.57655 -360.231709)
			(xy 405.511523 -360.288251) (xy 405.476964 -360.313986) (xy 402.21027 -362.694728) (xy 402.204174 -362.699808)
			(xy 402.098256 -362.805726) (xy 449.753734 -362.805726) (xy 449.757805 -362.750104) (xy 449.769931 -362.695667)
			(xy 449.789854 -362.643576) (xy 449.81715 -362.594941) (xy 449.851236 -362.550798) (xy 449.891385 -362.512089)
			(xy 449.936743 -362.479638) (xy 449.986343 -362.454137) (xy 450.039127 -362.43613) (xy 450.09397 -362.426)
			(xy 450.149704 -362.423963) (xy 450.205141 -362.430063) (xy 450.259098 -362.444169) (xy 450.310427 -362.465981)
			(xy 450.358033 -362.495035) (xy 450.400901 -362.53071) (xy 450.438118 -362.572247) (xy 450.468891 -362.61876)
			(xy 450.492563 -362.669257) (xy 450.508631 -362.722664) (xy 450.516751 -362.77784) (xy 450.51726 -362.805726)
			(xy 450.516751 -362.833612) (xy 450.508631 -362.888788) (xy 450.492563 -362.942195) (xy 450.468891 -362.992692)
			(xy 450.438118 -363.039205) (xy 450.400901 -363.080742) (xy 450.358033 -363.116417) (xy 450.310427 -363.145471)
			(xy 450.259098 -363.167283) (xy 450.205141 -363.181389) (xy 450.149704 -363.187489) (xy 450.09397 -363.185452)
			(xy 450.039127 -363.175322) (xy 449.986343 -363.157315) (xy 449.936743 -363.131814) (xy 449.891385 -363.099363)
			(xy 449.851236 -363.060654) (xy 449.81715 -363.016511) (xy 449.789854 -362.967876) (xy 449.769931 -362.915785)
			(xy 449.757805 -362.861348) (xy 449.753734 -362.805726) (xy 402.098256 -362.805726) (xy 401.017486 -363.886496)
			(xy 459.91729 -363.886496) (xy 459.921361 -363.830874) (xy 459.933487 -363.776437) (xy 459.95341 -363.724346)
			(xy 459.980706 -363.675711) (xy 460.014792 -363.631568) (xy 460.054941 -363.592859) (xy 460.100299 -363.560408)
			(xy 460.149899 -363.534907) (xy 460.202683 -363.5169) (xy 460.257526 -363.50677) (xy 460.31326 -363.504733)
			(xy 460.368697 -363.510833) (xy 460.422654 -363.524939) (xy 460.473983 -363.546751) (xy 460.521589 -363.575805)
			(xy 460.564457 -363.61148) (xy 460.601674 -363.653017) (xy 460.632447 -363.69953) (xy 460.656119 -363.750027)
			(xy 460.672187 -363.803434) (xy 460.680307 -363.85861) (xy 460.680816 -363.886496) (xy 460.680307 -363.914382)
			(xy 460.672187 -363.969558) (xy 460.656119 -364.022965) (xy 460.632447 -364.073462) (xy 460.601674 -364.119975)
			(xy 460.564457 -364.161512) (xy 460.521589 -364.197187) (xy 460.473983 -364.226241) (xy 460.422654 -364.248053)
			(xy 460.368697 -364.262159) (xy 460.31326 -364.268259) (xy 460.257526 -364.266222) (xy 460.202683 -364.256092)
			(xy 460.149899 -364.238085) (xy 460.100299 -364.212584) (xy 460.054941 -364.180133) (xy 460.014792 -364.141424)
			(xy 459.980706 -364.097281) (xy 459.95341 -364.048646) (xy 459.933487 -363.996555) (xy 459.921361 -363.942118)
			(xy 459.91729 -363.886496) (xy 401.017486 -363.886496) (xy 400.402298 -364.501684) (xy 457.804772 -364.501684)
			(xy 457.808843 -364.446062) (xy 457.820969 -364.391625) (xy 457.840892 -364.339534) (xy 457.868188 -364.290899)
			(xy 457.902274 -364.246756) (xy 457.942423 -364.208047) (xy 457.987781 -364.175596) (xy 458.037381 -364.150095)
			(xy 458.090165 -364.132088) (xy 458.145008 -364.121958) (xy 458.200742 -364.119921) (xy 458.256179 -364.126021)
			(xy 458.310136 -364.140127) (xy 458.361465 -364.161939) (xy 458.409071 -364.190993) (xy 458.451939 -364.226668)
			(xy 458.489156 -364.268205) (xy 458.519929 -364.314718) (xy 458.543601 -364.365215) (xy 458.559669 -364.418622)
			(xy 458.567789 -364.473798) (xy 458.568298 -364.501684) (xy 458.567789 -364.52957) (xy 458.559669 -364.584746)
			(xy 458.543601 -364.638153) (xy 458.519929 -364.68865) (xy 458.489156 -364.735163) (xy 458.451939 -364.7767)
			(xy 458.409071 -364.812375) (xy 458.361465 -364.841429) (xy 458.310136 -364.863241) (xy 458.256179 -364.877347)
			(xy 458.200742 -364.883447) (xy 458.145008 -364.88141) (xy 458.090165 -364.87128) (xy 458.037381 -364.853273)
			(xy 457.987781 -364.827772) (xy 457.942423 -364.795321) (xy 457.902274 -364.756612) (xy 457.868188 -364.712469)
			(xy 457.840892 -364.663834) (xy 457.820969 -364.611743) (xy 457.808843 -364.557306) (xy 457.804772 -364.501684)
			(xy 400.402298 -364.501684) (xy 399.626836 -365.277146) (xy 451.28764 -365.277146) (xy 451.291711 -365.221524)
			(xy 451.303837 -365.167087) (xy 451.32376 -365.114996) (xy 451.351056 -365.066361) (xy 451.385142 -365.022218)
			(xy 451.425291 -364.983509) (xy 451.470649 -364.951058) (xy 451.520249 -364.925557) (xy 451.573033 -364.90755)
			(xy 451.627876 -364.89742) (xy 451.68361 -364.895383) (xy 451.739047 -364.901483) (xy 451.793004 -364.915589)
			(xy 451.844333 -364.937401) (xy 451.891939 -364.966455) (xy 451.934807 -365.00213) (xy 451.972024 -365.043667)
			(xy 452.002797 -365.09018) (xy 452.025073 -365.1377) (xy 452.545194 -365.1377) (xy 452.549265 -365.082078)
			(xy 452.561391 -365.027641) (xy 452.581314 -364.97555) (xy 452.60861 -364.926915) (xy 452.642696 -364.882772)
			(xy 452.682845 -364.844063) (xy 452.728203 -364.811612) (xy 452.777803 -364.786111) (xy 452.830587 -364.768104)
			(xy 452.88543 -364.757974) (xy 452.941164 -364.755937) (xy 452.996601 -364.762037) (xy 453.050558 -364.776143)
			(xy 453.101887 -364.797955) (xy 453.149493 -364.827009) (xy 453.192361 -364.862684) (xy 453.229578 -364.904221)
			(xy 453.260351 -364.950734) (xy 453.284023 -365.001231) (xy 453.300091 -365.054638) (xy 453.308211 -365.109814)
			(xy 453.30872 -365.1377) (xy 453.308211 -365.165586) (xy 453.304278 -365.19231) (xy 453.705212 -365.19231)
			(xy 453.709283 -365.136688) (xy 453.721409 -365.082251) (xy 453.741332 -365.03016) (xy 453.768628 -364.981525)
			(xy 453.802714 -364.937382) (xy 453.842863 -364.898673) (xy 453.888221 -364.866222) (xy 453.937821 -364.840721)
			(xy 453.990605 -364.822714) (xy 454.045448 -364.812584) (xy 454.101182 -364.810547) (xy 454.156619 -364.816647)
			(xy 454.210576 -364.830753) (xy 454.261905 -364.852565) (xy 454.309511 -364.881619) (xy 454.352379 -364.917294)
			(xy 454.389596 -364.958831) (xy 454.420369 -365.005344) (xy 454.444041 -365.055841) (xy 454.460109 -365.109248)
			(xy 454.468229 -365.164424) (xy 454.468738 -365.19231) (xy 454.468229 -365.220196) (xy 454.460109 -365.275372)
			(xy 454.444041 -365.328779) (xy 454.420369 -365.379276) (xy 454.389596 -365.425789) (xy 454.352379 -365.467326)
			(xy 454.309511 -365.503001) (xy 454.261905 -365.532055) (xy 454.210576 -365.553867) (xy 454.156619 -365.567973)
			(xy 454.101182 -365.574073) (xy 454.045448 -365.572036) (xy 453.990605 -365.561906) (xy 453.937821 -365.543899)
			(xy 453.888221 -365.518398) (xy 453.842863 -365.485947) (xy 453.802714 -365.447238) (xy 453.768628 -365.403095)
			(xy 453.741332 -365.35446) (xy 453.721409 -365.302369) (xy 453.709283 -365.247932) (xy 453.705212 -365.19231)
			(xy 453.304278 -365.19231) (xy 453.300091 -365.220762) (xy 453.284023 -365.274169) (xy 453.260351 -365.324666)
			(xy 453.229578 -365.371179) (xy 453.192361 -365.412716) (xy 453.149493 -365.448391) (xy 453.101887 -365.477445)
			(xy 453.050558 -365.499257) (xy 452.996601 -365.513363) (xy 452.941164 -365.519463) (xy 452.88543 -365.517426)
			(xy 452.830587 -365.507296) (xy 452.777803 -365.489289) (xy 452.728203 -365.463788) (xy 452.682845 -365.431337)
			(xy 452.642696 -365.392628) (xy 452.60861 -365.348485) (xy 452.581314 -365.29985) (xy 452.561391 -365.247759)
			(xy 452.549265 -365.193322) (xy 452.545194 -365.1377) (xy 452.025073 -365.1377) (xy 452.026469 -365.140677)
			(xy 452.042537 -365.194084) (xy 452.050657 -365.24926) (xy 452.051166 -365.277146) (xy 452.050657 -365.305032)
			(xy 452.042537 -365.360208) (xy 452.026469 -365.413615) (xy 452.002797 -365.464112) (xy 451.972024 -365.510625)
			(xy 451.934807 -365.552162) (xy 451.891939 -365.587837) (xy 451.844333 -365.616891) (xy 451.793004 -365.638703)
			(xy 451.739047 -365.652809) (xy 451.68361 -365.658909) (xy 451.627876 -365.656872) (xy 451.573033 -365.646742)
			(xy 451.520249 -365.628735) (xy 451.470649 -365.603234) (xy 451.425291 -365.570783) (xy 451.385142 -365.532074)
			(xy 451.351056 -365.487931) (xy 451.32376 -365.439296) (xy 451.303837 -365.387205) (xy 451.291711 -365.332768)
			(xy 451.28764 -365.277146) (xy 399.626836 -365.277146) (xy 399.015966 -365.888016) (xy 406.102564 -365.888016)
			(xy 406.106635 -365.832394) (xy 406.118761 -365.777957) (xy 406.138684 -365.725866) (xy 406.16598 -365.677231)
			(xy 406.200066 -365.633088) (xy 406.240215 -365.594379) (xy 406.285573 -365.561928) (xy 406.335173 -365.536427)
			(xy 406.387957 -365.51842) (xy 406.4428 -365.50829) (xy 406.498534 -365.506253) (xy 406.553971 -365.512353)
			(xy 406.607928 -365.526459) (xy 406.659257 -365.548271) (xy 406.706863 -365.577325) (xy 406.749731 -365.613)
			(xy 406.786948 -365.654537) (xy 406.817721 -365.70105) (xy 406.841393 -365.751547) (xy 406.857461 -365.804954)
			(xy 406.865581 -365.86013) (xy 406.86609 -365.888016) (xy 406.865581 -365.915902) (xy 406.857461 -365.971078)
			(xy 406.841393 -366.024485) (xy 406.817721 -366.074982) (xy 406.786948 -366.121495) (xy 406.749731 -366.163032)
			(xy 406.706863 -366.198707) (xy 406.659257 -366.227761) (xy 406.607928 -366.249573) (xy 406.553971 -366.263679)
			(xy 406.498534 -366.269779) (xy 406.4428 -366.267742) (xy 406.387957 -366.257612) (xy 406.335173 -366.239605)
			(xy 406.285573 -366.214104) (xy 406.240215 -366.181653) (xy 406.200066 -366.142944) (xy 406.16598 -366.098801)
			(xy 406.138684 -366.050166) (xy 406.118761 -365.998075) (xy 406.106635 -365.943638) (xy 406.102564 -365.888016)
			(xy 399.015966 -365.888016) (xy 398.494504 -366.409478) (xy 405.202642 -366.409478) (xy 405.206713 -366.353856)
			(xy 405.218839 -366.299419) (xy 405.238762 -366.247328) (xy 405.266058 -366.198693) (xy 405.300144 -366.15455)
			(xy 405.340293 -366.115841) (xy 405.385651 -366.08339) (xy 405.435251 -366.057889) (xy 405.488035 -366.039882)
			(xy 405.542878 -366.029752) (xy 405.598612 -366.027715) (xy 405.654049 -366.033815) (xy 405.708006 -366.047921)
			(xy 405.759335 -366.069733) (xy 405.806941 -366.098787) (xy 405.849809 -366.134462) (xy 405.887026 -366.175999)
			(xy 405.917799 -366.222512) (xy 405.941471 -366.273009) (xy 405.957539 -366.326416) (xy 405.965659 -366.381592)
			(xy 405.966168 -366.409478) (xy 405.965659 -366.437364) (xy 405.957539 -366.49254) (xy 405.941471 -366.545947)
			(xy 405.917799 -366.596444) (xy 405.887026 -366.642957) (xy 405.849809 -366.684494) (xy 405.826839 -366.70361)
			(xy 453.285096 -366.70361) (xy 453.289167 -366.647988) (xy 453.301293 -366.593551) (xy 453.321216 -366.54146)
			(xy 453.348512 -366.492825) (xy 453.382598 -366.448682) (xy 453.422747 -366.409973) (xy 453.468105 -366.377522)
			(xy 453.517705 -366.352021) (xy 453.570489 -366.334014) (xy 453.625332 -366.323884) (xy 453.681066 -366.321847)
			(xy 453.736503 -366.327947) (xy 453.79046 -366.342053) (xy 453.841789 -366.363865) (xy 453.889395 -366.392919)
			(xy 453.932263 -366.428594) (xy 453.96948 -366.470131) (xy 454.000253 -366.516644) (xy 454.023925 -366.567141)
			(xy 454.039993 -366.620548) (xy 454.048113 -366.675724) (xy 454.048622 -366.70361) (xy 454.048113 -366.731496)
			(xy 454.039993 -366.786672) (xy 454.023925 -366.840079) (xy 454.000253 -366.890576) (xy 453.984807 -366.913922)
			(xy 455.642978 -366.913922) (xy 455.647049 -366.8583) (xy 455.659175 -366.803863) (xy 455.679098 -366.751772)
			(xy 455.706394 -366.703137) (xy 455.74048 -366.658994) (xy 455.780629 -366.620285) (xy 455.825987 -366.587834)
			(xy 455.875587 -366.562333) (xy 455.928371 -366.544326) (xy 455.983214 -366.534196) (xy 456.038948 -366.532159)
			(xy 456.094385 -366.538259) (xy 456.148342 -366.552365) (xy 456.199671 -366.574177) (xy 456.247277 -366.603231)
			(xy 456.290145 -366.638906) (xy 456.327362 -366.680443) (xy 456.358135 -366.726956) (xy 456.381807 -366.777453)
			(xy 456.397875 -366.83086) (xy 456.405995 -366.886036) (xy 456.406504 -366.913922) (xy 458.450694 -366.913922)
			(xy 458.454765 -366.8583) (xy 458.466891 -366.803863) (xy 458.486814 -366.751772) (xy 458.51411 -366.703137)
			(xy 458.548196 -366.658994) (xy 458.588345 -366.620285) (xy 458.633703 -366.587834) (xy 458.683303 -366.562333)
			(xy 458.736087 -366.544326) (xy 458.79093 -366.534196) (xy 458.846664 -366.532159) (xy 458.902101 -366.538259)
			(xy 458.956058 -366.552365) (xy 459.007387 -366.574177) (xy 459.054993 -366.603231) (xy 459.097861 -366.638906)
			(xy 459.135078 -366.680443) (xy 459.165851 -366.726956) (xy 459.189523 -366.777453) (xy 459.205591 -366.83086)
			(xy 459.213711 -366.886036) (xy 459.21422 -366.913922) (xy 459.213711 -366.941808) (xy 459.205591 -366.996984)
			(xy 459.189523 -367.050391) (xy 459.165851 -367.100888) (xy 459.135078 -367.147401) (xy 459.097861 -367.188938)
			(xy 459.054993 -367.224613) (xy 459.007387 -367.253667) (xy 458.956058 -367.275479) (xy 458.902101 -367.289585)
			(xy 458.846664 -367.295685) (xy 458.79093 -367.293648) (xy 458.736087 -367.283518) (xy 458.683303 -367.265511)
			(xy 458.633703 -367.24001) (xy 458.588345 -367.207559) (xy 458.548196 -367.16885) (xy 458.51411 -367.124707)
			(xy 458.486814 -367.076072) (xy 458.466891 -367.023981) (xy 458.454765 -366.969544) (xy 458.450694 -366.913922)
			(xy 456.406504 -366.913922) (xy 456.405995 -366.941808) (xy 456.397875 -366.996984) (xy 456.381807 -367.050391)
			(xy 456.358135 -367.100888) (xy 456.327362 -367.147401) (xy 456.290145 -367.188938) (xy 456.247277 -367.224613)
			(xy 456.199671 -367.253667) (xy 456.148342 -367.275479) (xy 456.094385 -367.289585) (xy 456.038948 -367.295685)
			(xy 455.983214 -367.293648) (xy 455.928371 -367.283518) (xy 455.875587 -367.265511) (xy 455.825987 -367.24001)
			(xy 455.780629 -367.207559) (xy 455.74048 -367.16885) (xy 455.706394 -367.124707) (xy 455.679098 -367.076072)
			(xy 455.659175 -367.023981) (xy 455.647049 -366.969544) (xy 455.642978 -366.913922) (xy 453.984807 -366.913922)
			(xy 453.96948 -366.937089) (xy 453.932263 -366.978626) (xy 453.889395 -367.014301) (xy 453.841789 -367.043355)
			(xy 453.79046 -367.065167) (xy 453.736503 -367.079273) (xy 453.681066 -367.085373) (xy 453.625332 -367.083336)
			(xy 453.570489 -367.073206) (xy 453.517705 -367.055199) (xy 453.468105 -367.029698) (xy 453.422747 -366.997247)
			(xy 453.382598 -366.958538) (xy 453.348512 -366.914395) (xy 453.321216 -366.86576) (xy 453.301293 -366.813669)
			(xy 453.289167 -366.759232) (xy 453.285096 -366.70361) (xy 405.826839 -366.70361) (xy 405.806941 -366.720169)
			(xy 405.759335 -366.749223) (xy 405.708006 -366.771035) (xy 405.654049 -366.785141) (xy 405.598612 -366.791241)
			(xy 405.542878 -366.789204) (xy 405.488035 -366.779074) (xy 405.435251 -366.761067) (xy 405.385651 -366.735566)
			(xy 405.340293 -366.703115) (xy 405.300144 -366.664406) (xy 405.266058 -366.620263) (xy 405.238762 -366.571628)
			(xy 405.218839 -366.519537) (xy 405.206713 -366.4651) (xy 405.202642 -366.409478) (xy 398.494504 -366.409478)
			(xy 397.49603 -367.407952) (xy 405.214326 -367.407952) (xy 405.218397 -367.35233) (xy 405.230523 -367.297893)
			(xy 405.250446 -367.245802) (xy 405.277742 -367.197167) (xy 405.311828 -367.153024) (xy 405.351977 -367.114315)
			(xy 405.397335 -367.081864) (xy 405.446935 -367.056363) (xy 405.499719 -367.038356) (xy 405.554562 -367.028226)
			(xy 405.610296 -367.026189) (xy 405.665733 -367.032289) (xy 405.71969 -367.046395) (xy 405.771019 -367.068207)
			(xy 405.818625 -367.097261) (xy 405.861493 -367.132936) (xy 405.89871 -367.174473) (xy 405.929483 -367.220986)
			(xy 405.953155 -367.271483) (xy 405.969223 -367.32489) (xy 405.977343 -367.380066) (xy 405.977852 -367.407952)
			(xy 405.977343 -367.435838) (xy 405.969223 -367.491014) (xy 405.953155 -367.544421) (xy 405.929483 -367.594918)
			(xy 405.89871 -367.641431) (xy 405.861493 -367.682968) (xy 405.818625 -367.718643) (xy 405.771019 -367.747697)
			(xy 405.71969 -367.769509) (xy 405.665733 -367.783615) (xy 405.610296 -367.789715) (xy 405.554562 -367.787678)
			(xy 405.499719 -367.777548) (xy 405.446935 -367.759541) (xy 405.397335 -367.73404) (xy 405.351977 -367.701589)
			(xy 405.311828 -367.66288) (xy 405.277742 -367.618737) (xy 405.250446 -367.570102) (xy 405.230523 -367.518011)
			(xy 405.218397 -367.463574) (xy 405.214326 -367.407952) (xy 397.49603 -367.407952) (xy 396.88008 -368.023902)
			(xy 396.873225 -368.031297) (xy 396.865479 -368.049896) (xy 396.865094 -368.05997) (xy 396.865094 -368.063272)
			(xy 406.102564 -368.063272) (xy 406.106635 -368.00765) (xy 406.118761 -367.953213) (xy 406.138684 -367.901122)
			(xy 406.16598 -367.852487) (xy 406.200066 -367.808344) (xy 406.240215 -367.769635) (xy 406.285573 -367.737184)
			(xy 406.335173 -367.711683) (xy 406.387957 -367.693676) (xy 406.4428 -367.683546) (xy 406.498534 -367.681509)
			(xy 406.553971 -367.687609) (xy 406.607928 -367.701715) (xy 406.659257 -367.723527) (xy 406.706863 -367.752581)
			(xy 406.749731 -367.788256) (xy 406.786948 -367.829793) (xy 406.817721 -367.876306) (xy 406.841393 -367.926803)
			(xy 406.857461 -367.98021) (xy 406.865581 -368.035386) (xy 406.86609 -368.063272) (xy 406.865581 -368.091158)
			(xy 406.857461 -368.146334) (xy 406.841393 -368.199741) (xy 406.817721 -368.250238) (xy 406.786948 -368.296751)
			(xy 406.749731 -368.338288) (xy 406.706863 -368.373963) (xy 406.659257 -368.403017) (xy 406.607928 -368.424829)
			(xy 406.553971 -368.438935) (xy 406.498534 -368.445035) (xy 406.4428 -368.442998) (xy 406.387957 -368.432868)
			(xy 406.335173 -368.414861) (xy 406.285573 -368.38936) (xy 406.240215 -368.356909) (xy 406.200066 -368.3182)
			(xy 406.16598 -368.274057) (xy 406.138684 -368.225422) (xy 406.118761 -368.173331) (xy 406.106635 -368.118894)
			(xy 406.102564 -368.063272) (xy 396.865094 -368.063272) (xy 396.865094 -369.174268) (xy 406.517854 -369.174268)
			(xy 406.521925 -369.118646) (xy 406.534051 -369.064209) (xy 406.553974 -369.012118) (xy 406.58127 -368.963483)
			(xy 406.615356 -368.91934) (xy 406.655505 -368.880631) (xy 406.700863 -368.84818) (xy 406.750463 -368.822679)
			(xy 406.803247 -368.804672) (xy 406.85809 -368.794542) (xy 406.913824 -368.792505) (xy 406.969261 -368.798605)
			(xy 407.023218 -368.812711) (xy 407.074547 -368.834523) (xy 407.122153 -368.863577) (xy 407.165021 -368.899252)
			(xy 407.202238 -368.940789) (xy 407.233011 -368.987302) (xy 407.234331 -368.990118) (xy 421.203636 -368.990118)
			(xy 421.207627 -368.927951) (xy 421.219536 -368.866804) (xy 421.239165 -368.807683) (xy 421.266194 -368.751557)
			(xy 421.300178 -368.699348) (xy 421.34056 -368.651913) (xy 421.386676 -368.610032) (xy 421.437768 -368.574392)
			(xy 421.492999 -368.545578) (xy 421.551461 -368.524064) (xy 421.612195 -368.510202) (xy 421.674202 -368.50422)
			(xy 421.736465 -368.506216) (xy 421.797962 -368.516159) (xy 421.857683 -368.533883) (xy 421.914646 -368.5591)
			(xy 421.967917 -368.591393) (xy 422.016622 -368.630233) (xy 422.059959 -368.674983) (xy 422.097219 -368.724907)
			(xy 422.127788 -368.779186) (xy 422.151166 -368.836929) (xy 422.166967 -368.897187) (xy 422.174933 -368.95897)
			(xy 422.175432 -368.990118) (xy 425.603678 -368.990118) (xy 425.607669 -368.927951) (xy 425.619578 -368.866804)
			(xy 425.639207 -368.807683) (xy 425.666236 -368.751557) (xy 425.70022 -368.699348) (xy 425.740602 -368.651913)
			(xy 425.786718 -368.610032) (xy 425.83781 -368.574392) (xy 425.893041 -368.545578) (xy 425.951503 -368.524064)
			(xy 426.012237 -368.510202) (xy 426.074244 -368.50422) (xy 426.136507 -368.506216) (xy 426.198004 -368.516159)
			(xy 426.257725 -368.533883) (xy 426.314688 -368.5591) (xy 426.367959 -368.591393) (xy 426.416664 -368.630233)
			(xy 426.460001 -368.674983) (xy 426.497261 -368.724907) (xy 426.52783 -368.779186) (xy 426.551208 -368.836929)
			(xy 426.567009 -368.897187) (xy 426.574975 -368.95897) (xy 426.575474 -368.990118) (xy 430.00372 -368.990118)
			(xy 430.007711 -368.927951) (xy 430.01962 -368.866804) (xy 430.039249 -368.807683) (xy 430.066278 -368.751557)
			(xy 430.100262 -368.699348) (xy 430.140644 -368.651913) (xy 430.18676 -368.610032) (xy 430.237852 -368.574392)
			(xy 430.293083 -368.545578) (xy 430.351545 -368.524064) (xy 430.412279 -368.510202) (xy 430.474286 -368.50422)
			(xy 430.536549 -368.506216) (xy 430.598046 -368.516159) (xy 430.657767 -368.533883) (xy 430.71473 -368.5591)
			(xy 430.768001 -368.591393) (xy 430.816706 -368.630233) (xy 430.860043 -368.674983) (xy 430.897303 -368.724907)
			(xy 430.927872 -368.779186) (xy 430.95125 -368.836929) (xy 430.967051 -368.897187) (xy 430.975017 -368.95897)
			(xy 430.975516 -368.990118) (xy 434.403762 -368.990118) (xy 434.407753 -368.927951) (xy 434.419662 -368.866804)
			(xy 434.439291 -368.807683) (xy 434.46632 -368.751557) (xy 434.500304 -368.699348) (xy 434.540686 -368.651913)
			(xy 434.586802 -368.610032) (xy 434.637894 -368.574392) (xy 434.693125 -368.545578) (xy 434.751587 -368.524064)
			(xy 434.812321 -368.510202) (xy 434.874328 -368.50422) (xy 434.936591 -368.506216) (xy 434.998088 -368.516159)
			(xy 435.057809 -368.533883) (xy 435.114772 -368.5591) (xy 435.168043 -368.591393) (xy 435.216748 -368.630233)
			(xy 435.260085 -368.674983) (xy 435.297345 -368.724907) (xy 435.327914 -368.779186) (xy 435.351292 -368.836929)
			(xy 435.367093 -368.897187) (xy 435.375059 -368.95897) (xy 435.375558 -368.990118) (xy 438.803804 -368.990118)
			(xy 438.807795 -368.927951) (xy 438.819704 -368.866804) (xy 438.839333 -368.807683) (xy 438.866362 -368.751557)
			(xy 438.900346 -368.699348) (xy 438.940728 -368.651913) (xy 438.986844 -368.610032) (xy 439.037936 -368.574392)
			(xy 439.093167 -368.545578) (xy 439.151629 -368.524064) (xy 439.212363 -368.510202) (xy 439.27437 -368.50422)
			(xy 439.336633 -368.506216) (xy 439.39813 -368.516159) (xy 439.457851 -368.533883) (xy 439.514814 -368.5591)
			(xy 439.568085 -368.591393) (xy 439.61679 -368.630233) (xy 439.660127 -368.674983) (xy 439.697387 -368.724907)
			(xy 439.727956 -368.779186) (xy 439.751334 -368.836929) (xy 439.767135 -368.897187) (xy 439.775101 -368.95897)
			(xy 439.7756 -368.990118) (xy 439.775101 -369.021266) (xy 439.767135 -369.083049) (xy 439.751334 -369.143307)
			(xy 439.727956 -369.20105) (xy 439.697387 -369.255329) (xy 439.660127 -369.305253) (xy 439.61679 -369.350003)
			(xy 439.568085 -369.388843) (xy 439.514814 -369.421136) (xy 439.457851 -369.446353) (xy 439.39813 -369.464077)
			(xy 439.336633 -369.47402) (xy 439.27437 -369.476016) (xy 439.212363 -369.470034) (xy 439.151629 -369.456172)
			(xy 439.093167 -369.434658) (xy 439.037936 -369.405844) (xy 438.986844 -369.370204) (xy 438.940728 -369.328323)
			(xy 438.900346 -369.280888) (xy 438.866362 -369.228679) (xy 438.839333 -369.172553) (xy 438.819704 -369.113432)
			(xy 438.807795 -369.052285) (xy 438.803804 -368.990118) (xy 435.375558 -368.990118) (xy 435.375059 -369.021266)
			(xy 435.367093 -369.083049) (xy 435.351292 -369.143307) (xy 435.327914 -369.20105) (xy 435.297345 -369.255329)
			(xy 435.260085 -369.305253) (xy 435.216748 -369.350003) (xy 435.168043 -369.388843) (xy 435.114772 -369.421136)
			(xy 435.057809 -369.446353) (xy 434.998088 -369.464077) (xy 434.936591 -369.47402) (xy 434.874328 -369.476016)
			(xy 434.812321 -369.470034) (xy 434.751587 -369.456172) (xy 434.693125 -369.434658) (xy 434.637894 -369.405844)
			(xy 434.586802 -369.370204) (xy 434.540686 -369.328323) (xy 434.500304 -369.280888) (xy 434.46632 -369.228679)
			(xy 434.439291 -369.172553) (xy 434.419662 -369.113432) (xy 434.407753 -369.052285) (xy 434.403762 -368.990118)
			(xy 430.975516 -368.990118) (xy 430.975017 -369.021266) (xy 430.967051 -369.083049) (xy 430.95125 -369.143307)
			(xy 430.927872 -369.20105) (xy 430.897303 -369.255329) (xy 430.860043 -369.305253) (xy 430.816706 -369.350003)
			(xy 430.768001 -369.388843) (xy 430.71473 -369.421136) (xy 430.657767 -369.446353) (xy 430.598046 -369.464077)
			(xy 430.536549 -369.47402) (xy 430.474286 -369.476016) (xy 430.412279 -369.470034) (xy 430.351545 -369.456172)
			(xy 430.293083 -369.434658) (xy 430.237852 -369.405844) (xy 430.18676 -369.370204) (xy 430.140644 -369.328323)
			(xy 430.100262 -369.280888) (xy 430.066278 -369.228679) (xy 430.039249 -369.172553) (xy 430.01962 -369.113432)
			(xy 430.007711 -369.052285) (xy 430.00372 -368.990118) (xy 426.575474 -368.990118) (xy 426.574975 -369.021266)
			(xy 426.567009 -369.083049) (xy 426.551208 -369.143307) (xy 426.52783 -369.20105) (xy 426.497261 -369.255329)
			(xy 426.460001 -369.305253) (xy 426.416664 -369.350003) (xy 426.367959 -369.388843) (xy 426.314688 -369.421136)
			(xy 426.257725 -369.446353) (xy 426.198004 -369.464077) (xy 426.136507 -369.47402) (xy 426.074244 -369.476016)
			(xy 426.012237 -369.470034) (xy 425.951503 -369.456172) (xy 425.893041 -369.434658) (xy 425.83781 -369.405844)
			(xy 425.786718 -369.370204) (xy 425.740602 -369.328323) (xy 425.70022 -369.280888) (xy 425.666236 -369.228679)
			(xy 425.639207 -369.172553) (xy 425.619578 -369.113432) (xy 425.607669 -369.052285) (xy 425.603678 -368.990118)
			(xy 422.175432 -368.990118) (xy 422.174933 -369.021266) (xy 422.166967 -369.083049) (xy 422.151166 -369.143307)
			(xy 422.127788 -369.20105) (xy 422.097219 -369.255329) (xy 422.059959 -369.305253) (xy 422.016622 -369.350003)
			(xy 421.967917 -369.388843) (xy 421.914646 -369.421136) (xy 421.857683 -369.446353) (xy 421.797962 -369.464077)
			(xy 421.736465 -369.47402) (xy 421.674202 -369.476016) (xy 421.612195 -369.470034) (xy 421.551461 -369.456172)
			(xy 421.492999 -369.434658) (xy 421.437768 -369.405844) (xy 421.386676 -369.370204) (xy 421.34056 -369.328323)
			(xy 421.300178 -369.280888) (xy 421.266194 -369.228679) (xy 421.239165 -369.172553) (xy 421.219536 -369.113432)
			(xy 421.207627 -369.052285) (xy 421.203636 -368.990118) (xy 407.234331 -368.990118) (xy 407.256683 -369.037799)
			(xy 407.272751 -369.091206) (xy 407.280871 -369.146382) (xy 407.28138 -369.174268) (xy 407.280871 -369.202154)
			(xy 407.272751 -369.25733) (xy 407.256683 -369.310737) (xy 407.233011 -369.361234) (xy 407.202238 -369.407747)
			(xy 407.165021 -369.449284) (xy 407.122153 -369.484959) (xy 407.074547 -369.514013) (xy 407.023218 -369.535825)
			(xy 406.969261 -369.549931) (xy 406.913824 -369.556031) (xy 406.85809 -369.553994) (xy 406.803247 -369.543864)
			(xy 406.750463 -369.525857) (xy 406.700863 -369.500356) (xy 406.655505 -369.467905) (xy 406.615356 -369.429196)
			(xy 406.58127 -369.385053) (xy 406.553974 -369.336418) (xy 406.534051 -369.284327) (xy 406.521925 -369.22989)
			(xy 406.517854 -369.174268) (xy 396.865094 -369.174268) (xy 396.865094 -371.019578) (xy 404.149814 -371.019578)
			(xy 404.150207 -370.99322) (xy 404.157455 -370.941005) (xy 404.171825 -370.890286) (xy 404.193043 -370.842029)
			(xy 404.220703 -370.797153) (xy 404.25428 -370.756514) (xy 404.293133 -370.720885) (xy 404.336523 -370.690947)
			(xy 404.359872 -370.67871) (xy 404.372456 -370.671818) (xy 404.393539 -370.652384) (xy 404.408375 -370.627847)
			(xy 404.41579 -370.600149) (xy 404.415198 -370.571482) (xy 404.406645 -370.544113) (xy 404.390808 -370.52021)
			(xy 404.380192 -370.510562) (xy 404.359429 -370.492363) (xy 404.322896 -370.450966) (xy 404.292711 -370.404736)
			(xy 404.269504 -370.354639) (xy 404.253758 -370.30172) (xy 404.245804 -370.247084) (xy 404.245318 -370.219478)
			(xy 404.245804 -370.192227) (xy 404.25356 -370.138279) (xy 404.268915 -370.085984) (xy 404.291557 -370.036407)
			(xy 404.321023 -369.990557) (xy 404.356714 -369.949366) (xy 404.397905 -369.913675) (xy 404.443755 -369.884209)
			(xy 404.493332 -369.861567) (xy 404.545627 -369.846212) (xy 404.599575 -369.838456) (xy 404.654077 -369.838456)
			(xy 404.708025 -369.846212) (xy 404.76032 -369.861567) (xy 404.809897 -369.884209) (xy 404.855747 -369.913675)
			(xy 404.896938 -369.949366) (xy 404.932629 -369.990557) (xy 404.962095 -370.036407) (xy 404.984737 -370.085984)
			(xy 405.000092 -370.138279) (xy 405.007848 -370.192227) (xy 405.008334 -370.219478) (xy 405.007879 -370.245834)
			(xy 405.000637 -370.298045) (xy 404.986275 -370.348761) (xy 404.965066 -370.397017) (xy 404.937414 -370.441893)
			(xy 404.903846 -370.482533) (xy 404.865002 -370.518164) (xy 404.858417 -370.522709) (xy 419.004833 -370.522709)
			(xy 419.004834 -370.457271) (xy 419.01362 -370.392425) (xy 419.031031 -370.329346) (xy 419.056752 -370.269175)
			(xy 419.073076 -370.240814) (xy 419.076384 -370.234786) (xy 419.079994 -370.221525) (xy 419.080188 -370.214652)
			(xy 419.080188 -369.928902) (xy 419.080567 -369.918724) (xy 419.08836 -369.89992) (xy 419.10276 -369.885533)
			(xy 419.121572 -369.877757) (xy 419.13175 -369.87734) (xy 419.84803 -369.87734) (xy 419.85819 -369.877809)
			(xy 419.87696 -369.885593) (xy 419.891325 -369.899967) (xy 419.899098 -369.918742) (xy 419.899592 -369.928902)
			(xy 419.899592 -370.214652) (xy 419.899804 -370.221524) (xy 419.903399 -370.234786) (xy 419.906704 -370.240814)
			(xy 419.923015 -370.269181) (xy 419.948731 -370.329352) (xy 419.966139 -370.392429) (xy 419.974923 -370.457272)
			(xy 419.974924 -370.522707) (xy 419.966143 -370.587551) (xy 419.948738 -370.650629) (xy 419.923024 -370.7108)
			(xy 419.906704 -370.739162) (xy 419.903403 -370.745193) (xy 419.899789 -370.758452) (xy 419.899592 -370.765324)
			(xy 419.899592 -371.514878) (xy 419.899793 -371.521751) (xy 419.903395 -371.535013) (xy 419.906704 -371.54104)
			(xy 419.923037 -371.569395) (xy 419.948751 -371.629568) (xy 419.966156 -371.692648) (xy 419.974937 -371.757493)
			(xy 419.974936 -371.822931) (xy 419.966151 -371.887775) (xy 419.948743 -371.950854) (xy 419.923026 -372.011026)
			(xy 419.906704 -372.039388) (xy 419.903394 -372.045415) (xy 419.899785 -372.058677) (xy 419.899592 -372.06555)
			(xy 419.899592 -372.351554) (xy 419.899099 -372.361719) (xy 419.891335 -372.380507) (xy 419.876971 -372.394892)
			(xy 419.858194 -372.402684) (xy 419.84803 -372.403116) (xy 419.13175 -372.403116) (xy 419.121576 -372.402694)
			(xy 419.102773 -372.394917) (xy 419.088385 -372.38053) (xy 419.080607 -372.361728) (xy 419.080188 -372.351554)
			(xy 419.080188 -372.06555) (xy 419.079978 -372.058678) (xy 419.076382 -372.045415) (xy 419.073076 -372.039388)
			(xy 419.056764 -372.011021) (xy 419.031044 -371.950851) (xy 419.013633 -371.887774) (xy 419.004847 -371.82293)
			(xy 419.004846 -371.757494) (xy 419.013628 -371.69265) (xy 419.031036 -371.629571) (xy 419.056754 -371.569401)
			(xy 419.073076 -371.54104) (xy 419.076375 -371.535008) (xy 419.079991 -371.52175) (xy 419.080188 -371.514878)
			(xy 419.080188 -370.765324) (xy 419.079988 -370.758451) (xy 419.076385 -370.745189) (xy 419.073076 -370.739162)
			(xy 419.056742 -370.710807) (xy 419.031024 -370.650635) (xy 419.013615 -370.587555) (xy 419.004833 -370.522709)
			(xy 404.858417 -370.522709) (xy 404.821621 -370.548106) (xy 404.798276 -370.560346) (xy 404.785647 -370.567166)
			(xy 404.764551 -370.58661) (xy 404.749709 -370.611162) (xy 404.742295 -370.638877) (xy 404.742897 -370.66756)
			(xy 404.751468 -370.69494) (xy 404.767328 -370.718847) (xy 404.777956 -370.728494) (xy 404.798687 -370.746728)
			(xy 404.835224 -370.788116) (xy 404.865415 -370.834338) (xy 404.888629 -370.884429) (xy 404.90438 -370.937342)
			(xy 404.91234 -370.991974) (xy 404.912627 -371.008148) (xy 405.37206 -371.008148) (xy 405.376131 -370.952526)
			(xy 405.388257 -370.898089) (xy 405.40818 -370.845998) (xy 405.435476 -370.797363) (xy 405.469562 -370.75322)
			(xy 405.509711 -370.714511) (xy 405.555069 -370.68206) (xy 405.604669 -370.656559) (xy 405.657453 -370.638552)
			(xy 405.712296 -370.628422) (xy 405.76803 -370.626385) (xy 405.823467 -370.632485) (xy 405.877424 -370.646591)
			(xy 405.928753 -370.668403) (xy 405.976359 -370.697457) (xy 406.019227 -370.733132) (xy 406.056444 -370.774669)
			(xy 406.087217 -370.821182) (xy 406.110889 -370.871679) (xy 406.126957 -370.925086) (xy 406.135077 -370.980262)
			(xy 406.135586 -371.008148) (xy 406.135077 -371.036034) (xy 406.126957 -371.09121) (xy 406.110889 -371.144617)
			(xy 406.087217 -371.195114) (xy 406.056444 -371.241627) (xy 406.019227 -371.283164) (xy 405.976359 -371.318839)
			(xy 405.928753 -371.347893) (xy 405.877424 -371.369705) (xy 405.823467 -371.383811) (xy 405.76803 -371.389911)
			(xy 405.712296 -371.387874) (xy 405.657453 -371.377744) (xy 405.604669 -371.359737) (xy 405.555069 -371.334236)
			(xy 405.509711 -371.301785) (xy 405.469562 -371.263076) (xy 405.435476 -371.218933) (xy 405.40818 -371.170298)
			(xy 405.388257 -371.118207) (xy 405.376131 -371.06377) (xy 405.37206 -371.008148) (xy 404.912627 -371.008148)
			(xy 404.91283 -371.019578) (xy 404.912344 -371.046829) (xy 404.904588 -371.100777) (xy 404.889233 -371.153072)
			(xy 404.866591 -371.202649) (xy 404.837125 -371.248499) (xy 404.801434 -371.28969) (xy 404.760243 -371.325381)
			(xy 404.714393 -371.354847) (xy 404.664816 -371.377489) (xy 404.612521 -371.392844) (xy 404.558573 -371.4006)
			(xy 404.504071 -371.4006) (xy 404.450123 -371.392844) (xy 404.397828 -371.377489) (xy 404.348251 -371.354847)
			(xy 404.302401 -371.325381) (xy 404.26121 -371.28969) (xy 404.225519 -371.248499) (xy 404.196053 -371.202649)
			(xy 404.173411 -371.153072) (xy 404.158056 -371.100777) (xy 404.1503 -371.046829) (xy 404.149814 -371.019578)
			(xy 396.865094 -371.019578) (xy 396.865094 -372.877842) (xy 407.397202 -372.877842) (xy 407.401273 -372.82222)
			(xy 407.413399 -372.767783) (xy 407.433322 -372.715692) (xy 407.460618 -372.667057) (xy 407.494704 -372.622914)
			(xy 407.534853 -372.584205) (xy 407.580211 -372.551754) (xy 407.629811 -372.526253) (xy 407.682595 -372.508246)
			(xy 407.737438 -372.498116) (xy 407.793172 -372.496079) (xy 407.848609 -372.502179) (xy 407.902566 -372.516285)
			(xy 407.953895 -372.538097) (xy 408.001501 -372.567151) (xy 408.044369 -372.602826) (xy 408.081586 -372.644363)
			(xy 408.112359 -372.690876) (xy 408.136031 -372.741373) (xy 408.152099 -372.79478) (xy 408.160219 -372.849956)
			(xy 408.160728 -372.877842) (xy 408.160505 -372.890034) (xy 421.204136 -372.890034) (xy 421.204703 -372.857305)
			(xy 421.21356 -372.792447) (xy 421.23105 -372.729367) (xy 421.256856 -372.669208) (xy 421.273224 -372.64086)
			(xy 421.276555 -372.634843) (xy 421.28015 -372.621573) (xy 421.280336 -372.614698) (xy 421.280336 -371.865398)
			(xy 421.28014 -371.858525) (xy 421.276534 -371.845262) (xy 421.273224 -371.839236) (xy 421.256875 -371.810878)
			(xy 421.231069 -371.750722) (xy 421.213574 -371.687645) (xy 421.204709 -371.62279) (xy 421.204136 -371.590062)
			(xy 421.204716 -371.557333) (xy 421.213569 -371.492476) (xy 421.231055 -371.429396) (xy 421.256858 -371.369237)
			(xy 421.273224 -371.340888) (xy 421.276545 -371.334866) (xy 421.280146 -371.3216) (xy 421.280336 -371.314726)
			(xy 421.280336 -371.028722) (xy 421.280844 -371.018597) (xy 421.288564 -370.999877) (xy 421.302844 -370.98552)
			(xy 421.321522 -370.9777) (xy 421.331644 -370.97716) (xy 422.047924 -370.97716) (xy 422.058075 -370.977601)
			(xy 422.07682 -370.985397) (xy 422.091141 -370.999787) (xy 422.098847 -371.018569) (xy 422.099232 -371.028722)
			(xy 422.099232 -371.314726) (xy 422.09941 -371.3216) (xy 422.103028 -371.334863) (xy 422.106344 -371.340888)
			(xy 422.122699 -371.369243) (xy 422.148505 -371.4294) (xy 422.165998 -371.492478) (xy 422.174861 -371.557333)
			(xy 422.175432 -371.590062) (xy 422.174867 -371.622792) (xy 422.166011 -371.68765) (xy 422.14852 -371.75073)
			(xy 422.131582 -371.790214) (xy 423.404284 -371.790214) (xy 423.404836 -371.757484) (xy 423.413696 -371.692625)
			(xy 423.43119 -371.629545) (xy 423.457001 -371.569388) (xy 423.473372 -371.54104) (xy 423.476671 -371.535007)
			(xy 423.480287 -371.52175) (xy 423.480484 -371.514878) (xy 423.480484 -370.765324) (xy 423.480285 -370.758451)
			(xy 423.476682 -370.745188) (xy 423.473372 -370.739162) (xy 423.456989 -370.710823) (xy 423.431192 -370.650659)
			(xy 423.413707 -370.587577) (xy 423.404852 -370.522718) (xy 423.404284 -370.489988) (xy 423.404869 -370.457259)
			(xy 423.413719 -370.392402) (xy 423.431204 -370.329322) (xy 423.457006 -370.269163) (xy 423.473372 -370.240814)
			(xy 423.47668 -370.234786) (xy 423.48029 -370.221525) (xy 423.480484 -370.214652) (xy 423.480484 -369.928902)
			(xy 423.48093 -369.91877) (xy 423.488665 -369.900041) (xy 423.502964 -369.885683) (xy 423.521662 -369.877871)
			(xy 423.531792 -369.87734) (xy 424.248072 -369.87734) (xy 424.258229 -369.877745) (xy 424.276989 -369.885539)
			(xy 424.291315 -369.899942) (xy 424.299008 -369.918743) (xy 424.29938 -369.928902) (xy 424.29938 -370.214652)
			(xy 424.299593 -370.221524) (xy 424.303187 -370.234786) (xy 424.306492 -370.240814) (xy 424.322862 -370.269161)
			(xy 424.348663 -370.329321) (xy 424.366152 -370.392401) (xy 424.37501 -370.457259) (xy 424.37558 -370.489988)
			(xy 424.375034 -370.522709) (xy 427.804919 -370.522709) (xy 427.80492 -370.457271) (xy 427.813706 -370.392425)
			(xy 427.831116 -370.329346) (xy 427.856836 -370.269175) (xy 427.87316 -370.240814) (xy 427.876466 -370.234785)
			(xy 427.880078 -370.221525) (xy 427.880272 -370.214652) (xy 427.880272 -369.928902) (xy 427.880666 -369.918726)
			(xy 427.888457 -369.899925) (xy 427.902852 -369.885539) (xy 427.921658 -369.87776) (xy 427.931834 -369.87734)
			(xy 428.648114 -369.87734) (xy 428.658273 -369.877822) (xy 428.677043 -369.885602) (xy 428.691407 -369.899971)
			(xy 428.699181 -369.918743) (xy 428.699676 -369.928902) (xy 428.699676 -370.214652) (xy 428.699889 -370.221524)
			(xy 428.703483 -370.234786) (xy 428.706788 -370.240814) (xy 428.723099 -370.269181) (xy 428.748816 -370.329351)
			(xy 428.766225 -370.392429) (xy 428.775009 -370.457272) (xy 428.77501 -370.522707) (xy 428.77501 -370.522709)
			(xy 432.204708 -370.522709) (xy 432.20471 -370.457271) (xy 432.213495 -370.392426) (xy 432.230905 -370.329346)
			(xy 432.256625 -370.269175) (xy 432.272948 -370.240814) (xy 432.276254 -370.234785) (xy 432.279866 -370.221525)
			(xy 432.28006 -370.214652) (xy 432.28006 -369.928902) (xy 432.280466 -369.918728) (xy 432.288254 -369.899929)
			(xy 432.302646 -369.885543) (xy 432.321448 -369.877762) (xy 432.331622 -369.87734) (xy 433.047902 -369.87734)
			(xy 433.05806 -369.877832) (xy 433.07683 -369.885607) (xy 433.091195 -369.899974) (xy 433.098969 -369.918744)
			(xy 433.099464 -369.928902) (xy 433.099464 -370.214652) (xy 433.099679 -370.221524) (xy 433.103272 -370.234786)
			(xy 433.106576 -370.240814) (xy 433.122888 -370.269181) (xy 433.148605 -370.329351) (xy 433.166014 -370.392428)
			(xy 433.174799 -370.457272) (xy 433.174799 -370.489988) (xy 436.603656 -370.489988) (xy 436.607647 -370.427821)
			(xy 436.619556 -370.366674) (xy 436.639185 -370.307553) (xy 436.666214 -370.251427) (xy 436.700198 -370.199218)
			(xy 436.74058 -370.151783) (xy 436.786696 -370.109902) (xy 436.837788 -370.074262) (xy 436.893019 -370.045448)
			(xy 436.951481 -370.023934) (xy 437.012215 -370.010072) (xy 437.074222 -370.00409) (xy 437.136485 -370.006086)
			(xy 437.197982 -370.016029) (xy 437.257703 -370.033753) (xy 437.314666 -370.05897) (xy 437.367937 -370.091263)
			(xy 437.416642 -370.130103) (xy 437.459979 -370.174853) (xy 437.497239 -370.224777) (xy 437.527808 -370.279056)
			(xy 437.551186 -370.336799) (xy 437.566987 -370.397057) (xy 437.574953 -370.45884) (xy 437.575452 -370.489988)
			(xy 437.574953 -370.521136) (xy 437.566987 -370.582919) (xy 437.551186 -370.643177) (xy 437.527808 -370.70092)
			(xy 437.497239 -370.755199) (xy 437.459979 -370.805123) (xy 437.416642 -370.849873) (xy 437.367937 -370.888713)
			(xy 437.314666 -370.921006) (xy 437.257703 -370.946223) (xy 437.197982 -370.963947) (xy 437.136485 -370.97389)
			(xy 437.074222 -370.975886) (xy 437.012215 -370.969904) (xy 436.951481 -370.956042) (xy 436.893019 -370.934528)
			(xy 436.837788 -370.905714) (xy 436.786696 -370.870074) (xy 436.74058 -370.828193) (xy 436.700198 -370.780758)
			(xy 436.666214 -370.728549) (xy 436.639185 -370.672423) (xy 436.619556 -370.613302) (xy 436.607647 -370.552155)
			(xy 436.603656 -370.489988) (xy 433.174799 -370.489988) (xy 433.1748 -370.522708) (xy 433.166018 -370.587551)
			(xy 433.148612 -370.65063) (xy 433.122897 -370.710801) (xy 433.106576 -370.739162) (xy 433.103273 -370.745192)
			(xy 433.09966 -370.758452) (xy 433.099464 -370.765324) (xy 433.099464 -371.514878) (xy 433.099669 -371.52175)
			(xy 433.103269 -371.535013) (xy 433.106576 -371.54104) (xy 433.12291 -371.569395) (xy 433.145727 -371.622787)
			(xy 434.404849 -371.622787) (xy 434.404853 -371.557348) (xy 434.413641 -371.492502) (xy 434.431052 -371.429422)
			(xy 434.456773 -371.36925) (xy 434.473096 -371.340888) (xy 434.476415 -371.334865) (xy 434.480018 -371.3216)
			(xy 434.480208 -371.314726) (xy 434.480208 -371.028722) (xy 434.48075 -371.018569) (xy 434.488512 -370.999806)
			(xy 434.502863 -370.985441) (xy 434.521618 -370.977661) (xy 434.53177 -370.97716) (xy 435.24805 -370.97716)
			(xy 435.258221 -370.977605) (xy 435.277019 -370.985378) (xy 435.291406 -370.999758) (xy 435.299189 -371.018551)
			(xy 435.299612 -371.028722) (xy 435.299612 -371.314726) (xy 435.299792 -371.3216) (xy 435.303408 -371.334863)
			(xy 435.306724 -371.340888) (xy 435.323015 -371.369267) (xy 435.348738 -371.429433) (xy 435.366151 -371.492508)
			(xy 435.374939 -371.55735) (xy 435.374943 -371.622785) (xy 435.366164 -371.687628) (xy 435.348759 -371.750705)
			(xy 435.331875 -371.790214) (xy 436.603656 -371.790214) (xy 436.607647 -371.728047) (xy 436.619556 -371.6669)
			(xy 436.639185 -371.607779) (xy 436.666214 -371.551653) (xy 436.700198 -371.499444) (xy 436.74058 -371.452009)
			(xy 436.786696 -371.410128) (xy 436.837788 -371.374488) (xy 436.893019 -371.345674) (xy 436.951481 -371.32416)
			(xy 437.012215 -371.310298) (xy 437.074222 -371.304316) (xy 437.136485 -371.306312) (xy 437.197982 -371.316255)
			(xy 437.257703 -371.333979) (xy 437.314666 -371.359196) (xy 437.367937 -371.391489) (xy 437.416642 -371.430329)
			(xy 437.459979 -371.475079) (xy 437.497239 -371.525003) (xy 437.527808 -371.579282) (xy 437.532172 -371.590062)
			(xy 438.803804 -371.590062) (xy 438.807795 -371.527895) (xy 438.819704 -371.466748) (xy 438.839333 -371.407627)
			(xy 438.866362 -371.351501) (xy 438.900346 -371.299292) (xy 438.940728 -371.251857) (xy 438.986844 -371.209976)
			(xy 439.037936 -371.174336) (xy 439.093167 -371.145522) (xy 439.151629 -371.124008) (xy 439.212363 -371.110146)
			(xy 439.27437 -371.104164) (xy 439.336633 -371.10616) (xy 439.39813 -371.116103) (xy 439.457851 -371.133827)
			(xy 439.514814 -371.159044) (xy 439.568085 -371.191337) (xy 439.61679 -371.230177) (xy 439.660127 -371.274927)
			(xy 439.697387 -371.324851) (xy 439.727956 -371.37913) (xy 439.751334 -371.436873) (xy 439.767135 -371.497131)
			(xy 439.775101 -371.558914) (xy 439.7756 -371.590062) (xy 439.775101 -371.62121) (xy 439.767135 -371.682993)
			(xy 439.751334 -371.743251) (xy 439.727956 -371.800994) (xy 439.697387 -371.855273) (xy 439.694001 -371.85981)
			(xy 457.532994 -371.85981) (xy 457.53348 -371.832559) (xy 457.541236 -371.778611) (xy 457.556591 -371.726316)
			(xy 457.579233 -371.676739) (xy 457.608699 -371.630889) (xy 457.64439 -371.589698) (xy 457.685581 -371.554007)
			(xy 457.731431 -371.524541) (xy 457.781008 -371.501899) (xy 457.833303 -371.486544) (xy 457.887251 -371.478788)
			(xy 457.941753 -371.478788) (xy 457.995701 -371.486544) (xy 458.047996 -371.501899) (xy 458.097573 -371.524541)
			(xy 458.143423 -371.554007) (xy 458.184614 -371.589698) (xy 458.220305 -371.630889) (xy 458.249771 -371.676739)
			(xy 458.272413 -371.726316) (xy 458.287768 -371.778611) (xy 458.295524 -371.832559) (xy 458.29601 -371.85981)
			(xy 458.29539 -371.890148) (xy 458.285787 -371.950059) (xy 458.266823 -372.007696) (xy 458.238976 -372.061604)
			(xy 458.202949 -372.110427) (xy 458.18171 -372.132098) (xy 458.17212 -372.141991) (xy 458.1583 -372.165823)
			(xy 458.151349 -372.192479) (xy 458.151771 -372.220024) (xy 458.159536 -372.246455) (xy 458.174079 -372.269852)
			(xy 458.194344 -372.288513) (xy 458.218858 -372.301083) (xy 458.232256 -372.30431) (xy 458.260571 -372.310664)
			(xy 458.314998 -372.330791) (xy 458.365747 -372.358932) (xy 458.411647 -372.394436) (xy 458.451638 -372.436485)
			(xy 458.484797 -372.484106) (xy 458.510358 -372.536202) (xy 458.527732 -372.591569) (xy 458.536517 -372.648929)
			(xy 458.537056 -372.677944) (xy 458.53657 -372.705195) (xy 458.528814 -372.759143) (xy 458.513459 -372.811438)
			(xy 458.490817 -372.861015) (xy 458.461351 -372.906865) (xy 458.42566 -372.948056) (xy 458.384469 -372.983747)
			(xy 458.338619 -373.013213) (xy 458.289042 -373.035855) (xy 458.236747 -373.05121) (xy 458.182799 -373.058966)
			(xy 458.128297 -373.058966) (xy 458.074349 -373.05121) (xy 458.022054 -373.035855) (xy 457.972477 -373.013213)
			(xy 457.926627 -372.983747) (xy 457.885436 -372.948056) (xy 457.849745 -372.906865) (xy 457.820279 -372.861015)
			(xy 457.797637 -372.811438) (xy 457.782282 -372.759143) (xy 457.774526 -372.705195) (xy 457.77404 -372.677944)
			(xy 457.774616 -372.647604) (xy 457.784228 -372.58769) (xy 457.803202 -372.530053) (xy 457.831058 -372.476145)
			(xy 457.867095 -372.427325) (xy 457.88834 -372.405656) (xy 457.897843 -372.395687) (xy 457.911655 -372.371873)
			(xy 457.918606 -372.345236) (xy 457.918191 -372.317709) (xy 457.910439 -372.291294) (xy 457.895914 -372.267908)
			(xy 457.875672 -372.24925) (xy 457.851181 -372.236677) (xy 457.837794 -372.233444) (xy 457.809476 -372.227098)
			(xy 457.755046 -372.206974) (xy 457.704294 -372.178835) (xy 457.658391 -372.143331) (xy 457.618399 -372.101281)
			(xy 457.58524 -372.053657) (xy 457.55968 -372.001559) (xy 457.54231 -371.946188) (xy 457.53353 -371.888826)
			(xy 457.532994 -371.85981) (xy 439.694001 -371.85981) (xy 439.660127 -371.905197) (xy 439.61679 -371.949947)
			(xy 439.568085 -371.988787) (xy 439.514814 -372.02108) (xy 439.457851 -372.046297) (xy 439.39813 -372.064021)
			(xy 439.336633 -372.073964) (xy 439.27437 -372.07596) (xy 439.212363 -372.069978) (xy 439.151629 -372.056116)
			(xy 439.093167 -372.034602) (xy 439.037936 -372.005788) (xy 438.986844 -371.970148) (xy 438.940728 -371.928267)
			(xy 438.900346 -371.880832) (xy 438.866362 -371.828623) (xy 438.839333 -371.772497) (xy 438.819704 -371.713376)
			(xy 438.807795 -371.652229) (xy 438.803804 -371.590062) (xy 437.532172 -371.590062) (xy 437.551186 -371.637025)
			(xy 437.566987 -371.697283) (xy 437.574953 -371.759066) (xy 437.575452 -371.790214) (xy 437.574953 -371.821362)
			(xy 437.566987 -371.883145) (xy 437.551186 -371.943403) (xy 437.527808 -372.001146) (xy 437.497239 -372.055425)
			(xy 437.459979 -372.105349) (xy 437.416642 -372.150099) (xy 437.367937 -372.188939) (xy 437.314666 -372.221232)
			(xy 437.257703 -372.246449) (xy 437.197982 -372.264173) (xy 437.136485 -372.274116) (xy 437.074222 -372.276112)
			(xy 437.012215 -372.27013) (xy 436.951481 -372.256268) (xy 436.893019 -372.234754) (xy 436.837788 -372.20594)
			(xy 436.786696 -372.1703) (xy 436.74058 -372.128419) (xy 436.700198 -372.080984) (xy 436.666214 -372.028775)
			(xy 436.639185 -371.972649) (xy 436.619556 -371.913528) (xy 436.607647 -371.852381) (xy 436.603656 -371.790214)
			(xy 435.331875 -371.790214) (xy 435.323045 -371.810875) (xy 435.306724 -371.839236) (xy 435.303398 -371.845255)
			(xy 435.299799 -371.858523) (xy 435.299612 -371.865398) (xy 435.299612 -372.614698) (xy 435.299803 -372.621571)
			(xy 435.303412 -372.634834) (xy 435.306724 -372.64086) (xy 435.323076 -372.669205) (xy 435.348793 -372.72938)
			(xy 435.366199 -372.792462) (xy 435.37498 -372.857309) (xy 435.374978 -372.890034) (xy 438.803804 -372.890034)
			(xy 438.807795 -372.827867) (xy 438.819704 -372.76672) (xy 438.839333 -372.707599) (xy 438.866362 -372.651473)
			(xy 438.900346 -372.599264) (xy 438.940728 -372.551829) (xy 438.986844 -372.509948) (xy 439.037936 -372.474308)
			(xy 439.093167 -372.445494) (xy 439.151629 -372.42398) (xy 439.212363 -372.410118) (xy 439.27437 -372.404136)
			(xy 439.336633 -372.406132) (xy 439.39813 -372.416075) (xy 439.457851 -372.433799) (xy 439.514814 -372.459016)
			(xy 439.568085 -372.491309) (xy 439.61679 -372.530149) (xy 439.660127 -372.574899) (xy 439.697387 -372.624823)
			(xy 439.727956 -372.679102) (xy 439.751334 -372.736845) (xy 439.767135 -372.797103) (xy 439.775101 -372.858886)
			(xy 439.7756 -372.890034) (xy 439.775101 -372.921182) (xy 439.767135 -372.982965) (xy 439.751334 -373.043223)
			(xy 439.727956 -373.100966) (xy 439.697387 -373.155245) (xy 439.660127 -373.205169) (xy 439.61679 -373.249919)
			(xy 439.568085 -373.288759) (xy 439.514814 -373.321052) (xy 439.457851 -373.346269) (xy 439.39813 -373.363993)
			(xy 439.336633 -373.373936) (xy 439.27437 -373.375932) (xy 439.212363 -373.36995) (xy 439.151629 -373.356088)
			(xy 439.093167 -373.334574) (xy 439.037936 -373.30576) (xy 438.986844 -373.27012) (xy 438.940728 -373.228239)
			(xy 438.900346 -373.180804) (xy 438.866362 -373.128595) (xy 438.839333 -373.072469) (xy 438.819704 -373.013348)
			(xy 438.807795 -372.952201) (xy 438.803804 -372.890034) (xy 435.374978 -372.890034) (xy 435.374976 -372.922749)
			(xy 435.366188 -372.987596) (xy 435.348774 -373.050676) (xy 435.32305 -373.110847) (xy 435.306724 -373.139208)
			(xy 435.303408 -373.145232) (xy 435.299803 -373.158496) (xy 435.299612 -373.16537) (xy 435.299612 -373.451374)
			(xy 435.299532 -373.453406) (xy 451.256398 -373.453406) (xy 451.260469 -373.397784) (xy 451.272595 -373.343347)
			(xy 451.292518 -373.291256) (xy 451.319814 -373.242621) (xy 451.3539 -373.198478) (xy 451.394049 -373.159769)
			(xy 451.439407 -373.127318) (xy 451.489007 -373.101817) (xy 451.541791 -373.08381) (xy 451.596634 -373.07368)
			(xy 451.652368 -373.071643) (xy 451.707805 -373.077743) (xy 451.761762 -373.091849) (xy 451.813091 -373.113661)
			(xy 451.860697 -373.142715) (xy 451.903565 -373.17839) (xy 451.940782 -373.219927) (xy 451.971555 -373.26644)
			(xy 451.995227 -373.316937) (xy 452.011295 -373.370344) (xy 452.019415 -373.42552) (xy 452.019924 -373.453406)
			(xy 452.019415 -373.481292) (xy 452.011295 -373.536468) (xy 451.995227 -373.589875) (xy 451.971555 -373.640372)
			(xy 451.940782 -373.686885) (xy 451.903565 -373.728422) (xy 451.860697 -373.764097) (xy 451.813091 -373.793151)
			(xy 451.761762 -373.814963) (xy 451.707805 -373.829069) (xy 451.652368 -373.835169) (xy 451.596634 -373.833132)
			(xy 451.541791 -373.823002) (xy 451.489007 -373.804995) (xy 451.439407 -373.779494) (xy 451.394049 -373.747043)
			(xy 451.3539 -373.708334) (xy 451.319814 -373.664191) (xy 451.292518 -373.615556) (xy 451.272595 -373.563465)
			(xy 451.260469 -373.509028) (xy 451.256398 -373.453406) (xy 435.299532 -373.453406) (xy 435.299213 -373.46155)
			(xy 435.291428 -373.480354) (xy 435.277034 -373.494741) (xy 435.258226 -373.502518) (xy 435.24805 -373.502936)
			(xy 434.53177 -373.502936) (xy 434.521607 -373.502491) (xy 434.502832 -373.494701) (xy 434.488467 -373.480321)
			(xy 434.480698 -373.461537) (xy 434.480208 -373.451374) (xy 434.480208 -373.16537) (xy 434.480027 -373.158496)
			(xy 434.476411 -373.145233) (xy 434.473096 -373.139208) (xy 434.456804 -373.11083) (xy 434.431086 -373.050663)
			(xy 434.413676 -372.987587) (xy 434.40489 -372.922746) (xy 434.404886 -372.857312) (xy 434.413664 -372.79247)
			(xy 434.431067 -372.729393) (xy 434.456777 -372.669222) (xy 434.473096 -372.64086) (xy 434.476425 -372.634842)
			(xy 434.480022 -372.621573) (xy 434.480208 -372.614698) (xy 434.480208 -371.865398) (xy 434.480016 -371.858525)
			(xy 434.476408 -371.845262) (xy 434.473096 -371.839236) (xy 434.456743 -371.810892) (xy 434.431031 -371.750716)
			(xy 434.413628 -371.687634) (xy 434.404849 -371.622787) (xy 433.145727 -371.622787) (xy 433.148625 -371.629568)
			(xy 433.166032 -371.692648) (xy 433.174813 -371.757493) (xy 433.174812 -371.822931) (xy 433.166027 -371.887776)
			(xy 433.148617 -371.950855) (xy 433.122899 -372.011027) (xy 433.106576 -372.039388) (xy 433.103264 -372.045414)
			(xy 433.099657 -372.058677) (xy 433.099464 -372.06555) (xy 433.099464 -372.351554) (xy 433.098999 -372.361722)
			(xy 433.091229 -372.380516) (xy 433.076856 -372.394902) (xy 433.05807 -372.402689) (xy 433.047902 -372.403116)
			(xy 432.331622 -372.403116) (xy 432.321446 -372.402717) (xy 432.302643 -372.394931) (xy 432.288256 -372.380537)
			(xy 432.280478 -372.36173) (xy 432.28006 -372.351554) (xy 432.28006 -372.06555) (xy 432.279854 -372.058678)
			(xy 432.276256 -372.045415) (xy 432.272948 -372.039388) (xy 432.256637 -372.01102) (xy 432.230918 -371.950851)
			(xy 432.213508 -371.887773) (xy 432.204723 -371.82293) (xy 432.204722 -371.757494) (xy 432.213504 -371.69265)
			(xy 432.23091 -371.629572) (xy 432.256626 -371.569401) (xy 432.272948 -371.54104) (xy 432.276244 -371.535006)
			(xy 432.279862 -371.52175) (xy 432.28006 -371.514878) (xy 432.28006 -370.765324) (xy 432.279864 -370.758451)
			(xy 432.276259 -370.745188) (xy 432.272948 -370.739162) (xy 432.256615 -370.710806) (xy 432.230898 -370.650634)
			(xy 432.213491 -370.587554) (xy 432.204708 -370.522709) (xy 428.77501 -370.522709) (xy 428.766229 -370.587551)
			(xy 428.748823 -370.650629) (xy 428.723109 -370.7108) (xy 428.706788 -370.739162) (xy 428.703486 -370.745193)
			(xy 428.699873 -370.758452) (xy 428.699676 -370.765324) (xy 428.699676 -371.514878) (xy 428.699879 -371.52175)
			(xy 428.70348 -371.535013) (xy 428.706788 -371.54104) (xy 428.723121 -371.569395) (xy 428.748836 -371.629568)
			(xy 428.766242 -371.692648) (xy 428.775024 -371.757493) (xy 428.775022 -371.822931) (xy 428.766237 -371.887776)
			(xy 428.748828 -371.950855) (xy 428.72311 -372.011026) (xy 428.706788 -372.039388) (xy 428.703477 -372.045414)
			(xy 428.699869 -372.058677) (xy 428.699676 -372.06555) (xy 428.699676 -372.351554) (xy 428.699199 -372.361721)
			(xy 428.691432 -372.380512) (xy 428.677062 -372.394898) (xy 428.65828 -372.402687) (xy 428.648114 -372.403116)
			(xy 427.931834 -372.403116) (xy 427.921659 -372.402707) (xy 427.902856 -372.394925) (xy 427.888469 -372.380534)
			(xy 427.880691 -372.361729) (xy 427.880272 -372.351554) (xy 427.880272 -372.06555) (xy 427.880064 -372.058678)
			(xy 427.876467 -372.045415) (xy 427.87316 -372.039388) (xy 427.856849 -372.01102) (xy 427.831129 -371.950851)
			(xy 427.813719 -371.887774) (xy 427.804934 -371.82293) (xy 427.804932 -371.757494) (xy 427.813714 -371.69265)
			(xy 427.831121 -371.629572) (xy 427.856838 -371.569401) (xy 427.87316 -371.54104) (xy 427.876457 -371.535007)
			(xy 427.880074 -371.52175) (xy 427.880272 -371.514878) (xy 427.880272 -370.765324) (xy 427.880074 -370.758451)
			(xy 427.87647 -370.745188) (xy 427.87316 -370.739162) (xy 427.856827 -370.710807) (xy 427.831109 -370.650634)
			(xy 427.813701 -370.587554) (xy 427.804919 -370.522709) (xy 424.375034 -370.522709) (xy 424.375034 -370.522718)
			(xy 424.366173 -370.587577) (xy 424.348677 -370.650657) (xy 424.322863 -370.710815) (xy 424.306492 -370.739162)
			(xy 424.30319 -370.745193) (xy 424.299577 -370.758452) (xy 424.29938 -370.765324) (xy 424.29938 -371.514878)
			(xy 424.299583 -371.52175) (xy 424.303184 -371.535013) (xy 424.306492 -371.54104) (xy 424.322873 -371.569381)
			(xy 424.345774 -371.622787) (xy 425.604763 -371.622787) (xy 425.604767 -371.557348) (xy 425.613555 -371.492502)
			(xy 425.630967 -371.429422) (xy 425.656688 -371.36925) (xy 425.673012 -371.340888) (xy 425.676332 -371.334866)
			(xy 425.679934 -371.3216) (xy 425.680124 -371.314726) (xy 425.680124 -371.028722) (xy 425.680582 -371.018554)
			(xy 425.688357 -370.999762) (xy 425.702732 -370.985377) (xy 425.721518 -370.977589) (xy 425.731686 -370.97716)
			(xy 426.447966 -370.97716) (xy 426.458138 -370.977592) (xy 426.476936 -370.98537) (xy 426.491323 -370.999754)
			(xy 426.499105 -371.01855) (xy 426.499528 -371.028722) (xy 426.499528 -371.314726) (xy 426.499707 -371.3216)
			(xy 426.503324 -371.334863) (xy 426.50664 -371.340888) (xy 426.522931 -371.369267) (xy 426.548652 -371.429434)
			(xy 426.566065 -371.492509) (xy 426.574853 -371.55735) (xy 426.574857 -371.622785) (xy 426.566078 -371.687627)
			(xy 426.548674 -371.750705) (xy 426.52296 -371.810875) (xy 426.50664 -371.839236) (xy 426.503316 -371.845256)
			(xy 426.499716 -371.858523) (xy 426.499528 -371.865398) (xy 426.499528 -372.614698) (xy 426.499717 -372.621571)
			(xy 426.503327 -372.634834) (xy 426.50664 -372.64086) (xy 426.522992 -372.669205) (xy 426.548708 -372.72938)
			(xy 426.566113 -372.792462) (xy 426.574894 -372.857309) (xy 426.574892 -372.890034) (xy 430.00422 -372.890034)
			(xy 430.004776 -372.857304) (xy 430.013634 -372.792445) (xy 430.031127 -372.729365) (xy 430.056938 -372.669208)
			(xy 430.073308 -372.64086) (xy 430.076638 -372.634843) (xy 430.080234 -372.621573) (xy 430.08042 -372.614698)
			(xy 430.08042 -371.865398) (xy 430.080226 -371.858525) (xy 430.076619 -371.845262) (xy 430.073308 -371.839236)
			(xy 430.056958 -371.810878) (xy 430.031152 -371.750722) (xy 430.013658 -371.687645) (xy 430.004793 -371.62279)
			(xy 430.00422 -371.590062) (xy 430.004788 -371.557333) (xy 430.013643 -371.492474) (xy 430.031132 -371.429394)
			(xy 430.05694 -371.369236) (xy 430.073308 -371.340888) (xy 430.076628 -371.334866) (xy 430.08023 -371.3216)
			(xy 430.08042 -371.314726) (xy 430.08042 -371.028722) (xy 430.080944 -371.018599) (xy 430.088661 -370.999882)
			(xy 430.102935 -370.985526) (xy 430.121608 -370.977702) (xy 430.131728 -370.97716) (xy 430.848008 -370.97716)
			(xy 430.858158 -370.977614) (xy 430.876902 -370.985405) (xy 430.891224 -370.999791) (xy 430.898931 -371.018571)
			(xy 430.899316 -371.028722) (xy 430.899316 -371.314726) (xy 430.899496 -371.3216) (xy 430.903112 -371.334863)
			(xy 430.906428 -371.340888) (xy 430.922791 -371.369238) (xy 430.948593 -371.429398) (xy 430.966083 -371.492477)
			(xy 430.974945 -371.557333) (xy 430.975516 -371.590062) (xy 430.974954 -371.622792) (xy 430.966097 -371.68765)
			(xy 430.948605 -371.75073) (xy 430.922797 -371.810888) (xy 430.906428 -371.839236) (xy 430.903102 -371.845255)
			(xy 430.899503 -371.858523) (xy 430.899316 -371.865398) (xy 430.899316 -372.614698) (xy 430.899507 -372.621571)
			(xy 430.903116 -372.634834) (xy 430.906428 -372.64086) (xy 430.92278 -372.669216) (xy 430.948585 -372.729374)
			(xy 430.966078 -372.792451) (xy 430.974943 -372.857306) (xy 430.975516 -372.890034) (xy 430.974941 -372.922763)
			(xy 430.966087 -372.987621) (xy 430.9486 -373.050701) (xy 430.922795 -373.11086) (xy 430.906428 -373.139208)
			(xy 430.903112 -373.145232) (xy 430.899507 -373.158496) (xy 430.899316 -373.16537) (xy 430.899316 -373.451374)
			(xy 430.898851 -373.461504) (xy 430.891124 -373.480233) (xy 430.87683 -373.494592) (xy 430.858136 -373.502405)
			(xy 430.848008 -373.502936) (xy 430.131728 -373.502936) (xy 430.12158 -373.502456) (xy 430.102835 -373.494677)
			(xy 430.088512 -373.480298) (xy 430.080805 -373.461523) (xy 430.08042 -373.451374) (xy 430.08042 -373.16537)
			(xy 430.080237 -373.158496) (xy 430.076622 -373.145233) (xy 430.073308 -373.139208) (xy 430.056946 -373.110857)
			(xy 430.031143 -373.050698) (xy 430.013653 -372.987619) (xy 430.004791 -372.922763) (xy 430.00422 -372.890034)
			(xy 426.574892 -372.890034) (xy 426.57489 -372.922749) (xy 426.566102 -372.987595) (xy 426.548688 -373.050675)
			(xy 426.522965 -373.110847) (xy 426.50664 -373.139208) (xy 426.503326 -373.145233) (xy 426.499719 -373.158496)
			(xy 426.499528 -373.16537) (xy 426.499528 -373.451374) (xy 426.499114 -373.461548) (xy 426.491331 -373.480349)
			(xy 426.476942 -373.494736) (xy 426.45814 -373.502515) (xy 426.447966 -373.502936) (xy 425.731686 -373.502936)
			(xy 425.72151 -373.502547) (xy 425.70271 -373.494752) (xy 425.688325 -373.480356) (xy 425.680545 -373.46155)
			(xy 425.680124 -373.451374) (xy 425.680124 -373.16537) (xy 425.67994 -373.158496) (xy 425.676326 -373.145234)
			(xy 425.673012 -373.139208) (xy 425.656719 -373.110831) (xy 425.631001 -373.050663) (xy 425.61359 -372.987588)
			(xy 425.604804 -372.922746) (xy 425.6048 -372.857312) (xy 425.613579 -372.79247) (xy 425.630981 -372.729392)
			(xy 425.656693 -372.669221) (xy 425.673012 -372.64086) (xy 425.676342 -372.634843) (xy 425.679938 -372.621573)
			(xy 425.680124 -372.614698) (xy 425.680124 -371.865398) (xy 425.67993 -371.858525) (xy 425.676323 -371.845262)
			(xy 425.673012 -371.839236) (xy 425.656658 -371.810892) (xy 425.630945 -371.750717) (xy 425.613542 -371.687634)
			(xy 425.604763 -371.622787) (xy 424.345774 -371.622787) (xy 424.348671 -371.629543) (xy 424.366157 -371.692625)
			(xy 424.375012 -371.757484) (xy 424.37558 -371.790214) (xy 424.375001 -371.822943) (xy 424.366149 -371.887801)
			(xy 424.348663 -371.950881) (xy 424.322859 -372.01104) (xy 424.306492 -372.039388) (xy 424.303181 -372.045414)
			(xy 424.299573 -372.058677) (xy 424.29938 -372.06555) (xy 424.29938 -372.351554) (xy 424.298836 -372.361675)
			(xy 424.291127 -372.380392) (xy 424.276858 -372.394749) (xy 424.25819 -372.402573) (xy 424.248072 -372.403116)
			(xy 423.531792 -372.403116) (xy 423.521639 -372.402685) (xy 423.50289 -372.39489) (xy 423.488568 -372.380496)
			(xy 423.480865 -372.361709) (xy 423.480484 -372.351554) (xy 423.480484 -372.06555) (xy 423.480275 -372.058678)
			(xy 423.476678 -372.045415) (xy 423.473372 -372.039388) (xy 423.456999 -372.011043) (xy 423.4312 -371.950882)
			(xy 423.413712 -371.887801) (xy 423.404854 -371.822943) (xy 423.404284 -371.790214) (xy 422.131582 -371.790214)
			(xy 422.122713 -371.810888) (xy 422.106344 -371.839236) (xy 422.10302 -371.845256) (xy 422.09942 -371.858523)
			(xy 422.099232 -371.865398) (xy 422.099232 -372.614698) (xy 422.099421 -372.621572) (xy 422.103031 -372.634834)
			(xy 422.106344 -372.64086) (xy 422.122688 -372.669221) (xy 422.148497 -372.729376) (xy 422.165992 -372.792452)
			(xy 422.174859 -372.857306) (xy 422.175432 -372.890034) (xy 422.174855 -372.922763) (xy 422.166002 -372.987621)
			(xy 422.148515 -373.050701) (xy 422.122711 -373.11086) (xy 422.106344 -373.139208) (xy 422.10303 -373.145233)
			(xy 422.099423 -373.158496) (xy 422.099232 -373.16537) (xy 422.099232 -373.451374) (xy 422.098751 -373.461503)
			(xy 422.091027 -373.480228) (xy 422.076738 -373.494587) (xy 422.05805 -373.502402) (xy 422.047924 -373.502936)
			(xy 421.331644 -373.502936) (xy 421.321497 -373.502443) (xy 421.302753 -373.494669) (xy 421.288429 -373.480294)
			(xy 421.280721 -373.461522) (xy 421.280336 -373.451374) (xy 421.280336 -373.16537) (xy 421.280151 -373.158496)
			(xy 421.276537 -373.145234) (xy 421.273224 -373.139208) (xy 421.256864 -373.110856) (xy 421.23106 -373.050697)
			(xy 421.213569 -372.987619) (xy 421.204707 -372.922763) (xy 421.204136 -372.890034) (xy 408.160505 -372.890034)
			(xy 408.160219 -372.905728) (xy 408.152099 -372.960904) (xy 408.136031 -373.014311) (xy 408.112359 -373.064808)
			(xy 408.081586 -373.111321) (xy 408.044369 -373.152858) (xy 408.001501 -373.188533) (xy 407.953895 -373.217587)
			(xy 407.902566 -373.239399) (xy 407.848609 -373.253505) (xy 407.793172 -373.259605) (xy 407.737438 -373.257568)
			(xy 407.682595 -373.247438) (xy 407.629811 -373.229431) (xy 407.580211 -373.20393) (xy 407.534853 -373.171479)
			(xy 407.494704 -373.13277) (xy 407.460618 -373.088627) (xy 407.433322 -373.039992) (xy 407.413399 -372.987901)
			(xy 407.401273 -372.933464) (xy 407.397202 -372.877842) (xy 396.865094 -372.877842) (xy 396.865094 -374.16486)
			(xy 403.928832 -374.16486) (xy 403.932903 -374.109238) (xy 403.945029 -374.054801) (xy 403.964952 -374.00271)
			(xy 403.992248 -373.954075) (xy 404.026334 -373.909932) (xy 404.066483 -373.871223) (xy 404.111841 -373.838772)
			(xy 404.161441 -373.813271) (xy 404.214225 -373.795264) (xy 404.269068 -373.785134) (xy 404.324802 -373.783097)
			(xy 404.380239 -373.789197) (xy 404.434196 -373.803303) (xy 404.485525 -373.825115) (xy 404.533131 -373.854169)
			(xy 404.575999 -373.889844) (xy 404.613216 -373.931381) (xy 404.643989 -373.977894) (xy 404.667661 -374.028391)
			(xy 404.683729 -374.081798) (xy 404.691849 -374.136974) (xy 404.692358 -374.16486) (xy 404.691849 -374.192746)
			(xy 404.683729 -374.247922) (xy 404.667661 -374.301329) (xy 404.643989 -374.351826) (xy 404.613216 -374.398339)
			(xy 404.575999 -374.439876) (xy 404.533131 -374.475551) (xy 404.485525 -374.504605) (xy 404.434196 -374.526417)
			(xy 404.380239 -374.540523) (xy 404.324802 -374.546623) (xy 404.269068 -374.544586) (xy 404.214225 -374.534456)
			(xy 404.161441 -374.516449) (xy 404.111841 -374.490948) (xy 404.066483 -374.458497) (xy 404.026334 -374.419788)
			(xy 403.992248 -374.375645) (xy 403.964952 -374.32701) (xy 403.945029 -374.274919) (xy 403.932903 -374.220482)
			(xy 403.928832 -374.16486) (xy 396.865094 -374.16486) (xy 396.865094 -374.702653) (xy 405.266855 -374.702653)
			(xy 405.266855 -374.648147) (xy 405.274612 -374.594195) (xy 405.289969 -374.541897) (xy 405.312612 -374.492317)
			(xy 405.34208 -374.446463) (xy 405.377775 -374.40527) (xy 405.418968 -374.369577) (xy 405.464822 -374.340109)
			(xy 405.514403 -374.317467) (xy 405.566701 -374.302111) (xy 405.620653 -374.294355) (xy 405.647906 -374.293892)
			(xy 405.64816 -374.293892) (xy 405.676552 -374.294419) (xy 405.732706 -374.302865) (xy 405.78699 -374.319533)
			(xy 405.838208 -374.344055) (xy 405.885231 -374.375889) (xy 405.906478 -374.39473) (xy 405.913844 -374.401588)
			(xy 405.93264 -374.408446) (xy 406.014682 -374.405144) (xy 406.02457 -374.404284) (xy 406.042608 -374.396051)
			(xy 406.049734 -374.389142) (xy 406.049988 -374.388888) (xy 406.068094 -374.369853) (xy 406.108661 -374.336473)
			(xy 406.153427 -374.308978) (xy 406.201543 -374.287887) (xy 406.252098 -374.273602) (xy 406.304136 -374.266391)
			(xy 406.330404 -374.265952) (xy 406.357652 -374.266518) (xy 406.411594 -374.274275) (xy 406.463882 -374.289628)
			(xy 406.513454 -374.312267) (xy 406.559299 -374.341731) (xy 406.600484 -374.377418) (xy 406.636172 -374.418604)
			(xy 406.638922 -374.422884) (xy 419.004815 -374.422884) (xy 419.00482 -374.357444) (xy 419.01361 -374.292597)
			(xy 419.031025 -374.229517) (xy 419.05675 -374.169345) (xy 419.073076 -374.140984) (xy 419.076395 -374.134961)
			(xy 419.079998 -374.121696) (xy 419.080188 -374.114822) (xy 419.080188 -373.828818) (xy 419.08058 -373.818641)
			(xy 419.088368 -373.799837) (xy 419.102764 -373.78545) (xy 419.121573 -373.777673) (xy 419.13175 -373.777256)
			(xy 419.84803 -373.777256) (xy 419.858192 -373.777709) (xy 419.876965 -373.785497) (xy 419.89133 -373.799875)
			(xy 419.8991 -373.818656) (xy 419.899592 -373.828818) (xy 419.899592 -374.114822) (xy 419.899776 -374.121696)
			(xy 419.90339 -374.134959) (xy 419.906704 -374.140984) (xy 419.922989 -374.169365) (xy 419.948708 -374.229532)
			(xy 419.966118 -374.292607) (xy 419.974906 -374.357447) (xy 419.97491 -374.422881) (xy 419.966133 -374.487722)
			(xy 419.948732 -374.5508) (xy 419.923022 -374.61097) (xy 419.906704 -374.639332) (xy 419.903378 -374.645351)
			(xy 419.899779 -374.658619) (xy 419.899592 -374.665494) (xy 419.899592 -375.414794) (xy 419.899787 -375.421667)
			(xy 419.903393 -375.43493) (xy 419.906704 -375.440956) (xy 419.92305 -375.469304) (xy 419.948763 -375.529479)
			(xy 419.966167 -375.59256) (xy 419.974947 -375.657407) (xy 419.974943 -375.722845) (xy 419.966157 -375.787691)
			(xy 419.948746 -375.85077) (xy 419.923027 -375.910942) (xy 419.906704 -375.939304) (xy 419.903388 -375.945328)
			(xy 419.899783 -375.958592) (xy 419.899592 -375.965466) (xy 419.899592 -376.25147) (xy 419.899043 -376.261622)
			(xy 419.891284 -376.280385) (xy 419.876935 -376.29475) (xy 419.858182 -376.302531) (xy 419.84803 -376.303032)
			(xy 419.13175 -376.303032) (xy 419.121578 -376.302595) (xy 419.102779 -376.29482) (xy 419.088391 -376.280438)
			(xy 419.080609 -376.261642) (xy 419.080188 -376.25147) (xy 419.080188 -375.965466) (xy 419.080011 -375.958592)
			(xy 419.076393 -375.945329) (xy 419.073076 -375.939304) (xy 419.056778 -375.910929) (xy 419.031056 -375.850762)
			(xy 419.013644 -375.787686) (xy 419.004856 -375.722843) (xy 419.004853 -375.657408) (xy 419.013634 -375.592565)
			(xy 419.031039 -375.529487) (xy 419.056755 -375.469317) (xy 419.073076 -375.440956) (xy 419.076405 -375.434938)
			(xy 419.080002 -375.421669) (xy 419.080188 -375.414794) (xy 419.080188 -374.665494) (xy 419.08 -374.65862)
			(xy 419.076389 -374.645358) (xy 419.073076 -374.639332) (xy 419.056717 -374.610991) (xy 419.031001 -374.550815)
			(xy 419.013595 -374.487732) (xy 419.004815 -374.422884) (xy 406.638922 -374.422884) (xy 406.665634 -374.46445)
			(xy 406.688273 -374.514021) (xy 406.703626 -374.56631) (xy 406.711382 -374.620252) (xy 406.711382 -374.674748)
			(xy 406.703626 -374.72869) (xy 406.688273 -374.780979) (xy 406.665634 -374.83055) (xy 406.636172 -374.876396)
			(xy 406.600484 -374.917582) (xy 406.559299 -374.953269) (xy 406.513454 -374.982733) (xy 406.463882 -375.005372)
			(xy 406.411594 -375.020725) (xy 406.357652 -375.028482) (xy 406.330404 -375.028968) (xy 406.33015 -375.028968)
			(xy 406.301757 -375.028445) (xy 406.245603 -375.019999) (xy 406.191318 -375.003331) (xy 406.1401 -374.978809)
			(xy 406.093079 -374.946972) (xy 406.071832 -374.92813) (xy 406.064466 -374.921272) (xy 406.04567 -374.914414)
			(xy 405.963628 -374.917716) (xy 405.953738 -374.918564) (xy 405.935699 -374.926804) (xy 405.928576 -374.933718)
			(xy 405.928322 -374.933972) (xy 405.910204 -374.952995) (xy 405.86964 -374.986377) (xy 405.824877 -375.013875)
			(xy 405.776763 -375.034968) (xy 405.72621 -375.049256) (xy 405.674173 -375.056468) (xy 405.647906 -375.056908)
			(xy 405.620653 -375.056445) (xy 405.566701 -375.048689) (xy 405.514403 -375.033333) (xy 405.464822 -375.010691)
			(xy 405.418968 -374.981223) (xy 405.377775 -374.94553) (xy 405.34208 -374.904337) (xy 405.312612 -374.858483)
			(xy 405.289969 -374.808903) (xy 405.274612 -374.756605) (xy 405.266855 -374.702653) (xy 396.865094 -374.702653)
			(xy 396.865094 -376.790204) (xy 421.204136 -376.790204) (xy 421.20469 -376.757474) (xy 421.213551 -376.692616)
			(xy 421.231044 -376.629536) (xy 421.256854 -376.569378) (xy 421.273224 -376.54103) (xy 421.27653 -376.535001)
			(xy 421.280141 -376.521741) (xy 421.280336 -376.514868) (xy 421.280336 -375.765568) (xy 421.280152 -375.758694)
			(xy 421.276538 -375.745432) (xy 421.273224 -375.739406) (xy 421.256863 -375.711054) (xy 421.23106 -375.650896)
			(xy 421.213569 -375.587817) (xy 421.204707 -375.522961) (xy 421.204136 -375.490232) (xy 421.204702 -375.457503)
			(xy 421.213559 -375.392645) (xy 421.23105 -375.329565) (xy 421.256856 -375.269406) (xy 421.273224 -375.241058)
			(xy 421.276555 -375.235042) (xy 421.28015 -375.221771) (xy 421.280336 -375.214896) (xy 421.280336 -374.928638)
			(xy 421.280858 -374.918514) (xy 421.288572 -374.899795) (xy 421.302848 -374.885437) (xy 421.321523 -374.877616)
			(xy 421.331644 -374.877076) (xy 422.047924 -374.877076) (xy 422.058077 -374.877501) (xy 422.076825 -374.8853)
			(xy 422.091147 -374.899695) (xy 422.09885 -374.918483) (xy 422.099232 -374.928638) (xy 422.099232 -375.214896)
			(xy 422.099422 -375.221769) (xy 422.103031 -375.235032) (xy 422.106344 -375.241058) (xy 422.122688 -375.269419)
			(xy 422.148496 -375.329574) (xy 422.165992 -375.39265) (xy 422.174859 -375.457504) (xy 422.175432 -375.490232)
			(xy 422.174854 -375.522961) (xy 422.166001 -375.587819) (xy 422.148515 -375.650899) (xy 422.131688 -375.69013)
			(xy 423.404284 -375.69013) (xy 423.404843 -375.6574) (xy 423.413701 -375.592542) (xy 423.431193 -375.529462)
			(xy 423.457002 -375.469304) (xy 423.473372 -375.440956) (xy 423.4767 -375.434938) (xy 423.480298 -375.421669)
			(xy 423.480484 -375.414794) (xy 423.480484 -374.665494) (xy 423.480296 -374.65862) (xy 423.476685 -374.645358)
			(xy 423.473372 -374.639332) (xy 423.457016 -374.610977) (xy 423.431213 -374.55082) (xy 423.413721 -374.487742)
			(xy 423.404857 -374.422886) (xy 423.404284 -374.390158) (xy 423.404856 -374.357429) (xy 423.41371 -374.292571)
			(xy 423.431199 -374.229491) (xy 423.457004 -374.169332) (xy 423.473372 -374.140984) (xy 423.47669 -374.134961)
			(xy 423.480294 -374.121696) (xy 423.480484 -374.114822) (xy 423.480484 -373.828818) (xy 423.480942 -373.818687)
			(xy 423.488672 -373.799958) (xy 423.502968 -373.785599) (xy 423.521663 -373.777787) (xy 423.531792 -373.777256)
			(xy 424.248072 -373.777256) (xy 424.258219 -373.777743) (xy 424.276962 -373.785522) (xy 424.291285 -373.799898)
			(xy 424.298994 -373.81867) (xy 424.29938 -373.828818) (xy 424.29938 -374.114822) (xy 424.299566 -374.121696)
			(xy 424.303179 -374.134958) (xy 424.306492 -374.140984) (xy 424.32285 -374.169337) (xy 424.348654 -374.229495)
			(xy 424.366146 -374.292573) (xy 424.375008 -374.357429) (xy 424.37558 -374.390158) (xy 424.37502 -374.422884)
			(xy 427.804902 -374.422884) (xy 427.804907 -374.357444) (xy 427.813696 -374.292597) (xy 427.83111 -374.229517)
			(xy 427.856834 -374.169345) (xy 427.87316 -374.140984) (xy 427.876477 -374.13496) (xy 427.880082 -374.121696)
			(xy 427.880272 -374.114822) (xy 427.880272 -373.828818) (xy 427.880679 -373.818643) (xy 427.888465 -373.799842)
			(xy 427.902856 -373.785456) (xy 427.921659 -373.777676) (xy 427.931834 -373.777256) (xy 428.648114 -373.777256)
			(xy 428.658289 -373.777653) (xy 428.677087 -373.785446) (xy 428.691472 -373.79984) (xy 428.699253 -373.818643)
			(xy 428.699676 -373.828818) (xy 428.699676 -374.114822) (xy 428.699863 -374.121696) (xy 428.703475 -374.134958)
			(xy 428.706788 -374.140984) (xy 428.723074 -374.169365) (xy 428.748793 -374.229532) (xy 428.766204 -374.292607)
			(xy 428.774992 -374.357447) (xy 428.774997 -374.422881) (xy 428.774997 -374.422884) (xy 432.204691 -374.422884)
			(xy 432.204696 -374.357444) (xy 432.213485 -374.292597) (xy 432.230899 -374.229517) (xy 432.256623 -374.169345)
			(xy 432.272948 -374.140984) (xy 432.276264 -374.13496) (xy 432.27987 -374.121696) (xy 432.28006 -374.114822)
			(xy 432.28006 -373.828818) (xy 432.280479 -373.818645) (xy 432.288262 -373.799846) (xy 432.30265 -373.78546)
			(xy 432.321449 -373.777678) (xy 432.331622 -373.777256) (xy 433.047902 -373.777256) (xy 433.058076 -373.777663)
			(xy 433.076874 -373.785452) (xy 433.09126 -373.799843) (xy 433.099041 -373.818644) (xy 433.099464 -373.828818)
			(xy 433.099464 -374.114822) (xy 433.099652 -374.121695) (xy 433.103264 -374.134958) (xy 433.106576 -374.140984)
			(xy 433.122862 -374.169365) (xy 433.148582 -374.229532) (xy 433.165994 -374.292606) (xy 433.174781 -374.357447)
			(xy 433.174783 -374.390158) (xy 436.603656 -374.390158) (xy 436.607647 -374.327991) (xy 436.619556 -374.266844)
			(xy 436.639185 -374.207723) (xy 436.666214 -374.151597) (xy 436.700198 -374.099388) (xy 436.74058 -374.051953)
			(xy 436.786696 -374.010072) (xy 436.837788 -373.974432) (xy 436.893019 -373.945618) (xy 436.951481 -373.924104)
			(xy 437.012215 -373.910242) (xy 437.074222 -373.90426) (xy 437.136485 -373.906256) (xy 437.197982 -373.916199)
			(xy 437.257703 -373.933923) (xy 437.314666 -373.95914) (xy 437.367937 -373.991433) (xy 437.416642 -374.030273)
			(xy 437.459979 -374.075023) (xy 437.497239 -374.124947) (xy 437.527808 -374.179226) (xy 437.551186 -374.236969)
			(xy 437.566987 -374.297227) (xy 437.574953 -374.35901) (xy 437.575452 -374.390158) (xy 437.574953 -374.421306)
			(xy 437.566987 -374.483089) (xy 437.551186 -374.543347) (xy 437.527808 -374.60109) (xy 437.497239 -374.655369)
			(xy 437.459979 -374.705293) (xy 437.416642 -374.750043) (xy 437.367937 -374.788883) (xy 437.314666 -374.821176)
			(xy 437.257703 -374.846393) (xy 437.197982 -374.864117) (xy 437.136485 -374.87406) (xy 437.074222 -374.876056)
			(xy 437.012215 -374.870074) (xy 436.951481 -374.856212) (xy 436.893019 -374.834698) (xy 436.837788 -374.805884)
			(xy 436.786696 -374.770244) (xy 436.74058 -374.728363) (xy 436.700198 -374.680928) (xy 436.666214 -374.628719)
			(xy 436.639185 -374.572593) (xy 436.619556 -374.513472) (xy 436.607647 -374.452325) (xy 436.603656 -374.390158)
			(xy 433.174783 -374.390158) (xy 433.174786 -374.422881) (xy 433.166008 -374.487723) (xy 433.148606 -374.5508)
			(xy 433.122895 -374.610971) (xy 433.106576 -374.639332) (xy 433.103248 -374.64535) (xy 433.099651 -374.658619)
			(xy 433.099464 -374.665494) (xy 433.099464 -375.414794) (xy 433.099663 -375.421667) (xy 433.103267 -375.434929)
			(xy 433.106576 -375.440956) (xy 433.122923 -375.469303) (xy 433.148638 -375.529478) (xy 433.166042 -375.59256)
			(xy 433.174822 -375.657406) (xy 433.174819 -375.722845) (xy 433.166032 -375.787691) (xy 433.148621 -375.850771)
			(xy 433.1229 -375.910943) (xy 433.106576 -375.939304) (xy 433.103258 -375.945327) (xy 433.099655 -375.958592)
			(xy 433.099464 -375.965466) (xy 433.099464 -376.25147) (xy 433.099011 -376.261639) (xy 433.091237 -376.280433)
			(xy 433.07686 -376.294819) (xy 433.058071 -376.302605) (xy 433.047902 -376.303032) (xy 432.331622 -376.303032)
			(xy 432.321448 -376.302617) (xy 432.302648 -376.294834) (xy 432.288262 -376.280445) (xy 432.280481 -376.261644)
			(xy 432.28006 -376.25147) (xy 432.28006 -375.965466) (xy 432.279886 -375.958591) (xy 432.276266 -375.945328)
			(xy 432.272948 -375.939304) (xy 432.256651 -375.910929) (xy 432.23093 -375.850761) (xy 432.213519 -375.787685)
			(xy 432.204732 -375.722843) (xy 432.204729 -375.657408) (xy 432.213509 -375.592565) (xy 432.230913 -375.529488)
			(xy 432.256627 -375.469317) (xy 432.272948 -375.440956) (xy 432.276274 -375.434937) (xy 432.279873 -375.421669)
			(xy 432.28006 -375.414794) (xy 432.28006 -374.665494) (xy 432.279875 -374.65862) (xy 432.276263 -374.645357)
			(xy 432.272948 -374.639332) (xy 432.25659 -374.61099) (xy 432.230875 -374.550815) (xy 432.213471 -374.487732)
			(xy 432.204691 -374.422884) (xy 428.774997 -374.422884) (xy 428.766219 -374.487723) (xy 428.748817 -374.5508)
			(xy 428.723107 -374.610971) (xy 428.706788 -374.639332) (xy 428.703461 -374.645351) (xy 428.699863 -374.658619)
			(xy 428.699676 -374.665494) (xy 428.699676 -375.414794) (xy 428.699873 -375.421667) (xy 428.703478 -375.434929)
			(xy 428.706788 -375.440956) (xy 428.723135 -375.469304) (xy 428.748849 -375.529478) (xy 428.766253 -375.59256)
			(xy 428.775033 -375.657407) (xy 428.775029 -375.722845) (xy 428.766243 -375.787691) (xy 428.748832 -375.85077)
			(xy 428.723111 -375.910942) (xy 428.706788 -375.939304) (xy 428.703471 -375.945327) (xy 428.699867 -375.958592)
			(xy 428.699676 -375.965466) (xy 428.699676 -376.25147) (xy 428.699212 -376.261638) (xy 428.691439 -376.280429)
			(xy 428.677066 -376.294815) (xy 428.658282 -376.302603) (xy 428.648114 -376.303032) (xy 427.931834 -376.303032)
			(xy 427.921661 -376.302607) (xy 427.902861 -376.294828) (xy 427.888474 -376.280442) (xy 427.880693 -376.261643)
			(xy 427.880272 -376.25147) (xy 427.880272 -375.965466) (xy 427.880097 -375.958591) (xy 427.876478 -375.945328)
			(xy 427.87316 -375.939304) (xy 427.856863 -375.910929) (xy 427.831141 -375.850761) (xy 427.81373 -375.787685)
			(xy 427.804943 -375.722843) (xy 427.804939 -375.657408) (xy 427.813719 -375.592565) (xy 427.831124 -375.529487)
			(xy 427.856839 -375.469317) (xy 427.87316 -375.440956) (xy 427.876487 -375.434937) (xy 427.880085 -375.421669)
			(xy 427.880272 -375.414794) (xy 427.880272 -374.665494) (xy 427.880086 -374.65862) (xy 427.876474 -374.645357)
			(xy 427.87316 -374.639332) (xy 427.856802 -374.610991) (xy 427.831086 -374.550815) (xy 427.813681 -374.487732)
			(xy 427.804902 -374.422884) (xy 424.37502 -374.422884) (xy 424.37502 -374.422888) (xy 424.366163 -374.487746)
			(xy 424.348671 -374.550827) (xy 424.322862 -374.610984) (xy 424.306492 -374.639332) (xy 424.303165 -374.645351)
			(xy 424.299567 -374.658619) (xy 424.29938 -374.665494) (xy 424.29938 -375.414794) (xy 424.299577 -375.421667)
			(xy 424.303182 -375.43493) (xy 424.306492 -375.440956) (xy 424.322839 -375.469315) (xy 424.348646 -375.529471)
			(xy 424.366141 -375.592547) (xy 424.375007 -375.657402) (xy 424.37558 -375.69013) (xy 424.375008 -375.722859)
			(xy 424.366154 -375.787717) (xy 424.348666 -375.850798) (xy 424.32286 -375.910956) (xy 424.306492 -375.939304)
			(xy 424.303175 -375.945328) (xy 424.299571 -375.958592) (xy 424.29938 -375.965466) (xy 424.29938 -376.25147)
			(xy 424.29885 -376.261592) (xy 424.291135 -376.280309) (xy 424.276863 -376.294666) (xy 424.258191 -376.30249)
			(xy 424.248072 -376.303032) (xy 423.531792 -376.303032) (xy 423.521641 -376.302585) (xy 423.502895 -376.294793)
			(xy 423.488573 -376.280405) (xy 423.480868 -376.261622) (xy 423.480484 -376.25147) (xy 423.480484 -375.965466)
			(xy 423.480307 -375.958592) (xy 423.476689 -375.945329) (xy 423.473372 -375.939304) (xy 423.457005 -375.910955)
			(xy 423.431204 -375.850795) (xy 423.413715 -375.787716) (xy 423.404855 -375.722859) (xy 423.404284 -375.69013)
			(xy 422.131688 -375.69013) (xy 422.122711 -375.711058) (xy 422.106344 -375.739406) (xy 422.103031 -375.745431)
			(xy 422.099424 -375.758694) (xy 422.099232 -375.765568) (xy 422.099232 -376.514868) (xy 422.099432 -376.521741)
			(xy 422.103034 -376.535004) (xy 422.106344 -376.54103) (xy 422.122716 -376.569376) (xy 422.148518 -376.629536)
			(xy 422.166006 -376.692617) (xy 422.174863 -376.757475) (xy 422.174863 -376.757485) (xy 425.604786 -376.757485)
			(xy 425.613569 -376.692641) (xy 425.630975 -376.629563) (xy 425.656691 -376.569392) (xy 425.673012 -376.54103)
			(xy 425.676317 -376.535001) (xy 425.679929 -376.521741) (xy 425.680124 -376.514868) (xy 425.680124 -375.765568)
			(xy 425.679941 -375.758694) (xy 425.676326 -375.745431) (xy 425.673012 -375.739406) (xy 425.656718 -375.71103)
			(xy 425.630999 -375.650862) (xy 425.613589 -375.587786) (xy 425.604802 -375.522945) (xy 425.604799 -375.45751)
			(xy 425.613578 -375.392668) (xy 425.630981 -375.32959) (xy 425.656693 -375.26942) (xy 425.673012 -375.241058)
			(xy 425.676343 -375.235041) (xy 425.679938 -375.221771) (xy 425.680124 -375.214896) (xy 425.680124 -374.928638)
			(xy 425.680595 -374.918471) (xy 425.688365 -374.899679) (xy 425.702736 -374.885294) (xy 425.721519 -374.877505)
			(xy 425.731686 -374.877076) (xy 426.447966 -374.877076) (xy 426.45814 -374.877493) (xy 426.476941 -374.885274)
			(xy 426.491329 -374.899662) (xy 426.499108 -374.918464) (xy 426.499528 -374.928638) (xy 426.499528 -375.214896)
			(xy 426.499718 -375.221769) (xy 426.503327 -375.235032) (xy 426.50664 -375.241058) (xy 426.52299 -375.269404)
			(xy 426.548706 -375.329579) (xy 426.566112 -375.39266) (xy 426.574893 -375.457508) (xy 426.574889 -375.522947)
			(xy 426.566101 -375.587793) (xy 426.548688 -375.650873) (xy 426.522965 -375.711045) (xy 426.50664 -375.739406)
			(xy 426.503326 -375.745431) (xy 426.49972 -375.758694) (xy 426.499528 -375.765568) (xy 426.499528 -376.514868)
			(xy 426.499729 -376.521741) (xy 426.503331 -376.535004) (xy 426.50664 -376.54103) (xy 426.522966 -376.569389)
			(xy 426.548685 -376.629561) (xy 426.566093 -376.69264) (xy 426.574877 -376.757485) (xy 426.574876 -376.790204)
			(xy 430.00422 -376.790204) (xy 430.004763 -376.757474) (xy 430.013625 -376.692614) (xy 430.031122 -376.629534)
			(xy 430.056936 -376.569377) (xy 430.073308 -376.54103) (xy 430.076613 -376.535) (xy 430.080225 -376.52174)
			(xy 430.08042 -376.514868) (xy 430.08042 -375.765568) (xy 430.080238 -375.758694) (xy 430.076623 -375.745431)
			(xy 430.073308 -375.739406) (xy 430.056946 -375.711055) (xy 430.031143 -375.650896) (xy 430.013652 -375.587817)
			(xy 430.004791 -375.522961) (xy 430.00422 -375.490232) (xy 430.004775 -375.457502) (xy 430.013634 -375.392643)
			(xy 430.031127 -375.329563) (xy 430.056938 -375.269406) (xy 430.073308 -375.241058) (xy 430.076638 -375.235041)
			(xy 430.080234 -375.221771) (xy 430.08042 -375.214896) (xy 430.08042 -374.928638) (xy 430.080957 -374.918516)
			(xy 430.088669 -374.8998) (xy 430.10294 -374.885443) (xy 430.121609 -374.877619) (xy 430.131728 -374.877076)
			(xy 430.848008 -374.877076) (xy 430.85816 -374.877515) (xy 430.876907 -374.885308) (xy 430.89123 -374.899699)
			(xy 430.898933 -374.918484) (xy 430.899316 -374.928638) (xy 430.899316 -375.214896) (xy 430.899508 -375.221769)
			(xy 430.903116 -375.235032) (xy 430.906428 -375.241058) (xy 430.92278 -375.269415) (xy 430.948584 -375.329572)
			(xy 430.966078 -375.392649) (xy 430.974943 -375.457504) (xy 430.975516 -375.490232) (xy 430.97494 -375.522961)
			(xy 430.966087 -375.587819) (xy 430.948599 -375.650899) (xy 430.922795 -375.711057) (xy 430.906428 -375.739406)
			(xy 430.903113 -375.745431) (xy 430.899507 -375.758694) (xy 430.899316 -375.765568) (xy 430.899316 -376.514868)
			(xy 430.899518 -376.52174) (xy 430.903119 -376.535003) (xy 430.906428 -376.54103) (xy 430.922808 -376.569371)
			(xy 430.948606 -376.629534) (xy 430.966091 -376.692616) (xy 430.974948 -376.757474) (xy 430.974948 -376.757485)
			(xy 434.404872 -376.757485) (xy 434.413655 -376.692642) (xy 434.431061 -376.629563) (xy 434.456775 -376.569392)
			(xy 434.473096 -376.54103) (xy 434.4764 -376.535) (xy 434.480012 -376.52174) (xy 434.480208 -376.514868)
			(xy 434.480208 -375.765568) (xy 434.480027 -375.758694) (xy 434.476411 -375.745431) (xy 434.473096 -375.739406)
			(xy 434.456802 -375.711029) (xy 434.431084 -375.650861) (xy 434.413675 -375.587786) (xy 434.404889 -375.522944)
			(xy 434.404885 -375.45751) (xy 434.413664 -375.392668) (xy 434.431066 -375.329591) (xy 434.456777 -375.26942)
			(xy 434.473096 -375.241058) (xy 434.476425 -375.235041) (xy 434.480022 -375.221771) (xy 434.480208 -375.214896)
			(xy 434.480208 -374.928638) (xy 434.480694 -374.918473) (xy 434.488461 -374.899684) (xy 434.502827 -374.885299)
			(xy 434.521605 -374.877508) (xy 434.53177 -374.877076) (xy 435.24805 -374.877076) (xy 435.258223 -374.877506)
			(xy 435.277024 -374.885281) (xy 435.291412 -374.899666) (xy 435.299192 -374.918465) (xy 435.299612 -374.928638)
			(xy 435.299612 -375.214896) (xy 435.299804 -375.221769) (xy 435.303412 -375.235032) (xy 435.306724 -375.241058)
			(xy 435.323074 -375.269404) (xy 435.348792 -375.329578) (xy 435.366198 -375.39266) (xy 435.374979 -375.457508)
			(xy 435.374975 -375.522947) (xy 435.366187 -375.587794) (xy 435.348773 -375.650874) (xy 435.331991 -375.69013)
			(xy 436.603656 -375.69013) (xy 436.607647 -375.627963) (xy 436.619556 -375.566816) (xy 436.639185 -375.507695)
			(xy 436.666214 -375.451569) (xy 436.700198 -375.39936) (xy 436.74058 -375.351925) (xy 436.786696 -375.310044)
			(xy 436.837788 -375.274404) (xy 436.893019 -375.24559) (xy 436.951481 -375.224076) (xy 437.012215 -375.210214)
			(xy 437.074222 -375.204232) (xy 437.136485 -375.206228) (xy 437.197982 -375.216171) (xy 437.257703 -375.233895)
			(xy 437.314666 -375.259112) (xy 437.367937 -375.291405) (xy 437.416642 -375.330245) (xy 437.459979 -375.374995)
			(xy 437.497239 -375.424919) (xy 437.527808 -375.479198) (xy 437.532275 -375.490232) (xy 438.803804 -375.490232)
			(xy 438.807795 -375.428065) (xy 438.819704 -375.366918) (xy 438.839333 -375.307797) (xy 438.866362 -375.251671)
			(xy 438.900346 -375.199462) (xy 438.940728 -375.152027) (xy 438.986844 -375.110146) (xy 439.037936 -375.074506)
			(xy 439.093167 -375.045692) (xy 439.151629 -375.024178) (xy 439.212363 -375.010316) (xy 439.27437 -375.004334)
			(xy 439.336633 -375.00633) (xy 439.39813 -375.016273) (xy 439.457851 -375.033997) (xy 439.514814 -375.059214)
			(xy 439.565899 -375.090182) (xy 459.19085 -375.090182) (xy 459.194921 -375.03456) (xy 459.207047 -374.980123)
			(xy 459.22697 -374.928032) (xy 459.254266 -374.879397) (xy 459.288352 -374.835254) (xy 459.328501 -374.796545)
			(xy 459.373859 -374.764094) (xy 459.423459 -374.738593) (xy 459.476243 -374.720586) (xy 459.531086 -374.710456)
			(xy 459.58682 -374.708419) (xy 459.642257 -374.714519) (xy 459.696214 -374.728625) (xy 459.747543 -374.750437)
			(xy 459.795149 -374.779491) (xy 459.838017 -374.815166) (xy 459.875234 -374.856703) (xy 459.906007 -374.903216)
			(xy 459.929679 -374.953713) (xy 459.945747 -375.00712) (xy 459.953867 -375.062296) (xy 459.954376 -375.090182)
			(xy 459.953867 -375.118068) (xy 459.945747 -375.173244) (xy 459.929679 -375.226651) (xy 459.906007 -375.277148)
			(xy 459.875234 -375.323661) (xy 459.838017 -375.365198) (xy 459.795149 -375.400873) (xy 459.747543 -375.429927)
			(xy 459.696214 -375.451739) (xy 459.642257 -375.465845) (xy 459.58682 -375.471945) (xy 459.531086 -375.469908)
			(xy 459.476243 -375.459778) (xy 459.423459 -375.441771) (xy 459.373859 -375.41627) (xy 459.328501 -375.383819)
			(xy 459.288352 -375.34511) (xy 459.254266 -375.300967) (xy 459.22697 -375.252332) (xy 459.207047 -375.200241)
			(xy 459.194921 -375.145804) (xy 459.19085 -375.090182) (xy 439.565899 -375.090182) (xy 439.568085 -375.091507)
			(xy 439.61679 -375.130347) (xy 439.660127 -375.175097) (xy 439.697387 -375.225021) (xy 439.727956 -375.2793)
			(xy 439.751334 -375.337043) (xy 439.767135 -375.397301) (xy 439.775101 -375.459084) (xy 439.7756 -375.490232)
			(xy 439.775101 -375.52138) (xy 439.767135 -375.583163) (xy 439.751334 -375.643421) (xy 439.727956 -375.701164)
			(xy 439.697387 -375.755443) (xy 439.660127 -375.805367) (xy 439.61679 -375.850117) (xy 439.568085 -375.888957)
			(xy 439.514814 -375.92125) (xy 439.457851 -375.946467) (xy 439.39813 -375.964191) (xy 439.336633 -375.974134)
			(xy 439.27437 -375.97613) (xy 439.212363 -375.970148) (xy 439.151629 -375.956286) (xy 439.093167 -375.934772)
			(xy 439.037936 -375.905958) (xy 438.986844 -375.870318) (xy 438.940728 -375.828437) (xy 438.900346 -375.781002)
			(xy 438.866362 -375.728793) (xy 438.839333 -375.672667) (xy 438.819704 -375.613546) (xy 438.807795 -375.552399)
			(xy 438.803804 -375.490232) (xy 437.532275 -375.490232) (xy 437.551186 -375.536941) (xy 437.566987 -375.597199)
			(xy 437.574953 -375.658982) (xy 437.575452 -375.69013) (xy 437.574953 -375.721278) (xy 437.566987 -375.783061)
			(xy 437.551186 -375.843319) (xy 437.527808 -375.901062) (xy 437.497239 -375.955341) (xy 437.459979 -376.005265)
			(xy 437.416642 -376.050015) (xy 437.367937 -376.088855) (xy 437.314666 -376.121148) (xy 437.257703 -376.146365)
			(xy 437.197982 -376.164089) (xy 437.136485 -376.174032) (xy 437.074222 -376.176028) (xy 437.012215 -376.170046)
			(xy 436.951481 -376.156184) (xy 436.893019 -376.13467) (xy 436.837788 -376.105856) (xy 436.786696 -376.070216)
			(xy 436.74058 -376.028335) (xy 436.700198 -375.9809) (xy 436.666214 -375.928691) (xy 436.639185 -375.872565)
			(xy 436.619556 -375.813444) (xy 436.607647 -375.752297) (xy 436.603656 -375.69013) (xy 435.331991 -375.69013)
			(xy 435.32305 -375.711045) (xy 435.306724 -375.739406) (xy 435.303409 -375.74543) (xy 435.299803 -375.758694)
			(xy 435.299612 -375.765568) (xy 435.299612 -376.514868) (xy 435.299815 -376.52174) (xy 435.303416 -376.535003)
			(xy 435.306724 -376.54103) (xy 435.323051 -376.569389) (xy 435.34877 -376.62956) (xy 435.366179 -376.692639)
			(xy 435.374963 -376.757485) (xy 435.374962 -376.790204) (xy 438.803804 -376.790204) (xy 438.807795 -376.728037)
			(xy 438.819704 -376.66689) (xy 438.839333 -376.607769) (xy 438.866362 -376.551643) (xy 438.900346 -376.499434)
			(xy 438.940728 -376.451999) (xy 438.986844 -376.410118) (xy 439.037936 -376.374478) (xy 439.093167 -376.345664)
			(xy 439.151629 -376.32415) (xy 439.212363 -376.310288) (xy 439.27437 -376.304306) (xy 439.336633 -376.306302)
			(xy 439.39813 -376.316245) (xy 439.457851 -376.333969) (xy 439.514814 -376.359186) (xy 439.568085 -376.391479)
			(xy 439.61679 -376.430319) (xy 439.660127 -376.475069) (xy 439.697387 -376.524993) (xy 439.727956 -376.579272)
			(xy 439.751334 -376.637015) (xy 439.767135 -376.697273) (xy 439.775101 -376.759056) (xy 439.7756 -376.790204)
			(xy 439.775101 -376.821352) (xy 439.767135 -376.883135) (xy 439.751334 -376.943393) (xy 439.727956 -377.001136)
			(xy 439.697387 -377.055415) (xy 439.660127 -377.105339) (xy 439.61679 -377.150089) (xy 439.568085 -377.188929)
			(xy 439.514814 -377.221222) (xy 439.457851 -377.246439) (xy 439.39813 -377.264163) (xy 439.336633 -377.274106)
			(xy 439.27437 -377.276102) (xy 439.212363 -377.27012) (xy 439.151629 -377.256258) (xy 439.093167 -377.234744)
			(xy 439.037936 -377.20593) (xy 438.986844 -377.17029) (xy 438.940728 -377.128409) (xy 438.900346 -377.080974)
			(xy 438.866362 -377.028765) (xy 438.839333 -376.972639) (xy 438.819704 -376.913518) (xy 438.807795 -376.852371)
			(xy 438.803804 -376.790204) (xy 435.374962 -376.790204) (xy 435.374962 -376.822922) (xy 435.366178 -376.887767)
			(xy 435.348768 -376.950846) (xy 435.323048 -377.011017) (xy 435.306724 -377.039378) (xy 435.303419 -377.045407)
			(xy 435.299807 -377.058667) (xy 435.299612 -377.06554) (xy 435.299612 -377.35129) (xy 435.299227 -377.361467)
			(xy 435.291436 -377.380271) (xy 435.277038 -377.394658) (xy 435.258228 -377.402435) (xy 435.24805 -377.402852)
			(xy 434.53177 -377.402852) (xy 434.521609 -377.402391) (xy 434.502837 -377.394605) (xy 434.488473 -377.380229)
			(xy 434.480701 -377.361451) (xy 434.480208 -377.35129) (xy 434.480208 -377.06554) (xy 434.48 -377.058668)
			(xy 434.476402 -377.045405) (xy 434.473096 -377.039378) (xy 434.456778 -377.011014) (xy 434.431063 -376.950843)
			(xy 434.413656 -376.887765) (xy 434.404873 -376.822921) (xy 434.404872 -376.757485) (xy 430.974948 -376.757485)
			(xy 430.975516 -376.790204) (xy 430.974972 -376.822934) (xy 430.96611 -376.887793) (xy 430.948613 -376.950873)
			(xy 430.9228 -377.011031) (xy 430.906428 -377.039378) (xy 430.903123 -377.045407) (xy 430.899511 -377.058667)
			(xy 430.899316 -377.06554) (xy 430.899316 -377.35129) (xy 430.898864 -377.361421) (xy 430.891131 -377.380151)
			(xy 430.876834 -377.394509) (xy 430.858137 -377.402321) (xy 430.848008 -377.402852) (xy 430.131728 -377.402852)
			(xy 430.121582 -377.402357) (xy 430.10284 -377.39458) (xy 430.088518 -377.380207) (xy 430.080808 -377.361437)
			(xy 430.08042 -377.35129) (xy 430.08042 -377.06554) (xy 430.08021 -377.058668) (xy 430.076614 -377.045405)
			(xy 430.073308 -377.039378) (xy 430.056934 -377.011033) (xy 430.031134 -376.950872) (xy 430.013647 -376.887791)
			(xy 430.004789 -376.822933) (xy 430.00422 -376.790204) (xy 426.574876 -376.790204) (xy 426.574876 -376.822922)
			(xy 426.566092 -376.887767) (xy 426.548682 -376.950846) (xy 426.522963 -377.011017) (xy 426.50664 -377.039378)
			(xy 426.503336 -377.045408) (xy 426.499723 -377.058668) (xy 426.499528 -377.06554) (xy 426.499528 -377.35129)
			(xy 426.499127 -377.361465) (xy 426.491339 -377.380266) (xy 426.476946 -377.394653) (xy 426.458141 -377.402432)
			(xy 426.447966 -377.402852) (xy 425.731686 -377.402852) (xy 425.721526 -377.402378) (xy 425.702755 -377.394597)
			(xy 425.68839 -377.380225) (xy 425.680618 -377.36145) (xy 425.680124 -377.35129) (xy 425.680124 -377.06554)
			(xy 425.679914 -377.058668) (xy 425.676318 -377.045405) (xy 425.673012 -377.039378) (xy 425.656694 -377.011015)
			(xy 425.630977 -376.950844) (xy 425.61357 -376.887765) (xy 425.604787 -376.822921) (xy 425.604786 -376.757485)
			(xy 422.174863 -376.757485) (xy 422.175432 -376.790204) (xy 422.174886 -376.822934) (xy 422.166024 -376.887793)
			(xy 422.148528 -376.950873) (xy 422.122715 -377.011031) (xy 422.106344 -377.039378) (xy 422.103041 -377.045408)
			(xy 422.099427 -377.058668) (xy 422.099232 -377.06554) (xy 422.099232 -377.35129) (xy 422.098764 -377.36142)
			(xy 422.091035 -377.380146) (xy 422.076742 -377.394503) (xy 422.058051 -377.402318) (xy 422.047924 -377.402852)
			(xy 421.331644 -377.402852) (xy 421.321499 -377.402343) (xy 421.302758 -377.394572) (xy 421.288435 -377.380202)
			(xy 421.280724 -377.361436) (xy 421.280336 -377.35129) (xy 421.280336 -377.06554) (xy 421.280124 -377.058668)
			(xy 421.276529 -377.045406) (xy 421.273224 -377.039378) (xy 421.256852 -377.011032) (xy 421.231051 -376.950872)
			(xy 421.213563 -376.887791) (xy 421.204705 -376.822933) (xy 421.204136 -376.790204) (xy 396.865094 -376.790204)
			(xy 396.865094 -378.076968) (xy 406.020014 -378.076968) (xy 406.024085 -378.021346) (xy 406.036211 -377.966909)
			(xy 406.056134 -377.914818) (xy 406.08343 -377.866183) (xy 406.117516 -377.82204) (xy 406.157665 -377.783331)
			(xy 406.203023 -377.75088) (xy 406.252623 -377.725379) (xy 406.305407 -377.707372) (xy 406.36025 -377.697242)
			(xy 406.415984 -377.695205) (xy 406.471421 -377.701305) (xy 406.525378 -377.715411) (xy 406.576707 -377.737223)
			(xy 406.624313 -377.766277) (xy 406.667181 -377.801952) (xy 406.704398 -377.843489) (xy 406.735171 -377.890002)
			(xy 406.758843 -377.940499) (xy 406.774911 -377.993906) (xy 406.783031 -378.049082) (xy 406.78354 -378.076968)
			(xy 406.783031 -378.104854) (xy 406.774911 -378.16003) (xy 406.758843 -378.213437) (xy 406.735171 -378.263934)
			(xy 406.704398 -378.310447) (xy 406.693332 -378.322797) (xy 419.004825 -378.322797) (xy 419.004828 -378.257358)
			(xy 419.013615 -378.192512) (xy 419.031028 -378.129432) (xy 419.056751 -378.069261) (xy 419.073076 -378.0409)
			(xy 419.076389 -378.034874) (xy 419.079996 -378.021611) (xy 419.080188 -378.014738) (xy 419.080188 -377.728734)
			(xy 419.080593 -377.718558) (xy 419.088376 -377.699755) (xy 419.102768 -377.685367) (xy 419.121574 -377.67759)
			(xy 419.13175 -377.677172) (xy 419.84803 -377.677172) (xy 419.858208 -377.67754) (xy 419.87701 -377.685341)
			(xy 419.891395 -377.699744) (xy 419.899173 -377.718556) (xy 419.899592 -377.728734) (xy 419.899592 -378.014738)
			(xy 419.899809 -378.021609) (xy 419.9034 -378.034872) (xy 419.906704 -378.0409) (xy 419.923003 -378.069274)
			(xy 419.94872 -378.129443) (xy 419.966129 -378.192519) (xy 419.974915 -378.257361) (xy 419.974918 -378.322795)
			(xy 419.966138 -378.387638) (xy 419.948735 -378.450715) (xy 419.923023 -378.510886) (xy 419.906704 -378.539248)
			(xy 419.903372 -378.545264) (xy 419.899777 -378.558535) (xy 419.899592 -378.56541) (xy 419.899592 -379.31471)
			(xy 419.899781 -379.321583) (xy 419.903391 -379.334846) (xy 419.906704 -379.340872) (xy 419.923064 -379.369212)
			(xy 419.948776 -379.429389) (xy 419.966178 -379.492472) (xy 419.974956 -379.55732) (xy 419.97495 -379.622759)
			(xy 419.966162 -379.687606) (xy 419.948749 -379.750686) (xy 419.923028 -379.810858) (xy 419.906704 -379.83922)
			(xy 419.903382 -379.845241) (xy 419.899781 -379.858508) (xy 419.899592 -379.865382) (xy 419.899592 -380.151386)
			(xy 419.899056 -380.161539) (xy 419.891292 -380.180302) (xy 419.876939 -380.194667) (xy 419.858183 -380.202447)
			(xy 419.84803 -380.202948) (xy 419.13175 -380.202948) (xy 419.12158 -380.202495) (xy 419.102784 -380.194724)
			(xy 419.088396 -380.180347) (xy 419.080612 -380.161556) (xy 419.080188 -380.151386) (xy 419.080188 -379.865382)
			(xy 419.080005 -379.858508) (xy 419.076391 -379.845245) (xy 419.073076 -379.83922) (xy 419.056792 -379.810838)
			(xy 419.031068 -379.750672) (xy 419.013655 -379.687597) (xy 419.004866 -379.622756) (xy 419.00486 -379.557322)
			(xy 419.013639 -379.49248) (xy 419.031042 -379.429403) (xy 419.056756 -379.369233) (xy 419.073076 -379.340872)
			(xy 419.076399 -379.334851) (xy 419.08 -379.321585) (xy 419.080188 -379.31471) (xy 419.080188 -378.56541)
			(xy 419.079994 -378.558537) (xy 419.076387 -378.545274) (xy 419.073076 -378.539248) (xy 419.056731 -378.510899)
			(xy 419.031013 -378.450726) (xy 419.013606 -378.387644) (xy 419.004825 -378.322797) (xy 406.693332 -378.322797)
			(xy 406.667181 -378.351984) (xy 406.624313 -378.387659) (xy 406.576707 -378.416713) (xy 406.525378 -378.438525)
			(xy 406.471421 -378.452631) (xy 406.415984 -378.458731) (xy 406.36025 -378.456694) (xy 406.305407 -378.446564)
			(xy 406.252623 -378.428557) (xy 406.203023 -378.403056) (xy 406.157665 -378.370605) (xy 406.117516 -378.331896)
			(xy 406.08343 -378.287753) (xy 406.056134 -378.239118) (xy 406.036211 -378.187027) (xy 406.024085 -378.13259)
			(xy 406.020014 -378.076968) (xy 396.865094 -378.076968) (xy 396.865094 -378.968) (xy 405.011634 -378.968)
			(xy 405.015705 -378.912378) (xy 405.027831 -378.857941) (xy 405.047754 -378.80585) (xy 405.07505 -378.757215)
			(xy 405.109136 -378.713072) (xy 405.149285 -378.674363) (xy 405.194643 -378.641912) (xy 405.244243 -378.616411)
			(xy 405.297027 -378.598404) (xy 405.35187 -378.588274) (xy 405.407604 -378.586237) (xy 405.463041 -378.592337)
			(xy 405.516998 -378.606443) (xy 405.568327 -378.628255) (xy 405.615933 -378.657309) (xy 405.658801 -378.692984)
			(xy 405.696018 -378.734521) (xy 405.726791 -378.781034) (xy 405.750463 -378.831531) (xy 405.766531 -378.884938)
			(xy 405.774651 -378.940114) (xy 405.77516 -378.968) (xy 405.774651 -378.995886) (xy 405.766531 -379.051062)
			(xy 405.750463 -379.104469) (xy 405.726791 -379.154966) (xy 405.696018 -379.201479) (xy 405.658801 -379.243016)
			(xy 405.615933 -379.278691) (xy 405.568327 -379.307745) (xy 405.516998 -379.329557) (xy 405.463041 -379.343663)
			(xy 405.407604 -379.349763) (xy 405.35187 -379.347726) (xy 405.297027 -379.337596) (xy 405.244243 -379.319589)
			(xy 405.194643 -379.294088) (xy 405.149285 -379.261637) (xy 405.109136 -379.222928) (xy 405.07505 -379.178785)
			(xy 405.047754 -379.13015) (xy 405.027831 -379.078059) (xy 405.015705 -379.023622) (xy 405.011634 -378.968)
			(xy 396.865094 -378.968) (xy 396.865094 -380.69012) (xy 421.204136 -380.69012) (xy 421.204697 -380.65739)
			(xy 421.213556 -380.592532) (xy 421.231047 -380.529452) (xy 421.256855 -380.469294) (xy 421.273224 -380.440946)
			(xy 421.276524 -380.434914) (xy 421.280139 -380.421656) (xy 421.280336 -380.414784) (xy 421.280336 -379.665484)
			(xy 421.280146 -379.658611) (xy 421.276536 -379.645348) (xy 421.273224 -379.639322) (xy 421.256869 -379.610967)
			(xy 421.231064 -379.55081) (xy 421.213572 -379.487732) (xy 421.204708 -379.422877) (xy 421.204136 -379.390148)
			(xy 421.204709 -379.357419) (xy 421.213564 -379.292561) (xy 421.231052 -379.229481) (xy 421.256857 -379.169323)
			(xy 421.273224 -379.140974) (xy 421.27655 -379.134955) (xy 421.280148 -379.121687) (xy 421.280336 -379.114812)
			(xy 421.280336 -378.828554) (xy 421.280789 -378.818425) (xy 421.288531 -378.799703) (xy 421.302827 -378.785349)
			(xy 421.321517 -378.777531) (xy 421.331644 -378.776992) (xy 422.047924 -378.776992) (xy 422.058079 -378.777402)
			(xy 422.07683 -378.785204) (xy 422.091152 -378.799604) (xy 422.098853 -378.818397) (xy 422.099232 -378.828554)
			(xy 422.099232 -379.114812) (xy 422.099416 -379.121686) (xy 422.103029 -379.134949) (xy 422.106344 -379.140974)
			(xy 422.122694 -379.169332) (xy 422.148501 -379.229488) (xy 422.165995 -379.292565) (xy 422.17486 -379.35742)
			(xy 422.175432 -379.390148) (xy 422.174861 -379.422877) (xy 422.166006 -379.487735) (xy 422.148517 -379.550815)
			(xy 422.131689 -379.590046) (xy 423.404284 -379.590046) (xy 423.40485 -379.557317) (xy 423.413706 -379.492458)
			(xy 423.431197 -379.429378) (xy 423.457004 -379.36922) (xy 423.473372 -379.340872) (xy 423.476695 -379.334851)
			(xy 423.480296 -379.321585) (xy 423.480484 -379.31471) (xy 423.480484 -378.56541) (xy 423.48029 -378.558537)
			(xy 423.476683 -378.545274) (xy 423.473372 -378.539248) (xy 423.456983 -378.510912) (xy 423.431187 -378.450747)
			(xy 423.413705 -378.387664) (xy 423.404851 -378.322804) (xy 423.404284 -378.290074) (xy 423.404863 -378.257345)
			(xy 423.413715 -378.192487) (xy 423.431202 -378.129407) (xy 423.457005 -378.069249) (xy 423.473372 -378.0409)
			(xy 423.476685 -378.034874) (xy 423.480292 -378.021611) (xy 423.480484 -378.014738) (xy 423.480484 -377.728734)
			(xy 423.480956 -377.718604) (xy 423.488681 -377.699875) (xy 423.502972 -377.685516) (xy 423.521664 -377.677704)
			(xy 423.531792 -377.677172) (xy 424.248072 -377.677172) (xy 424.258221 -377.677644) (xy 424.276967 -377.685425)
			(xy 424.291291 -377.699806) (xy 424.298996 -377.718584) (xy 424.29938 -377.728734) (xy 424.29938 -378.014738)
			(xy 424.299598 -378.021609) (xy 424.303189 -378.034872) (xy 424.306492 -378.0409) (xy 424.322857 -378.06925)
			(xy 424.348659 -378.129409) (xy 424.366149 -378.192488) (xy 424.37501 -378.257345) (xy 424.37558 -378.290074)
			(xy 424.375028 -378.322797) (xy 427.804911 -378.322797) (xy 427.804914 -378.257358) (xy 427.813701 -378.192512)
			(xy 427.831113 -378.129433) (xy 427.856835 -378.069261) (xy 427.87316 -378.0409) (xy 427.876471 -378.034874)
			(xy 427.88008 -378.021611) (xy 427.880272 -378.014738) (xy 427.880272 -377.728734) (xy 427.880693 -377.71856)
			(xy 427.888473 -377.69976) (xy 427.90286 -377.685373) (xy 427.92166 -377.677593) (xy 427.931834 -377.677172)
			(xy 428.648114 -377.677172) (xy 428.658291 -377.677553) (xy 428.677092 -377.685349) (xy 428.691478 -377.699748)
			(xy 428.699256 -377.718557) (xy 428.699676 -377.728734) (xy 428.699676 -378.014738) (xy 428.699895 -378.021609)
			(xy 428.703485 -378.034872) (xy 428.706788 -378.0409) (xy 428.723087 -378.069274) (xy 428.748806 -378.129442)
			(xy 428.766215 -378.192518) (xy 428.775001 -378.25736) (xy 428.775004 -378.322795) (xy 428.775004 -378.322797)
			(xy 432.2047 -378.322797) (xy 432.204703 -378.257358) (xy 432.21349 -378.192512) (xy 432.230902 -378.129433)
			(xy 432.256624 -378.069261) (xy 432.272948 -378.0409) (xy 432.276259 -378.034873) (xy 432.279867 -378.021611)
			(xy 432.28006 -378.014738) (xy 432.28006 -377.728734) (xy 432.280492 -377.718562) (xy 432.28827 -377.699764)
			(xy 432.302654 -377.685377) (xy 432.32145 -377.677595) (xy 432.331622 -377.677172) (xy 433.047902 -377.677172)
			(xy 433.058078 -377.677563) (xy 433.076879 -377.685355) (xy 433.091265 -377.699751) (xy 433.099044 -377.718558)
			(xy 433.099464 -377.728734) (xy 433.099464 -378.014738) (xy 433.099684 -378.021609) (xy 433.103274 -378.034872)
			(xy 433.106576 -378.0409) (xy 433.122876 -378.069274) (xy 433.148595 -378.129442) (xy 433.166005 -378.192518)
			(xy 433.174791 -378.25736) (xy 433.174792 -378.290074) (xy 436.603656 -378.290074) (xy 436.607647 -378.227907)
			(xy 436.619556 -378.16676) (xy 436.639185 -378.107639) (xy 436.666214 -378.051513) (xy 436.700198 -377.999304)
			(xy 436.74058 -377.951869) (xy 436.786696 -377.909988) (xy 436.837788 -377.874348) (xy 436.893019 -377.845534)
			(xy 436.951481 -377.82402) (xy 437.012215 -377.810158) (xy 437.074222 -377.804176) (xy 437.136485 -377.806172)
			(xy 437.197982 -377.816115) (xy 437.257703 -377.833839) (xy 437.314666 -377.859056) (xy 437.367937 -377.891349)
			(xy 437.416642 -377.930189) (xy 437.459979 -377.974939) (xy 437.497239 -378.024863) (xy 437.527808 -378.079142)
			(xy 437.551186 -378.136885) (xy 437.566987 -378.197143) (xy 437.574953 -378.258926) (xy 437.575452 -378.290074)
			(xy 437.574953 -378.321222) (xy 437.566987 -378.383005) (xy 437.551186 -378.443263) (xy 437.527808 -378.501006)
			(xy 437.497239 -378.555285) (xy 437.459979 -378.605209) (xy 437.416642 -378.649959) (xy 437.367937 -378.688799)
			(xy 437.314666 -378.721092) (xy 437.257703 -378.746309) (xy 437.197982 -378.764033) (xy 437.136485 -378.773976)
			(xy 437.074222 -378.775972) (xy 437.012215 -378.76999) (xy 436.951481 -378.756128) (xy 436.893019 -378.734614)
			(xy 436.837788 -378.7058) (xy 436.786696 -378.67016) (xy 436.74058 -378.628279) (xy 436.700198 -378.580844)
			(xy 436.666214 -378.528635) (xy 436.639185 -378.472509) (xy 436.619556 -378.413388) (xy 436.607647 -378.352241)
			(xy 436.603656 -378.290074) (xy 433.174792 -378.290074) (xy 433.174794 -378.322795) (xy 433.166014 -378.387638)
			(xy 433.148609 -378.450716) (xy 433.122896 -378.510887) (xy 433.106576 -378.539248) (xy 433.103243 -378.545263)
			(xy 433.099649 -378.558534) (xy 433.099464 -378.56541) (xy 433.099464 -379.31471) (xy 433.099657 -379.321583)
			(xy 433.103265 -379.334846) (xy 433.106576 -379.340872) (xy 433.122937 -379.369212) (xy 433.14865 -379.429388)
			(xy 433.166053 -379.492471) (xy 433.174832 -379.55732) (xy 433.174826 -379.622759) (xy 433.166037 -379.687606)
			(xy 433.148624 -379.750686) (xy 433.122901 -379.810859) (xy 433.106576 -379.83922) (xy 433.103252 -379.84524)
			(xy 433.099653 -379.858507) (xy 433.099464 -379.865382) (xy 433.099464 -380.151386) (xy 433.099025 -380.161556)
			(xy 433.091245 -380.180351) (xy 433.076864 -380.194736) (xy 433.058072 -380.202522) (xy 433.047902 -380.202948)
			(xy 432.331622 -380.202948) (xy 432.32145 -380.202518) (xy 432.302653 -380.194737) (xy 432.288267 -380.180353)
			(xy 432.280484 -380.161558) (xy 432.28006 -380.151386) (xy 432.28006 -379.865382) (xy 432.27988 -379.858508)
			(xy 432.276264 -379.845245) (xy 432.272948 -379.83922) (xy 432.256664 -379.810837) (xy 432.230943 -379.750671)
			(xy 432.21353 -379.687597) (xy 432.204741 -379.622756) (xy 432.204736 -379.557323) (xy 432.213514 -379.49248)
			(xy 432.230917 -379.429403) (xy 432.256629 -379.369233) (xy 432.272948 -379.340872) (xy 432.276269 -379.33485)
			(xy 432.279871 -379.321584) (xy 432.28006 -379.31471) (xy 432.28006 -378.56541) (xy 432.279869 -378.558537)
			(xy 432.276261 -378.545274) (xy 432.272948 -378.539248) (xy 432.256603 -378.510899) (xy 432.230887 -378.450725)
			(xy 432.213481 -378.387644) (xy 432.2047 -378.322797) (xy 428.775004 -378.322797) (xy 428.766224 -378.387638)
			(xy 428.74882 -378.450716) (xy 428.723108 -378.510886) (xy 428.706788 -378.539248) (xy 428.703455 -378.545264)
			(xy 428.699861 -378.558534) (xy 428.699676 -378.56541) (xy 428.699676 -379.31471) (xy 428.699867 -379.321583)
			(xy 428.703476 -379.334846) (xy 428.706788 -379.340872) (xy 428.723148 -379.369212) (xy 428.748861 -379.429388)
			(xy 428.766264 -379.492472) (xy 428.775042 -379.55732) (xy 428.775037 -379.622759) (xy 428.766248 -379.687606)
			(xy 428.748835 -379.750686) (xy 428.723112 -379.810858) (xy 428.706788 -379.83922) (xy 428.703465 -379.845241)
			(xy 428.699865 -379.858508) (xy 428.699676 -379.865382) (xy 428.699676 -380.151386) (xy 428.699156 -380.161541)
			(xy 428.691388 -380.180307) (xy 428.677031 -380.194673) (xy 428.658269 -380.20245) (xy 428.648114 -380.202948)
			(xy 427.931834 -380.202948) (xy 427.921663 -380.202508) (xy 427.902866 -380.194731) (xy 427.88848 -380.180351)
			(xy 427.880696 -380.161557) (xy 427.880272 -380.151386) (xy 427.880272 -379.865382) (xy 427.88009 -379.858508)
			(xy 427.876475 -379.845245) (xy 427.87316 -379.83922) (xy 427.856876 -379.810837) (xy 427.831154 -379.750672)
			(xy 427.813741 -379.687597) (xy 427.804952 -379.622756) (xy 427.804946 -379.557323) (xy 427.813725 -379.49248)
			(xy 427.831128 -379.429403) (xy 427.85684 -379.369233) (xy 427.87316 -379.340872) (xy 427.876481 -379.334851)
			(xy 427.880083 -379.321584) (xy 427.880272 -379.31471) (xy 427.880272 -378.56541) (xy 427.88008 -378.558537)
			(xy 427.876472 -378.545274) (xy 427.87316 -378.539248) (xy 427.856815 -378.510899) (xy 427.831098 -378.450725)
			(xy 427.813692 -378.387644) (xy 427.804911 -378.322797) (xy 424.375028 -378.322797) (xy 424.375028 -378.322804)
			(xy 424.366168 -378.387663) (xy 424.348674 -378.450743) (xy 424.322863 -378.5109) (xy 424.306492 -378.539248)
			(xy 424.30316 -378.545264) (xy 424.299565 -378.558534) (xy 424.29938 -378.56541) (xy 424.29938 -379.31471)
			(xy 424.299571 -379.321583) (xy 424.30318 -379.334846) (xy 424.306492 -379.340872) (xy 424.322846 -379.369228)
			(xy 424.348651 -379.429385) (xy 424.366144 -379.492462) (xy 424.375008 -379.557318) (xy 424.37558 -379.590046)
			(xy 424.375015 -379.622776) (xy 424.366159 -379.687634) (xy 424.348669 -379.750714) (xy 424.322861 -379.810872)
			(xy 424.306492 -379.83922) (xy 424.30317 -379.845241) (xy 424.299569 -379.858508) (xy 424.29938 -379.865382)
			(xy 424.29938 -380.151386) (xy 424.298863 -380.161509) (xy 424.291143 -380.180226) (xy 424.276866 -380.194583)
			(xy 424.258193 -380.202406) (xy 424.248072 -380.202948) (xy 423.531792 -380.202948) (xy 423.521643 -380.202486)
			(xy 423.5029 -380.194697) (xy 423.488579 -380.180313) (xy 423.480871 -380.161536) (xy 423.480484 -380.151386)
			(xy 423.480484 -379.865382) (xy 423.480301 -379.858508) (xy 423.476687 -379.845245) (xy 423.473372 -379.83922)
			(xy 423.457012 -379.810868) (xy 423.431209 -379.750709) (xy 423.413718 -379.687631) (xy 423.404856 -379.622775)
			(xy 423.404284 -379.590046) (xy 422.131689 -379.590046) (xy 422.122712 -379.610974) (xy 422.106344 -379.639322)
			(xy 422.103025 -379.645345) (xy 422.099422 -379.65861) (xy 422.099232 -379.665484) (xy 422.099232 -380.414784)
			(xy 422.099426 -380.421657) (xy 422.103033 -380.43492) (xy 422.106344 -380.440946) (xy 422.122723 -380.469288)
			(xy 422.148523 -380.52945) (xy 422.166009 -380.592532) (xy 422.174864 -380.65739) (xy 422.174864 -380.6574)
			(xy 425.604793 -380.6574) (xy 425.613574 -380.592556) (xy 425.630978 -380.529479) (xy 425.656692 -380.469308)
			(xy 425.673012 -380.440946) (xy 425.676311 -380.434914) (xy 425.679926 -380.421656) (xy 425.680124 -380.414784)
			(xy 425.680124 -379.665484) (xy 425.679935 -379.658611) (xy 425.676324 -379.645348) (xy 425.673012 -379.639322)
			(xy 425.656731 -379.610938) (xy 425.631011 -379.550772) (xy 425.6136 -379.487698) (xy 425.604812 -379.422858)
			(xy 425.604806 -379.357425) (xy 425.613583 -379.292583) (xy 425.630984 -379.229506) (xy 425.656694 -379.169335)
			(xy 425.673012 -379.140974) (xy 425.676337 -379.134954) (xy 425.679936 -379.121687) (xy 425.680124 -379.114812)
			(xy 425.680124 -378.828554) (xy 425.680595 -378.818395) (xy 425.688382 -378.799628) (xy 425.702754 -378.785264)
			(xy 425.721527 -378.777489) (xy 425.731686 -378.776992) (xy 426.447966 -378.776992) (xy 426.458116 -378.77756)
			(xy 426.476875 -378.785315) (xy 426.49124 -378.799657) (xy 426.499024 -378.818405) (xy 426.499528 -378.828554)
			(xy 426.499528 -379.114812) (xy 426.499712 -379.121686) (xy 426.503325 -379.134949) (xy 426.50664 -379.140974)
			(xy 426.523004 -379.169313) (xy 426.548718 -379.229489) (xy 426.566123 -379.292572) (xy 426.574902 -379.357421)
			(xy 426.574896 -379.422861) (xy 426.566106 -379.487709) (xy 426.548691 -379.550789) (xy 426.522966 -379.610961)
			(xy 426.50664 -379.639322) (xy 426.503321 -379.645344) (xy 426.499718 -379.65861) (xy 426.499528 -379.665484)
			(xy 426.499528 -380.414784) (xy 426.499723 -380.421657) (xy 426.503329 -380.43492) (xy 426.50664 -380.440946)
			(xy 426.52298 -380.469298) (xy 426.548697 -380.529471) (xy 426.566104 -380.592552) (xy 426.574886 -380.657398)
			(xy 426.574884 -380.69012) (xy 430.00422 -380.69012) (xy 430.00477 -380.65739) (xy 430.01363 -380.592531)
			(xy 430.031125 -380.529451) (xy 430.056937 -380.469293) (xy 430.073308 -380.440946) (xy 430.076607 -380.434914)
			(xy 430.080222 -380.421656) (xy 430.08042 -380.414784) (xy 430.08042 -379.665484) (xy 430.080232 -379.658611)
			(xy 430.076621 -379.645348) (xy 430.073308 -379.639322) (xy 430.056952 -379.610968) (xy 430.031148 -379.55081)
			(xy 430.013655 -379.487732) (xy 430.004792 -379.422877) (xy 430.00422 -379.390148) (xy 430.004782 -379.357418)
			(xy 430.013639 -379.29256) (xy 430.03113 -379.22948) (xy 430.056939 -379.169322) (xy 430.073308 -379.140974)
			(xy 430.076633 -379.134954) (xy 430.080232 -379.121687) (xy 430.08042 -379.114812) (xy 430.08042 -378.828554)
			(xy 430.080888 -378.818427) (xy 430.088628 -378.799708) (xy 430.102919 -378.785354) (xy 430.121603 -378.777533)
			(xy 430.131728 -378.776992) (xy 430.848008 -378.776992) (xy 430.858162 -378.777415) (xy 430.876913 -378.785212)
			(xy 430.891235 -378.799608) (xy 430.898936 -378.818398) (xy 430.899316 -378.828554) (xy 430.899316 -379.114812)
			(xy 430.899501 -379.121686) (xy 430.903114 -379.134949) (xy 430.906428 -379.140974) (xy 430.922786 -379.169327)
			(xy 430.948589 -379.229486) (xy 430.966081 -379.292564) (xy 430.974944 -379.357419) (xy 430.975516 -379.390148)
			(xy 430.974947 -379.422877) (xy 430.966092 -379.487735) (xy 430.948602 -379.550816) (xy 430.922796 -379.610974)
			(xy 430.906428 -379.639322) (xy 430.903107 -379.645344) (xy 430.899505 -379.65861) (xy 430.899316 -379.665484)
			(xy 430.899316 -380.414784) (xy 430.899512 -380.421657) (xy 430.903117 -380.43492) (xy 430.906428 -380.440946)
			(xy 430.922815 -380.469284) (xy 430.948611 -380.529448) (xy 430.966094 -380.592531) (xy 430.974949 -380.65739)
			(xy 430.974949 -380.6574) (xy 434.40488 -380.6574) (xy 434.41366 -380.592557) (xy 434.431064 -380.529479)
			(xy 434.456776 -380.469308) (xy 434.473096 -380.440946) (xy 434.476394 -380.434913) (xy 434.48001 -380.421656)
			(xy 434.480208 -380.414784) (xy 434.480208 -379.665484) (xy 434.480021 -379.65861) (xy 434.476409 -379.645348)
			(xy 434.473096 -379.639322) (xy 434.456816 -379.610938) (xy 434.431097 -379.550772) (xy 434.413686 -379.487698)
			(xy 434.404898 -379.422858) (xy 434.404892 -379.357425) (xy 434.413669 -379.292583) (xy 434.431069 -379.229506)
			(xy 434.456778 -379.169336) (xy 434.473096 -379.140974) (xy 434.47642 -379.134954) (xy 434.48002 -379.121687)
			(xy 434.480208 -379.114812) (xy 434.480208 -378.828554) (xy 434.480695 -378.818397) (xy 434.488479 -378.799633)
			(xy 434.502846 -378.78527) (xy 434.521613 -378.777492) (xy 434.53177 -378.776992) (xy 435.24805 -378.776992)
			(xy 435.258213 -378.777504) (xy 435.276998 -378.785264) (xy 435.291383 -378.799622) (xy 435.299177 -378.818392)
			(xy 435.299612 -378.828554) (xy 435.299612 -379.114812) (xy 435.299798 -379.121686) (xy 435.30341 -379.134949)
			(xy 435.306724 -379.140974) (xy 435.323088 -379.169312) (xy 435.348804 -379.229489) (xy 435.366209 -379.292572)
			(xy 435.374988 -379.357421) (xy 435.374982 -379.422861) (xy 435.366192 -379.487709) (xy 435.348777 -379.550789)
			(xy 435.331993 -379.590046) (xy 436.603656 -379.590046) (xy 436.607647 -379.527879) (xy 436.619556 -379.466732)
			(xy 436.639185 -379.407611) (xy 436.666214 -379.351485) (xy 436.700198 -379.299276) (xy 436.74058 -379.251841)
			(xy 436.786696 -379.20996) (xy 436.837788 -379.17432) (xy 436.893019 -379.145506) (xy 436.951481 -379.123992)
			(xy 437.012215 -379.11013) (xy 437.074222 -379.104148) (xy 437.136485 -379.106144) (xy 437.197982 -379.116087)
			(xy 437.257703 -379.133811) (xy 437.314666 -379.159028) (xy 437.367937 -379.191321) (xy 437.416642 -379.230161)
			(xy 437.459979 -379.274911) (xy 437.497239 -379.324835) (xy 437.527808 -379.379114) (xy 437.532275 -379.390148)
			(xy 438.803804 -379.390148) (xy 438.807795 -379.327981) (xy 438.819704 -379.266834) (xy 438.839333 -379.207713)
			(xy 438.866362 -379.151587) (xy 438.900346 -379.099378) (xy 438.940728 -379.051943) (xy 438.986844 -379.010062)
			(xy 439.037936 -378.974422) (xy 439.093167 -378.945608) (xy 439.151629 -378.924094) (xy 439.212363 -378.910232)
			(xy 439.27437 -378.90425) (xy 439.336633 -378.906246) (xy 439.39813 -378.916189) (xy 439.457851 -378.933913)
			(xy 439.514814 -378.95913) (xy 439.568085 -378.991423) (xy 439.61679 -379.030263) (xy 439.660127 -379.075013)
			(xy 439.697387 -379.124937) (xy 439.727956 -379.179216) (xy 439.751334 -379.236959) (xy 439.767135 -379.297217)
			(xy 439.775101 -379.359) (xy 439.7756 -379.390148) (xy 439.775101 -379.421296) (xy 439.767135 -379.483079)
			(xy 439.751334 -379.543337) (xy 439.727956 -379.60108) (xy 439.697387 -379.655359) (xy 439.660127 -379.705283)
			(xy 439.61679 -379.750033) (xy 439.568085 -379.788873) (xy 439.514814 -379.821166) (xy 439.457851 -379.846383)
			(xy 439.39813 -379.864107) (xy 439.336633 -379.87405) (xy 439.27437 -379.876046) (xy 439.212363 -379.870064)
			(xy 439.151629 -379.856202) (xy 439.093167 -379.834688) (xy 439.037936 -379.805874) (xy 438.986844 -379.770234)
			(xy 438.940728 -379.728353) (xy 438.900346 -379.680918) (xy 438.866362 -379.628709) (xy 438.839333 -379.572583)
			(xy 438.819704 -379.513462) (xy 438.807795 -379.452315) (xy 438.803804 -379.390148) (xy 437.532275 -379.390148)
			(xy 437.551186 -379.436857) (xy 437.566987 -379.497115) (xy 437.574953 -379.558898) (xy 437.575452 -379.590046)
			(xy 437.574953 -379.621194) (xy 437.566987 -379.682977) (xy 437.551186 -379.743235) (xy 437.527808 -379.800978)
			(xy 437.497239 -379.855257) (xy 437.459979 -379.905181) (xy 437.416642 -379.949931) (xy 437.367937 -379.988771)
			(xy 437.314666 -380.021064) (xy 437.257703 -380.046281) (xy 437.197982 -380.064005) (xy 437.136485 -380.073948)
			(xy 437.074222 -380.075944) (xy 437.012215 -380.069962) (xy 436.951481 -380.0561) (xy 436.893019 -380.034586)
			(xy 436.837788 -380.005772) (xy 436.786696 -379.970132) (xy 436.74058 -379.928251) (xy 436.700198 -379.880816)
			(xy 436.666214 -379.828607) (xy 436.639185 -379.772481) (xy 436.619556 -379.71336) (xy 436.607647 -379.652213)
			(xy 436.603656 -379.590046) (xy 435.331993 -379.590046) (xy 435.323051 -379.610961) (xy 435.306724 -379.639322)
			(xy 435.303403 -379.645344) (xy 435.299801 -379.65861) (xy 435.299612 -379.665484) (xy 435.299612 -380.414784)
			(xy 435.299809 -380.421657) (xy 435.303414 -380.43492) (xy 435.306724 -380.440946) (xy 435.323064 -380.469298)
			(xy 435.348782 -380.529471) (xy 435.36619 -380.592551) (xy 435.374972 -380.657398) (xy 435.374971 -380.69012)
			(xy 438.803804 -380.69012) (xy 438.807795 -380.627953) (xy 438.819704 -380.566806) (xy 438.839333 -380.507685)
			(xy 438.866362 -380.451559) (xy 438.900346 -380.39935) (xy 438.940728 -380.351915) (xy 438.986844 -380.310034)
			(xy 439.037936 -380.274394) (xy 439.093167 -380.24558) (xy 439.151629 -380.224066) (xy 439.212363 -380.210204)
			(xy 439.27437 -380.204222) (xy 439.336633 -380.206218) (xy 439.39813 -380.216161) (xy 439.457851 -380.233885)
			(xy 439.514814 -380.259102) (xy 439.568085 -380.291395) (xy 439.61679 -380.330235) (xy 439.660127 -380.374985)
			(xy 439.697387 -380.424909) (xy 439.727956 -380.479188) (xy 439.751334 -380.536931) (xy 439.767135 -380.597189)
			(xy 439.775101 -380.658972) (xy 439.7756 -380.69012) (xy 439.775101 -380.721268) (xy 439.767135 -380.783051)
			(xy 439.751334 -380.843309) (xy 439.727956 -380.901052) (xy 439.697387 -380.955331) (xy 439.660127 -381.005255)
			(xy 439.61679 -381.050005) (xy 439.568085 -381.088845) (xy 439.514814 -381.121138) (xy 439.457851 -381.146355)
			(xy 439.39813 -381.164079) (xy 439.336633 -381.174022) (xy 439.27437 -381.176018) (xy 439.212363 -381.170036)
			(xy 439.151629 -381.156174) (xy 439.093167 -381.13466) (xy 439.037936 -381.105846) (xy 438.986844 -381.070206)
			(xy 438.940728 -381.028325) (xy 438.900346 -380.98089) (xy 438.866362 -380.928681) (xy 438.839333 -380.872555)
			(xy 438.819704 -380.813434) (xy 438.807795 -380.752287) (xy 438.803804 -380.69012) (xy 435.374971 -380.69012)
			(xy 435.37497 -380.722836) (xy 435.366183 -380.787682) (xy 435.348771 -380.850762) (xy 435.323049 -380.910933)
			(xy 435.306724 -380.939294) (xy 435.303413 -380.945321) (xy 435.299805 -380.958583) (xy 435.299612 -380.965456)
			(xy 435.299612 -381.251206) (xy 435.29924 -381.261384) (xy 435.291444 -381.280189) (xy 435.277041 -381.294575)
			(xy 435.258229 -381.302351) (xy 435.24805 -381.302768) (xy 434.53177 -381.302768) (xy 434.521611 -381.302291)
			(xy 434.502842 -381.294508) (xy 434.488478 -381.280138) (xy 434.480704 -381.261365) (xy 434.480208 -381.251206)
			(xy 434.480208 -380.965456) (xy 434.479993 -380.958584) (xy 434.4764 -380.945322) (xy 434.473096 -380.939294)
			(xy 434.456792 -380.910923) (xy 434.431075 -380.850754) (xy 434.413667 -380.787677) (xy 434.404882 -380.722835)
			(xy 434.40488 -380.6574) (xy 430.974949 -380.6574) (xy 430.975516 -380.69012) (xy 430.974935 -380.722849)
			(xy 430.966083 -380.787707) (xy 430.948597 -380.850787) (xy 430.922794 -380.910945) (xy 430.906428 -380.939294)
			(xy 430.903117 -380.945321) (xy 430.899509 -380.958583) (xy 430.899316 -380.965456) (xy 430.899316 -381.251206)
			(xy 430.898877 -381.261338) (xy 430.891139 -381.280068) (xy 430.876838 -381.294426) (xy 430.858138 -381.302237)
			(xy 430.848008 -381.302768) (xy 430.131728 -381.302768) (xy 430.121572 -381.302355) (xy 430.102814 -381.294563)
			(xy 430.088488 -381.280163) (xy 430.080793 -381.261364) (xy 430.08042 -381.251206) (xy 430.08042 -380.965456)
			(xy 430.080204 -380.958585) (xy 430.076612 -380.945322) (xy 430.073308 -380.939294) (xy 430.056941 -380.910946)
			(xy 430.031139 -380.850786) (xy 430.01365 -380.787706) (xy 430.00479 -380.722849) (xy 430.00422 -380.69012)
			(xy 426.574884 -380.69012) (xy 426.574883 -380.722836) (xy 426.566097 -380.787682) (xy 426.548686 -380.850762)
			(xy 426.522964 -380.910933) (xy 426.50664 -380.939294) (xy 426.503331 -380.945321) (xy 426.499721 -380.958583)
			(xy 426.499528 -380.965456) (xy 426.499528 -381.251206) (xy 426.49914 -381.261382) (xy 426.491347 -381.280184)
			(xy 426.47695 -381.294569) (xy 426.458143 -381.302348) (xy 426.447966 -381.302768) (xy 425.731686 -381.302768)
			(xy 425.721528 -381.302278) (xy 425.70276 -381.2945) (xy 425.688395 -381.280133) (xy 425.68062 -381.261364)
			(xy 425.680124 -381.251206) (xy 425.680124 -380.965456) (xy 425.679908 -380.958585) (xy 425.676316 -380.945322)
			(xy 425.673012 -380.939294) (xy 425.656708 -380.910923) (xy 425.63099 -380.850754) (xy 425.613581 -380.787677)
			(xy 425.604796 -380.722835) (xy 425.604793 -380.6574) (xy 422.174864 -380.6574) (xy 422.175432 -380.69012)
			(xy 422.174848 -380.722849) (xy 422.165997 -380.787706) (xy 422.148512 -380.850786) (xy 422.12271 -380.910945)
			(xy 422.106344 -380.939294) (xy 422.103035 -380.945321) (xy 422.099425 -380.958583) (xy 422.099232 -380.965456)
			(xy 422.099232 -381.251206) (xy 422.098777 -381.261337) (xy 422.091042 -381.280063) (xy 422.076746 -381.29442)
			(xy 422.058052 -381.302234) (xy 422.047924 -381.302768) (xy 421.331644 -381.302768) (xy 421.321489 -381.302342)
			(xy 421.302731 -381.294555) (xy 421.288405 -381.280159) (xy 421.28071 -381.261363) (xy 421.280336 -381.251206)
			(xy 421.280336 -380.965456) (xy 421.280118 -380.958585) (xy 421.276527 -380.945322) (xy 421.273224 -380.939294)
			(xy 421.256858 -380.910945) (xy 421.231056 -380.850785) (xy 421.213566 -380.787706) (xy 421.204706 -380.722849)
			(xy 421.204136 -380.69012) (xy 396.865094 -380.69012) (xy 396.865094 -381.50292) (xy 403.816564 -381.50292)
			(xy 403.820635 -381.447298) (xy 403.832761 -381.392861) (xy 403.852684 -381.34077) (xy 403.87998 -381.292135)
			(xy 403.914066 -381.247992) (xy 403.954215 -381.209283) (xy 403.999573 -381.176832) (xy 404.049173 -381.151331)
			(xy 404.101957 -381.133324) (xy 404.1568 -381.123194) (xy 404.212534 -381.121157) (xy 404.267971 -381.127257)
			(xy 404.321928 -381.141363) (xy 404.373257 -381.163175) (xy 404.420863 -381.192229) (xy 404.463731 -381.227904)
			(xy 404.500948 -381.269441) (xy 404.531721 -381.315954) (xy 404.555393 -381.366451) (xy 404.571461 -381.419858)
			(xy 404.579581 -381.475034) (xy 404.58009 -381.50292) (xy 404.579581 -381.530806) (xy 404.571461 -381.585982)
			(xy 404.555393 -381.639389) (xy 404.531721 -381.689886) (xy 404.500948 -381.736399) (xy 404.463731 -381.777936)
			(xy 404.420863 -381.813611) (xy 404.373257 -381.842665) (xy 404.321928 -381.864477) (xy 404.267971 -381.878583)
			(xy 404.212534 -381.884683) (xy 404.1568 -381.882646) (xy 404.101957 -381.872516) (xy 404.049173 -381.854509)
			(xy 403.999573 -381.829008) (xy 403.954215 -381.796557) (xy 403.914066 -381.757848) (xy 403.87998 -381.713705)
			(xy 403.852684 -381.66507) (xy 403.832761 -381.612979) (xy 403.820635 -381.558542) (xy 403.816564 -381.50292)
			(xy 396.865094 -381.50292) (xy 396.865094 -382.524) (xy 408.176982 -382.524) (xy 408.181053 -382.468378)
			(xy 408.193179 -382.413941) (xy 408.213102 -382.36185) (xy 408.240398 -382.313215) (xy 408.274484 -382.269072)
			(xy 408.314633 -382.230363) (xy 408.359991 -382.197912) (xy 408.409591 -382.172411) (xy 408.462375 -382.154404)
			(xy 408.517218 -382.144274) (xy 408.572952 -382.142237) (xy 408.628389 -382.148337) (xy 408.682346 -382.162443)
			(xy 408.733675 -382.184255) (xy 408.781281 -382.213309) (xy 408.792577 -382.22271) (xy 419.004834 -382.22271)
			(xy 419.004835 -382.157272) (xy 419.01362 -382.092427) (xy 419.031031 -382.029348) (xy 419.056752 -381.969177)
			(xy 419.073076 -381.940816) (xy 419.076383 -381.934788) (xy 419.079994 -381.921527) (xy 419.080188 -381.914654)
			(xy 419.080188 -381.628904) (xy 419.080625 -381.618752) (xy 419.088417 -381.600002) (xy 419.102809 -381.585679)
			(xy 419.121596 -381.577977) (xy 419.13175 -381.577596) (xy 419.84803 -381.577596) (xy 419.858153 -381.578101)
			(xy 419.876867 -381.58583) (xy 419.89122 -381.60011) (xy 419.899046 -381.618783) (xy 419.899592 -381.628904)
			(xy 419.899592 -381.914654) (xy 419.899803 -381.921526) (xy 419.903398 -381.934789) (xy 419.906704 -381.940816)
			(xy 419.923016 -381.969182) (xy 419.948733 -382.029353) (xy 419.96614 -382.09243) (xy 419.974924 -382.157274)
			(xy 419.974925 -382.222709) (xy 419.966143 -382.287553) (xy 419.948738 -382.350631) (xy 419.923024 -382.410802)
			(xy 419.906704 -382.439164) (xy 419.903402 -382.445195) (xy 419.899788 -382.458454) (xy 419.899592 -382.465326)
			(xy 419.899592 -383.21488) (xy 419.899792 -383.221753) (xy 419.903395 -383.235015) (xy 419.906704 -383.241042)
			(xy 419.923038 -383.269396) (xy 419.948753 -383.32957) (xy 419.966158 -383.39265) (xy 419.974939 -383.457495)
			(xy 419.974937 -383.522932) (xy 419.966152 -383.587777) (xy 419.948743 -383.650856) (xy 419.923026 -383.711028)
			(xy 419.906704 -383.73939) (xy 419.903393 -383.745417) (xy 419.899785 -383.758679) (xy 419.899592 -383.765552)
			(xy 419.899592 -384.051556) (xy 419.899142 -384.061708) (xy 419.89136 -384.080461) (xy 419.876971 -384.094786)
			(xy 419.858184 -384.102486) (xy 419.84803 -384.102864) (xy 419.13175 -384.102864) (xy 419.121627 -384.102333)
			(xy 419.102908 -384.094622) (xy 419.08855 -384.080349) (xy 419.080728 -384.061676) (xy 419.080188 -384.051556)
			(xy 419.080188 -383.765552) (xy 419.079978 -383.75868) (xy 419.076382 -383.745417) (xy 419.073076 -383.73939)
			(xy 419.056766 -383.711022) (xy 419.031045 -383.650853) (xy 419.013634 -383.587775) (xy 419.004848 -383.522932)
			(xy 419.004847 -383.457496) (xy 419.013629 -383.392652) (xy 419.031036 -383.329573) (xy 419.056754 -383.269403)
			(xy 419.073076 -383.241042) (xy 419.076374 -383.235009) (xy 419.079991 -383.221752) (xy 419.080188 -383.21488)
			(xy 419.080188 -382.465326) (xy 419.079987 -382.458453) (xy 419.076385 -382.445191) (xy 419.073076 -382.439164)
			(xy 419.056744 -382.410808) (xy 419.031025 -382.350636) (xy 419.013617 -382.287556) (xy 419.004834 -382.22271)
			(xy 408.792577 -382.22271) (xy 408.824149 -382.248984) (xy 408.861366 -382.290521) (xy 408.892139 -382.337034)
			(xy 408.915811 -382.387531) (xy 408.931879 -382.440938) (xy 408.939999 -382.496114) (xy 408.940508 -382.524)
			(xy 408.939999 -382.551886) (xy 408.931879 -382.607062) (xy 408.915811 -382.660469) (xy 408.892139 -382.710966)
			(xy 408.861366 -382.757479) (xy 408.824149 -382.799016) (xy 408.781281 -382.834691) (xy 408.733675 -382.863745)
			(xy 408.682346 -382.885557) (xy 408.628389 -382.899663) (xy 408.572952 -382.905763) (xy 408.517218 -382.903726)
			(xy 408.462375 -382.893596) (xy 408.409591 -382.875589) (xy 408.359991 -382.850088) (xy 408.314633 -382.817637)
			(xy 408.274484 -382.778928) (xy 408.240398 -382.734785) (xy 408.213102 -382.68615) (xy 408.193179 -382.634059)
			(xy 408.181053 -382.579622) (xy 408.176982 -382.524) (xy 396.865094 -382.524) (xy 396.865094 -384.06705)
			(xy 403.966932 -384.06705) (xy 403.971003 -384.011428) (xy 403.983129 -383.956991) (xy 404.003052 -383.9049)
			(xy 404.030348 -383.856265) (xy 404.064434 -383.812122) (xy 404.104583 -383.773413) (xy 404.149941 -383.740962)
			(xy 404.199541 -383.715461) (xy 404.252325 -383.697454) (xy 404.307168 -383.687324) (xy 404.362902 -383.685287)
			(xy 404.418339 -383.691387) (xy 404.472296 -383.705493) (xy 404.523625 -383.727305) (xy 404.571231 -383.756359)
			(xy 404.614099 -383.792034) (xy 404.651316 -383.833571) (xy 404.682089 -383.880084) (xy 404.705761 -383.930581)
			(xy 404.721829 -383.983988) (xy 404.729949 -384.039164) (xy 404.730458 -384.06705) (xy 404.729949 -384.094936)
			(xy 404.721829 -384.150112) (xy 404.705761 -384.203519) (xy 404.682089 -384.254016) (xy 404.651316 -384.300529)
			(xy 404.614099 -384.342066) (xy 404.571231 -384.377741) (xy 404.523625 -384.406795) (xy 404.472296 -384.428607)
			(xy 404.418339 -384.442713) (xy 404.362902 -384.448813) (xy 404.307168 -384.446776) (xy 404.252325 -384.436646)
			(xy 404.199541 -384.418639) (xy 404.149941 -384.393138) (xy 404.104583 -384.360687) (xy 404.064434 -384.321978)
			(xy 404.030348 -384.277835) (xy 404.003052 -384.2292) (xy 403.983129 -384.177109) (xy 403.971003 -384.122672)
			(xy 403.966932 -384.06705) (xy 396.865094 -384.06705) (xy 396.865094 -384.683) (xy 406.398982 -384.683)
			(xy 406.403053 -384.627378) (xy 406.415179 -384.572941) (xy 406.435102 -384.52085) (xy 406.462398 -384.472215)
			(xy 406.496484 -384.428072) (xy 406.536633 -384.389363) (xy 406.581991 -384.356912) (xy 406.631591 -384.331411)
			(xy 406.684375 -384.313404) (xy 406.739218 -384.303274) (xy 406.794952 -384.301237) (xy 406.850389 -384.307337)
			(xy 406.904346 -384.321443) (xy 406.955675 -384.343255) (xy 407.003281 -384.372309) (xy 407.046149 -384.407984)
			(xy 407.083366 -384.449521) (xy 407.114139 -384.496034) (xy 407.137811 -384.546531) (xy 407.153879 -384.599938)
			(xy 407.161999 -384.655114) (xy 407.162508 -384.683) (xy 407.161999 -384.710886) (xy 407.153879 -384.766062)
			(xy 407.14066 -384.81) (xy 408.176982 -384.81) (xy 408.181053 -384.754378) (xy 408.193179 -384.699941)
			(xy 408.213102 -384.64785) (xy 408.240398 -384.599215) (xy 408.274484 -384.555072) (xy 408.314633 -384.516363)
			(xy 408.359991 -384.483912) (xy 408.409591 -384.458411) (xy 408.462375 -384.440404) (xy 408.517218 -384.430274)
			(xy 408.572952 -384.428237) (xy 408.628389 -384.434337) (xy 408.682346 -384.448443) (xy 408.733675 -384.470255)
			(xy 408.781281 -384.499309) (xy 408.824149 -384.534984) (xy 408.861366 -384.576521) (xy 408.870308 -384.590036)
			(xy 421.204136 -384.590036) (xy 421.204704 -384.557307) (xy 421.213561 -384.492449) (xy 421.23105 -384.429369)
			(xy 421.256856 -384.36921) (xy 421.273224 -384.340862) (xy 421.276554 -384.334845) (xy 421.28015 -384.321575)
			(xy 421.280336 -384.3147) (xy 421.280336 -383.5654) (xy 421.28014 -383.558527) (xy 421.276534 -383.545265)
			(xy 421.273224 -383.539238) (xy 421.256876 -383.510879) (xy 421.231069 -383.450723) (xy 421.213575 -383.387647)
			(xy 421.204709 -383.322792) (xy 421.204136 -383.290064) (xy 421.204717 -383.257335) (xy 421.213569 -383.192478)
			(xy 421.231055 -383.129398) (xy 421.256858 -383.069239) (xy 421.273224 -383.04089) (xy 421.276544 -383.034868)
			(xy 421.280146 -383.021602) (xy 421.280336 -383.014728) (xy 421.280336 -382.728724) (xy 421.280736 -382.718599)
			(xy 421.288483 -382.699889) (xy 421.302805 -382.685572) (xy 421.321518 -382.677832) (xy 421.331644 -382.677416)
			(xy 422.047924 -382.677416) (xy 422.058036 -382.677866) (xy 422.076718 -382.685614) (xy 422.091013 -382.699922)
			(xy 422.098744 -382.718611) (xy 422.099232 -382.728724) (xy 422.099232 -383.014728) (xy 422.099409 -383.021602)
			(xy 422.103027 -383.034865) (xy 422.106344 -383.04089) (xy 422.1227 -383.069244) (xy 422.148506 -383.129402)
			(xy 422.165998 -383.19248) (xy 422.174861 -383.257335) (xy 422.175432 -383.290064) (xy 422.174868 -383.322794)
			(xy 422.166011 -383.387652) (xy 422.14852 -383.450732) (xy 422.131582 -383.490216) (xy 423.404284 -383.490216)
			(xy 423.404836 -383.457486) (xy 423.413696 -383.392627) (xy 423.431191 -383.329547) (xy 423.457002 -383.26939)
			(xy 423.473372 -383.241042) (xy 423.47667 -383.235009) (xy 423.480287 -383.221752) (xy 423.480484 -383.21488)
			(xy 423.480484 -382.465326) (xy 423.480284 -382.458453) (xy 423.476681 -382.445191) (xy 423.473372 -382.439164)
			(xy 423.456989 -382.410824) (xy 423.431192 -382.350661) (xy 423.413708 -382.287579) (xy 423.404852 -382.22272)
			(xy 423.404284 -382.18999) (xy 423.40487 -382.157261) (xy 423.41372 -382.092404) (xy 423.431205 -382.029324)
			(xy 423.457006 -381.969165) (xy 423.473372 -381.940816) (xy 423.476679 -381.934788) (xy 423.48029 -381.921527)
			(xy 423.480484 -381.914654) (xy 423.480484 -381.628904) (xy 423.480988 -381.618798) (xy 423.488721 -381.600122)
			(xy 423.503012 -381.585828) (xy 423.521686 -381.57809) (xy 423.531792 -381.577596) (xy 424.248072 -381.577596)
			(xy 424.258192 -381.578039) (xy 424.276895 -381.585777) (xy 424.29121 -381.600085) (xy 424.298957 -381.618784)
			(xy 424.29938 -381.628904) (xy 424.29938 -381.914654) (xy 424.299592 -381.921526) (xy 424.303187 -381.934788)
			(xy 424.306492 -381.940816) (xy 424.322863 -381.969162) (xy 424.348664 -382.029323) (xy 424.366152 -382.092403)
			(xy 424.375011 -382.157261) (xy 424.37558 -382.18999) (xy 424.375035 -382.22271) (xy 427.80492 -382.22271)
			(xy 427.804921 -382.157273) (xy 427.813706 -382.092427) (xy 427.831116 -382.029348) (xy 427.856836 -381.969177)
			(xy 427.87316 -381.940816) (xy 427.876466 -381.934787) (xy 427.880077 -381.921527) (xy 427.880272 -381.914654)
			(xy 427.880272 -381.628904) (xy 427.880724 -381.618754) (xy 427.888513 -381.600007) (xy 427.9029 -381.585684)
			(xy 427.921682 -381.577979) (xy 427.931834 -381.577596) (xy 428.648114 -381.577596) (xy 428.658236 -381.578114)
			(xy 428.676949 -381.585838) (xy 428.691303 -381.600114) (xy 428.69913 -381.618785) (xy 428.699676 -381.628904)
			(xy 428.699676 -381.914654) (xy 428.699888 -381.921526) (xy 428.703483 -381.934788) (xy 428.706788 -381.940816)
			(xy 428.723101 -381.969182) (xy 428.748818 -382.029353) (xy 428.766226 -382.09243) (xy 428.77501 -382.157274)
			(xy 428.775011 -382.222709) (xy 428.775011 -382.22271) (xy 432.20471 -382.22271) (xy 432.204711 -382.157273)
			(xy 432.213496 -382.092428) (xy 432.230905 -382.029348) (xy 432.256625 -381.969177) (xy 432.272948 -381.940816)
			(xy 432.276253 -381.934786) (xy 432.279865 -381.921527) (xy 432.28006 -381.914654) (xy 432.28006 -381.628904)
			(xy 432.280524 -381.618755) (xy 432.288311 -381.600011) (xy 432.302694 -381.585689) (xy 432.321471 -381.577981)
			(xy 432.331622 -381.577596) (xy 433.047902 -381.577596) (xy 433.058023 -381.578124) (xy 433.076736 -381.585844)
			(xy 433.091091 -381.600117) (xy 433.098918 -381.618786) (xy 433.099464 -381.628904) (xy 433.099464 -381.914654)
			(xy 433.099678 -381.921526) (xy 433.103272 -381.934788) (xy 433.106576 -381.940816) (xy 433.122889 -381.969182)
			(xy 433.148607 -382.029352) (xy 433.166015 -382.09243) (xy 433.1748 -382.157274) (xy 433.1748 -382.18999)
			(xy 436.603656 -382.18999) (xy 436.607647 -382.127823) (xy 436.619556 -382.066676) (xy 436.639185 -382.007555)
			(xy 436.666214 -381.951429) (xy 436.700198 -381.89922) (xy 436.74058 -381.851785) (xy 436.786696 -381.809904)
			(xy 436.837788 -381.774264) (xy 436.893019 -381.74545) (xy 436.951481 -381.723936) (xy 437.012215 -381.710074)
			(xy 437.074222 -381.704092) (xy 437.136485 -381.706088) (xy 437.197982 -381.716031) (xy 437.257703 -381.733755)
			(xy 437.314666 -381.758972) (xy 437.367937 -381.791265) (xy 437.416642 -381.830105) (xy 437.459979 -381.874855)
			(xy 437.497239 -381.924779) (xy 437.527808 -381.979058) (xy 437.551186 -382.036801) (xy 437.566987 -382.097059)
			(xy 437.574953 -382.158842) (xy 437.575452 -382.18999) (xy 437.574953 -382.221138) (xy 437.566987 -382.282921)
			(xy 437.551186 -382.343179) (xy 437.527808 -382.400922) (xy 437.497239 -382.455201) (xy 437.459979 -382.505125)
			(xy 437.416642 -382.549875) (xy 437.367937 -382.588715) (xy 437.314666 -382.621008) (xy 437.257703 -382.646225)
			(xy 437.197982 -382.663949) (xy 437.136485 -382.673892) (xy 437.074222 -382.675888) (xy 437.012215 -382.669906)
			(xy 436.951481 -382.656044) (xy 436.893019 -382.63453) (xy 436.837788 -382.605716) (xy 436.786696 -382.570076)
			(xy 436.74058 -382.528195) (xy 436.700198 -382.48076) (xy 436.666214 -382.428551) (xy 436.639185 -382.372425)
			(xy 436.619556 -382.313304) (xy 436.607647 -382.252157) (xy 436.603656 -382.18999) (xy 433.1748 -382.18999)
			(xy 433.174801 -382.222709) (xy 433.166019 -382.287553) (xy 433.148613 -382.350631) (xy 433.122897 -382.410803)
			(xy 433.106576 -382.439164) (xy 433.103272 -382.445194) (xy 433.09966 -382.458454) (xy 433.099464 -382.465326)
			(xy 433.099464 -383.21488) (xy 433.099668 -383.221752) (xy 433.103269 -383.235015) (xy 433.106576 -383.241042)
			(xy 433.122911 -383.269396) (xy 433.145729 -383.322788) (xy 434.40485 -383.322788) (xy 434.404854 -383.25735)
			(xy 434.413641 -383.192504) (xy 434.431053 -383.129424) (xy 434.456773 -383.069252) (xy 434.473096 -383.04089)
			(xy 434.476414 -383.034867) (xy 434.480018 -383.021602) (xy 434.480208 -383.014728) (xy 434.480208 -382.728724)
			(xy 434.480641 -382.71857) (xy 434.48843 -382.699817) (xy 434.502824 -382.685492) (xy 434.521614 -382.677793)
			(xy 434.53177 -382.677416) (xy 435.24805 -382.677416) (xy 435.258171 -382.677967) (xy 435.276886 -382.685674)
			(xy 435.291243 -382.69994) (xy 435.299068 -382.718607) (xy 435.299612 -382.728724) (xy 435.299612 -383.014728)
			(xy 435.299792 -383.021602) (xy 435.303408 -383.034865) (xy 435.306724 -383.04089) (xy 435.323017 -383.069268)
			(xy 435.348739 -383.129435) (xy 435.366152 -383.19251) (xy 435.37494 -383.257352) (xy 435.374944 -383.322786)
			(xy 435.366165 -383.387629) (xy 435.34876 -383.450707) (xy 435.331875 -383.490216) (xy 436.603656 -383.490216)
			(xy 436.607647 -383.428049) (xy 436.619556 -383.366902) (xy 436.639185 -383.307781) (xy 436.666214 -383.251655)
			(xy 436.700198 -383.199446) (xy 436.74058 -383.152011) (xy 436.786696 -383.11013) (xy 436.837788 -383.07449)
			(xy 436.893019 -383.045676) (xy 436.951481 -383.024162) (xy 437.012215 -383.0103) (xy 437.074222 -383.004318)
			(xy 437.136485 -383.006314) (xy 437.197982 -383.016257) (xy 437.257703 -383.033981) (xy 437.314666 -383.059198)
			(xy 437.367937 -383.091491) (xy 437.416642 -383.130331) (xy 437.459979 -383.175081) (xy 437.497239 -383.225005)
			(xy 437.527808 -383.279284) (xy 437.532172 -383.290064) (xy 438.803804 -383.290064) (xy 438.807795 -383.227897)
			(xy 438.819704 -383.16675) (xy 438.839333 -383.107629) (xy 438.866362 -383.051503) (xy 438.900346 -382.999294)
			(xy 438.940728 -382.951859) (xy 438.986844 -382.909978) (xy 439.037936 -382.874338) (xy 439.093167 -382.845524)
			(xy 439.151629 -382.82401) (xy 439.212363 -382.810148) (xy 439.27437 -382.804166) (xy 439.336633 -382.806162)
			(xy 439.39813 -382.816105) (xy 439.457851 -382.833829) (xy 439.514814 -382.859046) (xy 439.568085 -382.891339)
			(xy 439.61679 -382.930179) (xy 439.660127 -382.974929) (xy 439.697387 -383.024853) (xy 439.727956 -383.079132)
			(xy 439.751334 -383.136875) (xy 439.767135 -383.197133) (xy 439.775101 -383.258916) (xy 439.7756 -383.290064)
			(xy 439.775101 -383.321212) (xy 439.767135 -383.382995) (xy 439.751334 -383.443253) (xy 439.727956 -383.500996)
			(xy 439.697387 -383.555275) (xy 439.660127 -383.605199) (xy 439.61679 -383.649949) (xy 439.568085 -383.688789)
			(xy 439.514814 -383.721082) (xy 439.457851 -383.746299) (xy 439.39813 -383.764023) (xy 439.336633 -383.773966)
			(xy 439.27437 -383.775962) (xy 439.212363 -383.76998) (xy 439.151629 -383.756118) (xy 439.093167 -383.734604)
			(xy 439.037936 -383.70579) (xy 438.986844 -383.67015) (xy 438.940728 -383.628269) (xy 438.900346 -383.580834)
			(xy 438.866362 -383.528625) (xy 438.839333 -383.472499) (xy 438.819704 -383.413378) (xy 438.807795 -383.352231)
			(xy 438.803804 -383.290064) (xy 437.532172 -383.290064) (xy 437.551186 -383.337027) (xy 437.566987 -383.397285)
			(xy 437.574953 -383.459068) (xy 437.575452 -383.490216) (xy 437.574953 -383.521364) (xy 437.566987 -383.583147)
			(xy 437.551186 -383.643405) (xy 437.527808 -383.701148) (xy 437.497239 -383.755427) (xy 437.459979 -383.805351)
			(xy 437.416642 -383.850101) (xy 437.367937 -383.888941) (xy 437.314666 -383.921234) (xy 437.257703 -383.946451)
			(xy 437.197982 -383.964175) (xy 437.136485 -383.974118) (xy 437.074222 -383.976114) (xy 437.012215 -383.970132)
			(xy 436.951481 -383.95627) (xy 436.893019 -383.934756) (xy 436.837788 -383.905942) (xy 436.786696 -383.870302)
			(xy 436.74058 -383.828421) (xy 436.700198 -383.780986) (xy 436.666214 -383.728777) (xy 436.639185 -383.672651)
			(xy 436.619556 -383.61353) (xy 436.607647 -383.552383) (xy 436.603656 -383.490216) (xy 435.331875 -383.490216)
			(xy 435.323045 -383.510877) (xy 435.306724 -383.539238) (xy 435.303397 -383.545257) (xy 435.299799 -383.558525)
			(xy 435.299612 -383.5654) (xy 435.299612 -384.3147) (xy 435.299803 -384.321573) (xy 435.303412 -384.334836)
			(xy 435.306724 -384.340862) (xy 435.323078 -384.369206) (xy 435.348795 -384.429381) (xy 435.366201 -384.492463)
			(xy 435.374981 -384.557311) (xy 435.374979 -384.590036) (xy 438.803804 -384.590036) (xy 438.807795 -384.527869)
			(xy 438.819704 -384.466722) (xy 438.839333 -384.407601) (xy 438.866362 -384.351475) (xy 438.900346 -384.299266)
			(xy 438.940728 -384.251831) (xy 438.986844 -384.20995) (xy 439.037936 -384.17431) (xy 439.093167 -384.145496)
			(xy 439.151629 -384.123982) (xy 439.212363 -384.11012) (xy 439.27437 -384.104138) (xy 439.336633 -384.106134)
			(xy 439.39813 -384.116077) (xy 439.457851 -384.133801) (xy 439.514814 -384.159018) (xy 439.568085 -384.191311)
			(xy 439.61679 -384.230151) (xy 439.660127 -384.274901) (xy 439.697387 -384.324825) (xy 439.727956 -384.379104)
			(xy 439.751334 -384.436847) (xy 439.767135 -384.497105) (xy 439.775101 -384.558888) (xy 439.7756 -384.590036)
			(xy 439.775101 -384.621184) (xy 439.767135 -384.682967) (xy 439.751334 -384.743225) (xy 439.727956 -384.800968)
			(xy 439.697387 -384.855247) (xy 439.660127 -384.905171) (xy 439.61679 -384.949921) (xy 439.568085 -384.988761)
			(xy 439.514814 -385.021054) (xy 439.457851 -385.046271) (xy 439.39813 -385.063995) (xy 439.336633 -385.073938)
			(xy 439.27437 -385.075934) (xy 439.212363 -385.069952) (xy 439.151629 -385.05609) (xy 439.093167 -385.034576)
			(xy 439.037936 -385.005762) (xy 438.986844 -384.970122) (xy 438.940728 -384.928241) (xy 438.900346 -384.880806)
			(xy 438.866362 -384.828597) (xy 438.839333 -384.772471) (xy 438.819704 -384.71335) (xy 438.807795 -384.652203)
			(xy 438.803804 -384.590036) (xy 435.374979 -384.590036) (xy 435.374977 -384.622751) (xy 435.366188 -384.687598)
			(xy 435.348774 -384.750678) (xy 435.32305 -384.810849) (xy 435.306724 -384.83921) (xy 435.303407 -384.845234)
			(xy 435.299802 -384.858498) (xy 435.299612 -384.865372) (xy 435.299612 -385.151376) (xy 435.299159 -385.161527)
			(xy 435.291374 -385.180277) (xy 435.276987 -385.194601) (xy 435.258203 -385.202303) (xy 435.24805 -385.202684)
			(xy 434.53177 -385.202684) (xy 434.521644 -385.202199) (xy 434.502927 -385.194466) (xy 434.488573 -385.180179)
			(xy 434.48075 -385.161499) (xy 434.480208 -385.151376) (xy 434.480208 -384.865372) (xy 434.480026 -384.858498)
			(xy 434.476411 -384.845235) (xy 434.473096 -384.83921) (xy 434.456806 -384.810831) (xy 434.431087 -384.750664)
			(xy 434.413678 -384.687589) (xy 434.404891 -384.622748) (xy 434.404887 -384.557314) (xy 434.413665 -384.492472)
			(xy 434.431067 -384.429395) (xy 434.456778 -384.369224) (xy 434.473096 -384.340862) (xy 434.476424 -384.334844)
			(xy 434.480021 -384.321575) (xy 434.480208 -384.3147) (xy 434.480208 -383.5654) (xy 434.480015 -383.558527)
			(xy 434.476408 -383.545264) (xy 434.473096 -383.539238) (xy 434.456745 -383.510893) (xy 434.431032 -383.450718)
			(xy 434.413629 -383.387636) (xy 434.40485 -383.322788) (xy 433.145729 -383.322788) (xy 433.148627 -383.329569)
			(xy 433.166033 -383.392649) (xy 433.174815 -383.457495) (xy 433.174813 -383.522933) (xy 433.166027 -383.587778)
			(xy 433.148618 -383.650857) (xy 433.122899 -383.711029) (xy 433.106576 -383.73939) (xy 433.103263 -383.745415)
			(xy 433.099657 -383.758679) (xy 433.099464 -383.765552) (xy 433.099464 -384.051556) (xy 433.099042 -384.061712)
			(xy 433.091254 -384.08047) (xy 433.076856 -384.094796) (xy 433.05806 -384.102491) (xy 433.047902 -384.102864)
			(xy 432.331622 -384.102864) (xy 432.321497 -384.102356) (xy 432.302777 -384.094636) (xy 432.28842 -384.080356)
			(xy 432.2806 -384.061678) (xy 432.28006 -384.051556) (xy 432.28006 -383.765552) (xy 432.279853 -383.75868)
			(xy 432.276256 -383.745417) (xy 432.272948 -383.73939) (xy 432.256639 -383.711021) (xy 432.23092 -383.650852)
			(xy 432.21351 -383.587775) (xy 432.204724 -383.522932) (xy 432.204723 -383.457496) (xy 432.213504 -383.392652)
			(xy 432.230911 -383.329574) (xy 432.256627 -383.269403) (xy 432.272948 -383.241042) (xy 432.276244 -383.235008)
			(xy 432.279862 -383.221752) (xy 432.28006 -383.21488) (xy 432.28006 -382.465326) (xy 432.279863 -382.458453)
			(xy 432.276259 -382.44519) (xy 432.272948 -382.439164) (xy 432.256617 -382.410808) (xy 432.2309 -382.350635)
			(xy 432.213492 -382.287556) (xy 432.20471 -382.22271) (xy 428.775011 -382.22271) (xy 428.766229 -382.287553)
			(xy 428.748824 -382.350631) (xy 428.723109 -382.410802) (xy 428.706788 -382.439164) (xy 428.703485 -382.445194)
			(xy 428.699872 -382.458454) (xy 428.699676 -382.465326) (xy 428.699676 -383.21488) (xy 428.699879 -383.221752)
			(xy 428.70348 -383.235015) (xy 428.706788 -383.241042) (xy 428.723123 -383.269396) (xy 428.748838 -383.329569)
			(xy 428.766243 -383.392649) (xy 428.775025 -383.457495) (xy 428.775023 -383.522932) (xy 428.766238 -383.587778)
			(xy 428.748829 -383.650857) (xy 428.72311 -383.711028) (xy 428.706788 -383.73939) (xy 428.703476 -383.745416)
			(xy 428.699869 -383.758679) (xy 428.699676 -383.765552) (xy 428.699676 -384.051556) (xy 428.699242 -384.06171)
			(xy 428.691456 -384.080466) (xy 428.677063 -384.094792) (xy 428.65827 -384.102489) (xy 428.648114 -384.102864)
			(xy 427.931834 -384.102864) (xy 427.92171 -384.102345) (xy 427.90299 -384.09463) (xy 427.888633 -384.080353)
			(xy 427.880812 -384.061677) (xy 427.880272 -384.051556) (xy 427.880272 -383.765552) (xy 427.880064 -383.75868)
			(xy 427.876467 -383.745417) (xy 427.87316 -383.73939) (xy 427.856851 -383.711021) (xy 427.831131 -383.650852)
			(xy 427.81372 -383.587775) (xy 427.804935 -383.522932) (xy 427.804933 -383.457496) (xy 427.813715 -383.392652)
			(xy 427.831122 -383.329574) (xy 427.856838 -383.269403) (xy 427.87316 -383.241042) (xy 427.876457 -383.235008)
			(xy 427.880074 -383.221752) (xy 427.880272 -383.21488) (xy 427.880272 -382.465326) (xy 427.880074 -382.458453)
			(xy 427.87647 -382.44519) (xy 427.87316 -382.439164) (xy 427.856829 -382.410808) (xy 427.831111 -382.350636)
			(xy 427.813703 -382.287556) (xy 427.80492 -382.22271) (xy 424.375035 -382.22271) (xy 424.375035 -382.22272)
			(xy 424.366173 -382.287579) (xy 424.348677 -382.35066) (xy 424.322863 -382.410817) (xy 424.306492 -382.439164)
			(xy 424.303189 -382.445195) (xy 424.299576 -382.458454) (xy 424.29938 -382.465326) (xy 424.29938 -383.21488)
			(xy 424.299582 -383.221752) (xy 424.303184 -383.235015) (xy 424.306492 -383.241042) (xy 424.322874 -383.269382)
			(xy 424.345775 -383.322789) (xy 425.604764 -383.322789) (xy 425.604768 -383.25735) (xy 425.613555 -383.192504)
			(xy 425.630967 -383.129424) (xy 425.656688 -383.069252) (xy 425.673012 -383.04089) (xy 425.676331 -383.034868)
			(xy 425.679934 -383.021602) (xy 425.680124 -383.014728) (xy 425.680124 -382.728724) (xy 425.680542 -382.718568)
			(xy 425.688334 -382.699812) (xy 425.702732 -382.685487) (xy 425.721528 -382.67779) (xy 425.731686 -382.677416)
			(xy 426.447966 -382.677416) (xy 426.458088 -382.677954) (xy 426.476803 -382.685666) (xy 426.49116 -382.699937)
			(xy 426.498984 -382.718606) (xy 426.499528 -382.728724) (xy 426.499528 -383.014728) (xy 426.499705 -383.021602)
			(xy 426.503323 -383.034865) (xy 426.50664 -383.04089) (xy 426.522932 -383.069268) (xy 426.548654 -383.129435)
			(xy 426.566066 -383.19251) (xy 426.574854 -383.257352) (xy 426.574858 -383.322786) (xy 426.566079 -383.387629)
			(xy 426.548674 -383.450707) (xy 426.52296 -383.510877) (xy 426.50664 -383.539238) (xy 426.503315 -383.545258)
			(xy 426.499715 -383.558525) (xy 426.499528 -383.5654) (xy 426.499528 -384.3147) (xy 426.499717 -384.321574)
			(xy 426.503327 -384.334836) (xy 426.50664 -384.340862) (xy 426.522993 -384.369206) (xy 426.548709 -384.429381)
			(xy 426.566115 -384.492463) (xy 426.574895 -384.557311) (xy 426.574893 -384.590036) (xy 430.00422 -384.590036)
			(xy 430.004777 -384.557306) (xy 430.013635 -384.492447) (xy 430.031128 -384.429367) (xy 430.056938 -384.36921)
			(xy 430.073308 -384.340862) (xy 430.076637 -384.334844) (xy 430.080233 -384.321575) (xy 430.08042 -384.3147)
			(xy 430.08042 -383.5654) (xy 430.080226 -383.558527) (xy 430.076619 -383.545264) (xy 430.073308 -383.539238)
			(xy 430.056958 -383.51088) (xy 430.031152 -383.450724) (xy 430.013658 -383.387647) (xy 430.004793 -383.322792)
			(xy 430.00422 -383.290064) (xy 430.004789 -383.257335) (xy 430.013644 -383.192476) (xy 430.031133 -383.129396)
			(xy 430.05694 -383.069238) (xy 430.073308 -383.04089) (xy 430.076627 -383.034867) (xy 430.08023 -383.021602)
			(xy 430.08042 -383.014728) (xy 430.08042 -382.728724) (xy 430.080836 -382.718601) (xy 430.08858 -382.699894)
			(xy 430.102897 -382.685578) (xy 430.121605 -382.677835) (xy 430.131728 -382.677416) (xy 430.848008 -382.677416)
			(xy 430.858133 -382.67781) (xy 430.87684 -382.685564) (xy 430.891154 -382.699887) (xy 430.898896 -382.718599)
			(xy 430.899316 -382.728724) (xy 430.899316 -383.014728) (xy 430.899495 -383.021602) (xy 430.903112 -383.034865)
			(xy 430.906428 -383.04089) (xy 430.922792 -383.06924) (xy 430.948594 -383.129399) (xy 430.966084 -383.192479)
			(xy 430.974945 -383.257335) (xy 430.975516 -383.290064) (xy 430.974955 -383.322794) (xy 430.966097 -383.387652)
			(xy 430.948606 -383.450732) (xy 430.922797 -383.51089) (xy 430.906428 -383.539238) (xy 430.903102 -383.545257)
			(xy 430.899503 -383.558525) (xy 430.899316 -383.5654) (xy 430.899316 -384.3147) (xy 430.899506 -384.321573)
			(xy 430.903116 -384.334836) (xy 430.906428 -384.340862) (xy 430.922781 -384.369218) (xy 430.948585 -384.429375)
			(xy 430.966078 -384.492453) (xy 430.974943 -384.557308) (xy 430.975516 -384.590036) (xy 430.974942 -384.622765)
			(xy 430.966088 -384.687623) (xy 430.9486 -384.750703) (xy 430.922795 -384.810862) (xy 430.906428 -384.83921)
			(xy 430.903112 -384.845234) (xy 430.899507 -384.858498) (xy 430.899316 -384.865372) (xy 430.899316 -385.151376)
			(xy 430.898865 -385.161495) (xy 430.891128 -385.180195) (xy 430.876822 -385.19451) (xy 430.858127 -385.202259)
			(xy 430.848008 -385.202684) (xy 430.131728 -385.202684) (xy 430.121605 -385.202261) (xy 430.102899 -385.194519)
			(xy 430.088583 -385.180204) (xy 430.08084 -385.161499) (xy 430.08042 -385.151376) (xy 430.08042 -384.865372)
			(xy 430.080236 -384.858498) (xy 430.076622 -384.845236) (xy 430.073308 -384.83921) (xy 430.056947 -384.810858)
			(xy 430.031144 -384.7507) (xy 430.013653 -384.687621) (xy 430.004791 -384.622765) (xy 430.00422 -384.590036)
			(xy 426.574893 -384.590036) (xy 426.574891 -384.622751) (xy 426.566102 -384.687597) (xy 426.548689 -384.750677)
			(xy 426.522965 -384.810849) (xy 426.50664 -384.83921) (xy 426.503325 -384.845235) (xy 426.499719 -384.858498)
			(xy 426.499528 -384.865372) (xy 426.499528 -385.151376) (xy 426.499059 -385.161525) (xy 426.491277 -385.180272)
			(xy 426.476895 -385.194595) (xy 426.458117 -385.202301) (xy 426.447966 -385.202684) (xy 425.731686 -385.202684)
			(xy 425.721561 -385.202185) (xy 425.702845 -385.194457) (xy 425.68849 -385.180175) (xy 425.680667 -385.161498)
			(xy 425.680124 -385.151376) (xy 425.680124 -384.865372) (xy 425.67994 -384.858498) (xy 425.676326 -384.845236)
			(xy 425.673012 -384.83921) (xy 425.656721 -384.810832) (xy 425.631002 -384.750664) (xy 425.613592 -384.687589)
			(xy 425.604805 -384.622748) (xy 425.604801 -384.557314) (xy 425.613579 -384.492472) (xy 425.630982 -384.429394)
			(xy 425.656693 -384.369223) (xy 425.673012 -384.340862) (xy 425.676341 -384.334844) (xy 425.679937 -384.321575)
			(xy 425.680124 -384.3147) (xy 425.680124 -383.5654) (xy 425.679929 -383.558527) (xy 425.676323 -383.545264)
			(xy 425.673012 -383.539238) (xy 425.65666 -383.510893) (xy 425.630947 -383.450718) (xy 425.613543 -383.387636)
			(xy 425.604764 -383.322789) (xy 424.345775 -383.322789) (xy 424.348672 -383.329545) (xy 424.366157 -383.392627)
			(xy 424.375012 -383.457486) (xy 424.37558 -383.490216) (xy 424.375002 -383.522945) (xy 424.36615 -383.587803)
			(xy 424.348664 -383.650883) (xy 424.322859 -383.711042) (xy 424.306492 -383.73939) (xy 424.30318 -383.745416)
			(xy 424.299573 -383.758679) (xy 424.29938 -383.765552) (xy 424.29938 -384.051556) (xy 424.298947 -384.061678)
			(xy 424.29121 -384.080385) (xy 424.276898 -384.094701) (xy 424.258194 -384.102444) (xy 424.248072 -384.102864)
			(xy 423.531792 -384.102864) (xy 423.521665 -384.10249) (xy 423.502954 -384.094732) (xy 423.488639 -384.080402)
			(xy 423.4809 -384.061684) (xy 423.480484 -384.051556) (xy 423.480484 -383.765552) (xy 423.480274 -383.75868)
			(xy 423.476678 -383.745417) (xy 423.473372 -383.73939) (xy 423.457 -383.711044) (xy 423.4312 -383.650883)
			(xy 423.413713 -383.587803) (xy 423.404854 -383.522945) (xy 423.404284 -383.490216) (xy 422.131582 -383.490216)
			(xy 422.122713 -383.51089) (xy 422.106344 -383.539238) (xy 422.103019 -383.545258) (xy 422.099419 -383.558525)
			(xy 422.099232 -383.5654) (xy 422.099232 -384.3147) (xy 422.09942 -384.321574) (xy 422.103031 -384.334836)
			(xy 422.106344 -384.340862) (xy 422.122689 -384.369223) (xy 422.148497 -384.429378) (xy 422.165993 -384.492454)
			(xy 422.174859 -384.557308) (xy 422.175432 -384.590036) (xy 422.174856 -384.622765) (xy 422.166003 -384.687623)
			(xy 422.148515 -384.750703) (xy 422.122711 -384.810862) (xy 422.106344 -384.83921) (xy 422.103029 -384.845235)
			(xy 422.099423 -384.858498) (xy 422.099232 -384.865372) (xy 422.099232 -385.151376) (xy 422.098696 -385.161479)
			(xy 422.090972 -385.180151) (xy 422.076691 -385.194445) (xy 422.058027 -385.202187) (xy 422.047924 -385.202684)
			(xy 421.331644 -385.202684) (xy 421.321522 -385.202247) (xy 421.302817 -385.194511) (xy 421.2885 -385.1802)
			(xy 421.280756 -385.161497) (xy 421.280336 -385.151376) (xy 421.280336 -384.865372) (xy 421.28015 -384.858498)
			(xy 421.276537 -384.845236) (xy 421.273224 -384.83921) (xy 421.256865 -384.810857) (xy 421.231061 -384.750699)
			(xy 421.213569 -384.687621) (xy 421.204707 -384.622765) (xy 421.204136 -384.590036) (xy 408.870308 -384.590036)
			(xy 408.892139 -384.623034) (xy 408.915811 -384.673531) (xy 408.931879 -384.726938) (xy 408.939999 -384.782114)
			(xy 408.940508 -384.81) (xy 408.939999 -384.837886) (xy 408.931879 -384.893062) (xy 408.915811 -384.946469)
			(xy 408.892139 -384.996966) (xy 408.861366 -385.043479) (xy 408.824149 -385.085016) (xy 408.781281 -385.120691)
			(xy 408.733675 -385.149745) (xy 408.682346 -385.171557) (xy 408.628389 -385.185663) (xy 408.572952 -385.191763)
			(xy 408.517218 -385.189726) (xy 408.462375 -385.179596) (xy 408.409591 -385.161589) (xy 408.359991 -385.136088)
			(xy 408.314633 -385.103637) (xy 408.274484 -385.064928) (xy 408.240398 -385.020785) (xy 408.213102 -384.97215)
			(xy 408.193179 -384.920059) (xy 408.181053 -384.865622) (xy 408.176982 -384.81) (xy 407.14066 -384.81)
			(xy 407.137811 -384.819469) (xy 407.114139 -384.869966) (xy 407.083366 -384.916479) (xy 407.046149 -384.958016)
			(xy 407.003281 -384.993691) (xy 406.955675 -385.022745) (xy 406.904346 -385.044557) (xy 406.850389 -385.058663)
			(xy 406.794952 -385.064763) (xy 406.739218 -385.062726) (xy 406.684375 -385.052596) (xy 406.631591 -385.034589)
			(xy 406.581991 -385.009088) (xy 406.536633 -384.976637) (xy 406.496484 -384.937928) (xy 406.462398 -384.893785)
			(xy 406.435102 -384.84515) (xy 406.415179 -384.793059) (xy 406.403053 -384.738622) (xy 406.398982 -384.683)
			(xy 396.865094 -384.683) (xy 396.865094 -385.826) (xy 407.033982 -385.826) (xy 407.038053 -385.770378)
			(xy 407.050179 -385.715941) (xy 407.070102 -385.66385) (xy 407.097398 -385.615215) (xy 407.131484 -385.571072)
			(xy 407.171633 -385.532363) (xy 407.216991 -385.499912) (xy 407.266591 -385.474411) (xy 407.319375 -385.456404)
			(xy 407.374218 -385.446274) (xy 407.429952 -385.444237) (xy 407.485389 -385.450337) (xy 407.539346 -385.464443)
			(xy 407.590675 -385.486255) (xy 407.638281 -385.515309) (xy 407.681149 -385.550984) (xy 407.718366 -385.592521)
			(xy 407.728856 -385.608376) (xy 454.303373 -385.608376) (xy 454.303373 -385.479236) (xy 454.311323 -385.350341)
			(xy 454.327193 -385.222181) (xy 454.350922 -385.09524) (xy 454.382421 -384.970001) (xy 454.42157 -384.846938)
			(xy 454.468221 -384.726519) (xy 454.522196 -384.6092) (xy 454.583291 -384.495426) (xy 454.651274 -384.385629)
			(xy 454.725888 -384.280226) (xy 454.806849 -384.179616) (xy 454.893849 -384.084181) (xy 454.98656 -383.994282)
			(xy 455.08463 -383.910261) (xy 455.187685 -383.832437) (xy 455.295336 -383.761105) (xy 455.407175 -383.696535)
			(xy 455.522776 -383.638973) (xy 455.641701 -383.588636) (xy 455.7635 -383.545716) (xy 455.88771 -383.510375)
			(xy 456.013859 -383.482748) (xy 456.141471 -383.462939) (xy 456.27006 -383.451023) (xy 456.399138 -383.447047)
			(xy 456.528216 -383.451023) (xy 456.656805 -383.462939) (xy 456.784417 -383.482748) (xy 456.910566 -383.510375)
			(xy 457.034776 -383.545716) (xy 457.156575 -383.588636) (xy 457.2755 -383.638973) (xy 457.391101 -383.696535)
			(xy 457.50294 -383.761105) (xy 457.610591 -383.832437) (xy 457.713646 -383.910261) (xy 457.811716 -383.994282)
			(xy 457.904427 -384.084181) (xy 457.991427 -384.179616) (xy 458.072388 -384.280226) (xy 458.147002 -384.385629)
			(xy 458.214985 -384.495426) (xy 458.27608 -384.6092) (xy 458.330055 -384.726519) (xy 458.376706 -384.846938)
			(xy 458.415855 -384.970001) (xy 458.447354 -385.09524) (xy 458.471083 -385.222181) (xy 458.486953 -385.350341)
			(xy 458.494903 -385.479236) (xy 458.4954 -385.543806) (xy 458.494903 -385.608376) (xy 458.486953 -385.737271)
			(xy 458.471083 -385.865431) (xy 458.447354 -385.992372) (xy 458.415855 -386.117611) (xy 458.376706 -386.240674)
			(xy 458.330055 -386.361093) (xy 458.27608 -386.478412) (xy 458.214985 -386.592186) (xy 458.147002 -386.701983)
			(xy 458.072388 -386.807386) (xy 457.991427 -386.907996) (xy 457.904427 -387.003431) (xy 457.811716 -387.09333)
			(xy 457.713646 -387.177351) (xy 457.610591 -387.255175) (xy 457.50294 -387.326507) (xy 457.391101 -387.391077)
			(xy 457.2755 -387.448639) (xy 457.156575 -387.498976) (xy 457.034776 -387.541896) (xy 456.910566 -387.577237)
			(xy 456.784417 -387.604864) (xy 456.656805 -387.624673) (xy 456.528216 -387.636589) (xy 456.399138 -387.640566)
			(xy 456.27006 -387.636589) (xy 456.141471 -387.624673) (xy 456.013859 -387.604864) (xy 455.88771 -387.577237)
			(xy 455.7635 -387.541896) (xy 455.641701 -387.498976) (xy 455.522776 -387.448639) (xy 455.407175 -387.391077)
			(xy 455.295336 -387.326507) (xy 455.187685 -387.255175) (xy 455.08463 -387.177351) (xy 454.98656 -387.09333)
			(xy 454.893849 -387.003431) (xy 454.806849 -386.907996) (xy 454.725888 -386.807386) (xy 454.651274 -386.701983)
			(xy 454.583291 -386.592186) (xy 454.522196 -386.478412) (xy 454.468221 -386.361093) (xy 454.42157 -386.240674)
			(xy 454.382421 -386.117611) (xy 454.350922 -385.992372) (xy 454.327193 -385.865431) (xy 454.311323 -385.737271)
			(xy 454.303373 -385.608376) (xy 407.728856 -385.608376) (xy 407.749139 -385.639034) (xy 407.772811 -385.689531)
			(xy 407.788879 -385.742938) (xy 407.796999 -385.798114) (xy 407.797508 -385.826) (xy 407.796999 -385.853886)
			(xy 407.788879 -385.909062) (xy 407.772811 -385.962469) (xy 407.749139 -386.012966) (xy 407.718366 -386.059479)
			(xy 407.681149 -386.101016) (xy 407.638281 -386.136691) (xy 407.590675 -386.165745) (xy 407.539346 -386.187557)
			(xy 407.485389 -386.201663) (xy 407.429952 -386.207763) (xy 407.374218 -386.205726) (xy 407.319375 -386.195596)
			(xy 407.266591 -386.177589) (xy 407.216991 -386.152088) (xy 407.171633 -386.119637) (xy 407.131484 -386.080928)
			(xy 407.097398 -386.036785) (xy 407.070102 -385.98815) (xy 407.050179 -385.936059) (xy 407.038053 -385.881622)
			(xy 407.033982 -385.826) (xy 396.865094 -385.826) (xy 396.865094 -386.937758) (xy 403.667974 -386.937758)
			(xy 403.672045 -386.882136) (xy 403.684171 -386.827699) (xy 403.704094 -386.775608) (xy 403.73139 -386.726973)
			(xy 403.765476 -386.68283) (xy 403.805625 -386.644121) (xy 403.850983 -386.61167) (xy 403.900583 -386.586169)
			(xy 403.953367 -386.568162) (xy 404.00821 -386.558032) (xy 404.063944 -386.555995) (xy 404.119381 -386.562095)
			(xy 404.173338 -386.576201) (xy 404.224667 -386.598013) (xy 404.272273 -386.627067) (xy 404.315141 -386.662742)
			(xy 404.352358 -386.704279) (xy 404.383131 -386.750792) (xy 404.406803 -386.801289) (xy 404.422871 -386.854696)
			(xy 404.430991 -386.909872) (xy 404.431301 -386.926836) (xy 409.520642 -386.926836) (xy 409.524713 -386.871214)
			(xy 409.536839 -386.816777) (xy 409.556762 -386.764686) (xy 409.584058 -386.716051) (xy 409.618144 -386.671908)
			(xy 409.658293 -386.633199) (xy 409.703651 -386.600748) (xy 409.753251 -386.575247) (xy 409.806035 -386.55724)
			(xy 409.860878 -386.54711) (xy 409.916612 -386.545073) (xy 409.972049 -386.551173) (xy 410.026006 -386.565279)
			(xy 410.077335 -386.587091) (xy 410.124941 -386.616145) (xy 410.167809 -386.65182) (xy 410.205026 -386.693357)
			(xy 410.235799 -386.73987) (xy 410.259471 -386.790367) (xy 410.275539 -386.843774) (xy 410.283659 -386.89895)
			(xy 410.284168 -386.926836) (xy 410.283659 -386.954722) (xy 410.275539 -387.009898) (xy 410.259471 -387.063305)
			(xy 410.235799 -387.113802) (xy 410.205026 -387.160315) (xy 410.167809 -387.201852) (xy 410.124941 -387.237527)
			(xy 410.077335 -387.266581) (xy 410.026006 -387.288393) (xy 409.972049 -387.302499) (xy 409.916612 -387.308599)
			(xy 409.860878 -387.306562) (xy 409.806035 -387.296432) (xy 409.753251 -387.278425) (xy 409.703651 -387.252924)
			(xy 409.658293 -387.220473) (xy 409.618144 -387.181764) (xy 409.584058 -387.137621) (xy 409.556762 -387.088986)
			(xy 409.536839 -387.036895) (xy 409.524713 -386.982458) (xy 409.520642 -386.926836) (xy 404.431301 -386.926836)
			(xy 404.4315 -386.937758) (xy 404.430991 -386.965644) (xy 404.422871 -387.02082) (xy 404.406803 -387.074227)
			(xy 404.383131 -387.124724) (xy 404.352358 -387.171237) (xy 404.315141 -387.212774) (xy 404.272273 -387.248449)
			(xy 404.224667 -387.277503) (xy 404.173338 -387.299315) (xy 404.119381 -387.313421) (xy 404.063944 -387.319521)
			(xy 404.00821 -387.317484) (xy 403.953367 -387.307354) (xy 403.900583 -387.289347) (xy 403.850983 -387.263846)
			(xy 403.805625 -387.231395) (xy 403.765476 -387.192686) (xy 403.73139 -387.148543) (xy 403.704094 -387.099908)
			(xy 403.684171 -387.047817) (xy 403.672045 -386.99338) (xy 403.667974 -386.937758) (xy 396.865094 -386.937758)
			(xy 396.865094 -387.942836) (xy 408.392374 -387.942836) (xy 408.396445 -387.887214) (xy 408.408571 -387.832777)
			(xy 408.428494 -387.780686) (xy 408.45579 -387.732051) (xy 408.489876 -387.687908) (xy 408.530025 -387.649199)
			(xy 408.575383 -387.616748) (xy 408.624983 -387.591247) (xy 408.677767 -387.57324) (xy 408.73261 -387.56311)
			(xy 408.788344 -387.561073) (xy 408.843781 -387.567173) (xy 408.897738 -387.581279) (xy 408.949067 -387.603091)
			(xy 408.996673 -387.632145) (xy 409.039541 -387.66782) (xy 409.076758 -387.709357) (xy 409.107531 -387.75587)
			(xy 409.131203 -387.806367) (xy 409.147271 -387.859774) (xy 409.155391 -387.91495) (xy 409.1559 -387.942836)
			(xy 409.155391 -387.970722) (xy 409.147271 -388.025898) (xy 409.131203 -388.079305) (xy 409.107531 -388.129802)
			(xy 409.076758 -388.176315) (xy 409.039541 -388.217852) (xy 408.996673 -388.253527) (xy 408.949067 -388.282581)
			(xy 408.897738 -388.304393) (xy 408.843781 -388.318499) (xy 408.788344 -388.324599) (xy 408.73261 -388.322562)
			(xy 408.677767 -388.312432) (xy 408.624983 -388.294425) (xy 408.575383 -388.268924) (xy 408.530025 -388.236473)
			(xy 408.489876 -388.197764) (xy 408.45579 -388.153621) (xy 408.428494 -388.104986) (xy 408.408571 -388.052895)
			(xy 408.396445 -387.998458) (xy 408.392374 -387.942836) (xy 396.865094 -387.942836) (xy 396.865094 -388.958836)
			(xy 409.520642 -388.958836) (xy 409.524713 -388.903214) (xy 409.536839 -388.848777) (xy 409.556762 -388.796686)
			(xy 409.584058 -388.748051) (xy 409.618144 -388.703908) (xy 409.658293 -388.665199) (xy 409.703651 -388.632748)
			(xy 409.753251 -388.607247) (xy 409.806035 -388.58924) (xy 409.860878 -388.57911) (xy 409.916612 -388.577073)
			(xy 409.972049 -388.583173) (xy 410.026006 -388.597279) (xy 410.077335 -388.619091) (xy 410.124941 -388.648145)
			(xy 410.167809 -388.68382) (xy 410.205026 -388.725357) (xy 410.235799 -388.77187) (xy 410.259471 -388.822367)
			(xy 410.275539 -388.875774) (xy 410.283659 -388.93095) (xy 410.284168 -388.958836) (xy 410.283659 -388.986722)
			(xy 410.275539 -389.041898) (xy 410.259471 -389.095305) (xy 410.235799 -389.145802) (xy 410.205026 -389.192315)
			(xy 410.167809 -389.233852) (xy 410.124941 -389.269527) (xy 410.077335 -389.298581) (xy 410.026006 -389.320393)
			(xy 409.972049 -389.334499) (xy 409.916612 -389.340599) (xy 409.860878 -389.338562) (xy 409.806035 -389.328432)
			(xy 409.753251 -389.310425) (xy 409.703651 -389.284924) (xy 409.658293 -389.252473) (xy 409.618144 -389.213764)
			(xy 409.584058 -389.169621) (xy 409.556762 -389.120986) (xy 409.536839 -389.068895) (xy 409.524713 -389.014458)
			(xy 409.520642 -388.958836) (xy 396.865094 -388.958836) (xy 396.865094 -389.974836) (xy 408.392374 -389.974836)
			(xy 408.396445 -389.919214) (xy 408.408571 -389.864777) (xy 408.428494 -389.812686) (xy 408.45579 -389.764051)
			(xy 408.489876 -389.719908) (xy 408.530025 -389.681199) (xy 408.575383 -389.648748) (xy 408.624983 -389.623247)
			(xy 408.677767 -389.60524) (xy 408.73261 -389.59511) (xy 408.788344 -389.593073) (xy 408.843781 -389.599173)
			(xy 408.897738 -389.613279) (xy 408.949067 -389.635091) (xy 408.996673 -389.664145) (xy 409.039541 -389.69982)
			(xy 409.076758 -389.741357) (xy 409.107531 -389.78787) (xy 409.131203 -389.838367) (xy 409.147271 -389.891774)
			(xy 409.155391 -389.94695) (xy 409.1559 -389.974836) (xy 409.155391 -390.002722) (xy 409.147271 -390.057898)
			(xy 409.131203 -390.111305) (xy 409.107531 -390.161802) (xy 409.076758 -390.208315) (xy 409.039541 -390.249852)
			(xy 408.996673 -390.285527) (xy 408.949067 -390.314581) (xy 408.897738 -390.336393) (xy 408.843781 -390.350499)
			(xy 408.788344 -390.356599) (xy 408.73261 -390.354562) (xy 408.677767 -390.344432) (xy 408.624983 -390.326425)
			(xy 408.575383 -390.300924) (xy 408.530025 -390.268473) (xy 408.489876 -390.229764) (xy 408.45579 -390.185621)
			(xy 408.428494 -390.136986) (xy 408.408571 -390.084895) (xy 408.396445 -390.030458) (xy 408.392374 -389.974836)
			(xy 396.865094 -389.974836) (xy 396.865094 -390.990836) (xy 406.20391 -390.990836) (xy 406.207981 -390.935214)
			(xy 406.220107 -390.880777) (xy 406.24003 -390.828686) (xy 406.267326 -390.780051) (xy 406.301412 -390.735908)
			(xy 406.341561 -390.697199) (xy 406.386919 -390.664748) (xy 406.436519 -390.639247) (xy 406.489303 -390.62124)
			(xy 406.544146 -390.61111) (xy 406.59988 -390.609073) (xy 406.655317 -390.615173) (xy 406.709274 -390.629279)
			(xy 406.760603 -390.651091) (xy 406.808209 -390.680145) (xy 406.851077 -390.71582) (xy 406.888294 -390.757357)
			(xy 406.919067 -390.80387) (xy 406.942739 -390.854367) (xy 406.958807 -390.907774) (xy 406.966927 -390.96295)
			(xy 406.967436 -390.990836) (xy 406.966927 -391.018722) (xy 406.958807 -391.073898) (xy 406.942739 -391.127305)
			(xy 406.919067 -391.177802) (xy 406.888294 -391.224315) (xy 406.851077 -391.265852) (xy 406.808209 -391.301527)
			(xy 406.760603 -391.330581) (xy 406.709274 -391.352393) (xy 406.655317 -391.366499) (xy 406.59988 -391.372599)
			(xy 406.544146 -391.370562) (xy 406.489303 -391.360432) (xy 406.436519 -391.342425) (xy 406.386919 -391.316924)
			(xy 406.341561 -391.284473) (xy 406.301412 -391.245764) (xy 406.267326 -391.201621) (xy 406.24003 -391.152986)
			(xy 406.220107 -391.100895) (xy 406.207981 -391.046458) (xy 406.20391 -390.990836) (xy 396.865094 -390.990836)
			(xy 396.865094 -392.016742) (xy 405.655778 -392.016742) (xy 405.659849 -391.96112) (xy 405.671975 -391.906683)
			(xy 405.691898 -391.854592) (xy 405.719194 -391.805957) (xy 405.75328 -391.761814) (xy 405.793429 -391.723105)
			(xy 405.838787 -391.690654) (xy 405.888387 -391.665153) (xy 405.941171 -391.647146) (xy 405.996014 -391.637016)
			(xy 406.051748 -391.634979) (xy 406.107185 -391.641079) (xy 406.161142 -391.655185) (xy 406.212471 -391.676997)
			(xy 406.260077 -391.706051) (xy 406.302945 -391.741726) (xy 406.340162 -391.783263) (xy 406.370935 -391.829776)
			(xy 406.394607 -391.880273) (xy 406.410675 -391.93368) (xy 406.418795 -391.988856) (xy 406.419304 -392.016742)
			(xy 406.418795 -392.044628) (xy 406.410675 -392.099804) (xy 406.394607 -392.153211) (xy 406.370935 -392.203708)
			(xy 406.340162 -392.250221) (xy 406.302945 -392.291758) (xy 406.260077 -392.327433) (xy 406.212471 -392.356487)
			(xy 406.161142 -392.378299) (xy 406.107185 -392.392405) (xy 406.051748 -392.398505) (xy 405.996014 -392.396468)
			(xy 405.941171 -392.386338) (xy 405.888387 -392.368331) (xy 405.838787 -392.34283) (xy 405.793429 -392.310379)
			(xy 405.75328 -392.27167) (xy 405.719194 -392.227527) (xy 405.691898 -392.178892) (xy 405.671975 -392.126801)
			(xy 405.659849 -392.072364) (xy 405.655778 -392.016742) (xy 396.865094 -392.016742) (xy 396.865094 -392.549126)
			(xy 396.865521 -392.559194) (xy 396.873242 -392.577793) (xy 396.88008 -392.585194) (xy 398.479264 -394.184378)
			(xy 416.325556 -394.184378) (xy 416.329627 -394.128756) (xy 416.341753 -394.074319) (xy 416.361676 -394.022228)
			(xy 416.388972 -393.973593) (xy 416.423058 -393.92945) (xy 416.463207 -393.890741) (xy 416.508565 -393.85829)
			(xy 416.558165 -393.832789) (xy 416.610949 -393.814782) (xy 416.665792 -393.804652) (xy 416.721526 -393.802615)
			(xy 416.776963 -393.808715) (xy 416.83092 -393.822821) (xy 416.882249 -393.844633) (xy 416.929855 -393.873687)
			(xy 416.972723 -393.909362) (xy 417.00994 -393.950899) (xy 417.040713 -393.997412) (xy 417.064385 -394.047909)
			(xy 417.080453 -394.101316) (xy 417.088573 -394.156492) (xy 417.089082 -394.184378) (xy 417.088573 -394.212264)
			(xy 417.080453 -394.26744) (xy 417.064385 -394.320847) (xy 417.040713 -394.371344) (xy 417.00994 -394.417857)
			(xy 416.972723 -394.459394) (xy 416.929855 -394.495069) (xy 416.882249 -394.524123) (xy 416.83092 -394.545935)
			(xy 416.776963 -394.560041) (xy 416.721526 -394.566141) (xy 416.665792 -394.564104) (xy 416.610949 -394.553974)
			(xy 416.558165 -394.535967) (xy 416.508565 -394.510466) (xy 416.463207 -394.478015) (xy 416.423058 -394.439306)
			(xy 416.388972 -394.395163) (xy 416.361676 -394.346528) (xy 416.341753 -394.294437) (xy 416.329627 -394.24)
			(xy 416.325556 -394.184378) (xy 398.479264 -394.184378) (xy 398.625822 -394.330936) (xy 398.633219 -394.337786)
			(xy 398.651817 -394.345522) (xy 398.66189 -394.345922) (xy 401.023328 -394.345922) (xy 401.032906 -394.345532)
			(xy 401.050737 -394.338533) (xy 401.064759 -394.325484) (xy 401.07302 -394.308201) (xy 401.074128 -394.298678)
			(xy 401.074128 -394.27912) (xy 414.451292 -394.27912) (xy 414.525968 -394.353542) (xy 414.525968 -397.822887)
			(xy 419.004818 -397.822887) (xy 419.004822 -397.757448) (xy 419.013611 -397.692601) (xy 419.031025 -397.62952)
			(xy 419.05675 -397.569349) (xy 419.073076 -397.540988) (xy 419.076393 -397.534965) (xy 419.079998 -397.5217)
			(xy 419.080188 -397.514826) (xy 419.080188 -396.765526) (xy 419.079987 -396.758653) (xy 419.076385 -396.745391)
			(xy 419.073076 -396.739364) (xy 419.056744 -396.711008) (xy 419.031025 -396.650836) (xy 419.013617 -396.587756)
			(xy 419.004834 -396.52291) (xy 419.004835 -396.457472) (xy 419.01362 -396.392627) (xy 419.031031 -396.329548)
			(xy 419.056752 -396.269377) (xy 419.073076 -396.241016) (xy 419.076383 -396.234988) (xy 419.079994 -396.221727)
			(xy 419.080188 -396.214854) (xy 419.080188 -395.92885) (xy 419.080606 -395.918675) (xy 419.088384 -395.899872)
			(xy 419.102772 -395.885484) (xy 419.121575 -395.877706) (xy 419.13175 -395.877288) (xy 419.84803 -395.877288)
			(xy 419.85821 -395.87764) (xy 419.877015 -395.885445) (xy 419.8914 -395.899852) (xy 419.899175 -395.91867)
			(xy 419.899592 -395.92885) (xy 419.899592 -396.214854) (xy 419.899803 -396.221726) (xy 419.903398 -396.234989)
			(xy 419.906704 -396.241016) (xy 419.923016 -396.269382) (xy 419.948733 -396.329553) (xy 419.96614 -396.39263)
			(xy 419.974924 -396.457474) (xy 419.974925 -396.522909) (xy 419.966143 -396.587753) (xy 419.948738 -396.650831)
			(xy 419.923024 -396.711002) (xy 419.906704 -396.739364) (xy 419.903402 -396.745395) (xy 419.899788 -396.758654)
			(xy 419.899592 -396.765526) (xy 419.899592 -397.514826) (xy 419.899775 -397.5217) (xy 419.903389 -397.534963)
			(xy 419.906704 -397.540988) (xy 419.922993 -397.569367) (xy 419.948711 -397.629535) (xy 419.966121 -397.69261)
			(xy 419.974908 -397.757451) (xy 419.974912 -397.822884) (xy 419.966134 -397.887726) (xy 419.948733 -397.950803)
			(xy 419.923022 -398.010974) (xy 419.906704 -398.039336) (xy 419.903377 -398.045355) (xy 419.899779 -398.058623)
			(xy 419.899592 -398.065498) (xy 419.899592 -398.351502) (xy 419.899069 -398.361656) (xy 419.891299 -398.38042)
			(xy 419.876943 -398.394784) (xy 419.858184 -398.402563) (xy 419.84803 -398.403064) (xy 419.13175 -398.403064)
			(xy 419.121582 -398.402595) (xy 419.102789 -398.394827) (xy 419.088402 -398.380455) (xy 419.080615 -398.36167)
			(xy 419.080188 -398.351502) (xy 419.080188 -398.065498) (xy 419.079999 -398.058625) (xy 419.076389 -398.045362)
			(xy 419.073076 -398.039336) (xy 419.05672 -398.010993) (xy 419.031004 -397.950818) (xy 419.013598 -397.887735)
			(xy 419.004818 -397.822887) (xy 414.525968 -397.822887) (xy 414.525968 -398.890236) (xy 421.204136 -398.890236)
			(xy 421.204704 -398.857507) (xy 421.213561 -398.792649) (xy 421.23105 -398.729569) (xy 421.256856 -398.66941)
			(xy 421.273224 -398.641062) (xy 421.276554 -398.635045) (xy 421.28015 -398.621775) (xy 421.280336 -398.6149)
			(xy 421.280336 -397.865346) (xy 421.280122 -397.858474) (xy 421.276528 -397.845212) (xy 421.273224 -397.839184)
			(xy 421.256854 -397.810837) (xy 421.231053 -397.750677) (xy 421.213564 -397.687597) (xy 421.204705 -397.622739)
			(xy 421.204136 -397.59001) (xy 421.204693 -397.55728) (xy 421.213552 -397.492422) (xy 421.231046 -397.429342)
			(xy 421.256855 -397.369184) (xy 421.273224 -397.340836) (xy 421.276528 -397.334806) (xy 421.28014 -397.321546)
			(xy 421.280336 -397.314674) (xy 421.280336 -397.028924) (xy 421.280736 -397.018799) (xy 421.288483 -397.000089)
			(xy 421.302805 -396.985772) (xy 421.321518 -396.978032) (xy 421.331644 -396.977616) (xy 422.047924 -396.977616)
			(xy 422.058036 -396.978066) (xy 422.076718 -396.985814) (xy 422.091013 -397.000122) (xy 422.098744 -397.018811)
			(xy 422.099232 -397.028924) (xy 422.099232 -397.314674) (xy 422.09943 -397.321547) (xy 422.103034 -397.33481)
			(xy 422.106344 -397.340836) (xy 422.122719 -397.36918) (xy 422.148519 -397.429341) (xy 422.166007 -397.492422)
			(xy 422.174864 -397.557281) (xy 422.175432 -397.59001) (xy 422.174844 -397.622739) (xy 422.165994 -397.687596)
			(xy 422.14851 -397.750676) (xy 422.131575 -397.790162) (xy 423.404284 -397.790162) (xy 423.404857 -397.757433)
			(xy 423.413711 -397.692575) (xy 423.431199 -397.629495) (xy 423.457005 -397.569336) (xy 423.473372 -397.540988)
			(xy 423.476689 -397.534964) (xy 423.480294 -397.5217) (xy 423.480484 -397.514826) (xy 423.480484 -396.765526)
			(xy 423.480284 -396.758653) (xy 423.476681 -396.745391) (xy 423.473372 -396.739364) (xy 423.456989 -396.711024)
			(xy 423.431192 -396.650861) (xy 423.413708 -396.587779) (xy 423.404852 -396.52292) (xy 423.404284 -396.49019)
			(xy 423.40487 -396.457461) (xy 423.41372 -396.392604) (xy 423.431205 -396.329524) (xy 423.457006 -396.269365)
			(xy 423.473372 -396.241016) (xy 423.476679 -396.234988) (xy 423.48029 -396.221727) (xy 423.480484 -396.214854)
			(xy 423.480484 -395.92885) (xy 423.480969 -395.918721) (xy 423.488688 -395.899993) (xy 423.502976 -395.885633)
			(xy 423.521666 -395.87782) (xy 423.531792 -395.877288) (xy 424.248072 -395.877288) (xy 424.258223 -395.877744)
			(xy 424.276972 -395.885528) (xy 424.291296 -395.899914) (xy 424.298999 -395.918697) (xy 424.29938 -395.92885)
			(xy 424.29938 -396.214854) (xy 424.299592 -396.221726) (xy 424.303187 -396.234988) (xy 424.306492 -396.241016)
			(xy 424.322863 -396.269362) (xy 424.348664 -396.329523) (xy 424.366152 -396.392603) (xy 424.375011 -396.457461)
			(xy 424.37558 -396.49019) (xy 424.375035 -396.52292) (xy 424.366173 -396.587779) (xy 424.348677 -396.65086)
			(xy 424.322863 -396.711017) (xy 424.306492 -396.739364) (xy 424.303189 -396.745395) (xy 424.299576 -396.758654)
			(xy 424.29938 -396.765526) (xy 424.29938 -397.514826) (xy 424.299565 -397.5217) (xy 424.303178 -397.534962)
			(xy 424.306492 -397.540988) (xy 424.315899 -397.557291) (xy 425.604789 -397.557291) (xy 425.613571 -397.492447)
			(xy 425.630976 -397.429369) (xy 425.656691 -397.369198) (xy 425.673012 -397.340836) (xy 425.676315 -397.334806)
			(xy 425.679928 -397.321546) (xy 425.680124 -397.314674) (xy 425.680124 -397.028924) (xy 425.680542 -397.018768)
			(xy 425.688334 -397.000012) (xy 425.702732 -396.985687) (xy 425.721528 -396.97799) (xy 425.731686 -396.977616)
			(xy 426.447966 -396.977616) (xy 426.458088 -396.978154) (xy 426.476803 -396.985866) (xy 426.49116 -397.000137)
			(xy 426.498984 -397.018806) (xy 426.499528 -397.028924) (xy 426.499528 -397.314674) (xy 426.499726 -397.321547)
			(xy 426.50333 -397.33481) (xy 426.50664 -397.340836) (xy 426.522971 -397.369192) (xy 426.548689 -397.429364)
			(xy 426.566097 -397.492444) (xy 426.57488 -397.55729) (xy 426.574879 -397.622727) (xy 426.566094 -397.687573)
			(xy 426.548684 -397.750652) (xy 426.522964 -397.810823) (xy 426.51602 -397.822887) (xy 427.804904 -397.822887)
			(xy 427.804908 -397.757448) (xy 427.813697 -397.692601) (xy 427.831111 -397.629521) (xy 427.856835 -397.569349)
			(xy 427.87316 -397.540988) (xy 427.876476 -397.534964) (xy 427.880081 -397.5217) (xy 427.880272 -397.514826)
			(xy 427.880272 -396.765526) (xy 427.880074 -396.758653) (xy 427.87647 -396.74539) (xy 427.87316 -396.739364)
			(xy 427.856829 -396.711008) (xy 427.831111 -396.650836) (xy 427.813703 -396.587756) (xy 427.80492 -396.52291)
			(xy 427.804921 -396.457473) (xy 427.813706 -396.392627) (xy 427.831116 -396.329548) (xy 427.856836 -396.269377)
			(xy 427.87316 -396.241016) (xy 427.876466 -396.234987) (xy 427.880077 -396.221727) (xy 427.880272 -396.214854)
			(xy 427.880272 -395.92885) (xy 427.880706 -395.918677) (xy 427.88848 -395.899877) (xy 427.902864 -395.885489)
			(xy 427.921662 -395.877709) (xy 427.931834 -395.877288) (xy 428.648114 -395.877288) (xy 428.658293 -395.877654)
			(xy 428.677097 -395.885453) (xy 428.691483 -395.899857) (xy 428.699259 -395.918671) (xy 428.699676 -395.92885)
			(xy 428.699676 -396.214854) (xy 428.699888 -396.221726) (xy 428.703483 -396.234988) (xy 428.706788 -396.241016)
			(xy 428.723101 -396.269382) (xy 428.748818 -396.329553) (xy 428.766226 -396.39263) (xy 428.77501 -396.457474)
			(xy 428.775011 -396.522909) (xy 428.766229 -396.587753) (xy 428.748824 -396.650831) (xy 428.723109 -396.711002)
			(xy 428.706788 -396.739364) (xy 428.703485 -396.745394) (xy 428.699872 -396.758654) (xy 428.699676 -396.765526)
			(xy 428.699676 -397.514826) (xy 428.699861 -397.5217) (xy 428.703474 -397.534962) (xy 428.706788 -397.540988)
			(xy 428.723077 -397.569367) (xy 428.748796 -397.629535) (xy 428.766207 -397.692609) (xy 428.774994 -397.757451)
			(xy 428.774998 -397.822884) (xy 428.76622 -397.887727) (xy 428.748818 -397.950804) (xy 428.723107 -398.010975)
			(xy 428.706788 -398.039336) (xy 428.70346 -398.045354) (xy 428.699863 -398.058623) (xy 428.699676 -398.065498)
			(xy 428.699676 -398.351502) (xy 428.699169 -398.361658) (xy 428.691396 -398.380425) (xy 428.677035 -398.394789)
			(xy 428.65827 -398.402566) (xy 428.648114 -398.403064) (xy 427.931834 -398.403064) (xy 427.921665 -398.402608)
			(xy 427.902871 -398.394835) (xy 427.888485 -398.380459) (xy 427.880699 -398.361671) (xy 427.880272 -398.351502)
			(xy 427.880272 -398.065498) (xy 427.880084 -398.058624) (xy 427.876473 -398.045362) (xy 427.87316 -398.039336)
			(xy 427.856805 -398.010993) (xy 427.831089 -397.950818) (xy 427.813684 -397.887735) (xy 427.804904 -397.822887)
			(xy 426.51602 -397.822887) (xy 426.50664 -397.839184) (xy 426.503334 -397.845213) (xy 426.499723 -397.858473)
			(xy 426.499528 -397.865346) (xy 426.499528 -398.6149) (xy 426.499717 -398.621774) (xy 426.503327 -398.635036)
			(xy 426.50664 -398.641062) (xy 426.522993 -398.669406) (xy 426.548709 -398.729581) (xy 426.566115 -398.792663)
			(xy 426.574895 -398.857511) (xy 426.574893 -398.890236) (xy 430.00422 -398.890236) (xy 430.004777 -398.857506)
			(xy 430.013635 -398.792647) (xy 430.031128 -398.729567) (xy 430.056938 -398.66941) (xy 430.073308 -398.641062)
			(xy 430.076637 -398.635044) (xy 430.080233 -398.621775) (xy 430.08042 -398.6149) (xy 430.08042 -397.865346)
			(xy 430.080208 -397.858474) (xy 430.076613 -397.845212) (xy 430.073308 -397.839184) (xy 430.056937 -397.810838)
			(xy 430.031136 -397.750677) (xy 430.013648 -397.687597) (xy 430.004789 -397.622739) (xy 430.00422 -397.59001)
			(xy 430.004765 -397.55728) (xy 430.013627 -397.492421) (xy 430.031123 -397.42934) (xy 430.056937 -397.369183)
			(xy 430.073308 -397.340836) (xy 430.076611 -397.334805) (xy 430.080224 -397.321546) (xy 430.08042 -397.314674)
			(xy 430.08042 -397.028924) (xy 430.080836 -397.018801) (xy 430.08858 -397.000094) (xy 430.102897 -396.985778)
			(xy 430.121605 -396.978035) (xy 430.131728 -396.977616) (xy 430.848008 -396.977616) (xy 430.858133 -396.97801)
			(xy 430.87684 -396.985764) (xy 430.891154 -397.000087) (xy 430.898896 -397.018799) (xy 430.899316 -397.028924)
			(xy 430.899316 -397.314674) (xy 430.899516 -397.321547) (xy 430.903119 -397.334809) (xy 430.906428 -397.340836)
			(xy 430.922811 -397.369176) (xy 430.948608 -397.429339) (xy 430.966092 -397.492421) (xy 430.974948 -397.55728)
			(xy 430.975516 -397.59001) (xy 430.97493 -397.622739) (xy 430.96608 -397.687596) (xy 430.948595 -397.750676)
			(xy 430.922794 -397.810835) (xy 430.915836 -397.822887) (xy 432.204694 -397.822887) (xy 432.204698 -397.757448)
			(xy 432.213486 -397.692601) (xy 432.2309 -397.629521) (xy 432.256623 -397.569349) (xy 432.272948 -397.540988)
			(xy 432.276263 -397.534963) (xy 432.279869 -397.5217) (xy 432.28006 -397.514826) (xy 432.28006 -396.765526)
			(xy 432.279863 -396.758653) (xy 432.276259 -396.74539) (xy 432.272948 -396.739364) (xy 432.256617 -396.711008)
			(xy 432.2309 -396.650835) (xy 432.213492 -396.587756) (xy 432.20471 -396.52291) (xy 432.204711 -396.457473)
			(xy 432.213496 -396.392628) (xy 432.230905 -396.329548) (xy 432.256625 -396.269377) (xy 432.272948 -396.241016)
			(xy 432.276253 -396.234986) (xy 432.279865 -396.221727) (xy 432.28006 -396.214854) (xy 432.28006 -395.92885)
			(xy 432.280505 -395.918679) (xy 432.288278 -395.899881) (xy 432.302658 -395.885494) (xy 432.321451 -395.877711)
			(xy 432.331622 -395.877288) (xy 433.047902 -395.877288) (xy 433.05808 -395.877663) (xy 433.076884 -395.885458)
			(xy 433.091271 -395.899859) (xy 433.099047 -395.918672) (xy 433.099464 -395.92885) (xy 433.099464 -396.214854)
			(xy 433.099678 -396.221726) (xy 433.103272 -396.234988) (xy 433.106576 -396.241016) (xy 433.122889 -396.269382)
			(xy 433.148607 -396.329552) (xy 433.166015 -396.39263) (xy 433.1748 -396.457474) (xy 433.1748 -396.49019)
			(xy 436.603656 -396.49019) (xy 436.607647 -396.428023) (xy 436.619556 -396.366876) (xy 436.639185 -396.307755)
			(xy 436.666214 -396.251629) (xy 436.700198 -396.19942) (xy 436.74058 -396.151985) (xy 436.786696 -396.110104)
			(xy 436.837788 -396.074464) (xy 436.893019 -396.04565) (xy 436.951481 -396.024136) (xy 437.012215 -396.010274)
			(xy 437.074222 -396.004292) (xy 437.136485 -396.006288) (xy 437.197982 -396.016231) (xy 437.257703 -396.033955)
			(xy 437.314666 -396.059172) (xy 437.367937 -396.091465) (xy 437.416642 -396.130305) (xy 437.459979 -396.175055)
			(xy 437.497239 -396.224979) (xy 437.527808 -396.279258) (xy 437.551186 -396.337001) (xy 437.566987 -396.397259)
			(xy 437.574953 -396.459042) (xy 437.575452 -396.49019) (xy 437.574953 -396.521338) (xy 437.566987 -396.583121)
			(xy 437.551186 -396.643379) (xy 437.527808 -396.701122) (xy 437.497239 -396.755401) (xy 437.459979 -396.805325)
			(xy 437.416642 -396.850075) (xy 437.367937 -396.888915) (xy 437.314666 -396.921208) (xy 437.257703 -396.946425)
			(xy 437.197982 -396.964149) (xy 437.136485 -396.974092) (xy 437.074222 -396.976088) (xy 437.012215 -396.970106)
			(xy 436.951481 -396.956244) (xy 436.893019 -396.93473) (xy 436.837788 -396.905916) (xy 436.786696 -396.870276)
			(xy 436.74058 -396.828395) (xy 436.700198 -396.78096) (xy 436.666214 -396.728751) (xy 436.639185 -396.672625)
			(xy 436.619556 -396.613504) (xy 436.607647 -396.552357) (xy 436.603656 -396.49019) (xy 433.1748 -396.49019)
			(xy 433.174801 -396.522909) (xy 433.166019 -396.587753) (xy 433.148613 -396.650831) (xy 433.122897 -396.711003)
			(xy 433.106576 -396.739364) (xy 433.103272 -396.745394) (xy 433.09966 -396.758654) (xy 433.099464 -396.765526)
			(xy 433.099464 -397.514826) (xy 433.099651 -397.5217) (xy 433.103263 -397.534962) (xy 433.106576 -397.540988)
			(xy 433.115934 -397.557291) (xy 434.404875 -397.557291) (xy 434.413657 -397.492447) (xy 434.431062 -397.429369)
			(xy 434.456776 -397.369198) (xy 434.473096 -397.340836) (xy 434.476398 -397.334805) (xy 434.480012 -397.321546)
			(xy 434.480208 -397.314674) (xy 434.480208 -397.028924) (xy 434.480641 -397.01877) (xy 434.48843 -397.000017)
			(xy 434.502824 -396.985692) (xy 434.521614 -396.977993) (xy 434.53177 -396.977616) (xy 435.24805 -396.977616)
			(xy 435.258171 -396.978167) (xy 435.276886 -396.985874) (xy 435.291243 -397.00014) (xy 435.299068 -397.018807)
			(xy 435.299612 -397.028924) (xy 435.299612 -397.314674) (xy 435.299813 -397.321547) (xy 435.303415 -397.334809)
			(xy 435.306724 -397.340836) (xy 435.323056 -397.369192) (xy 435.348775 -397.429364) (xy 435.366183 -397.492444)
			(xy 435.374966 -397.55729) (xy 435.374965 -397.622728) (xy 435.36618 -397.687573) (xy 435.348769 -397.750652)
			(xy 435.33188 -397.790162) (xy 436.603656 -397.790162) (xy 436.607647 -397.727995) (xy 436.619556 -397.666848)
			(xy 436.639185 -397.607727) (xy 436.666214 -397.551601) (xy 436.700198 -397.499392) (xy 436.74058 -397.451957)
			(xy 436.786696 -397.410076) (xy 436.837788 -397.374436) (xy 436.893019 -397.345622) (xy 436.951481 -397.324108)
			(xy 437.012215 -397.310246) (xy 437.074222 -397.304264) (xy 437.136485 -397.30626) (xy 437.197982 -397.316203)
			(xy 437.257703 -397.333927) (xy 437.314666 -397.359144) (xy 437.367937 -397.391437) (xy 437.416642 -397.430277)
			(xy 437.459979 -397.475027) (xy 437.497239 -397.524951) (xy 437.527808 -397.57923) (xy 437.532172 -397.59001)
			(xy 438.803804 -397.59001) (xy 438.807795 -397.527843) (xy 438.819704 -397.466696) (xy 438.839333 -397.407575)
			(xy 438.866362 -397.351449) (xy 438.900346 -397.29924) (xy 438.940728 -397.251805) (xy 438.986844 -397.209924)
			(xy 439.037936 -397.174284) (xy 439.093167 -397.14547) (xy 439.151629 -397.123956) (xy 439.212363 -397.110094)
			(xy 439.27437 -397.104112) (xy 439.336633 -397.106108) (xy 439.39813 -397.116051) (xy 439.457851 -397.133775)
			(xy 439.514814 -397.158992) (xy 439.568085 -397.191285) (xy 439.61679 -397.230125) (xy 439.660127 -397.274875)
			(xy 439.697387 -397.324799) (xy 439.727956 -397.379078) (xy 439.751334 -397.436821) (xy 439.767135 -397.497079)
			(xy 439.775101 -397.558862) (xy 439.7756 -397.59001) (xy 439.775101 -397.621158) (xy 439.767135 -397.682941)
			(xy 439.751334 -397.743199) (xy 439.727956 -397.800942) (xy 439.697387 -397.855221) (xy 439.660127 -397.905145)
			(xy 439.61679 -397.949895) (xy 439.568085 -397.988735) (xy 439.514814 -398.021028) (xy 439.457851 -398.046245)
			(xy 439.39813 -398.063969) (xy 439.336633 -398.073912) (xy 439.27437 -398.075908) (xy 439.212363 -398.069926)
			(xy 439.151629 -398.056064) (xy 439.093167 -398.03455) (xy 439.037936 -398.005736) (xy 438.986844 -397.970096)
			(xy 438.940728 -397.928215) (xy 438.900346 -397.88078) (xy 438.866362 -397.828571) (xy 438.839333 -397.772445)
			(xy 438.819704 -397.713324) (xy 438.807795 -397.652177) (xy 438.803804 -397.59001) (xy 437.532172 -397.59001)
			(xy 437.551186 -397.636973) (xy 437.566987 -397.697231) (xy 437.574953 -397.759014) (xy 437.575452 -397.790162)
			(xy 437.574953 -397.82131) (xy 437.566987 -397.883093) (xy 437.551186 -397.943351) (xy 437.527808 -398.001094)
			(xy 437.497239 -398.055373) (xy 437.463901 -398.100042) (xy 459.541382 -398.100042) (xy 459.545364 -397.972056)
			(xy 459.557296 -397.844565) (xy 459.57713 -397.718062) (xy 459.604791 -397.593037) (xy 459.640171 -397.469974)
			(xy 459.683133 -397.349348) (xy 459.733511 -397.231627) (xy 459.791111 -397.117265) (xy 459.855709 -397.006706)
			(xy 459.927056 -396.900376) (xy 460.004875 -396.798688) (xy 460.088865 -396.702034) (xy 460.178702 -396.610789)
			(xy 460.274038 -396.525306) (xy 460.374503 -396.445915) (xy 460.479711 -396.372923) (xy 460.589252 -396.306614)
			(xy 460.702704 -396.247243) (xy 460.819628 -396.195039) (xy 460.939571 -396.150206) (xy 461.062069 -396.112917)
			(xy 461.186649 -396.083315) (xy 461.312827 -396.061516) (xy 461.440117 -396.047603) (xy 461.568026 -396.041631)
			(xy 461.696059 -396.043622) (xy 461.82372 -396.05357) (xy 461.950516 -396.071434) (xy 462.075955 -396.097147)
			(xy 462.199554 -396.130609) (xy 462.320833 -396.17169) (xy 462.439324 -396.220232) (xy 462.554568 -396.276046)
			(xy 462.666118 -396.338917) (xy 462.773545 -396.408601) (xy 462.876431 -396.484829) (xy 462.974379 -396.567306)
			(xy 463.06701 -396.655713) (xy 463.153966 -396.749708) (xy 463.23491 -396.848927) (xy 463.309529 -396.952986)
			(xy 463.377534 -397.061483) (xy 463.438662 -397.173998) (xy 463.492677 -397.290096) (xy 463.53937 -397.409327)
			(xy 463.57856 -397.531231) (xy 463.610096 -397.655335) (xy 463.633855 -397.781159) (xy 463.649745 -397.908218)
			(xy 463.657706 -398.036018) (xy 463.658204 -398.100042) (xy 463.657706 -398.164066) (xy 463.649745 -398.291866)
			(xy 463.633855 -398.418925) (xy 463.610096 -398.544749) (xy 463.57856 -398.668853) (xy 463.53937 -398.790757)
			(xy 463.492677 -398.909988) (xy 463.438662 -399.026086) (xy 463.377534 -399.138601) (xy 463.309529 -399.247098)
			(xy 463.23491 -399.351157) (xy 463.153966 -399.450376) (xy 463.06701 -399.544371) (xy 462.974379 -399.632778)
			(xy 462.876431 -399.715255) (xy 462.773545 -399.791483) (xy 462.666118 -399.861167) (xy 462.554568 -399.924038)
			(xy 462.439324 -399.979852) (xy 462.320833 -400.028394) (xy 462.199554 -400.069475) (xy 462.075955 -400.102937)
			(xy 461.950516 -400.12865) (xy 461.82372 -400.146514) (xy 461.696059 -400.156462) (xy 461.568026 -400.158453)
			(xy 461.440117 -400.152481) (xy 461.312827 -400.138568) (xy 461.186649 -400.116769) (xy 461.062069 -400.087167)
			(xy 460.939571 -400.049878) (xy 460.819628 -400.005045) (xy 460.702704 -399.952841) (xy 460.589252 -399.89347)
			(xy 460.479711 -399.827161) (xy 460.374503 -399.754169) (xy 460.274038 -399.674778) (xy 460.178702 -399.589295)
			(xy 460.088865 -399.49805) (xy 460.004875 -399.401396) (xy 459.927056 -399.299708) (xy 459.855709 -399.193378)
			(xy 459.791111 -399.082819) (xy 459.733511 -398.968457) (xy 459.683133 -398.850736) (xy 459.640171 -398.73011)
			(xy 459.604791 -398.607047) (xy 459.57713 -398.482022) (xy 459.557296 -398.355519) (xy 459.545364 -398.228028)
			(xy 459.541382 -398.100042) (xy 437.463901 -398.100042) (xy 437.459979 -398.105297) (xy 437.416642 -398.150047)
			(xy 437.367937 -398.188887) (xy 437.314666 -398.22118) (xy 437.257703 -398.246397) (xy 437.197982 -398.264121)
			(xy 437.136485 -398.274064) (xy 437.074222 -398.27606) (xy 437.012215 -398.270078) (xy 436.951481 -398.256216)
			(xy 436.893019 -398.234702) (xy 436.837788 -398.205888) (xy 436.786696 -398.170248) (xy 436.74058 -398.128367)
			(xy 436.700198 -398.080932) (xy 436.666214 -398.028723) (xy 436.639185 -397.972597) (xy 436.619556 -397.913476)
			(xy 436.607647 -397.852329) (xy 436.603656 -397.790162) (xy 435.33188 -397.790162) (xy 435.323048 -397.810823)
			(xy 435.306724 -397.839184) (xy 435.303417 -397.845212) (xy 435.299806 -397.858473) (xy 435.299612 -397.865346)
			(xy 435.299612 -398.6149) (xy 435.299803 -398.621773) (xy 435.303412 -398.635036) (xy 435.306724 -398.641062)
			(xy 435.323078 -398.669406) (xy 435.348795 -398.729581) (xy 435.366201 -398.792663) (xy 435.374981 -398.857511)
			(xy 435.374979 -398.890236) (xy 438.803804 -398.890236) (xy 438.807795 -398.828069) (xy 438.819704 -398.766922)
			(xy 438.839333 -398.707801) (xy 438.866362 -398.651675) (xy 438.900346 -398.599466) (xy 438.940728 -398.552031)
			(xy 438.986844 -398.51015) (xy 439.037936 -398.47451) (xy 439.093167 -398.445696) (xy 439.151629 -398.424182)
			(xy 439.212363 -398.41032) (xy 439.27437 -398.404338) (xy 439.336633 -398.406334) (xy 439.39813 -398.416277)
			(xy 439.457851 -398.434001) (xy 439.514814 -398.459218) (xy 439.568085 -398.491511) (xy 439.61679 -398.530351)
			(xy 439.660127 -398.575101) (xy 439.697387 -398.625025) (xy 439.727956 -398.679304) (xy 439.751334 -398.737047)
			(xy 439.767135 -398.797305) (xy 439.775101 -398.859088) (xy 439.7756 -398.890236) (xy 439.775101 -398.921384)
			(xy 439.767135 -398.983167) (xy 439.751334 -399.043425) (xy 439.727956 -399.101168) (xy 439.697387 -399.155447)
			(xy 439.660127 -399.205371) (xy 439.61679 -399.250121) (xy 439.568085 -399.288961) (xy 439.514814 -399.321254)
			(xy 439.457851 -399.346471) (xy 439.39813 -399.364195) (xy 439.336633 -399.374138) (xy 439.27437 -399.376134)
			(xy 439.212363 -399.370152) (xy 439.151629 -399.35629) (xy 439.093167 -399.334776) (xy 439.037936 -399.305962)
			(xy 438.986844 -399.270322) (xy 438.940728 -399.228441) (xy 438.900346 -399.181006) (xy 438.866362 -399.128797)
			(xy 438.839333 -399.072671) (xy 438.819704 -399.01355) (xy 438.807795 -398.952403) (xy 438.803804 -398.890236)
			(xy 435.374979 -398.890236) (xy 435.374977 -398.922951) (xy 435.366188 -398.987798) (xy 435.348774 -399.050878)
			(xy 435.32305 -399.111049) (xy 435.306724 -399.13941) (xy 435.303407 -399.145434) (xy 435.299802 -399.158698)
			(xy 435.299612 -399.165572) (xy 435.299612 -399.451576) (xy 435.299159 -399.461727) (xy 435.291374 -399.480477)
			(xy 435.276987 -399.494801) (xy 435.258203 -399.502503) (xy 435.24805 -399.502884) (xy 434.53177 -399.502884)
			(xy 434.521644 -399.502399) (xy 434.502927 -399.494666) (xy 434.488573 -399.480379) (xy 434.48075 -399.461699)
			(xy 434.480208 -399.451576) (xy 434.480208 -399.165572) (xy 434.480026 -399.158698) (xy 434.476411 -399.145435)
			(xy 434.473096 -399.13941) (xy 434.456806 -399.111031) (xy 434.431087 -399.050864) (xy 434.413678 -398.987789)
			(xy 434.404891 -398.922948) (xy 434.404887 -398.857514) (xy 434.413665 -398.792672) (xy 434.431067 -398.729595)
			(xy 434.456778 -398.669424) (xy 434.473096 -398.641062) (xy 434.476424 -398.635044) (xy 434.480021 -398.621775)
			(xy 434.480208 -398.6149) (xy 434.480208 -397.865346) (xy 434.479997 -397.858474) (xy 434.476402 -397.845211)
			(xy 434.473096 -397.839184) (xy 434.456784 -397.810818) (xy 434.431067 -397.750647) (xy 434.41366 -397.68757)
			(xy 434.404876 -397.622726) (xy 434.404875 -397.557291) (xy 433.115934 -397.557291) (xy 433.122866 -397.569367)
			(xy 433.148585 -397.629534) (xy 433.165996 -397.692609) (xy 433.174784 -397.75745) (xy 433.174788 -397.822884)
			(xy 433.16601 -397.887727) (xy 433.148607 -397.950804) (xy 433.122895 -398.010975) (xy 433.106576 -398.039336)
			(xy 433.103247 -398.045353) (xy 433.099651 -398.058623) (xy 433.099464 -398.065498) (xy 433.099464 -398.351502)
			(xy 433.098968 -398.36166) (xy 433.091194 -398.380428) (xy 433.076828 -398.394794) (xy 433.05806 -398.402568)
			(xy 433.047902 -398.403064) (xy 432.331622 -398.403064) (xy 432.321452 -398.402618) (xy 432.302658 -398.394841)
			(xy 432.288273 -398.380462) (xy 432.280487 -398.361672) (xy 432.28006 -398.351502) (xy 432.28006 -398.065498)
			(xy 432.279874 -398.058624) (xy 432.276262 -398.045361) (xy 432.272948 -398.039336) (xy 432.256593 -398.010993)
			(xy 432.230878 -397.950817) (xy 432.213473 -397.887735) (xy 432.204694 -397.822887) (xy 430.915836 -397.822887)
			(xy 430.906428 -397.839184) (xy 430.903121 -397.845212) (xy 430.89951 -397.858473) (xy 430.899316 -397.865346)
			(xy 430.899316 -398.6149) (xy 430.899506 -398.621773) (xy 430.903116 -398.635036) (xy 430.906428 -398.641062)
			(xy 430.922781 -398.669418) (xy 430.948585 -398.729575) (xy 430.966078 -398.792653) (xy 430.974943 -398.857508)
			(xy 430.975516 -398.890236) (xy 430.974942 -398.922965) (xy 430.966088 -398.987823) (xy 430.9486 -399.050903)
			(xy 430.922795 -399.111062) (xy 430.906428 -399.13941) (xy 430.903112 -399.145434) (xy 430.899507 -399.158698)
			(xy 430.899316 -399.165572) (xy 430.899316 -399.451576) (xy 430.898865 -399.461695) (xy 430.891128 -399.480395)
			(xy 430.876822 -399.49471) (xy 430.858127 -399.502459) (xy 430.848008 -399.502884) (xy 430.131728 -399.502884)
			(xy 430.121605 -399.502461) (xy 430.102899 -399.494719) (xy 430.088583 -399.480404) (xy 430.08084 -399.461699)
			(xy 430.08042 -399.451576) (xy 430.08042 -399.165572) (xy 430.080236 -399.158698) (xy 430.076622 -399.145436)
			(xy 430.073308 -399.13941) (xy 430.056947 -399.111058) (xy 430.031144 -399.0509) (xy 430.013653 -398.987821)
			(xy 430.004791 -398.922965) (xy 430.00422 -398.890236) (xy 426.574893 -398.890236) (xy 426.574891 -398.922951)
			(xy 426.566102 -398.987797) (xy 426.548689 -399.050877) (xy 426.522965 -399.111049) (xy 426.50664 -399.13941)
			(xy 426.503325 -399.145435) (xy 426.499719 -399.158698) (xy 426.499528 -399.165572) (xy 426.499528 -399.451576)
			(xy 426.499059 -399.461725) (xy 426.491277 -399.480472) (xy 426.476895 -399.494795) (xy 426.458117 -399.502501)
			(xy 426.447966 -399.502884) (xy 425.731686 -399.502884) (xy 425.721561 -399.502385) (xy 425.702845 -399.494657)
			(xy 425.68849 -399.480375) (xy 425.680667 -399.461698) (xy 425.680124 -399.451576) (xy 425.680124 -399.165572)
			(xy 425.67994 -399.158698) (xy 425.676326 -399.145436) (xy 425.673012 -399.13941) (xy 425.656721 -399.111032)
			(xy 425.631002 -399.050864) (xy 425.613592 -398.987789) (xy 425.604805 -398.922948) (xy 425.604801 -398.857514)
			(xy 425.613579 -398.792672) (xy 425.630982 -398.729594) (xy 425.656693 -398.669423) (xy 425.673012 -398.641062)
			(xy 425.676341 -398.635044) (xy 425.679937 -398.621775) (xy 425.680124 -398.6149) (xy 425.680124 -397.865346)
			(xy 425.679912 -397.858474) (xy 425.676317 -397.845212) (xy 425.673012 -397.839184) (xy 425.656699 -397.810818)
			(xy 425.630982 -397.750647) (xy 425.613574 -397.68757) (xy 425.60479 -397.622726) (xy 425.604789 -397.557291)
			(xy 424.315899 -397.557291) (xy 424.322852 -397.56934) (xy 424.348655 -397.629499) (xy 424.366147 -397.692577)
			(xy 424.375009 -397.757433) (xy 424.37558 -397.790162) (xy 424.375022 -397.822892) (xy 424.366164 -397.88775)
			(xy 424.348672 -397.950831) (xy 424.322862 -398.010988) (xy 424.306492 -398.039336) (xy 424.303164 -398.045354)
			(xy 424.299567 -398.058623) (xy 424.29938 -398.065498) (xy 424.29938 -398.351502) (xy 424.298876 -398.361626)
			(xy 424.291151 -398.380344) (xy 424.27687 -398.394699) (xy 424.258194 -398.402522) (xy 424.248072 -398.403064)
			(xy 423.531792 -398.403064) (xy 423.521633 -398.402684) (xy 423.502873 -398.394879) (xy 423.488549 -398.380469)
			(xy 423.480856 -398.361663) (xy 423.480484 -398.351502) (xy 423.480484 -398.065498) (xy 423.480295 -398.058625)
			(xy 423.476685 -398.045362) (xy 423.473372 -398.039336) (xy 423.457018 -398.01098) (xy 423.431214 -397.950823)
			(xy 423.413721 -397.887746) (xy 423.404857 -397.82289) (xy 423.404284 -397.790162) (xy 422.131575 -397.790162)
			(xy 422.122709 -397.810835) (xy 422.106344 -397.839184) (xy 422.103039 -397.845213) (xy 422.099427 -397.858473)
			(xy 422.099232 -397.865346) (xy 422.099232 -398.6149) (xy 422.09942 -398.621774) (xy 422.103031 -398.635036)
			(xy 422.106344 -398.641062) (xy 422.122689 -398.669423) (xy 422.148497 -398.729578) (xy 422.165993 -398.792654)
			(xy 422.174859 -398.857508) (xy 422.175432 -398.890236) (xy 422.174856 -398.922965) (xy 422.166003 -398.987823)
			(xy 422.148515 -399.050903) (xy 422.122711 -399.111062) (xy 422.106344 -399.13941) (xy 422.103029 -399.145435)
			(xy 422.099423 -399.158698) (xy 422.099232 -399.165572) (xy 422.099232 -399.451576) (xy 422.098696 -399.461679)
			(xy 422.090972 -399.480351) (xy 422.076691 -399.494645) (xy 422.058027 -399.502387) (xy 422.047924 -399.502884)
			(xy 421.331644 -399.502884) (xy 421.321522 -399.502447) (xy 421.302817 -399.494711) (xy 421.2885 -399.4804)
			(xy 421.280756 -399.461697) (xy 421.280336 -399.451576) (xy 421.280336 -399.165572) (xy 421.28015 -399.158698)
			(xy 421.276537 -399.145436) (xy 421.273224 -399.13941) (xy 421.256865 -399.111057) (xy 421.231061 -399.050899)
			(xy 421.213569 -398.987821) (xy 421.204707 -398.922965) (xy 421.204136 -398.890236) (xy 414.525968 -398.890236)
			(xy 414.525968 -401.7228) (xy 419.004827 -401.7228) (xy 419.004829 -401.657362) (xy 419.013616 -401.592516)
			(xy 419.031029 -401.529436) (xy 419.056751 -401.469265) (xy 419.073076 -401.440904) (xy 419.076388 -401.434878)
			(xy 419.079996 -401.421615) (xy 419.080188 -401.414742) (xy 419.080188 -400.665442) (xy 419.079981 -400.65857)
			(xy 419.076383 -400.645307) (xy 419.073076 -400.63928) (xy 419.056758 -400.610916) (xy 419.031038 -400.550746)
			(xy 419.013628 -400.487668) (xy 419.004843 -400.422824) (xy 419.004842 -400.357387) (xy 419.013626 -400.292542)
			(xy 419.031034 -400.229464) (xy 419.056753 -400.169293) (xy 419.073076 -400.140932) (xy 419.076378 -400.134901)
			(xy 419.079992 -400.121642) (xy 419.080188 -400.11477) (xy 419.080188 -399.828766) (xy 419.080537 -399.818586)
			(xy 419.088343 -399.799781) (xy 419.102752 -399.785395) (xy 419.121569 -399.777621) (xy 419.13175 -399.777204)
			(xy 419.84803 -399.777204) (xy 419.858186 -399.777708) (xy 419.876949 -399.785486) (xy 419.891312 -399.799848)
			(xy 419.899091 -399.818611) (xy 419.899592 -399.828766) (xy 419.899592 -400.11477) (xy 419.899796 -400.121642)
			(xy 419.903396 -400.134905) (xy 419.906704 -400.140932) (xy 419.92303 -400.169291) (xy 419.948745 -400.229463)
			(xy 419.966151 -400.292542) (xy 419.974933 -400.357387) (xy 419.974932 -400.422823) (xy 419.966149 -400.487668)
			(xy 419.948741 -400.550747) (xy 419.923025 -400.610918) (xy 419.906704 -400.63928) (xy 419.903397 -400.645308)
			(xy 419.899786 -400.658569) (xy 419.899592 -400.665442) (xy 419.899592 -401.414742) (xy 419.899807 -401.421614)
			(xy 419.9034 -401.434876) (xy 419.906704 -401.440904) (xy 419.923006 -401.469276) (xy 419.948723 -401.529445)
			(xy 419.966132 -401.592522) (xy 419.974917 -401.657364) (xy 419.97492 -401.722798) (xy 419.96614 -401.787641)
			(xy 419.948736 -401.850719) (xy 419.923023 -401.91089) (xy 419.906704 -401.939252) (xy 419.903371 -401.945268)
			(xy 419.899777 -401.958538) (xy 419.899592 -401.965414) (xy 419.899592 -402.251418) (xy 419.899082 -402.261573)
			(xy 419.891308 -402.280337) (xy 419.876947 -402.294701) (xy 419.858185 -402.30248) (xy 419.84803 -402.30298)
			(xy 419.13175 -402.30298) (xy 419.121584 -402.302496) (xy 419.102794 -402.29473) (xy 419.088408 -402.280363)
			(xy 419.080618 -402.261584) (xy 419.080188 -402.251418) (xy 419.080188 -401.965414) (xy 419.079992 -401.958541)
			(xy 419.076387 -401.945278) (xy 419.073076 -401.939252) (xy 419.056734 -401.910901) (xy 419.031016 -401.850728)
			(xy 419.013609 -401.787647) (xy 419.004827 -401.7228) (xy 414.525968 -401.7228) (xy 414.525968 -402.790152)
			(xy 421.204136 -402.790152) (xy 421.204711 -402.757423) (xy 421.213566 -402.692565) (xy 421.231053 -402.629485)
			(xy 421.256857 -402.569327) (xy 421.273224 -402.540978) (xy 421.276548 -402.534958) (xy 421.280147 -402.521691)
			(xy 421.280336 -402.514816) (xy 421.280336 -401.765516) (xy 421.280133 -401.758644) (xy 421.276532 -401.745381)
			(xy 421.273224 -401.739354) (xy 421.256842 -401.711014) (xy 421.231044 -401.650851) (xy 421.213559 -401.587769)
			(xy 421.204703 -401.52291) (xy 421.204136 -401.49018) (xy 421.204724 -401.457451) (xy 421.213574 -401.392594)
			(xy 421.231058 -401.329514) (xy 421.256859 -401.269355) (xy 421.273224 -401.241006) (xy 421.276538 -401.234981)
			(xy 421.280144 -401.221718) (xy 421.280336 -401.214844) (xy 421.280336 -400.92884) (xy 421.28075 -400.918716)
			(xy 421.288491 -400.900006) (xy 421.302809 -400.885689) (xy 421.32152 -400.877949) (xy 421.331644 -400.877532)
			(xy 422.047924 -400.877532) (xy 422.058052 -400.877897) (xy 422.076762 -400.885659) (xy 422.091077 -400.899991)
			(xy 422.098816 -400.918711) (xy 422.099232 -400.92884) (xy 422.099232 -401.214844) (xy 422.099441 -401.221716)
			(xy 422.103037 -401.234979) (xy 422.106344 -401.241006) (xy 422.122707 -401.269357) (xy 422.14851 -401.329515)
			(xy 422.166001 -401.392594) (xy 422.174862 -401.457451) (xy 422.175432 -401.49018) (xy 422.174876 -401.52291)
			(xy 422.166016 -401.587768) (xy 422.148523 -401.650848) (xy 422.131693 -401.690078) (xy 423.404284 -401.690078)
			(xy 423.404865 -401.657349) (xy 423.413716 -401.592491) (xy 423.431202 -401.529411) (xy 423.457006 -401.469253)
			(xy 423.473372 -401.440904) (xy 423.476683 -401.434878) (xy 423.480292 -401.421615) (xy 423.480484 -401.414742)
			(xy 423.480484 -400.665442) (xy 423.480278 -400.65857) (xy 423.476679 -400.645307) (xy 423.473372 -400.63928)
			(xy 423.456996 -400.610937) (xy 423.431197 -400.550775) (xy 423.413711 -400.487694) (xy 423.404853 -400.422835)
			(xy 423.404284 -400.390106) (xy 423.404832 -400.357376) (xy 423.413693 -400.292517) (xy 423.431189 -400.229437)
			(xy 423.457001 -400.169279) (xy 423.473372 -400.140932) (xy 423.476673 -400.134901) (xy 423.480288 -400.121642)
			(xy 423.480484 -400.11477) (xy 423.480484 -399.828766) (xy 423.4809 -399.818632) (xy 423.488647 -399.799901)
			(xy 423.502955 -399.785545) (xy 423.521659 -399.777735) (xy 423.531792 -399.777204) (xy 424.248072 -399.777204)
			(xy 424.258225 -399.777644) (xy 424.276977 -399.785431) (xy 424.291302 -399.799823) (xy 424.299002 -399.818611)
			(xy 424.29938 -399.828766) (xy 424.29938 -400.11477) (xy 424.299586 -400.121642) (xy 424.303185 -400.134905)
			(xy 424.306492 -400.140932) (xy 424.32287 -400.169275) (xy 424.348669 -400.229437) (xy 424.366155 -400.292518)
			(xy 424.375012 -400.357376) (xy 424.37558 -400.390106) (xy 424.374997 -400.422835) (xy 424.366147 -400.487693)
			(xy 424.348662 -400.550773) (xy 424.322859 -400.610931) (xy 424.306492 -400.63928) (xy 424.303184 -400.645308)
			(xy 424.299574 -400.658569) (xy 424.29938 -400.665442) (xy 424.29938 -401.414742) (xy 424.299597 -401.421613)
			(xy 424.303189 -401.434876) (xy 424.306492 -401.440904) (xy 424.322858 -401.469253) (xy 424.34866 -401.529412)
			(xy 424.36615 -401.592492) (xy 424.37501 -401.657349) (xy 424.37558 -401.690078) (xy 424.375029 -401.722808)
			(xy 424.366169 -401.787667) (xy 424.348675 -401.850747) (xy 424.322863 -401.910905) (xy 424.306492 -401.939252)
			(xy 424.303158 -401.945267) (xy 424.299565 -401.958538) (xy 424.29938 -401.965414) (xy 424.29938 -402.251418)
			(xy 424.298889 -402.261543) (xy 424.291159 -402.280261) (xy 424.276874 -402.294616) (xy 424.258195 -402.302438)
			(xy 424.248072 -402.30298) (xy 423.531792 -402.30298) (xy 423.521635 -402.302584) (xy 423.502879 -402.294782)
			(xy 423.488555 -402.280378) (xy 423.480859 -402.261577) (xy 423.480484 -402.251418) (xy 423.480484 -401.965414)
			(xy 423.480289 -401.958541) (xy 423.476683 -401.945278) (xy 423.473372 -401.939252) (xy 423.456985 -401.910915)
			(xy 423.431189 -401.850751) (xy 423.413705 -401.787668) (xy 423.404851 -401.722808) (xy 423.404284 -401.690078)
			(xy 422.131693 -401.690078) (xy 422.122714 -401.711006) (xy 422.106344 -401.739354) (xy 422.103049 -401.745388)
			(xy 422.09943 -401.758645) (xy 422.099232 -401.765516) (xy 422.099232 -402.514816) (xy 422.099414 -402.52169)
			(xy 422.103029 -402.534953) (xy 422.106344 -402.540978) (xy 422.122695 -402.569335) (xy 422.148502 -402.629491)
			(xy 422.165996 -402.692568) (xy 422.17486 -402.757424) (xy 422.175432 -402.790152) (xy 422.174863 -402.822879)
			(xy 425.604757 -402.822879) (xy 425.604762 -402.757439) (xy 425.613551 -402.692592) (xy 425.630965 -402.629512)
			(xy 425.656687 -402.56934) (xy 425.673012 -402.540978) (xy 425.676335 -402.534958) (xy 425.679935 -402.521691)
			(xy 425.680124 -402.514816) (xy 425.680124 -401.765516) (xy 425.679923 -401.758643) (xy 425.676321 -401.745381)
			(xy 425.673012 -401.739354) (xy 425.656674 -401.711002) (xy 425.630959 -401.650828) (xy 425.613554 -401.587748)
			(xy 425.604773 -401.522902) (xy 425.604775 -401.457464) (xy 425.613561 -401.392619) (xy 425.63097 -401.329539)
			(xy 425.656689 -401.269368) (xy 425.673012 -401.241006) (xy 425.676325 -401.234981) (xy 425.679932 -401.221717)
			(xy 425.680124 -401.214844) (xy 425.680124 -400.92884) (xy 425.680555 -400.918686) (xy 425.688342 -400.899929)
			(xy 425.702736 -400.885604) (xy 425.72153 -400.877907) (xy 425.731686 -400.877532) (xy 426.447966 -400.877532)
			(xy 426.45809 -400.878054) (xy 426.476808 -400.88577) (xy 426.491165 -400.900045) (xy 426.498987 -400.918719)
			(xy 426.499528 -400.92884) (xy 426.499528 -401.214844) (xy 426.499738 -401.221716) (xy 426.503334 -401.234979)
			(xy 426.50664 -401.241006) (xy 426.522946 -401.269376) (xy 426.548666 -401.329545) (xy 426.566077 -401.392622)
			(xy 426.574863 -401.457465) (xy 426.574865 -401.522901) (xy 426.566084 -401.587744) (xy 426.548678 -401.650822)
			(xy 426.522962 -401.710993) (xy 426.516167 -401.7228) (xy 427.804913 -401.7228) (xy 427.804916 -401.657362)
			(xy 427.813702 -401.592516) (xy 427.831114 -401.529436) (xy 427.856836 -401.469265) (xy 427.87316 -401.440904)
			(xy 427.87647 -401.434877) (xy 427.880079 -401.421615) (xy 427.880272 -401.414742) (xy 427.880272 -400.665442)
			(xy 427.880067 -400.65857) (xy 427.876468 -400.645307) (xy 427.87316 -400.63928) (xy 427.856842 -400.610916)
			(xy 427.831123 -400.550746) (xy 427.813714 -400.487668) (xy 427.804929 -400.422823) (xy 427.804928 -400.357387)
			(xy 427.813712 -400.292542) (xy 427.83112 -400.229464) (xy 427.856838 -400.169293) (xy 427.87316 -400.140932)
			(xy 427.87646 -400.1349) (xy 427.880075 -400.121642) (xy 427.880272 -400.11477) (xy 427.880272 -399.828766)
			(xy 427.880706 -399.818602) (xy 427.888498 -399.799825) (xy 427.902883 -399.78546) (xy 427.921669 -399.777693)
			(xy 427.931834 -399.777204) (xy 428.648114 -399.777204) (xy 428.658268 -399.777721) (xy 428.677031 -399.785494)
			(xy 428.691395 -399.799852) (xy 428.699175 -399.818612) (xy 428.699676 -399.828766) (xy 428.699676 -400.11477)
			(xy 428.699882 -400.121642) (xy 428.703481 -400.134905) (xy 428.706788 -400.140932) (xy 428.723114 -400.169291)
			(xy 428.74883 -400.229463) (xy 428.766237 -400.292542) (xy 428.775019 -400.357387) (xy 428.775018 -400.422824)
			(xy 428.766235 -400.487668) (xy 428.748827 -400.550747) (xy 428.72311 -400.610918) (xy 428.706788 -400.63928)
			(xy 428.70348 -400.645308) (xy 428.69987 -400.658569) (xy 428.699676 -400.665442) (xy 428.699676 -401.414742)
			(xy 428.699893 -401.421613) (xy 428.703484 -401.434876) (xy 428.706788 -401.440904) (xy 428.723091 -401.469276)
			(xy 428.748809 -401.529445) (xy 428.766218 -401.592521) (xy 428.775003 -401.657364) (xy 428.775006 -401.722799)
			(xy 428.766225 -401.787642) (xy 428.748821 -401.850719) (xy 428.723108 -401.91089) (xy 428.706788 -401.939252)
			(xy 428.703454 -401.945267) (xy 428.699861 -401.958538) (xy 428.699676 -401.965414) (xy 428.699676 -402.251418)
			(xy 428.699182 -402.261575) (xy 428.691404 -402.280342) (xy 428.677039 -402.294706) (xy 428.658271 -402.302483)
			(xy 428.648114 -402.30298) (xy 427.931834 -402.30298) (xy 427.921667 -402.302509) (xy 427.902876 -402.294738)
			(xy 427.888491 -402.280367) (xy 427.880702 -402.261585) (xy 427.880272 -402.251418) (xy 427.880272 -401.965414)
			(xy 427.880078 -401.958541) (xy 427.876471 -401.945278) (xy 427.87316 -401.939252) (xy 427.856818 -401.910901)
			(xy 427.831102 -401.850728) (xy 427.813695 -401.787647) (xy 427.804913 -401.7228) (xy 426.516167 -401.7228)
			(xy 426.50664 -401.739354) (xy 426.503345 -401.745388) (xy 426.499726 -401.758645) (xy 426.499528 -401.765516)
			(xy 426.499528 -402.514816) (xy 426.499711 -402.52169) (xy 426.503325 -402.534953) (xy 426.50664 -402.540978)
			(xy 426.522922 -402.569361) (xy 426.548645 -402.629527) (xy 426.566058 -402.692601) (xy 426.574847 -402.757442)
			(xy 426.57485 -402.790152) (xy 430.00422 -402.790152) (xy 430.004784 -402.757422) (xy 430.01364 -402.692564)
			(xy 430.031131 -402.629484) (xy 430.056939 -402.569326) (xy 430.073308 -402.540978) (xy 430.076631 -402.534958)
			(xy 430.080231 -402.521691) (xy 430.08042 -402.514816) (xy 430.08042 -401.765516) (xy 430.08022 -401.758643)
			(xy 430.076617 -401.745381) (xy 430.073308 -401.739354) (xy 430.056925 -401.711014) (xy 430.031127 -401.650851)
			(xy 430.013642 -401.587769) (xy 430.004787 -401.52291) (xy 430.00422 -401.49018) (xy 430.004796 -401.457451)
			(xy 430.013649 -401.392593) (xy 430.031136 -401.329513) (xy 430.056941 -401.269354) (xy 430.073308 -401.241006)
			(xy 430.076621 -401.234981) (xy 430.080228 -401.221717) (xy 430.08042 -401.214844) (xy 430.08042 -400.92884)
			(xy 430.080849 -400.918718) (xy 430.088588 -400.900011) (xy 430.102901 -400.885695) (xy 430.121606 -400.877952)
			(xy 430.131728 -400.877532) (xy 430.848008 -400.877532) (xy 430.858135 -400.87791) (xy 430.876845 -400.885667)
			(xy 430.89116 -400.899996) (xy 430.898899 -400.918713) (xy 430.899316 -400.92884) (xy 430.899316 -401.214844)
			(xy 430.899527 -401.221716) (xy 430.903122 -401.234979) (xy 430.906428 -401.241006) (xy 430.922799 -401.269352)
			(xy 430.948599 -401.329513) (xy 430.966087 -401.392593) (xy 430.974946 -401.457451) (xy 430.975516 -401.49018)
			(xy 430.974962 -401.52291) (xy 430.966102 -401.587769) (xy 430.948609 -401.650849) (xy 430.922798 -401.711006)
			(xy 430.915987 -401.7228) (xy 432.204703 -401.7228) (xy 432.204705 -401.657362) (xy 432.213492 -401.592516)
			(xy 432.230903 -401.529437) (xy 432.256624 -401.469265) (xy 432.272948 -401.440904) (xy 432.276257 -401.434877)
			(xy 432.279867 -401.421615) (xy 432.28006 -401.414742) (xy 432.28006 -400.665442) (xy 432.279857 -400.65857)
			(xy 432.276257 -400.645307) (xy 432.272948 -400.63928) (xy 432.256631 -400.610916) (xy 432.230912 -400.550746)
			(xy 432.213503 -400.487667) (xy 432.204719 -400.422823) (xy 432.204718 -400.357387) (xy 432.213501 -400.292543)
			(xy 432.230909 -400.229464) (xy 432.256626 -400.169293) (xy 432.272948 -400.140932) (xy 432.276247 -400.1349)
			(xy 432.279863 -400.121642) (xy 432.28006 -400.11477) (xy 432.28006 -399.828766) (xy 432.280506 -399.818603)
			(xy 432.288296 -399.799829) (xy 432.302676 -399.785464) (xy 432.321459 -399.777695) (xy 432.331622 -399.777204)
			(xy 433.047902 -399.777204) (xy 433.058056 -399.777731) (xy 433.076818 -399.7855) (xy 433.091182 -399.799855)
			(xy 433.098963 -399.818613) (xy 433.099464 -399.828766) (xy 433.099464 -400.11477) (xy 433.099672 -400.121642)
			(xy 433.10327 -400.134905) (xy 433.106576 -400.140932) (xy 433.122903 -400.169291) (xy 433.148619 -400.229463)
			(xy 433.166026 -400.292542) (xy 433.174809 -400.357387) (xy 433.174808 -400.390106) (xy 436.603656 -400.390106)
			(xy 436.607647 -400.327939) (xy 436.619556 -400.266792) (xy 436.639185 -400.207671) (xy 436.666214 -400.151545)
			(xy 436.700198 -400.099336) (xy 436.74058 -400.051901) (xy 436.786696 -400.01002) (xy 436.837788 -399.97438)
			(xy 436.893019 -399.945566) (xy 436.951481 -399.924052) (xy 437.012215 -399.91019) (xy 437.074222 -399.904208)
			(xy 437.136485 -399.906204) (xy 437.197982 -399.916147) (xy 437.257703 -399.933871) (xy 437.314666 -399.959088)
			(xy 437.367937 -399.991381) (xy 437.416642 -400.030221) (xy 437.459979 -400.074971) (xy 437.497239 -400.124895)
			(xy 437.527808 -400.179174) (xy 437.551186 -400.236917) (xy 437.566987 -400.297175) (xy 437.574953 -400.358958)
			(xy 437.575452 -400.390106) (xy 437.574953 -400.421254) (xy 437.566987 -400.483037) (xy 437.551186 -400.543295)
			(xy 437.527808 -400.601038) (xy 437.497239 -400.655317) (xy 437.459979 -400.705241) (xy 437.416642 -400.749991)
			(xy 437.369142 -400.78787) (xy 446.249042 -400.78787) (xy 446.253113 -400.732248) (xy 446.265239 -400.677811)
			(xy 446.285162 -400.62572) (xy 446.312458 -400.577085) (xy 446.346544 -400.532942) (xy 446.386693 -400.494233)
			(xy 446.432051 -400.461782) (xy 446.481651 -400.436281) (xy 446.534435 -400.418274) (xy 446.589278 -400.408144)
			(xy 446.645012 -400.406107) (xy 446.700449 -400.412207) (xy 446.754406 -400.426313) (xy 446.805735 -400.448125)
			(xy 446.853341 -400.477179) (xy 446.896209 -400.512854) (xy 446.933426 -400.554391) (xy 446.964199 -400.600904)
			(xy 446.987871 -400.651401) (xy 447.003939 -400.704808) (xy 447.012059 -400.759984) (xy 447.012568 -400.78787)
			(xy 447.012059 -400.815756) (xy 447.003939 -400.870932) (xy 446.987871 -400.924339) (xy 446.964199 -400.974836)
			(xy 446.933426 -401.021349) (xy 446.896209 -401.062886) (xy 446.853341 -401.098561) (xy 446.805735 -401.127615)
			(xy 446.754406 -401.149427) (xy 446.700449 -401.163533) (xy 446.645012 -401.169633) (xy 446.589278 -401.167596)
			(xy 446.534435 -401.157466) (xy 446.481651 -401.139459) (xy 446.432051 -401.113958) (xy 446.386693 -401.081507)
			(xy 446.346544 -401.042798) (xy 446.312458 -400.998655) (xy 446.285162 -400.95002) (xy 446.265239 -400.897929)
			(xy 446.253113 -400.843492) (xy 446.249042 -400.78787) (xy 437.369142 -400.78787) (xy 437.367937 -400.788831)
			(xy 437.314666 -400.821124) (xy 437.257703 -400.846341) (xy 437.197982 -400.864065) (xy 437.136485 -400.874008)
			(xy 437.074222 -400.876004) (xy 437.012215 -400.870022) (xy 436.951481 -400.85616) (xy 436.893019 -400.834646)
			(xy 436.837788 -400.805832) (xy 436.786696 -400.770192) (xy 436.74058 -400.728311) (xy 436.700198 -400.680876)
			(xy 436.666214 -400.628667) (xy 436.639185 -400.572541) (xy 436.619556 -400.51342) (xy 436.607647 -400.452273)
			(xy 436.603656 -400.390106) (xy 433.174808 -400.390106) (xy 433.174808 -400.422824) (xy 433.166024 -400.487668)
			(xy 433.148616 -400.550747) (xy 433.122898 -400.610919) (xy 433.106576 -400.63928) (xy 433.103267 -400.645307)
			(xy 433.099658 -400.658569) (xy 433.099464 -400.665442) (xy 433.099464 -401.414742) (xy 433.099682 -401.421613)
			(xy 433.103273 -401.434876) (xy 433.106576 -401.440904) (xy 433.122879 -401.469276) (xy 433.148598 -401.529445)
			(xy 433.166007 -401.592521) (xy 433.174793 -401.657364) (xy 433.174795 -401.722799) (xy 433.166015 -401.787642)
			(xy 433.14861 -401.85072) (xy 433.122896 -401.910891) (xy 433.106576 -401.939252) (xy 433.103241 -401.945267)
			(xy 433.099649 -401.958538) (xy 433.099464 -401.965414) (xy 433.099464 -402.251418) (xy 433.098982 -402.261577)
			(xy 433.091202 -402.280346) (xy 433.076833 -402.294711) (xy 433.058061 -402.302485) (xy 433.047902 -402.30298)
			(xy 432.331622 -402.30298) (xy 432.321454 -402.302518) (xy 432.302663 -402.294744) (xy 432.288278 -402.28037)
			(xy 432.28049 -402.261586) (xy 432.28006 -402.251418) (xy 432.28006 -401.965414) (xy 432.279868 -401.958541)
			(xy 432.27626 -401.945278) (xy 432.272948 -401.939252) (xy 432.256607 -401.910901) (xy 432.230891 -401.850728)
			(xy 432.213484 -401.787647) (xy 432.204703 -401.7228) (xy 430.915987 -401.7228) (xy 430.906428 -401.739354)
			(xy 430.903132 -401.745388) (xy 430.899514 -401.758644) (xy 430.899316 -401.765516) (xy 430.899316 -402.514816)
			(xy 430.8995 -402.52169) (xy 430.903113 -402.534953) (xy 430.906428 -402.540978) (xy 430.922787 -402.569331)
			(xy 430.94859 -402.629489) (xy 430.966081 -402.692567) (xy 430.974944 -402.757423) (xy 430.975516 -402.790152)
			(xy 430.974949 -402.822879) (xy 434.404843 -402.822879) (xy 434.404849 -402.757439) (xy 434.413637 -402.692592)
			(xy 434.43105 -402.629512) (xy 434.456772 -402.56934) (xy 434.473096 -402.540978) (xy 434.476418 -402.534957)
			(xy 434.480019 -402.52169) (xy 434.480208 -402.514816) (xy 434.480208 -401.765516) (xy 434.480009 -401.758643)
			(xy 434.476406 -401.74538) (xy 434.473096 -401.739354) (xy 434.456758 -401.711002) (xy 434.431044 -401.650828)
			(xy 434.41364 -401.587747) (xy 434.404859 -401.522902) (xy 434.404861 -401.457464) (xy 434.413647 -401.392619)
			(xy 434.431056 -401.32954) (xy 434.456774 -401.269368) (xy 434.473096 -401.241006) (xy 434.476408 -401.23498)
			(xy 434.480016 -401.221717) (xy 434.480208 -401.214844) (xy 434.480208 -400.92884) (xy 434.480655 -400.918688)
			(xy 434.488438 -400.899934) (xy 434.502828 -400.885609) (xy 434.521616 -400.87791) (xy 434.53177 -400.877532)
			(xy 435.24805 -400.877532) (xy 435.258173 -400.878067) (xy 435.276891 -400.885777) (xy 435.291249 -400.900049)
			(xy 435.299071 -400.918721) (xy 435.299612 -400.92884) (xy 435.299612 -401.214844) (xy 435.299824 -401.221716)
			(xy 435.303418 -401.234979) (xy 435.306724 -401.241006) (xy 435.32303 -401.269376) (xy 435.348752 -401.329545)
			(xy 435.366163 -401.392622) (xy 435.374949 -401.457465) (xy 435.374952 -401.522901) (xy 435.36617 -401.587745)
			(xy 435.348763 -401.650823) (xy 435.331985 -401.690078) (xy 436.603656 -401.690078) (xy 436.607647 -401.627911)
			(xy 436.619556 -401.566764) (xy 436.639185 -401.507643) (xy 436.666214 -401.451517) (xy 436.700198 -401.399308)
			(xy 436.74058 -401.351873) (xy 436.786696 -401.309992) (xy 436.837788 -401.274352) (xy 436.893019 -401.245538)
			(xy 436.951481 -401.224024) (xy 437.012215 -401.210162) (xy 437.074222 -401.20418) (xy 437.136485 -401.206176)
			(xy 437.197982 -401.216119) (xy 437.257703 -401.233843) (xy 437.314666 -401.25906) (xy 437.367937 -401.291353)
			(xy 437.416642 -401.330193) (xy 437.459979 -401.374943) (xy 437.497239 -401.424867) (xy 437.527808 -401.479146)
			(xy 437.532275 -401.49018) (xy 438.803804 -401.49018) (xy 438.807795 -401.428013) (xy 438.819704 -401.366866)
			(xy 438.839333 -401.307745) (xy 438.866362 -401.251619) (xy 438.900346 -401.19941) (xy 438.940728 -401.151975)
			(xy 438.986844 -401.110094) (xy 439.037936 -401.074454) (xy 439.093167 -401.04564) (xy 439.151629 -401.024126)
			(xy 439.212363 -401.010264) (xy 439.27437 -401.004282) (xy 439.336633 -401.006278) (xy 439.39813 -401.016221)
			(xy 439.457851 -401.033945) (xy 439.514814 -401.059162) (xy 439.568085 -401.091455) (xy 439.61679 -401.130295)
			(xy 439.660127 -401.175045) (xy 439.697387 -401.224969) (xy 439.727956 -401.279248) (xy 439.751334 -401.336991)
			(xy 439.760066 -401.370292) (xy 448.261484 -401.370292) (xy 448.265555 -401.31467) (xy 448.277681 -401.260233)
			(xy 448.297604 -401.208142) (xy 448.3249 -401.159507) (xy 448.358986 -401.115364) (xy 448.399135 -401.076655)
			(xy 448.444493 -401.044204) (xy 448.494093 -401.018703) (xy 448.546877 -401.000696) (xy 448.60172 -400.990566)
			(xy 448.657454 -400.988529) (xy 448.712891 -400.994629) (xy 448.766848 -401.008735) (xy 448.818177 -401.030547)
			(xy 448.865783 -401.059601) (xy 448.908651 -401.095276) (xy 448.945868 -401.136813) (xy 448.976641 -401.183326)
			(xy 449.000313 -401.233823) (xy 449.016381 -401.28723) (xy 449.024501 -401.342406) (xy 449.02501 -401.370292)
			(xy 449.024501 -401.398178) (xy 449.016381 -401.453354) (xy 449.000313 -401.506761) (xy 448.976641 -401.557258)
			(xy 448.945868 -401.603771) (xy 448.908651 -401.645308) (xy 448.865783 -401.680983) (xy 448.818177 -401.710037)
			(xy 448.766848 -401.731849) (xy 448.712891 -401.745955) (xy 448.657454 -401.752055) (xy 448.60172 -401.750018)
			(xy 448.546877 -401.739888) (xy 448.494093 -401.721881) (xy 448.444493 -401.69638) (xy 448.399135 -401.663929)
			(xy 448.358986 -401.62522) (xy 448.3249 -401.581077) (xy 448.297604 -401.532442) (xy 448.277681 -401.480351)
			(xy 448.265555 -401.425914) (xy 448.261484 -401.370292) (xy 439.760066 -401.370292) (xy 439.767135 -401.397249)
			(xy 439.775101 -401.459032) (xy 439.7756 -401.49018) (xy 439.775101 -401.521328) (xy 439.767135 -401.583111)
			(xy 439.751334 -401.643369) (xy 439.727956 -401.701112) (xy 439.697387 -401.755391) (xy 439.660127 -401.805315)
			(xy 439.61679 -401.850065) (xy 439.568085 -401.888905) (xy 439.514814 -401.921198) (xy 439.457851 -401.946415)
			(xy 439.39813 -401.964139) (xy 439.336633 -401.974082) (xy 439.27437 -401.976078) (xy 439.212363 -401.970096)
			(xy 439.151629 -401.956234) (xy 439.093167 -401.93472) (xy 439.037936 -401.905906) (xy 438.986844 -401.870266)
			(xy 438.940728 -401.828385) (xy 438.900346 -401.78095) (xy 438.866362 -401.728741) (xy 438.839333 -401.672615)
			(xy 438.819704 -401.613494) (xy 438.807795 -401.552347) (xy 438.803804 -401.49018) (xy 437.532275 -401.49018)
			(xy 437.551186 -401.536889) (xy 437.566987 -401.597147) (xy 437.574953 -401.65893) (xy 437.575452 -401.690078)
			(xy 437.574953 -401.721226) (xy 437.566987 -401.783009) (xy 437.551186 -401.843267) (xy 437.527808 -401.90101)
			(xy 437.497239 -401.955289) (xy 437.459979 -402.005213) (xy 437.416642 -402.049963) (xy 437.367937 -402.088803)
			(xy 437.314666 -402.121096) (xy 437.257703 -402.146313) (xy 437.197982 -402.164037) (xy 437.136485 -402.17398)
			(xy 437.074222 -402.175976) (xy 437.012215 -402.169994) (xy 436.951481 -402.156132) (xy 436.893019 -402.134618)
			(xy 436.837788 -402.105804) (xy 436.786696 -402.070164) (xy 436.74058 -402.028283) (xy 436.700198 -401.980848)
			(xy 436.666214 -401.928639) (xy 436.639185 -401.872513) (xy 436.619556 -401.813392) (xy 436.607647 -401.752245)
			(xy 436.603656 -401.690078) (xy 435.331985 -401.690078) (xy 435.323046 -401.710993) (xy 435.306724 -401.739354)
			(xy 435.303427 -401.745388) (xy 435.29981 -401.758644) (xy 435.299612 -401.765516) (xy 435.299612 -402.514816)
			(xy 435.299796 -402.52169) (xy 435.303409 -402.534953) (xy 435.306724 -402.540978) (xy 435.323007 -402.569361)
			(xy 435.34873 -402.629527) (xy 435.366144 -402.692601) (xy 435.374933 -402.757442) (xy 435.374936 -402.790152)
			(xy 438.803804 -402.790152) (xy 438.807795 -402.727985) (xy 438.819704 -402.666838) (xy 438.839333 -402.607717)
			(xy 438.866362 -402.551591) (xy 438.900346 -402.499382) (xy 438.940728 -402.451947) (xy 438.986844 -402.410066)
			(xy 439.037936 -402.374426) (xy 439.093167 -402.345612) (xy 439.151629 -402.324098) (xy 439.212363 -402.310236)
			(xy 439.27437 -402.304254) (xy 439.336633 -402.30625) (xy 439.39813 -402.316193) (xy 439.457851 -402.333917)
			(xy 439.514814 -402.359134) (xy 439.568085 -402.391427) (xy 439.61679 -402.430267) (xy 439.660127 -402.475017)
			(xy 439.697387 -402.524941) (xy 439.727956 -402.57922) (xy 439.751334 -402.636963) (xy 439.767135 -402.697221)
			(xy 439.775101 -402.759004) (xy 439.7756 -402.790152) (xy 439.775101 -402.8213) (xy 439.767135 -402.883083)
			(xy 439.751334 -402.943341) (xy 439.727956 -403.001084) (xy 439.697387 -403.055363) (xy 439.660127 -403.105287)
			(xy 439.61679 -403.150037) (xy 439.568085 -403.188877) (xy 439.514814 -403.22117) (xy 439.457851 -403.246387)
			(xy 439.39813 -403.264111) (xy 439.336633 -403.274054) (xy 439.27437 -403.27605) (xy 439.212363 -403.270068)
			(xy 439.151629 -403.256206) (xy 439.093167 -403.234692) (xy 439.037936 -403.205878) (xy 438.986844 -403.170238)
			(xy 438.940728 -403.128357) (xy 438.900346 -403.080922) (xy 438.866362 -403.028713) (xy 438.839333 -402.972587)
			(xy 438.819704 -402.913466) (xy 438.807795 -402.852319) (xy 438.803804 -402.790152) (xy 435.374936 -402.790152)
			(xy 435.374939 -402.822876) (xy 435.366161 -402.887718) (xy 435.348757 -402.950795) (xy 435.323044 -403.010965)
			(xy 435.306724 -403.039326) (xy 435.303402 -403.045347) (xy 435.2998 -403.058613) (xy 435.299612 -403.065488)
			(xy 435.299612 -403.351492) (xy 435.299172 -403.361644) (xy 435.291381 -403.380394) (xy 435.27699 -403.394717)
			(xy 435.258204 -403.402419) (xy 435.24805 -403.4028) (xy 434.53177 -403.4028) (xy 434.521646 -403.402299)
			(xy 434.502932 -403.394569) (xy 434.488578 -403.380288) (xy 434.480753 -403.361613) (xy 434.480208 -403.351492)
			(xy 434.480208 -403.065488) (xy 434.48002 -403.058615) (xy 434.476409 -403.045352) (xy 434.473096 -403.039326)
			(xy 434.456734 -403.010987) (xy 434.431023 -402.95081) (xy 434.413621 -402.887727) (xy 434.404843 -402.822879)
			(xy 430.974949 -402.822879) (xy 430.974949 -402.822881) (xy 430.966093 -402.88774) (xy 430.948603 -402.95082)
			(xy 430.922796 -403.010978) (xy 430.906428 -403.039326) (xy 430.903106 -403.045347) (xy 430.899504 -403.058614)
			(xy 430.899316 -403.065488) (xy 430.899316 -403.351492) (xy 430.898809 -403.361598) (xy 430.891077 -403.380273)
			(xy 430.876787 -403.394568) (xy 430.858114 -403.402306) (xy 430.848008 -403.4028) (xy 430.131728 -403.4028)
			(xy 430.121607 -403.402361) (xy 430.102904 -403.394622) (xy 430.088589 -403.380313) (xy 430.080843 -403.361613)
			(xy 430.08042 -403.351492) (xy 430.08042 -403.065488) (xy 430.08023 -403.058615) (xy 430.07662 -403.045352)
			(xy 430.073308 -403.039326) (xy 430.056954 -403.010971) (xy 430.031149 -402.950813) (xy 430.013656 -402.887736)
			(xy 430.004792 -402.82288) (xy 430.00422 -402.790152) (xy 426.57485 -402.790152) (xy 426.574853 -402.822876)
			(xy 426.566075 -402.887718) (xy 426.548672 -402.950795) (xy 426.52296 -403.010965) (xy 426.50664 -403.039326)
			(xy 426.503319 -403.045348) (xy 426.499717 -403.058614) (xy 426.499528 -403.065488) (xy 426.499528 -403.351492)
			(xy 426.499072 -403.361642) (xy 426.491285 -403.380389) (xy 426.476899 -403.394712) (xy 426.458118 -403.402417)
			(xy 426.447966 -403.4028) (xy 425.731686 -403.4028) (xy 425.721563 -403.402286) (xy 425.70285 -403.394561)
			(xy 425.688495 -403.380284) (xy 425.68067 -403.361612) (xy 425.680124 -403.351492) (xy 425.680124 -403.065488)
			(xy 425.679934 -403.058615) (xy 425.676324 -403.045352) (xy 425.673012 -403.039326) (xy 425.65665 -403.010987)
			(xy 425.630938 -402.95081) (xy 425.613535 -402.887727) (xy 425.604757 -402.822879) (xy 422.174863 -402.822879)
			(xy 422.174863 -402.822881) (xy 422.166008 -402.887739) (xy 422.148518 -402.95082) (xy 422.122712 -403.010978)
			(xy 422.106344 -403.039326) (xy 422.103024 -403.045348) (xy 422.099421 -403.058614) (xy 422.099232 -403.065488)
			(xy 422.099232 -403.351492) (xy 422.098709 -403.361596) (xy 422.09098 -403.380268) (xy 422.076695 -403.394562)
			(xy 422.058028 -403.402303) (xy 422.047924 -403.4028) (xy 421.331644 -403.4028) (xy 421.321524 -403.402348)
			(xy 421.302822 -403.394614) (xy 421.288506 -403.380308) (xy 421.280759 -403.361611) (xy 421.280336 -403.351492)
			(xy 421.280336 -403.065488) (xy 421.280144 -403.058615) (xy 421.276535 -403.045352) (xy 421.273224 -403.039326)
			(xy 421.256871 -403.01097) (xy 421.231066 -402.950813) (xy 421.213572 -402.887736) (xy 421.204708 -402.82288)
			(xy 421.204136 -402.790152) (xy 414.525968 -402.790152) (xy 414.525968 -405.622714) (xy 419.004836 -405.622714)
			(xy 419.004837 -405.557276) (xy 419.013622 -405.492431) (xy 419.031032 -405.429352) (xy 419.056752 -405.369181)
			(xy 419.073076 -405.34082) (xy 419.076382 -405.334791) (xy 419.079994 -405.321531) (xy 419.080188 -405.314658)
			(xy 419.080188 -404.565358) (xy 419.079975 -404.558486) (xy 419.076381 -404.545223) (xy 419.073076 -404.539196)
			(xy 419.056771 -404.510825) (xy 419.03105 -404.450656) (xy 419.013638 -404.38758) (xy 419.004852 -404.322737)
			(xy 419.004849 -404.257301) (xy 419.013631 -404.192457) (xy 419.031037 -404.129379) (xy 419.056754 -404.069209)
			(xy 419.073076 -404.040848) (xy 419.076408 -404.034832) (xy 419.080003 -404.021562) (xy 419.080188 -404.014686)
			(xy 419.080188 -403.728682) (xy 419.08055 -403.718503) (xy 419.088351 -403.699698) (xy 419.102756 -403.685313)
			(xy 419.12157 -403.677537) (xy 419.13175 -403.67712) (xy 419.84803 -403.67712) (xy 419.858187 -403.677608)
			(xy 419.876954 -403.685389) (xy 419.891317 -403.699756) (xy 419.899094 -403.718524) (xy 419.899592 -403.728682)
			(xy 419.899592 -404.014686) (xy 419.89979 -404.021559) (xy 419.903394 -404.034822) (xy 419.906704 -404.040848)
			(xy 419.923044 -404.069199) (xy 419.948757 -404.129373) (xy 419.966162 -404.192454) (xy 419.974942 -404.2573)
			(xy 419.974939 -404.322738) (xy 419.966154 -404.387583) (xy 419.948745 -404.450662) (xy 419.923026 -404.510834)
			(xy 419.906704 -404.539196) (xy 419.903391 -404.545221) (xy 419.899784 -404.558485) (xy 419.899592 -404.565358)
			(xy 419.899592 -405.314658) (xy 419.899801 -405.32153) (xy 419.903398 -405.334793) (xy 419.906704 -405.34082)
			(xy 419.92302 -405.369185) (xy 419.948736 -405.429355) (xy 419.966143 -405.492433) (xy 419.974926 -405.557277)
			(xy 419.974927 -405.622713) (xy 419.966145 -405.687557) (xy 419.948739 -405.750635) (xy 419.923024 -405.810806)
			(xy 419.906704 -405.839168) (xy 419.903401 -405.845198) (xy 419.899788 -405.858458) (xy 419.899592 -405.86533)
			(xy 419.899592 -406.151334) (xy 419.899095 -406.16149) (xy 419.891315 -406.180254) (xy 419.876951 -406.194617)
			(xy 419.858186 -406.202396) (xy 419.84803 -406.202896) (xy 419.13175 -406.202896) (xy 419.121586 -406.202396)
			(xy 419.102799 -406.194634) (xy 419.088413 -406.180272) (xy 419.08062 -406.161497) (xy 419.080188 -406.151334)
			(xy 419.080188 -405.86533) (xy 419.079986 -405.858458) (xy 419.076385 -405.845195) (xy 419.073076 -405.839168)
			(xy 419.056748 -405.81081) (xy 419.031028 -405.750638) (xy 419.01362 -405.687559) (xy 419.004836 -405.622714)
			(xy 414.525968 -405.622714) (xy 414.525968 -406.690068) (xy 421.204136 -406.690068) (xy 421.204718 -406.657339)
			(xy 421.213571 -406.592482) (xy 421.231056 -406.529402) (xy 421.256858 -406.469243) (xy 421.273224 -406.440894)
			(xy 421.276543 -406.434871) (xy 421.280145 -406.421606) (xy 421.280336 -406.414732) (xy 421.280336 -405.665432)
			(xy 421.280127 -405.65856) (xy 421.27653 -405.645297) (xy 421.273224 -405.63927) (xy 421.256849 -405.610926)
			(xy 421.231049 -405.550765) (xy 421.213562 -405.487684) (xy 421.204705 -405.422825) (xy 421.204136 -405.390096)
			(xy 421.204686 -405.357366) (xy 421.213548 -405.292507) (xy 421.231043 -405.229428) (xy 421.256854 -405.16927)
			(xy 421.273224 -405.140922) (xy 421.276533 -405.134894) (xy 421.280142 -405.121633) (xy 421.280336 -405.11476)
			(xy 421.280336 -404.828756) (xy 421.28075 -404.81864) (xy 421.288509 -404.799954) (xy 421.302828 -404.785659)
			(xy 421.321527 -404.777933) (xy 421.331644 -404.777448) (xy 422.047924 -404.777448) (xy 422.058028 -404.777964)
			(xy 422.076697 -404.7857) (xy 422.090989 -404.799986) (xy 422.098732 -404.818652) (xy 422.099232 -404.828756)
			(xy 422.099232 -405.11476) (xy 422.099435 -405.121632) (xy 422.103035 -405.134895) (xy 422.106344 -405.140922)
			(xy 422.122713 -405.169269) (xy 422.148515 -405.229429) (xy 422.166004 -405.292509) (xy 422.174863 -405.357367)
			(xy 422.175432 -405.390096) (xy 422.174883 -405.422826) (xy 422.166021 -405.487685) (xy 422.148526 -405.550765)
			(xy 422.131694 -405.589994) (xy 423.404284 -405.589994) (xy 423.404872 -405.557265) (xy 423.413721 -405.492408)
			(xy 423.431205 -405.429328) (xy 423.457007 -405.369169) (xy 423.473372 -405.34082) (xy 423.476678 -405.334791)
			(xy 423.48029 -405.321531) (xy 423.480484 -405.314658) (xy 423.480484 -404.565358) (xy 423.480272 -404.558486)
			(xy 423.476678 -404.545223) (xy 423.473372 -404.539196) (xy 423.457002 -404.510849) (xy 423.431202 -404.450689)
			(xy 423.413714 -404.387608) (xy 423.404854 -404.322751) (xy 423.404284 -404.290022) (xy 423.404839 -404.257292)
			(xy 423.413698 -404.192434) (xy 423.431192 -404.129353) (xy 423.457002 -404.069196) (xy 423.473372 -404.040848)
			(xy 423.476703 -404.034831) (xy 423.480299 -404.021561) (xy 423.480484 -404.014686) (xy 423.480484 -403.728682)
			(xy 423.480913 -403.718549) (xy 423.488655 -403.699819) (xy 423.502959 -403.685461) (xy 423.521661 -403.677651)
			(xy 423.531792 -403.67712) (xy 424.248072 -403.67712) (xy 424.258227 -403.677545) (xy 424.276983 -403.685335)
			(xy 424.291308 -403.699731) (xy 424.299005 -403.718525) (xy 424.29938 -403.728682) (xy 424.29938 -404.014686)
			(xy 424.29958 -404.021559) (xy 424.303183 -404.034821) (xy 424.306492 -404.040848) (xy 424.322876 -404.069187)
			(xy 424.348674 -404.12935) (xy 424.366158 -404.192433) (xy 424.375013 -404.257292) (xy 424.37558 -404.290022)
			(xy 424.375004 -404.322751) (xy 424.366152 -404.387609) (xy 424.348665 -404.450689) (xy 424.322859 -404.510848)
			(xy 424.306492 -404.539196) (xy 424.303178 -404.545221) (xy 424.299572 -404.558484) (xy 424.29938 -404.565358)
			(xy 424.29938 -405.314658) (xy 424.29959 -405.32153) (xy 424.303186 -405.334793) (xy 424.306492 -405.34082)
			(xy 424.322865 -405.369165) (xy 424.348665 -405.429326) (xy 424.366153 -405.492407) (xy 424.375011 -405.557265)
			(xy 424.37558 -405.589994) (xy 424.375037 -405.622724) (xy 424.366174 -405.687583) (xy 424.348678 -405.750664)
			(xy 424.322864 -405.810821) (xy 424.306492 -405.839168) (xy 424.303188 -405.845198) (xy 424.299576 -405.858458)
			(xy 424.29938 -405.86533) (xy 424.29938 -406.151334) (xy 424.298902 -406.16146) (xy 424.291167 -406.180179)
			(xy 424.276878 -406.194533) (xy 424.258196 -406.202355) (xy 424.248072 -406.202896) (xy 423.531792 -406.202896)
			(xy 423.521637 -406.202485) (xy 423.502884 -406.194686) (xy 423.48856 -406.180286) (xy 423.480862 -406.161491)
			(xy 423.480484 -406.151334) (xy 423.480484 -405.86533) (xy 423.480282 -405.858457) (xy 423.476681 -405.845195)
			(xy 423.473372 -405.839168) (xy 423.456991 -405.810827) (xy 423.431194 -405.750664) (xy 423.413708 -405.687582)
			(xy 423.404852 -405.622724) (xy 423.404284 -405.589994) (xy 422.131694 -405.589994) (xy 422.122715 -405.610922)
			(xy 422.106344 -405.63927) (xy 422.103043 -405.645302) (xy 422.099428 -405.65856) (xy 422.099232 -405.665432)
			(xy 422.099232 -406.414732) (xy 422.099408 -406.421606) (xy 422.103027 -406.434869) (xy 422.106344 -406.440894)
			(xy 422.122702 -406.469248) (xy 422.148507 -406.529405) (xy 422.165999 -406.592483) (xy 422.174861 -406.657339)
			(xy 422.175432 -406.690068) (xy 422.17487 -406.722792) (xy 425.604766 -406.722792) (xy 425.60477 -406.657353)
			(xy 425.613557 -406.592507) (xy 425.630968 -406.529428) (xy 425.656688 -406.469256) (xy 425.673012 -406.440894)
			(xy 425.67633 -406.434871) (xy 425.679933 -406.421606) (xy 425.680124 -406.414732) (xy 425.680124 -405.665432)
			(xy 425.679917 -405.65856) (xy 425.676319 -405.645297) (xy 425.673012 -405.63927) (xy 425.656687 -405.61091)
			(xy 425.630971 -405.550738) (xy 425.613565 -405.487659) (xy 425.604782 -405.422815) (xy 425.604782 -405.357378)
			(xy 425.613566 -405.292534) (xy 425.630974 -405.229455) (xy 425.65669 -405.169284) (xy 425.673012 -405.140922)
			(xy 425.67632 -405.134894) (xy 425.67993 -405.121633) (xy 425.680124 -405.11476) (xy 425.680124 -404.828756)
			(xy 425.680486 -404.818596) (xy 425.688301 -404.799838) (xy 425.702716 -404.785515) (xy 425.721523 -404.777822)
			(xy 425.731686 -404.777448) (xy 426.447966 -404.777448) (xy 426.458091 -404.777955) (xy 426.476813 -404.785673)
			(xy 426.491171 -404.799953) (xy 426.49899 -404.818633) (xy 426.499528 -404.828756) (xy 426.499528 -405.11476)
			(xy 426.499732 -405.121632) (xy 426.503332 -405.134895) (xy 426.50664 -405.140922) (xy 426.522959 -405.169285)
			(xy 426.548679 -405.229455) (xy 426.566088 -405.292534) (xy 426.574872 -405.357378) (xy 426.574873 -405.422815)
			(xy 426.566089 -405.487659) (xy 426.548681 -405.550738) (xy 426.522963 -405.610909) (xy 426.516169 -405.622714)
			(xy 427.804922 -405.622714) (xy 427.804923 -405.557276) (xy 427.813708 -405.492431) (xy 427.831117 -405.429352)
			(xy 427.856837 -405.369181) (xy 427.87316 -405.34082) (xy 427.876464 -405.33479) (xy 427.880077 -405.321531)
			(xy 427.880272 -405.314658) (xy 427.880272 -404.565358) (xy 427.880061 -404.558486) (xy 427.876466 -404.545223)
			(xy 427.87316 -404.539196) (xy 427.856856 -404.510825) (xy 427.831135 -404.450656) (xy 427.813724 -404.387579)
			(xy 427.804938 -404.322737) (xy 427.804936 -404.257301) (xy 427.813717 -404.192458) (xy 427.831123 -404.12938)
			(xy 427.856839 -404.069209) (xy 427.87316 -404.040848) (xy 427.87649 -404.034831) (xy 427.880086 -404.021561)
			(xy 427.880272 -404.014686) (xy 427.880272 -403.728682) (xy 427.88065 -403.718505) (xy 427.888447 -403.699703)
			(xy 427.902847 -403.685318) (xy 427.921657 -403.67754) (xy 427.931834 -403.67712) (xy 428.648114 -403.67712)
			(xy 428.65827 -403.677622) (xy 428.677036 -403.685397) (xy 428.6914 -403.69976) (xy 428.699178 -403.718526)
			(xy 428.699676 -403.728682) (xy 428.699676 -404.014686) (xy 428.699876 -404.021559) (xy 428.703479 -404.034821)
			(xy 428.706788 -404.040848) (xy 428.723128 -404.069199) (xy 428.748842 -404.129373) (xy 428.766248 -404.192454)
			(xy 428.775028 -404.2573) (xy 428.775026 -404.322738) (xy 428.76624 -404.387583) (xy 428.74883 -404.450663)
			(xy 428.723111 -404.510834) (xy 428.706788 -404.539196) (xy 428.703474 -404.545221) (xy 428.699868 -404.558484)
			(xy 428.699676 -404.565358) (xy 428.699676 -405.314658) (xy 428.699887 -405.32153) (xy 428.703482 -405.334793)
			(xy 428.706788 -405.34082) (xy 428.723104 -405.369184) (xy 428.748821 -405.429355) (xy 428.766229 -405.492433)
			(xy 428.775012 -405.557277) (xy 428.775013 -405.622713) (xy 428.766231 -405.687557) (xy 428.748824 -405.750635)
			(xy 428.723109 -405.810806) (xy 428.706788 -405.839168) (xy 428.703484 -405.845198) (xy 428.699872 -405.858458)
			(xy 428.699676 -405.86533) (xy 428.699676 -406.151334) (xy 428.699195 -406.161492) (xy 428.691412 -406.180259)
			(xy 428.677043 -406.194623) (xy 428.658272 -406.202399) (xy 428.648114 -406.202896) (xy 427.931834 -406.202896)
			(xy 427.921683 -406.202339) (xy 427.902921 -406.194583) (xy 427.888556 -406.180236) (xy 427.880774 -406.161485)
			(xy 427.880272 -406.151334) (xy 427.880272 -405.86533) (xy 427.880072 -405.858457) (xy 427.87647 -405.845194)
			(xy 427.87316 -405.839168) (xy 427.856832 -405.81081) (xy 427.831114 -405.750638) (xy 427.813705 -405.687559)
			(xy 427.804922 -405.622714) (xy 426.516169 -405.622714) (xy 426.50664 -405.63927) (xy 426.503339 -405.645302)
			(xy 426.499724 -405.65856) (xy 426.499528 -405.665432) (xy 426.499528 -406.414732) (xy 426.499704 -406.421606)
			(xy 426.503323 -406.434869) (xy 426.50664 -406.440894) (xy 426.522936 -406.46927) (xy 426.548657 -406.529437)
			(xy 426.566069 -406.592513) (xy 426.574856 -406.657355) (xy 426.574858 -406.690068) (xy 430.00422 -406.690068)
			(xy 430.004791 -406.657339) (xy 430.013645 -406.59248) (xy 430.031134 -406.5294) (xy 430.05694 -406.469242)
			(xy 430.073308 -406.440894) (xy 430.076625 -406.434871) (xy 430.080229 -406.421606) (xy 430.08042 -406.414732)
			(xy 430.08042 -405.665432) (xy 430.080213 -405.65856) (xy 430.076615 -405.645297) (xy 430.073308 -405.63927)
			(xy 430.056931 -405.610927) (xy 430.031132 -405.550765) (xy 430.013645 -405.487684) (xy 430.004788 -405.422826)
			(xy 430.00422 -405.390096) (xy 430.004759 -405.357365) (xy 430.013622 -405.292506) (xy 430.03112 -405.229426)
			(xy 430.056936 -405.169269) (xy 430.073308 -405.140922) (xy 430.076615 -405.134894) (xy 430.080226 -405.121633)
			(xy 430.08042 -405.11476) (xy 430.08042 -404.828756) (xy 430.08085 -404.818642) (xy 430.088605 -404.799959)
			(xy 430.102919 -404.785665) (xy 430.121613 -404.777935) (xy 430.131728 -404.777448) (xy 430.848008 -404.777448)
			(xy 430.858111 -404.777977) (xy 430.876779 -404.785708) (xy 430.891072 -404.799991) (xy 430.898815 -404.818654)
			(xy 430.899316 -404.828756) (xy 430.899316 -405.11476) (xy 430.899521 -405.121632) (xy 430.90312 -405.134895)
			(xy 430.906428 -405.140922) (xy 430.922805 -405.169265) (xy 430.948603 -405.229427) (xy 430.96609 -405.292508)
			(xy 430.974947 -405.357366) (xy 430.975516 -405.390096) (xy 430.974969 -405.422826) (xy 430.966107 -405.487685)
			(xy 430.948612 -405.550765) (xy 430.922799 -405.610923) (xy 430.91599 -405.622713) (xy 432.204712 -405.622713)
			(xy 432.204713 -405.557276) (xy 432.213497 -405.492431) (xy 432.230906 -405.429352) (xy 432.256625 -405.369181)
			(xy 432.272948 -405.34082) (xy 432.276251 -405.33479) (xy 432.279865 -405.32153) (xy 432.28006 -405.314658)
			(xy 432.28006 -404.565358) (xy 432.279851 -404.558486) (xy 432.276255 -404.545223) (xy 432.272948 -404.539196)
			(xy 432.256644 -404.510825) (xy 432.230924 -404.450656) (xy 432.213514 -404.387579) (xy 432.204728 -404.322737)
			(xy 432.204725 -404.257301) (xy 432.213506 -404.192458) (xy 432.230912 -404.12938) (xy 432.256627 -404.069209)
			(xy 432.272948 -404.040848) (xy 432.276277 -404.03483) (xy 432.279874 -404.021561) (xy 432.28006 -404.014686)
			(xy 432.28006 -403.728682) (xy 432.28045 -403.718507) (xy 432.288245 -403.699707) (xy 432.302641 -403.685322)
			(xy 432.321446 -403.677542) (xy 432.331622 -403.67712) (xy 433.047902 -403.67712) (xy 433.058058 -403.677631)
			(xy 433.076823 -403.685403) (xy 433.091188 -403.699763) (xy 433.098965 -403.718526) (xy 433.099464 -403.728682)
			(xy 433.099464 -404.014686) (xy 433.099666 -404.021558) (xy 433.103268 -404.034821) (xy 433.106576 -404.040848)
			(xy 433.122916 -404.069199) (xy 433.148631 -404.129373) (xy 433.166037 -404.192454) (xy 433.174818 -404.2573)
			(xy 433.174816 -404.290022) (xy 436.603656 -404.290022) (xy 436.607647 -404.227855) (xy 436.619556 -404.166708)
			(xy 436.639185 -404.107587) (xy 436.666214 -404.051461) (xy 436.700198 -403.999252) (xy 436.74058 -403.951817)
			(xy 436.786696 -403.909936) (xy 436.837788 -403.874296) (xy 436.893019 -403.845482) (xy 436.951481 -403.823968)
			(xy 437.012215 -403.810106) (xy 437.074222 -403.804124) (xy 437.136485 -403.80612) (xy 437.197982 -403.816063)
			(xy 437.257703 -403.833787) (xy 437.314666 -403.859004) (xy 437.367937 -403.891297) (xy 437.416642 -403.930137)
			(xy 437.459979 -403.974887) (xy 437.497239 -404.024811) (xy 437.507272 -404.042626) (xy 446.93027 -404.042626)
			(xy 446.934341 -403.987004) (xy 446.946467 -403.932567) (xy 446.96639 -403.880476) (xy 446.993686 -403.831841)
			(xy 447.027772 -403.787698) (xy 447.067921 -403.748989) (xy 447.113279 -403.716538) (xy 447.162879 -403.691037)
			(xy 447.215663 -403.67303) (xy 447.270506 -403.6629) (xy 447.32624 -403.660863) (xy 447.381677 -403.666963)
			(xy 447.435634 -403.681069) (xy 447.486963 -403.702881) (xy 447.534569 -403.731935) (xy 447.577437 -403.76761)
			(xy 447.614654 -403.809147) (xy 447.645427 -403.85566) (xy 447.669099 -403.906157) (xy 447.685167 -403.959564)
			(xy 447.693287 -404.01474) (xy 447.693796 -404.042626) (xy 447.693287 -404.070512) (xy 447.685167 -404.125688)
			(xy 447.669099 -404.179095) (xy 447.645427 -404.229592) (xy 447.614654 -404.276105) (xy 447.577437 -404.317642)
			(xy 447.534569 -404.353317) (xy 447.486963 -404.382371) (xy 447.435634 -404.404183) (xy 447.381677 -404.418289)
			(xy 447.32624 -404.424389) (xy 447.270506 -404.422352) (xy 447.215663 -404.412222) (xy 447.162879 -404.394215)
			(xy 447.113279 -404.368714) (xy 447.067921 -404.336263) (xy 447.027772 -404.297554) (xy 446.993686 -404.253411)
			(xy 446.96639 -404.204776) (xy 446.946467 -404.152685) (xy 446.934341 -404.098248) (xy 446.93027 -404.042626)
			(xy 437.507272 -404.042626) (xy 437.527808 -404.07909) (xy 437.551186 -404.136833) (xy 437.566987 -404.197091)
			(xy 437.574953 -404.258874) (xy 437.575452 -404.290022) (xy 437.574953 -404.32117) (xy 437.566987 -404.382953)
			(xy 437.551186 -404.443211) (xy 437.527808 -404.500954) (xy 437.497239 -404.555233) (xy 437.459979 -404.605157)
			(xy 437.416642 -404.649907) (xy 437.367937 -404.688747) (xy 437.314666 -404.72104) (xy 437.257703 -404.746257)
			(xy 437.197982 -404.763981) (xy 437.136485 -404.773924) (xy 437.074222 -404.77592) (xy 437.012215 -404.769938)
			(xy 436.951481 -404.756076) (xy 436.893019 -404.734562) (xy 436.837788 -404.705748) (xy 436.786696 -404.670108)
			(xy 436.74058 -404.628227) (xy 436.700198 -404.580792) (xy 436.666214 -404.528583) (xy 436.639185 -404.472457)
			(xy 436.619556 -404.413336) (xy 436.607647 -404.352189) (xy 436.603656 -404.290022) (xy 433.174816 -404.290022)
			(xy 433.174815 -404.322738) (xy 433.166029 -404.387583) (xy 433.148619 -404.450663) (xy 433.122899 -404.510835)
			(xy 433.106576 -404.539196) (xy 433.103261 -404.54522) (xy 433.099656 -404.558484) (xy 433.099464 -404.565358)
			(xy 433.099464 -405.314658) (xy 433.099676 -405.32153) (xy 433.103271 -405.334792) (xy 433.106576 -405.34082)
			(xy 433.122893 -405.369184) (xy 433.14861 -405.429355) (xy 433.166018 -405.492433) (xy 433.174802 -405.557277)
			(xy 433.174803 -405.622713) (xy 433.16602 -405.687557) (xy 433.148613 -405.750635) (xy 433.122897 -405.810807)
			(xy 433.106576 -405.839168) (xy 433.103271 -405.845197) (xy 433.09966 -405.858457) (xy 433.099464 -405.86533)
			(xy 433.099464 -406.151334) (xy 433.098995 -406.161494) (xy 433.091209 -406.180263) (xy 433.076836 -406.194627)
			(xy 433.058062 -406.202401) (xy 433.047902 -406.202896) (xy 432.331622 -406.202896) (xy 432.32147 -406.20235)
			(xy 432.302708 -406.194589) (xy 432.288343 -406.180239) (xy 432.280561 -406.161486) (xy 432.28006 -406.151334)
			(xy 432.28006 -405.86533) (xy 432.279862 -405.858457) (xy 432.276258 -405.845194) (xy 432.272948 -405.839168)
			(xy 432.25662 -405.81081) (xy 432.230903 -405.750638) (xy 432.213495 -405.687559) (xy 432.204712 -405.622713)
			(xy 430.91599 -405.622713) (xy 430.906428 -405.63927) (xy 430.903126 -405.645301) (xy 430.899512 -405.65856)
			(xy 430.899316 -405.665432) (xy 430.899316 -406.414732) (xy 430.899494 -406.421606) (xy 430.903111 -406.434869)
			(xy 430.906428 -406.440894) (xy 430.922794 -406.469243) (xy 430.948595 -406.529403) (xy 430.966084 -406.592482)
			(xy 430.974945 -406.657339) (xy 430.975516 -406.690068) (xy 430.974956 -406.722792) (xy 434.404852 -406.722792)
			(xy 434.404856 -406.657353) (xy 434.413643 -406.592508) (xy 434.431053 -406.529428) (xy 434.456773 -406.469256)
			(xy 434.473096 -406.440894) (xy 434.476413 -406.43487) (xy 434.480017 -406.421606) (xy 434.480208 -406.414732)
			(xy 434.480208 -405.665432) (xy 434.480003 -405.65856) (xy 434.476404 -405.645297) (xy 434.473096 -405.63927)
			(xy 434.456772 -405.61091) (xy 434.431057 -405.550738) (xy 434.413651 -405.487659) (xy 434.404868 -405.422815)
			(xy 434.404869 -405.357378) (xy 434.413652 -405.292534) (xy 434.431059 -405.229455) (xy 434.456775 -405.169284)
			(xy 434.473096 -405.140922) (xy 434.476403 -405.134893) (xy 434.480013 -405.121633) (xy 434.480208 -405.11476)
			(xy 434.480208 -404.828756) (xy 434.480586 -404.818598) (xy 434.488397 -404.799843) (xy 434.502807 -404.785521)
			(xy 434.52161 -404.777824) (xy 434.53177 -404.777448) (xy 435.24805 -404.777448) (xy 435.258175 -404.777968)
			(xy 435.276896 -404.785681) (xy 435.291254 -404.799957) (xy 435.299074 -404.818634) (xy 435.299612 -404.828756)
			(xy 435.299612 -405.11476) (xy 435.299818 -405.121632) (xy 435.303417 -405.134895) (xy 435.306724 -405.140922)
			(xy 435.323044 -405.169285) (xy 435.348764 -405.229455) (xy 435.366174 -405.292534) (xy 435.374958 -405.357378)
			(xy 435.374959 -405.422815) (xy 435.366175 -405.48766) (xy 435.348766 -405.550738) (xy 435.331987 -405.589994)
			(xy 436.603656 -405.589994) (xy 436.607647 -405.527827) (xy 436.619556 -405.46668) (xy 436.639185 -405.407559)
			(xy 436.666214 -405.351433) (xy 436.700198 -405.299224) (xy 436.74058 -405.251789) (xy 436.786696 -405.209908)
			(xy 436.837788 -405.174268) (xy 436.893019 -405.145454) (xy 436.951481 -405.12394) (xy 437.012215 -405.110078)
			(xy 437.074222 -405.104096) (xy 437.136485 -405.106092) (xy 437.197982 -405.116035) (xy 437.257703 -405.133759)
			(xy 437.314666 -405.158976) (xy 437.367937 -405.191269) (xy 437.416642 -405.230109) (xy 437.459979 -405.274859)
			(xy 437.497239 -405.324783) (xy 437.527808 -405.379062) (xy 437.532275 -405.390096) (xy 438.803804 -405.390096)
			(xy 438.807795 -405.327929) (xy 438.819704 -405.266782) (xy 438.839333 -405.207661) (xy 438.866362 -405.151535)
			(xy 438.900346 -405.099326) (xy 438.940728 -405.051891) (xy 438.986844 -405.01001) (xy 439.037936 -404.97437)
			(xy 439.093167 -404.945556) (xy 439.151629 -404.924042) (xy 439.212363 -404.91018) (xy 439.27437 -404.904198)
			(xy 439.336633 -404.906194) (xy 439.39813 -404.916137) (xy 439.457851 -404.933861) (xy 439.514814 -404.959078)
			(xy 439.568085 -404.991371) (xy 439.61679 -405.030211) (xy 439.660127 -405.074961) (xy 439.697387 -405.124885)
			(xy 439.727956 -405.179164) (xy 439.751334 -405.236907) (xy 439.767135 -405.297165) (xy 439.775101 -405.358948)
			(xy 439.7756 -405.390096) (xy 439.775101 -405.421244) (xy 439.767135 -405.483027) (xy 439.751334 -405.543285)
			(xy 439.727956 -405.601028) (xy 439.697387 -405.655307) (xy 439.660127 -405.705231) (xy 439.61679 -405.749981)
			(xy 439.568085 -405.788821) (xy 439.514814 -405.821114) (xy 439.457851 -405.846331) (xy 439.39813 -405.864055)
			(xy 439.336633 -405.873998) (xy 439.27437 -405.875994) (xy 439.212363 -405.870012) (xy 439.151629 -405.85615)
			(xy 439.093167 -405.834636) (xy 439.037936 -405.805822) (xy 438.986844 -405.770182) (xy 438.940728 -405.728301)
			(xy 438.900346 -405.680866) (xy 438.866362 -405.628657) (xy 438.839333 -405.572531) (xy 438.819704 -405.51341)
			(xy 438.807795 -405.452263) (xy 438.803804 -405.390096) (xy 437.532275 -405.390096) (xy 437.551186 -405.436805)
			(xy 437.566987 -405.497063) (xy 437.574953 -405.558846) (xy 437.575452 -405.589994) (xy 437.574953 -405.621142)
			(xy 437.566987 -405.682925) (xy 437.551186 -405.743183) (xy 437.527808 -405.800926) (xy 437.497239 -405.855205)
			(xy 437.459979 -405.905129) (xy 437.416642 -405.949879) (xy 437.367937 -405.988719) (xy 437.314666 -406.021012)
			(xy 437.257703 -406.046229) (xy 437.197982 -406.063953) (xy 437.136485 -406.073896) (xy 437.074222 -406.075892)
			(xy 437.012215 -406.06991) (xy 436.951481 -406.056048) (xy 436.893019 -406.034534) (xy 436.837788 -406.00572)
			(xy 436.786696 -405.97008) (xy 436.74058 -405.928199) (xy 436.700198 -405.880764) (xy 436.666214 -405.828555)
			(xy 436.639185 -405.772429) (xy 436.619556 -405.713308) (xy 436.607647 -405.652161) (xy 436.603656 -405.589994)
			(xy 435.331987 -405.589994) (xy 435.323047 -405.610909) (xy 435.306724 -405.63927) (xy 435.303422 -405.645301)
			(xy 435.299808 -405.65856) (xy 435.299612 -405.665432) (xy 435.299612 -406.153366) (xy 446.64452 -406.153366)
			(xy 446.648591 -406.097744) (xy 446.660717 -406.043307) (xy 446.68064 -405.991216) (xy 446.707936 -405.942581)
			(xy 446.742022 -405.898438) (xy 446.782171 -405.859729) (xy 446.827529 -405.827278) (xy 446.877129 -405.801777)
			(xy 446.929913 -405.78377) (xy 446.984756 -405.77364) (xy 447.04049 -405.771603) (xy 447.095927 -405.777703)
			(xy 447.149884 -405.791809) (xy 447.201213 -405.813621) (xy 447.248819 -405.842675) (xy 447.291687 -405.87835)
			(xy 447.328904 -405.919887) (xy 447.359677 -405.9664) (xy 447.383349 -406.016897) (xy 447.399417 -406.070304)
			(xy 447.407537 -406.12548) (xy 447.408046 -406.153366) (xy 447.407537 -406.181252) (xy 447.399417 -406.236428)
			(xy 447.387573 -406.275794) (xy 447.938142 -406.275794) (xy 447.942213 -406.220172) (xy 447.954339 -406.165735)
			(xy 447.974262 -406.113644) (xy 448.001558 -406.065009) (xy 448.035644 -406.020866) (xy 448.075793 -405.982157)
			(xy 448.121151 -405.949706) (xy 448.170751 -405.924205) (xy 448.223535 -405.906198) (xy 448.278378 -405.896068)
			(xy 448.334112 -405.894031) (xy 448.389549 -405.900131) (xy 448.443506 -405.914237) (xy 448.494835 -405.936049)
			(xy 448.542441 -405.965103) (xy 448.585309 -406.000778) (xy 448.622526 -406.042315) (xy 448.653299 -406.088828)
			(xy 448.676971 -406.139325) (xy 448.693039 -406.192732) (xy 448.701159 -406.247908) (xy 448.701668 -406.275794)
			(xy 448.701159 -406.30368) (xy 448.693039 -406.358856) (xy 448.676971 -406.412263) (xy 448.653299 -406.46276)
			(xy 448.622526 -406.509273) (xy 448.585309 -406.55081) (xy 448.542441 -406.586485) (xy 448.494835 -406.615539)
			(xy 448.443506 -406.637351) (xy 448.389549 -406.651457) (xy 448.334112 -406.657557) (xy 448.278378 -406.65552)
			(xy 448.223535 -406.64539) (xy 448.170751 -406.627383) (xy 448.121151 -406.601882) (xy 448.075793 -406.569431)
			(xy 448.035644 -406.530722) (xy 448.001558 -406.486579) (xy 447.974262 -406.437944) (xy 447.954339 -406.385853)
			(xy 447.942213 -406.331416) (xy 447.938142 -406.275794) (xy 447.387573 -406.275794) (xy 447.383349 -406.289835)
			(xy 447.359677 -406.340332) (xy 447.328904 -406.386845) (xy 447.291687 -406.428382) (xy 447.248819 -406.464057)
			(xy 447.201213 -406.493111) (xy 447.149884 -406.514923) (xy 447.095927 -406.529029) (xy 447.04049 -406.535129)
			(xy 446.984756 -406.533092) (xy 446.929913 -406.522962) (xy 446.877129 -406.504955) (xy 446.827529 -406.479454)
			(xy 446.782171 -406.447003) (xy 446.742022 -406.408294) (xy 446.707936 -406.364151) (xy 446.68064 -406.315516)
			(xy 446.660717 -406.263425) (xy 446.648591 -406.208988) (xy 446.64452 -406.153366) (xy 435.299612 -406.153366)
			(xy 435.299612 -406.414732) (xy 435.29979 -406.421606) (xy 435.303408 -406.434869) (xy 435.306724 -406.440894)
			(xy 435.32302 -406.46927) (xy 435.348742 -406.529437) (xy 435.366155 -406.592513) (xy 435.374942 -406.657355)
			(xy 435.374944 -406.690068) (xy 438.803804 -406.690068) (xy 438.807795 -406.627901) (xy 438.819704 -406.566754)
			(xy 438.839333 -406.507633) (xy 438.866362 -406.451507) (xy 438.900346 -406.399298) (xy 438.940728 -406.351863)
			(xy 438.986844 -406.309982) (xy 439.037936 -406.274342) (xy 439.093167 -406.245528) (xy 439.151629 -406.224014)
			(xy 439.212363 -406.210152) (xy 439.27437 -406.20417) (xy 439.336633 -406.206166) (xy 439.39813 -406.216109)
			(xy 439.457851 -406.233833) (xy 439.514814 -406.25905) (xy 439.568085 -406.291343) (xy 439.61679 -406.330183)
			(xy 439.660127 -406.374933) (xy 439.697387 -406.424857) (xy 439.727956 -406.479136) (xy 439.751334 -406.536879)
			(xy 439.767135 -406.597137) (xy 439.775101 -406.65892) (xy 439.7756 -406.690068) (xy 439.775101 -406.721216)
			(xy 439.767135 -406.782999) (xy 439.751334 -406.843257) (xy 439.727956 -406.901) (xy 439.697387 -406.955279)
			(xy 439.660127 -407.005203) (xy 439.61679 -407.049953) (xy 439.568085 -407.088793) (xy 439.514814 -407.121086)
			(xy 439.457851 -407.146303) (xy 439.39813 -407.164027) (xy 439.336633 -407.17397) (xy 439.27437 -407.175966)
			(xy 439.212363 -407.169984) (xy 439.151629 -407.156122) (xy 439.093167 -407.134608) (xy 439.037936 -407.105794)
			(xy 438.986844 -407.070154) (xy 438.940728 -407.028273) (xy 438.900346 -406.980838) (xy 438.866362 -406.928629)
			(xy 438.839333 -406.872503) (xy 438.819704 -406.813382) (xy 438.807795 -406.752235) (xy 438.803804 -406.690068)
			(xy 435.374944 -406.690068) (xy 435.374946 -406.72279) (xy 435.366166 -406.787633) (xy 435.348761 -406.850711)
			(xy 435.323045 -406.910881) (xy 435.306724 -406.939242) (xy 435.303396 -406.94526) (xy 435.299798 -406.958529)
			(xy 435.299612 -406.965404) (xy 435.299612 -407.251408) (xy 435.299185 -407.261561) (xy 435.291389 -407.280311)
			(xy 435.276994 -407.294634) (xy 435.258205 -407.302335) (xy 435.24805 -407.302716) (xy 434.53177 -407.302716)
			(xy 434.521636 -407.302297) (xy 434.502906 -407.294551) (xy 434.488549 -407.280244) (xy 434.480739 -407.26154)
			(xy 434.480208 -407.251408) (xy 434.480208 -406.965404) (xy 434.480014 -406.958531) (xy 434.476407 -406.945268)
			(xy 434.473096 -406.939242) (xy 434.456748 -406.910895) (xy 434.431035 -406.85072) (xy 434.413632 -406.787639)
			(xy 434.404852 -406.722792) (xy 430.974956 -406.722792) (xy 430.974956 -406.722798) (xy 430.966099 -406.787656)
			(xy 430.948606 -406.850736) (xy 430.922797 -406.910894) (xy 430.906428 -406.939242) (xy 430.9031 -406.94526)
			(xy 430.899502 -406.958529) (xy 430.899316 -406.965404) (xy 430.899316 -407.251408) (xy 430.898822 -407.261515)
			(xy 430.891084 -407.28019) (xy 430.87679 -407.294484) (xy 430.858115 -407.302222) (xy 430.848008 -407.302716)
			(xy 430.131728 -407.302716) (xy 430.121609 -407.302262) (xy 430.102909 -407.294526) (xy 430.088595 -407.280221)
			(xy 430.080845 -407.261526) (xy 430.08042 -407.251408) (xy 430.08042 -406.965404) (xy 430.080224 -406.958531)
			(xy 430.076618 -406.945268) (xy 430.073308 -406.939242) (xy 430.05696 -406.910883) (xy 430.031154 -406.850727)
			(xy 430.013659 -406.787651) (xy 430.004793 -406.722796) (xy 430.00422 -406.690068) (xy 426.574858 -406.690068)
			(xy 426.57486 -406.72279) (xy 426.56608 -406.787633) (xy 426.548675 -406.850711) (xy 426.522961 -406.910881)
			(xy 426.50664 -406.939242) (xy 426.503314 -406.945261) (xy 426.499715 -406.958529) (xy 426.499528 -406.965404)
			(xy 426.499528 -407.251408) (xy 426.499085 -407.261559) (xy 426.491292 -407.280306) (xy 426.476903 -407.294628)
			(xy 426.458119 -407.302333) (xy 426.447966 -407.302716) (xy 425.731686 -407.302716) (xy 425.721553 -407.302283)
			(xy 425.702823 -407.294543) (xy 425.688466 -407.28024) (xy 425.680655 -407.261539) (xy 425.680124 -407.251408)
			(xy 425.680124 -406.965404) (xy 425.679928 -406.958531) (xy 425.676322 -406.945268) (xy 425.673012 -406.939242)
			(xy 425.656663 -406.910895) (xy 425.63095 -406.850721) (xy 425.613546 -406.787639) (xy 425.604766 -406.722792)
			(xy 422.17487 -406.722792) (xy 422.17487 -406.722798) (xy 422.166013 -406.787656) (xy 422.148521 -406.850736)
			(xy 422.122713 -406.910894) (xy 422.106344 -406.939242) (xy 422.103018 -406.945261) (xy 422.099419 -406.958529)
			(xy 422.099232 -406.965404) (xy 422.099232 -407.251408) (xy 422.098722 -407.261513) (xy 422.090988 -407.280185)
			(xy 422.076699 -407.294479) (xy 422.058029 -407.302219) (xy 422.047924 -407.302716) (xy 421.331644 -407.302716)
			(xy 421.321526 -407.302248) (xy 421.302827 -407.294518) (xy 421.288512 -407.280217) (xy 421.280762 -407.261525)
			(xy 421.280336 -407.251408) (xy 421.280336 -406.965404) (xy 421.280138 -406.958531) (xy 421.276533 -406.945269)
			(xy 421.273224 -406.939242) (xy 421.256877 -406.910882) (xy 421.23107 -406.850727) (xy 421.213575 -406.78765)
			(xy 421.204709 -406.722796) (xy 421.204136 -406.690068) (xy 414.525968 -406.690068) (xy 414.525968 -409.522889)
			(xy 419.004819 -409.522889) (xy 419.004823 -409.457449) (xy 419.013612 -409.392602) (xy 419.031026 -409.329522)
			(xy 419.05675 -409.269351) (xy 419.073076 -409.24099) (xy 419.076393 -409.234966) (xy 419.079998 -409.221702)
			(xy 419.080188 -409.214828) (xy 419.080188 -408.465528) (xy 419.079987 -408.458655) (xy 419.076385 -408.445393)
			(xy 419.073076 -408.439366) (xy 419.056746 -408.411009) (xy 419.031027 -408.350837) (xy 419.013618 -408.287758)
			(xy 419.004835 -408.222912) (xy 419.004836 -408.157474) (xy 419.013621 -408.092629) (xy 419.031031 -408.02955)
			(xy 419.056752 -407.969379) (xy 419.073076 -407.941018) (xy 419.076383 -407.934989) (xy 419.079994 -407.921729)
			(xy 419.080188 -407.914856) (xy 419.080188 -407.628852) (xy 419.080582 -407.618696) (xy 419.088391 -407.599945)
			(xy 419.102796 -407.585624) (xy 419.121592 -407.577924) (xy 419.13175 -407.577544) (xy 419.84803 -407.577544)
			(xy 419.858159 -407.578002) (xy 419.876882 -407.58574) (xy 419.891237 -407.600035) (xy 419.899055 -407.618725)
			(xy 419.899592 -407.628852) (xy 419.899592 -407.914856) (xy 419.899802 -407.921728) (xy 419.903398 -407.934991)
			(xy 419.906704 -407.941018) (xy 419.923018 -407.969383) (xy 419.948734 -408.029554) (xy 419.966141 -408.092632)
			(xy 419.974925 -408.157475) (xy 419.974926 -408.222911) (xy 419.966144 -408.287755) (xy 419.948739 -408.350833)
			(xy 419.923024 -408.411004) (xy 419.906704 -408.439366) (xy 419.903402 -408.445397) (xy 419.899788 -408.458656)
			(xy 419.899592 -408.465528) (xy 419.899592 -409.214828) (xy 419.899774 -409.221702) (xy 419.903389 -409.234965)
			(xy 419.906704 -409.24099) (xy 419.922994 -409.269369) (xy 419.948713 -409.329536) (xy 419.966122 -409.392611)
			(xy 419.974909 -409.457452) (xy 419.974913 -409.522886) (xy 419.966135 -409.587728) (xy 419.948733 -409.650805)
			(xy 419.923022 -409.710976) (xy 419.906704 -409.739338) (xy 419.903376 -409.745356) (xy 419.899779 -409.758625)
			(xy 419.899592 -409.7655) (xy 419.899592 -410.051504) (xy 419.899181 -410.061659) (xy 419.891383 -410.080413)
			(xy 419.876983 -410.094737) (xy 419.858187 -410.102435) (xy 419.84803 -410.102812) (xy 419.13175 -410.102812)
			(xy 419.121633 -410.102234) (xy 419.102923 -410.094532) (xy 419.088567 -410.080274) (xy 419.080736 -410.061618)
			(xy 419.080188 -410.051504) (xy 419.080188 -409.7655) (xy 419.079997 -409.758627) (xy 419.076388 -409.745364)
			(xy 419.073076 -409.739338) (xy 419.056722 -409.710994) (xy 419.031005 -409.650819) (xy 419.013599 -409.587737)
			(xy 419.004819 -409.522889) (xy 414.525968 -409.522889) (xy 414.525968 -410.589984) (xy 421.204136 -410.589984)
			(xy 421.204725 -410.557255) (xy 421.213576 -410.492398) (xy 421.231059 -410.429318) (xy 421.256859 -410.369159)
			(xy 421.273224 -410.34081) (xy 421.276537 -410.334785) (xy 421.280143 -410.321521) (xy 421.280336 -410.314648)
			(xy 421.280336 -409.565348) (xy 421.280121 -409.558476) (xy 421.276528 -409.545214) (xy 421.273224 -409.539186)
			(xy 421.256855 -409.510839) (xy 421.231054 -409.450679) (xy 421.213565 -409.387598) (xy 421.204706 -409.322741)
			(xy 421.204136 -409.290012) (xy 421.204693 -409.257282) (xy 421.213553 -409.192424) (xy 421.231046 -409.129344)
			(xy 421.256855 -409.069186) (xy 421.273224 -409.040838) (xy 421.276527 -409.034808) (xy 421.28014 -409.021548)
			(xy 421.280336 -409.014676) (xy 421.280336 -408.728672) (xy 421.280694 -408.718543) (xy 421.288458 -408.699832)
			(xy 421.302793 -408.685517) (xy 421.321515 -408.67778) (xy 421.331644 -408.677364) (xy 422.047924 -408.677364)
			(xy 422.05803 -408.677864) (xy 422.076702 -408.685603) (xy 422.090994 -408.699895) (xy 422.098735 -408.718566)
			(xy 422.099232 -408.728672) (xy 422.099232 -409.014676) (xy 422.099429 -409.021549) (xy 422.103033 -409.034812)
			(xy 422.106344 -409.040838) (xy 422.122719 -409.069182) (xy 422.14852 -409.129343) (xy 422.166007 -409.192424)
			(xy 422.174864 -409.257282) (xy 422.175432 -409.290012) (xy 422.174845 -409.322741) (xy 422.165995 -409.387598)
			(xy 422.14851 -409.450678) (xy 422.131575 -409.490164) (xy 423.404284 -409.490164) (xy 423.404858 -409.457435)
			(xy 423.413712 -409.392577) (xy 423.4312 -409.329497) (xy 423.457005 -409.269338) (xy 423.473372 -409.24099)
			(xy 423.476688 -409.234966) (xy 423.480293 -409.221702) (xy 423.480484 -409.214828) (xy 423.480484 -408.465528)
			(xy 423.480283 -408.458655) (xy 423.476681 -408.445393) (xy 423.473372 -408.439366) (xy 423.45699 -408.411026)
			(xy 423.431193 -408.350863) (xy 423.413708 -408.287781) (xy 423.404852 -408.222922) (xy 423.404284 -408.190192)
			(xy 423.404871 -408.157463) (xy 423.413721 -408.092606) (xy 423.431205 -408.029526) (xy 423.457006 -407.969367)
			(xy 423.473372 -407.941018) (xy 423.476678 -407.934989) (xy 423.48029 -407.921729) (xy 423.480484 -407.914856)
			(xy 423.480484 -407.628852) (xy 423.480946 -407.618742) (xy 423.488696 -407.600066) (xy 423.503 -407.585774)
			(xy 423.521682 -407.578038) (xy 423.531792 -407.577544) (xy 424.248072 -407.577544) (xy 424.258172 -407.578106)
			(xy 424.276839 -407.585825) (xy 424.291133 -407.600097) (xy 424.298879 -407.618753) (xy 424.29938 -407.628852)
			(xy 424.29938 -407.914856) (xy 424.299591 -407.921728) (xy 424.303186 -407.934991) (xy 424.306492 -407.941018)
			(xy 424.322864 -407.969364) (xy 424.348664 -408.029524) (xy 424.366152 -408.092605) (xy 424.375011 -408.157463)
			(xy 424.37558 -408.190192) (xy 424.375036 -408.222922) (xy 424.366174 -408.287781) (xy 424.348677 -408.350862)
			(xy 424.322864 -408.411019) (xy 424.306492 -408.439366) (xy 424.303189 -408.445396) (xy 424.299576 -408.458656)
			(xy 424.29938 -408.465528) (xy 424.29938 -409.214828) (xy 424.299564 -409.221702) (xy 424.303178 -409.234964)
			(xy 424.306492 -409.24099) (xy 424.322853 -409.269342) (xy 424.348656 -409.3295) (xy 424.366147 -409.392579)
			(xy 424.375009 -409.457435) (xy 424.37558 -409.490164) (xy 424.375023 -409.522894) (xy 424.366165 -409.587753)
			(xy 424.348672 -409.650833) (xy 424.322862 -409.71099) (xy 424.306492 -409.739338) (xy 424.303163 -409.745356)
			(xy 424.299567 -409.758625) (xy 424.29938 -409.7655) (xy 424.29938 -410.051504) (xy 424.298987 -410.061629)
			(xy 424.291234 -410.080337) (xy 424.27691 -410.094651) (xy 424.258197 -410.102393) (xy 424.248072 -410.102812)
			(xy 423.531792 -410.102812) (xy 423.521684 -410.102322) (xy 423.503008 -410.094584) (xy 423.488714 -410.080288)
			(xy 423.480978 -410.061612) (xy 423.480484 -410.051504) (xy 423.480484 -409.7655) (xy 423.480294 -409.758627)
			(xy 423.476684 -409.745364) (xy 423.473372 -409.739338) (xy 423.457019 -409.710982) (xy 423.431215 -409.650825)
			(xy 423.413722 -409.587747) (xy 423.404857 -409.522892) (xy 423.404284 -409.490164) (xy 422.131575 -409.490164)
			(xy 422.122709 -409.510837) (xy 422.106344 -409.539186) (xy 422.103038 -409.545215) (xy 422.099426 -409.558475)
			(xy 422.099232 -409.565348) (xy 422.099232 -410.314648) (xy 422.09944 -410.32152) (xy 422.103037 -410.334783)
			(xy 422.106344 -410.34081) (xy 422.122708 -410.36916) (xy 422.148512 -410.429319) (xy 422.166002 -410.492398)
			(xy 422.174862 -410.557255) (xy 422.175432 -410.589984) (xy 422.174877 -410.622705) (xy 425.604775 -410.622705)
			(xy 425.604777 -410.557268) (xy 425.613562 -410.492422) (xy 425.630971 -410.429343) (xy 425.65669 -410.369172)
			(xy 425.673012 -410.34081) (xy 425.676324 -410.334784) (xy 425.679931 -410.321521) (xy 425.680124 -410.314648)
			(xy 425.680124 -409.565348) (xy 425.679911 -409.558476) (xy 425.676317 -409.545214) (xy 425.673012 -409.539186)
			(xy 425.656701 -409.510819) (xy 425.630984 -409.450649) (xy 425.613575 -409.387571) (xy 425.604791 -409.322728)
			(xy 425.60479 -409.257293) (xy 425.613571 -409.192449) (xy 425.630977 -409.129371) (xy 425.656691 -409.0692)
			(xy 425.673012 -409.040838) (xy 425.676314 -409.034807) (xy 425.679927 -409.021548) (xy 425.680124 -409.014676)
			(xy 425.680124 -408.728672) (xy 425.680499 -408.718513) (xy 425.688308 -408.699755) (xy 425.70272 -408.685432)
			(xy 425.721525 -408.677738) (xy 425.731686 -408.677364) (xy 426.447966 -408.677364) (xy 426.458093 -408.677855)
			(xy 426.476818 -408.685576) (xy 426.491177 -408.699862) (xy 426.498993 -408.718547) (xy 426.499528 -408.728672)
			(xy 426.499528 -409.014676) (xy 426.499726 -409.021549) (xy 426.50333 -409.034812) (xy 426.50664 -409.040838)
			(xy 426.522973 -409.069193) (xy 426.548691 -409.129366) (xy 426.566099 -409.192446) (xy 426.574881 -409.257291)
			(xy 426.57488 -409.322729) (xy 426.566094 -409.387575) (xy 426.548684 -409.450654) (xy 426.522964 -409.510825)
			(xy 426.51602 -409.522889) (xy 427.804905 -409.522889) (xy 427.804909 -409.457449) (xy 427.813698 -409.392603)
			(xy 427.831111 -409.329523) (xy 427.856835 -409.269351) (xy 427.87316 -409.24099) (xy 427.876475 -409.234965)
			(xy 427.880081 -409.221702) (xy 427.880272 -409.214828) (xy 427.880272 -408.465528) (xy 427.880073 -408.458655)
			(xy 427.87647 -408.445392) (xy 427.87316 -408.439366) (xy 427.85683 -408.411009) (xy 427.831112 -408.350837)
			(xy 427.813704 -408.287757) (xy 427.804921 -408.222912) (xy 427.804922 -408.157474) (xy 427.813707 -408.092629)
			(xy 427.831117 -408.02955) (xy 427.856837 -407.969379) (xy 427.87316 -407.941018) (xy 427.876465 -407.934989)
			(xy 427.880077 -407.921729) (xy 427.880272 -407.914856) (xy 427.880272 -407.628852) (xy 427.880682 -407.618698)
			(xy 427.888488 -407.59995) (xy 427.902887 -407.58563) (xy 427.921678 -407.577927) (xy 427.931834 -407.577544)
			(xy 428.648114 -407.577544) (xy 428.658242 -407.578015) (xy 428.676964 -407.585749) (xy 428.69132 -407.600039)
			(xy 428.699138 -407.618726) (xy 428.699676 -407.628852) (xy 428.699676 -407.914856) (xy 428.699888 -407.921728)
			(xy 428.703483 -407.93499) (xy 428.706788 -407.941018) (xy 428.723103 -407.969383) (xy 428.748819 -408.029554)
			(xy 428.766227 -408.092632) (xy 428.775011 -408.157475) (xy 428.775012 -408.222911) (xy 428.76623 -408.287755)
			(xy 428.748824 -408.350833) (xy 428.723109 -408.411004) (xy 428.706788 -408.439366) (xy 428.703485 -408.445396)
			(xy 428.699872 -408.458656) (xy 428.699676 -408.465528) (xy 428.699676 -409.214828) (xy 428.69986 -409.221702)
			(xy 428.703474 -409.234964) (xy 428.706788 -409.24099) (xy 428.723079 -409.269368) (xy 428.748798 -409.329536)
			(xy 428.766208 -409.392611) (xy 428.774995 -409.457452) (xy 428.774999 -409.522886) (xy 428.766221 -409.587728)
			(xy 428.748818 -409.650806) (xy 428.723107 -409.710977) (xy 428.706788 -409.739338) (xy 428.703459 -409.745356)
			(xy 428.699863 -409.758625) (xy 428.699676 -409.7655) (xy 428.699676 -410.051504) (xy 428.699281 -410.061661)
			(xy 428.69148 -410.080418) (xy 428.677074 -410.094742) (xy 428.658274 -410.102438) (xy 428.648114 -410.102812)
			(xy 427.931834 -410.102812) (xy 427.921716 -410.102247) (xy 427.903005 -410.09454) (xy 427.88865 -410.080278)
			(xy 427.88082 -410.061619) (xy 427.880272 -410.051504) (xy 427.880272 -409.7655) (xy 427.880083 -409.758626)
			(xy 427.876473 -409.745364) (xy 427.87316 -409.739338) (xy 427.856807 -409.710994) (xy 427.831091 -409.650819)
			(xy 427.813685 -409.587737) (xy 427.804905 -409.522889) (xy 426.51602 -409.522889) (xy 426.50664 -409.539186)
			(xy 426.503334 -409.545215) (xy 426.499722 -409.558475) (xy 426.499528 -409.565348) (xy 426.499528 -410.314648)
			(xy 426.499736 -410.32152) (xy 426.503333 -410.334783) (xy 426.50664 -410.34081) (xy 426.522949 -410.369179)
			(xy 426.548669 -410.429348) (xy 426.56608 -410.492425) (xy 426.574865 -410.557268) (xy 426.574866 -410.589984)
			(xy 430.00422 -410.589984) (xy 430.004798 -410.557255) (xy 430.01365 -410.492397) (xy 430.031136 -410.429317)
			(xy 430.056941 -410.369158) (xy 430.073308 -410.34081) (xy 430.07662 -410.334784) (xy 430.080227 -410.321521)
			(xy 430.08042 -410.314648) (xy 430.08042 -409.565348) (xy 430.080207 -409.558476) (xy 430.076613 -409.545214)
			(xy 430.073308 -409.539186) (xy 430.056938 -409.510839) (xy 430.031137 -409.450679) (xy 430.013648 -409.387599)
			(xy 430.00479 -409.322741) (xy 430.00422 -409.290012) (xy 430.004766 -409.257282) (xy 430.013627 -409.192423)
			(xy 430.031123 -409.129343) (xy 430.056937 -409.069185) (xy 430.073308 -409.040838) (xy 430.07661 -409.034807)
			(xy 430.080223 -409.021548) (xy 430.08042 -409.014676) (xy 430.08042 -408.728672) (xy 430.080863 -408.718559)
			(xy 430.088613 -408.699876) (xy 430.102923 -408.685582) (xy 430.121614 -408.677852) (xy 430.131728 -408.677364)
			(xy 430.848008 -408.677364) (xy 430.858113 -408.677878) (xy 430.876784 -408.685611) (xy 430.891077 -408.699899)
			(xy 430.898818 -408.718567) (xy 430.899316 -408.728672) (xy 430.899316 -409.014676) (xy 430.899515 -409.021549)
			(xy 430.903118 -409.034812) (xy 430.906428 -409.040838) (xy 430.922811 -409.069177) (xy 430.948608 -409.129341)
			(xy 430.966093 -409.192423) (xy 430.974948 -409.257282) (xy 430.975516 -409.290012) (xy 430.974931 -409.322741)
			(xy 430.966081 -409.387598) (xy 430.948596 -409.450678) (xy 430.922794 -409.510837) (xy 430.915836 -409.522889)
			(xy 432.204695 -409.522889) (xy 432.204699 -409.457449) (xy 432.213487 -409.392603) (xy 432.2309 -409.329523)
			(xy 432.256623 -409.269351) (xy 432.272948 -409.24099) (xy 432.276262 -409.234965) (xy 432.279869 -409.221702)
			(xy 432.28006 -409.214828) (xy 432.28006 -408.465528) (xy 432.279862 -408.458655) (xy 432.276259 -408.445392)
			(xy 432.272948 -408.439366) (xy 432.256619 -408.411009) (xy 432.230901 -408.350837) (xy 432.213494 -408.287757)
			(xy 432.204711 -408.222912) (xy 432.204712 -408.157474) (xy 432.213496 -408.092629) (xy 432.230906 -408.02955)
			(xy 432.256625 -407.969379) (xy 432.272948 -407.941018) (xy 432.276252 -407.934988) (xy 432.279865 -407.921729)
			(xy 432.28006 -407.914856) (xy 432.28006 -407.628852) (xy 432.280482 -407.6187) (xy 432.288286 -407.599954)
			(xy 432.302681 -407.585634) (xy 432.321468 -407.577929) (xy 432.331622 -407.577544) (xy 433.047902 -407.577544)
			(xy 433.058029 -407.578025) (xy 433.076751 -407.585754) (xy 433.091108 -407.600042) (xy 433.098926 -407.618727)
			(xy 433.099464 -407.628852) (xy 433.099464 -407.914856) (xy 433.099677 -407.921728) (xy 433.103271 -407.93499)
			(xy 433.106576 -407.941018) (xy 433.122891 -407.969383) (xy 433.148608 -408.029554) (xy 433.166017 -408.092631)
			(xy 433.174801 -408.157475) (xy 433.174801 -408.190192) (xy 436.603656 -408.190192) (xy 436.607647 -408.128025)
			(xy 436.619556 -408.066878) (xy 436.639185 -408.007757) (xy 436.666214 -407.951631) (xy 436.700198 -407.899422)
			(xy 436.74058 -407.851987) (xy 436.786696 -407.810106) (xy 436.837788 -407.774466) (xy 436.893019 -407.745652)
			(xy 436.951481 -407.724138) (xy 437.012215 -407.710276) (xy 437.074222 -407.704294) (xy 437.136485 -407.70629)
			(xy 437.197982 -407.716233) (xy 437.257703 -407.733957) (xy 437.314666 -407.759174) (xy 437.367937 -407.791467)
			(xy 437.416642 -407.830307) (xy 437.459979 -407.875057) (xy 437.497239 -407.924981) (xy 437.527808 -407.97926)
			(xy 437.551186 -408.037003) (xy 437.566987 -408.097261) (xy 437.574953 -408.159044) (xy 437.575452 -408.190192)
			(xy 437.574953 -408.22134) (xy 437.566987 -408.283123) (xy 437.551186 -408.343381) (xy 437.527808 -408.401124)
			(xy 437.497239 -408.455403) (xy 437.459979 -408.505327) (xy 437.416642 -408.550077) (xy 437.367937 -408.588917)
			(xy 437.314666 -408.62121) (xy 437.257703 -408.646427) (xy 437.197982 -408.664151) (xy 437.136485 -408.674094)
			(xy 437.074222 -408.67609) (xy 437.012215 -408.670108) (xy 436.951481 -408.656246) (xy 436.893019 -408.634732)
			(xy 436.837788 -408.605918) (xy 436.786696 -408.570278) (xy 436.74058 -408.528397) (xy 436.700198 -408.480962)
			(xy 436.666214 -408.428753) (xy 436.639185 -408.372627) (xy 436.619556 -408.313506) (xy 436.607647 -408.252359)
			(xy 436.603656 -408.190192) (xy 433.174801 -408.190192) (xy 433.174802 -408.222911) (xy 433.16602 -408.287755)
			(xy 433.148613 -408.350833) (xy 433.122897 -408.411005) (xy 433.106576 -408.439366) (xy 433.103272 -408.445396)
			(xy 433.09966 -408.458656) (xy 433.099464 -408.465528) (xy 433.099464 -409.214828) (xy 433.09965 -409.221702)
			(xy 433.103263 -409.234964) (xy 433.106576 -409.24099) (xy 433.122867 -409.269368) (xy 433.148587 -409.329536)
			(xy 433.165998 -409.392611) (xy 433.174785 -409.457452) (xy 433.174789 -409.522886) (xy 433.16601 -409.587729)
			(xy 433.148607 -409.650806) (xy 433.122895 -409.710977) (xy 433.106576 -409.739338) (xy 433.103246 -409.745355)
			(xy 433.09965 -409.758625) (xy 433.099464 -409.7655) (xy 433.099464 -410.051504) (xy 433.099081 -410.061663)
			(xy 433.091277 -410.080422) (xy 433.076868 -410.094747) (xy 433.058063 -410.10244) (xy 433.047902 -410.102812)
			(xy 432.331622 -410.102812) (xy 432.321503 -410.102257) (xy 432.302792 -410.094546) (xy 432.288437 -410.080281)
			(xy 432.280608 -410.06162) (xy 432.28006 -410.051504) (xy 432.28006 -409.7655) (xy 432.279873 -409.758626)
			(xy 432.276262 -409.745363) (xy 432.272948 -409.739338) (xy 432.256595 -409.710994) (xy 432.23088 -409.650819)
			(xy 432.213475 -409.587736) (xy 432.204695 -409.522889) (xy 430.915836 -409.522889) (xy 430.906428 -409.539186)
			(xy 430.90312 -409.545214) (xy 430.89951 -409.558475) (xy 430.899316 -409.565348) (xy 430.899316 -410.314648)
			(xy 430.899526 -410.32152) (xy 430.903122 -410.334783) (xy 430.906428 -410.34081) (xy 430.9228 -410.369156)
			(xy 430.9486 -410.429317) (xy 430.966087 -410.492397) (xy 430.974946 -410.557255) (xy 430.975516 -410.589984)
			(xy 430.974964 -410.622705) (xy 434.404861 -410.622705) (xy 434.404863 -410.557268) (xy 434.413648 -410.492423)
			(xy 434.431057 -410.429344) (xy 434.456774 -410.369172) (xy 434.473096 -410.34081) (xy 434.476407 -410.334783)
			(xy 434.480015 -410.321521) (xy 434.480208 -410.314648) (xy 434.480208 -409.565348) (xy 434.479996 -409.558476)
			(xy 434.476401 -409.545214) (xy 434.473096 -409.539186) (xy 434.456785 -409.510819) (xy 434.431069 -409.450648)
			(xy 434.413661 -409.387571) (xy 434.404877 -409.322728) (xy 434.404876 -409.257293) (xy 434.413657 -409.192449)
			(xy 434.431062 -409.129371) (xy 434.456776 -409.0692) (xy 434.473096 -409.040838) (xy 434.476397 -409.034807)
			(xy 434.480011 -409.021548) (xy 434.480208 -409.014676) (xy 434.480208 -408.728672) (xy 434.480599 -408.718515)
			(xy 434.488405 -408.69976) (xy 434.502811 -408.685438) (xy 434.521611 -408.67774) (xy 434.53177 -408.677364)
			(xy 435.24805 -408.677364) (xy 435.258176 -408.677868) (xy 435.276901 -408.685584) (xy 435.29126 -408.699866)
			(xy 435.299077 -408.718548) (xy 435.299612 -408.728672) (xy 435.299612 -409.014676) (xy 435.299812 -409.021549)
			(xy 435.303415 -409.034811) (xy 435.306724 -409.040838) (xy 435.323058 -409.069193) (xy 435.348776 -409.129365)
			(xy 435.366185 -409.192445) (xy 435.374967 -409.257291) (xy 435.374966 -409.322729) (xy 435.36618 -409.387575)
			(xy 435.348769 -409.450654) (xy 435.33188 -409.490164) (xy 436.603656 -409.490164) (xy 436.607647 -409.427997)
			(xy 436.619556 -409.36685) (xy 436.639185 -409.307729) (xy 436.666214 -409.251603) (xy 436.700198 -409.199394)
			(xy 436.74058 -409.151959) (xy 436.786696 -409.110078) (xy 436.837788 -409.074438) (xy 436.893019 -409.045624)
			(xy 436.951481 -409.02411) (xy 437.012215 -409.010248) (xy 437.074222 -409.004266) (xy 437.136485 -409.006262)
			(xy 437.197982 -409.016205) (xy 437.257703 -409.033929) (xy 437.314666 -409.059146) (xy 437.367937 -409.091439)
			(xy 437.416642 -409.130279) (xy 437.459979 -409.175029) (xy 437.497239 -409.224953) (xy 437.527808 -409.279232)
			(xy 437.532172 -409.290012) (xy 438.803804 -409.290012) (xy 438.807795 -409.227845) (xy 438.819704 -409.166698)
			(xy 438.839333 -409.107577) (xy 438.866362 -409.051451) (xy 438.900346 -408.999242) (xy 438.940728 -408.951807)
			(xy 438.986844 -408.909926) (xy 439.037936 -408.874286) (xy 439.093167 -408.845472) (xy 439.151629 -408.823958)
			(xy 439.212363 -408.810096) (xy 439.27437 -408.804114) (xy 439.336633 -408.80611) (xy 439.39813 -408.816053)
			(xy 439.457851 -408.833777) (xy 439.514814 -408.858994) (xy 439.568085 -408.891287) (xy 439.61679 -408.930127)
			(xy 439.660127 -408.974877) (xy 439.697387 -409.024801) (xy 439.727956 -409.07908) (xy 439.751334 -409.136823)
			(xy 439.767135 -409.197081) (xy 439.775101 -409.258864) (xy 439.7756 -409.290012) (xy 439.775101 -409.32116)
			(xy 439.767135 -409.382943) (xy 439.751334 -409.443201) (xy 439.727956 -409.500944) (xy 439.697387 -409.555223)
			(xy 439.660127 -409.605147) (xy 439.61679 -409.649897) (xy 439.568085 -409.688737) (xy 439.514814 -409.72103)
			(xy 439.457851 -409.746247) (xy 439.39813 -409.763971) (xy 439.336633 -409.773914) (xy 439.27437 -409.77591)
			(xy 439.212363 -409.769928) (xy 439.151629 -409.756066) (xy 439.093167 -409.734552) (xy 439.037936 -409.705738)
			(xy 438.986844 -409.670098) (xy 438.940728 -409.628217) (xy 438.900346 -409.580782) (xy 438.866362 -409.528573)
			(xy 438.839333 -409.472447) (xy 438.819704 -409.413326) (xy 438.807795 -409.352179) (xy 438.803804 -409.290012)
			(xy 437.532172 -409.290012) (xy 437.551186 -409.336975) (xy 437.566987 -409.397233) (xy 437.574953 -409.459016)
			(xy 437.575452 -409.490164) (xy 437.574953 -409.521312) (xy 437.566987 -409.583095) (xy 437.551186 -409.643353)
			(xy 437.527808 -409.701096) (xy 437.497239 -409.755375) (xy 437.459979 -409.805299) (xy 437.416642 -409.850049)
			(xy 437.367937 -409.888889) (xy 437.314666 -409.921182) (xy 437.257703 -409.946399) (xy 437.197982 -409.964123)
			(xy 437.136485 -409.974066) (xy 437.074222 -409.976062) (xy 437.012215 -409.97008) (xy 436.951481 -409.956218)
			(xy 436.893019 -409.934704) (xy 436.837788 -409.90589) (xy 436.786696 -409.87025) (xy 436.74058 -409.828369)
			(xy 436.700198 -409.780934) (xy 436.666214 -409.728725) (xy 436.639185 -409.672599) (xy 436.619556 -409.613478)
			(xy 436.607647 -409.552331) (xy 436.603656 -409.490164) (xy 435.33188 -409.490164) (xy 435.323048 -409.510825)
			(xy 435.306724 -409.539186) (xy 435.303416 -409.545214) (xy 435.299806 -409.558475) (xy 435.299612 -409.565348)
			(xy 435.299612 -410.314648) (xy 435.299822 -410.32152) (xy 435.303418 -410.334783) (xy 435.306724 -410.34081)
			(xy 435.323034 -410.369178) (xy 435.348755 -410.429347) (xy 435.366166 -410.492425) (xy 435.374952 -410.557268)
			(xy 435.374952 -410.589984) (xy 438.803804 -410.589984) (xy 438.807795 -410.527817) (xy 438.819704 -410.46667)
			(xy 438.839333 -410.407549) (xy 438.866362 -410.351423) (xy 438.900346 -410.299214) (xy 438.940728 -410.251779)
			(xy 438.986844 -410.209898) (xy 439.037936 -410.174258) (xy 439.093167 -410.145444) (xy 439.151629 -410.12393)
			(xy 439.212363 -410.110068) (xy 439.27437 -410.104086) (xy 439.336633 -410.106082) (xy 439.39813 -410.116025)
			(xy 439.457851 -410.133749) (xy 439.514814 -410.158966) (xy 439.568085 -410.191259) (xy 439.61679 -410.230099)
			(xy 439.660127 -410.274849) (xy 439.697387 -410.324773) (xy 439.727956 -410.379052) (xy 439.751334 -410.436795)
			(xy 439.767135 -410.497053) (xy 439.775101 -410.558836) (xy 439.7756 -410.589984) (xy 439.775101 -410.621132)
			(xy 439.767135 -410.682915) (xy 439.751334 -410.743173) (xy 439.727956 -410.800916) (xy 439.697387 -410.855195)
			(xy 439.660127 -410.905119) (xy 439.61679 -410.949869) (xy 439.568085 -410.988709) (xy 439.514814 -411.021002)
			(xy 439.457851 -411.046219) (xy 439.39813 -411.063943) (xy 439.336633 -411.073886) (xy 439.27437 -411.075882)
			(xy 439.212363 -411.0699) (xy 439.151629 -411.056038) (xy 439.093167 -411.034524) (xy 439.037936 -411.00571)
			(xy 438.986844 -410.97007) (xy 438.940728 -410.928189) (xy 438.900346 -410.880754) (xy 438.866362 -410.828545)
			(xy 438.839333 -410.772419) (xy 438.819704 -410.713298) (xy 438.807795 -410.652151) (xy 438.803804 -410.589984)
			(xy 435.374952 -410.589984) (xy 435.374953 -410.622704) (xy 435.366171 -410.687548) (xy 435.348764 -410.750627)
			(xy 435.323046 -410.810797) (xy 435.306724 -410.839158) (xy 435.303426 -410.845191) (xy 435.299809 -410.858448)
			(xy 435.299612 -410.86532) (xy 435.299612 -411.151324) (xy 435.299198 -411.161478) (xy 435.291397 -411.180229)
			(xy 435.276998 -411.194551) (xy 435.258206 -411.202252) (xy 435.24805 -411.202632) (xy 434.53177 -411.202632)
			(xy 434.521638 -411.202197) (xy 434.502911 -411.194454) (xy 434.488554 -411.180152) (xy 434.480741 -411.161454)
			(xy 434.480208 -411.151324) (xy 434.480208 -410.86532) (xy 434.480008 -410.858447) (xy 434.476405 -410.845185)
			(xy 434.473096 -410.839158) (xy 434.456762 -410.810804) (xy 434.431047 -410.75063) (xy 434.413642 -410.68755)
			(xy 434.404861 -410.622705) (xy 430.974964 -410.622705) (xy 430.974964 -410.622714) (xy 430.966104 -410.687573)
			(xy 430.948609 -410.750653) (xy 430.922798 -410.81081) (xy 430.906428 -410.839158) (xy 430.90313 -410.845191)
			(xy 430.899513 -410.858448) (xy 430.899316 -410.86532) (xy 430.899316 -411.151324) (xy 430.898835 -411.161432)
			(xy 430.891092 -411.180108) (xy 430.876795 -411.194401) (xy 430.858116 -411.202138) (xy 430.848008 -411.202632)
			(xy 430.131728 -411.202632) (xy 430.121611 -411.202162) (xy 430.102914 -411.194429) (xy 430.0886 -411.180129)
			(xy 430.080848 -411.16144) (xy 430.08042 -411.151324) (xy 430.08042 -410.86532) (xy 430.080218 -410.858448)
			(xy 430.076616 -410.845185) (xy 430.073308 -410.839158) (xy 430.056926 -410.810818) (xy 430.031128 -410.750655)
			(xy 430.013643 -410.687573) (xy 430.004788 -410.622714) (xy 430.00422 -410.589984) (xy 426.574866 -410.589984)
			(xy 426.574867 -410.622704) (xy 426.566085 -410.687548) (xy 426.548678 -410.750626) (xy 426.522962 -410.810797)
			(xy 426.50664 -410.839158) (xy 426.503343 -410.845192) (xy 426.499726 -410.858448) (xy 426.499528 -410.86532)
			(xy 426.499528 -411.151324) (xy 426.499099 -411.161476) (xy 426.4913 -411.180224) (xy 426.476907 -411.194545)
			(xy 426.45812 -411.202249) (xy 426.447966 -411.202632) (xy 425.731686 -411.202632) (xy 425.721555 -411.202184)
			(xy 425.702828 -411.194446) (xy 425.688472 -411.180148) (xy 425.680658 -411.161453) (xy 425.680124 -411.151324)
			(xy 425.680124 -410.86532) (xy 425.679921 -410.858448) (xy 425.67632 -410.845185) (xy 425.673012 -410.839158)
			(xy 425.656677 -410.810804) (xy 425.630962 -410.750631) (xy 425.613557 -410.687551) (xy 425.604775 -410.622705)
			(xy 422.174877 -410.622705) (xy 422.174877 -410.622714) (xy 422.166018 -410.687572) (xy 422.148524 -410.750652)
			(xy 422.122714 -410.81081) (xy 422.106344 -410.839158) (xy 422.103048 -410.845192) (xy 422.09943 -410.858448)
			(xy 422.099232 -410.86532) (xy 422.099232 -411.151324) (xy 422.098735 -411.16143) (xy 422.090996 -411.180103)
			(xy 422.076703 -411.194396) (xy 422.05803 -411.202135) (xy 422.047924 -411.202632) (xy 421.331644 -411.202632)
			(xy 421.321528 -411.202149) (xy 421.302832 -411.194421) (xy 421.288517 -411.180125) (xy 421.280765 -411.161439)
			(xy 421.280336 -411.151324) (xy 421.280336 -410.86532) (xy 421.280132 -410.858448) (xy 421.276531 -410.845185)
			(xy 421.273224 -410.839158) (xy 421.256844 -410.810817) (xy 421.231045 -410.750654) (xy 421.213559 -410.687572)
			(xy 421.204704 -410.622714) (xy 421.204136 -410.589984) (xy 414.525968 -410.589984) (xy 414.525968 -412.090108)
			(xy 419.003742 -412.090108) (xy 419.007733 -412.027941) (xy 419.019642 -411.966794) (xy 419.039271 -411.907673)
			(xy 419.0663 -411.851547) (xy 419.100284 -411.799338) (xy 419.140666 -411.751903) (xy 419.186782 -411.710022)
			(xy 419.237874 -411.674382) (xy 419.293105 -411.645568) (xy 419.351567 -411.624054) (xy 419.412301 -411.610192)
			(xy 419.474308 -411.60421) (xy 419.536571 -411.606206) (xy 419.598068 -411.616149) (xy 419.657789 -411.633873)
			(xy 419.714752 -411.65909) (xy 419.768023 -411.691383) (xy 419.816728 -411.730223) (xy 419.860065 -411.774973)
			(xy 419.897325 -411.824897) (xy 419.927894 -411.879176) (xy 419.951272 -411.936919) (xy 419.967073 -411.997177)
			(xy 419.975039 -412.05896) (xy 419.975538 -412.090108) (xy 423.403784 -412.090108) (xy 423.407775 -412.027941)
			(xy 423.419684 -411.966794) (xy 423.439313 -411.907673) (xy 423.466342 -411.851547) (xy 423.500326 -411.799338)
			(xy 423.540708 -411.751903) (xy 423.586824 -411.710022) (xy 423.637916 -411.674382) (xy 423.693147 -411.645568)
			(xy 423.751609 -411.624054) (xy 423.812343 -411.610192) (xy 423.87435 -411.60421) (xy 423.936613 -411.606206)
			(xy 423.99811 -411.616149) (xy 424.057831 -411.633873) (xy 424.114794 -411.65909) (xy 424.168065 -411.691383)
			(xy 424.21677 -411.730223) (xy 424.260107 -411.774973) (xy 424.297367 -411.824897) (xy 424.327936 -411.879176)
			(xy 424.351314 -411.936919) (xy 424.367115 -411.997177) (xy 424.375081 -412.05896) (xy 424.37558 -412.090108)
			(xy 427.803826 -412.090108) (xy 427.807817 -412.027941) (xy 427.819726 -411.966794) (xy 427.839355 -411.907673)
			(xy 427.866384 -411.851547) (xy 427.900368 -411.799338) (xy 427.94075 -411.751903) (xy 427.986866 -411.710022)
			(xy 428.037958 -411.674382) (xy 428.093189 -411.645568) (xy 428.151651 -411.624054) (xy 428.212385 -411.610192)
			(xy 428.274392 -411.60421) (xy 428.336655 -411.606206) (xy 428.398152 -411.616149) (xy 428.457873 -411.633873)
			(xy 428.514836 -411.65909) (xy 428.568107 -411.691383) (xy 428.616812 -411.730223) (xy 428.660149 -411.774973)
			(xy 428.697409 -411.824897) (xy 428.727978 -411.879176) (xy 428.751356 -411.936919) (xy 428.767157 -411.997177)
			(xy 428.775123 -412.05896) (xy 428.775622 -412.090108) (xy 432.203614 -412.090108) (xy 432.207605 -412.027941)
			(xy 432.219514 -411.966794) (xy 432.239143 -411.907673) (xy 432.266172 -411.851547) (xy 432.300156 -411.799338)
			(xy 432.340538 -411.751903) (xy 432.386654 -411.710022) (xy 432.437746 -411.674382) (xy 432.492977 -411.645568)
			(xy 432.551439 -411.624054) (xy 432.612173 -411.610192) (xy 432.67418 -411.60421) (xy 432.736443 -411.606206)
			(xy 432.79794 -411.616149) (xy 432.857661 -411.633873) (xy 432.914624 -411.65909) (xy 432.967895 -411.691383)
			(xy 433.0166 -411.730223) (xy 433.059937 -411.774973) (xy 433.097197 -411.824897) (xy 433.127766 -411.879176)
			(xy 433.151144 -411.936919) (xy 433.166945 -411.997177) (xy 433.174911 -412.05896) (xy 433.17541 -412.090108)
			(xy 436.603656 -412.090108) (xy 436.607647 -412.027941) (xy 436.619556 -411.966794) (xy 436.639185 -411.907673)
			(xy 436.666214 -411.851547) (xy 436.700198 -411.799338) (xy 436.74058 -411.751903) (xy 436.786696 -411.710022)
			(xy 436.837788 -411.674382) (xy 436.893019 -411.645568) (xy 436.951481 -411.624054) (xy 437.012215 -411.610192)
			(xy 437.074222 -411.60421) (xy 437.136485 -411.606206) (xy 437.197982 -411.616149) (xy 437.257703 -411.633873)
			(xy 437.314666 -411.65909) (xy 437.367937 -411.691383) (xy 437.416642 -411.730223) (xy 437.459979 -411.774973)
			(xy 437.497239 -411.824897) (xy 437.527808 -411.879176) (xy 437.536286 -411.900116) (xy 444.291972 -411.900116)
			(xy 444.296043 -411.844494) (xy 444.308169 -411.790057) (xy 444.328092 -411.737966) (xy 444.355388 -411.689331)
			(xy 444.389474 -411.645188) (xy 444.429623 -411.606479) (xy 444.474981 -411.574028) (xy 444.524581 -411.548527)
			(xy 444.577365 -411.53052) (xy 444.632208 -411.52039) (xy 444.687942 -411.518353) (xy 444.743379 -411.524453)
			(xy 444.797336 -411.538559) (xy 444.848665 -411.560371) (xy 444.896271 -411.589425) (xy 444.939139 -411.6251)
			(xy 444.976356 -411.666637) (xy 445.007129 -411.71315) (xy 445.030801 -411.763647) (xy 445.046869 -411.817054)
			(xy 445.054989 -411.87223) (xy 445.055498 -411.900116) (xy 445.054989 -411.928002) (xy 445.046869 -411.983178)
			(xy 445.030801 -412.036585) (xy 445.007129 -412.087082) (xy 444.976356 -412.133595) (xy 444.939139 -412.175132)
			(xy 444.896271 -412.210807) (xy 444.848665 -412.239861) (xy 444.797336 -412.261673) (xy 444.743379 -412.275779)
			(xy 444.687942 -412.281879) (xy 444.632208 -412.279842) (xy 444.577365 -412.269712) (xy 444.524581 -412.251705)
			(xy 444.474981 -412.226204) (xy 444.429623 -412.193753) (xy 444.389474 -412.155044) (xy 444.355388 -412.110901)
			(xy 444.328092 -412.062266) (xy 444.308169 -412.010175) (xy 444.296043 -411.955738) (xy 444.291972 -411.900116)
			(xy 437.536286 -411.900116) (xy 437.551186 -411.936919) (xy 437.566987 -411.997177) (xy 437.574953 -412.05896)
			(xy 437.575452 -412.090108) (xy 437.574953 -412.121256) (xy 437.566987 -412.183039) (xy 437.551186 -412.243297)
			(xy 437.527808 -412.30104) (xy 437.497239 -412.355319) (xy 437.459979 -412.405243) (xy 437.416642 -412.449993)
			(xy 437.367937 -412.488833) (xy 437.314666 -412.521126) (xy 437.257703 -412.546343) (xy 437.197982 -412.564067)
			(xy 437.136485 -412.57401) (xy 437.074222 -412.576006) (xy 437.012215 -412.570024) (xy 436.951481 -412.556162)
			(xy 436.893019 -412.534648) (xy 436.837788 -412.505834) (xy 436.786696 -412.470194) (xy 436.74058 -412.428313)
			(xy 436.700198 -412.380878) (xy 436.666214 -412.328669) (xy 436.639185 -412.272543) (xy 436.619556 -412.213422)
			(xy 436.607647 -412.152275) (xy 436.603656 -412.090108) (xy 433.17541 -412.090108) (xy 433.174911 -412.121256)
			(xy 433.166945 -412.183039) (xy 433.151144 -412.243297) (xy 433.127766 -412.30104) (xy 433.097197 -412.355319)
			(xy 433.059937 -412.405243) (xy 433.0166 -412.449993) (xy 432.967895 -412.488833) (xy 432.914624 -412.521126)
			(xy 432.857661 -412.546343) (xy 432.79794 -412.564067) (xy 432.736443 -412.57401) (xy 432.67418 -412.576006)
			(xy 432.612173 -412.570024) (xy 432.551439 -412.556162) (xy 432.492977 -412.534648) (xy 432.437746 -412.505834)
			(xy 432.386654 -412.470194) (xy 432.340538 -412.428313) (xy 432.300156 -412.380878) (xy 432.266172 -412.328669)
			(xy 432.239143 -412.272543) (xy 432.219514 -412.213422) (xy 432.207605 -412.152275) (xy 432.203614 -412.090108)
			(xy 428.775622 -412.090108) (xy 428.775123 -412.121256) (xy 428.767157 -412.183039) (xy 428.751356 -412.243297)
			(xy 428.727978 -412.30104) (xy 428.697409 -412.355319) (xy 428.660149 -412.405243) (xy 428.616812 -412.449993)
			(xy 428.568107 -412.488833) (xy 428.514836 -412.521126) (xy 428.457873 -412.546343) (xy 428.398152 -412.564067)
			(xy 428.336655 -412.57401) (xy 428.274392 -412.576006) (xy 428.212385 -412.570024) (xy 428.151651 -412.556162)
			(xy 428.093189 -412.534648) (xy 428.037958 -412.505834) (xy 427.986866 -412.470194) (xy 427.94075 -412.428313)
			(xy 427.900368 -412.380878) (xy 427.866384 -412.328669) (xy 427.839355 -412.272543) (xy 427.819726 -412.213422)
			(xy 427.807817 -412.152275) (xy 427.803826 -412.090108) (xy 424.37558 -412.090108) (xy 424.375081 -412.121256)
			(xy 424.367115 -412.183039) (xy 424.351314 -412.243297) (xy 424.327936 -412.30104) (xy 424.297367 -412.355319)
			(xy 424.260107 -412.405243) (xy 424.21677 -412.449993) (xy 424.168065 -412.488833) (xy 424.114794 -412.521126)
			(xy 424.057831 -412.546343) (xy 423.99811 -412.564067) (xy 423.936613 -412.57401) (xy 423.87435 -412.576006)
			(xy 423.812343 -412.570024) (xy 423.751609 -412.556162) (xy 423.693147 -412.534648) (xy 423.637916 -412.505834)
			(xy 423.586824 -412.470194) (xy 423.540708 -412.428313) (xy 423.500326 -412.380878) (xy 423.466342 -412.328669)
			(xy 423.439313 -412.272543) (xy 423.419684 -412.213422) (xy 423.407775 -412.152275) (xy 423.403784 -412.090108)
			(xy 419.975538 -412.090108) (xy 419.975039 -412.121256) (xy 419.967073 -412.183039) (xy 419.951272 -412.243297)
			(xy 419.927894 -412.30104) (xy 419.897325 -412.355319) (xy 419.860065 -412.405243) (xy 419.816728 -412.449993)
			(xy 419.768023 -412.488833) (xy 419.714752 -412.521126) (xy 419.657789 -412.546343) (xy 419.598068 -412.564067)
			(xy 419.536571 -412.57401) (xy 419.474308 -412.576006) (xy 419.412301 -412.570024) (xy 419.351567 -412.556162)
			(xy 419.293105 -412.534648) (xy 419.237874 -412.505834) (xy 419.186782 -412.470194) (xy 419.140666 -412.428313)
			(xy 419.100284 -412.380878) (xy 419.0663 -412.328669) (xy 419.039271 -412.272543) (xy 419.019642 -412.213422)
			(xy 419.007733 -412.152275) (xy 419.003742 -412.090108) (xy 414.525968 -412.090108) (xy 414.525968 -414.403794)
			(xy 447.176396 -414.403794) (xy 447.180467 -414.348172) (xy 447.192593 -414.293735) (xy 447.212516 -414.241644)
			(xy 447.239812 -414.193009) (xy 447.273898 -414.148866) (xy 447.314047 -414.110157) (xy 447.359405 -414.077706)
			(xy 447.409005 -414.052205) (xy 447.461789 -414.034198) (xy 447.516632 -414.024068) (xy 447.572366 -414.022031)
			(xy 447.627803 -414.028131) (xy 447.68176 -414.042237) (xy 447.733089 -414.064049) (xy 447.780695 -414.093103)
			(xy 447.823563 -414.128778) (xy 447.86078 -414.170315) (xy 447.891553 -414.216828) (xy 447.915225 -414.267325)
			(xy 447.931293 -414.320732) (xy 447.939413 -414.375908) (xy 447.939922 -414.403794) (xy 447.939413 -414.43168)
			(xy 447.931293 -414.486856) (xy 447.915225 -414.540263) (xy 447.891801 -414.59023) (xy 448.79717 -414.59023)
			(xy 448.801241 -414.534608) (xy 448.813367 -414.480171) (xy 448.83329 -414.42808) (xy 448.860586 -414.379445)
			(xy 448.894672 -414.335302) (xy 448.934821 -414.296593) (xy 448.980179 -414.264142) (xy 449.029779 -414.238641)
			(xy 449.082563 -414.220634) (xy 449.137406 -414.210504) (xy 449.19314 -414.208467) (xy 449.248577 -414.214567)
			(xy 449.302534 -414.228673) (xy 449.353863 -414.250485) (xy 449.401469 -414.279539) (xy 449.444337 -414.315214)
			(xy 449.461574 -414.334452) (xy 450.168262 -414.334452) (xy 450.172333 -414.27883) (xy 450.184459 -414.224393)
			(xy 450.204382 -414.172302) (xy 450.231678 -414.123667) (xy 450.265764 -414.079524) (xy 450.305913 -414.040815)
			(xy 450.351271 -414.008364) (xy 450.400871 -413.982863) (xy 450.453655 -413.964856) (xy 450.508498 -413.954726)
			(xy 450.564232 -413.952689) (xy 450.619669 -413.958789) (xy 450.673626 -413.972895) (xy 450.724955 -413.994707)
			(xy 450.772561 -414.023761) (xy 450.815429 -414.059436) (xy 450.852646 -414.100973) (xy 450.883419 -414.147486)
			(xy 450.907091 -414.197983) (xy 450.923159 -414.25139) (xy 450.931279 -414.306566) (xy 450.931788 -414.334452)
			(xy 450.931279 -414.362338) (xy 450.923159 -414.417514) (xy 450.907091 -414.470921) (xy 450.883419 -414.521418)
			(xy 450.852646 -414.567931) (xy 450.815429 -414.609468) (xy 450.772561 -414.645143) (xy 450.724955 -414.674197)
			(xy 450.673626 -414.696009) (xy 450.619669 -414.710115) (xy 450.564232 -414.716215) (xy 450.508498 -414.714178)
			(xy 450.453655 -414.704048) (xy 450.400871 -414.686041) (xy 450.351271 -414.66054) (xy 450.305913 -414.628089)
			(xy 450.265764 -414.58938) (xy 450.231678 -414.545237) (xy 450.204382 -414.496602) (xy 450.184459 -414.444511)
			(xy 450.172333 -414.390074) (xy 450.168262 -414.334452) (xy 449.461574 -414.334452) (xy 449.481554 -414.356751)
			(xy 449.512327 -414.403264) (xy 449.535999 -414.453761) (xy 449.552067 -414.507168) (xy 449.560187 -414.562344)
			(xy 449.560696 -414.59023) (xy 449.560187 -414.618116) (xy 449.552067 -414.673292) (xy 449.535999 -414.726699)
			(xy 449.512327 -414.777196) (xy 449.481554 -414.823709) (xy 449.444337 -414.865246) (xy 449.401469 -414.900921)
			(xy 449.353863 -414.929975) (xy 449.302534 -414.951787) (xy 449.248577 -414.965893) (xy 449.19314 -414.971993)
			(xy 449.137406 -414.969956) (xy 449.082563 -414.959826) (xy 449.029779 -414.941819) (xy 448.980179 -414.916318)
			(xy 448.934821 -414.883867) (xy 448.894672 -414.845158) (xy 448.860586 -414.801015) (xy 448.83329 -414.75238)
			(xy 448.813367 -414.700289) (xy 448.801241 -414.645852) (xy 448.79717 -414.59023) (xy 447.891801 -414.59023)
			(xy 447.891553 -414.59076) (xy 447.86078 -414.637273) (xy 447.823563 -414.67881) (xy 447.780695 -414.714485)
			(xy 447.733089 -414.743539) (xy 447.68176 -414.765351) (xy 447.627803 -414.779457) (xy 447.572366 -414.785557)
			(xy 447.516632 -414.78352) (xy 447.461789 -414.77339) (xy 447.409005 -414.755383) (xy 447.359405 -414.729882)
			(xy 447.314047 -414.697431) (xy 447.273898 -414.658722) (xy 447.239812 -414.614579) (xy 447.212516 -414.565944)
			(xy 447.192593 -414.513853) (xy 447.180467 -414.459416) (xy 447.176396 -414.403794) (xy 414.525968 -414.403794)
			(xy 414.525968 -416.58921) (xy 414.527435 -416.598332) (xy 414.535959 -416.614705) (xy 414.549762 -416.626961)
			(xy 414.567029 -416.63349) (xy 414.57626 -416.633914) (xy 415.62782 -416.633914) (xy 415.637888 -416.634341)
			(xy 415.656486 -416.642062) (xy 415.663888 -416.6489) (xy 416.053778 -417.03879) (xy 416.06118 -417.045625)
			(xy 416.079779 -417.053333) (xy 416.089846 -417.053776)
		)
		(stroke
			(width 0)
			(type solid)
		)
		(fill yes)
		(layer "In15.Cu")
		(net "GND")
	)
	(gr_poly
		(pts
			(xy 349.570802 -327.338436) (xy 349.578408 -327.336923) (xy 349.592244 -327.329939) (xy 349.59798 -327.32472)
			(xy 350.358456 -326.564244) (xy 350.358964 -326.563736) (xy 350.365543 -326.556354) (xy 350.372988 -326.538055)
			(xy 350.373442 -326.528176) (xy 350.373442 -304.532792) (xy 350.357948 -304.5079) (xy 350.344486 -304.50155)
			(xy 350.320526 -304.489545) (xy 350.275935 -304.45982) (xy 350.235942 -304.424147) (xy 350.201334 -304.383229)
			(xy 350.172793 -304.337871) (xy 350.15088 -304.288965) (xy 350.136027 -304.237473) (xy 350.128526 -304.18441)
			(xy 350.128524 -304.130819) (xy 350.136021 -304.077756) (xy 350.15087 -304.026263) (xy 350.172779 -303.977355)
			(xy 350.201317 -303.931995) (xy 350.235921 -303.891074) (xy 350.275911 -303.855398) (xy 350.3205 -303.82567)
			(xy 350.344486 -303.813718) (xy 350.357948 -303.807368) (xy 350.373442 -303.782476) (xy 350.373442 -303.516792)
			(xy 350.357948 -303.4919) (xy 350.344486 -303.48555) (xy 350.320526 -303.473545) (xy 350.275935 -303.44382)
			(xy 350.235942 -303.408147) (xy 350.201334 -303.367229) (xy 350.172793 -303.321871) (xy 350.15088 -303.272965)
			(xy 350.136027 -303.221473) (xy 350.128526 -303.16841) (xy 350.128524 -303.114819) (xy 350.136021 -303.061756)
			(xy 350.15087 -303.010263) (xy 350.172779 -302.961355) (xy 350.201317 -302.915995) (xy 350.235921 -302.875074)
			(xy 350.275911 -302.839398) (xy 350.3205 -302.80967) (xy 350.344486 -302.797718) (xy 350.357948 -302.791368)
			(xy 350.373442 -302.766476) (xy 350.373442 -294.409368) (xy 350.373011 -294.399302) (xy 350.365282 -294.380711)
			(xy 350.358456 -294.3733) (xy 350.072198 -294.087042) (xy 350.064801 -294.080191) (xy 350.046203 -294.072451)
			(xy 350.03613 -294.072056) (xy 343.674954 -294.072056) (xy 343.664798 -294.072504) (xy 343.646064 -294.08036)
			(xy 343.638632 -294.087296) (xy 343.587832 -294.138858) (xy 343.581013 -294.14647) (xy 343.573535 -294.165471)
			(xy 343.573354 -294.175688) (xy 343.573354 -294.1828) (xy 343.572868 -294.210051) (xy 343.565112 -294.263999)
			(xy 343.549757 -294.316294) (xy 343.527115 -294.365871) (xy 343.497649 -294.411721) (xy 343.461958 -294.452912)
			(xy 343.420767 -294.488603) (xy 343.374917 -294.518069) (xy 343.32534 -294.540711) (xy 343.273045 -294.556066)
			(xy 343.219097 -294.563822) (xy 343.164595 -294.563822) (xy 343.110647 -294.556066) (xy 343.058352 -294.540711)
			(xy 343.008775 -294.518069) (xy 342.962925 -294.488603) (xy 342.921734 -294.452912) (xy 342.886043 -294.411721)
			(xy 342.856577 -294.365871) (xy 342.833935 -294.316294) (xy 342.81858 -294.263999) (xy 342.810824 -294.210051)
			(xy 342.810338 -294.1828) (xy 342.810338 -294.175688) (xy 342.810143 -294.16547) (xy 342.802689 -294.146459)
			(xy 342.79586 -294.138858) (xy 342.745314 -294.08755) (xy 342.744806 -294.087042) (xy 342.73741 -294.08019)
			(xy 342.718811 -294.072447) (xy 342.708738 -294.072056) (xy 334.116426 -294.072056) (xy 334.106363 -294.071618)
			(xy 334.087782 -294.06388) (xy 334.080358 -294.05707) (xy 332.890622 -292.867334) (xy 332.88423 -292.86149)
			(xy 332.868589 -292.854077) (xy 332.851378 -292.852247) (xy 332.84287 -292.853872) (xy 332.831948 -292.856666)
			(xy 332.826868 -292.858952) (xy 332.750263 -292.895587) (xy 332.593983 -292.96205) (xy 332.43456 -293.020576)
			(xy 332.272399 -293.071019) (xy 332.107908 -293.113252) (xy 331.941503 -293.147166) (xy 331.773605 -293.172678)
			(xy 331.604636 -293.189721) (xy 331.435025 -293.198254) (xy 331.350112 -293.198804) (xy 331.267182 -293.198304)
			(xy 331.10152 -293.190166) (xy 330.936458 -293.173909) (xy 330.772392 -293.149573) (xy 330.609718 -293.117215)
			(xy 330.448828 -293.076915) (xy 330.290108 -293.028768) (xy 330.133943 -292.972892) (xy 329.980707 -292.90942)
			(xy 329.83077 -292.838506) (xy 329.684494 -292.76032) (xy 329.54223 -292.67505) (xy 329.404322 -292.582903)
			(xy 329.271101 -292.4841) (xy 329.142888 -292.378879) (xy 329.019993 -292.267494) (xy 328.902712 -292.150213)
			(xy 328.791326 -292.027318) (xy 328.686105 -291.899106) (xy 328.587302 -291.765885) (xy 328.495154 -291.627977)
			(xy 328.409884 -291.485713) (xy 328.331698 -291.339437) (xy 328.260783 -291.1895) (xy 328.197311 -291.036265)
			(xy 328.141434 -290.880099) (xy 328.093287 -290.72138) (xy 328.052986 -290.56049) (xy 328.020629 -290.397816)
			(xy 327.996292 -290.23375) (xy 327.980035 -290.068688) (xy 327.971897 -289.903026) (xy 327.971404 -289.820096)
			(xy 327.971902 -289.737611) (xy 327.979953 -289.572839) (xy 327.996035 -289.408656) (xy 328.020111 -289.245453)
			(xy 328.052122 -289.08362) (xy 328.091994 -288.923541) (xy 328.139629 -288.7656) (xy 328.194916 -288.610171)
			(xy 328.257722 -288.457625) (xy 328.327897 -288.308326) (xy 328.405275 -288.16263) (xy 328.489671 -288.020883)
			(xy 328.580884 -287.883424) (xy 328.678696 -287.75058) (xy 328.782875 -287.622668) (xy 328.893172 -287.499992)
			(xy 329.009324 -287.382845) (xy 329.131055 -287.271506) (xy 329.258075 -287.16624) (xy 329.39008 -287.067299)
			(xy 329.526756 -286.974917) (xy 329.667778 -286.889316) (xy 329.812809 -286.810698) (xy 329.961504 -286.739252)
			(xy 330.113509 -286.675148) (xy 330.268461 -286.618538) (xy 330.347066 -286.593534) (xy 330.350368 -286.592518)
			(xy 330.36002 -286.587946) (xy 330.362814 -286.586422) (xy 330.37272 -286.581342) (xy 330.38669 -286.56407)
			(xy 330.38923 -286.553148) (xy 330.39431 -286.53359) (xy 330.39431 -286.533082) (xy 330.397438 -286.518045)
			(xy 330.395532 -286.487403) (xy 330.384615 -286.458709) (xy 330.365671 -286.43455) (xy 330.34041 -286.417104)
			(xy 330.311107 -286.407944) (xy 330.295758 -286.407352) (xy 314.982606 -286.407352) (xy 314.954158 -286.431482)
			(xy 314.95111 -286.44977) (xy 314.946481 -286.474624) (xy 314.930098 -286.522448) (xy 314.906063 -286.566921)
			(xy 314.875032 -286.606829) (xy 314.837852 -286.641082) (xy 314.79554 -286.668745) (xy 314.74925 -286.689062)
			(xy 314.700246 -286.701478) (xy 314.649866 -286.705655) (xy 314.599486 -286.701478) (xy 314.550482 -286.689062)
			(xy 314.504192 -286.668745) (xy 314.46188 -286.641082) (xy 314.4247 -286.606829) (xy 314.393669 -286.566921)
			(xy 314.369634 -286.522448) (xy 314.353251 -286.474624) (xy 314.348622 -286.44977) (xy 314.345574 -286.431482)
			(xy 314.317126 -286.407352) (xy 314.032646 -286.407352) (xy 314.004198 -286.431482) (xy 314.00115 -286.44977)
			(xy 313.996521 -286.474624) (xy 313.980138 -286.522448) (xy 313.956103 -286.566921) (xy 313.925072 -286.606829)
			(xy 313.887892 -286.641082) (xy 313.84558 -286.668745) (xy 313.79929 -286.689062) (xy 313.750286 -286.701478)
			(xy 313.699906 -286.705655) (xy 313.649526 -286.701478) (xy 313.600522 -286.689062) (xy 313.554232 -286.668745)
			(xy 313.51192 -286.641082) (xy 313.47474 -286.606829) (xy 313.443709 -286.566921) (xy 313.419674 -286.522448)
			(xy 313.403291 -286.474624) (xy 313.398662 -286.44977) (xy 313.395614 -286.431482) (xy 313.367166 -286.407352)
			(xy 313.104022 -286.407352) (xy 313.075574 -286.431736) (xy 313.07278 -286.450278) (xy 313.068345 -286.475642)
			(xy 313.052549 -286.524648) (xy 313.029269 -286.570573) (xy 312.999078 -286.612282) (xy 312.962724 -286.648744)
			(xy 312.921105 -286.679058) (xy 312.875248 -286.702474) (xy 312.826289 -286.718414) (xy 312.775436 -286.726483)
			(xy 312.723948 -286.726483) (xy 312.673095 -286.718414) (xy 312.624136 -286.702474) (xy 312.578279 -286.679058)
			(xy 312.53666 -286.648744) (xy 312.500306 -286.612282) (xy 312.470115 -286.570573) (xy 312.446835 -286.524648)
			(xy 312.431039 -286.475642) (xy 312.426604 -286.450278) (xy 312.42381 -286.431736) (xy 312.395362 -286.407352)
			(xy 312.154062 -286.407352) (xy 312.125614 -286.431736) (xy 312.12282 -286.450278) (xy 312.118385 -286.475642)
			(xy 312.102589 -286.524648) (xy 312.079309 -286.570573) (xy 312.049118 -286.612282) (xy 312.012764 -286.648744)
			(xy 311.971145 -286.679058) (xy 311.925288 -286.702474) (xy 311.876329 -286.718414) (xy 311.825476 -286.726483)
			(xy 311.773988 -286.726483) (xy 311.723135 -286.718414) (xy 311.674176 -286.702474) (xy 311.628319 -286.679058)
			(xy 311.5867 -286.648744) (xy 311.550346 -286.612282) (xy 311.520155 -286.570573) (xy 311.496875 -286.524648)
			(xy 311.481079 -286.475642) (xy 311.476644 -286.450278) (xy 311.47385 -286.431736) (xy 311.445402 -286.407352)
			(xy 311.182512 -286.407352) (xy 311.154064 -286.431482) (xy 311.151016 -286.44977) (xy 311.146387 -286.474624)
			(xy 311.130004 -286.522448) (xy 311.105969 -286.566921) (xy 311.074938 -286.606829) (xy 311.037758 -286.641082)
			(xy 310.995446 -286.668745) (xy 310.949156 -286.689062) (xy 310.900152 -286.701478) (xy 310.849772 -286.705655)
			(xy 310.799392 -286.701478) (xy 310.750388 -286.689062) (xy 310.704098 -286.668745) (xy 310.661786 -286.641082)
			(xy 310.624606 -286.606829) (xy 310.593575 -286.566921) (xy 310.56954 -286.522448) (xy 310.553157 -286.474624)
			(xy 310.548528 -286.44977) (xy 310.54548 -286.431482) (xy 310.517032 -286.407352) (xy 310.254396 -286.407352)
			(xy 310.225948 -286.431736) (xy 310.2229 -286.450278) (xy 310.218465 -286.475642) (xy 310.202669 -286.524648)
			(xy 310.179389 -286.570573) (xy 310.149198 -286.612282) (xy 310.112844 -286.648744) (xy 310.071225 -286.679058)
			(xy 310.025368 -286.702474) (xy 309.976409 -286.718414) (xy 309.925556 -286.726483) (xy 309.874068 -286.726483)
			(xy 309.823215 -286.718414) (xy 309.774256 -286.702474) (xy 309.728399 -286.679058) (xy 309.68678 -286.648744)
			(xy 309.650426 -286.612282) (xy 309.620235 -286.570573) (xy 309.596955 -286.524648) (xy 309.581159 -286.475642)
			(xy 309.576724 -286.450278) (xy 309.573676 -286.431736) (xy 309.545228 -286.407352) (xy 309.304436 -286.407352)
			(xy 309.275988 -286.431736) (xy 309.27294 -286.450278) (xy 309.268505 -286.475642) (xy 309.252709 -286.524648)
			(xy 309.229429 -286.570573) (xy 309.199238 -286.612282) (xy 309.162884 -286.648744) (xy 309.121265 -286.679058)
			(xy 309.075408 -286.702474) (xy 309.026449 -286.718414) (xy 308.975596 -286.726483) (xy 308.924108 -286.726483)
			(xy 308.873255 -286.718414) (xy 308.824296 -286.702474) (xy 308.778439 -286.679058) (xy 308.73682 -286.648744)
			(xy 308.700466 -286.612282) (xy 308.670275 -286.570573) (xy 308.646995 -286.524648) (xy 308.631199 -286.475642)
			(xy 308.626764 -286.450278) (xy 308.623716 -286.431736) (xy 308.595268 -286.407352) (xy 308.332632 -286.407352)
			(xy 308.304184 -286.431482) (xy 308.301136 -286.44977) (xy 308.296507 -286.474624) (xy 308.280124 -286.522448)
			(xy 308.256089 -286.566921) (xy 308.225058 -286.606829) (xy 308.187878 -286.641082) (xy 308.145566 -286.668745)
			(xy 308.099276 -286.689062) (xy 308.050272 -286.701478) (xy 307.999892 -286.705655) (xy 307.949512 -286.701478)
			(xy 307.900508 -286.689062) (xy 307.854218 -286.668745) (xy 307.811906 -286.641082) (xy 307.774726 -286.606829)
			(xy 307.743695 -286.566921) (xy 307.71966 -286.522448) (xy 307.703277 -286.474624) (xy 307.698648 -286.44977)
			(xy 307.6956 -286.431482) (xy 307.667152 -286.407352) (xy 307.382672 -286.407352) (xy 307.354224 -286.431482)
			(xy 307.351176 -286.44977) (xy 307.346547 -286.474624) (xy 307.330164 -286.522448) (xy 307.306129 -286.566921)
			(xy 307.275098 -286.606829) (xy 307.237918 -286.641082) (xy 307.195606 -286.668745) (xy 307.149316 -286.689062)
			(xy 307.100312 -286.701478) (xy 307.049932 -286.705655) (xy 306.999552 -286.701478) (xy 306.950548 -286.689062)
			(xy 306.904258 -286.668745) (xy 306.861946 -286.641082) (xy 306.824766 -286.606829) (xy 306.793735 -286.566921)
			(xy 306.7697 -286.522448) (xy 306.753317 -286.474624) (xy 306.748688 -286.44977) (xy 306.74564 -286.431482)
			(xy 306.717192 -286.407352) (xy 306.432458 -286.407352) (xy 306.40401 -286.431482) (xy 306.400962 -286.44977)
			(xy 306.396333 -286.474624) (xy 306.37995 -286.522448) (xy 306.355915 -286.566921) (xy 306.324884 -286.606829)
			(xy 306.287704 -286.641082) (xy 306.245392 -286.668745) (xy 306.199102 -286.689062) (xy 306.150098 -286.701478)
			(xy 306.099718 -286.705655) (xy 306.049338 -286.701478) (xy 306.000334 -286.689062) (xy 305.954044 -286.668745)
			(xy 305.911732 -286.641082) (xy 305.874552 -286.606829) (xy 305.843521 -286.566921) (xy 305.819486 -286.522448)
			(xy 305.803103 -286.474624) (xy 305.798474 -286.44977) (xy 305.795426 -286.431482) (xy 305.766978 -286.407352)
			(xy 279.98801 -286.407352) (xy 279.97794 -286.407775) (xy 279.959338 -286.415492) (xy 279.951942 -286.422338)
			(xy 279.887934 -286.486346) (xy 279.881231 -286.493788) (xy 279.873613 -286.51229) (xy 279.873611 -286.532299)
			(xy 279.877012 -286.541718) (xy 279.882854 -286.555942) (xy 279.908254 -286.57296) (xy 279.929844 -286.57296)
			(xy 279.9334 -286.572452) (xy 279.9437 -286.571141) (xy 279.964419 -286.569745) (xy 279.974802 -286.569658)
			(xy 280.00006 -286.57018) (xy 280.049887 -286.578495) (xy 280.097666 -286.594898) (xy 280.142093 -286.618941)
			(xy 280.181958 -286.649969) (xy 280.216171 -286.687134) (xy 280.243801 -286.729425) (xy 280.264093 -286.775686)
			(xy 280.276493 -286.824656) (xy 280.280662 -286.874966) (xy 280.618958 -286.874966) (xy 280.622918 -286.825912)
			(xy 280.634695 -286.778128) (xy 280.653986 -286.732852) (xy 280.680289 -286.691256) (xy 280.712924 -286.654419)
			(xy 280.751045 -286.623294) (xy 280.793666 -286.598687) (xy 280.839682 -286.581235) (xy 280.887901 -286.571391)
			(xy 280.937076 -286.56941) (xy 280.985931 -286.575342) (xy 281.033202 -286.589034) (xy 281.077664 -286.610132)
			(xy 281.118167 -286.638088) (xy 281.15366 -286.67218) (xy 281.183225 -286.711524) (xy 281.206096 -286.755101)
			(xy 281.22168 -286.801782) (xy 281.229575 -286.850359) (xy 281.23007 -286.874966) (xy 281.568918 -286.874966)
			(xy 281.572878 -286.825912) (xy 281.584655 -286.778128) (xy 281.603946 -286.732852) (xy 281.630249 -286.691256)
			(xy 281.662884 -286.654419) (xy 281.701005 -286.623294) (xy 281.743626 -286.598687) (xy 281.789642 -286.581235)
			(xy 281.837861 -286.571391) (xy 281.887036 -286.56941) (xy 281.935891 -286.575342) (xy 281.983162 -286.589034)
			(xy 282.027624 -286.610132) (xy 282.068127 -286.638088) (xy 282.10362 -286.67218) (xy 282.133185 -286.711524)
			(xy 282.156056 -286.755101) (xy 282.17164 -286.801782) (xy 282.179535 -286.850359) (xy 282.18003 -286.874966)
			(xy 282.519132 -286.874966) (xy 282.523092 -286.825912) (xy 282.534869 -286.778128) (xy 282.55416 -286.732852)
			(xy 282.580463 -286.691256) (xy 282.613098 -286.654419) (xy 282.651219 -286.623294) (xy 282.69384 -286.598687)
			(xy 282.739856 -286.581235) (xy 282.788075 -286.571391) (xy 282.83725 -286.56941) (xy 282.886105 -286.575342)
			(xy 282.933376 -286.589034) (xy 282.977838 -286.610132) (xy 283.018341 -286.638088) (xy 283.053834 -286.67218)
			(xy 283.083399 -286.711524) (xy 283.10627 -286.755101) (xy 283.121854 -286.801782) (xy 283.129749 -286.850359)
			(xy 283.130244 -286.874966) (xy 283.469092 -286.874966) (xy 283.473052 -286.825912) (xy 283.484829 -286.778128)
			(xy 283.50412 -286.732852) (xy 283.530423 -286.691256) (xy 283.563058 -286.654419) (xy 283.601179 -286.623294)
			(xy 283.6438 -286.598687) (xy 283.689816 -286.581235) (xy 283.738035 -286.571391) (xy 283.78721 -286.56941)
			(xy 283.836065 -286.575342) (xy 283.883336 -286.589034) (xy 283.927798 -286.610132) (xy 283.968301 -286.638088)
			(xy 284.003794 -286.67218) (xy 284.033359 -286.711524) (xy 284.05623 -286.755101) (xy 284.071814 -286.801782)
			(xy 284.079709 -286.850359) (xy 284.080204 -286.874966) (xy 284.419052 -286.874966) (xy 284.423012 -286.825912)
			(xy 284.434789 -286.778128) (xy 284.45408 -286.732852) (xy 284.480383 -286.691256) (xy 284.513018 -286.654419)
			(xy 284.551139 -286.623294) (xy 284.59376 -286.598687) (xy 284.639776 -286.581235) (xy 284.687995 -286.571391)
			(xy 284.73717 -286.56941) (xy 284.786025 -286.575342) (xy 284.833296 -286.589034) (xy 284.877758 -286.610132)
			(xy 284.918261 -286.638088) (xy 284.953754 -286.67218) (xy 284.983319 -286.711524) (xy 285.00619 -286.755101)
			(xy 285.021774 -286.801782) (xy 285.029669 -286.850359) (xy 285.030164 -286.874966) (xy 285.369012 -286.874966)
			(xy 285.372972 -286.825912) (xy 285.384749 -286.778128) (xy 285.40404 -286.732852) (xy 285.430343 -286.691256)
			(xy 285.462978 -286.654419) (xy 285.501099 -286.623294) (xy 285.54372 -286.598687) (xy 285.589736 -286.581235)
			(xy 285.637955 -286.571391) (xy 285.68713 -286.56941) (xy 285.735985 -286.575342) (xy 285.783256 -286.589034)
			(xy 285.827718 -286.610132) (xy 285.868221 -286.638088) (xy 285.903714 -286.67218) (xy 285.933279 -286.711524)
			(xy 285.95615 -286.755101) (xy 285.971734 -286.801782) (xy 285.979629 -286.850359) (xy 285.980124 -286.874966)
			(xy 286.318972 -286.874966) (xy 286.322932 -286.825912) (xy 286.334709 -286.778128) (xy 286.354 -286.732852)
			(xy 286.380303 -286.691256) (xy 286.412938 -286.654419) (xy 286.451059 -286.623294) (xy 286.49368 -286.598687)
			(xy 286.539696 -286.581235) (xy 286.587915 -286.571391) (xy 286.63709 -286.56941) (xy 286.685945 -286.575342)
			(xy 286.733216 -286.589034) (xy 286.777678 -286.610132) (xy 286.818181 -286.638088) (xy 286.853674 -286.67218)
			(xy 286.883239 -286.711524) (xy 286.90611 -286.755101) (xy 286.921694 -286.801782) (xy 286.929589 -286.850359)
			(xy 286.930084 -286.874966) (xy 287.268932 -286.874966) (xy 287.272892 -286.825912) (xy 287.284669 -286.778128)
			(xy 287.30396 -286.732852) (xy 287.330263 -286.691256) (xy 287.362898 -286.654419) (xy 287.401019 -286.623294)
			(xy 287.44364 -286.598687) (xy 287.489656 -286.581235) (xy 287.537875 -286.571391) (xy 287.58705 -286.56941)
			(xy 287.635905 -286.575342) (xy 287.683176 -286.589034) (xy 287.727638 -286.610132) (xy 287.768141 -286.638088)
			(xy 287.803634 -286.67218) (xy 287.833199 -286.711524) (xy 287.85607 -286.755101) (xy 287.871654 -286.801782)
			(xy 287.879549 -286.850359) (xy 287.880044 -286.874966) (xy 288.218892 -286.874966) (xy 288.222852 -286.825912)
			(xy 288.234629 -286.778128) (xy 288.25392 -286.732852) (xy 288.280223 -286.691256) (xy 288.312858 -286.654419)
			(xy 288.350979 -286.623294) (xy 288.3936 -286.598687) (xy 288.439616 -286.581235) (xy 288.487835 -286.571391)
			(xy 288.53701 -286.56941) (xy 288.585865 -286.575342) (xy 288.633136 -286.589034) (xy 288.677598 -286.610132)
			(xy 288.718101 -286.638088) (xy 288.753594 -286.67218) (xy 288.783159 -286.711524) (xy 288.80603 -286.755101)
			(xy 288.821614 -286.801782) (xy 288.829509 -286.850359) (xy 288.830004 -286.874966) (xy 289.169106 -286.874966)
			(xy 289.173066 -286.825912) (xy 289.184843 -286.778128) (xy 289.204134 -286.732852) (xy 289.230437 -286.691256)
			(xy 289.263072 -286.654419) (xy 289.301193 -286.623294) (xy 289.343814 -286.598687) (xy 289.38983 -286.581235)
			(xy 289.438049 -286.571391) (xy 289.487224 -286.56941) (xy 289.536079 -286.575342) (xy 289.58335 -286.589034)
			(xy 289.627812 -286.610132) (xy 289.668315 -286.638088) (xy 289.703808 -286.67218) (xy 289.733373 -286.711524)
			(xy 289.756244 -286.755101) (xy 289.771828 -286.801782) (xy 289.779723 -286.850359) (xy 289.780218 -286.874966)
			(xy 290.119066 -286.874966) (xy 290.123026 -286.825912) (xy 290.134803 -286.778128) (xy 290.154094 -286.732852)
			(xy 290.180397 -286.691256) (xy 290.213032 -286.654419) (xy 290.251153 -286.623294) (xy 290.293774 -286.598687)
			(xy 290.33979 -286.581235) (xy 290.388009 -286.571391) (xy 290.437184 -286.56941) (xy 290.486039 -286.575342)
			(xy 290.53331 -286.589034) (xy 290.577772 -286.610132) (xy 290.618275 -286.638088) (xy 290.653768 -286.67218)
			(xy 290.683333 -286.711524) (xy 290.706204 -286.755101) (xy 290.721788 -286.801782) (xy 290.729683 -286.850359)
			(xy 290.730178 -286.874966) (xy 292.018986 -286.874966) (xy 292.022946 -286.825912) (xy 292.034723 -286.778128)
			(xy 292.054014 -286.732852) (xy 292.080317 -286.691256) (xy 292.112952 -286.654419) (xy 292.151073 -286.623294)
			(xy 292.193694 -286.598687) (xy 292.23971 -286.581235) (xy 292.287929 -286.571391) (xy 292.337104 -286.56941)
			(xy 292.385959 -286.575342) (xy 292.43323 -286.589034) (xy 292.477692 -286.610132) (xy 292.518195 -286.638088)
			(xy 292.553688 -286.67218) (xy 292.583253 -286.711524) (xy 292.606124 -286.755101) (xy 292.621708 -286.801782)
			(xy 292.629603 -286.850359) (xy 292.630098 -286.874966) (xy 292.968946 -286.874966) (xy 292.972906 -286.825912)
			(xy 292.984683 -286.778128) (xy 293.003974 -286.732852) (xy 293.030277 -286.691256) (xy 293.062912 -286.654419)
			(xy 293.101033 -286.623294) (xy 293.143654 -286.598687) (xy 293.18967 -286.581235) (xy 293.237889 -286.571391)
			(xy 293.287064 -286.56941) (xy 293.335919 -286.575342) (xy 293.38319 -286.589034) (xy 293.427652 -286.610132)
			(xy 293.468155 -286.638088) (xy 293.503648 -286.67218) (xy 293.533213 -286.711524) (xy 293.556084 -286.755101)
			(xy 293.571668 -286.801782) (xy 293.579563 -286.850359) (xy 293.580058 -286.874966) (xy 293.918906 -286.874966)
			(xy 293.922866 -286.825912) (xy 293.934643 -286.778128) (xy 293.953934 -286.732852) (xy 293.980237 -286.691256)
			(xy 294.012872 -286.654419) (xy 294.050993 -286.623294) (xy 294.093614 -286.598687) (xy 294.13963 -286.581235)
			(xy 294.187849 -286.571391) (xy 294.237024 -286.56941) (xy 294.285879 -286.575342) (xy 294.33315 -286.589034)
			(xy 294.377612 -286.610132) (xy 294.418115 -286.638088) (xy 294.453608 -286.67218) (xy 294.483173 -286.711524)
			(xy 294.506044 -286.755101) (xy 294.521628 -286.801782) (xy 294.529523 -286.850359) (xy 294.530018 -286.874966)
			(xy 294.86912 -286.874966) (xy 294.87308 -286.825912) (xy 294.884857 -286.778128) (xy 294.904148 -286.732852)
			(xy 294.930451 -286.691256) (xy 294.963086 -286.654419) (xy 295.001207 -286.623294) (xy 295.043828 -286.598687)
			(xy 295.089844 -286.581235) (xy 295.138063 -286.571391) (xy 295.187238 -286.56941) (xy 295.236093 -286.575342)
			(xy 295.283364 -286.589034) (xy 295.327826 -286.610132) (xy 295.368329 -286.638088) (xy 295.403822 -286.67218)
			(xy 295.433387 -286.711524) (xy 295.456258 -286.755101) (xy 295.471842 -286.801782) (xy 295.479737 -286.850359)
			(xy 295.480232 -286.874966) (xy 295.81908 -286.874966) (xy 295.82304 -286.825912) (xy 295.834817 -286.778128)
			(xy 295.854108 -286.732852) (xy 295.880411 -286.691256) (xy 295.913046 -286.654419) (xy 295.951167 -286.623294)
			(xy 295.993788 -286.598687) (xy 296.039804 -286.581235) (xy 296.088023 -286.571391) (xy 296.137198 -286.56941)
			(xy 296.186053 -286.575342) (xy 296.233324 -286.589034) (xy 296.277786 -286.610132) (xy 296.318289 -286.638088)
			(xy 296.353782 -286.67218) (xy 296.383347 -286.711524) (xy 296.406218 -286.755101) (xy 296.421802 -286.801782)
			(xy 296.429697 -286.850359) (xy 296.430192 -286.874966) (xy 296.76904 -286.874966) (xy 296.773 -286.825912)
			(xy 296.784777 -286.778128) (xy 296.804068 -286.732852) (xy 296.830371 -286.691256) (xy 296.863006 -286.654419)
			(xy 296.901127 -286.623294) (xy 296.943748 -286.598687) (xy 296.989764 -286.581235) (xy 297.037983 -286.571391)
			(xy 297.087158 -286.56941) (xy 297.136013 -286.575342) (xy 297.183284 -286.589034) (xy 297.227746 -286.610132)
			(xy 297.268249 -286.638088) (xy 297.303742 -286.67218) (xy 297.333307 -286.711524) (xy 297.356178 -286.755101)
			(xy 297.371762 -286.801782) (xy 297.379657 -286.850359) (xy 297.380152 -286.874966) (xy 297.719 -286.874966)
			(xy 297.72296 -286.825912) (xy 297.734737 -286.778128) (xy 297.754028 -286.732852) (xy 297.780331 -286.691256)
			(xy 297.812966 -286.654419) (xy 297.851087 -286.623294) (xy 297.893708 -286.598687) (xy 297.939724 -286.581235)
			(xy 297.987943 -286.571391) (xy 298.037118 -286.56941) (xy 298.085973 -286.575342) (xy 298.133244 -286.589034)
			(xy 298.177706 -286.610132) (xy 298.218209 -286.638088) (xy 298.253702 -286.67218) (xy 298.283267 -286.711524)
			(xy 298.306138 -286.755101) (xy 298.321722 -286.801782) (xy 298.329617 -286.850359) (xy 298.330112 -286.874966)
			(xy 298.66896 -286.874966) (xy 298.67292 -286.825912) (xy 298.684697 -286.778128) (xy 298.703988 -286.732852)
			(xy 298.730291 -286.691256) (xy 298.762926 -286.654419) (xy 298.801047 -286.623294) (xy 298.843668 -286.598687)
			(xy 298.889684 -286.581235) (xy 298.937903 -286.571391) (xy 298.987078 -286.56941) (xy 299.035933 -286.575342)
			(xy 299.083204 -286.589034) (xy 299.127666 -286.610132) (xy 299.168169 -286.638088) (xy 299.203662 -286.67218)
			(xy 299.233227 -286.711524) (xy 299.256098 -286.755101) (xy 299.271682 -286.801782) (xy 299.279577 -286.850359)
			(xy 299.280072 -286.874966) (xy 299.61892 -286.874966) (xy 299.62288 -286.825912) (xy 299.634657 -286.778128)
			(xy 299.653948 -286.732852) (xy 299.680251 -286.691256) (xy 299.712886 -286.654419) (xy 299.751007 -286.623294)
			(xy 299.793628 -286.598687) (xy 299.839644 -286.581235) (xy 299.887863 -286.571391) (xy 299.937038 -286.56941)
			(xy 299.985893 -286.575342) (xy 300.033164 -286.589034) (xy 300.077626 -286.610132) (xy 300.118129 -286.638088)
			(xy 300.153622 -286.67218) (xy 300.183187 -286.711524) (xy 300.206058 -286.755101) (xy 300.221642 -286.801782)
			(xy 300.229537 -286.850359) (xy 300.230032 -286.874966) (xy 300.56888 -286.874966) (xy 300.57284 -286.825912)
			(xy 300.584617 -286.778128) (xy 300.603908 -286.732852) (xy 300.630211 -286.691256) (xy 300.662846 -286.654419)
			(xy 300.700967 -286.623294) (xy 300.743588 -286.598687) (xy 300.789604 -286.581235) (xy 300.837823 -286.571391)
			(xy 300.886998 -286.56941) (xy 300.935853 -286.575342) (xy 300.983124 -286.589034) (xy 301.027586 -286.610132)
			(xy 301.068089 -286.638088) (xy 301.103582 -286.67218) (xy 301.133147 -286.711524) (xy 301.156018 -286.755101)
			(xy 301.171602 -286.801782) (xy 301.179497 -286.850359) (xy 301.179992 -286.874966) (xy 301.519094 -286.874966)
			(xy 301.523054 -286.825912) (xy 301.534831 -286.778128) (xy 301.554122 -286.732852) (xy 301.580425 -286.691256)
			(xy 301.61306 -286.654419) (xy 301.651181 -286.623294) (xy 301.693802 -286.598687) (xy 301.739818 -286.581235)
			(xy 301.788037 -286.571391) (xy 301.837212 -286.56941) (xy 301.886067 -286.575342) (xy 301.933338 -286.589034)
			(xy 301.9778 -286.610132) (xy 302.018303 -286.638088) (xy 302.053796 -286.67218) (xy 302.083361 -286.711524)
			(xy 302.106232 -286.755101) (xy 302.121816 -286.801782) (xy 302.129711 -286.850359) (xy 302.130206 -286.874966)
			(xy 302.469054 -286.874966) (xy 302.473014 -286.825912) (xy 302.484791 -286.778128) (xy 302.504082 -286.732852)
			(xy 302.530385 -286.691256) (xy 302.56302 -286.654419) (xy 302.601141 -286.623294) (xy 302.643762 -286.598687)
			(xy 302.689778 -286.581235) (xy 302.737997 -286.571391) (xy 302.787172 -286.56941) (xy 302.836027 -286.575342)
			(xy 302.883298 -286.589034) (xy 302.92776 -286.610132) (xy 302.968263 -286.638088) (xy 303.003756 -286.67218)
			(xy 303.033321 -286.711524) (xy 303.056192 -286.755101) (xy 303.071776 -286.801782) (xy 303.079671 -286.850359)
			(xy 303.080166 -286.874966) (xy 303.079671 -286.899573) (xy 303.071776 -286.94815) (xy 303.056192 -286.994831)
			(xy 303.033321 -287.038408) (xy 303.003756 -287.077752) (xy 302.968263 -287.111844) (xy 302.92776 -287.1398)
			(xy 302.883298 -287.160898) (xy 302.836027 -287.17459) (xy 302.787172 -287.180522) (xy 302.737997 -287.178541)
			(xy 302.689778 -287.168697) (xy 302.643762 -287.151245) (xy 302.601141 -287.126638) (xy 302.56302 -287.095513)
			(xy 302.530385 -287.058676) (xy 302.504082 -287.01708) (xy 302.484791 -286.971804) (xy 302.473014 -286.92402)
			(xy 302.469054 -286.874966) (xy 302.130206 -286.874966) (xy 302.129711 -286.899573) (xy 302.121816 -286.94815)
			(xy 302.106232 -286.994831) (xy 302.083361 -287.038408) (xy 302.053796 -287.077752) (xy 302.018303 -287.111844)
			(xy 301.9778 -287.1398) (xy 301.933338 -287.160898) (xy 301.886067 -287.17459) (xy 301.837212 -287.180522)
			(xy 301.788037 -287.178541) (xy 301.739818 -287.168697) (xy 301.693802 -287.151245) (xy 301.651181 -287.126638)
			(xy 301.61306 -287.095513) (xy 301.580425 -287.058676) (xy 301.554122 -287.01708) (xy 301.534831 -286.971804)
			(xy 301.523054 -286.92402) (xy 301.519094 -286.874966) (xy 301.179992 -286.874966) (xy 301.179497 -286.899573)
			(xy 301.171602 -286.94815) (xy 301.156018 -286.994831) (xy 301.133147 -287.038408) (xy 301.103582 -287.077752)
			(xy 301.068089 -287.111844) (xy 301.027586 -287.1398) (xy 300.983124 -287.160898) (xy 300.935853 -287.17459)
			(xy 300.886998 -287.180522) (xy 300.837823 -287.178541) (xy 300.789604 -287.168697) (xy 300.743588 -287.151245)
			(xy 300.700967 -287.126638) (xy 300.662846 -287.095513) (xy 300.630211 -287.058676) (xy 300.603908 -287.01708)
			(xy 300.584617 -286.971804) (xy 300.57284 -286.92402) (xy 300.56888 -286.874966) (xy 300.230032 -286.874966)
			(xy 300.229537 -286.899573) (xy 300.221642 -286.94815) (xy 300.206058 -286.994831) (xy 300.183187 -287.038408)
			(xy 300.153622 -287.077752) (xy 300.118129 -287.111844) (xy 300.077626 -287.1398) (xy 300.033164 -287.160898)
			(xy 299.985893 -287.17459) (xy 299.937038 -287.180522) (xy 299.887863 -287.178541) (xy 299.839644 -287.168697)
			(xy 299.793628 -287.151245) (xy 299.751007 -287.126638) (xy 299.712886 -287.095513) (xy 299.680251 -287.058676)
			(xy 299.653948 -287.01708) (xy 299.634657 -286.971804) (xy 299.62288 -286.92402) (xy 299.61892 -286.874966)
			(xy 299.280072 -286.874966) (xy 299.279577 -286.899573) (xy 299.271682 -286.94815) (xy 299.256098 -286.994831)
			(xy 299.233227 -287.038408) (xy 299.203662 -287.077752) (xy 299.168169 -287.111844) (xy 299.127666 -287.1398)
			(xy 299.083204 -287.160898) (xy 299.035933 -287.17459) (xy 298.987078 -287.180522) (xy 298.937903 -287.178541)
			(xy 298.889684 -287.168697) (xy 298.843668 -287.151245) (xy 298.801047 -287.126638) (xy 298.762926 -287.095513)
			(xy 298.730291 -287.058676) (xy 298.703988 -287.01708) (xy 298.684697 -286.971804) (xy 298.67292 -286.92402)
			(xy 298.66896 -286.874966) (xy 298.330112 -286.874966) (xy 298.329617 -286.899573) (xy 298.321722 -286.94815)
			(xy 298.306138 -286.994831) (xy 298.283267 -287.038408) (xy 298.253702 -287.077752) (xy 298.218209 -287.111844)
			(xy 298.177706 -287.1398) (xy 298.133244 -287.160898) (xy 298.085973 -287.17459) (xy 298.037118 -287.180522)
			(xy 297.987943 -287.178541) (xy 297.939724 -287.168697) (xy 297.893708 -287.151245) (xy 297.851087 -287.126638)
			(xy 297.812966 -287.095513) (xy 297.780331 -287.058676) (xy 297.754028 -287.01708) (xy 297.734737 -286.971804)
			(xy 297.72296 -286.92402) (xy 297.719 -286.874966) (xy 297.380152 -286.874966) (xy 297.379657 -286.899573)
			(xy 297.371762 -286.94815) (xy 297.356178 -286.994831) (xy 297.333307 -287.038408) (xy 297.303742 -287.077752)
			(xy 297.268249 -287.111844) (xy 297.227746 -287.1398) (xy 297.183284 -287.160898) (xy 297.136013 -287.17459)
			(xy 297.087158 -287.180522) (xy 297.037983 -287.178541) (xy 296.989764 -287.168697) (xy 296.943748 -287.151245)
			(xy 296.901127 -287.126638) (xy 296.863006 -287.095513) (xy 296.830371 -287.058676) (xy 296.804068 -287.01708)
			(xy 296.784777 -286.971804) (xy 296.773 -286.92402) (xy 296.76904 -286.874966) (xy 296.430192 -286.874966)
			(xy 296.429697 -286.899573) (xy 296.421802 -286.94815) (xy 296.406218 -286.994831) (xy 296.383347 -287.038408)
			(xy 296.353782 -287.077752) (xy 296.318289 -287.111844) (xy 296.277786 -287.1398) (xy 296.233324 -287.160898)
			(xy 296.186053 -287.17459) (xy 296.137198 -287.180522) (xy 296.088023 -287.178541) (xy 296.039804 -287.168697)
			(xy 295.993788 -287.151245) (xy 295.951167 -287.126638) (xy 295.913046 -287.095513) (xy 295.880411 -287.058676)
			(xy 295.854108 -287.01708) (xy 295.834817 -286.971804) (xy 295.82304 -286.92402) (xy 295.81908 -286.874966)
			(xy 295.480232 -286.874966) (xy 295.479737 -286.899573) (xy 295.471842 -286.94815) (xy 295.456258 -286.994831)
			(xy 295.433387 -287.038408) (xy 295.403822 -287.077752) (xy 295.368329 -287.111844) (xy 295.327826 -287.1398)
			(xy 295.283364 -287.160898) (xy 295.236093 -287.17459) (xy 295.187238 -287.180522) (xy 295.138063 -287.178541)
			(xy 295.089844 -287.168697) (xy 295.043828 -287.151245) (xy 295.001207 -287.126638) (xy 294.963086 -287.095513)
			(xy 294.930451 -287.058676) (xy 294.904148 -287.01708) (xy 294.884857 -286.971804) (xy 294.87308 -286.92402)
			(xy 294.86912 -286.874966) (xy 294.530018 -286.874966) (xy 294.529523 -286.899573) (xy 294.521628 -286.94815)
			(xy 294.506044 -286.994831) (xy 294.483173 -287.038408) (xy 294.453608 -287.077752) (xy 294.418115 -287.111844)
			(xy 294.377612 -287.1398) (xy 294.33315 -287.160898) (xy 294.285879 -287.17459) (xy 294.237024 -287.180522)
			(xy 294.187849 -287.178541) (xy 294.13963 -287.168697) (xy 294.093614 -287.151245) (xy 294.050993 -287.126638)
			(xy 294.012872 -287.095513) (xy 293.980237 -287.058676) (xy 293.953934 -287.01708) (xy 293.934643 -286.971804)
			(xy 293.922866 -286.92402) (xy 293.918906 -286.874966) (xy 293.580058 -286.874966) (xy 293.579563 -286.899573)
			(xy 293.571668 -286.94815) (xy 293.556084 -286.994831) (xy 293.533213 -287.038408) (xy 293.503648 -287.077752)
			(xy 293.468155 -287.111844) (xy 293.427652 -287.1398) (xy 293.38319 -287.160898) (xy 293.335919 -287.17459)
			(xy 293.287064 -287.180522) (xy 293.237889 -287.178541) (xy 293.18967 -287.168697) (xy 293.143654 -287.151245)
			(xy 293.101033 -287.126638) (xy 293.062912 -287.095513) (xy 293.030277 -287.058676) (xy 293.003974 -287.01708)
			(xy 292.984683 -286.971804) (xy 292.972906 -286.92402) (xy 292.968946 -286.874966) (xy 292.630098 -286.874966)
			(xy 292.629603 -286.899573) (xy 292.621708 -286.94815) (xy 292.606124 -286.994831) (xy 292.583253 -287.038408)
			(xy 292.553688 -287.077752) (xy 292.518195 -287.111844) (xy 292.477692 -287.1398) (xy 292.43323 -287.160898)
			(xy 292.385959 -287.17459) (xy 292.337104 -287.180522) (xy 292.287929 -287.178541) (xy 292.23971 -287.168697)
			(xy 292.193694 -287.151245) (xy 292.151073 -287.126638) (xy 292.112952 -287.095513) (xy 292.080317 -287.058676)
			(xy 292.054014 -287.01708) (xy 292.034723 -286.971804) (xy 292.022946 -286.92402) (xy 292.018986 -286.874966)
			(xy 290.730178 -286.874966) (xy 290.729683 -286.899573) (xy 290.721788 -286.94815) (xy 290.706204 -286.994831)
			(xy 290.683333 -287.038408) (xy 290.653768 -287.077752) (xy 290.618275 -287.111844) (xy 290.577772 -287.1398)
			(xy 290.53331 -287.160898) (xy 290.486039 -287.17459) (xy 290.437184 -287.180522) (xy 290.388009 -287.178541)
			(xy 290.33979 -287.168697) (xy 290.293774 -287.151245) (xy 290.251153 -287.126638) (xy 290.213032 -287.095513)
			(xy 290.180397 -287.058676) (xy 290.154094 -287.01708) (xy 290.134803 -286.971804) (xy 290.123026 -286.92402)
			(xy 290.119066 -286.874966) (xy 289.780218 -286.874966) (xy 289.779723 -286.899573) (xy 289.771828 -286.94815)
			(xy 289.756244 -286.994831) (xy 289.733373 -287.038408) (xy 289.703808 -287.077752) (xy 289.668315 -287.111844)
			(xy 289.627812 -287.1398) (xy 289.58335 -287.160898) (xy 289.536079 -287.17459) (xy 289.487224 -287.180522)
			(xy 289.438049 -287.178541) (xy 289.38983 -287.168697) (xy 289.343814 -287.151245) (xy 289.301193 -287.126638)
			(xy 289.263072 -287.095513) (xy 289.230437 -287.058676) (xy 289.204134 -287.01708) (xy 289.184843 -286.971804)
			(xy 289.173066 -286.92402) (xy 289.169106 -286.874966) (xy 288.830004 -286.874966) (xy 288.829509 -286.899573)
			(xy 288.821614 -286.94815) (xy 288.80603 -286.994831) (xy 288.783159 -287.038408) (xy 288.753594 -287.077752)
			(xy 288.718101 -287.111844) (xy 288.677598 -287.1398) (xy 288.633136 -287.160898) (xy 288.585865 -287.17459)
			(xy 288.53701 -287.180522) (xy 288.487835 -287.178541) (xy 288.439616 -287.168697) (xy 288.3936 -287.151245)
			(xy 288.350979 -287.126638) (xy 288.312858 -287.095513) (xy 288.280223 -287.058676) (xy 288.25392 -287.01708)
			(xy 288.234629 -286.971804) (xy 288.222852 -286.92402) (xy 288.218892 -286.874966) (xy 287.880044 -286.874966)
			(xy 287.879549 -286.899573) (xy 287.871654 -286.94815) (xy 287.85607 -286.994831) (xy 287.833199 -287.038408)
			(xy 287.803634 -287.077752) (xy 287.768141 -287.111844) (xy 287.727638 -287.1398) (xy 287.683176 -287.160898)
			(xy 287.635905 -287.17459) (xy 287.58705 -287.180522) (xy 287.537875 -287.178541) (xy 287.489656 -287.168697)
			(xy 287.44364 -287.151245) (xy 287.401019 -287.126638) (xy 287.362898 -287.095513) (xy 287.330263 -287.058676)
			(xy 287.30396 -287.01708) (xy 287.284669 -286.971804) (xy 287.272892 -286.92402) (xy 287.268932 -286.874966)
			(xy 286.930084 -286.874966) (xy 286.929589 -286.899573) (xy 286.921694 -286.94815) (xy 286.90611 -286.994831)
			(xy 286.883239 -287.038408) (xy 286.853674 -287.077752) (xy 286.818181 -287.111844) (xy 286.777678 -287.1398)
			(xy 286.733216 -287.160898) (xy 286.685945 -287.17459) (xy 286.63709 -287.180522) (xy 286.587915 -287.178541)
			(xy 286.539696 -287.168697) (xy 286.49368 -287.151245) (xy 286.451059 -287.126638) (xy 286.412938 -287.095513)
			(xy 286.380303 -287.058676) (xy 286.354 -287.01708) (xy 286.334709 -286.971804) (xy 286.322932 -286.92402)
			(xy 286.318972 -286.874966) (xy 285.980124 -286.874966) (xy 285.979629 -286.899573) (xy 285.971734 -286.94815)
			(xy 285.95615 -286.994831) (xy 285.933279 -287.038408) (xy 285.903714 -287.077752) (xy 285.868221 -287.111844)
			(xy 285.827718 -287.1398) (xy 285.783256 -287.160898) (xy 285.735985 -287.17459) (xy 285.68713 -287.180522)
			(xy 285.637955 -287.178541) (xy 285.589736 -287.168697) (xy 285.54372 -287.151245) (xy 285.501099 -287.126638)
			(xy 285.462978 -287.095513) (xy 285.430343 -287.058676) (xy 285.40404 -287.01708) (xy 285.384749 -286.971804)
			(xy 285.372972 -286.92402) (xy 285.369012 -286.874966) (xy 285.030164 -286.874966) (xy 285.029669 -286.899573)
			(xy 285.021774 -286.94815) (xy 285.00619 -286.994831) (xy 284.983319 -287.038408) (xy 284.953754 -287.077752)
			(xy 284.918261 -287.111844) (xy 284.877758 -287.1398) (xy 284.833296 -287.160898) (xy 284.786025 -287.17459)
			(xy 284.73717 -287.180522) (xy 284.687995 -287.178541) (xy 284.639776 -287.168697) (xy 284.59376 -287.151245)
			(xy 284.551139 -287.126638) (xy 284.513018 -287.095513) (xy 284.480383 -287.058676) (xy 284.45408 -287.01708)
			(xy 284.434789 -286.971804) (xy 284.423012 -286.92402) (xy 284.419052 -286.874966) (xy 284.080204 -286.874966)
			(xy 284.079709 -286.899573) (xy 284.071814 -286.94815) (xy 284.05623 -286.994831) (xy 284.033359 -287.038408)
			(xy 284.003794 -287.077752) (xy 283.968301 -287.111844) (xy 283.927798 -287.1398) (xy 283.883336 -287.160898)
			(xy 283.836065 -287.17459) (xy 283.78721 -287.180522) (xy 283.738035 -287.178541) (xy 283.689816 -287.168697)
			(xy 283.6438 -287.151245) (xy 283.601179 -287.126638) (xy 283.563058 -287.095513) (xy 283.530423 -287.058676)
			(xy 283.50412 -287.01708) (xy 283.484829 -286.971804) (xy 283.473052 -286.92402) (xy 283.469092 -286.874966)
			(xy 283.130244 -286.874966) (xy 283.129749 -286.899573) (xy 283.121854 -286.94815) (xy 283.10627 -286.994831)
			(xy 283.083399 -287.038408) (xy 283.053834 -287.077752) (xy 283.018341 -287.111844) (xy 282.977838 -287.1398)
			(xy 282.933376 -287.160898) (xy 282.886105 -287.17459) (xy 282.83725 -287.180522) (xy 282.788075 -287.178541)
			(xy 282.739856 -287.168697) (xy 282.69384 -287.151245) (xy 282.651219 -287.126638) (xy 282.613098 -287.095513)
			(xy 282.580463 -287.058676) (xy 282.55416 -287.01708) (xy 282.534869 -286.971804) (xy 282.523092 -286.92402)
			(xy 282.519132 -286.874966) (xy 282.18003 -286.874966) (xy 282.179535 -286.899573) (xy 282.17164 -286.94815)
			(xy 282.156056 -286.994831) (xy 282.133185 -287.038408) (xy 282.10362 -287.077752) (xy 282.068127 -287.111844)
			(xy 282.027624 -287.1398) (xy 281.983162 -287.160898) (xy 281.935891 -287.17459) (xy 281.887036 -287.180522)
			(xy 281.837861 -287.178541) (xy 281.789642 -287.168697) (xy 281.743626 -287.151245) (xy 281.701005 -287.126638)
			(xy 281.662884 -287.095513) (xy 281.630249 -287.058676) (xy 281.603946 -287.01708) (xy 281.584655 -286.971804)
			(xy 281.572878 -286.92402) (xy 281.568918 -286.874966) (xy 281.23007 -286.874966) (xy 281.229575 -286.899573)
			(xy 281.22168 -286.94815) (xy 281.206096 -286.994831) (xy 281.183225 -287.038408) (xy 281.15366 -287.077752)
			(xy 281.118167 -287.111844) (xy 281.077664 -287.1398) (xy 281.033202 -287.160898) (xy 280.985931 -287.17459)
			(xy 280.937076 -287.180522) (xy 280.887901 -287.178541) (xy 280.839682 -287.168697) (xy 280.793666 -287.151245)
			(xy 280.751045 -287.126638) (xy 280.712924 -287.095513) (xy 280.680289 -287.058676) (xy 280.653986 -287.01708)
			(xy 280.634695 -286.971804) (xy 280.622918 -286.92402) (xy 280.618958 -286.874966) (xy 280.280662 -286.874966)
			(xy 280.280665 -286.875) (xy 280.276493 -286.925344) (xy 280.264093 -286.974314) (xy 280.243801 -287.020575)
			(xy 280.216171 -287.062866) (xy 280.181958 -287.100031) (xy 280.142093 -287.131059) (xy 280.097666 -287.155102)
			(xy 280.049887 -287.171505) (xy 280.00006 -287.17982) (xy 279.974802 -287.180274) (xy 279.962039 -287.180137)
			(xy 279.936604 -287.177978) (xy 279.924002 -287.175956) (xy 279.924002 -287.17621) (xy 279.900861 -287.171865)
			(xy 279.856187 -287.156999) (xy 279.814323 -287.135452) (xy 279.776263 -287.107736) (xy 279.742909 -287.074505)
			(xy 279.71505 -287.036549) (xy 279.693347 -286.994767) (xy 279.678314 -286.950148) (xy 279.673812 -286.927036)
			(xy 279.673812 -286.926528) (xy 279.672398 -286.919816) (xy 279.666476 -286.907449) (xy 279.662128 -286.902144)
			(xy 279.657394 -286.897076) (xy 279.645804 -286.889473) (xy 279.639268 -286.887158) (xy 279.553416 -286.859726)
			(xy 279.544447 -286.857272) (xy 279.525897 -286.858282) (xy 279.508936 -286.865863) (xy 279.502108 -286.872172)
			(xy 279.428956 -286.945324) (xy 279.422107 -286.952721) (xy 279.414373 -286.97132) (xy 279.41397 -286.981392)
			(xy 279.41397 -287.349946) (xy 305.793914 -287.349946) (xy 305.797874 -287.300892) (xy 305.809651 -287.253108)
			(xy 305.828942 -287.207832) (xy 305.855245 -287.166236) (xy 305.88788 -287.129399) (xy 305.926001 -287.098274)
			(xy 305.968622 -287.073667) (xy 306.014638 -287.056215) (xy 306.062857 -287.046371) (xy 306.112032 -287.04439)
			(xy 306.160887 -287.050322) (xy 306.208158 -287.064014) (xy 306.25262 -287.085112) (xy 306.293123 -287.113068)
			(xy 306.328616 -287.14716) (xy 306.358181 -287.186504) (xy 306.381052 -287.230081) (xy 306.396636 -287.276762)
			(xy 306.404531 -287.325339) (xy 306.405026 -287.349946) (xy 306.404531 -287.374553) (xy 306.404352 -287.375654)
			(xy 306.72303 -287.375654) (xy 306.72303 -287.324238) (xy 306.731073 -287.273456) (xy 306.746961 -287.224557)
			(xy 306.770304 -287.178745) (xy 306.800525 -287.137149) (xy 306.836881 -287.100793) (xy 306.878477 -287.070572)
			(xy 306.924289 -287.047229) (xy 306.973188 -287.031341) (xy 307.02397 -287.023298) (xy 307.075386 -287.023298)
			(xy 307.126168 -287.031341) (xy 307.175067 -287.047229) (xy 307.220879 -287.070572) (xy 307.262475 -287.100793)
			(xy 307.298831 -287.137149) (xy 307.329052 -287.178745) (xy 307.352395 -287.224557) (xy 307.368283 -287.273456)
			(xy 307.376326 -287.324238) (xy 307.37683 -287.349946) (xy 307.376326 -287.375654) (xy 307.673244 -287.375654)
			(xy 307.673244 -287.324238) (xy 307.681287 -287.273456) (xy 307.697175 -287.224557) (xy 307.720518 -287.178745)
			(xy 307.750739 -287.137149) (xy 307.787095 -287.100793) (xy 307.828691 -287.070572) (xy 307.874503 -287.047229)
			(xy 307.923402 -287.031341) (xy 307.974184 -287.023298) (xy 308.0256 -287.023298) (xy 308.076382 -287.031341)
			(xy 308.125281 -287.047229) (xy 308.171093 -287.070572) (xy 308.212689 -287.100793) (xy 308.249045 -287.137149)
			(xy 308.279266 -287.178745) (xy 308.302609 -287.224557) (xy 308.318497 -287.273456) (xy 308.32654 -287.324238)
			(xy 308.327044 -287.349946) (xy 308.644048 -287.349946) (xy 308.648008 -287.300892) (xy 308.659785 -287.253108)
			(xy 308.679076 -287.207832) (xy 308.705379 -287.166236) (xy 308.738014 -287.129399) (xy 308.776135 -287.098274)
			(xy 308.818756 -287.073667) (xy 308.864772 -287.056215) (xy 308.912991 -287.046371) (xy 308.962166 -287.04439)
			(xy 309.011021 -287.050322) (xy 309.058292 -287.064014) (xy 309.102754 -287.085112) (xy 309.143257 -287.113068)
			(xy 309.17875 -287.14716) (xy 309.208315 -287.186504) (xy 309.231186 -287.230081) (xy 309.24677 -287.276762)
			(xy 309.254665 -287.325339) (xy 309.25516 -287.349946) (xy 309.594008 -287.349946) (xy 309.597968 -287.300892)
			(xy 309.609745 -287.253108) (xy 309.629036 -287.207832) (xy 309.655339 -287.166236) (xy 309.687974 -287.129399)
			(xy 309.726095 -287.098274) (xy 309.768716 -287.073667) (xy 309.814732 -287.056215) (xy 309.862951 -287.046371)
			(xy 309.912126 -287.04439) (xy 309.960981 -287.050322) (xy 310.008252 -287.064014) (xy 310.052714 -287.085112)
			(xy 310.093217 -287.113068) (xy 310.12871 -287.14716) (xy 310.158275 -287.186504) (xy 310.181146 -287.230081)
			(xy 310.19673 -287.276762) (xy 310.204625 -287.325339) (xy 310.20512 -287.349946) (xy 310.543968 -287.349946)
			(xy 310.547928 -287.300892) (xy 310.559705 -287.253108) (xy 310.578996 -287.207832) (xy 310.605299 -287.166236)
			(xy 310.637934 -287.129399) (xy 310.676055 -287.098274) (xy 310.718676 -287.073667) (xy 310.764692 -287.056215)
			(xy 310.812911 -287.046371) (xy 310.862086 -287.04439) (xy 310.910941 -287.050322) (xy 310.958212 -287.064014)
			(xy 311.002674 -287.085112) (xy 311.043177 -287.113068) (xy 311.07867 -287.14716) (xy 311.108235 -287.186504)
			(xy 311.131106 -287.230081) (xy 311.14669 -287.276762) (xy 311.154585 -287.325339) (xy 311.15508 -287.349946)
			(xy 311.493674 -287.349946) (xy 311.497634 -287.300892) (xy 311.509411 -287.253108) (xy 311.528702 -287.207832)
			(xy 311.555005 -287.166236) (xy 311.58764 -287.129399) (xy 311.625761 -287.098274) (xy 311.668382 -287.073667)
			(xy 311.714398 -287.056215) (xy 311.762617 -287.046371) (xy 311.811792 -287.04439) (xy 311.860647 -287.050322)
			(xy 311.907918 -287.064014) (xy 311.95238 -287.085112) (xy 311.992883 -287.113068) (xy 312.028376 -287.14716)
			(xy 312.057941 -287.186504) (xy 312.080812 -287.230081) (xy 312.096396 -287.276762) (xy 312.104291 -287.325339)
			(xy 312.104786 -287.349946) (xy 312.443888 -287.349946) (xy 312.447848 -287.300892) (xy 312.459625 -287.253108)
			(xy 312.478916 -287.207832) (xy 312.505219 -287.166236) (xy 312.537854 -287.129399) (xy 312.575975 -287.098274)
			(xy 312.618596 -287.073667) (xy 312.664612 -287.056215) (xy 312.712831 -287.046371) (xy 312.762006 -287.04439)
			(xy 312.810861 -287.050322) (xy 312.858132 -287.064014) (xy 312.902594 -287.085112) (xy 312.943097 -287.113068)
			(xy 312.97859 -287.14716) (xy 313.008155 -287.186504) (xy 313.031026 -287.230081) (xy 313.04661 -287.276762)
			(xy 313.054505 -287.325339) (xy 313.055 -287.349946) (xy 313.054505 -287.374553) (xy 313.054326 -287.375654)
			(xy 313.373258 -287.375654) (xy 313.373258 -287.324238) (xy 313.381301 -287.273456) (xy 313.397189 -287.224557)
			(xy 313.420532 -287.178745) (xy 313.450753 -287.137149) (xy 313.487109 -287.100793) (xy 313.528705 -287.070572)
			(xy 313.574517 -287.047229) (xy 313.623416 -287.031341) (xy 313.674198 -287.023298) (xy 313.725614 -287.023298)
			(xy 313.776396 -287.031341) (xy 313.825295 -287.047229) (xy 313.871107 -287.070572) (xy 313.912703 -287.100793)
			(xy 313.949059 -287.137149) (xy 313.97928 -287.178745) (xy 314.002623 -287.224557) (xy 314.018511 -287.273456)
			(xy 314.026554 -287.324238) (xy 314.027058 -287.349946) (xy 314.026554 -287.375654) (xy 314.323218 -287.375654)
			(xy 314.323218 -287.324238) (xy 314.331261 -287.273456) (xy 314.347149 -287.224557) (xy 314.370492 -287.178745)
			(xy 314.400713 -287.137149) (xy 314.437069 -287.100793) (xy 314.478665 -287.070572) (xy 314.524477 -287.047229)
			(xy 314.573376 -287.031341) (xy 314.624158 -287.023298) (xy 314.675574 -287.023298) (xy 314.726356 -287.031341)
			(xy 314.775255 -287.047229) (xy 314.821067 -287.070572) (xy 314.862663 -287.100793) (xy 314.899019 -287.137149)
			(xy 314.92924 -287.178745) (xy 314.952583 -287.224557) (xy 314.968471 -287.273456) (xy 314.976514 -287.324238)
			(xy 314.977018 -287.349946) (xy 314.977013 -287.3502) (xy 315.294276 -287.3502) (xy 315.298236 -287.301146)
			(xy 315.310013 -287.253362) (xy 315.329304 -287.208086) (xy 315.355607 -287.16649) (xy 315.388242 -287.129653)
			(xy 315.426363 -287.098528) (xy 315.468984 -287.073921) (xy 315.515 -287.056469) (xy 315.563219 -287.046625)
			(xy 315.612394 -287.044644) (xy 315.661249 -287.050576) (xy 315.70852 -287.064268) (xy 315.752982 -287.085366)
			(xy 315.793485 -287.113322) (xy 315.828978 -287.147414) (xy 315.858543 -287.186758) (xy 315.881414 -287.230335)
			(xy 315.896998 -287.277016) (xy 315.904893 -287.325593) (xy 315.905388 -287.3502) (xy 315.904893 -287.374807)
			(xy 315.896998 -287.423384) (xy 315.881414 -287.470065) (xy 315.858543 -287.513642) (xy 315.828978 -287.552986)
			(xy 315.793485 -287.587078) (xy 315.752982 -287.615034) (xy 315.70852 -287.636132) (xy 315.661249 -287.649824)
			(xy 315.612394 -287.655756) (xy 315.563219 -287.653775) (xy 315.515 -287.643931) (xy 315.468984 -287.626479)
			(xy 315.426363 -287.601872) (xy 315.388242 -287.570747) (xy 315.355607 -287.53391) (xy 315.329304 -287.492314)
			(xy 315.310013 -287.447038) (xy 315.298236 -287.399254) (xy 315.294276 -287.3502) (xy 314.977013 -287.3502)
			(xy 314.976514 -287.375654) (xy 314.968471 -287.426436) (xy 314.952583 -287.475335) (xy 314.92924 -287.521147)
			(xy 314.899019 -287.562743) (xy 314.862663 -287.599099) (xy 314.821067 -287.62932) (xy 314.775255 -287.652663)
			(xy 314.726356 -287.668551) (xy 314.675574 -287.676594) (xy 314.624158 -287.676594) (xy 314.573376 -287.668551)
			(xy 314.524477 -287.652663) (xy 314.478665 -287.62932) (xy 314.437069 -287.599099) (xy 314.400713 -287.562743)
			(xy 314.370492 -287.521147) (xy 314.347149 -287.475335) (xy 314.331261 -287.426436) (xy 314.323218 -287.375654)
			(xy 314.026554 -287.375654) (xy 314.018511 -287.426436) (xy 314.002623 -287.475335) (xy 313.97928 -287.521147)
			(xy 313.949059 -287.562743) (xy 313.912703 -287.599099) (xy 313.871107 -287.62932) (xy 313.825295 -287.652663)
			(xy 313.776396 -287.668551) (xy 313.725614 -287.676594) (xy 313.674198 -287.676594) (xy 313.623416 -287.668551)
			(xy 313.574517 -287.652663) (xy 313.528705 -287.62932) (xy 313.487109 -287.599099) (xy 313.450753 -287.562743)
			(xy 313.420532 -287.521147) (xy 313.397189 -287.475335) (xy 313.381301 -287.426436) (xy 313.373258 -287.375654)
			(xy 313.054326 -287.375654) (xy 313.04661 -287.42313) (xy 313.031026 -287.469811) (xy 313.008155 -287.513388)
			(xy 312.97859 -287.552732) (xy 312.943097 -287.586824) (xy 312.902594 -287.61478) (xy 312.858132 -287.635878)
			(xy 312.810861 -287.64957) (xy 312.762006 -287.655502) (xy 312.712831 -287.653521) (xy 312.664612 -287.643677)
			(xy 312.618596 -287.626225) (xy 312.575975 -287.601618) (xy 312.537854 -287.570493) (xy 312.505219 -287.533656)
			(xy 312.478916 -287.49206) (xy 312.459625 -287.446784) (xy 312.447848 -287.399) (xy 312.443888 -287.349946)
			(xy 312.104786 -287.349946) (xy 312.104291 -287.374553) (xy 312.096396 -287.42313) (xy 312.080812 -287.469811)
			(xy 312.057941 -287.513388) (xy 312.028376 -287.552732) (xy 311.992883 -287.586824) (xy 311.95238 -287.61478)
			(xy 311.907918 -287.635878) (xy 311.860647 -287.64957) (xy 311.811792 -287.655502) (xy 311.762617 -287.653521)
			(xy 311.714398 -287.643677) (xy 311.668382 -287.626225) (xy 311.625761 -287.601618) (xy 311.58764 -287.570493)
			(xy 311.555005 -287.533656) (xy 311.528702 -287.49206) (xy 311.509411 -287.446784) (xy 311.497634 -287.399)
			(xy 311.493674 -287.349946) (xy 311.15508 -287.349946) (xy 311.154585 -287.374553) (xy 311.14669 -287.42313)
			(xy 311.131106 -287.469811) (xy 311.108235 -287.513388) (xy 311.07867 -287.552732) (xy 311.043177 -287.586824)
			(xy 311.002674 -287.61478) (xy 310.958212 -287.635878) (xy 310.910941 -287.64957) (xy 310.862086 -287.655502)
			(xy 310.812911 -287.653521) (xy 310.764692 -287.643677) (xy 310.718676 -287.626225) (xy 310.676055 -287.601618)
			(xy 310.637934 -287.570493) (xy 310.605299 -287.533656) (xy 310.578996 -287.49206) (xy 310.559705 -287.446784)
			(xy 310.547928 -287.399) (xy 310.543968 -287.349946) (xy 310.20512 -287.349946) (xy 310.204625 -287.374553)
			(xy 310.19673 -287.42313) (xy 310.181146 -287.469811) (xy 310.158275 -287.513388) (xy 310.12871 -287.552732)
			(xy 310.093217 -287.586824) (xy 310.052714 -287.61478) (xy 310.008252 -287.635878) (xy 309.960981 -287.64957)
			(xy 309.912126 -287.655502) (xy 309.862951 -287.653521) (xy 309.814732 -287.643677) (xy 309.768716 -287.626225)
			(xy 309.726095 -287.601618) (xy 309.687974 -287.570493) (xy 309.655339 -287.533656) (xy 309.629036 -287.49206)
			(xy 309.609745 -287.446784) (xy 309.597968 -287.399) (xy 309.594008 -287.349946) (xy 309.25516 -287.349946)
			(xy 309.254665 -287.374553) (xy 309.24677 -287.42313) (xy 309.231186 -287.469811) (xy 309.208315 -287.513388)
			(xy 309.17875 -287.552732) (xy 309.143257 -287.586824) (xy 309.102754 -287.61478) (xy 309.058292 -287.635878)
			(xy 309.011021 -287.64957) (xy 308.962166 -287.655502) (xy 308.912991 -287.653521) (xy 308.864772 -287.643677)
			(xy 308.818756 -287.626225) (xy 308.776135 -287.601618) (xy 308.738014 -287.570493) (xy 308.705379 -287.533656)
			(xy 308.679076 -287.49206) (xy 308.659785 -287.446784) (xy 308.648008 -287.399) (xy 308.644048 -287.349946)
			(xy 308.327044 -287.349946) (xy 308.32654 -287.375654) (xy 308.318497 -287.426436) (xy 308.302609 -287.475335)
			(xy 308.279266 -287.521147) (xy 308.249045 -287.562743) (xy 308.212689 -287.599099) (xy 308.171093 -287.62932)
			(xy 308.125281 -287.652663) (xy 308.076382 -287.668551) (xy 308.0256 -287.676594) (xy 307.974184 -287.676594)
			(xy 307.923402 -287.668551) (xy 307.874503 -287.652663) (xy 307.828691 -287.62932) (xy 307.787095 -287.599099)
			(xy 307.750739 -287.562743) (xy 307.720518 -287.521147) (xy 307.697175 -287.475335) (xy 307.681287 -287.426436)
			(xy 307.673244 -287.375654) (xy 307.376326 -287.375654) (xy 307.368283 -287.426436) (xy 307.352395 -287.475335)
			(xy 307.329052 -287.521147) (xy 307.298831 -287.562743) (xy 307.262475 -287.599099) (xy 307.220879 -287.62932)
			(xy 307.175067 -287.652663) (xy 307.126168 -287.668551) (xy 307.075386 -287.676594) (xy 307.02397 -287.676594)
			(xy 306.973188 -287.668551) (xy 306.924289 -287.652663) (xy 306.878477 -287.62932) (xy 306.836881 -287.599099)
			(xy 306.800525 -287.562743) (xy 306.770304 -287.521147) (xy 306.746961 -287.475335) (xy 306.731073 -287.426436)
			(xy 306.72303 -287.375654) (xy 306.404352 -287.375654) (xy 306.396636 -287.42313) (xy 306.381052 -287.469811)
			(xy 306.358181 -287.513388) (xy 306.328616 -287.552732) (xy 306.293123 -287.586824) (xy 306.25262 -287.61478)
			(xy 306.208158 -287.635878) (xy 306.160887 -287.64957) (xy 306.112032 -287.655502) (xy 306.062857 -287.653521)
			(xy 306.014638 -287.643677) (xy 305.968622 -287.626225) (xy 305.926001 -287.601618) (xy 305.88788 -287.570493)
			(xy 305.855245 -287.533656) (xy 305.828942 -287.49206) (xy 305.809651 -287.446784) (xy 305.797874 -287.399)
			(xy 305.793914 -287.349946) (xy 279.41397 -287.349946) (xy 279.41397 -287.824926) (xy 279.668998 -287.824926)
			(xy 279.672958 -287.775872) (xy 279.684735 -287.728088) (xy 279.704026 -287.682812) (xy 279.730329 -287.641216)
			(xy 279.762964 -287.604379) (xy 279.801085 -287.573254) (xy 279.843706 -287.548647) (xy 279.889722 -287.531195)
			(xy 279.937941 -287.521351) (xy 279.987116 -287.51937) (xy 280.035971 -287.525302) (xy 280.083242 -287.538994)
			(xy 280.127704 -287.560092) (xy 280.168207 -287.588048) (xy 280.2037 -287.62214) (xy 280.233265 -287.661484)
			(xy 280.256136 -287.705061) (xy 280.27172 -287.751742) (xy 280.279615 -287.800319) (xy 280.28011 -287.824926)
			(xy 280.618958 -287.824926) (xy 280.622918 -287.775872) (xy 280.634695 -287.728088) (xy 280.653986 -287.682812)
			(xy 280.680289 -287.641216) (xy 280.712924 -287.604379) (xy 280.751045 -287.573254) (xy 280.793666 -287.548647)
			(xy 280.839682 -287.531195) (xy 280.887901 -287.521351) (xy 280.937076 -287.51937) (xy 280.985931 -287.525302)
			(xy 281.033202 -287.538994) (xy 281.077664 -287.560092) (xy 281.118167 -287.588048) (xy 281.15366 -287.62214)
			(xy 281.183225 -287.661484) (xy 281.206096 -287.705061) (xy 281.22168 -287.751742) (xy 281.229575 -287.800319)
			(xy 281.23007 -287.824926) (xy 281.568918 -287.824926) (xy 281.572878 -287.775872) (xy 281.584655 -287.728088)
			(xy 281.603946 -287.682812) (xy 281.630249 -287.641216) (xy 281.662884 -287.604379) (xy 281.701005 -287.573254)
			(xy 281.743626 -287.548647) (xy 281.789642 -287.531195) (xy 281.837861 -287.521351) (xy 281.887036 -287.51937)
			(xy 281.935891 -287.525302) (xy 281.983162 -287.538994) (xy 282.027624 -287.560092) (xy 282.068127 -287.588048)
			(xy 282.10362 -287.62214) (xy 282.133185 -287.661484) (xy 282.156056 -287.705061) (xy 282.17164 -287.751742)
			(xy 282.179535 -287.800319) (xy 282.18003 -287.824926) (xy 282.519132 -287.824926) (xy 282.523092 -287.775872)
			(xy 282.534869 -287.728088) (xy 282.55416 -287.682812) (xy 282.580463 -287.641216) (xy 282.613098 -287.604379)
			(xy 282.651219 -287.573254) (xy 282.69384 -287.548647) (xy 282.739856 -287.531195) (xy 282.788075 -287.521351)
			(xy 282.83725 -287.51937) (xy 282.886105 -287.525302) (xy 282.933376 -287.538994) (xy 282.977838 -287.560092)
			(xy 283.018341 -287.588048) (xy 283.053834 -287.62214) (xy 283.083399 -287.661484) (xy 283.10627 -287.705061)
			(xy 283.121854 -287.751742) (xy 283.129749 -287.800319) (xy 283.130244 -287.824926) (xy 283.469092 -287.824926)
			(xy 283.473052 -287.775872) (xy 283.484829 -287.728088) (xy 283.50412 -287.682812) (xy 283.530423 -287.641216)
			(xy 283.563058 -287.604379) (xy 283.601179 -287.573254) (xy 283.6438 -287.548647) (xy 283.689816 -287.531195)
			(xy 283.738035 -287.521351) (xy 283.78721 -287.51937) (xy 283.836065 -287.525302) (xy 283.883336 -287.538994)
			(xy 283.927798 -287.560092) (xy 283.968301 -287.588048) (xy 284.003794 -287.62214) (xy 284.033359 -287.661484)
			(xy 284.05623 -287.705061) (xy 284.071814 -287.751742) (xy 284.079709 -287.800319) (xy 284.080204 -287.824926)
			(xy 284.419052 -287.824926) (xy 284.423012 -287.775872) (xy 284.434789 -287.728088) (xy 284.45408 -287.682812)
			(xy 284.480383 -287.641216) (xy 284.513018 -287.604379) (xy 284.551139 -287.573254) (xy 284.59376 -287.548647)
			(xy 284.639776 -287.531195) (xy 284.687995 -287.521351) (xy 284.73717 -287.51937) (xy 284.786025 -287.525302)
			(xy 284.833296 -287.538994) (xy 284.877758 -287.560092) (xy 284.918261 -287.588048) (xy 284.953754 -287.62214)
			(xy 284.983319 -287.661484) (xy 285.00619 -287.705061) (xy 285.021774 -287.751742) (xy 285.029669 -287.800319)
			(xy 285.030164 -287.824926) (xy 285.369012 -287.824926) (xy 285.372972 -287.775872) (xy 285.384749 -287.728088)
			(xy 285.40404 -287.682812) (xy 285.430343 -287.641216) (xy 285.462978 -287.604379) (xy 285.501099 -287.573254)
			(xy 285.54372 -287.548647) (xy 285.589736 -287.531195) (xy 285.637955 -287.521351) (xy 285.68713 -287.51937)
			(xy 285.735985 -287.525302) (xy 285.783256 -287.538994) (xy 285.827718 -287.560092) (xy 285.868221 -287.588048)
			(xy 285.903714 -287.62214) (xy 285.933279 -287.661484) (xy 285.95615 -287.705061) (xy 285.971734 -287.751742)
			(xy 285.979629 -287.800319) (xy 285.980124 -287.824926) (xy 286.318972 -287.824926) (xy 286.322932 -287.775872)
			(xy 286.334709 -287.728088) (xy 286.354 -287.682812) (xy 286.380303 -287.641216) (xy 286.412938 -287.604379)
			(xy 286.451059 -287.573254) (xy 286.49368 -287.548647) (xy 286.539696 -287.531195) (xy 286.587915 -287.521351)
			(xy 286.63709 -287.51937) (xy 286.685945 -287.525302) (xy 286.733216 -287.538994) (xy 286.777678 -287.560092)
			(xy 286.818181 -287.588048) (xy 286.853674 -287.62214) (xy 286.883239 -287.661484) (xy 286.90611 -287.705061)
			(xy 286.921694 -287.751742) (xy 286.929589 -287.800319) (xy 286.930084 -287.824926) (xy 287.268932 -287.824926)
			(xy 287.272892 -287.775872) (xy 287.284669 -287.728088) (xy 287.30396 -287.682812) (xy 287.330263 -287.641216)
			(xy 287.362898 -287.604379) (xy 287.401019 -287.573254) (xy 287.44364 -287.548647) (xy 287.489656 -287.531195)
			(xy 287.537875 -287.521351) (xy 287.58705 -287.51937) (xy 287.635905 -287.525302) (xy 287.683176 -287.538994)
			(xy 287.727638 -287.560092) (xy 287.768141 -287.588048) (xy 287.803634 -287.62214) (xy 287.833199 -287.661484)
			(xy 287.85607 -287.705061) (xy 287.871654 -287.751742) (xy 287.879549 -287.800319) (xy 287.880044 -287.824926)
			(xy 288.218892 -287.824926) (xy 288.222852 -287.775872) (xy 288.234629 -287.728088) (xy 288.25392 -287.682812)
			(xy 288.280223 -287.641216) (xy 288.312858 -287.604379) (xy 288.350979 -287.573254) (xy 288.3936 -287.548647)
			(xy 288.439616 -287.531195) (xy 288.487835 -287.521351) (xy 288.53701 -287.51937) (xy 288.585865 -287.525302)
			(xy 288.633136 -287.538994) (xy 288.677598 -287.560092) (xy 288.718101 -287.588048) (xy 288.753594 -287.62214)
			(xy 288.783159 -287.661484) (xy 288.80603 -287.705061) (xy 288.821614 -287.751742) (xy 288.829509 -287.800319)
			(xy 288.830004 -287.824926) (xy 289.169106 -287.824926) (xy 289.173066 -287.775872) (xy 289.184843 -287.728088)
			(xy 289.204134 -287.682812) (xy 289.230437 -287.641216) (xy 289.263072 -287.604379) (xy 289.301193 -287.573254)
			(xy 289.343814 -287.548647) (xy 289.38983 -287.531195) (xy 289.438049 -287.521351) (xy 289.487224 -287.51937)
			(xy 289.536079 -287.525302) (xy 289.58335 -287.538994) (xy 289.627812 -287.560092) (xy 289.668315 -287.588048)
			(xy 289.703808 -287.62214) (xy 289.733373 -287.661484) (xy 289.753566 -287.699958) (xy 290.143958 -287.699958)
			(xy 290.147918 -287.650904) (xy 290.159695 -287.60312) (xy 290.178986 -287.557844) (xy 290.205289 -287.516248)
			(xy 290.237924 -287.479411) (xy 290.276045 -287.448286) (xy 290.318666 -287.423679) (xy 290.364682 -287.406227)
			(xy 290.412901 -287.396383) (xy 290.462076 -287.394402) (xy 290.510931 -287.400334) (xy 290.558202 -287.414026)
			(xy 290.602664 -287.435124) (xy 290.643167 -287.46308) (xy 290.67866 -287.497172) (xy 290.708225 -287.536516)
			(xy 290.731096 -287.580093) (xy 290.74668 -287.626774) (xy 290.754575 -287.675351) (xy 290.75507 -287.699958)
			(xy 290.754575 -287.724565) (xy 290.74668 -287.773142) (xy 290.731096 -287.819823) (xy 290.708225 -287.8634)
			(xy 290.68083 -287.899856) (xy 292.018986 -287.899856) (xy 292.022946 -287.850802) (xy 292.034723 -287.803018)
			(xy 292.054014 -287.757742) (xy 292.080317 -287.716146) (xy 292.112952 -287.679309) (xy 292.151073 -287.648184)
			(xy 292.193694 -287.623577) (xy 292.23971 -287.606125) (xy 292.287929 -287.596281) (xy 292.337104 -287.5943)
			(xy 292.385959 -287.600232) (xy 292.43323 -287.613924) (xy 292.477692 -287.635022) (xy 292.518195 -287.662978)
			(xy 292.553688 -287.69707) (xy 292.583253 -287.736414) (xy 292.606124 -287.779991) (xy 292.621125 -287.824926)
			(xy 292.968946 -287.824926) (xy 292.972906 -287.775872) (xy 292.984683 -287.728088) (xy 293.003974 -287.682812)
			(xy 293.030277 -287.641216) (xy 293.062912 -287.604379) (xy 293.101033 -287.573254) (xy 293.143654 -287.548647)
			(xy 293.18967 -287.531195) (xy 293.237889 -287.521351) (xy 293.287064 -287.51937) (xy 293.335919 -287.525302)
			(xy 293.38319 -287.538994) (xy 293.427652 -287.560092) (xy 293.468155 -287.588048) (xy 293.503648 -287.62214)
			(xy 293.533213 -287.661484) (xy 293.556084 -287.705061) (xy 293.571668 -287.751742) (xy 293.579563 -287.800319)
			(xy 293.580058 -287.824926) (xy 293.918906 -287.824926) (xy 293.922866 -287.775872) (xy 293.934643 -287.728088)
			(xy 293.953934 -287.682812) (xy 293.980237 -287.641216) (xy 294.012872 -287.604379) (xy 294.050993 -287.573254)
			(xy 294.093614 -287.548647) (xy 294.13963 -287.531195) (xy 294.187849 -287.521351) (xy 294.237024 -287.51937)
			(xy 294.285879 -287.525302) (xy 294.33315 -287.538994) (xy 294.377612 -287.560092) (xy 294.418115 -287.588048)
			(xy 294.453608 -287.62214) (xy 294.483173 -287.661484) (xy 294.506044 -287.705061) (xy 294.521628 -287.751742)
			(xy 294.529523 -287.800319) (xy 294.530018 -287.824926) (xy 294.86912 -287.824926) (xy 294.87308 -287.775872)
			(xy 294.884857 -287.728088) (xy 294.904148 -287.682812) (xy 294.930451 -287.641216) (xy 294.963086 -287.604379)
			(xy 295.001207 -287.573254) (xy 295.043828 -287.548647) (xy 295.089844 -287.531195) (xy 295.138063 -287.521351)
			(xy 295.187238 -287.51937) (xy 295.236093 -287.525302) (xy 295.283364 -287.538994) (xy 295.327826 -287.560092)
			(xy 295.368329 -287.588048) (xy 295.403822 -287.62214) (xy 295.433387 -287.661484) (xy 295.456258 -287.705061)
			(xy 295.471842 -287.751742) (xy 295.479737 -287.800319) (xy 295.480232 -287.824926) (xy 295.81908 -287.824926)
			(xy 295.82304 -287.775872) (xy 295.834817 -287.728088) (xy 295.854108 -287.682812) (xy 295.880411 -287.641216)
			(xy 295.913046 -287.604379) (xy 295.951167 -287.573254) (xy 295.993788 -287.548647) (xy 296.039804 -287.531195)
			(xy 296.088023 -287.521351) (xy 296.137198 -287.51937) (xy 296.186053 -287.525302) (xy 296.233324 -287.538994)
			(xy 296.277786 -287.560092) (xy 296.318289 -287.588048) (xy 296.353782 -287.62214) (xy 296.383347 -287.661484)
			(xy 296.406218 -287.705061) (xy 296.421802 -287.751742) (xy 296.429697 -287.800319) (xy 296.430192 -287.824926)
			(xy 296.76904 -287.824926) (xy 296.773 -287.775872) (xy 296.784777 -287.728088) (xy 296.804068 -287.682812)
			(xy 296.830371 -287.641216) (xy 296.863006 -287.604379) (xy 296.901127 -287.573254) (xy 296.943748 -287.548647)
			(xy 296.989764 -287.531195) (xy 297.037983 -287.521351) (xy 297.087158 -287.51937) (xy 297.136013 -287.525302)
			(xy 297.183284 -287.538994) (xy 297.227746 -287.560092) (xy 297.268249 -287.588048) (xy 297.303742 -287.62214)
			(xy 297.333307 -287.661484) (xy 297.356178 -287.705061) (xy 297.371762 -287.751742) (xy 297.379657 -287.800319)
			(xy 297.380152 -287.824926) (xy 297.719 -287.824926) (xy 297.72296 -287.775872) (xy 297.734737 -287.728088)
			(xy 297.754028 -287.682812) (xy 297.780331 -287.641216) (xy 297.812966 -287.604379) (xy 297.851087 -287.573254)
			(xy 297.893708 -287.548647) (xy 297.939724 -287.531195) (xy 297.987943 -287.521351) (xy 298.037118 -287.51937)
			(xy 298.085973 -287.525302) (xy 298.133244 -287.538994) (xy 298.177706 -287.560092) (xy 298.218209 -287.588048)
			(xy 298.253702 -287.62214) (xy 298.283267 -287.661484) (xy 298.306138 -287.705061) (xy 298.321722 -287.751742)
			(xy 298.329617 -287.800319) (xy 298.330112 -287.824926) (xy 298.66896 -287.824926) (xy 298.67292 -287.775872)
			(xy 298.684697 -287.728088) (xy 298.703988 -287.682812) (xy 298.730291 -287.641216) (xy 298.762926 -287.604379)
			(xy 298.801047 -287.573254) (xy 298.843668 -287.548647) (xy 298.889684 -287.531195) (xy 298.937903 -287.521351)
			(xy 298.987078 -287.51937) (xy 299.035933 -287.525302) (xy 299.083204 -287.538994) (xy 299.127666 -287.560092)
			(xy 299.168169 -287.588048) (xy 299.203662 -287.62214) (xy 299.233227 -287.661484) (xy 299.256098 -287.705061)
			(xy 299.271682 -287.751742) (xy 299.279577 -287.800319) (xy 299.280072 -287.824926) (xy 299.61892 -287.824926)
			(xy 299.62288 -287.775872) (xy 299.634657 -287.728088) (xy 299.653948 -287.682812) (xy 299.680251 -287.641216)
			(xy 299.712886 -287.604379) (xy 299.751007 -287.573254) (xy 299.793628 -287.548647) (xy 299.839644 -287.531195)
			(xy 299.887863 -287.521351) (xy 299.937038 -287.51937) (xy 299.985893 -287.525302) (xy 300.033164 -287.538994)
			(xy 300.077626 -287.560092) (xy 300.118129 -287.588048) (xy 300.153622 -287.62214) (xy 300.183187 -287.661484)
			(xy 300.206058 -287.705061) (xy 300.221642 -287.751742) (xy 300.229537 -287.800319) (xy 300.230032 -287.824926)
			(xy 300.56888 -287.824926) (xy 300.57284 -287.775872) (xy 300.584617 -287.728088) (xy 300.603908 -287.682812)
			(xy 300.630211 -287.641216) (xy 300.662846 -287.604379) (xy 300.700967 -287.573254) (xy 300.743588 -287.548647)
			(xy 300.789604 -287.531195) (xy 300.837823 -287.521351) (xy 300.886998 -287.51937) (xy 300.935853 -287.525302)
			(xy 300.983124 -287.538994) (xy 301.027586 -287.560092) (xy 301.068089 -287.588048) (xy 301.103582 -287.62214)
			(xy 301.133147 -287.661484) (xy 301.156018 -287.705061) (xy 301.171602 -287.751742) (xy 301.179497 -287.800319)
			(xy 301.179992 -287.824926) (xy 302.469054 -287.824926) (xy 302.473014 -287.775872) (xy 302.484791 -287.728088)
			(xy 302.504082 -287.682812) (xy 302.530385 -287.641216) (xy 302.56302 -287.604379) (xy 302.601141 -287.573254)
			(xy 302.643762 -287.548647) (xy 302.689778 -287.531195) (xy 302.737997 -287.521351) (xy 302.787172 -287.51937)
			(xy 302.836027 -287.525302) (xy 302.883298 -287.538994) (xy 302.92776 -287.560092) (xy 302.968263 -287.588048)
			(xy 303.003756 -287.62214) (xy 303.033321 -287.661484) (xy 303.056192 -287.705061) (xy 303.071776 -287.751742)
			(xy 303.079671 -287.800319) (xy 303.080166 -287.824926) (xy 303.079671 -287.849533) (xy 303.071776 -287.89811)
			(xy 303.056192 -287.944791) (xy 303.033321 -287.988368) (xy 303.003756 -288.027712) (xy 302.968263 -288.061804)
			(xy 302.92776 -288.08976) (xy 302.883298 -288.110858) (xy 302.836027 -288.12455) (xy 302.787172 -288.130482)
			(xy 302.737997 -288.128501) (xy 302.689778 -288.118657) (xy 302.643762 -288.101205) (xy 302.601141 -288.076598)
			(xy 302.56302 -288.045473) (xy 302.530385 -288.008636) (xy 302.504082 -287.96704) (xy 302.484791 -287.921764)
			(xy 302.473014 -287.87398) (xy 302.469054 -287.824926) (xy 301.179992 -287.824926) (xy 301.179497 -287.849533)
			(xy 301.171602 -287.89811) (xy 301.156018 -287.944791) (xy 301.133147 -287.988368) (xy 301.103582 -288.027712)
			(xy 301.068089 -288.061804) (xy 301.027586 -288.08976) (xy 300.983124 -288.110858) (xy 300.935853 -288.12455)
			(xy 300.886998 -288.130482) (xy 300.837823 -288.128501) (xy 300.789604 -288.118657) (xy 300.743588 -288.101205)
			(xy 300.700967 -288.076598) (xy 300.662846 -288.045473) (xy 300.630211 -288.008636) (xy 300.603908 -287.96704)
			(xy 300.584617 -287.921764) (xy 300.57284 -287.87398) (xy 300.56888 -287.824926) (xy 300.230032 -287.824926)
			(xy 300.229537 -287.849533) (xy 300.221642 -287.89811) (xy 300.206058 -287.944791) (xy 300.183187 -287.988368)
			(xy 300.153622 -288.027712) (xy 300.118129 -288.061804) (xy 300.077626 -288.08976) (xy 300.033164 -288.110858)
			(xy 299.985893 -288.12455) (xy 299.937038 -288.130482) (xy 299.887863 -288.128501) (xy 299.839644 -288.118657)
			(xy 299.793628 -288.101205) (xy 299.751007 -288.076598) (xy 299.712886 -288.045473) (xy 299.680251 -288.008636)
			(xy 299.653948 -287.96704) (xy 299.634657 -287.921764) (xy 299.62288 -287.87398) (xy 299.61892 -287.824926)
			(xy 299.280072 -287.824926) (xy 299.279577 -287.849533) (xy 299.271682 -287.89811) (xy 299.256098 -287.944791)
			(xy 299.233227 -287.988368) (xy 299.203662 -288.027712) (xy 299.168169 -288.061804) (xy 299.127666 -288.08976)
			(xy 299.083204 -288.110858) (xy 299.035933 -288.12455) (xy 298.987078 -288.130482) (xy 298.937903 -288.128501)
			(xy 298.889684 -288.118657) (xy 298.843668 -288.101205) (xy 298.801047 -288.076598) (xy 298.762926 -288.045473)
			(xy 298.730291 -288.008636) (xy 298.703988 -287.96704) (xy 298.684697 -287.921764) (xy 298.67292 -287.87398)
			(xy 298.66896 -287.824926) (xy 298.330112 -287.824926) (xy 298.329617 -287.849533) (xy 298.321722 -287.89811)
			(xy 298.306138 -287.944791) (xy 298.283267 -287.988368) (xy 298.253702 -288.027712) (xy 298.218209 -288.061804)
			(xy 298.177706 -288.08976) (xy 298.133244 -288.110858) (xy 298.085973 -288.12455) (xy 298.037118 -288.130482)
			(xy 297.987943 -288.128501) (xy 297.939724 -288.118657) (xy 297.893708 -288.101205) (xy 297.851087 -288.076598)
			(xy 297.812966 -288.045473) (xy 297.780331 -288.008636) (xy 297.754028 -287.96704) (xy 297.734737 -287.921764)
			(xy 297.72296 -287.87398) (xy 297.719 -287.824926) (xy 297.380152 -287.824926) (xy 297.379657 -287.849533)
			(xy 297.371762 -287.89811) (xy 297.356178 -287.944791) (xy 297.333307 -287.988368) (xy 297.303742 -288.027712)
			(xy 297.268249 -288.061804) (xy 297.227746 -288.08976) (xy 297.183284 -288.110858) (xy 297.136013 -288.12455)
			(xy 297.087158 -288.130482) (xy 297.037983 -288.128501) (xy 296.989764 -288.118657) (xy 296.943748 -288.101205)
			(xy 296.901127 -288.076598) (xy 296.863006 -288.045473) (xy 296.830371 -288.008636) (xy 296.804068 -287.96704)
			(xy 296.784777 -287.921764) (xy 296.773 -287.87398) (xy 296.76904 -287.824926) (xy 296.430192 -287.824926)
			(xy 296.429697 -287.849533) (xy 296.421802 -287.89811) (xy 296.406218 -287.944791) (xy 296.383347 -287.988368)
			(xy 296.353782 -288.027712) (xy 296.318289 -288.061804) (xy 296.277786 -288.08976) (xy 296.233324 -288.110858)
			(xy 296.186053 -288.12455) (xy 296.137198 -288.130482) (xy 296.088023 -288.128501) (xy 296.039804 -288.118657)
			(xy 295.993788 -288.101205) (xy 295.951167 -288.076598) (xy 295.913046 -288.045473) (xy 295.880411 -288.008636)
			(xy 295.854108 -287.96704) (xy 295.834817 -287.921764) (xy 295.82304 -287.87398) (xy 295.81908 -287.824926)
			(xy 295.480232 -287.824926) (xy 295.479737 -287.849533) (xy 295.471842 -287.89811) (xy 295.456258 -287.944791)
			(xy 295.433387 -287.988368) (xy 295.403822 -288.027712) (xy 295.368329 -288.061804) (xy 295.327826 -288.08976)
			(xy 295.283364 -288.110858) (xy 295.236093 -288.12455) (xy 295.187238 -288.130482) (xy 295.138063 -288.128501)
			(xy 295.089844 -288.118657) (xy 295.043828 -288.101205) (xy 295.001207 -288.076598) (xy 294.963086 -288.045473)
			(xy 294.930451 -288.008636) (xy 294.904148 -287.96704) (xy 294.884857 -287.921764) (xy 294.87308 -287.87398)
			(xy 294.86912 -287.824926) (xy 294.530018 -287.824926) (xy 294.529523 -287.849533) (xy 294.521628 -287.89811)
			(xy 294.506044 -287.944791) (xy 294.483173 -287.988368) (xy 294.453608 -288.027712) (xy 294.418115 -288.061804)
			(xy 294.377612 -288.08976) (xy 294.33315 -288.110858) (xy 294.285879 -288.12455) (xy 294.237024 -288.130482)
			(xy 294.187849 -288.128501) (xy 294.13963 -288.118657) (xy 294.093614 -288.101205) (xy 294.050993 -288.076598)
			(xy 294.012872 -288.045473) (xy 293.980237 -288.008636) (xy 293.953934 -287.96704) (xy 293.934643 -287.921764)
			(xy 293.922866 -287.87398) (xy 293.918906 -287.824926) (xy 293.580058 -287.824926) (xy 293.579563 -287.849533)
			(xy 293.571668 -287.89811) (xy 293.556084 -287.944791) (xy 293.533213 -287.988368) (xy 293.503648 -288.027712)
			(xy 293.468155 -288.061804) (xy 293.427652 -288.08976) (xy 293.38319 -288.110858) (xy 293.335919 -288.12455)
			(xy 293.287064 -288.130482) (xy 293.237889 -288.128501) (xy 293.18967 -288.118657) (xy 293.143654 -288.101205)
			(xy 293.101033 -288.076598) (xy 293.062912 -288.045473) (xy 293.030277 -288.008636) (xy 293.003974 -287.96704)
			(xy 292.984683 -287.921764) (xy 292.972906 -287.87398) (xy 292.968946 -287.824926) (xy 292.621125 -287.824926)
			(xy 292.621708 -287.826672) (xy 292.629603 -287.875249) (xy 292.630098 -287.899856) (xy 292.629603 -287.924463)
			(xy 292.621708 -287.97304) (xy 292.606124 -288.019721) (xy 292.583253 -288.063298) (xy 292.553688 -288.102642)
			(xy 292.518195 -288.136734) (xy 292.477692 -288.16469) (xy 292.43323 -288.185788) (xy 292.385959 -288.19948)
			(xy 292.337104 -288.205412) (xy 292.287929 -288.203431) (xy 292.23971 -288.193587) (xy 292.193694 -288.176135)
			(xy 292.151073 -288.151528) (xy 292.112952 -288.120403) (xy 292.080317 -288.083566) (xy 292.054014 -288.04197)
			(xy 292.034723 -287.996694) (xy 292.022946 -287.94891) (xy 292.018986 -287.899856) (xy 290.68083 -287.899856)
			(xy 290.67866 -287.902744) (xy 290.643167 -287.936836) (xy 290.602664 -287.964792) (xy 290.558202 -287.98589)
			(xy 290.510931 -287.999582) (xy 290.462076 -288.005514) (xy 290.412901 -288.003533) (xy 290.364682 -287.993689)
			(xy 290.318666 -287.976237) (xy 290.276045 -287.95163) (xy 290.237924 -287.920505) (xy 290.205289 -287.883668)
			(xy 290.178986 -287.842072) (xy 290.159695 -287.796796) (xy 290.147918 -287.749012) (xy 290.143958 -287.699958)
			(xy 289.753566 -287.699958) (xy 289.756244 -287.705061) (xy 289.771828 -287.751742) (xy 289.779723 -287.800319)
			(xy 289.780218 -287.824926) (xy 289.779723 -287.849533) (xy 289.771828 -287.89811) (xy 289.756244 -287.944791)
			(xy 289.733373 -287.988368) (xy 289.703808 -288.027712) (xy 289.668315 -288.061804) (xy 289.627812 -288.08976)
			(xy 289.58335 -288.110858) (xy 289.536079 -288.12455) (xy 289.487224 -288.130482) (xy 289.438049 -288.128501)
			(xy 289.38983 -288.118657) (xy 289.343814 -288.101205) (xy 289.301193 -288.076598) (xy 289.263072 -288.045473)
			(xy 289.230437 -288.008636) (xy 289.204134 -287.96704) (xy 289.184843 -287.921764) (xy 289.173066 -287.87398)
			(xy 289.169106 -287.824926) (xy 288.830004 -287.824926) (xy 288.829509 -287.849533) (xy 288.821614 -287.89811)
			(xy 288.80603 -287.944791) (xy 288.783159 -287.988368) (xy 288.753594 -288.027712) (xy 288.718101 -288.061804)
			(xy 288.677598 -288.08976) (xy 288.633136 -288.110858) (xy 288.585865 -288.12455) (xy 288.53701 -288.130482)
			(xy 288.487835 -288.128501) (xy 288.439616 -288.118657) (xy 288.3936 -288.101205) (xy 288.350979 -288.076598)
			(xy 288.312858 -288.045473) (xy 288.280223 -288.008636) (xy 288.25392 -287.96704) (xy 288.234629 -287.921764)
			(xy 288.222852 -287.87398) (xy 288.218892 -287.824926) (xy 287.880044 -287.824926) (xy 287.879549 -287.849533)
			(xy 287.871654 -287.89811) (xy 287.85607 -287.944791) (xy 287.833199 -287.988368) (xy 287.803634 -288.027712)
			(xy 287.768141 -288.061804) (xy 287.727638 -288.08976) (xy 287.683176 -288.110858) (xy 287.635905 -288.12455)
			(xy 287.58705 -288.130482) (xy 287.537875 -288.128501) (xy 287.489656 -288.118657) (xy 287.44364 -288.101205)
			(xy 287.401019 -288.076598) (xy 287.362898 -288.045473) (xy 287.330263 -288.008636) (xy 287.30396 -287.96704)
			(xy 287.284669 -287.921764) (xy 287.272892 -287.87398) (xy 287.268932 -287.824926) (xy 286.930084 -287.824926)
			(xy 286.929589 -287.849533) (xy 286.921694 -287.89811) (xy 286.90611 -287.944791) (xy 286.883239 -287.988368)
			(xy 286.853674 -288.027712) (xy 286.818181 -288.061804) (xy 286.777678 -288.08976) (xy 286.733216 -288.110858)
			(xy 286.685945 -288.12455) (xy 286.63709 -288.130482) (xy 286.587915 -288.128501) (xy 286.539696 -288.118657)
			(xy 286.49368 -288.101205) (xy 286.451059 -288.076598) (xy 286.412938 -288.045473) (xy 286.380303 -288.008636)
			(xy 286.354 -287.96704) (xy 286.334709 -287.921764) (xy 286.322932 -287.87398) (xy 286.318972 -287.824926)
			(xy 285.980124 -287.824926) (xy 285.979629 -287.849533) (xy 285.971734 -287.89811) (xy 285.95615 -287.944791)
			(xy 285.933279 -287.988368) (xy 285.903714 -288.027712) (xy 285.868221 -288.061804) (xy 285.827718 -288.08976)
			(xy 285.783256 -288.110858) (xy 285.735985 -288.12455) (xy 285.68713 -288.130482) (xy 285.637955 -288.128501)
			(xy 285.589736 -288.118657) (xy 285.54372 -288.101205) (xy 285.501099 -288.076598) (xy 285.462978 -288.045473)
			(xy 285.430343 -288.008636) (xy 285.40404 -287.96704) (xy 285.384749 -287.921764) (xy 285.372972 -287.87398)
			(xy 285.369012 -287.824926) (xy 285.030164 -287.824926) (xy 285.029669 -287.849533) (xy 285.021774 -287.89811)
			(xy 285.00619 -287.944791) (xy 284.983319 -287.988368) (xy 284.953754 -288.027712) (xy 284.918261 -288.061804)
			(xy 284.877758 -288.08976) (xy 284.833296 -288.110858) (xy 284.786025 -288.12455) (xy 284.73717 -288.130482)
			(xy 284.687995 -288.128501) (xy 284.639776 -288.118657) (xy 284.59376 -288.101205) (xy 284.551139 -288.076598)
			(xy 284.513018 -288.045473) (xy 284.480383 -288.008636) (xy 284.45408 -287.96704) (xy 284.434789 -287.921764)
			(xy 284.423012 -287.87398) (xy 284.419052 -287.824926) (xy 284.080204 -287.824926) (xy 284.079709 -287.849533)
			(xy 284.071814 -287.89811) (xy 284.05623 -287.944791) (xy 284.033359 -287.988368) (xy 284.003794 -288.027712)
			(xy 283.968301 -288.061804) (xy 283.927798 -288.08976) (xy 283.883336 -288.110858) (xy 283.836065 -288.12455)
			(xy 283.78721 -288.130482) (xy 283.738035 -288.128501) (xy 283.689816 -288.118657) (xy 283.6438 -288.101205)
			(xy 283.601179 -288.076598) (xy 283.563058 -288.045473) (xy 283.530423 -288.008636) (xy 283.50412 -287.96704)
			(xy 283.484829 -287.921764) (xy 283.473052 -287.87398) (xy 283.469092 -287.824926) (xy 283.130244 -287.824926)
			(xy 283.129749 -287.849533) (xy 283.121854 -287.89811) (xy 283.10627 -287.944791) (xy 283.083399 -287.988368)
			(xy 283.053834 -288.027712) (xy 283.018341 -288.061804) (xy 282.977838 -288.08976) (xy 282.933376 -288.110858)
			(xy 282.886105 -288.12455) (xy 282.83725 -288.130482) (xy 282.788075 -288.128501) (xy 282.739856 -288.118657)
			(xy 282.69384 -288.101205) (xy 282.651219 -288.076598) (xy 282.613098 -288.045473) (xy 282.580463 -288.008636)
			(xy 282.55416 -287.96704) (xy 282.534869 -287.921764) (xy 282.523092 -287.87398) (xy 282.519132 -287.824926)
			(xy 282.18003 -287.824926) (xy 282.179535 -287.849533) (xy 282.17164 -287.89811) (xy 282.156056 -287.944791)
			(xy 282.133185 -287.988368) (xy 282.10362 -288.027712) (xy 282.068127 -288.061804) (xy 282.027624 -288.08976)
			(xy 281.983162 -288.110858) (xy 281.935891 -288.12455) (xy 281.887036 -288.130482) (xy 281.837861 -288.128501)
			(xy 281.789642 -288.118657) (xy 281.743626 -288.101205) (xy 281.701005 -288.076598) (xy 281.662884 -288.045473)
			(xy 281.630249 -288.008636) (xy 281.603946 -287.96704) (xy 281.584655 -287.921764) (xy 281.572878 -287.87398)
			(xy 281.568918 -287.824926) (xy 281.23007 -287.824926) (xy 281.229575 -287.849533) (xy 281.22168 -287.89811)
			(xy 281.206096 -287.944791) (xy 281.183225 -287.988368) (xy 281.15366 -288.027712) (xy 281.118167 -288.061804)
			(xy 281.077664 -288.08976) (xy 281.033202 -288.110858) (xy 280.985931 -288.12455) (xy 280.937076 -288.130482)
			(xy 280.887901 -288.128501) (xy 280.839682 -288.118657) (xy 280.793666 -288.101205) (xy 280.751045 -288.076598)
			(xy 280.712924 -288.045473) (xy 280.680289 -288.008636) (xy 280.653986 -287.96704) (xy 280.634695 -287.921764)
			(xy 280.622918 -287.87398) (xy 280.618958 -287.824926) (xy 280.28011 -287.824926) (xy 280.279615 -287.849533)
			(xy 280.27172 -287.89811) (xy 280.256136 -287.944791) (xy 280.233265 -287.988368) (xy 280.2037 -288.027712)
			(xy 280.168207 -288.061804) (xy 280.127704 -288.08976) (xy 280.083242 -288.110858) (xy 280.035971 -288.12455)
			(xy 279.987116 -288.130482) (xy 279.937941 -288.128501) (xy 279.889722 -288.118657) (xy 279.843706 -288.101205)
			(xy 279.801085 -288.076598) (xy 279.762964 -288.045473) (xy 279.730329 -288.008636) (xy 279.704026 -287.96704)
			(xy 279.684735 -287.921764) (xy 279.672958 -287.87398) (xy 279.668998 -287.824926) (xy 279.41397 -287.824926)
			(xy 279.41397 -288.308192) (xy 305.793963 -288.308192) (xy 305.79665 -288.25862) (xy 305.80732 -288.210135)
			(xy 305.825695 -288.164015) (xy 305.851289 -288.121475) (xy 305.883428 -288.083636) (xy 305.921265 -288.051496)
			(xy 305.963804 -288.0259) (xy 306.009923 -288.007524) (xy 306.058408 -287.996851) (xy 306.10798 -287.994163)
			(xy 306.157335 -287.99953) (xy 306.205171 -288.012812) (xy 306.250228 -288.033658) (xy 306.291319 -288.061518)
			(xy 306.327361 -288.095659) (xy 306.357405 -288.135182) (xy 306.380658 -288.179045) (xy 306.39651 -288.226092)
			(xy 306.404541 -288.275083) (xy 306.405026 -288.299906) (xy 306.40485 -288.314089) (xy 306.402177 -288.342329)
			(xy 306.399692 -288.356294) (xy 306.397406 -288.36874) (xy 306.404772 -288.392362) (xy 306.482242 -288.469832)
			(xy 306.505864 -288.477198) (xy 306.51831 -288.474912) (xy 306.532276 -288.472438) (xy 306.560516 -288.469765)
			(xy 306.574698 -288.469578) (xy 306.588945 -288.469746) (xy 306.617313 -288.472414) (xy 306.63134 -288.474912)
			(xy 306.643532 -288.477198) (xy 306.667662 -288.469832) (xy 306.744878 -288.392616) (xy 306.752244 -288.36874)
			(xy 306.749958 -288.356294) (xy 306.747485 -288.342328) (xy 306.744811 -288.314088) (xy 306.744624 -288.299906)
			(xy 306.745071 -288.275085) (xy 306.753101 -288.226097) (xy 306.768951 -288.179053) (xy 306.792202 -288.135194)
			(xy 306.822243 -288.095673) (xy 306.858282 -288.061533) (xy 306.899368 -288.033674) (xy 306.944421 -288.012828)
			(xy 306.992253 -287.999545) (xy 307.041604 -287.994176) (xy 307.091173 -287.996861) (xy 307.139654 -288.00753)
			(xy 307.185772 -288.025901) (xy 307.228309 -288.051492) (xy 307.266146 -288.083627) (xy 307.298286 -288.12146)
			(xy 307.323882 -288.163994) (xy 307.342259 -288.210109) (xy 307.352934 -288.25859) (xy 307.355177 -288.299906)
			(xy 307.694088 -288.299906) (xy 307.698048 -288.250852) (xy 307.709825 -288.203068) (xy 307.729116 -288.157792)
			(xy 307.755419 -288.116196) (xy 307.788054 -288.079359) (xy 307.826175 -288.048234) (xy 307.868796 -288.023627)
			(xy 307.914812 -288.006175) (xy 307.963031 -287.996331) (xy 308.012206 -287.99435) (xy 308.061061 -288.000282)
			(xy 308.108332 -288.013974) (xy 308.152794 -288.035072) (xy 308.193297 -288.063028) (xy 308.22879 -288.09712)
			(xy 308.258355 -288.136464) (xy 308.281226 -288.180041) (xy 308.29681 -288.226722) (xy 308.304705 -288.275299)
			(xy 308.3052 -288.299906) (xy 308.304705 -288.324513) (xy 308.304526 -288.325614) (xy 308.623204 -288.325614)
			(xy 308.623204 -288.274198) (xy 308.631247 -288.223416) (xy 308.647135 -288.174517) (xy 308.670478 -288.128705)
			(xy 308.700699 -288.087109) (xy 308.737055 -288.050753) (xy 308.778651 -288.020532) (xy 308.824463 -287.997189)
			(xy 308.873362 -287.981301) (xy 308.924144 -287.973258) (xy 308.97556 -287.973258) (xy 309.026342 -287.981301)
			(xy 309.075241 -287.997189) (xy 309.121053 -288.020532) (xy 309.162649 -288.050753) (xy 309.199005 -288.087109)
			(xy 309.229226 -288.128705) (xy 309.252569 -288.174517) (xy 309.268457 -288.223416) (xy 309.2765 -288.274198)
			(xy 309.277004 -288.299906) (xy 309.2765 -288.325614) (xy 309.573164 -288.325614) (xy 309.573164 -288.274198)
			(xy 309.581207 -288.223416) (xy 309.597095 -288.174517) (xy 309.620438 -288.128705) (xy 309.650659 -288.087109)
			(xy 309.687015 -288.050753) (xy 309.728611 -288.020532) (xy 309.774423 -287.997189) (xy 309.823322 -287.981301)
			(xy 309.874104 -287.973258) (xy 309.92552 -287.973258) (xy 309.976302 -287.981301) (xy 310.025201 -287.997189)
			(xy 310.071013 -288.020532) (xy 310.112609 -288.050753) (xy 310.148965 -288.087109) (xy 310.179186 -288.128705)
			(xy 310.202529 -288.174517) (xy 310.218417 -288.223416) (xy 310.22646 -288.274198) (xy 310.226964 -288.299906)
			(xy 310.543968 -288.299906) (xy 310.547928 -288.250852) (xy 310.559705 -288.203068) (xy 310.578996 -288.157792)
			(xy 310.605299 -288.116196) (xy 310.637934 -288.079359) (xy 310.676055 -288.048234) (xy 310.718676 -288.023627)
			(xy 310.764692 -288.006175) (xy 310.812911 -287.996331) (xy 310.862086 -287.99435) (xy 310.910941 -288.000282)
			(xy 310.958212 -288.013974) (xy 311.002674 -288.035072) (xy 311.043177 -288.063028) (xy 311.07867 -288.09712)
			(xy 311.108235 -288.136464) (xy 311.131106 -288.180041) (xy 311.14669 -288.226722) (xy 311.154585 -288.275299)
			(xy 311.15508 -288.299906) (xy 311.154585 -288.324513) (xy 311.154446 -288.325369) (xy 311.472991 -288.325369)
			(xy 311.472998 -288.273936) (xy 311.481053 -288.223139) (xy 311.496956 -288.174226) (xy 311.520315 -288.128405)
			(xy 311.550557 -288.086802) (xy 311.586935 -288.050444) (xy 311.628553 -288.020224) (xy 311.674387 -287.996889)
			(xy 311.723308 -287.981012) (xy 311.77411 -287.972985) (xy 311.825543 -287.973004) (xy 311.876339 -287.981071)
			(xy 311.925247 -287.996986) (xy 311.971063 -288.020357) (xy 312.012658 -288.050608) (xy 312.049008 -288.086995)
			(xy 312.079217 -288.128621) (xy 312.102541 -288.174461) (xy 312.118407 -288.223385) (xy 312.126422 -288.274189)
			(xy 312.126884 -288.299906) (xy 312.126671 -288.313629) (xy 312.124258 -288.340969) (xy 312.122058 -288.354516)
			(xy 312.12028 -288.366454) (xy 312.127138 -288.389314) (xy 312.200798 -288.465768) (xy 312.223404 -288.473642)
			(xy 312.235342 -288.472118) (xy 312.245141 -288.470931) (xy 312.264841 -288.469659) (xy 312.274712 -288.469578)
			(xy 312.284583 -288.469649) (xy 312.304284 -288.470922) (xy 312.314082 -288.472118) (xy 312.32602 -288.473642)
			(xy 312.348626 -288.465768) (xy 312.422286 -288.389314) (xy 312.429144 -288.366454) (xy 312.427366 -288.354516)
			(xy 312.425145 -288.340972) (xy 312.422731 -288.31363) (xy 312.42254 -288.299906) (xy 312.423044 -288.274198)
			(xy 312.431087 -288.223416) (xy 312.446975 -288.174517) (xy 312.470318 -288.128705) (xy 312.500539 -288.087109)
			(xy 312.536895 -288.050753) (xy 312.578491 -288.020532) (xy 312.624303 -287.997189) (xy 312.673202 -287.981301)
			(xy 312.723984 -287.973258) (xy 312.7754 -287.973258) (xy 312.826182 -287.981301) (xy 312.875081 -287.997189)
			(xy 312.920893 -288.020532) (xy 312.962489 -288.050753) (xy 312.998845 -288.087109) (xy 313.029066 -288.128705)
			(xy 313.052409 -288.174517) (xy 313.068297 -288.223416) (xy 313.07634 -288.274198) (xy 313.076844 -288.299906)
			(xy 313.076631 -288.313629) (xy 313.074218 -288.340969) (xy 313.072018 -288.354516) (xy 313.069986 -288.366454)
			(xy 313.077098 -288.389314) (xy 313.150758 -288.465768) (xy 313.173364 -288.473642) (xy 313.185556 -288.472118)
			(xy 313.195355 -288.470929) (xy 313.215055 -288.469658) (xy 313.224926 -288.469578) (xy 313.239109 -288.469751)
			(xy 313.267349 -288.472426) (xy 313.281314 -288.474912) (xy 313.29376 -288.477198) (xy 313.317382 -288.469832)
			(xy 313.394852 -288.392362) (xy 313.402218 -288.36874) (xy 313.399932 -288.356294) (xy 313.397459 -288.342328)
			(xy 313.394785 -288.314088) (xy 313.394598 -288.299906) (xy 313.39512 -288.274651) (xy 313.403433 -288.224829)
			(xy 313.419834 -288.177055) (xy 313.443875 -288.132632) (xy 313.474899 -288.092772) (xy 313.512061 -288.058562)
			(xy 313.554347 -288.030936) (xy 313.600603 -288.010646) (xy 313.649568 -287.998246) (xy 313.699906 -287.994075)
			(xy 313.750244 -287.998246) (xy 313.799209 -288.010646) (xy 313.845465 -288.030936) (xy 313.887751 -288.058562)
			(xy 313.924913 -288.092772) (xy 313.955937 -288.132632) (xy 313.979978 -288.177055) (xy 313.996379 -288.224829)
			(xy 314.004692 -288.274651) (xy 314.005214 -288.299906) (xy 314.005038 -288.314089) (xy 314.002365 -288.342329)
			(xy 313.99988 -288.356294) (xy 313.997594 -288.36874) (xy 314.00496 -288.392362) (xy 314.08243 -288.469832)
			(xy 314.106052 -288.477198) (xy 314.118498 -288.474912) (xy 314.132465 -288.47244) (xy 314.160704 -288.469765)
			(xy 314.174886 -288.469578) (xy 314.189069 -288.469757) (xy 314.217309 -288.472427) (xy 314.231274 -288.474912)
			(xy 314.24372 -288.477198) (xy 314.267342 -288.469832) (xy 314.344812 -288.392362) (xy 314.352178 -288.36874)
			(xy 314.349892 -288.356294) (xy 314.347419 -288.342328) (xy 314.344745 -288.314088) (xy 314.344558 -288.299906)
			(xy 314.34508 -288.274651) (xy 314.353393 -288.224829) (xy 314.369794 -288.177055) (xy 314.393835 -288.132632)
			(xy 314.424859 -288.092772) (xy 314.462021 -288.058562) (xy 314.504307 -288.030936) (xy 314.550563 -288.010646)
			(xy 314.599528 -287.998246) (xy 314.649866 -287.994075) (xy 314.700204 -287.998246) (xy 314.749169 -288.010646)
			(xy 314.795425 -288.030936) (xy 314.837711 -288.058562) (xy 314.874873 -288.092772) (xy 314.905897 -288.132632)
			(xy 314.929938 -288.177055) (xy 314.946339 -288.224829) (xy 314.950281 -288.248456) (xy 319.795821 -288.248456)
			(xy 319.795821 -288.193944) (xy 319.803579 -288.139988) (xy 319.818936 -288.087685) (xy 319.841581 -288.0381)
			(xy 319.871053 -287.992243) (xy 319.90675 -287.951046) (xy 319.947947 -287.915349) (xy 319.993805 -287.885879)
			(xy 320.043391 -287.863234) (xy 320.095694 -287.847877) (xy 320.14965 -287.840121) (xy 320.176906 -287.839658)
			(xy 320.203022 -287.840108) (xy 320.254766 -287.847246) (xy 320.305052 -287.861374) (xy 320.352941 -287.882229)
			(xy 320.397539 -287.90942) (xy 320.438012 -287.942439) (xy 320.473603 -287.98067) (xy 320.503648 -288.023397)
			(xy 320.515996 -288.046414) (xy 320.522763 -288.058628) (xy 320.541766 -288.079074) (xy 320.565592 -288.093616)
			(xy 320.592463 -288.101168) (xy 320.620377 -288.101168) (xy 320.647248 -288.093616) (xy 320.671074 -288.079074)
			(xy 320.690077 -288.058628) (xy 320.696844 -288.046414) (xy 320.709203 -288.0234) (xy 320.739231 -287.980657)
			(xy 320.774814 -287.942413) (xy 320.815283 -287.909383) (xy 320.859881 -287.882187) (xy 320.907775 -287.861332)
			(xy 320.958067 -287.84721) (xy 321.009815 -287.840085) (xy 321.035934 -287.839658) (xy 321.063181 -287.840215)
			(xy 321.11712 -287.847974) (xy 321.169406 -287.863331) (xy 321.218975 -287.885972) (xy 321.264817 -287.915437)
			(xy 321.305999 -287.951125) (xy 321.341684 -287.99231) (xy 321.371144 -288.038155) (xy 321.393781 -288.087726)
			(xy 321.409133 -288.140013) (xy 321.416888 -288.193953) (xy 321.416888 -288.248445) (xy 321.67082 -288.248445)
			(xy 321.670822 -288.193932) (xy 321.678582 -288.139975) (xy 321.693942 -288.087671) (xy 321.716589 -288.038085)
			(xy 321.746064 -287.992228) (xy 321.781764 -287.951032) (xy 321.822964 -287.915336) (xy 321.868825 -287.885868)
			(xy 321.918413 -287.863226) (xy 321.970719 -287.847872) (xy 322.024678 -287.840119) (xy 322.051934 -287.839658)
			(xy 322.076572 -287.84042) (xy 322.089272 -287.841182) (xy 322.11137 -287.83153) (xy 322.179442 -287.74771)
			(xy 322.184522 -287.723834) (xy 322.180966 -287.711642) (xy 322.17443 -287.686493) (xy 322.16742 -287.635007)
			(xy 322.166996 -287.609026) (xy 322.167482 -287.581775) (xy 322.175238 -287.527827) (xy 322.190593 -287.475532)
			(xy 322.213235 -287.425955) (xy 322.242701 -287.380105) (xy 322.278392 -287.338914) (xy 322.319583 -287.303223)
			(xy 322.365433 -287.273757) (xy 322.41501 -287.251115) (xy 322.467305 -287.23576) (xy 322.521253 -287.228004)
			(xy 322.575755 -287.228004) (xy 322.629703 -287.23576) (xy 322.681998 -287.251115) (xy 322.731575 -287.273757)
			(xy 322.777425 -287.303223) (xy 322.818616 -287.338914) (xy 322.854307 -287.380105) (xy 322.883773 -287.425955)
			(xy 322.906415 -287.475532) (xy 322.92177 -287.527827) (xy 322.929526 -287.581775) (xy 322.930012 -287.609026)
			(xy 322.929581 -287.63547) (xy 322.922318 -287.687857) (xy 322.915534 -287.71342) (xy 322.911978 -287.725866)
			(xy 322.917312 -287.75025) (xy 322.988432 -287.834324) (xy 323.0118 -287.843468) (xy 323.024754 -287.842198)
			(xy 323.035511 -287.841027) (xy 323.057114 -287.839756) (xy 323.067934 -287.839658) (xy 323.082158 -287.839912)
			(xy 323.093842 -287.84042) (xy 323.114924 -287.831276) (xy 323.18198 -287.75406) (xy 323.188076 -287.732216)
			(xy 323.186044 -287.720786) (xy 323.183307 -287.704285) (xy 323.180382 -287.670963) (xy 323.180202 -287.654238)
			(xy 323.180688 -287.626987) (xy 323.188444 -287.573039) (xy 323.203799 -287.520744) (xy 323.226441 -287.471167)
			(xy 323.255907 -287.425317) (xy 323.291598 -287.384126) (xy 323.332789 -287.348435) (xy 323.378639 -287.318969)
			(xy 323.428216 -287.296327) (xy 323.480511 -287.280972) (xy 323.534459 -287.273216) (xy 323.588961 -287.273216)
			(xy 323.642909 -287.280972) (xy 323.695204 -287.296327) (xy 323.744781 -287.318969) (xy 323.790631 -287.348435)
			(xy 323.831822 -287.384126) (xy 323.867513 -287.425317) (xy 323.896979 -287.471167) (xy 323.919621 -287.520744)
			(xy 323.934976 -287.573039) (xy 323.942732 -287.626987) (xy 323.943218 -287.654238) (xy 323.943035 -287.6709)
			(xy 323.940109 -287.704095) (xy 323.937376 -287.720532) (xy 323.935344 -287.732216) (xy 323.94144 -287.753806)
			(xy 324.008242 -287.831022) (xy 324.028816 -287.840166) (xy 324.0405 -287.839912) (xy 324.051676 -287.839658)
			(xy 324.078932 -287.840129) (xy 324.132888 -287.847884) (xy 324.185192 -287.863239) (xy 324.234778 -287.885881)
			(xy 324.280637 -287.91535) (xy 324.321835 -287.951045) (xy 324.357533 -287.99224) (xy 324.387005 -288.038097)
			(xy 324.409651 -288.087681) (xy 324.42501 -288.139984) (xy 324.432769 -288.19394) (xy 324.432769 -288.248451)
			(xy 324.425012 -288.302407) (xy 324.409655 -288.35471) (xy 324.38701 -288.404295) (xy 324.357539 -288.450152)
			(xy 324.321841 -288.491348) (xy 324.280644 -288.527045) (xy 324.234786 -288.556515) (xy 324.185201 -288.579158)
			(xy 324.132897 -288.594514) (xy 324.078941 -288.60227) (xy 324.02443 -288.602268) (xy 323.970474 -288.594508)
			(xy 323.918172 -288.579148) (xy 323.868588 -288.556501) (xy 323.822732 -288.527027) (xy 323.781538 -288.491328)
			(xy 323.745844 -288.450129) (xy 323.716376 -288.404269) (xy 323.693735 -288.354682) (xy 323.678382 -288.302378)
			(xy 323.670629 -288.248422) (xy 323.670168 -288.221166) (xy 323.670351 -288.204504) (xy 323.673277 -288.171309)
			(xy 323.67601 -288.154872) (xy 323.678042 -288.143188) (xy 323.671946 -288.121598) (xy 323.605144 -288.044382)
			(xy 323.58457 -288.035238) (xy 323.572886 -288.035492) (xy 323.56171 -288.035746) (xy 323.547486 -288.035492)
			(xy 323.535802 -288.034984) (xy 323.51472 -288.044128) (xy 323.447664 -288.121344) (xy 323.441568 -288.143188)
			(xy 323.4436 -288.154618) (xy 323.446338 -288.171119) (xy 323.449262 -288.204441) (xy 323.449442 -288.221166)
			(xy 323.448956 -288.248417) (xy 323.4412 -288.302365) (xy 323.425845 -288.35466) (xy 323.403203 -288.404237)
			(xy 323.373737 -288.450087) (xy 323.338046 -288.491278) (xy 323.296855 -288.526969) (xy 323.251005 -288.556435)
			(xy 323.201428 -288.579077) (xy 323.149133 -288.594432) (xy 323.095185 -288.602188) (xy 323.040683 -288.602188)
			(xy 322.986735 -288.594432) (xy 322.93444 -288.579077) (xy 322.884863 -288.556435) (xy 322.839013 -288.526969)
			(xy 322.797822 -288.491278) (xy 322.762131 -288.450087) (xy 322.732665 -288.404237) (xy 322.710023 -288.35466)
			(xy 322.694668 -288.302365) (xy 322.686912 -288.248417) (xy 322.686426 -288.221166) (xy 322.686854 -288.194722)
			(xy 322.694119 -288.142335) (xy 322.700904 -288.116772) (xy 322.70446 -288.104326) (xy 322.699126 -288.079942)
			(xy 322.628006 -287.995868) (xy 322.604638 -287.986724) (xy 322.591684 -287.987994) (xy 322.580927 -287.989162)
			(xy 322.559324 -287.990435) (xy 322.548504 -287.990534) (xy 322.523866 -287.989772) (xy 322.511166 -287.98901)
			(xy 322.489068 -287.998662) (xy 322.420996 -288.082482) (xy 322.415916 -288.106358) (xy 322.419472 -288.11855)
			(xy 322.426007 -288.143699) (xy 322.433018 -288.195185) (xy 322.433442 -288.221166) (xy 322.432981 -288.248422)
			(xy 322.425228 -288.302381) (xy 322.409874 -288.354687) (xy 322.387232 -288.404275) (xy 322.357764 -288.450136)
			(xy 322.322068 -288.491336) (xy 322.280872 -288.527036) (xy 322.235015 -288.556511) (xy 322.185429 -288.579158)
			(xy 322.133125 -288.594518) (xy 322.079168 -288.602278) (xy 322.024655 -288.60228) (xy 321.970697 -288.594523)
			(xy 321.918392 -288.579166) (xy 321.868805 -288.556521) (xy 321.822946 -288.52705) (xy 321.781748 -288.491352)
			(xy 321.74605 -288.450154) (xy 321.716579 -288.404295) (xy 321.693934 -288.354708) (xy 321.678577 -288.302403)
			(xy 321.67082 -288.248445) (xy 321.416888 -288.248445) (xy 321.416888 -288.248447) (xy 321.409133 -288.302387)
			(xy 321.393781 -288.354674) (xy 321.371144 -288.404245) (xy 321.341684 -288.45009) (xy 321.305999 -288.491275)
			(xy 321.264817 -288.526963) (xy 321.218975 -288.556428) (xy 321.169406 -288.579069) (xy 321.11712 -288.594426)
			(xy 321.063181 -288.602185) (xy 321.035934 -288.602674) (xy 321.009817 -288.602228) (xy 320.958072 -288.595094)
			(xy 320.907784 -288.580968) (xy 320.859893 -288.560114) (xy 320.815294 -288.532922) (xy 320.774822 -288.499901)
			(xy 320.739232 -288.461667) (xy 320.70919 -288.418937) (xy 320.696844 -288.395918) (xy 320.690077 -288.383704)
			(xy 320.671074 -288.363258) (xy 320.647248 -288.348716) (xy 320.620377 -288.341164) (xy 320.592463 -288.341164)
			(xy 320.565592 -288.348716) (xy 320.541766 -288.363258) (xy 320.522763 -288.383704) (xy 320.515996 -288.395918)
			(xy 320.503621 -288.418923) (xy 320.473593 -288.461664) (xy 320.438012 -288.499907) (xy 320.397545 -288.532936)
			(xy 320.352949 -288.560133) (xy 320.305059 -288.58099) (xy 320.25477 -288.595115) (xy 320.203024 -288.602245)
			(xy 320.176906 -288.602674) (xy 320.14965 -288.602279) (xy 320.095694 -288.594523) (xy 320.043391 -288.579166)
			(xy 319.993805 -288.556521) (xy 319.947947 -288.527051) (xy 319.90675 -288.491354) (xy 319.871053 -288.450157)
			(xy 319.841581 -288.4043) (xy 319.818936 -288.354715) (xy 319.803579 -288.302412) (xy 319.795821 -288.248456)
			(xy 314.950281 -288.248456) (xy 314.954652 -288.274651) (xy 314.955174 -288.299906) (xy 314.954999 -288.314089)
			(xy 314.952326 -288.342329) (xy 314.94984 -288.356294) (xy 314.947554 -288.36874) (xy 314.95492 -288.392362)
			(xy 315.03239 -288.469832) (xy 315.056012 -288.477198) (xy 315.068458 -288.474912) (xy 315.082423 -288.472432)
			(xy 315.110663 -288.469762) (xy 315.124846 -288.469578) (xy 315.147629 -288.469993) (xy 315.192686 -288.476777)
			(xy 315.236238 -288.490173) (xy 315.277319 -288.509884) (xy 315.31502 -288.535474) (xy 315.348506 -288.566376)
			(xy 315.363098 -288.583878) (xy 315.370664 -288.592477) (xy 315.391281 -288.602401) (xy 315.402722 -288.602928)
			(xy 315.48197 -288.602928) (xy 315.493383 -288.60227) (xy 315.51396 -288.592386) (xy 315.521594 -288.583878)
			(xy 315.53619 -288.566378) (xy 315.569664 -288.535461) (xy 315.607361 -288.509862) (xy 315.648444 -288.49015)
			(xy 315.692 -288.476762) (xy 315.737062 -288.469997) (xy 315.759846 -288.469578) (xy 315.785098 -288.470131)
			(xy 315.834911 -288.47845) (xy 315.882676 -288.494855) (xy 315.92709 -288.518896) (xy 315.966942 -288.54992)
			(xy 316.001145 -288.587079) (xy 316.028765 -288.62936) (xy 316.04905 -288.675611) (xy 316.061447 -288.724569)
			(xy 316.065617 -288.7749) (xy 316.061447 -288.825231) (xy 316.04905 -288.874189) (xy 316.028765 -288.92044)
			(xy 316.001145 -288.962721) (xy 315.966942 -288.99988) (xy 315.92709 -289.030904) (xy 315.882676 -289.054945)
			(xy 315.834911 -289.07135) (xy 315.785098 -289.079669) (xy 315.759846 -289.080194) (xy 315.737063 -289.079795)
			(xy 315.692004 -289.073009) (xy 315.648451 -289.059611) (xy 315.60737 -289.039896) (xy 315.569669 -289.014303)
			(xy 315.536185 -288.983397) (xy 315.521594 -288.965894) (xy 315.514036 -288.957287) (xy 315.493412 -288.947369)
			(xy 315.48197 -288.946844) (xy 315.402722 -288.946844) (xy 315.39131 -288.947507) (xy 315.370733 -288.957388)
			(xy 315.363098 -288.965894) (xy 315.348524 -288.983413) (xy 315.315044 -289.014326) (xy 315.277341 -289.03992)
			(xy 315.236254 -289.059629) (xy 315.192695 -289.073013) (xy 315.147631 -289.079776) (xy 315.124846 -289.080194)
			(xy 315.100853 -289.079719) (xy 315.053458 -289.072219) (xy 315.00782 -289.057396) (xy 314.965063 -289.035615)
			(xy 314.92624 -289.007413) (xy 314.892308 -288.973484) (xy 314.864102 -288.934664) (xy 314.842316 -288.89191)
			(xy 314.827488 -288.846273) (xy 314.819983 -288.798879) (xy 314.819538 -288.774886) (xy 314.819712 -288.760703)
			(xy 314.822386 -288.732463) (xy 314.824872 -288.718498) (xy 314.827158 -288.706052) (xy 314.819792 -288.68243)
			(xy 314.742322 -288.60496) (xy 314.7187 -288.597594) (xy 314.706254 -288.59988) (xy 314.692288 -288.602359)
			(xy 314.664049 -288.605029) (xy 314.649866 -288.605214) (xy 314.635683 -288.605042) (xy 314.607443 -288.602367)
			(xy 314.593478 -288.59988) (xy 314.581032 -288.597594) (xy 314.55741 -288.60496) (xy 314.47994 -288.68243)
			(xy 314.472574 -288.706052) (xy 314.47486 -288.718498) (xy 314.477332 -288.732465) (xy 314.480007 -288.760704)
			(xy 314.480194 -288.774886) (xy 314.479672 -288.800141) (xy 314.471359 -288.849963) (xy 314.454958 -288.897737)
			(xy 314.430917 -288.94216) (xy 314.399893 -288.98202) (xy 314.362731 -289.01623) (xy 314.320445 -289.043856)
			(xy 314.274189 -289.064146) (xy 314.225224 -289.076546) (xy 314.174886 -289.080717) (xy 314.124548 -289.076546)
			(xy 314.075583 -289.064146) (xy 314.029327 -289.043856) (xy 313.987041 -289.01623) (xy 313.949879 -288.98202)
			(xy 313.918855 -288.94216) (xy 313.894814 -288.897737) (xy 313.878413 -288.849963) (xy 313.8701 -288.800141)
			(xy 313.869578 -288.774886) (xy 313.869753 -288.760703) (xy 313.872426 -288.732463) (xy 313.874912 -288.718498)
			(xy 313.877198 -288.706052) (xy 313.869832 -288.68243) (xy 313.792362 -288.60496) (xy 313.76874 -288.597594)
			(xy 313.756294 -288.59988) (xy 313.742328 -288.602353) (xy 313.714088 -288.605027) (xy 313.699906 -288.605214)
			(xy 313.685723 -288.605036) (xy 313.657483 -288.602365) (xy 313.643518 -288.59988) (xy 313.631072 -288.597594)
			(xy 313.60745 -288.60496) (xy 313.52998 -288.68243) (xy 313.522614 -288.706052) (xy 313.5249 -288.718498)
			(xy 313.527372 -288.732465) (xy 313.530047 -288.760704) (xy 313.530234 -288.774886) (xy 313.529712 -288.800141)
			(xy 313.521399 -288.849963) (xy 313.504998 -288.897737) (xy 313.480957 -288.94216) (xy 313.449933 -288.98202)
			(xy 313.412771 -289.01623) (xy 313.370485 -289.043856) (xy 313.324229 -289.064146) (xy 313.275264 -289.076546)
			(xy 313.224926 -289.080717) (xy 313.174588 -289.076546) (xy 313.125623 -289.064146) (xy 313.079367 -289.043856)
			(xy 313.037081 -289.01623) (xy 312.999919 -288.98202) (xy 312.968895 -288.94216) (xy 312.944854 -288.897737)
			(xy 312.928453 -288.849963) (xy 312.92014 -288.800141) (xy 312.919618 -288.774886) (xy 312.919689 -288.765015)
			(xy 312.920961 -288.745314) (xy 312.922158 -288.735516) (xy 312.923682 -288.723578) (xy 312.915808 -288.700718)
			(xy 312.839354 -288.627312) (xy 312.816494 -288.6202) (xy 312.804302 -288.622232) (xy 312.790753 -288.62439)
			(xy 312.763411 -288.626677) (xy 312.749692 -288.626804) (xy 312.735974 -288.626658) (xy 312.708633 -288.62437)
			(xy 312.695082 -288.622232) (xy 312.683144 -288.620454) (xy 312.660284 -288.627312) (xy 312.58383 -288.700972)
			(xy 312.575956 -288.723578) (xy 312.57748 -288.735516) (xy 312.578665 -288.745316) (xy 312.579938 -288.765015)
			(xy 312.58002 -288.774886) (xy 312.579498 -288.800141) (xy 312.571185 -288.849963) (xy 312.554784 -288.897737)
			(xy 312.530743 -288.94216) (xy 312.499719 -288.98202) (xy 312.462557 -289.01623) (xy 312.420271 -289.043856)
			(xy 312.374015 -289.064146) (xy 312.32505 -289.076546) (xy 312.274712 -289.080717) (xy 312.224374 -289.076546)
			(xy 312.175409 -289.064146) (xy 312.129153 -289.043856) (xy 312.086867 -289.01623) (xy 312.049705 -288.98202)
			(xy 312.018681 -288.94216) (xy 311.99464 -288.897737) (xy 311.978239 -288.849963) (xy 311.969926 -288.800141)
			(xy 311.969404 -288.774886) (xy 311.969475 -288.765015) (xy 311.970747 -288.745314) (xy 311.971944 -288.735516)
			(xy 311.973468 -288.723578) (xy 311.965594 -288.700972) (xy 311.88914 -288.627312) (xy 311.86628 -288.620454)
			(xy 311.854342 -288.622232) (xy 311.840793 -288.624385) (xy 311.813451 -288.626675) (xy 311.799732 -288.626804)
			(xy 311.774016 -288.626408) (xy 311.723216 -288.618366) (xy 311.6743 -288.602475) (xy 311.628472 -288.579126)
			(xy 311.586863 -288.548895) (xy 311.550495 -288.512526) (xy 311.520266 -288.470914) (xy 311.496919 -288.425086)
			(xy 311.48103 -288.376169) (xy 311.472991 -288.325369) (xy 311.154446 -288.325369) (xy 311.14669 -288.37309)
			(xy 311.131106 -288.419771) (xy 311.108235 -288.463348) (xy 311.07867 -288.502692) (xy 311.043177 -288.536784)
			(xy 311.002674 -288.56474) (xy 310.958212 -288.585838) (xy 310.910941 -288.59953) (xy 310.862086 -288.605462)
			(xy 310.812911 -288.603481) (xy 310.764692 -288.593637) (xy 310.718676 -288.576185) (xy 310.676055 -288.551578)
			(xy 310.637934 -288.520453) (xy 310.605299 -288.483616) (xy 310.578996 -288.44202) (xy 310.559705 -288.396744)
			(xy 310.547928 -288.34896) (xy 310.543968 -288.299906) (xy 310.226964 -288.299906) (xy 310.22646 -288.325614)
			(xy 310.218417 -288.376396) (xy 310.202529 -288.425295) (xy 310.179186 -288.471107) (xy 310.148965 -288.512703)
			(xy 310.112609 -288.549059) (xy 310.071013 -288.57928) (xy 310.025201 -288.602623) (xy 309.976302 -288.618511)
			(xy 309.92552 -288.626554) (xy 309.874104 -288.626554) (xy 309.823322 -288.618511) (xy 309.774423 -288.602623)
			(xy 309.728611 -288.57928) (xy 309.687015 -288.549059) (xy 309.650659 -288.512703) (xy 309.620438 -288.471107)
			(xy 309.597095 -288.425295) (xy 309.581207 -288.376396) (xy 309.573164 -288.325614) (xy 309.2765 -288.325614)
			(xy 309.268457 -288.376396) (xy 309.252569 -288.425295) (xy 309.229226 -288.471107) (xy 309.199005 -288.512703)
			(xy 309.162649 -288.549059) (xy 309.121053 -288.57928) (xy 309.075241 -288.602623) (xy 309.026342 -288.618511)
			(xy 308.97556 -288.626554) (xy 308.924144 -288.626554) (xy 308.873362 -288.618511) (xy 308.824463 -288.602623)
			(xy 308.778651 -288.57928) (xy 308.737055 -288.549059) (xy 308.700699 -288.512703) (xy 308.670478 -288.471107)
			(xy 308.647135 -288.425295) (xy 308.631247 -288.376396) (xy 308.623204 -288.325614) (xy 308.304526 -288.325614)
			(xy 308.29681 -288.37309) (xy 308.281226 -288.419771) (xy 308.258355 -288.463348) (xy 308.22879 -288.502692)
			(xy 308.193297 -288.536784) (xy 308.152794 -288.56474) (xy 308.108332 -288.585838) (xy 308.061061 -288.59953)
			(xy 308.012206 -288.605462) (xy 307.963031 -288.603481) (xy 307.914812 -288.593637) (xy 307.868796 -288.576185)
			(xy 307.826175 -288.551578) (xy 307.788054 -288.520453) (xy 307.755419 -288.483616) (xy 307.729116 -288.44202)
			(xy 307.709825 -288.396744) (xy 307.698048 -288.34896) (xy 307.694088 -288.299906) (xy 307.355177 -288.299906)
			(xy 307.355625 -288.308158) (xy 307.350262 -288.35751) (xy 307.336985 -288.405343) (xy 307.316145 -288.450398)
			(xy 307.28829 -288.491489) (xy 307.254155 -288.527532) (xy 307.214638 -288.557577) (xy 307.170781 -288.580834)
			(xy 307.12374 -288.596689) (xy 307.074753 -288.604726) (xy 307.049932 -288.605214) (xy 307.035685 -288.605049)
			(xy 307.007318 -288.602375) (xy 306.99329 -288.59988) (xy 306.981098 -288.597594) (xy 306.956968 -288.60496)
			(xy 306.879752 -288.682176) (xy 306.872386 -288.706052) (xy 306.874672 -288.718498) (xy 306.877144 -288.732465)
			(xy 306.879819 -288.760704) (xy 306.880006 -288.774886) (xy 306.879484 -288.800141) (xy 306.871171 -288.849963)
			(xy 306.85477 -288.897737) (xy 306.830729 -288.94216) (xy 306.799705 -288.98202) (xy 306.762543 -289.01623)
			(xy 306.720257 -289.043856) (xy 306.674001 -289.064146) (xy 306.625036 -289.076546) (xy 306.574698 -289.080717)
			(xy 306.52436 -289.076546) (xy 306.475395 -289.064146) (xy 306.429139 -289.043856) (xy 306.386853 -289.01623)
			(xy 306.349691 -288.98202) (xy 306.318667 -288.94216) (xy 306.294626 -288.897737) (xy 306.278225 -288.849963)
			(xy 306.269912 -288.800141) (xy 306.26939 -288.774886) (xy 306.269565 -288.760703) (xy 306.272238 -288.732463)
			(xy 306.274724 -288.718498) (xy 306.27701 -288.706052) (xy 306.269644 -288.68243) (xy 306.192174 -288.60496)
			(xy 306.168552 -288.597594) (xy 306.156106 -288.59988) (xy 306.142139 -288.602352) (xy 306.1139 -288.605027)
			(xy 306.099718 -288.605214) (xy 306.074895 -288.604741) (xy 306.025903 -288.596713) (xy 305.978856 -288.580863)
			(xy 305.934992 -288.557611) (xy 305.895468 -288.527569) (xy 305.861326 -288.491528) (xy 305.833463 -288.450438)
			(xy 305.812616 -288.405382) (xy 305.799333 -288.357547) (xy 305.793963 -288.308192) (xy 279.41397 -288.308192)
			(xy 279.41397 -288.774886) (xy 279.668998 -288.774886) (xy 279.672958 -288.725832) (xy 279.684735 -288.678048)
			(xy 279.704026 -288.632772) (xy 279.730329 -288.591176) (xy 279.762964 -288.554339) (xy 279.801085 -288.523214)
			(xy 279.843706 -288.498607) (xy 279.889722 -288.481155) (xy 279.937941 -288.471311) (xy 279.987116 -288.46933)
			(xy 280.035971 -288.475262) (xy 280.083242 -288.488954) (xy 280.127704 -288.510052) (xy 280.168207 -288.538008)
			(xy 280.2037 -288.5721) (xy 280.233265 -288.611444) (xy 280.256136 -288.655021) (xy 280.27172 -288.701702)
			(xy 280.279615 -288.750279) (xy 280.28011 -288.774886) (xy 280.618958 -288.774886) (xy 280.622918 -288.725832)
			(xy 280.634695 -288.678048) (xy 280.653986 -288.632772) (xy 280.680289 -288.591176) (xy 280.712924 -288.554339)
			(xy 280.751045 -288.523214) (xy 280.793666 -288.498607) (xy 280.839682 -288.481155) (xy 280.887901 -288.471311)
			(xy 280.937076 -288.46933) (xy 280.985931 -288.475262) (xy 281.033202 -288.488954) (xy 281.077664 -288.510052)
			(xy 281.118167 -288.538008) (xy 281.15366 -288.5721) (xy 281.183225 -288.611444) (xy 281.206096 -288.655021)
			(xy 281.22168 -288.701702) (xy 281.229575 -288.750279) (xy 281.23007 -288.774886) (xy 281.568918 -288.774886)
			(xy 281.572878 -288.725832) (xy 281.584655 -288.678048) (xy 281.603946 -288.632772) (xy 281.630249 -288.591176)
			(xy 281.662884 -288.554339) (xy 281.701005 -288.523214) (xy 281.743626 -288.498607) (xy 281.789642 -288.481155)
			(xy 281.837861 -288.471311) (xy 281.887036 -288.46933) (xy 281.935891 -288.475262) (xy 281.983162 -288.488954)
			(xy 282.027624 -288.510052) (xy 282.068127 -288.538008) (xy 282.10362 -288.5721) (xy 282.133185 -288.611444)
			(xy 282.156056 -288.655021) (xy 282.17164 -288.701702) (xy 282.179535 -288.750279) (xy 282.18003 -288.774886)
			(xy 282.519132 -288.774886) (xy 282.523092 -288.725832) (xy 282.534869 -288.678048) (xy 282.55416 -288.632772)
			(xy 282.580463 -288.591176) (xy 282.613098 -288.554339) (xy 282.651219 -288.523214) (xy 282.69384 -288.498607)
			(xy 282.739856 -288.481155) (xy 282.788075 -288.471311) (xy 282.83725 -288.46933) (xy 282.886105 -288.475262)
			(xy 282.933376 -288.488954) (xy 282.977838 -288.510052) (xy 283.018341 -288.538008) (xy 283.053834 -288.5721)
			(xy 283.083399 -288.611444) (xy 283.10627 -288.655021) (xy 283.121854 -288.701702) (xy 283.129749 -288.750279)
			(xy 283.130244 -288.774886) (xy 283.469092 -288.774886) (xy 283.473052 -288.725832) (xy 283.484829 -288.678048)
			(xy 283.50412 -288.632772) (xy 283.530423 -288.591176) (xy 283.563058 -288.554339) (xy 283.601179 -288.523214)
			(xy 283.6438 -288.498607) (xy 283.689816 -288.481155) (xy 283.738035 -288.471311) (xy 283.78721 -288.46933)
			(xy 283.836065 -288.475262) (xy 283.883336 -288.488954) (xy 283.927798 -288.510052) (xy 283.968301 -288.538008)
			(xy 284.003794 -288.5721) (xy 284.033359 -288.611444) (xy 284.05623 -288.655021) (xy 284.071814 -288.701702)
			(xy 284.079709 -288.750279) (xy 284.080204 -288.774886) (xy 284.419052 -288.774886) (xy 284.423012 -288.725832)
			(xy 284.434789 -288.678048) (xy 284.45408 -288.632772) (xy 284.480383 -288.591176) (xy 284.513018 -288.554339)
			(xy 284.551139 -288.523214) (xy 284.59376 -288.498607) (xy 284.639776 -288.481155) (xy 284.687995 -288.471311)
			(xy 284.73717 -288.46933) (xy 284.786025 -288.475262) (xy 284.833296 -288.488954) (xy 284.877758 -288.510052)
			(xy 284.918261 -288.538008) (xy 284.953754 -288.5721) (xy 284.983319 -288.611444) (xy 285.00619 -288.655021)
			(xy 285.021774 -288.701702) (xy 285.029669 -288.750279) (xy 285.030164 -288.774886) (xy 285.369012 -288.774886)
			(xy 285.372972 -288.725832) (xy 285.384749 -288.678048) (xy 285.40404 -288.632772) (xy 285.430343 -288.591176)
			(xy 285.462978 -288.554339) (xy 285.501099 -288.523214) (xy 285.54372 -288.498607) (xy 285.589736 -288.481155)
			(xy 285.637955 -288.471311) (xy 285.68713 -288.46933) (xy 285.735985 -288.475262) (xy 285.783256 -288.488954)
			(xy 285.827718 -288.510052) (xy 285.868221 -288.538008) (xy 285.903714 -288.5721) (xy 285.933279 -288.611444)
			(xy 285.95615 -288.655021) (xy 285.971734 -288.701702) (xy 285.979629 -288.750279) (xy 285.980124 -288.774886)
			(xy 286.318972 -288.774886) (xy 286.322932 -288.725832) (xy 286.334709 -288.678048) (xy 286.354 -288.632772)
			(xy 286.380303 -288.591176) (xy 286.412938 -288.554339) (xy 286.451059 -288.523214) (xy 286.49368 -288.498607)
			(xy 286.539696 -288.481155) (xy 286.587915 -288.471311) (xy 286.63709 -288.46933) (xy 286.685945 -288.475262)
			(xy 286.733216 -288.488954) (xy 286.777678 -288.510052) (xy 286.818181 -288.538008) (xy 286.853674 -288.5721)
			(xy 286.883239 -288.611444) (xy 286.90611 -288.655021) (xy 286.921694 -288.701702) (xy 286.929589 -288.750279)
			(xy 286.930084 -288.774886) (xy 287.268932 -288.774886) (xy 287.272892 -288.725832) (xy 287.284669 -288.678048)
			(xy 287.30396 -288.632772) (xy 287.330263 -288.591176) (xy 287.362898 -288.554339) (xy 287.401019 -288.523214)
			(xy 287.44364 -288.498607) (xy 287.489656 -288.481155) (xy 287.537875 -288.471311) (xy 287.58705 -288.46933)
			(xy 287.635905 -288.475262) (xy 287.683176 -288.488954) (xy 287.727638 -288.510052) (xy 287.768141 -288.538008)
			(xy 287.803634 -288.5721) (xy 287.833199 -288.611444) (xy 287.85607 -288.655021) (xy 287.871654 -288.701702)
			(xy 287.879549 -288.750279) (xy 287.880044 -288.774886) (xy 288.218892 -288.774886) (xy 288.222852 -288.725832)
			(xy 288.234629 -288.678048) (xy 288.25392 -288.632772) (xy 288.280223 -288.591176) (xy 288.312858 -288.554339)
			(xy 288.350979 -288.523214) (xy 288.3936 -288.498607) (xy 288.439616 -288.481155) (xy 288.487835 -288.471311)
			(xy 288.53701 -288.46933) (xy 288.585865 -288.475262) (xy 288.633136 -288.488954) (xy 288.677598 -288.510052)
			(xy 288.718101 -288.538008) (xy 288.753594 -288.5721) (xy 288.783159 -288.611444) (xy 288.80603 -288.655021)
			(xy 288.821614 -288.701702) (xy 288.829509 -288.750279) (xy 288.830004 -288.774886) (xy 289.169106 -288.774886)
			(xy 289.173066 -288.725832) (xy 289.184843 -288.678048) (xy 289.204134 -288.632772) (xy 289.230437 -288.591176)
			(xy 289.263072 -288.554339) (xy 289.301193 -288.523214) (xy 289.343814 -288.498607) (xy 289.38983 -288.481155)
			(xy 289.438049 -288.471311) (xy 289.487224 -288.46933) (xy 289.536079 -288.475262) (xy 289.58335 -288.488954)
			(xy 289.627812 -288.510052) (xy 289.668315 -288.538008) (xy 289.703808 -288.5721) (xy 289.733373 -288.611444)
			(xy 289.756244 -288.655021) (xy 289.771828 -288.701702) (xy 289.779723 -288.750279) (xy 289.780218 -288.774886)
			(xy 290.119066 -288.774886) (xy 290.123026 -288.725832) (xy 290.134803 -288.678048) (xy 290.154094 -288.632772)
			(xy 290.180397 -288.591176) (xy 290.213032 -288.554339) (xy 290.251153 -288.523214) (xy 290.293774 -288.498607)
			(xy 290.33979 -288.481155) (xy 290.388009 -288.471311) (xy 290.437184 -288.46933) (xy 290.486039 -288.475262)
			(xy 290.53331 -288.488954) (xy 290.577772 -288.510052) (xy 290.618275 -288.538008) (xy 290.653768 -288.5721)
			(xy 290.683333 -288.611444) (xy 290.706204 -288.655021) (xy 290.721788 -288.701702) (xy 290.729683 -288.750279)
			(xy 290.730178 -288.774886) (xy 292.018986 -288.774886) (xy 292.022946 -288.725832) (xy 292.034723 -288.678048)
			(xy 292.054014 -288.632772) (xy 292.080317 -288.591176) (xy 292.112952 -288.554339) (xy 292.151073 -288.523214)
			(xy 292.193694 -288.498607) (xy 292.23971 -288.481155) (xy 292.287929 -288.471311) (xy 292.337104 -288.46933)
			(xy 292.385959 -288.475262) (xy 292.43323 -288.488954) (xy 292.477692 -288.510052) (xy 292.518195 -288.538008)
			(xy 292.553688 -288.5721) (xy 292.583253 -288.611444) (xy 292.606124 -288.655021) (xy 292.621708 -288.701702)
			(xy 292.629603 -288.750279) (xy 292.630098 -288.774886) (xy 292.968946 -288.774886) (xy 292.972906 -288.725832)
			(xy 292.984683 -288.678048) (xy 293.003974 -288.632772) (xy 293.030277 -288.591176) (xy 293.062912 -288.554339)
			(xy 293.101033 -288.523214) (xy 293.143654 -288.498607) (xy 293.18967 -288.481155) (xy 293.237889 -288.471311)
			(xy 293.287064 -288.46933) (xy 293.335919 -288.475262) (xy 293.38319 -288.488954) (xy 293.427652 -288.510052)
			(xy 293.468155 -288.538008) (xy 293.503648 -288.5721) (xy 293.533213 -288.611444) (xy 293.556084 -288.655021)
			(xy 293.571668 -288.701702) (xy 293.579563 -288.750279) (xy 293.580058 -288.774886) (xy 293.918906 -288.774886)
			(xy 293.922866 -288.725832) (xy 293.934643 -288.678048) (xy 293.953934 -288.632772) (xy 293.980237 -288.591176)
			(xy 294.012872 -288.554339) (xy 294.050993 -288.523214) (xy 294.093614 -288.498607) (xy 294.13963 -288.481155)
			(xy 294.187849 -288.471311) (xy 294.237024 -288.46933) (xy 294.285879 -288.475262) (xy 294.33315 -288.488954)
			(xy 294.377612 -288.510052) (xy 294.418115 -288.538008) (xy 294.453608 -288.5721) (xy 294.483173 -288.611444)
			(xy 294.506044 -288.655021) (xy 294.521628 -288.701702) (xy 294.529523 -288.750279) (xy 294.530018 -288.774886)
			(xy 294.86912 -288.774886) (xy 294.87308 -288.725832) (xy 294.884857 -288.678048) (xy 294.904148 -288.632772)
			(xy 294.930451 -288.591176) (xy 294.963086 -288.554339) (xy 295.001207 -288.523214) (xy 295.043828 -288.498607)
			(xy 295.089844 -288.481155) (xy 295.138063 -288.471311) (xy 295.187238 -288.46933) (xy 295.236093 -288.475262)
			(xy 295.283364 -288.488954) (xy 295.327826 -288.510052) (xy 295.368329 -288.538008) (xy 295.403822 -288.5721)
			(xy 295.433387 -288.611444) (xy 295.456258 -288.655021) (xy 295.471842 -288.701702) (xy 295.479737 -288.750279)
			(xy 295.480232 -288.774886) (xy 295.81908 -288.774886) (xy 295.82304 -288.725832) (xy 295.834817 -288.678048)
			(xy 295.854108 -288.632772) (xy 295.880411 -288.591176) (xy 295.913046 -288.554339) (xy 295.951167 -288.523214)
			(xy 295.993788 -288.498607) (xy 296.039804 -288.481155) (xy 296.088023 -288.471311) (xy 296.137198 -288.46933)
			(xy 296.186053 -288.475262) (xy 296.233324 -288.488954) (xy 296.277786 -288.510052) (xy 296.318289 -288.538008)
			(xy 296.353782 -288.5721) (xy 296.383347 -288.611444) (xy 296.406218 -288.655021) (xy 296.421802 -288.701702)
			(xy 296.429697 -288.750279) (xy 296.430192 -288.774886) (xy 296.76904 -288.774886) (xy 296.773 -288.725832)
			(xy 296.784777 -288.678048) (xy 296.804068 -288.632772) (xy 296.830371 -288.591176) (xy 296.863006 -288.554339)
			(xy 296.901127 -288.523214) (xy 296.943748 -288.498607) (xy 296.989764 -288.481155) (xy 297.037983 -288.471311)
			(xy 297.087158 -288.46933) (xy 297.136013 -288.475262) (xy 297.183284 -288.488954) (xy 297.227746 -288.510052)
			(xy 297.268249 -288.538008) (xy 297.303742 -288.5721) (xy 297.333307 -288.611444) (xy 297.356178 -288.655021)
			(xy 297.371762 -288.701702) (xy 297.379657 -288.750279) (xy 297.380152 -288.774886) (xy 297.719 -288.774886)
			(xy 297.72296 -288.725832) (xy 297.734737 -288.678048) (xy 297.754028 -288.632772) (xy 297.780331 -288.591176)
			(xy 297.812966 -288.554339) (xy 297.851087 -288.523214) (xy 297.893708 -288.498607) (xy 297.939724 -288.481155)
			(xy 297.987943 -288.471311) (xy 298.037118 -288.46933) (xy 298.085973 -288.475262) (xy 298.133244 -288.488954)
			(xy 298.177706 -288.510052) (xy 298.218209 -288.538008) (xy 298.253702 -288.5721) (xy 298.283267 -288.611444)
			(xy 298.306138 -288.655021) (xy 298.321722 -288.701702) (xy 298.329617 -288.750279) (xy 298.330112 -288.774886)
			(xy 298.66896 -288.774886) (xy 298.67292 -288.725832) (xy 298.684697 -288.678048) (xy 298.703988 -288.632772)
			(xy 298.730291 -288.591176) (xy 298.762926 -288.554339) (xy 298.801047 -288.523214) (xy 298.843668 -288.498607)
			(xy 298.889684 -288.481155) (xy 298.937903 -288.471311) (xy 298.987078 -288.46933) (xy 299.035933 -288.475262)
			(xy 299.083204 -288.488954) (xy 299.127666 -288.510052) (xy 299.168169 -288.538008) (xy 299.203662 -288.5721)
			(xy 299.233227 -288.611444) (xy 299.256098 -288.655021) (xy 299.271682 -288.701702) (xy 299.279577 -288.750279)
			(xy 299.280072 -288.774886) (xy 299.61892 -288.774886) (xy 299.62288 -288.725832) (xy 299.634657 -288.678048)
			(xy 299.653948 -288.632772) (xy 299.680251 -288.591176) (xy 299.712886 -288.554339) (xy 299.751007 -288.523214)
			(xy 299.793628 -288.498607) (xy 299.839644 -288.481155) (xy 299.887863 -288.471311) (xy 299.937038 -288.46933)
			(xy 299.985893 -288.475262) (xy 300.033164 -288.488954) (xy 300.077626 -288.510052) (xy 300.118129 -288.538008)
			(xy 300.153622 -288.5721) (xy 300.183187 -288.611444) (xy 300.206058 -288.655021) (xy 300.221642 -288.701702)
			(xy 300.229537 -288.750279) (xy 300.230032 -288.774886) (xy 300.56888 -288.774886) (xy 300.57284 -288.725832)
			(xy 300.584617 -288.678048) (xy 300.603908 -288.632772) (xy 300.630211 -288.591176) (xy 300.662846 -288.554339)
			(xy 300.700967 -288.523214) (xy 300.743588 -288.498607) (xy 300.789604 -288.481155) (xy 300.837823 -288.471311)
			(xy 300.886998 -288.46933) (xy 300.935853 -288.475262) (xy 300.983124 -288.488954) (xy 301.027586 -288.510052)
			(xy 301.068089 -288.538008) (xy 301.103582 -288.5721) (xy 301.133147 -288.611444) (xy 301.156018 -288.655021)
			(xy 301.171602 -288.701702) (xy 301.179497 -288.750279) (xy 301.179992 -288.774886) (xy 301.519094 -288.774886)
			(xy 301.523054 -288.725832) (xy 301.534831 -288.678048) (xy 301.554122 -288.632772) (xy 301.580425 -288.591176)
			(xy 301.61306 -288.554339) (xy 301.651181 -288.523214) (xy 301.693802 -288.498607) (xy 301.739818 -288.481155)
			(xy 301.788037 -288.471311) (xy 301.837212 -288.46933) (xy 301.886067 -288.475262) (xy 301.933338 -288.488954)
			(xy 301.9778 -288.510052) (xy 302.018303 -288.538008) (xy 302.053796 -288.5721) (xy 302.083361 -288.611444)
			(xy 302.106232 -288.655021) (xy 302.121816 -288.701702) (xy 302.129711 -288.750279) (xy 302.130206 -288.774886)
			(xy 302.469054 -288.774886) (xy 302.473014 -288.725832) (xy 302.484791 -288.678048) (xy 302.504082 -288.632772)
			(xy 302.530385 -288.591176) (xy 302.56302 -288.554339) (xy 302.601141 -288.523214) (xy 302.643762 -288.498607)
			(xy 302.689778 -288.481155) (xy 302.737997 -288.471311) (xy 302.787172 -288.46933) (xy 302.836027 -288.475262)
			(xy 302.883298 -288.488954) (xy 302.92776 -288.510052) (xy 302.968263 -288.538008) (xy 303.003756 -288.5721)
			(xy 303.033321 -288.611444) (xy 303.056192 -288.655021) (xy 303.071776 -288.701702) (xy 303.079671 -288.750279)
			(xy 303.080166 -288.774886) (xy 303.419014 -288.774886) (xy 303.422974 -288.725832) (xy 303.434751 -288.678048)
			(xy 303.454042 -288.632772) (xy 303.480345 -288.591176) (xy 303.51298 -288.554339) (xy 303.551101 -288.523214)
			(xy 303.593722 -288.498607) (xy 303.639738 -288.481155) (xy 303.687957 -288.471311) (xy 303.737132 -288.46933)
			(xy 303.785987 -288.475262) (xy 303.833258 -288.488954) (xy 303.87772 -288.510052) (xy 303.918223 -288.538008)
			(xy 303.953716 -288.5721) (xy 303.983281 -288.611444) (xy 304.006152 -288.655021) (xy 304.021736 -288.701702)
			(xy 304.029631 -288.750279) (xy 304.030126 -288.774886) (xy 304.368974 -288.774886) (xy 304.372934 -288.725832)
			(xy 304.384711 -288.678048) (xy 304.404002 -288.632772) (xy 304.430305 -288.591176) (xy 304.46294 -288.554339)
			(xy 304.501061 -288.523214) (xy 304.543682 -288.498607) (xy 304.589698 -288.481155) (xy 304.637917 -288.471311)
			(xy 304.687092 -288.46933) (xy 304.735947 -288.475262) (xy 304.783218 -288.488954) (xy 304.82768 -288.510052)
			(xy 304.868183 -288.538008) (xy 304.903676 -288.5721) (xy 304.933241 -288.611444) (xy 304.956112 -288.655021)
			(xy 304.971696 -288.701702) (xy 304.979591 -288.750279) (xy 304.980086 -288.774886) (xy 304.979591 -288.799493)
			(xy 304.971696 -288.84807) (xy 304.956112 -288.894751) (xy 304.933241 -288.938328) (xy 304.903676 -288.977672)
			(xy 304.868183 -289.011764) (xy 304.82768 -289.03972) (xy 304.783218 -289.060818) (xy 304.735947 -289.07451)
			(xy 304.687092 -289.080442) (xy 304.637917 -289.078461) (xy 304.589698 -289.068617) (xy 304.543682 -289.051165)
			(xy 304.501061 -289.026558) (xy 304.46294 -288.995433) (xy 304.430305 -288.958596) (xy 304.404002 -288.917)
			(xy 304.384711 -288.871724) (xy 304.372934 -288.82394) (xy 304.368974 -288.774886) (xy 304.030126 -288.774886)
			(xy 304.029631 -288.799493) (xy 304.021736 -288.84807) (xy 304.006152 -288.894751) (xy 303.983281 -288.938328)
			(xy 303.953716 -288.977672) (xy 303.918223 -289.011764) (xy 303.87772 -289.03972) (xy 303.833258 -289.060818)
			(xy 303.785987 -289.07451) (xy 303.737132 -289.080442) (xy 303.687957 -289.078461) (xy 303.639738 -289.068617)
			(xy 303.593722 -289.051165) (xy 303.551101 -289.026558) (xy 303.51298 -288.995433) (xy 303.480345 -288.958596)
			(xy 303.454042 -288.917) (xy 303.434751 -288.871724) (xy 303.422974 -288.82394) (xy 303.419014 -288.774886)
			(xy 303.080166 -288.774886) (xy 303.079671 -288.799493) (xy 303.071776 -288.84807) (xy 303.056192 -288.894751)
			(xy 303.033321 -288.938328) (xy 303.003756 -288.977672) (xy 302.968263 -289.011764) (xy 302.92776 -289.03972)
			(xy 302.883298 -289.060818) (xy 302.836027 -289.07451) (xy 302.787172 -289.080442) (xy 302.737997 -289.078461)
			(xy 302.689778 -289.068617) (xy 302.643762 -289.051165) (xy 302.601141 -289.026558) (xy 302.56302 -288.995433)
			(xy 302.530385 -288.958596) (xy 302.504082 -288.917) (xy 302.484791 -288.871724) (xy 302.473014 -288.82394)
			(xy 302.469054 -288.774886) (xy 302.130206 -288.774886) (xy 302.129711 -288.799493) (xy 302.121816 -288.84807)
			(xy 302.106232 -288.894751) (xy 302.083361 -288.938328) (xy 302.053796 -288.977672) (xy 302.018303 -289.011764)
			(xy 301.9778 -289.03972) (xy 301.933338 -289.060818) (xy 301.886067 -289.07451) (xy 301.837212 -289.080442)
			(xy 301.788037 -289.078461) (xy 301.739818 -289.068617) (xy 301.693802 -289.051165) (xy 301.651181 -289.026558)
			(xy 301.61306 -288.995433) (xy 301.580425 -288.958596) (xy 301.554122 -288.917) (xy 301.534831 -288.871724)
			(xy 301.523054 -288.82394) (xy 301.519094 -288.774886) (xy 301.179992 -288.774886) (xy 301.179497 -288.799493)
			(xy 301.171602 -288.84807) (xy 301.156018 -288.894751) (xy 301.133147 -288.938328) (xy 301.103582 -288.977672)
			(xy 301.068089 -289.011764) (xy 301.027586 -289.03972) (xy 300.983124 -289.060818) (xy 300.935853 -289.07451)
			(xy 300.886998 -289.080442) (xy 300.837823 -289.078461) (xy 300.789604 -289.068617) (xy 300.743588 -289.051165)
			(xy 300.700967 -289.026558) (xy 300.662846 -288.995433) (xy 300.630211 -288.958596) (xy 300.603908 -288.917)
			(xy 300.584617 -288.871724) (xy 300.57284 -288.82394) (xy 300.56888 -288.774886) (xy 300.230032 -288.774886)
			(xy 300.229537 -288.799493) (xy 300.221642 -288.84807) (xy 300.206058 -288.894751) (xy 300.183187 -288.938328)
			(xy 300.153622 -288.977672) (xy 300.118129 -289.011764) (xy 300.077626 -289.03972) (xy 300.033164 -289.060818)
			(xy 299.985893 -289.07451) (xy 299.937038 -289.080442) (xy 299.887863 -289.078461) (xy 299.839644 -289.068617)
			(xy 299.793628 -289.051165) (xy 299.751007 -289.026558) (xy 299.712886 -288.995433) (xy 299.680251 -288.958596)
			(xy 299.653948 -288.917) (xy 299.634657 -288.871724) (xy 299.62288 -288.82394) (xy 299.61892 -288.774886)
			(xy 299.280072 -288.774886) (xy 299.279577 -288.799493) (xy 299.271682 -288.84807) (xy 299.256098 -288.894751)
			(xy 299.233227 -288.938328) (xy 299.203662 -288.977672) (xy 299.168169 -289.011764) (xy 299.127666 -289.03972)
			(xy 299.083204 -289.060818) (xy 299.035933 -289.07451) (xy 298.987078 -289.080442) (xy 298.937903 -289.078461)
			(xy 298.889684 -289.068617) (xy 298.843668 -289.051165) (xy 298.801047 -289.026558) (xy 298.762926 -288.995433)
			(xy 298.730291 -288.958596) (xy 298.703988 -288.917) (xy 298.684697 -288.871724) (xy 298.67292 -288.82394)
			(xy 298.66896 -288.774886) (xy 298.330112 -288.774886) (xy 298.329617 -288.799493) (xy 298.321722 -288.84807)
			(xy 298.306138 -288.894751) (xy 298.283267 -288.938328) (xy 298.253702 -288.977672) (xy 298.218209 -289.011764)
			(xy 298.177706 -289.03972) (xy 298.133244 -289.060818) (xy 298.085973 -289.07451) (xy 298.037118 -289.080442)
			(xy 297.987943 -289.078461) (xy 297.939724 -289.068617) (xy 297.893708 -289.051165) (xy 297.851087 -289.026558)
			(xy 297.812966 -288.995433) (xy 297.780331 -288.958596) (xy 297.754028 -288.917) (xy 297.734737 -288.871724)
			(xy 297.72296 -288.82394) (xy 297.719 -288.774886) (xy 297.380152 -288.774886) (xy 297.379657 -288.799493)
			(xy 297.371762 -288.84807) (xy 297.356178 -288.894751) (xy 297.333307 -288.938328) (xy 297.303742 -288.977672)
			(xy 297.268249 -289.011764) (xy 297.227746 -289.03972) (xy 297.183284 -289.060818) (xy 297.136013 -289.07451)
			(xy 297.087158 -289.080442) (xy 297.037983 -289.078461) (xy 296.989764 -289.068617) (xy 296.943748 -289.051165)
			(xy 296.901127 -289.026558) (xy 296.863006 -288.995433) (xy 296.830371 -288.958596) (xy 296.804068 -288.917)
			(xy 296.784777 -288.871724) (xy 296.773 -288.82394) (xy 296.76904 -288.774886) (xy 296.430192 -288.774886)
			(xy 296.429697 -288.799493) (xy 296.421802 -288.84807) (xy 296.406218 -288.894751) (xy 296.383347 -288.938328)
			(xy 296.353782 -288.977672) (xy 296.318289 -289.011764) (xy 296.277786 -289.03972) (xy 296.233324 -289.060818)
			(xy 296.186053 -289.07451) (xy 296.137198 -289.080442) (xy 296.088023 -289.078461) (xy 296.039804 -289.068617)
			(xy 295.993788 -289.051165) (xy 295.951167 -289.026558) (xy 295.913046 -288.995433) (xy 295.880411 -288.958596)
			(xy 295.854108 -288.917) (xy 295.834817 -288.871724) (xy 295.82304 -288.82394) (xy 295.81908 -288.774886)
			(xy 295.480232 -288.774886) (xy 295.479737 -288.799493) (xy 295.471842 -288.84807) (xy 295.456258 -288.894751)
			(xy 295.433387 -288.938328) (xy 295.403822 -288.977672) (xy 295.368329 -289.011764) (xy 295.327826 -289.03972)
			(xy 295.283364 -289.060818) (xy 295.236093 -289.07451) (xy 295.187238 -289.080442) (xy 295.138063 -289.078461)
			(xy 295.089844 -289.068617) (xy 295.043828 -289.051165) (xy 295.001207 -289.026558) (xy 294.963086 -288.995433)
			(xy 294.930451 -288.958596) (xy 294.904148 -288.917) (xy 294.884857 -288.871724) (xy 294.87308 -288.82394)
			(xy 294.86912 -288.774886) (xy 294.530018 -288.774886) (xy 294.529523 -288.799493) (xy 294.521628 -288.84807)
			(xy 294.506044 -288.894751) (xy 294.483173 -288.938328) (xy 294.453608 -288.977672) (xy 294.418115 -289.011764)
			(xy 294.377612 -289.03972) (xy 294.33315 -289.060818) (xy 294.285879 -289.07451) (xy 294.237024 -289.080442)
			(xy 294.187849 -289.078461) (xy 294.13963 -289.068617) (xy 294.093614 -289.051165) (xy 294.050993 -289.026558)
			(xy 294.012872 -288.995433) (xy 293.980237 -288.958596) (xy 293.953934 -288.917) (xy 293.934643 -288.871724)
			(xy 293.922866 -288.82394) (xy 293.918906 -288.774886) (xy 293.580058 -288.774886) (xy 293.579563 -288.799493)
			(xy 293.571668 -288.84807) (xy 293.556084 -288.894751) (xy 293.533213 -288.938328) (xy 293.503648 -288.977672)
			(xy 293.468155 -289.011764) (xy 293.427652 -289.03972) (xy 293.38319 -289.060818) (xy 293.335919 -289.07451)
			(xy 293.287064 -289.080442) (xy 293.237889 -289.078461) (xy 293.18967 -289.068617) (xy 293.143654 -289.051165)
			(xy 293.101033 -289.026558) (xy 293.062912 -288.995433) (xy 293.030277 -288.958596) (xy 293.003974 -288.917)
			(xy 292.984683 -288.871724) (xy 292.972906 -288.82394) (xy 292.968946 -288.774886) (xy 292.630098 -288.774886)
			(xy 292.629603 -288.799493) (xy 292.621708 -288.84807) (xy 292.606124 -288.894751) (xy 292.583253 -288.938328)
			(xy 292.553688 -288.977672) (xy 292.518195 -289.011764) (xy 292.477692 -289.03972) (xy 292.43323 -289.060818)
			(xy 292.385959 -289.07451) (xy 292.337104 -289.080442) (xy 292.287929 -289.078461) (xy 292.23971 -289.068617)
			(xy 292.193694 -289.051165) (xy 292.151073 -289.026558) (xy 292.112952 -288.995433) (xy 292.080317 -288.958596)
			(xy 292.054014 -288.917) (xy 292.034723 -288.871724) (xy 292.022946 -288.82394) (xy 292.018986 -288.774886)
			(xy 290.730178 -288.774886) (xy 290.729683 -288.799493) (xy 290.721788 -288.84807) (xy 290.706204 -288.894751)
			(xy 290.683333 -288.938328) (xy 290.653768 -288.977672) (xy 290.618275 -289.011764) (xy 290.577772 -289.03972)
			(xy 290.53331 -289.060818) (xy 290.486039 -289.07451) (xy 290.437184 -289.080442) (xy 290.388009 -289.078461)
			(xy 290.33979 -289.068617) (xy 290.293774 -289.051165) (xy 290.251153 -289.026558) (xy 290.213032 -288.995433)
			(xy 290.180397 -288.958596) (xy 290.154094 -288.917) (xy 290.134803 -288.871724) (xy 290.123026 -288.82394)
			(xy 290.119066 -288.774886) (xy 289.780218 -288.774886) (xy 289.779723 -288.799493) (xy 289.771828 -288.84807)
			(xy 289.756244 -288.894751) (xy 289.733373 -288.938328) (xy 289.703808 -288.977672) (xy 289.668315 -289.011764)
			(xy 289.627812 -289.03972) (xy 289.58335 -289.060818) (xy 289.536079 -289.07451) (xy 289.487224 -289.080442)
			(xy 289.438049 -289.078461) (xy 289.38983 -289.068617) (xy 289.343814 -289.051165) (xy 289.301193 -289.026558)
			(xy 289.263072 -288.995433) (xy 289.230437 -288.958596) (xy 289.204134 -288.917) (xy 289.184843 -288.871724)
			(xy 289.173066 -288.82394) (xy 289.169106 -288.774886) (xy 288.830004 -288.774886) (xy 288.829509 -288.799493)
			(xy 288.821614 -288.84807) (xy 288.80603 -288.894751) (xy 288.783159 -288.938328) (xy 288.753594 -288.977672)
			(xy 288.718101 -289.011764) (xy 288.677598 -289.03972) (xy 288.633136 -289.060818) (xy 288.585865 -289.07451)
			(xy 288.53701 -289.080442) (xy 288.487835 -289.078461) (xy 288.439616 -289.068617) (xy 288.3936 -289.051165)
			(xy 288.350979 -289.026558) (xy 288.312858 -288.995433) (xy 288.280223 -288.958596) (xy 288.25392 -288.917)
			(xy 288.234629 -288.871724) (xy 288.222852 -288.82394) (xy 288.218892 -288.774886) (xy 287.880044 -288.774886)
			(xy 287.879549 -288.799493) (xy 287.871654 -288.84807) (xy 287.85607 -288.894751) (xy 287.833199 -288.938328)
			(xy 287.803634 -288.977672) (xy 287.768141 -289.011764) (xy 287.727638 -289.03972) (xy 287.683176 -289.060818)
			(xy 287.635905 -289.07451) (xy 287.58705 -289.080442) (xy 287.537875 -289.078461) (xy 287.489656 -289.068617)
			(xy 287.44364 -289.051165) (xy 287.401019 -289.026558) (xy 287.362898 -288.995433) (xy 287.330263 -288.958596)
			(xy 287.30396 -288.917) (xy 287.284669 -288.871724) (xy 287.272892 -288.82394) (xy 287.268932 -288.774886)
			(xy 286.930084 -288.774886) (xy 286.929589 -288.799493) (xy 286.921694 -288.84807) (xy 286.90611 -288.894751)
			(xy 286.883239 -288.938328) (xy 286.853674 -288.977672) (xy 286.818181 -289.011764) (xy 286.777678 -289.03972)
			(xy 286.733216 -289.060818) (xy 286.685945 -289.07451) (xy 286.63709 -289.080442) (xy 286.587915 -289.078461)
			(xy 286.539696 -289.068617) (xy 286.49368 -289.051165) (xy 286.451059 -289.026558) (xy 286.412938 -288.995433)
			(xy 286.380303 -288.958596) (xy 286.354 -288.917) (xy 286.334709 -288.871724) (xy 286.322932 -288.82394)
			(xy 286.318972 -288.774886) (xy 285.980124 -288.774886) (xy 285.979629 -288.799493) (xy 285.971734 -288.84807)
			(xy 285.95615 -288.894751) (xy 285.933279 -288.938328) (xy 285.903714 -288.977672) (xy 285.868221 -289.011764)
			(xy 285.827718 -289.03972) (xy 285.783256 -289.060818) (xy 285.735985 -289.07451) (xy 285.68713 -289.080442)
			(xy 285.637955 -289.078461) (xy 285.589736 -289.068617) (xy 285.54372 -289.051165) (xy 285.501099 -289.026558)
			(xy 285.462978 -288.995433) (xy 285.430343 -288.958596) (xy 285.40404 -288.917) (xy 285.384749 -288.871724)
			(xy 285.372972 -288.82394) (xy 285.369012 -288.774886) (xy 285.030164 -288.774886) (xy 285.029669 -288.799493)
			(xy 285.021774 -288.84807) (xy 285.00619 -288.894751) (xy 284.983319 -288.938328) (xy 284.953754 -288.977672)
			(xy 284.918261 -289.011764) (xy 284.877758 -289.03972) (xy 284.833296 -289.060818) (xy 284.786025 -289.07451)
			(xy 284.73717 -289.080442) (xy 284.687995 -289.078461) (xy 284.639776 -289.068617) (xy 284.59376 -289.051165)
			(xy 284.551139 -289.026558) (xy 284.513018 -288.995433) (xy 284.480383 -288.958596) (xy 284.45408 -288.917)
			(xy 284.434789 -288.871724) (xy 284.423012 -288.82394) (xy 284.419052 -288.774886) (xy 284.080204 -288.774886)
			(xy 284.079709 -288.799493) (xy 284.071814 -288.84807) (xy 284.05623 -288.894751) (xy 284.033359 -288.938328)
			(xy 284.003794 -288.977672) (xy 283.968301 -289.011764) (xy 283.927798 -289.03972) (xy 283.883336 -289.060818)
			(xy 283.836065 -289.07451) (xy 283.78721 -289.080442) (xy 283.738035 -289.078461) (xy 283.689816 -289.068617)
			(xy 283.6438 -289.051165) (xy 283.601179 -289.026558) (xy 283.563058 -288.995433) (xy 283.530423 -288.958596)
			(xy 283.50412 -288.917) (xy 283.484829 -288.871724) (xy 283.473052 -288.82394) (xy 283.469092 -288.774886)
			(xy 283.130244 -288.774886) (xy 283.129749 -288.799493) (xy 283.121854 -288.84807) (xy 283.10627 -288.894751)
			(xy 283.083399 -288.938328) (xy 283.053834 -288.977672) (xy 283.018341 -289.011764) (xy 282.977838 -289.03972)
			(xy 282.933376 -289.060818) (xy 282.886105 -289.07451) (xy 282.83725 -289.080442) (xy 282.788075 -289.078461)
			(xy 282.739856 -289.068617) (xy 282.69384 -289.051165) (xy 282.651219 -289.026558) (xy 282.613098 -288.995433)
			(xy 282.580463 -288.958596) (xy 282.55416 -288.917) (xy 282.534869 -288.871724) (xy 282.523092 -288.82394)
			(xy 282.519132 -288.774886) (xy 282.18003 -288.774886) (xy 282.179535 -288.799493) (xy 282.17164 -288.84807)
			(xy 282.156056 -288.894751) (xy 282.133185 -288.938328) (xy 282.10362 -288.977672) (xy 282.068127 -289.011764)
			(xy 282.027624 -289.03972) (xy 281.983162 -289.060818) (xy 281.935891 -289.07451) (xy 281.887036 -289.080442)
			(xy 281.837861 -289.078461) (xy 281.789642 -289.068617) (xy 281.743626 -289.051165) (xy 281.701005 -289.026558)
			(xy 281.662884 -288.995433) (xy 281.630249 -288.958596) (xy 281.603946 -288.917) (xy 281.584655 -288.871724)
			(xy 281.572878 -288.82394) (xy 281.568918 -288.774886) (xy 281.23007 -288.774886) (xy 281.229575 -288.799493)
			(xy 281.22168 -288.84807) (xy 281.206096 -288.894751) (xy 281.183225 -288.938328) (xy 281.15366 -288.977672)
			(xy 281.118167 -289.011764) (xy 281.077664 -289.03972) (xy 281.033202 -289.060818) (xy 280.985931 -289.07451)
			(xy 280.937076 -289.080442) (xy 280.887901 -289.078461) (xy 280.839682 -289.068617) (xy 280.793666 -289.051165)
			(xy 280.751045 -289.026558) (xy 280.712924 -288.995433) (xy 280.680289 -288.958596) (xy 280.653986 -288.917)
			(xy 280.634695 -288.871724) (xy 280.622918 -288.82394) (xy 280.618958 -288.774886) (xy 280.28011 -288.774886)
			(xy 280.279615 -288.799493) (xy 280.27172 -288.84807) (xy 280.256136 -288.894751) (xy 280.233265 -288.938328)
			(xy 280.2037 -288.977672) (xy 280.168207 -289.011764) (xy 280.127704 -289.03972) (xy 280.083242 -289.060818)
			(xy 280.035971 -289.07451) (xy 279.987116 -289.080442) (xy 279.937941 -289.078461) (xy 279.889722 -289.068617)
			(xy 279.843706 -289.051165) (xy 279.801085 -289.026558) (xy 279.762964 -288.995433) (xy 279.730329 -288.958596)
			(xy 279.704026 -288.917) (xy 279.684735 -288.871724) (xy 279.672958 -288.82394) (xy 279.668998 -288.774886)
			(xy 279.41397 -288.774886) (xy 279.41397 -289.08502) (xy 317.987678 -289.08502) (xy 317.991749 -289.029398)
			(xy 318.003875 -288.974961) (xy 318.023798 -288.92287) (xy 318.051094 -288.874235) (xy 318.08518 -288.830092)
			(xy 318.125329 -288.791383) (xy 318.170687 -288.758932) (xy 318.220287 -288.733431) (xy 318.273071 -288.715424)
			(xy 318.327914 -288.705294) (xy 318.383648 -288.703257) (xy 318.439085 -288.709357) (xy 318.493042 -288.723463)
			(xy 318.544371 -288.745275) (xy 318.591977 -288.774329) (xy 318.634845 -288.810004) (xy 318.653448 -288.830766)
			(xy 325.352916 -288.830766) (xy 325.356987 -288.775144) (xy 325.369113 -288.720707) (xy 325.389036 -288.668616)
			(xy 325.416332 -288.619981) (xy 325.450418 -288.575838) (xy 325.490567 -288.537129) (xy 325.535925 -288.504678)
			(xy 325.585525 -288.479177) (xy 325.638309 -288.46117) (xy 325.693152 -288.45104) (xy 325.748886 -288.449003)
			(xy 325.804323 -288.455103) (xy 325.85828 -288.469209) (xy 325.909609 -288.491021) (xy 325.957215 -288.520075)
			(xy 326.000083 -288.55575) (xy 326.0373 -288.597287) (xy 326.068073 -288.6438) (xy 326.091745 -288.694297)
			(xy 326.107813 -288.747704) (xy 326.115933 -288.80288) (xy 326.116442 -288.830766) (xy 326.115933 -288.858652)
			(xy 326.107813 -288.913828) (xy 326.091745 -288.967235) (xy 326.068073 -289.017732) (xy 326.0373 -289.064245)
			(xy 326.000083 -289.105782) (xy 325.957215 -289.141457) (xy 325.909609 -289.170511) (xy 325.85828 -289.192323)
			(xy 325.804323 -289.206429) (xy 325.748886 -289.212529) (xy 325.693152 -289.210492) (xy 325.638309 -289.200362)
			(xy 325.585525 -289.182355) (xy 325.535925 -289.156854) (xy 325.490567 -289.124403) (xy 325.450418 -289.085694)
			(xy 325.416332 -289.041551) (xy 325.389036 -288.992916) (xy 325.369113 -288.940825) (xy 325.356987 -288.886388)
			(xy 325.352916 -288.830766) (xy 318.653448 -288.830766) (xy 318.672062 -288.851541) (xy 318.702835 -288.898054)
			(xy 318.726507 -288.948551) (xy 318.742575 -289.001958) (xy 318.750695 -289.057134) (xy 318.751204 -289.08502)
			(xy 318.750695 -289.112906) (xy 318.742575 -289.168082) (xy 318.726507 -289.221489) (xy 318.702835 -289.271986)
			(xy 318.672062 -289.318499) (xy 318.634845 -289.360036) (xy 318.591977 -289.395711) (xy 318.544371 -289.424765)
			(xy 318.493042 -289.446577) (xy 318.439085 -289.460683) (xy 318.383648 -289.466783) (xy 318.327914 -289.464746)
			(xy 318.273071 -289.454616) (xy 318.220287 -289.436609) (xy 318.170687 -289.411108) (xy 318.125329 -289.378657)
			(xy 318.08518 -289.339948) (xy 318.051094 -289.295805) (xy 318.023798 -289.24717) (xy 318.003875 -289.195079)
			(xy 317.991749 -289.140642) (xy 317.987678 -289.08502) (xy 279.41397 -289.08502) (xy 279.41397 -289.724846)
			(xy 279.668998 -289.724846) (xy 279.672958 -289.675792) (xy 279.684735 -289.628008) (xy 279.704026 -289.582732)
			(xy 279.730329 -289.541136) (xy 279.762964 -289.504299) (xy 279.801085 -289.473174) (xy 279.843706 -289.448567)
			(xy 279.889722 -289.431115) (xy 279.937941 -289.421271) (xy 279.987116 -289.41929) (xy 280.035971 -289.425222)
			(xy 280.083242 -289.438914) (xy 280.127704 -289.460012) (xy 280.168207 -289.487968) (xy 280.2037 -289.52206)
			(xy 280.233265 -289.561404) (xy 280.256136 -289.604981) (xy 280.27172 -289.651662) (xy 280.279615 -289.700239)
			(xy 280.28011 -289.724846) (xy 280.618958 -289.724846) (xy 280.622918 -289.675792) (xy 280.634695 -289.628008)
			(xy 280.653986 -289.582732) (xy 280.680289 -289.541136) (xy 280.712924 -289.504299) (xy 280.751045 -289.473174)
			(xy 280.793666 -289.448567) (xy 280.839682 -289.431115) (xy 280.887901 -289.421271) (xy 280.937076 -289.41929)
			(xy 280.985931 -289.425222) (xy 281.033202 -289.438914) (xy 281.077664 -289.460012) (xy 281.118167 -289.487968)
			(xy 281.15366 -289.52206) (xy 281.183225 -289.561404) (xy 281.206096 -289.604981) (xy 281.22168 -289.651662)
			(xy 281.229575 -289.700239) (xy 281.23007 -289.724846) (xy 281.568918 -289.724846) (xy 281.572878 -289.675792)
			(xy 281.584655 -289.628008) (xy 281.603946 -289.582732) (xy 281.630249 -289.541136) (xy 281.662884 -289.504299)
			(xy 281.701005 -289.473174) (xy 281.743626 -289.448567) (xy 281.789642 -289.431115) (xy 281.837861 -289.421271)
			(xy 281.887036 -289.41929) (xy 281.935891 -289.425222) (xy 281.983162 -289.438914) (xy 282.027624 -289.460012)
			(xy 282.068127 -289.487968) (xy 282.10362 -289.52206) (xy 282.133185 -289.561404) (xy 282.156056 -289.604981)
			(xy 282.17164 -289.651662) (xy 282.179535 -289.700239) (xy 282.18003 -289.724846) (xy 282.519132 -289.724846)
			(xy 282.523092 -289.675792) (xy 282.534869 -289.628008) (xy 282.55416 -289.582732) (xy 282.580463 -289.541136)
			(xy 282.613098 -289.504299) (xy 282.651219 -289.473174) (xy 282.69384 -289.448567) (xy 282.739856 -289.431115)
			(xy 282.788075 -289.421271) (xy 282.83725 -289.41929) (xy 282.886105 -289.425222) (xy 282.933376 -289.438914)
			(xy 282.977838 -289.460012) (xy 283.018341 -289.487968) (xy 283.053834 -289.52206) (xy 283.083399 -289.561404)
			(xy 283.10627 -289.604981) (xy 283.121854 -289.651662) (xy 283.129749 -289.700239) (xy 283.130244 -289.724846)
			(xy 283.469092 -289.724846) (xy 283.473052 -289.675792) (xy 283.484829 -289.628008) (xy 283.50412 -289.582732)
			(xy 283.530423 -289.541136) (xy 283.563058 -289.504299) (xy 283.601179 -289.473174) (xy 283.6438 -289.448567)
			(xy 283.689816 -289.431115) (xy 283.738035 -289.421271) (xy 283.78721 -289.41929) (xy 283.836065 -289.425222)
			(xy 283.883336 -289.438914) (xy 283.927798 -289.460012) (xy 283.968301 -289.487968) (xy 284.003794 -289.52206)
			(xy 284.033359 -289.561404) (xy 284.05623 -289.604981) (xy 284.071814 -289.651662) (xy 284.079709 -289.700239)
			(xy 284.080204 -289.724846) (xy 284.419052 -289.724846) (xy 284.423012 -289.675792) (xy 284.434789 -289.628008)
			(xy 284.45408 -289.582732) (xy 284.480383 -289.541136) (xy 284.513018 -289.504299) (xy 284.551139 -289.473174)
			(xy 284.59376 -289.448567) (xy 284.639776 -289.431115) (xy 284.687995 -289.421271) (xy 284.73717 -289.41929)
			(xy 284.786025 -289.425222) (xy 284.833296 -289.438914) (xy 284.877758 -289.460012) (xy 284.918261 -289.487968)
			(xy 284.953754 -289.52206) (xy 284.983319 -289.561404) (xy 285.00619 -289.604981) (xy 285.021774 -289.651662)
			(xy 285.029669 -289.700239) (xy 285.030164 -289.724846) (xy 285.369012 -289.724846) (xy 285.372972 -289.675792)
			(xy 285.384749 -289.628008) (xy 285.40404 -289.582732) (xy 285.430343 -289.541136) (xy 285.462978 -289.504299)
			(xy 285.501099 -289.473174) (xy 285.54372 -289.448567) (xy 285.589736 -289.431115) (xy 285.637955 -289.421271)
			(xy 285.68713 -289.41929) (xy 285.735985 -289.425222) (xy 285.783256 -289.438914) (xy 285.827718 -289.460012)
			(xy 285.868221 -289.487968) (xy 285.903714 -289.52206) (xy 285.933279 -289.561404) (xy 285.95615 -289.604981)
			(xy 285.971734 -289.651662) (xy 285.979629 -289.700239) (xy 285.980124 -289.724846) (xy 286.318972 -289.724846)
			(xy 286.322932 -289.675792) (xy 286.334709 -289.628008) (xy 286.354 -289.582732) (xy 286.380303 -289.541136)
			(xy 286.412938 -289.504299) (xy 286.451059 -289.473174) (xy 286.49368 -289.448567) (xy 286.539696 -289.431115)
			(xy 286.587915 -289.421271) (xy 286.63709 -289.41929) (xy 286.685945 -289.425222) (xy 286.733216 -289.438914)
			(xy 286.777678 -289.460012) (xy 286.818181 -289.487968) (xy 286.853674 -289.52206) (xy 286.883239 -289.561404)
			(xy 286.90611 -289.604981) (xy 286.921694 -289.651662) (xy 286.929589 -289.700239) (xy 286.930084 -289.724846)
			(xy 287.268932 -289.724846) (xy 287.272892 -289.675792) (xy 287.284669 -289.628008) (xy 287.30396 -289.582732)
			(xy 287.330263 -289.541136) (xy 287.362898 -289.504299) (xy 287.401019 -289.473174) (xy 287.44364 -289.448567)
			(xy 287.489656 -289.431115) (xy 287.537875 -289.421271) (xy 287.58705 -289.41929) (xy 287.635905 -289.425222)
			(xy 287.683176 -289.438914) (xy 287.727638 -289.460012) (xy 287.768141 -289.487968) (xy 287.803634 -289.52206)
			(xy 287.833199 -289.561404) (xy 287.85607 -289.604981) (xy 287.871654 -289.651662) (xy 287.879549 -289.700239)
			(xy 287.880044 -289.724846) (xy 288.218892 -289.724846) (xy 288.222852 -289.675792) (xy 288.234629 -289.628008)
			(xy 288.25392 -289.582732) (xy 288.280223 -289.541136) (xy 288.312858 -289.504299) (xy 288.350979 -289.473174)
			(xy 288.3936 -289.448567) (xy 288.439616 -289.431115) (xy 288.487835 -289.421271) (xy 288.53701 -289.41929)
			(xy 288.585865 -289.425222) (xy 288.633136 -289.438914) (xy 288.677598 -289.460012) (xy 288.718101 -289.487968)
			(xy 288.753594 -289.52206) (xy 288.783159 -289.561404) (xy 288.80603 -289.604981) (xy 288.821614 -289.651662)
			(xy 288.829509 -289.700239) (xy 288.830004 -289.724846) (xy 289.169106 -289.724846) (xy 289.173066 -289.675792)
			(xy 289.184843 -289.628008) (xy 289.204134 -289.582732) (xy 289.230437 -289.541136) (xy 289.263072 -289.504299)
			(xy 289.301193 -289.473174) (xy 289.343814 -289.448567) (xy 289.38983 -289.431115) (xy 289.438049 -289.421271)
			(xy 289.487224 -289.41929) (xy 289.536079 -289.425222) (xy 289.58335 -289.438914) (xy 289.627812 -289.460012)
			(xy 289.668315 -289.487968) (xy 289.703808 -289.52206) (xy 289.733373 -289.561404) (xy 289.756244 -289.604981)
			(xy 289.771828 -289.651662) (xy 289.779723 -289.700239) (xy 289.780218 -289.724846) (xy 290.119066 -289.724846)
			(xy 290.123026 -289.675792) (xy 290.134803 -289.628008) (xy 290.154094 -289.582732) (xy 290.180397 -289.541136)
			(xy 290.213032 -289.504299) (xy 290.251153 -289.473174) (xy 290.293774 -289.448567) (xy 290.33979 -289.431115)
			(xy 290.388009 -289.421271) (xy 290.437184 -289.41929) (xy 290.486039 -289.425222) (xy 290.53331 -289.438914)
			(xy 290.577772 -289.460012) (xy 290.618275 -289.487968) (xy 290.653768 -289.52206) (xy 290.683333 -289.561404)
			(xy 290.706204 -289.604981) (xy 290.721788 -289.651662) (xy 290.729683 -289.700239) (xy 290.730178 -289.724846)
			(xy 292.018986 -289.724846) (xy 292.022946 -289.675792) (xy 292.034723 -289.628008) (xy 292.054014 -289.582732)
			(xy 292.080317 -289.541136) (xy 292.112952 -289.504299) (xy 292.151073 -289.473174) (xy 292.193694 -289.448567)
			(xy 292.23971 -289.431115) (xy 292.287929 -289.421271) (xy 292.337104 -289.41929) (xy 292.385959 -289.425222)
			(xy 292.43323 -289.438914) (xy 292.477692 -289.460012) (xy 292.518195 -289.487968) (xy 292.553688 -289.52206)
			(xy 292.583253 -289.561404) (xy 292.606124 -289.604981) (xy 292.621708 -289.651662) (xy 292.629603 -289.700239)
			(xy 292.630098 -289.724846) (xy 292.968946 -289.724846) (xy 292.972906 -289.675792) (xy 292.984683 -289.628008)
			(xy 293.003974 -289.582732) (xy 293.030277 -289.541136) (xy 293.062912 -289.504299) (xy 293.101033 -289.473174)
			(xy 293.143654 -289.448567) (xy 293.18967 -289.431115) (xy 293.237889 -289.421271) (xy 293.287064 -289.41929)
			(xy 293.335919 -289.425222) (xy 293.38319 -289.438914) (xy 293.427652 -289.460012) (xy 293.468155 -289.487968)
			(xy 293.503648 -289.52206) (xy 293.533213 -289.561404) (xy 293.556084 -289.604981) (xy 293.571668 -289.651662)
			(xy 293.579563 -289.700239) (xy 293.580058 -289.724846) (xy 293.918906 -289.724846) (xy 293.922866 -289.675792)
			(xy 293.934643 -289.628008) (xy 293.953934 -289.582732) (xy 293.980237 -289.541136) (xy 294.012872 -289.504299)
			(xy 294.050993 -289.473174) (xy 294.093614 -289.448567) (xy 294.13963 -289.431115) (xy 294.187849 -289.421271)
			(xy 294.237024 -289.41929) (xy 294.285879 -289.425222) (xy 294.33315 -289.438914) (xy 294.377612 -289.460012)
			(xy 294.418115 -289.487968) (xy 294.453608 -289.52206) (xy 294.483173 -289.561404) (xy 294.506044 -289.604981)
			(xy 294.521628 -289.651662) (xy 294.529523 -289.700239) (xy 294.530018 -289.724846) (xy 294.86912 -289.724846)
			(xy 294.87308 -289.675792) (xy 294.884857 -289.628008) (xy 294.904148 -289.582732) (xy 294.930451 -289.541136)
			(xy 294.963086 -289.504299) (xy 295.001207 -289.473174) (xy 295.043828 -289.448567) (xy 295.089844 -289.431115)
			(xy 295.138063 -289.421271) (xy 295.187238 -289.41929) (xy 295.236093 -289.425222) (xy 295.283364 -289.438914)
			(xy 295.327826 -289.460012) (xy 295.368329 -289.487968) (xy 295.403822 -289.52206) (xy 295.433387 -289.561404)
			(xy 295.456258 -289.604981) (xy 295.471842 -289.651662) (xy 295.479737 -289.700239) (xy 295.480232 -289.724846)
			(xy 295.81908 -289.724846) (xy 295.82304 -289.675792) (xy 295.834817 -289.628008) (xy 295.854108 -289.582732)
			(xy 295.880411 -289.541136) (xy 295.913046 -289.504299) (xy 295.951167 -289.473174) (xy 295.993788 -289.448567)
			(xy 296.039804 -289.431115) (xy 296.088023 -289.421271) (xy 296.137198 -289.41929) (xy 296.186053 -289.425222)
			(xy 296.233324 -289.438914) (xy 296.277786 -289.460012) (xy 296.318289 -289.487968) (xy 296.353782 -289.52206)
			(xy 296.383347 -289.561404) (xy 296.406218 -289.604981) (xy 296.421802 -289.651662) (xy 296.429697 -289.700239)
			(xy 296.430192 -289.724846) (xy 296.76904 -289.724846) (xy 296.773 -289.675792) (xy 296.784777 -289.628008)
			(xy 296.804068 -289.582732) (xy 296.830371 -289.541136) (xy 296.863006 -289.504299) (xy 296.901127 -289.473174)
			(xy 296.943748 -289.448567) (xy 296.989764 -289.431115) (xy 297.037983 -289.421271) (xy 297.087158 -289.41929)
			(xy 297.136013 -289.425222) (xy 297.183284 -289.438914) (xy 297.227746 -289.460012) (xy 297.268249 -289.487968)
			(xy 297.303742 -289.52206) (xy 297.333307 -289.561404) (xy 297.356178 -289.604981) (xy 297.371762 -289.651662)
			(xy 297.379657 -289.700239) (xy 297.380152 -289.724846) (xy 297.719 -289.724846) (xy 297.72296 -289.675792)
			(xy 297.734737 -289.628008) (xy 297.754028 -289.582732) (xy 297.780331 -289.541136) (xy 297.812966 -289.504299)
			(xy 297.851087 -289.473174) (xy 297.893708 -289.448567) (xy 297.939724 -289.431115) (xy 297.987943 -289.421271)
			(xy 298.037118 -289.41929) (xy 298.085973 -289.425222) (xy 298.133244 -289.438914) (xy 298.177706 -289.460012)
			(xy 298.218209 -289.487968) (xy 298.253702 -289.52206) (xy 298.283267 -289.561404) (xy 298.306138 -289.604981)
			(xy 298.321722 -289.651662) (xy 298.329617 -289.700239) (xy 298.330112 -289.724846) (xy 298.66896 -289.724846)
			(xy 298.67292 -289.675792) (xy 298.684697 -289.628008) (xy 298.703988 -289.582732) (xy 298.730291 -289.541136)
			(xy 298.762926 -289.504299) (xy 298.801047 -289.473174) (xy 298.843668 -289.448567) (xy 298.889684 -289.431115)
			(xy 298.937903 -289.421271) (xy 298.987078 -289.41929) (xy 299.035933 -289.425222) (xy 299.083204 -289.438914)
			(xy 299.127666 -289.460012) (xy 299.168169 -289.487968) (xy 299.203662 -289.52206) (xy 299.233227 -289.561404)
			(xy 299.256098 -289.604981) (xy 299.271682 -289.651662) (xy 299.279577 -289.700239) (xy 299.280072 -289.724846)
			(xy 299.61892 -289.724846) (xy 299.62288 -289.675792) (xy 299.634657 -289.628008) (xy 299.653948 -289.582732)
			(xy 299.680251 -289.541136) (xy 299.712886 -289.504299) (xy 299.751007 -289.473174) (xy 299.793628 -289.448567)
			(xy 299.839644 -289.431115) (xy 299.887863 -289.421271) (xy 299.937038 -289.41929) (xy 299.985893 -289.425222)
			(xy 300.033164 -289.438914) (xy 300.077626 -289.460012) (xy 300.118129 -289.487968) (xy 300.153622 -289.52206)
			(xy 300.183187 -289.561404) (xy 300.206058 -289.604981) (xy 300.221642 -289.651662) (xy 300.229537 -289.700239)
			(xy 300.230032 -289.724846) (xy 300.56888 -289.724846) (xy 300.57284 -289.675792) (xy 300.584617 -289.628008)
			(xy 300.603908 -289.582732) (xy 300.630211 -289.541136) (xy 300.662846 -289.504299) (xy 300.700967 -289.473174)
			(xy 300.743588 -289.448567) (xy 300.789604 -289.431115) (xy 300.837823 -289.421271) (xy 300.886998 -289.41929)
			(xy 300.935853 -289.425222) (xy 300.983124 -289.438914) (xy 301.027586 -289.460012) (xy 301.068089 -289.487968)
			(xy 301.103582 -289.52206) (xy 301.133147 -289.561404) (xy 301.156018 -289.604981) (xy 301.171602 -289.651662)
			(xy 301.179497 -289.700239) (xy 301.179992 -289.724846) (xy 301.519094 -289.724846) (xy 301.523054 -289.675792)
			(xy 301.534831 -289.628008) (xy 301.554122 -289.582732) (xy 301.580425 -289.541136) (xy 301.61306 -289.504299)
			(xy 301.651181 -289.473174) (xy 301.693802 -289.448567) (xy 301.739818 -289.431115) (xy 301.788037 -289.421271)
			(xy 301.837212 -289.41929) (xy 301.886067 -289.425222) (xy 301.933338 -289.438914) (xy 301.9778 -289.460012)
			(xy 302.018303 -289.487968) (xy 302.053796 -289.52206) (xy 302.083361 -289.561404) (xy 302.106232 -289.604981)
			(xy 302.121816 -289.651662) (xy 302.129711 -289.700239) (xy 302.130206 -289.724846) (xy 302.469054 -289.724846)
			(xy 302.473014 -289.675792) (xy 302.484791 -289.628008) (xy 302.504082 -289.582732) (xy 302.530385 -289.541136)
			(xy 302.56302 -289.504299) (xy 302.601141 -289.473174) (xy 302.643762 -289.448567) (xy 302.689778 -289.431115)
			(xy 302.737997 -289.421271) (xy 302.787172 -289.41929) (xy 302.836027 -289.425222) (xy 302.883298 -289.438914)
			(xy 302.92776 -289.460012) (xy 302.968263 -289.487968) (xy 303.003756 -289.52206) (xy 303.033321 -289.561404)
			(xy 303.056192 -289.604981) (xy 303.071776 -289.651662) (xy 303.079671 -289.700239) (xy 303.080166 -289.724846)
			(xy 303.419014 -289.724846) (xy 303.422974 -289.675792) (xy 303.434751 -289.628008) (xy 303.454042 -289.582732)
			(xy 303.480345 -289.541136) (xy 303.51298 -289.504299) (xy 303.551101 -289.473174) (xy 303.593722 -289.448567)
			(xy 303.639738 -289.431115) (xy 303.687957 -289.421271) (xy 303.737132 -289.41929) (xy 303.785987 -289.425222)
			(xy 303.833258 -289.438914) (xy 303.87772 -289.460012) (xy 303.918223 -289.487968) (xy 303.953716 -289.52206)
			(xy 303.983281 -289.561404) (xy 304.006152 -289.604981) (xy 304.021736 -289.651662) (xy 304.029631 -289.700239)
			(xy 304.030126 -289.724846) (xy 304.368974 -289.724846) (xy 304.372934 -289.675792) (xy 304.384711 -289.628008)
			(xy 304.404002 -289.582732) (xy 304.430305 -289.541136) (xy 304.46294 -289.504299) (xy 304.501061 -289.473174)
			(xy 304.543682 -289.448567) (xy 304.589698 -289.431115) (xy 304.637917 -289.421271) (xy 304.687092 -289.41929)
			(xy 304.735947 -289.425222) (xy 304.783218 -289.438914) (xy 304.82768 -289.460012) (xy 304.868183 -289.487968)
			(xy 304.903676 -289.52206) (xy 304.933241 -289.561404) (xy 304.956112 -289.604981) (xy 304.971696 -289.651662)
			(xy 304.979591 -289.700239) (xy 304.980086 -289.724846) (xy 305.318934 -289.724846) (xy 305.322894 -289.675792)
			(xy 305.334671 -289.628008) (xy 305.353962 -289.582732) (xy 305.380265 -289.541136) (xy 305.4129 -289.504299)
			(xy 305.451021 -289.473174) (xy 305.493642 -289.448567) (xy 305.539658 -289.431115) (xy 305.587877 -289.421271)
			(xy 305.637052 -289.41929) (xy 305.685907 -289.425222) (xy 305.733178 -289.438914) (xy 305.77764 -289.460012)
			(xy 305.818143 -289.487968) (xy 305.853636 -289.52206) (xy 305.883201 -289.561404) (xy 305.906072 -289.604981)
			(xy 305.921656 -289.651662) (xy 305.929551 -289.700239) (xy 305.930046 -289.724846) (xy 306.269148 -289.724846)
			(xy 306.273108 -289.675792) (xy 306.284885 -289.628008) (xy 306.304176 -289.582732) (xy 306.330479 -289.541136)
			(xy 306.363114 -289.504299) (xy 306.401235 -289.473174) (xy 306.443856 -289.448567) (xy 306.489872 -289.431115)
			(xy 306.538091 -289.421271) (xy 306.587266 -289.41929) (xy 306.636121 -289.425222) (xy 306.683392 -289.438914)
			(xy 306.727854 -289.460012) (xy 306.768357 -289.487968) (xy 306.80385 -289.52206) (xy 306.833415 -289.561404)
			(xy 306.856286 -289.604981) (xy 306.87187 -289.651662) (xy 306.879765 -289.700239) (xy 306.88026 -289.724846)
			(xy 308.169068 -289.724846) (xy 308.173028 -289.675792) (xy 308.184805 -289.628008) (xy 308.204096 -289.582732)
			(xy 308.230399 -289.541136) (xy 308.263034 -289.504299) (xy 308.301155 -289.473174) (xy 308.343776 -289.448567)
			(xy 308.389792 -289.431115) (xy 308.438011 -289.421271) (xy 308.487186 -289.41929) (xy 308.536041 -289.425222)
			(xy 308.583312 -289.438914) (xy 308.627774 -289.460012) (xy 308.668277 -289.487968) (xy 308.70377 -289.52206)
			(xy 308.733335 -289.561404) (xy 308.756206 -289.604981) (xy 308.77179 -289.651662) (xy 308.779685 -289.700239)
			(xy 308.78018 -289.724846) (xy 309.119028 -289.724846) (xy 309.122988 -289.675792) (xy 309.134765 -289.628008)
			(xy 309.154056 -289.582732) (xy 309.180359 -289.541136) (xy 309.212994 -289.504299) (xy 309.251115 -289.473174)
			(xy 309.293736 -289.448567) (xy 309.339752 -289.431115) (xy 309.387971 -289.421271) (xy 309.437146 -289.41929)
			(xy 309.486001 -289.425222) (xy 309.533272 -289.438914) (xy 309.577734 -289.460012) (xy 309.618237 -289.487968)
			(xy 309.65373 -289.52206) (xy 309.683295 -289.561404) (xy 309.706166 -289.604981) (xy 309.72175 -289.651662)
			(xy 309.729645 -289.700239) (xy 309.73014 -289.724846) (xy 310.068988 -289.724846) (xy 310.072948 -289.675792)
			(xy 310.084725 -289.628008) (xy 310.104016 -289.582732) (xy 310.130319 -289.541136) (xy 310.162954 -289.504299)
			(xy 310.201075 -289.473174) (xy 310.243696 -289.448567) (xy 310.289712 -289.431115) (xy 310.337931 -289.421271)
			(xy 310.387106 -289.41929) (xy 310.435961 -289.425222) (xy 310.483232 -289.438914) (xy 310.527694 -289.460012)
			(xy 310.568197 -289.487968) (xy 310.60369 -289.52206) (xy 310.633255 -289.561404) (xy 310.656126 -289.604981)
			(xy 310.67171 -289.651662) (xy 310.679605 -289.700239) (xy 310.6801 -289.724846) (xy 311.018948 -289.724846)
			(xy 311.022908 -289.675792) (xy 311.034685 -289.628008) (xy 311.053976 -289.582732) (xy 311.080279 -289.541136)
			(xy 311.112914 -289.504299) (xy 311.151035 -289.473174) (xy 311.193656 -289.448567) (xy 311.239672 -289.431115)
			(xy 311.287891 -289.421271) (xy 311.337066 -289.41929) (xy 311.385921 -289.425222) (xy 311.433192 -289.438914)
			(xy 311.477654 -289.460012) (xy 311.518157 -289.487968) (xy 311.55365 -289.52206) (xy 311.583215 -289.561404)
			(xy 311.606086 -289.604981) (xy 311.62167 -289.651662) (xy 311.629565 -289.700239) (xy 311.63006 -289.724846)
			(xy 311.968908 -289.724846) (xy 311.972868 -289.675792) (xy 311.984645 -289.628008) (xy 312.003936 -289.582732)
			(xy 312.030239 -289.541136) (xy 312.062874 -289.504299) (xy 312.100995 -289.473174) (xy 312.143616 -289.448567)
			(xy 312.189632 -289.431115) (xy 312.237851 -289.421271) (xy 312.287026 -289.41929) (xy 312.335881 -289.425222)
			(xy 312.383152 -289.438914) (xy 312.427614 -289.460012) (xy 312.468117 -289.487968) (xy 312.50361 -289.52206)
			(xy 312.533175 -289.561404) (xy 312.556046 -289.604981) (xy 312.57163 -289.651662) (xy 312.579525 -289.700239)
			(xy 312.58002 -289.724846) (xy 312.919122 -289.724846) (xy 312.923082 -289.675792) (xy 312.934859 -289.628008)
			(xy 312.95415 -289.582732) (xy 312.980453 -289.541136) (xy 313.013088 -289.504299) (xy 313.051209 -289.473174)
			(xy 313.09383 -289.448567) (xy 313.139846 -289.431115) (xy 313.188065 -289.421271) (xy 313.23724 -289.41929)
			(xy 313.286095 -289.425222) (xy 313.333366 -289.438914) (xy 313.377828 -289.460012) (xy 313.418331 -289.487968)
			(xy 313.453824 -289.52206) (xy 313.483389 -289.561404) (xy 313.50626 -289.604981) (xy 313.521844 -289.651662)
			(xy 313.529739 -289.700239) (xy 313.530234 -289.724846) (xy 313.869082 -289.724846) (xy 313.873042 -289.675792)
			(xy 313.884819 -289.628008) (xy 313.90411 -289.582732) (xy 313.930413 -289.541136) (xy 313.963048 -289.504299)
			(xy 314.001169 -289.473174) (xy 314.04379 -289.448567) (xy 314.089806 -289.431115) (xy 314.138025 -289.421271)
			(xy 314.1872 -289.41929) (xy 314.236055 -289.425222) (xy 314.283326 -289.438914) (xy 314.327788 -289.460012)
			(xy 314.368291 -289.487968) (xy 314.403784 -289.52206) (xy 314.433349 -289.561404) (xy 314.45622 -289.604981)
			(xy 314.471804 -289.651662) (xy 314.479699 -289.700239) (xy 314.480194 -289.724846) (xy 314.819042 -289.724846)
			(xy 314.823002 -289.675792) (xy 314.834779 -289.628008) (xy 314.85407 -289.582732) (xy 314.880373 -289.541136)
			(xy 314.913008 -289.504299) (xy 314.951129 -289.473174) (xy 314.99375 -289.448567) (xy 315.039766 -289.431115)
			(xy 315.087985 -289.421271) (xy 315.13716 -289.41929) (xy 315.186015 -289.425222) (xy 315.233286 -289.438914)
			(xy 315.277748 -289.460012) (xy 315.318251 -289.487968) (xy 315.353744 -289.52206) (xy 315.383309 -289.561404)
			(xy 315.40618 -289.604981) (xy 315.421764 -289.651662) (xy 315.429659 -289.700239) (xy 315.430154 -289.724846)
			(xy 315.429659 -289.749453) (xy 315.421764 -289.79803) (xy 315.40618 -289.844711) (xy 315.383309 -289.888288)
			(xy 315.353744 -289.927632) (xy 315.318251 -289.961724) (xy 315.277748 -289.98968) (xy 315.233286 -290.010778)
			(xy 315.186015 -290.02447) (xy 315.13716 -290.030402) (xy 315.087985 -290.028421) (xy 315.039766 -290.018577)
			(xy 314.99375 -290.001125) (xy 314.951129 -289.976518) (xy 314.913008 -289.945393) (xy 314.880373 -289.908556)
			(xy 314.85407 -289.86696) (xy 314.834779 -289.821684) (xy 314.823002 -289.7739) (xy 314.819042 -289.724846)
			(xy 314.480194 -289.724846) (xy 314.479699 -289.749453) (xy 314.471804 -289.79803) (xy 314.45622 -289.844711)
			(xy 314.433349 -289.888288) (xy 314.403784 -289.927632) (xy 314.368291 -289.961724) (xy 314.327788 -289.98968)
			(xy 314.283326 -290.010778) (xy 314.236055 -290.02447) (xy 314.1872 -290.030402) (xy 314.138025 -290.028421)
			(xy 314.089806 -290.018577) (xy 314.04379 -290.001125) (xy 314.001169 -289.976518) (xy 313.963048 -289.945393)
			(xy 313.930413 -289.908556) (xy 313.90411 -289.86696) (xy 313.884819 -289.821684) (xy 313.873042 -289.7739)
			(xy 313.869082 -289.724846) (xy 313.530234 -289.724846) (xy 313.529739 -289.749453) (xy 313.521844 -289.79803)
			(xy 313.50626 -289.844711) (xy 313.483389 -289.888288) (xy 313.453824 -289.927632) (xy 313.418331 -289.961724)
			(xy 313.377828 -289.98968) (xy 313.333366 -290.010778) (xy 313.286095 -290.02447) (xy 313.23724 -290.030402)
			(xy 313.188065 -290.028421) (xy 313.139846 -290.018577) (xy 313.09383 -290.001125) (xy 313.051209 -289.976518)
			(xy 313.013088 -289.945393) (xy 312.980453 -289.908556) (xy 312.95415 -289.86696) (xy 312.934859 -289.821684)
			(xy 312.923082 -289.7739) (xy 312.919122 -289.724846) (xy 312.58002 -289.724846) (xy 312.579525 -289.749453)
			(xy 312.57163 -289.79803) (xy 312.556046 -289.844711) (xy 312.533175 -289.888288) (xy 312.50361 -289.927632)
			(xy 312.468117 -289.961724) (xy 312.427614 -289.98968) (xy 312.383152 -290.010778) (xy 312.335881 -290.02447)
			(xy 312.287026 -290.030402) (xy 312.237851 -290.028421) (xy 312.189632 -290.018577) (xy 312.143616 -290.001125)
			(xy 312.100995 -289.976518) (xy 312.062874 -289.945393) (xy 312.030239 -289.908556) (xy 312.003936 -289.86696)
			(xy 311.984645 -289.821684) (xy 311.972868 -289.7739) (xy 311.968908 -289.724846) (xy 311.63006 -289.724846)
			(xy 311.629565 -289.749453) (xy 311.62167 -289.79803) (xy 311.606086 -289.844711) (xy 311.583215 -289.888288)
			(xy 311.55365 -289.927632) (xy 311.518157 -289.961724) (xy 311.477654 -289.98968) (xy 311.433192 -290.010778)
			(xy 311.385921 -290.02447) (xy 311.337066 -290.030402) (xy 311.287891 -290.028421) (xy 311.239672 -290.018577)
			(xy 311.193656 -290.001125) (xy 311.151035 -289.976518) (xy 311.112914 -289.945393) (xy 311.080279 -289.908556)
			(xy 311.053976 -289.86696) (xy 311.034685 -289.821684) (xy 311.022908 -289.7739) (xy 311.018948 -289.724846)
			(xy 310.6801 -289.724846) (xy 310.679605 -289.749453) (xy 310.67171 -289.79803) (xy 310.656126 -289.844711)
			(xy 310.633255 -289.888288) (xy 310.60369 -289.927632) (xy 310.568197 -289.961724) (xy 310.527694 -289.98968)
			(xy 310.483232 -290.010778) (xy 310.435961 -290.02447) (xy 310.387106 -290.030402) (xy 310.337931 -290.028421)
			(xy 310.289712 -290.018577) (xy 310.243696 -290.001125) (xy 310.201075 -289.976518) (xy 310.162954 -289.945393)
			(xy 310.130319 -289.908556) (xy 310.104016 -289.86696) (xy 310.084725 -289.821684) (xy 310.072948 -289.7739)
			(xy 310.068988 -289.724846) (xy 309.73014 -289.724846) (xy 309.729645 -289.749453) (xy 309.72175 -289.79803)
			(xy 309.706166 -289.844711) (xy 309.683295 -289.888288) (xy 309.65373 -289.927632) (xy 309.618237 -289.961724)
			(xy 309.577734 -289.98968) (xy 309.533272 -290.010778) (xy 309.486001 -290.02447) (xy 309.437146 -290.030402)
			(xy 309.387971 -290.028421) (xy 309.339752 -290.018577) (xy 309.293736 -290.001125) (xy 309.251115 -289.976518)
			(xy 309.212994 -289.945393) (xy 309.180359 -289.908556) (xy 309.154056 -289.86696) (xy 309.134765 -289.821684)
			(xy 309.122988 -289.7739) (xy 309.119028 -289.724846) (xy 308.78018 -289.724846) (xy 308.779685 -289.749453)
			(xy 308.77179 -289.79803) (xy 308.756206 -289.844711) (xy 308.733335 -289.888288) (xy 308.70377 -289.927632)
			(xy 308.668277 -289.961724) (xy 308.627774 -289.98968) (xy 308.583312 -290.010778) (xy 308.536041 -290.02447)
			(xy 308.487186 -290.030402) (xy 308.438011 -290.028421) (xy 308.389792 -290.018577) (xy 308.343776 -290.001125)
			(xy 308.301155 -289.976518) (xy 308.263034 -289.945393) (xy 308.230399 -289.908556) (xy 308.204096 -289.86696)
			(xy 308.184805 -289.821684) (xy 308.173028 -289.7739) (xy 308.169068 -289.724846) (xy 306.88026 -289.724846)
			(xy 306.879765 -289.749453) (xy 306.87187 -289.79803) (xy 306.856286 -289.844711) (xy 306.833415 -289.888288)
			(xy 306.80385 -289.927632) (xy 306.768357 -289.961724) (xy 306.727854 -289.98968) (xy 306.683392 -290.010778)
			(xy 306.636121 -290.02447) (xy 306.587266 -290.030402) (xy 306.538091 -290.028421) (xy 306.489872 -290.018577)
			(xy 306.443856 -290.001125) (xy 306.401235 -289.976518) (xy 306.363114 -289.945393) (xy 306.330479 -289.908556)
			(xy 306.304176 -289.86696) (xy 306.284885 -289.821684) (xy 306.273108 -289.7739) (xy 306.269148 -289.724846)
			(xy 305.930046 -289.724846) (xy 305.929551 -289.749453) (xy 305.921656 -289.79803) (xy 305.906072 -289.844711)
			(xy 305.883201 -289.888288) (xy 305.853636 -289.927632) (xy 305.818143 -289.961724) (xy 305.77764 -289.98968)
			(xy 305.733178 -290.010778) (xy 305.685907 -290.02447) (xy 305.637052 -290.030402) (xy 305.587877 -290.028421)
			(xy 305.539658 -290.018577) (xy 305.493642 -290.001125) (xy 305.451021 -289.976518) (xy 305.4129 -289.945393)
			(xy 305.380265 -289.908556) (xy 305.353962 -289.86696) (xy 305.334671 -289.821684) (xy 305.322894 -289.7739)
			(xy 305.318934 -289.724846) (xy 304.980086 -289.724846) (xy 304.979591 -289.749453) (xy 304.971696 -289.79803)
			(xy 304.956112 -289.844711) (xy 304.933241 -289.888288) (xy 304.903676 -289.927632) (xy 304.868183 -289.961724)
			(xy 304.82768 -289.98968) (xy 304.783218 -290.010778) (xy 304.735947 -290.02447) (xy 304.687092 -290.030402)
			(xy 304.637917 -290.028421) (xy 304.589698 -290.018577) (xy 304.543682 -290.001125) (xy 304.501061 -289.976518)
			(xy 304.46294 -289.945393) (xy 304.430305 -289.908556) (xy 304.404002 -289.86696) (xy 304.384711 -289.821684)
			(xy 304.372934 -289.7739) (xy 304.368974 -289.724846) (xy 304.030126 -289.724846) (xy 304.029631 -289.749453)
			(xy 304.021736 -289.79803) (xy 304.006152 -289.844711) (xy 303.983281 -289.888288) (xy 303.953716 -289.927632)
			(xy 303.918223 -289.961724) (xy 303.87772 -289.98968) (xy 303.833258 -290.010778) (xy 303.785987 -290.02447)
			(xy 303.737132 -290.030402) (xy 303.687957 -290.028421) (xy 303.639738 -290.018577) (xy 303.593722 -290.001125)
			(xy 303.551101 -289.976518) (xy 303.51298 -289.945393) (xy 303.480345 -289.908556) (xy 303.454042 -289.86696)
			(xy 303.434751 -289.821684) (xy 303.422974 -289.7739) (xy 303.419014 -289.724846) (xy 303.080166 -289.724846)
			(xy 303.079671 -289.749453) (xy 303.071776 -289.79803) (xy 303.056192 -289.844711) (xy 303.033321 -289.888288)
			(xy 303.003756 -289.927632) (xy 302.968263 -289.961724) (xy 302.92776 -289.98968) (xy 302.883298 -290.010778)
			(xy 302.836027 -290.02447) (xy 302.787172 -290.030402) (xy 302.737997 -290.028421) (xy 302.689778 -290.018577)
			(xy 302.643762 -290.001125) (xy 302.601141 -289.976518) (xy 302.56302 -289.945393) (xy 302.530385 -289.908556)
			(xy 302.504082 -289.86696) (xy 302.484791 -289.821684) (xy 302.473014 -289.7739) (xy 302.469054 -289.724846)
			(xy 302.130206 -289.724846) (xy 302.129711 -289.749453) (xy 302.121816 -289.79803) (xy 302.106232 -289.844711)
			(xy 302.083361 -289.888288) (xy 302.053796 -289.927632) (xy 302.018303 -289.961724) (xy 301.9778 -289.98968)
			(xy 301.933338 -290.010778) (xy 301.886067 -290.02447) (xy 301.837212 -290.030402) (xy 301.788037 -290.028421)
			(xy 301.739818 -290.018577) (xy 301.693802 -290.001125) (xy 301.651181 -289.976518) (xy 301.61306 -289.945393)
			(xy 301.580425 -289.908556) (xy 301.554122 -289.86696) (xy 301.534831 -289.821684) (xy 301.523054 -289.7739)
			(xy 301.519094 -289.724846) (xy 301.179992 -289.724846) (xy 301.179497 -289.749453) (xy 301.171602 -289.79803)
			(xy 301.156018 -289.844711) (xy 301.133147 -289.888288) (xy 301.103582 -289.927632) (xy 301.068089 -289.961724)
			(xy 301.027586 -289.98968) (xy 300.983124 -290.010778) (xy 300.935853 -290.02447) (xy 300.886998 -290.030402)
			(xy 300.837823 -290.028421) (xy 300.789604 -290.018577) (xy 300.743588 -290.001125) (xy 300.700967 -289.976518)
			(xy 300.662846 -289.945393) (xy 300.630211 -289.908556) (xy 300.603908 -289.86696) (xy 300.584617 -289.821684)
			(xy 300.57284 -289.7739) (xy 300.56888 -289.724846) (xy 300.230032 -289.724846) (xy 300.229537 -289.749453)
			(xy 300.221642 -289.79803) (xy 300.206058 -289.844711) (xy 300.183187 -289.888288) (xy 300.153622 -289.927632)
			(xy 300.118129 -289.961724) (xy 300.077626 -289.98968) (xy 300.033164 -290.010778) (xy 299.985893 -290.02447)
			(xy 299.937038 -290.030402) (xy 299.887863 -290.028421) (xy 299.839644 -290.018577) (xy 299.793628 -290.001125)
			(xy 299.751007 -289.976518) (xy 299.712886 -289.945393) (xy 299.680251 -289.908556) (xy 299.653948 -289.86696)
			(xy 299.634657 -289.821684) (xy 299.62288 -289.7739) (xy 299.61892 -289.724846) (xy 299.280072 -289.724846)
			(xy 299.279577 -289.749453) (xy 299.271682 -289.79803) (xy 299.256098 -289.844711) (xy 299.233227 -289.888288)
			(xy 299.203662 -289.927632) (xy 299.168169 -289.961724) (xy 299.127666 -289.98968) (xy 299.083204 -290.010778)
			(xy 299.035933 -290.02447) (xy 298.987078 -290.030402) (xy 298.937903 -290.028421) (xy 298.889684 -290.018577)
			(xy 298.843668 -290.001125) (xy 298.801047 -289.976518) (xy 298.762926 -289.945393) (xy 298.730291 -289.908556)
			(xy 298.703988 -289.86696) (xy 298.684697 -289.821684) (xy 298.67292 -289.7739) (xy 298.66896 -289.724846)
			(xy 298.330112 -289.724846) (xy 298.329617 -289.749453) (xy 298.321722 -289.79803) (xy 298.306138 -289.844711)
			(xy 298.283267 -289.888288) (xy 298.253702 -289.927632) (xy 298.218209 -289.961724) (xy 298.177706 -289.98968)
			(xy 298.133244 -290.010778) (xy 298.085973 -290.02447) (xy 298.037118 -290.030402) (xy 297.987943 -290.028421)
			(xy 297.939724 -290.018577) (xy 297.893708 -290.001125) (xy 297.851087 -289.976518) (xy 297.812966 -289.945393)
			(xy 297.780331 -289.908556) (xy 297.754028 -289.86696) (xy 297.734737 -289.821684) (xy 297.72296 -289.7739)
			(xy 297.719 -289.724846) (xy 297.380152 -289.724846) (xy 297.379657 -289.749453) (xy 297.371762 -289.79803)
			(xy 297.356178 -289.844711) (xy 297.333307 -289.888288) (xy 297.303742 -289.927632) (xy 297.268249 -289.961724)
			(xy 297.227746 -289.98968) (xy 297.183284 -290.010778) (xy 297.136013 -290.02447) (xy 297.087158 -290.030402)
			(xy 297.037983 -290.028421) (xy 296.989764 -290.018577) (xy 296.943748 -290.001125) (xy 296.901127 -289.976518)
			(xy 296.863006 -289.945393) (xy 296.830371 -289.908556) (xy 296.804068 -289.86696) (xy 296.784777 -289.821684)
			(xy 296.773 -289.7739) (xy 296.76904 -289.724846) (xy 296.430192 -289.724846) (xy 296.429697 -289.749453)
			(xy 296.421802 -289.79803) (xy 296.406218 -289.844711) (xy 296.383347 -289.888288) (xy 296.353782 -289.927632)
			(xy 296.318289 -289.961724) (xy 296.277786 -289.98968) (xy 296.233324 -290.010778) (xy 296.186053 -290.02447)
			(xy 296.137198 -290.030402) (xy 296.088023 -290.028421) (xy 296.039804 -290.018577) (xy 295.993788 -290.001125)
			(xy 295.951167 -289.976518) (xy 295.913046 -289.945393) (xy 295.880411 -289.908556) (xy 295.854108 -289.86696)
			(xy 295.834817 -289.821684) (xy 295.82304 -289.7739) (xy 295.81908 -289.724846) (xy 295.480232 -289.724846)
			(xy 295.479737 -289.749453) (xy 295.471842 -289.79803) (xy 295.456258 -289.844711) (xy 295.433387 -289.888288)
			(xy 295.403822 -289.927632) (xy 295.368329 -289.961724) (xy 295.327826 -289.98968) (xy 295.283364 -290.010778)
			(xy 295.236093 -290.02447) (xy 295.187238 -290.030402) (xy 295.138063 -290.028421) (xy 295.089844 -290.018577)
			(xy 295.043828 -290.001125) (xy 295.001207 -289.976518) (xy 294.963086 -289.945393) (xy 294.930451 -289.908556)
			(xy 294.904148 -289.86696) (xy 294.884857 -289.821684) (xy 294.87308 -289.7739) (xy 294.86912 -289.724846)
			(xy 294.530018 -289.724846) (xy 294.529523 -289.749453) (xy 294.521628 -289.79803) (xy 294.506044 -289.844711)
			(xy 294.483173 -289.888288) (xy 294.453608 -289.927632) (xy 294.418115 -289.961724) (xy 294.377612 -289.98968)
			(xy 294.33315 -290.010778) (xy 294.285879 -290.02447) (xy 294.237024 -290.030402) (xy 294.187849 -290.028421)
			(xy 294.13963 -290.018577) (xy 294.093614 -290.001125) (xy 294.050993 -289.976518) (xy 294.012872 -289.945393)
			(xy 293.980237 -289.908556) (xy 293.953934 -289.86696) (xy 293.934643 -289.821684) (xy 293.922866 -289.7739)
			(xy 293.918906 -289.724846) (xy 293.580058 -289.724846) (xy 293.579563 -289.749453) (xy 293.571668 -289.79803)
			(xy 293.556084 -289.844711) (xy 293.533213 -289.888288) (xy 293.503648 -289.927632) (xy 293.468155 -289.961724)
			(xy 293.427652 -289.98968) (xy 293.38319 -290.010778) (xy 293.335919 -290.02447) (xy 293.287064 -290.030402)
			(xy 293.237889 -290.028421) (xy 293.18967 -290.018577) (xy 293.143654 -290.001125) (xy 293.101033 -289.976518)
			(xy 293.062912 -289.945393) (xy 293.030277 -289.908556) (xy 293.003974 -289.86696) (xy 292.984683 -289.821684)
			(xy 292.972906 -289.7739) (xy 292.968946 -289.724846) (xy 292.630098 -289.724846) (xy 292.629603 -289.749453)
			(xy 292.621708 -289.79803) (xy 292.606124 -289.844711) (xy 292.583253 -289.888288) (xy 292.553688 -289.927632)
			(xy 292.518195 -289.961724) (xy 292.477692 -289.98968) (xy 292.43323 -290.010778) (xy 292.385959 -290.02447)
			(xy 292.337104 -290.030402) (xy 292.287929 -290.028421) (xy 292.23971 -290.018577) (xy 292.193694 -290.001125)
			(xy 292.151073 -289.976518) (xy 292.112952 -289.945393) (xy 292.080317 -289.908556) (xy 292.054014 -289.86696)
			(xy 292.034723 -289.821684) (xy 292.022946 -289.7739) (xy 292.018986 -289.724846) (xy 290.730178 -289.724846)
			(xy 290.729683 -289.749453) (xy 290.721788 -289.79803) (xy 290.706204 -289.844711) (xy 290.683333 -289.888288)
			(xy 290.653768 -289.927632) (xy 290.618275 -289.961724) (xy 290.577772 -289.98968) (xy 290.53331 -290.010778)
			(xy 290.486039 -290.02447) (xy 290.437184 -290.030402) (xy 290.388009 -290.028421) (xy 290.33979 -290.018577)
			(xy 290.293774 -290.001125) (xy 290.251153 -289.976518) (xy 290.213032 -289.945393) (xy 290.180397 -289.908556)
			(xy 290.154094 -289.86696) (xy 290.134803 -289.821684) (xy 290.123026 -289.7739) (xy 290.119066 -289.724846)
			(xy 289.780218 -289.724846) (xy 289.779723 -289.749453) (xy 289.771828 -289.79803) (xy 289.756244 -289.844711)
			(xy 289.733373 -289.888288) (xy 289.703808 -289.927632) (xy 289.668315 -289.961724) (xy 289.627812 -289.98968)
			(xy 289.58335 -290.010778) (xy 289.536079 -290.02447) (xy 289.487224 -290.030402) (xy 289.438049 -290.028421)
			(xy 289.38983 -290.018577) (xy 289.343814 -290.001125) (xy 289.301193 -289.976518) (xy 289.263072 -289.945393)
			(xy 289.230437 -289.908556) (xy 289.204134 -289.86696) (xy 289.184843 -289.821684) (xy 289.173066 -289.7739)
			(xy 289.169106 -289.724846) (xy 288.830004 -289.724846) (xy 288.829509 -289.749453) (xy 288.821614 -289.79803)
			(xy 288.80603 -289.844711) (xy 288.783159 -289.888288) (xy 288.753594 -289.927632) (xy 288.718101 -289.961724)
			(xy 288.677598 -289.98968) (xy 288.633136 -290.010778) (xy 288.585865 -290.02447) (xy 288.53701 -290.030402)
			(xy 288.487835 -290.028421) (xy 288.439616 -290.018577) (xy 288.3936 -290.001125) (xy 288.350979 -289.976518)
			(xy 288.312858 -289.945393) (xy 288.280223 -289.908556) (xy 288.25392 -289.86696) (xy 288.234629 -289.821684)
			(xy 288.222852 -289.7739) (xy 288.218892 -289.724846) (xy 287.880044 -289.724846) (xy 287.879549 -289.749453)
			(xy 287.871654 -289.79803) (xy 287.85607 -289.844711) (xy 287.833199 -289.888288) (xy 287.803634 -289.927632)
			(xy 287.768141 -289.961724) (xy 287.727638 -289.98968) (xy 287.683176 -290.010778) (xy 287.635905 -290.02447)
			(xy 287.58705 -290.030402) (xy 287.537875 -290.028421) (xy 287.489656 -290.018577) (xy 287.44364 -290.001125)
			(xy 287.401019 -289.976518) (xy 287.362898 -289.945393) (xy 287.330263 -289.908556) (xy 287.30396 -289.86696)
			(xy 287.284669 -289.821684) (xy 287.272892 -289.7739) (xy 287.268932 -289.724846) (xy 286.930084 -289.724846)
			(xy 286.929589 -289.749453) (xy 286.921694 -289.79803) (xy 286.90611 -289.844711) (xy 286.883239 -289.888288)
			(xy 286.853674 -289.927632) (xy 286.818181 -289.961724) (xy 286.777678 -289.98968) (xy 286.733216 -290.010778)
			(xy 286.685945 -290.02447) (xy 286.63709 -290.030402) (xy 286.587915 -290.028421) (xy 286.539696 -290.018577)
			(xy 286.49368 -290.001125) (xy 286.451059 -289.976518) (xy 286.412938 -289.945393) (xy 286.380303 -289.908556)
			(xy 286.354 -289.86696) (xy 286.334709 -289.821684) (xy 286.322932 -289.7739) (xy 286.318972 -289.724846)
			(xy 285.980124 -289.724846) (xy 285.979629 -289.749453) (xy 285.971734 -289.79803) (xy 285.95615 -289.844711)
			(xy 285.933279 -289.888288) (xy 285.903714 -289.927632) (xy 285.868221 -289.961724) (xy 285.827718 -289.98968)
			(xy 285.783256 -290.010778) (xy 285.735985 -290.02447) (xy 285.68713 -290.030402) (xy 285.637955 -290.028421)
			(xy 285.589736 -290.018577) (xy 285.54372 -290.001125) (xy 285.501099 -289.976518) (xy 285.462978 -289.945393)
			(xy 285.430343 -289.908556) (xy 285.40404 -289.86696) (xy 285.384749 -289.821684) (xy 285.372972 -289.7739)
			(xy 285.369012 -289.724846) (xy 285.030164 -289.724846) (xy 285.029669 -289.749453) (xy 285.021774 -289.79803)
			(xy 285.00619 -289.844711) (xy 284.983319 -289.888288) (xy 284.953754 -289.927632) (xy 284.918261 -289.961724)
			(xy 284.877758 -289.98968) (xy 284.833296 -290.010778) (xy 284.786025 -290.02447) (xy 284.73717 -290.030402)
			(xy 284.687995 -290.028421) (xy 284.639776 -290.018577) (xy 284.59376 -290.001125) (xy 284.551139 -289.976518)
			(xy 284.513018 -289.945393) (xy 284.480383 -289.908556) (xy 284.45408 -289.86696) (xy 284.434789 -289.821684)
			(xy 284.423012 -289.7739) (xy 284.419052 -289.724846) (xy 284.080204 -289.724846) (xy 284.079709 -289.749453)
			(xy 284.071814 -289.79803) (xy 284.05623 -289.844711) (xy 284.033359 -289.888288) (xy 284.003794 -289.927632)
			(xy 283.968301 -289.961724) (xy 283.927798 -289.98968) (xy 283.883336 -290.010778) (xy 283.836065 -290.02447)
			(xy 283.78721 -290.030402) (xy 283.738035 -290.028421) (xy 283.689816 -290.018577) (xy 283.6438 -290.001125)
			(xy 283.601179 -289.976518) (xy 283.563058 -289.945393) (xy 283.530423 -289.908556) (xy 283.50412 -289.86696)
			(xy 283.484829 -289.821684) (xy 283.473052 -289.7739) (xy 283.469092 -289.724846) (xy 283.130244 -289.724846)
			(xy 283.129749 -289.749453) (xy 283.121854 -289.79803) (xy 283.10627 -289.844711) (xy 283.083399 -289.888288)
			(xy 283.053834 -289.927632) (xy 283.018341 -289.961724) (xy 282.977838 -289.98968) (xy 282.933376 -290.010778)
			(xy 282.886105 -290.02447) (xy 282.83725 -290.030402) (xy 282.788075 -290.028421) (xy 282.739856 -290.018577)
			(xy 282.69384 -290.001125) (xy 282.651219 -289.976518) (xy 282.613098 -289.945393) (xy 282.580463 -289.908556)
			(xy 282.55416 -289.86696) (xy 282.534869 -289.821684) (xy 282.523092 -289.7739) (xy 282.519132 -289.724846)
			(xy 282.18003 -289.724846) (xy 282.179535 -289.749453) (xy 282.17164 -289.79803) (xy 282.156056 -289.844711)
			(xy 282.133185 -289.888288) (xy 282.10362 -289.927632) (xy 282.068127 -289.961724) (xy 282.027624 -289.98968)
			(xy 281.983162 -290.010778) (xy 281.935891 -290.02447) (xy 281.887036 -290.030402) (xy 281.837861 -290.028421)
			(xy 281.789642 -290.018577) (xy 281.743626 -290.001125) (xy 281.701005 -289.976518) (xy 281.662884 -289.945393)
			(xy 281.630249 -289.908556) (xy 281.603946 -289.86696) (xy 281.584655 -289.821684) (xy 281.572878 -289.7739)
			(xy 281.568918 -289.724846) (xy 281.23007 -289.724846) (xy 281.229575 -289.749453) (xy 281.22168 -289.79803)
			(xy 281.206096 -289.844711) (xy 281.183225 -289.888288) (xy 281.15366 -289.927632) (xy 281.118167 -289.961724)
			(xy 281.077664 -289.98968) (xy 281.033202 -290.010778) (xy 280.985931 -290.02447) (xy 280.937076 -290.030402)
			(xy 280.887901 -290.028421) (xy 280.839682 -290.018577) (xy 280.793666 -290.001125) (xy 280.751045 -289.976518)
			(xy 280.712924 -289.945393) (xy 280.680289 -289.908556) (xy 280.653986 -289.86696) (xy 280.634695 -289.821684)
			(xy 280.622918 -289.7739) (xy 280.618958 -289.724846) (xy 280.28011 -289.724846) (xy 280.279615 -289.749453)
			(xy 280.27172 -289.79803) (xy 280.256136 -289.844711) (xy 280.233265 -289.888288) (xy 280.2037 -289.927632)
			(xy 280.168207 -289.961724) (xy 280.127704 -289.98968) (xy 280.083242 -290.010778) (xy 280.035971 -290.02447)
			(xy 279.987116 -290.030402) (xy 279.937941 -290.028421) (xy 279.889722 -290.018577) (xy 279.843706 -290.001125)
			(xy 279.801085 -289.976518) (xy 279.762964 -289.945393) (xy 279.730329 -289.908556) (xy 279.704026 -289.86696)
			(xy 279.684735 -289.821684) (xy 279.672958 -289.7739) (xy 279.668998 -289.724846) (xy 279.41397 -289.724846)
			(xy 279.41397 -290.278312) (xy 317.353694 -290.278312) (xy 317.357765 -290.22269) (xy 317.369891 -290.168253)
			(xy 317.389814 -290.116162) (xy 317.41711 -290.067527) (xy 317.451196 -290.023384) (xy 317.491345 -289.984675)
			(xy 317.536703 -289.952224) (xy 317.586303 -289.926723) (xy 317.639087 -289.908716) (xy 317.69393 -289.898586)
			(xy 317.749664 -289.896549) (xy 317.805101 -289.902649) (xy 317.859058 -289.916755) (xy 317.910387 -289.938567)
			(xy 317.957993 -289.967621) (xy 318.000861 -290.003296) (xy 318.038078 -290.044833) (xy 318.068851 -290.091346)
			(xy 318.092523 -290.141843) (xy 318.108591 -290.19525) (xy 318.114759 -290.237164) (xy 321.364354 -290.237164)
			(xy 321.368425 -290.181542) (xy 321.380551 -290.127105) (xy 321.400474 -290.075014) (xy 321.42777 -290.026379)
			(xy 321.461856 -289.982236) (xy 321.502005 -289.943527) (xy 321.547363 -289.911076) (xy 321.596963 -289.885575)
			(xy 321.649747 -289.867568) (xy 321.70459 -289.857438) (xy 321.760324 -289.855401) (xy 321.815761 -289.861501)
			(xy 321.869718 -289.875607) (xy 321.921047 -289.897419) (xy 321.968653 -289.926473) (xy 322.011521 -289.962148)
			(xy 322.048738 -290.003685) (xy 322.079511 -290.050198) (xy 322.103183 -290.100695) (xy 322.119251 -290.154102)
			(xy 322.127371 -290.209278) (xy 322.12788 -290.237164) (xy 322.127371 -290.26505) (xy 322.119251 -290.320226)
			(xy 322.103183 -290.373633) (xy 322.079511 -290.42413) (xy 322.048738 -290.470643) (xy 322.011521 -290.51218)
			(xy 321.968653 -290.547855) (xy 321.921047 -290.576909) (xy 321.869718 -290.598721) (xy 321.815761 -290.612827)
			(xy 321.760324 -290.618927) (xy 321.70459 -290.61689) (xy 321.649747 -290.60676) (xy 321.596963 -290.588753)
			(xy 321.547363 -290.563252) (xy 321.502005 -290.530801) (xy 321.461856 -290.492092) (xy 321.42777 -290.447949)
			(xy 321.400474 -290.399314) (xy 321.380551 -290.347223) (xy 321.368425 -290.292786) (xy 321.364354 -290.237164)
			(xy 318.114759 -290.237164) (xy 318.116711 -290.250426) (xy 318.11722 -290.278312) (xy 318.116711 -290.306198)
			(xy 318.108591 -290.361374) (xy 318.092523 -290.414781) (xy 318.068851 -290.465278) (xy 318.038078 -290.511791)
			(xy 318.000861 -290.553328) (xy 317.957993 -290.589003) (xy 317.910387 -290.618057) (xy 317.859058 -290.639869)
			(xy 317.805101 -290.653975) (xy 317.749664 -290.660075) (xy 317.69393 -290.658038) (xy 317.639087 -290.647908)
			(xy 317.586303 -290.629901) (xy 317.536703 -290.6044) (xy 317.491345 -290.571949) (xy 317.451196 -290.53324)
			(xy 317.41711 -290.489097) (xy 317.389814 -290.440462) (xy 317.369891 -290.388371) (xy 317.357765 -290.333934)
			(xy 317.353694 -290.278312) (xy 279.41397 -290.278312) (xy 279.41397 -290.674806) (xy 279.668998 -290.674806)
			(xy 279.672958 -290.625752) (xy 279.684735 -290.577968) (xy 279.704026 -290.532692) (xy 279.730329 -290.491096)
			(xy 279.762964 -290.454259) (xy 279.801085 -290.423134) (xy 279.843706 -290.398527) (xy 279.889722 -290.381075)
			(xy 279.937941 -290.371231) (xy 279.987116 -290.36925) (xy 280.035971 -290.375182) (xy 280.083242 -290.388874)
			(xy 280.127704 -290.409972) (xy 280.168207 -290.437928) (xy 280.2037 -290.47202) (xy 280.233265 -290.511364)
			(xy 280.256136 -290.554941) (xy 280.27172 -290.601622) (xy 280.279615 -290.650199) (xy 280.28011 -290.674806)
			(xy 280.618958 -290.674806) (xy 280.622918 -290.625752) (xy 280.634695 -290.577968) (xy 280.653986 -290.532692)
			(xy 280.680289 -290.491096) (xy 280.712924 -290.454259) (xy 280.751045 -290.423134) (xy 280.793666 -290.398527)
			(xy 280.839682 -290.381075) (xy 280.887901 -290.371231) (xy 280.937076 -290.36925) (xy 280.985931 -290.375182)
			(xy 281.033202 -290.388874) (xy 281.077664 -290.409972) (xy 281.118167 -290.437928) (xy 281.15366 -290.47202)
			(xy 281.183225 -290.511364) (xy 281.206096 -290.554941) (xy 281.22168 -290.601622) (xy 281.229575 -290.650199)
			(xy 281.23007 -290.674806) (xy 281.568918 -290.674806) (xy 281.572878 -290.625752) (xy 281.584655 -290.577968)
			(xy 281.603946 -290.532692) (xy 281.630249 -290.491096) (xy 281.662884 -290.454259) (xy 281.701005 -290.423134)
			(xy 281.743626 -290.398527) (xy 281.789642 -290.381075) (xy 281.837861 -290.371231) (xy 281.887036 -290.36925)
			(xy 281.935891 -290.375182) (xy 281.983162 -290.388874) (xy 282.027624 -290.409972) (xy 282.068127 -290.437928)
			(xy 282.10362 -290.47202) (xy 282.133185 -290.511364) (xy 282.156056 -290.554941) (xy 282.17164 -290.601622)
			(xy 282.179535 -290.650199) (xy 282.18003 -290.674806) (xy 300.56888 -290.674806) (xy 300.57284 -290.625752)
			(xy 300.584617 -290.577968) (xy 300.603908 -290.532692) (xy 300.630211 -290.491096) (xy 300.662846 -290.454259)
			(xy 300.700967 -290.423134) (xy 300.743588 -290.398527) (xy 300.789604 -290.381075) (xy 300.837823 -290.371231)
			(xy 300.886998 -290.36925) (xy 300.935853 -290.375182) (xy 300.983124 -290.388874) (xy 301.027586 -290.409972)
			(xy 301.068089 -290.437928) (xy 301.103582 -290.47202) (xy 301.133147 -290.511364) (xy 301.156018 -290.554941)
			(xy 301.171602 -290.601622) (xy 301.179497 -290.650199) (xy 301.179992 -290.674806) (xy 301.519094 -290.674806)
			(xy 301.523054 -290.625752) (xy 301.534831 -290.577968) (xy 301.554122 -290.532692) (xy 301.580425 -290.491096)
			(xy 301.61306 -290.454259) (xy 301.651181 -290.423134) (xy 301.693802 -290.398527) (xy 301.739818 -290.381075)
			(xy 301.788037 -290.371231) (xy 301.837212 -290.36925) (xy 301.886067 -290.375182) (xy 301.933338 -290.388874)
			(xy 301.9778 -290.409972) (xy 302.018303 -290.437928) (xy 302.053796 -290.47202) (xy 302.083361 -290.511364)
			(xy 302.106232 -290.554941) (xy 302.121816 -290.601622) (xy 302.129711 -290.650199) (xy 302.130206 -290.674806)
			(xy 302.469054 -290.674806) (xy 302.473014 -290.625752) (xy 302.484791 -290.577968) (xy 302.504082 -290.532692)
			(xy 302.530385 -290.491096) (xy 302.56302 -290.454259) (xy 302.601141 -290.423134) (xy 302.643762 -290.398527)
			(xy 302.689778 -290.381075) (xy 302.737997 -290.371231) (xy 302.787172 -290.36925) (xy 302.836027 -290.375182)
			(xy 302.883298 -290.388874) (xy 302.92776 -290.409972) (xy 302.968263 -290.437928) (xy 303.003756 -290.47202)
			(xy 303.033321 -290.511364) (xy 303.056192 -290.554941) (xy 303.071776 -290.601622) (xy 303.079671 -290.650199)
			(xy 303.080166 -290.674806) (xy 303.419014 -290.674806) (xy 303.422974 -290.625752) (xy 303.434751 -290.577968)
			(xy 303.454042 -290.532692) (xy 303.480345 -290.491096) (xy 303.51298 -290.454259) (xy 303.551101 -290.423134)
			(xy 303.593722 -290.398527) (xy 303.639738 -290.381075) (xy 303.687957 -290.371231) (xy 303.737132 -290.36925)
			(xy 303.785987 -290.375182) (xy 303.833258 -290.388874) (xy 303.87772 -290.409972) (xy 303.918223 -290.437928)
			(xy 303.953716 -290.47202) (xy 303.983281 -290.511364) (xy 304.006152 -290.554941) (xy 304.021736 -290.601622)
			(xy 304.029631 -290.650199) (xy 304.030126 -290.674806) (xy 304.368974 -290.674806) (xy 304.372934 -290.625752)
			(xy 304.384711 -290.577968) (xy 304.404002 -290.532692) (xy 304.430305 -290.491096) (xy 304.46294 -290.454259)
			(xy 304.501061 -290.423134) (xy 304.543682 -290.398527) (xy 304.589698 -290.381075) (xy 304.637917 -290.371231)
			(xy 304.687092 -290.36925) (xy 304.735947 -290.375182) (xy 304.783218 -290.388874) (xy 304.82768 -290.409972)
			(xy 304.868183 -290.437928) (xy 304.903676 -290.47202) (xy 304.933241 -290.511364) (xy 304.956112 -290.554941)
			(xy 304.971696 -290.601622) (xy 304.979591 -290.650199) (xy 304.980086 -290.674806) (xy 305.318934 -290.674806)
			(xy 305.322894 -290.625752) (xy 305.334671 -290.577968) (xy 305.353962 -290.532692) (xy 305.380265 -290.491096)
			(xy 305.4129 -290.454259) (xy 305.451021 -290.423134) (xy 305.493642 -290.398527) (xy 305.539658 -290.381075)
			(xy 305.587877 -290.371231) (xy 305.637052 -290.36925) (xy 305.685907 -290.375182) (xy 305.733178 -290.388874)
			(xy 305.77764 -290.409972) (xy 305.818143 -290.437928) (xy 305.853636 -290.47202) (xy 305.883201 -290.511364)
			(xy 305.906072 -290.554941) (xy 305.921656 -290.601622) (xy 305.929551 -290.650199) (xy 305.930046 -290.674806)
			(xy 306.268894 -290.674806) (xy 306.272854 -290.625752) (xy 306.284631 -290.577968) (xy 306.303922 -290.532692)
			(xy 306.330225 -290.491096) (xy 306.36286 -290.454259) (xy 306.400981 -290.423134) (xy 306.443602 -290.398527)
			(xy 306.489618 -290.381075) (xy 306.537837 -290.371231) (xy 306.587012 -290.36925) (xy 306.635867 -290.375182)
			(xy 306.683138 -290.388874) (xy 306.7276 -290.409972) (xy 306.768103 -290.437928) (xy 306.803596 -290.47202)
			(xy 306.833161 -290.511364) (xy 306.856032 -290.554941) (xy 306.871616 -290.601622) (xy 306.879511 -290.650199)
			(xy 306.880006 -290.674806) (xy 307.219108 -290.674806) (xy 307.223068 -290.625752) (xy 307.234845 -290.577968)
			(xy 307.254136 -290.532692) (xy 307.280439 -290.491096) (xy 307.313074 -290.454259) (xy 307.351195 -290.423134)
			(xy 307.393816 -290.398527) (xy 307.439832 -290.381075) (xy 307.488051 -290.371231) (xy 307.537226 -290.36925)
			(xy 307.586081 -290.375182) (xy 307.633352 -290.388874) (xy 307.677814 -290.409972) (xy 307.718317 -290.437928)
			(xy 307.75381 -290.47202) (xy 307.783375 -290.511364) (xy 307.806246 -290.554941) (xy 307.82183 -290.601622)
			(xy 307.829725 -290.650199) (xy 307.83022 -290.674806) (xy 308.169068 -290.674806) (xy 308.173028 -290.625752)
			(xy 308.184805 -290.577968) (xy 308.204096 -290.532692) (xy 308.230399 -290.491096) (xy 308.263034 -290.454259)
			(xy 308.301155 -290.423134) (xy 308.343776 -290.398527) (xy 308.389792 -290.381075) (xy 308.438011 -290.371231)
			(xy 308.487186 -290.36925) (xy 308.536041 -290.375182) (xy 308.583312 -290.388874) (xy 308.627774 -290.409972)
			(xy 308.668277 -290.437928) (xy 308.70377 -290.47202) (xy 308.733335 -290.511364) (xy 308.756206 -290.554941)
			(xy 308.77179 -290.601622) (xy 308.779685 -290.650199) (xy 308.78018 -290.674806) (xy 309.119028 -290.674806)
			(xy 309.122988 -290.625752) (xy 309.134765 -290.577968) (xy 309.154056 -290.532692) (xy 309.180359 -290.491096)
			(xy 309.212994 -290.454259) (xy 309.251115 -290.423134) (xy 309.293736 -290.398527) (xy 309.339752 -290.381075)
			(xy 309.387971 -290.371231) (xy 309.437146 -290.36925) (xy 309.486001 -290.375182) (xy 309.533272 -290.388874)
			(xy 309.577734 -290.409972) (xy 309.618237 -290.437928) (xy 309.65373 -290.47202) (xy 309.683295 -290.511364)
			(xy 309.706166 -290.554941) (xy 309.72175 -290.601622) (xy 309.729645 -290.650199) (xy 309.73014 -290.674806)
			(xy 310.068988 -290.674806) (xy 310.072948 -290.625752) (xy 310.084725 -290.577968) (xy 310.104016 -290.532692)
			(xy 310.130319 -290.491096) (xy 310.162954 -290.454259) (xy 310.201075 -290.423134) (xy 310.243696 -290.398527)
			(xy 310.289712 -290.381075) (xy 310.337931 -290.371231) (xy 310.387106 -290.36925) (xy 310.435961 -290.375182)
			(xy 310.483232 -290.388874) (xy 310.527694 -290.409972) (xy 310.568197 -290.437928) (xy 310.60369 -290.47202)
			(xy 310.633255 -290.511364) (xy 310.656126 -290.554941) (xy 310.67171 -290.601622) (xy 310.679605 -290.650199)
			(xy 310.6801 -290.674806) (xy 311.018948 -290.674806) (xy 311.022908 -290.625752) (xy 311.034685 -290.577968)
			(xy 311.053976 -290.532692) (xy 311.080279 -290.491096) (xy 311.112914 -290.454259) (xy 311.151035 -290.423134)
			(xy 311.193656 -290.398527) (xy 311.239672 -290.381075) (xy 311.287891 -290.371231) (xy 311.337066 -290.36925)
			(xy 311.385921 -290.375182) (xy 311.433192 -290.388874) (xy 311.477654 -290.409972) (xy 311.518157 -290.437928)
			(xy 311.55365 -290.47202) (xy 311.583215 -290.511364) (xy 311.606086 -290.554941) (xy 311.62167 -290.601622)
			(xy 311.629565 -290.650199) (xy 311.63006 -290.674806) (xy 311.968908 -290.674806) (xy 311.972868 -290.625752)
			(xy 311.984645 -290.577968) (xy 312.003936 -290.532692) (xy 312.030239 -290.491096) (xy 312.062874 -290.454259)
			(xy 312.100995 -290.423134) (xy 312.143616 -290.398527) (xy 312.189632 -290.381075) (xy 312.237851 -290.371231)
			(xy 312.287026 -290.36925) (xy 312.335881 -290.375182) (xy 312.383152 -290.388874) (xy 312.427614 -290.409972)
			(xy 312.468117 -290.437928) (xy 312.50361 -290.47202) (xy 312.533175 -290.511364) (xy 312.556046 -290.554941)
			(xy 312.57163 -290.601622) (xy 312.579525 -290.650199) (xy 312.58002 -290.674806) (xy 312.919122 -290.674806)
			(xy 312.923082 -290.625752) (xy 312.934859 -290.577968) (xy 312.95415 -290.532692) (xy 312.980453 -290.491096)
			(xy 313.013088 -290.454259) (xy 313.051209 -290.423134) (xy 313.09383 -290.398527) (xy 313.139846 -290.381075)
			(xy 313.188065 -290.371231) (xy 313.23724 -290.36925) (xy 313.286095 -290.375182) (xy 313.333366 -290.388874)
			(xy 313.377828 -290.409972) (xy 313.418331 -290.437928) (xy 313.453824 -290.47202) (xy 313.483389 -290.511364)
			(xy 313.50626 -290.554941) (xy 313.521844 -290.601622) (xy 313.529739 -290.650199) (xy 313.530234 -290.674806)
			(xy 313.869082 -290.674806) (xy 313.873042 -290.625752) (xy 313.884819 -290.577968) (xy 313.90411 -290.532692)
			(xy 313.930413 -290.491096) (xy 313.963048 -290.454259) (xy 314.001169 -290.423134) (xy 314.04379 -290.398527)
			(xy 314.089806 -290.381075) (xy 314.138025 -290.371231) (xy 314.1872 -290.36925) (xy 314.236055 -290.375182)
			(xy 314.283326 -290.388874) (xy 314.327788 -290.409972) (xy 314.368291 -290.437928) (xy 314.403784 -290.47202)
			(xy 314.433349 -290.511364) (xy 314.45622 -290.554941) (xy 314.471804 -290.601622) (xy 314.479699 -290.650199)
			(xy 314.480194 -290.674806) (xy 314.819042 -290.674806) (xy 314.823002 -290.625752) (xy 314.834779 -290.577968)
			(xy 314.85407 -290.532692) (xy 314.880373 -290.491096) (xy 314.913008 -290.454259) (xy 314.951129 -290.423134)
			(xy 314.99375 -290.398527) (xy 315.039766 -290.381075) (xy 315.087985 -290.371231) (xy 315.13716 -290.36925)
			(xy 315.186015 -290.375182) (xy 315.233286 -290.388874) (xy 315.277748 -290.409972) (xy 315.318251 -290.437928)
			(xy 315.353744 -290.47202) (xy 315.383309 -290.511364) (xy 315.40618 -290.554941) (xy 315.421764 -290.601622)
			(xy 315.429659 -290.650199) (xy 315.430154 -290.674806) (xy 315.429659 -290.699413) (xy 315.421764 -290.74799)
			(xy 315.40618 -290.794671) (xy 315.383309 -290.838248) (xy 315.353744 -290.877592) (xy 315.318251 -290.911684)
			(xy 315.277748 -290.93964) (xy 315.233286 -290.960738) (xy 315.186015 -290.97443) (xy 315.13716 -290.980362)
			(xy 315.087985 -290.978381) (xy 315.039766 -290.968537) (xy 314.99375 -290.951085) (xy 314.951129 -290.926478)
			(xy 314.913008 -290.895353) (xy 314.880373 -290.858516) (xy 314.85407 -290.81692) (xy 314.834779 -290.771644)
			(xy 314.823002 -290.72386) (xy 314.819042 -290.674806) (xy 314.480194 -290.674806) (xy 314.479699 -290.699413)
			(xy 314.471804 -290.74799) (xy 314.45622 -290.794671) (xy 314.433349 -290.838248) (xy 314.403784 -290.877592)
			(xy 314.368291 -290.911684) (xy 314.327788 -290.93964) (xy 314.283326 -290.960738) (xy 314.236055 -290.97443)
			(xy 314.1872 -290.980362) (xy 314.138025 -290.978381) (xy 314.089806 -290.968537) (xy 314.04379 -290.951085)
			(xy 314.001169 -290.926478) (xy 313.963048 -290.895353) (xy 313.930413 -290.858516) (xy 313.90411 -290.81692)
			(xy 313.884819 -290.771644) (xy 313.873042 -290.72386) (xy 313.869082 -290.674806) (xy 313.530234 -290.674806)
			(xy 313.529739 -290.699413) (xy 313.521844 -290.74799) (xy 313.50626 -290.794671) (xy 313.483389 -290.838248)
			(xy 313.453824 -290.877592) (xy 313.418331 -290.911684) (xy 313.377828 -290.93964) (xy 313.333366 -290.960738)
			(xy 313.286095 -290.97443) (xy 313.23724 -290.980362) (xy 313.188065 -290.978381) (xy 313.139846 -290.968537)
			(xy 313.09383 -290.951085) (xy 313.051209 -290.926478) (xy 313.013088 -290.895353) (xy 312.980453 -290.858516)
			(xy 312.95415 -290.81692) (xy 312.934859 -290.771644) (xy 312.923082 -290.72386) (xy 312.919122 -290.674806)
			(xy 312.58002 -290.674806) (xy 312.579525 -290.699413) (xy 312.57163 -290.74799) (xy 312.556046 -290.794671)
			(xy 312.533175 -290.838248) (xy 312.50361 -290.877592) (xy 312.468117 -290.911684) (xy 312.427614 -290.93964)
			(xy 312.383152 -290.960738) (xy 312.335881 -290.97443) (xy 312.287026 -290.980362) (xy 312.237851 -290.978381)
			(xy 312.189632 -290.968537) (xy 312.143616 -290.951085) (xy 312.100995 -290.926478) (xy 312.062874 -290.895353)
			(xy 312.030239 -290.858516) (xy 312.003936 -290.81692) (xy 311.984645 -290.771644) (xy 311.972868 -290.72386)
			(xy 311.968908 -290.674806) (xy 311.63006 -290.674806) (xy 311.629565 -290.699413) (xy 311.62167 -290.74799)
			(xy 311.606086 -290.794671) (xy 311.583215 -290.838248) (xy 311.55365 -290.877592) (xy 311.518157 -290.911684)
			(xy 311.477654 -290.93964) (xy 311.433192 -290.960738) (xy 311.385921 -290.97443) (xy 311.337066 -290.980362)
			(xy 311.287891 -290.978381) (xy 311.239672 -290.968537) (xy 311.193656 -290.951085) (xy 311.151035 -290.926478)
			(xy 311.112914 -290.895353) (xy 311.080279 -290.858516) (xy 311.053976 -290.81692) (xy 311.034685 -290.771644)
			(xy 311.022908 -290.72386) (xy 311.018948 -290.674806) (xy 310.6801 -290.674806) (xy 310.679605 -290.699413)
			(xy 310.67171 -290.74799) (xy 310.656126 -290.794671) (xy 310.633255 -290.838248) (xy 310.60369 -290.877592)
			(xy 310.568197 -290.911684) (xy 310.527694 -290.93964) (xy 310.483232 -290.960738) (xy 310.435961 -290.97443)
			(xy 310.387106 -290.980362) (xy 310.337931 -290.978381) (xy 310.289712 -290.968537) (xy 310.243696 -290.951085)
			(xy 310.201075 -290.926478) (xy 310.162954 -290.895353) (xy 310.130319 -290.858516) (xy 310.104016 -290.81692)
			(xy 310.084725 -290.771644) (xy 310.072948 -290.72386) (xy 310.068988 -290.674806) (xy 309.73014 -290.674806)
			(xy 309.729645 -290.699413) (xy 309.72175 -290.74799) (xy 309.706166 -290.794671) (xy 309.683295 -290.838248)
			(xy 309.65373 -290.877592) (xy 309.618237 -290.911684) (xy 309.577734 -290.93964) (xy 309.533272 -290.960738)
			(xy 309.486001 -290.97443) (xy 309.437146 -290.980362) (xy 309.387971 -290.978381) (xy 309.339752 -290.968537)
			(xy 309.293736 -290.951085) (xy 309.251115 -290.926478) (xy 309.212994 -290.895353) (xy 309.180359 -290.858516)
			(xy 309.154056 -290.81692) (xy 309.134765 -290.771644) (xy 309.122988 -290.72386) (xy 309.119028 -290.674806)
			(xy 308.78018 -290.674806) (xy 308.779685 -290.699413) (xy 308.77179 -290.74799) (xy 308.756206 -290.794671)
			(xy 308.733335 -290.838248) (xy 308.70377 -290.877592) (xy 308.668277 -290.911684) (xy 308.627774 -290.93964)
			(xy 308.583312 -290.960738) (xy 308.536041 -290.97443) (xy 308.487186 -290.980362) (xy 308.438011 -290.978381)
			(xy 308.389792 -290.968537) (xy 308.343776 -290.951085) (xy 308.301155 -290.926478) (xy 308.263034 -290.895353)
			(xy 308.230399 -290.858516) (xy 308.204096 -290.81692) (xy 308.184805 -290.771644) (xy 308.173028 -290.72386)
			(xy 308.169068 -290.674806) (xy 307.83022 -290.674806) (xy 307.829725 -290.699413) (xy 307.82183 -290.74799)
			(xy 307.806246 -290.794671) (xy 307.783375 -290.838248) (xy 307.75381 -290.877592) (xy 307.718317 -290.911684)
			(xy 307.677814 -290.93964) (xy 307.633352 -290.960738) (xy 307.586081 -290.97443) (xy 307.537226 -290.980362)
			(xy 307.488051 -290.978381) (xy 307.439832 -290.968537) (xy 307.393816 -290.951085) (xy 307.351195 -290.926478)
			(xy 307.313074 -290.895353) (xy 307.280439 -290.858516) (xy 307.254136 -290.81692) (xy 307.234845 -290.771644)
			(xy 307.223068 -290.72386) (xy 307.219108 -290.674806) (xy 306.880006 -290.674806) (xy 306.879511 -290.699413)
			(xy 306.871616 -290.74799) (xy 306.856032 -290.794671) (xy 306.833161 -290.838248) (xy 306.803596 -290.877592)
			(xy 306.768103 -290.911684) (xy 306.7276 -290.93964) (xy 306.683138 -290.960738) (xy 306.635867 -290.97443)
			(xy 306.587012 -290.980362) (xy 306.537837 -290.978381) (xy 306.489618 -290.968537) (xy 306.443602 -290.951085)
			(xy 306.400981 -290.926478) (xy 306.36286 -290.895353) (xy 306.330225 -290.858516) (xy 306.303922 -290.81692)
			(xy 306.284631 -290.771644) (xy 306.272854 -290.72386) (xy 306.268894 -290.674806) (xy 305.930046 -290.674806)
			(xy 305.929551 -290.699413) (xy 305.921656 -290.74799) (xy 305.906072 -290.794671) (xy 305.883201 -290.838248)
			(xy 305.853636 -290.877592) (xy 305.818143 -290.911684) (xy 305.77764 -290.93964) (xy 305.733178 -290.960738)
			(xy 305.685907 -290.97443) (xy 305.637052 -290.980362) (xy 305.587877 -290.978381) (xy 305.539658 -290.968537)
			(xy 305.493642 -290.951085) (xy 305.451021 -290.926478) (xy 305.4129 -290.895353) (xy 305.380265 -290.858516)
			(xy 305.353962 -290.81692) (xy 305.334671 -290.771644) (xy 305.322894 -290.72386) (xy 305.318934 -290.674806)
			(xy 304.980086 -290.674806) (xy 304.979591 -290.699413) (xy 304.971696 -290.74799) (xy 304.956112 -290.794671)
			(xy 304.933241 -290.838248) (xy 304.903676 -290.877592) (xy 304.868183 -290.911684) (xy 304.82768 -290.93964)
			(xy 304.783218 -290.960738) (xy 304.735947 -290.97443) (xy 304.687092 -290.980362) (xy 304.637917 -290.978381)
			(xy 304.589698 -290.968537) (xy 304.543682 -290.951085) (xy 304.501061 -290.926478) (xy 304.46294 -290.895353)
			(xy 304.430305 -290.858516) (xy 304.404002 -290.81692) (xy 304.384711 -290.771644) (xy 304.372934 -290.72386)
			(xy 304.368974 -290.674806) (xy 304.030126 -290.674806) (xy 304.029631 -290.699413) (xy 304.021736 -290.74799)
			(xy 304.006152 -290.794671) (xy 303.983281 -290.838248) (xy 303.953716 -290.877592) (xy 303.918223 -290.911684)
			(xy 303.87772 -290.93964) (xy 303.833258 -290.960738) (xy 303.785987 -290.97443) (xy 303.737132 -290.980362)
			(xy 303.687957 -290.978381) (xy 303.639738 -290.968537) (xy 303.593722 -290.951085) (xy 303.551101 -290.926478)
			(xy 303.51298 -290.895353) (xy 303.480345 -290.858516) (xy 303.454042 -290.81692) (xy 303.434751 -290.771644)
			(xy 303.422974 -290.72386) (xy 303.419014 -290.674806) (xy 303.080166 -290.674806) (xy 303.079671 -290.699413)
			(xy 303.071776 -290.74799) (xy 303.056192 -290.794671) (xy 303.033321 -290.838248) (xy 303.003756 -290.877592)
			(xy 302.968263 -290.911684) (xy 302.92776 -290.93964) (xy 302.883298 -290.960738) (xy 302.836027 -290.97443)
			(xy 302.787172 -290.980362) (xy 302.737997 -290.978381) (xy 302.689778 -290.968537) (xy 302.643762 -290.951085)
			(xy 302.601141 -290.926478) (xy 302.56302 -290.895353) (xy 302.530385 -290.858516) (xy 302.504082 -290.81692)
			(xy 302.484791 -290.771644) (xy 302.473014 -290.72386) (xy 302.469054 -290.674806) (xy 302.130206 -290.674806)
			(xy 302.129711 -290.699413) (xy 302.121816 -290.74799) (xy 302.106232 -290.794671) (xy 302.083361 -290.838248)
			(xy 302.053796 -290.877592) (xy 302.018303 -290.911684) (xy 301.9778 -290.93964) (xy 301.933338 -290.960738)
			(xy 301.886067 -290.97443) (xy 301.837212 -290.980362) (xy 301.788037 -290.978381) (xy 301.739818 -290.968537)
			(xy 301.693802 -290.951085) (xy 301.651181 -290.926478) (xy 301.61306 -290.895353) (xy 301.580425 -290.858516)
			(xy 301.554122 -290.81692) (xy 301.534831 -290.771644) (xy 301.523054 -290.72386) (xy 301.519094 -290.674806)
			(xy 301.179992 -290.674806) (xy 301.179497 -290.699413) (xy 301.171602 -290.74799) (xy 301.156018 -290.794671)
			(xy 301.133147 -290.838248) (xy 301.103582 -290.877592) (xy 301.068089 -290.911684) (xy 301.027586 -290.93964)
			(xy 300.983124 -290.960738) (xy 300.935853 -290.97443) (xy 300.886998 -290.980362) (xy 300.837823 -290.978381)
			(xy 300.789604 -290.968537) (xy 300.743588 -290.951085) (xy 300.700967 -290.926478) (xy 300.662846 -290.895353)
			(xy 300.630211 -290.858516) (xy 300.603908 -290.81692) (xy 300.584617 -290.771644) (xy 300.57284 -290.72386)
			(xy 300.56888 -290.674806) (xy 282.18003 -290.674806) (xy 282.179535 -290.699413) (xy 282.17164 -290.74799)
			(xy 282.156056 -290.794671) (xy 282.133185 -290.838248) (xy 282.10362 -290.877592) (xy 282.068127 -290.911684)
			(xy 282.027624 -290.93964) (xy 281.983162 -290.960738) (xy 281.935891 -290.97443) (xy 281.887036 -290.980362)
			(xy 281.837861 -290.978381) (xy 281.789642 -290.968537) (xy 281.743626 -290.951085) (xy 281.701005 -290.926478)
			(xy 281.662884 -290.895353) (xy 281.630249 -290.858516) (xy 281.603946 -290.81692) (xy 281.584655 -290.771644)
			(xy 281.572878 -290.72386) (xy 281.568918 -290.674806) (xy 281.23007 -290.674806) (xy 281.229575 -290.699413)
			(xy 281.22168 -290.74799) (xy 281.206096 -290.794671) (xy 281.183225 -290.838248) (xy 281.15366 -290.877592)
			(xy 281.118167 -290.911684) (xy 281.077664 -290.93964) (xy 281.033202 -290.960738) (xy 280.985931 -290.97443)
			(xy 280.937076 -290.980362) (xy 280.887901 -290.978381) (xy 280.839682 -290.968537) (xy 280.793666 -290.951085)
			(xy 280.751045 -290.926478) (xy 280.712924 -290.895353) (xy 280.680289 -290.858516) (xy 280.653986 -290.81692)
			(xy 280.634695 -290.771644) (xy 280.622918 -290.72386) (xy 280.618958 -290.674806) (xy 280.28011 -290.674806)
			(xy 280.279615 -290.699413) (xy 280.27172 -290.74799) (xy 280.256136 -290.794671) (xy 280.233265 -290.838248)
			(xy 280.2037 -290.877592) (xy 280.168207 -290.911684) (xy 280.127704 -290.93964) (xy 280.083242 -290.960738)
			(xy 280.035971 -290.97443) (xy 279.987116 -290.980362) (xy 279.937941 -290.978381) (xy 279.889722 -290.968537)
			(xy 279.843706 -290.951085) (xy 279.801085 -290.926478) (xy 279.762964 -290.895353) (xy 279.730329 -290.858516)
			(xy 279.704026 -290.81692) (xy 279.684735 -290.771644) (xy 279.672958 -290.72386) (xy 279.668998 -290.674806)
			(xy 279.41397 -290.674806) (xy 279.41397 -291.2364) (xy 318.184782 -291.2364) (xy 318.188853 -291.180778)
			(xy 318.200979 -291.126341) (xy 318.220902 -291.07425) (xy 318.248198 -291.025615) (xy 318.282284 -290.981472)
			(xy 318.322433 -290.942763) (xy 318.367791 -290.910312) (xy 318.417391 -290.884811) (xy 318.470175 -290.866804)
			(xy 318.525018 -290.856674) (xy 318.580752 -290.854637) (xy 318.636189 -290.860737) (xy 318.690146 -290.874843)
			(xy 318.741475 -290.896655) (xy 318.789081 -290.925709) (xy 318.831949 -290.961384) (xy 318.869166 -291.002921)
			(xy 318.899939 -291.049434) (xy 318.923611 -291.099931) (xy 318.939679 -291.153338) (xy 318.947799 -291.208514)
			(xy 318.948308 -291.2364) (xy 318.947799 -291.264286) (xy 318.939679 -291.319462) (xy 318.923611 -291.372869)
			(xy 318.899939 -291.423366) (xy 318.869166 -291.469879) (xy 318.831949 -291.511416) (xy 318.789081 -291.547091)
			(xy 318.741475 -291.576145) (xy 318.704164 -291.592) (xy 320.641724 -291.592) (xy 320.645795 -291.536378)
			(xy 320.657921 -291.481941) (xy 320.677844 -291.42985) (xy 320.70514 -291.381215) (xy 320.739226 -291.337072)
			(xy 320.779375 -291.298363) (xy 320.824733 -291.265912) (xy 320.874333 -291.240411) (xy 320.927117 -291.222404)
			(xy 320.98196 -291.212274) (xy 321.037694 -291.210237) (xy 321.093131 -291.216337) (xy 321.147088 -291.230443)
			(xy 321.198417 -291.252255) (xy 321.246023 -291.281309) (xy 321.288891 -291.316984) (xy 321.326108 -291.358521)
			(xy 321.356881 -291.405034) (xy 321.380553 -291.455531) (xy 321.396621 -291.508938) (xy 321.404741 -291.564114)
			(xy 321.40525 -291.592) (xy 321.404741 -291.619886) (xy 321.396621 -291.675062) (xy 321.380553 -291.728469)
			(xy 321.356881 -291.778966) (xy 321.326108 -291.825479) (xy 321.288891 -291.867016) (xy 321.246023 -291.902691)
			(xy 321.198417 -291.931745) (xy 321.147088 -291.953557) (xy 321.093131 -291.967663) (xy 321.037694 -291.973763)
			(xy 320.98196 -291.971726) (xy 320.927117 -291.961596) (xy 320.874333 -291.943589) (xy 320.824733 -291.918088)
			(xy 320.779375 -291.885637) (xy 320.739226 -291.846928) (xy 320.70514 -291.802785) (xy 320.677844 -291.75415)
			(xy 320.657921 -291.702059) (xy 320.645795 -291.647622) (xy 320.641724 -291.592) (xy 318.704164 -291.592)
			(xy 318.690146 -291.597957) (xy 318.636189 -291.612063) (xy 318.580752 -291.618163) (xy 318.525018 -291.616126)
			(xy 318.470175 -291.605996) (xy 318.417391 -291.587989) (xy 318.367791 -291.562488) (xy 318.322433 -291.530037)
			(xy 318.282284 -291.491328) (xy 318.248198 -291.447185) (xy 318.220902 -291.39855) (xy 318.200979 -291.346459)
			(xy 318.188853 -291.292022) (xy 318.184782 -291.2364) (xy 279.41397 -291.2364) (xy 279.41397 -291.624766)
			(xy 279.668998 -291.624766) (xy 279.672958 -291.575712) (xy 279.684735 -291.527928) (xy 279.704026 -291.482652)
			(xy 279.730329 -291.441056) (xy 279.762964 -291.404219) (xy 279.801085 -291.373094) (xy 279.843706 -291.348487)
			(xy 279.889722 -291.331035) (xy 279.937941 -291.321191) (xy 279.987116 -291.31921) (xy 280.035971 -291.325142)
			(xy 280.083242 -291.338834) (xy 280.127704 -291.359932) (xy 280.168207 -291.387888) (xy 280.2037 -291.42198)
			(xy 280.233265 -291.461324) (xy 280.256136 -291.504901) (xy 280.27172 -291.551582) (xy 280.279615 -291.600159)
			(xy 280.28011 -291.624766) (xy 280.618958 -291.624766) (xy 280.622918 -291.575712) (xy 280.634695 -291.527928)
			(xy 280.653986 -291.482652) (xy 280.680289 -291.441056) (xy 280.712924 -291.404219) (xy 280.751045 -291.373094)
			(xy 280.793666 -291.348487) (xy 280.839682 -291.331035) (xy 280.887901 -291.321191) (xy 280.937076 -291.31921)
			(xy 280.985931 -291.325142) (xy 281.033202 -291.338834) (xy 281.077664 -291.359932) (xy 281.118167 -291.387888)
			(xy 281.15366 -291.42198) (xy 281.183225 -291.461324) (xy 281.206096 -291.504901) (xy 281.22168 -291.551582)
			(xy 281.229575 -291.600159) (xy 281.23007 -291.624766) (xy 281.568918 -291.624766) (xy 281.572878 -291.575712)
			(xy 281.584655 -291.527928) (xy 281.603946 -291.482652) (xy 281.630249 -291.441056) (xy 281.662884 -291.404219)
			(xy 281.701005 -291.373094) (xy 281.743626 -291.348487) (xy 281.789642 -291.331035) (xy 281.837861 -291.321191)
			(xy 281.887036 -291.31921) (xy 281.935891 -291.325142) (xy 281.983162 -291.338834) (xy 282.027624 -291.359932)
			(xy 282.068127 -291.387888) (xy 282.10362 -291.42198) (xy 282.133185 -291.461324) (xy 282.156056 -291.504901)
			(xy 282.17164 -291.551582) (xy 282.179535 -291.600159) (xy 282.18003 -291.624766) (xy 282.519132 -291.624766)
			(xy 282.523092 -291.575712) (xy 282.534869 -291.527928) (xy 282.55416 -291.482652) (xy 282.580463 -291.441056)
			(xy 282.613098 -291.404219) (xy 282.651219 -291.373094) (xy 282.69384 -291.348487) (xy 282.739856 -291.331035)
			(xy 282.788075 -291.321191) (xy 282.83725 -291.31921) (xy 282.886105 -291.325142) (xy 282.933376 -291.338834)
			(xy 282.977838 -291.359932) (xy 283.018341 -291.387888) (xy 283.053834 -291.42198) (xy 283.083399 -291.461324)
			(xy 283.10627 -291.504901) (xy 283.121854 -291.551582) (xy 283.129749 -291.600159) (xy 283.130244 -291.624766)
			(xy 283.469092 -291.624766) (xy 283.473052 -291.575712) (xy 283.484829 -291.527928) (xy 283.50412 -291.482652)
			(xy 283.530423 -291.441056) (xy 283.563058 -291.404219) (xy 283.601179 -291.373094) (xy 283.6438 -291.348487)
			(xy 283.689816 -291.331035) (xy 283.738035 -291.321191) (xy 283.78721 -291.31921) (xy 283.836065 -291.325142)
			(xy 283.883336 -291.338834) (xy 283.927798 -291.359932) (xy 283.968301 -291.387888) (xy 284.003794 -291.42198)
			(xy 284.033359 -291.461324) (xy 284.05623 -291.504901) (xy 284.071814 -291.551582) (xy 284.079709 -291.600159)
			(xy 284.080204 -291.624766) (xy 284.419052 -291.624766) (xy 284.423012 -291.575712) (xy 284.434789 -291.527928)
			(xy 284.45408 -291.482652) (xy 284.480383 -291.441056) (xy 284.513018 -291.404219) (xy 284.551139 -291.373094)
			(xy 284.59376 -291.348487) (xy 284.639776 -291.331035) (xy 284.687995 -291.321191) (xy 284.73717 -291.31921)
			(xy 284.786025 -291.325142) (xy 284.833296 -291.338834) (xy 284.877758 -291.359932) (xy 284.918261 -291.387888)
			(xy 284.953754 -291.42198) (xy 284.983319 -291.461324) (xy 285.00619 -291.504901) (xy 285.021774 -291.551582)
			(xy 285.029669 -291.600159) (xy 285.030164 -291.624766) (xy 285.369012 -291.624766) (xy 285.372972 -291.575712)
			(xy 285.384749 -291.527928) (xy 285.40404 -291.482652) (xy 285.430343 -291.441056) (xy 285.462978 -291.404219)
			(xy 285.501099 -291.373094) (xy 285.54372 -291.348487) (xy 285.589736 -291.331035) (xy 285.637955 -291.321191)
			(xy 285.68713 -291.31921) (xy 285.735985 -291.325142) (xy 285.783256 -291.338834) (xy 285.827718 -291.359932)
			(xy 285.868221 -291.387888) (xy 285.903714 -291.42198) (xy 285.933279 -291.461324) (xy 285.95615 -291.504901)
			(xy 285.971734 -291.551582) (xy 285.979629 -291.600159) (xy 285.980124 -291.624766) (xy 286.318972 -291.624766)
			(xy 286.322932 -291.575712) (xy 286.334709 -291.527928) (xy 286.354 -291.482652) (xy 286.380303 -291.441056)
			(xy 286.412938 -291.404219) (xy 286.451059 -291.373094) (xy 286.49368 -291.348487) (xy 286.539696 -291.331035)
			(xy 286.587915 -291.321191) (xy 286.63709 -291.31921) (xy 286.685945 -291.325142) (xy 286.733216 -291.338834)
			(xy 286.777678 -291.359932) (xy 286.818181 -291.387888) (xy 286.853674 -291.42198) (xy 286.883239 -291.461324)
			(xy 286.90611 -291.504901) (xy 286.921694 -291.551582) (xy 286.929589 -291.600159) (xy 286.930084 -291.624766)
			(xy 287.268932 -291.624766) (xy 287.272892 -291.575712) (xy 287.284669 -291.527928) (xy 287.30396 -291.482652)
			(xy 287.330263 -291.441056) (xy 287.362898 -291.404219) (xy 287.401019 -291.373094) (xy 287.44364 -291.348487)
			(xy 287.489656 -291.331035) (xy 287.537875 -291.321191) (xy 287.58705 -291.31921) (xy 287.635905 -291.325142)
			(xy 287.683176 -291.338834) (xy 287.727638 -291.359932) (xy 287.768141 -291.387888) (xy 287.803634 -291.42198)
			(xy 287.833199 -291.461324) (xy 287.85607 -291.504901) (xy 287.871654 -291.551582) (xy 287.879549 -291.600159)
			(xy 287.880044 -291.624766) (xy 288.218892 -291.624766) (xy 288.222852 -291.575712) (xy 288.234629 -291.527928)
			(xy 288.25392 -291.482652) (xy 288.280223 -291.441056) (xy 288.312858 -291.404219) (xy 288.350979 -291.373094)
			(xy 288.3936 -291.348487) (xy 288.439616 -291.331035) (xy 288.487835 -291.321191) (xy 288.53701 -291.31921)
			(xy 288.585865 -291.325142) (xy 288.633136 -291.338834) (xy 288.677598 -291.359932) (xy 288.718101 -291.387888)
			(xy 288.753594 -291.42198) (xy 288.783159 -291.461324) (xy 288.80603 -291.504901) (xy 288.821614 -291.551582)
			(xy 288.829509 -291.600159) (xy 288.830004 -291.624766) (xy 289.169106 -291.624766) (xy 289.173066 -291.575712)
			(xy 289.184843 -291.527928) (xy 289.204134 -291.482652) (xy 289.230437 -291.441056) (xy 289.263072 -291.404219)
			(xy 289.301193 -291.373094) (xy 289.343814 -291.348487) (xy 289.38983 -291.331035) (xy 289.438049 -291.321191)
			(xy 289.487224 -291.31921) (xy 289.536079 -291.325142) (xy 289.58335 -291.338834) (xy 289.627812 -291.359932)
			(xy 289.668315 -291.387888) (xy 289.703808 -291.42198) (xy 289.733373 -291.461324) (xy 289.756244 -291.504901)
			(xy 289.771828 -291.551582) (xy 289.779723 -291.600159) (xy 289.780218 -291.624766) (xy 290.119066 -291.624766)
			(xy 290.123026 -291.575712) (xy 290.134803 -291.527928) (xy 290.154094 -291.482652) (xy 290.180397 -291.441056)
			(xy 290.213032 -291.404219) (xy 290.251153 -291.373094) (xy 290.293774 -291.348487) (xy 290.33979 -291.331035)
			(xy 290.388009 -291.321191) (xy 290.437184 -291.31921) (xy 290.486039 -291.325142) (xy 290.53331 -291.338834)
			(xy 290.577772 -291.359932) (xy 290.618275 -291.387888) (xy 290.653768 -291.42198) (xy 290.683333 -291.461324)
			(xy 290.706204 -291.504901) (xy 290.721788 -291.551582) (xy 290.729683 -291.600159) (xy 290.730178 -291.624766)
			(xy 292.018986 -291.624766) (xy 292.022946 -291.575712) (xy 292.034723 -291.527928) (xy 292.054014 -291.482652)
			(xy 292.080317 -291.441056) (xy 292.112952 -291.404219) (xy 292.151073 -291.373094) (xy 292.193694 -291.348487)
			(xy 292.23971 -291.331035) (xy 292.287929 -291.321191) (xy 292.337104 -291.31921) (xy 292.385959 -291.325142)
			(xy 292.43323 -291.338834) (xy 292.477692 -291.359932) (xy 292.518195 -291.387888) (xy 292.553688 -291.42198)
			(xy 292.583253 -291.461324) (xy 292.606124 -291.504901) (xy 292.621708 -291.551582) (xy 292.629603 -291.600159)
			(xy 292.630098 -291.624766) (xy 292.968946 -291.624766) (xy 292.972906 -291.575712) (xy 292.984683 -291.527928)
			(xy 293.003974 -291.482652) (xy 293.030277 -291.441056) (xy 293.062912 -291.404219) (xy 293.101033 -291.373094)
			(xy 293.143654 -291.348487) (xy 293.18967 -291.331035) (xy 293.237889 -291.321191) (xy 293.287064 -291.31921)
			(xy 293.335919 -291.325142) (xy 293.38319 -291.338834) (xy 293.427652 -291.359932) (xy 293.468155 -291.387888)
			(xy 293.503648 -291.42198) (xy 293.533213 -291.461324) (xy 293.556084 -291.504901) (xy 293.571668 -291.551582)
			(xy 293.579563 -291.600159) (xy 293.580058 -291.624766) (xy 293.918906 -291.624766) (xy 293.922866 -291.575712)
			(xy 293.934643 -291.527928) (xy 293.953934 -291.482652) (xy 293.980237 -291.441056) (xy 294.012872 -291.404219)
			(xy 294.050993 -291.373094) (xy 294.093614 -291.348487) (xy 294.13963 -291.331035) (xy 294.187849 -291.321191)
			(xy 294.237024 -291.31921) (xy 294.285879 -291.325142) (xy 294.33315 -291.338834) (xy 294.377612 -291.359932)
			(xy 294.418115 -291.387888) (xy 294.453608 -291.42198) (xy 294.483173 -291.461324) (xy 294.506044 -291.504901)
			(xy 294.521628 -291.551582) (xy 294.529523 -291.600159) (xy 294.530018 -291.624766) (xy 294.86912 -291.624766)
			(xy 294.87308 -291.575712) (xy 294.884857 -291.527928) (xy 294.904148 -291.482652) (xy 294.930451 -291.441056)
			(xy 294.963086 -291.404219) (xy 295.001207 -291.373094) (xy 295.043828 -291.348487) (xy 295.089844 -291.331035)
			(xy 295.138063 -291.321191) (xy 295.187238 -291.31921) (xy 295.236093 -291.325142) (xy 295.283364 -291.338834)
			(xy 295.327826 -291.359932) (xy 295.368329 -291.387888) (xy 295.403822 -291.42198) (xy 295.433387 -291.461324)
			(xy 295.456258 -291.504901) (xy 295.471842 -291.551582) (xy 295.479737 -291.600159) (xy 295.480232 -291.624766)
			(xy 295.81908 -291.624766) (xy 295.82304 -291.575712) (xy 295.834817 -291.527928) (xy 295.854108 -291.482652)
			(xy 295.880411 -291.441056) (xy 295.913046 -291.404219) (xy 295.951167 -291.373094) (xy 295.993788 -291.348487)
			(xy 296.039804 -291.331035) (xy 296.088023 -291.321191) (xy 296.137198 -291.31921) (xy 296.186053 -291.325142)
			(xy 296.233324 -291.338834) (xy 296.277786 -291.359932) (xy 296.318289 -291.387888) (xy 296.353782 -291.42198)
			(xy 296.383347 -291.461324) (xy 296.406218 -291.504901) (xy 296.421802 -291.551582) (xy 296.429697 -291.600159)
			(xy 296.430192 -291.624766) (xy 296.76904 -291.624766) (xy 296.773 -291.575712) (xy 296.784777 -291.527928)
			(xy 296.804068 -291.482652) (xy 296.830371 -291.441056) (xy 296.863006 -291.404219) (xy 296.901127 -291.373094)
			(xy 296.943748 -291.348487) (xy 296.989764 -291.331035) (xy 297.037983 -291.321191) (xy 297.087158 -291.31921)
			(xy 297.136013 -291.325142) (xy 297.183284 -291.338834) (xy 297.227746 -291.359932) (xy 297.268249 -291.387888)
			(xy 297.303742 -291.42198) (xy 297.333307 -291.461324) (xy 297.356178 -291.504901) (xy 297.371762 -291.551582)
			(xy 297.379657 -291.600159) (xy 297.380152 -291.624766) (xy 297.719 -291.624766) (xy 297.72296 -291.575712)
			(xy 297.734737 -291.527928) (xy 297.754028 -291.482652) (xy 297.780331 -291.441056) (xy 297.812966 -291.404219)
			(xy 297.851087 -291.373094) (xy 297.893708 -291.348487) (xy 297.939724 -291.331035) (xy 297.987943 -291.321191)
			(xy 298.037118 -291.31921) (xy 298.085973 -291.325142) (xy 298.133244 -291.338834) (xy 298.177706 -291.359932)
			(xy 298.218209 -291.387888) (xy 298.253702 -291.42198) (xy 298.283267 -291.461324) (xy 298.306138 -291.504901)
			(xy 298.321722 -291.551582) (xy 298.329617 -291.600159) (xy 298.330112 -291.624766) (xy 298.66896 -291.624766)
			(xy 298.67292 -291.575712) (xy 298.684697 -291.527928) (xy 298.703988 -291.482652) (xy 298.730291 -291.441056)
			(xy 298.762926 -291.404219) (xy 298.801047 -291.373094) (xy 298.843668 -291.348487) (xy 298.889684 -291.331035)
			(xy 298.937903 -291.321191) (xy 298.987078 -291.31921) (xy 299.035933 -291.325142) (xy 299.083204 -291.338834)
			(xy 299.127666 -291.359932) (xy 299.168169 -291.387888) (xy 299.203662 -291.42198) (xy 299.233227 -291.461324)
			(xy 299.256098 -291.504901) (xy 299.271682 -291.551582) (xy 299.279577 -291.600159) (xy 299.280072 -291.624766)
			(xy 299.61892 -291.624766) (xy 299.62288 -291.575712) (xy 299.634657 -291.527928) (xy 299.653948 -291.482652)
			(xy 299.680251 -291.441056) (xy 299.712886 -291.404219) (xy 299.751007 -291.373094) (xy 299.793628 -291.348487)
			(xy 299.839644 -291.331035) (xy 299.887863 -291.321191) (xy 299.937038 -291.31921) (xy 299.985893 -291.325142)
			(xy 300.033164 -291.338834) (xy 300.077626 -291.359932) (xy 300.118129 -291.387888) (xy 300.153622 -291.42198)
			(xy 300.183187 -291.461324) (xy 300.206058 -291.504901) (xy 300.221642 -291.551582) (xy 300.229537 -291.600159)
			(xy 300.230032 -291.624766) (xy 300.56888 -291.624766) (xy 300.57284 -291.575712) (xy 300.584617 -291.527928)
			(xy 300.603908 -291.482652) (xy 300.630211 -291.441056) (xy 300.662846 -291.404219) (xy 300.700967 -291.373094)
			(xy 300.743588 -291.348487) (xy 300.789604 -291.331035) (xy 300.837823 -291.321191) (xy 300.886998 -291.31921)
			(xy 300.935853 -291.325142) (xy 300.983124 -291.338834) (xy 301.027586 -291.359932) (xy 301.068089 -291.387888)
			(xy 301.103582 -291.42198) (xy 301.133147 -291.461324) (xy 301.156018 -291.504901) (xy 301.171602 -291.551582)
			(xy 301.179497 -291.600159) (xy 301.179992 -291.624766) (xy 301.519094 -291.624766) (xy 301.523054 -291.575712)
			(xy 301.534831 -291.527928) (xy 301.554122 -291.482652) (xy 301.580425 -291.441056) (xy 301.61306 -291.404219)
			(xy 301.651181 -291.373094) (xy 301.693802 -291.348487) (xy 301.739818 -291.331035) (xy 301.788037 -291.321191)
			(xy 301.837212 -291.31921) (xy 301.886067 -291.325142) (xy 301.933338 -291.338834) (xy 301.9778 -291.359932)
			(xy 302.018303 -291.387888) (xy 302.053796 -291.42198) (xy 302.083361 -291.461324) (xy 302.106232 -291.504901)
			(xy 302.121816 -291.551582) (xy 302.129711 -291.600159) (xy 302.130206 -291.624766) (xy 302.469054 -291.624766)
			(xy 302.473014 -291.575712) (xy 302.484791 -291.527928) (xy 302.504082 -291.482652) (xy 302.530385 -291.441056)
			(xy 302.56302 -291.404219) (xy 302.601141 -291.373094) (xy 302.643762 -291.348487) (xy 302.689778 -291.331035)
			(xy 302.737997 -291.321191) (xy 302.787172 -291.31921) (xy 302.836027 -291.325142) (xy 302.883298 -291.338834)
			(xy 302.92776 -291.359932) (xy 302.968263 -291.387888) (xy 303.003756 -291.42198) (xy 303.033321 -291.461324)
			(xy 303.056192 -291.504901) (xy 303.071776 -291.551582) (xy 303.079671 -291.600159) (xy 303.080166 -291.624766)
			(xy 303.419014 -291.624766) (xy 303.422974 -291.575712) (xy 303.434751 -291.527928) (xy 303.454042 -291.482652)
			(xy 303.480345 -291.441056) (xy 303.51298 -291.404219) (xy 303.551101 -291.373094) (xy 303.593722 -291.348487)
			(xy 303.639738 -291.331035) (xy 303.687957 -291.321191) (xy 303.737132 -291.31921) (xy 303.785987 -291.325142)
			(xy 303.833258 -291.338834) (xy 303.87772 -291.359932) (xy 303.918223 -291.387888) (xy 303.953716 -291.42198)
			(xy 303.983281 -291.461324) (xy 304.006152 -291.504901) (xy 304.021736 -291.551582) (xy 304.029631 -291.600159)
			(xy 304.030126 -291.624766) (xy 304.368974 -291.624766) (xy 304.372934 -291.575712) (xy 304.384711 -291.527928)
			(xy 304.404002 -291.482652) (xy 304.430305 -291.441056) (xy 304.46294 -291.404219) (xy 304.501061 -291.373094)
			(xy 304.543682 -291.348487) (xy 304.589698 -291.331035) (xy 304.637917 -291.321191) (xy 304.687092 -291.31921)
			(xy 304.735947 -291.325142) (xy 304.783218 -291.338834) (xy 304.82768 -291.359932) (xy 304.868183 -291.387888)
			(xy 304.903676 -291.42198) (xy 304.933241 -291.461324) (xy 304.956112 -291.504901) (xy 304.971696 -291.551582)
			(xy 304.979591 -291.600159) (xy 304.980086 -291.624766) (xy 305.318934 -291.624766) (xy 305.322894 -291.575712)
			(xy 305.334671 -291.527928) (xy 305.353962 -291.482652) (xy 305.380265 -291.441056) (xy 305.4129 -291.404219)
			(xy 305.451021 -291.373094) (xy 305.493642 -291.348487) (xy 305.539658 -291.331035) (xy 305.587877 -291.321191)
			(xy 305.637052 -291.31921) (xy 305.685907 -291.325142) (xy 305.733178 -291.338834) (xy 305.77764 -291.359932)
			(xy 305.818143 -291.387888) (xy 305.853636 -291.42198) (xy 305.883201 -291.461324) (xy 305.906072 -291.504901)
			(xy 305.921656 -291.551582) (xy 305.929551 -291.600159) (xy 305.930046 -291.624766) (xy 306.269148 -291.624766)
			(xy 306.273108 -291.575712) (xy 306.284885 -291.527928) (xy 306.304176 -291.482652) (xy 306.330479 -291.441056)
			(xy 306.363114 -291.404219) (xy 306.401235 -291.373094) (xy 306.443856 -291.348487) (xy 306.489872 -291.331035)
			(xy 306.538091 -291.321191) (xy 306.587266 -291.31921) (xy 306.636121 -291.325142) (xy 306.683392 -291.338834)
			(xy 306.727854 -291.359932) (xy 306.768357 -291.387888) (xy 306.80385 -291.42198) (xy 306.833415 -291.461324)
			(xy 306.856286 -291.504901) (xy 306.87187 -291.551582) (xy 306.879765 -291.600159) (xy 306.88026 -291.624766)
			(xy 308.169068 -291.624766) (xy 308.173028 -291.575712) (xy 308.184805 -291.527928) (xy 308.204096 -291.482652)
			(xy 308.230399 -291.441056) (xy 308.263034 -291.404219) (xy 308.301155 -291.373094) (xy 308.343776 -291.348487)
			(xy 308.389792 -291.331035) (xy 308.438011 -291.321191) (xy 308.487186 -291.31921) (xy 308.536041 -291.325142)
			(xy 308.583312 -291.338834) (xy 308.627774 -291.359932) (xy 308.668277 -291.387888) (xy 308.70377 -291.42198)
			(xy 308.733335 -291.461324) (xy 308.756206 -291.504901) (xy 308.77179 -291.551582) (xy 308.779685 -291.600159)
			(xy 308.78018 -291.624766) (xy 309.119028 -291.624766) (xy 309.122988 -291.575712) (xy 309.134765 -291.527928)
			(xy 309.154056 -291.482652) (xy 309.180359 -291.441056) (xy 309.212994 -291.404219) (xy 309.251115 -291.373094)
			(xy 309.293736 -291.348487) (xy 309.339752 -291.331035) (xy 309.387971 -291.321191) (xy 309.437146 -291.31921)
			(xy 309.486001 -291.325142) (xy 309.533272 -291.338834) (xy 309.577734 -291.359932) (xy 309.618237 -291.387888)
			(xy 309.65373 -291.42198) (xy 309.683295 -291.461324) (xy 309.706166 -291.504901) (xy 309.72175 -291.551582)
			(xy 309.729645 -291.600159) (xy 309.73014 -291.624766) (xy 310.068988 -291.624766) (xy 310.072948 -291.575712)
			(xy 310.084725 -291.527928) (xy 310.104016 -291.482652) (xy 310.130319 -291.441056) (xy 310.162954 -291.404219)
			(xy 310.201075 -291.373094) (xy 310.243696 -291.348487) (xy 310.289712 -291.331035) (xy 310.337931 -291.321191)
			(xy 310.387106 -291.31921) (xy 310.435961 -291.325142) (xy 310.483232 -291.338834) (xy 310.527694 -291.359932)
			(xy 310.568197 -291.387888) (xy 310.60369 -291.42198) (xy 310.633255 -291.461324) (xy 310.656126 -291.504901)
			(xy 310.67171 -291.551582) (xy 310.679605 -291.600159) (xy 310.6801 -291.624766) (xy 311.018948 -291.624766)
			(xy 311.022908 -291.575712) (xy 311.034685 -291.527928) (xy 311.053976 -291.482652) (xy 311.080279 -291.441056)
			(xy 311.112914 -291.404219) (xy 311.151035 -291.373094) (xy 311.193656 -291.348487) (xy 311.239672 -291.331035)
			(xy 311.287891 -291.321191) (xy 311.337066 -291.31921) (xy 311.385921 -291.325142) (xy 311.433192 -291.338834)
			(xy 311.477654 -291.359932) (xy 311.518157 -291.387888) (xy 311.55365 -291.42198) (xy 311.583215 -291.461324)
			(xy 311.606086 -291.504901) (xy 311.62167 -291.551582) (xy 311.629565 -291.600159) (xy 311.63006 -291.624766)
			(xy 311.968908 -291.624766) (xy 311.972868 -291.575712) (xy 311.984645 -291.527928) (xy 312.003936 -291.482652)
			(xy 312.030239 -291.441056) (xy 312.062874 -291.404219) (xy 312.100995 -291.373094) (xy 312.143616 -291.348487)
			(xy 312.189632 -291.331035) (xy 312.237851 -291.321191) (xy 312.287026 -291.31921) (xy 312.335881 -291.325142)
			(xy 312.383152 -291.338834) (xy 312.427614 -291.359932) (xy 312.468117 -291.387888) (xy 312.50361 -291.42198)
			(xy 312.533175 -291.461324) (xy 312.556046 -291.504901) (xy 312.57163 -291.551582) (xy 312.579525 -291.600159)
			(xy 312.58002 -291.624766) (xy 312.919122 -291.624766) (xy 312.923082 -291.575712) (xy 312.934859 -291.527928)
			(xy 312.95415 -291.482652) (xy 312.980453 -291.441056) (xy 313.013088 -291.404219) (xy 313.051209 -291.373094)
			(xy 313.09383 -291.348487) (xy 313.139846 -291.331035) (xy 313.188065 -291.321191) (xy 313.23724 -291.31921)
			(xy 313.286095 -291.325142) (xy 313.333366 -291.338834) (xy 313.377828 -291.359932) (xy 313.418331 -291.387888)
			(xy 313.453824 -291.42198) (xy 313.483389 -291.461324) (xy 313.50626 -291.504901) (xy 313.521844 -291.551582)
			(xy 313.529739 -291.600159) (xy 313.530234 -291.624766) (xy 313.869082 -291.624766) (xy 313.873042 -291.575712)
			(xy 313.884819 -291.527928) (xy 313.90411 -291.482652) (xy 313.930413 -291.441056) (xy 313.963048 -291.404219)
			(xy 314.001169 -291.373094) (xy 314.04379 -291.348487) (xy 314.089806 -291.331035) (xy 314.138025 -291.321191)
			(xy 314.1872 -291.31921) (xy 314.236055 -291.325142) (xy 314.283326 -291.338834) (xy 314.327788 -291.359932)
			(xy 314.368291 -291.387888) (xy 314.403784 -291.42198) (xy 314.433349 -291.461324) (xy 314.45622 -291.504901)
			(xy 314.471804 -291.551582) (xy 314.479699 -291.600159) (xy 314.480194 -291.624766) (xy 314.819042 -291.624766)
			(xy 314.823002 -291.575712) (xy 314.834779 -291.527928) (xy 314.85407 -291.482652) (xy 314.880373 -291.441056)
			(xy 314.913008 -291.404219) (xy 314.951129 -291.373094) (xy 314.99375 -291.348487) (xy 315.039766 -291.331035)
			(xy 315.087985 -291.321191) (xy 315.13716 -291.31921) (xy 315.186015 -291.325142) (xy 315.233286 -291.338834)
			(xy 315.277748 -291.359932) (xy 315.318251 -291.387888) (xy 315.353744 -291.42198) (xy 315.383309 -291.461324)
			(xy 315.40618 -291.504901) (xy 315.421764 -291.551582) (xy 315.429659 -291.600159) (xy 315.430154 -291.624766)
			(xy 315.429659 -291.649373) (xy 315.421764 -291.69795) (xy 315.40618 -291.744631) (xy 315.383309 -291.788208)
			(xy 315.353744 -291.827552) (xy 315.318251 -291.861644) (xy 315.277748 -291.8896) (xy 315.233286 -291.910698)
			(xy 315.186015 -291.92439) (xy 315.13716 -291.930322) (xy 315.087985 -291.928341) (xy 315.039766 -291.918497)
			(xy 314.99375 -291.901045) (xy 314.951129 -291.876438) (xy 314.913008 -291.845313) (xy 314.880373 -291.808476)
			(xy 314.85407 -291.76688) (xy 314.834779 -291.721604) (xy 314.823002 -291.67382) (xy 314.819042 -291.624766)
			(xy 314.480194 -291.624766) (xy 314.479699 -291.649373) (xy 314.471804 -291.69795) (xy 314.45622 -291.744631)
			(xy 314.433349 -291.788208) (xy 314.403784 -291.827552) (xy 314.368291 -291.861644) (xy 314.327788 -291.8896)
			(xy 314.283326 -291.910698) (xy 314.236055 -291.92439) (xy 314.1872 -291.930322) (xy 314.138025 -291.928341)
			(xy 314.089806 -291.918497) (xy 314.04379 -291.901045) (xy 314.001169 -291.876438) (xy 313.963048 -291.845313)
			(xy 313.930413 -291.808476) (xy 313.90411 -291.76688) (xy 313.884819 -291.721604) (xy 313.873042 -291.67382)
			(xy 313.869082 -291.624766) (xy 313.530234 -291.624766) (xy 313.529739 -291.649373) (xy 313.521844 -291.69795)
			(xy 313.50626 -291.744631) (xy 313.483389 -291.788208) (xy 313.453824 -291.827552) (xy 313.418331 -291.861644)
			(xy 313.377828 -291.8896) (xy 313.333366 -291.910698) (xy 313.286095 -291.92439) (xy 313.23724 -291.930322)
			(xy 313.188065 -291.928341) (xy 313.139846 -291.918497) (xy 313.09383 -291.901045) (xy 313.051209 -291.876438)
			(xy 313.013088 -291.845313) (xy 312.980453 -291.808476) (xy 312.95415 -291.76688) (xy 312.934859 -291.721604)
			(xy 312.923082 -291.67382) (xy 312.919122 -291.624766) (xy 312.58002 -291.624766) (xy 312.579525 -291.649373)
			(xy 312.57163 -291.69795) (xy 312.556046 -291.744631) (xy 312.533175 -291.788208) (xy 312.50361 -291.827552)
			(xy 312.468117 -291.861644) (xy 312.427614 -291.8896) (xy 312.383152 -291.910698) (xy 312.335881 -291.92439)
			(xy 312.287026 -291.930322) (xy 312.237851 -291.928341) (xy 312.189632 -291.918497) (xy 312.143616 -291.901045)
			(xy 312.100995 -291.876438) (xy 312.062874 -291.845313) (xy 312.030239 -291.808476) (xy 312.003936 -291.76688)
			(xy 311.984645 -291.721604) (xy 311.972868 -291.67382) (xy 311.968908 -291.624766) (xy 311.63006 -291.624766)
			(xy 311.629565 -291.649373) (xy 311.62167 -291.69795) (xy 311.606086 -291.744631) (xy 311.583215 -291.788208)
			(xy 311.55365 -291.827552) (xy 311.518157 -291.861644) (xy 311.477654 -291.8896) (xy 311.433192 -291.910698)
			(xy 311.385921 -291.92439) (xy 311.337066 -291.930322) (xy 311.287891 -291.928341) (xy 311.239672 -291.918497)
			(xy 311.193656 -291.901045) (xy 311.151035 -291.876438) (xy 311.112914 -291.845313) (xy 311.080279 -291.808476)
			(xy 311.053976 -291.76688) (xy 311.034685 -291.721604) (xy 311.022908 -291.67382) (xy 311.018948 -291.624766)
			(xy 310.6801 -291.624766) (xy 310.679605 -291.649373) (xy 310.67171 -291.69795) (xy 310.656126 -291.744631)
			(xy 310.633255 -291.788208) (xy 310.60369 -291.827552) (xy 310.568197 -291.861644) (xy 310.527694 -291.8896)
			(xy 310.483232 -291.910698) (xy 310.435961 -291.92439) (xy 310.387106 -291.930322) (xy 310.337931 -291.928341)
			(xy 310.289712 -291.918497) (xy 310.243696 -291.901045) (xy 310.201075 -291.876438) (xy 310.162954 -291.845313)
			(xy 310.130319 -291.808476) (xy 310.104016 -291.76688) (xy 310.084725 -291.721604) (xy 310.072948 -291.67382)
			(xy 310.068988 -291.624766) (xy 309.73014 -291.624766) (xy 309.729645 -291.649373) (xy 309.72175 -291.69795)
			(xy 309.706166 -291.744631) (xy 309.683295 -291.788208) (xy 309.65373 -291.827552) (xy 309.618237 -291.861644)
			(xy 309.577734 -291.8896) (xy 309.533272 -291.910698) (xy 309.486001 -291.92439) (xy 309.437146 -291.930322)
			(xy 309.387971 -291.928341) (xy 309.339752 -291.918497) (xy 309.293736 -291.901045) (xy 309.251115 -291.876438)
			(xy 309.212994 -291.845313) (xy 309.180359 -291.808476) (xy 309.154056 -291.76688) (xy 309.134765 -291.721604)
			(xy 309.122988 -291.67382) (xy 309.119028 -291.624766) (xy 308.78018 -291.624766) (xy 308.779685 -291.649373)
			(xy 308.77179 -291.69795) (xy 308.756206 -291.744631) (xy 308.733335 -291.788208) (xy 308.70377 -291.827552)
			(xy 308.668277 -291.861644) (xy 308.627774 -291.8896) (xy 308.583312 -291.910698) (xy 308.536041 -291.92439)
			(xy 308.487186 -291.930322) (xy 308.438011 -291.928341) (xy 308.389792 -291.918497) (xy 308.343776 -291.901045)
			(xy 308.301155 -291.876438) (xy 308.263034 -291.845313) (xy 308.230399 -291.808476) (xy 308.204096 -291.76688)
			(xy 308.184805 -291.721604) (xy 308.173028 -291.67382) (xy 308.169068 -291.624766) (xy 306.88026 -291.624766)
			(xy 306.879765 -291.649373) (xy 306.87187 -291.69795) (xy 306.856286 -291.744631) (xy 306.833415 -291.788208)
			(xy 306.80385 -291.827552) (xy 306.768357 -291.861644) (xy 306.727854 -291.8896) (xy 306.683392 -291.910698)
			(xy 306.636121 -291.92439) (xy 306.587266 -291.930322) (xy 306.538091 -291.928341) (xy 306.489872 -291.918497)
			(xy 306.443856 -291.901045) (xy 306.401235 -291.876438) (xy 306.363114 -291.845313) (xy 306.330479 -291.808476)
			(xy 306.304176 -291.76688) (xy 306.284885 -291.721604) (xy 306.273108 -291.67382) (xy 306.269148 -291.624766)
			(xy 305.930046 -291.624766) (xy 305.929551 -291.649373) (xy 305.921656 -291.69795) (xy 305.906072 -291.744631)
			(xy 305.883201 -291.788208) (xy 305.853636 -291.827552) (xy 305.818143 -291.861644) (xy 305.77764 -291.8896)
			(xy 305.733178 -291.910698) (xy 305.685907 -291.92439) (xy 305.637052 -291.930322) (xy 305.587877 -291.928341)
			(xy 305.539658 -291.918497) (xy 305.493642 -291.901045) (xy 305.451021 -291.876438) (xy 305.4129 -291.845313)
			(xy 305.380265 -291.808476) (xy 305.353962 -291.76688) (xy 305.334671 -291.721604) (xy 305.322894 -291.67382)
			(xy 305.318934 -291.624766) (xy 304.980086 -291.624766) (xy 304.979591 -291.649373) (xy 304.971696 -291.69795)
			(xy 304.956112 -291.744631) (xy 304.933241 -291.788208) (xy 304.903676 -291.827552) (xy 304.868183 -291.861644)
			(xy 304.82768 -291.8896) (xy 304.783218 -291.910698) (xy 304.735947 -291.92439) (xy 304.687092 -291.930322)
			(xy 304.637917 -291.928341) (xy 304.589698 -291.918497) (xy 304.543682 -291.901045) (xy 304.501061 -291.876438)
			(xy 304.46294 -291.845313) (xy 304.430305 -291.808476) (xy 304.404002 -291.76688) (xy 304.384711 -291.721604)
			(xy 304.372934 -291.67382) (xy 304.368974 -291.624766) (xy 304.030126 -291.624766) (xy 304.029631 -291.649373)
			(xy 304.021736 -291.69795) (xy 304.006152 -291.744631) (xy 303.983281 -291.788208) (xy 303.953716 -291.827552)
			(xy 303.918223 -291.861644) (xy 303.87772 -291.8896) (xy 303.833258 -291.910698) (xy 303.785987 -291.92439)
			(xy 303.737132 -291.930322) (xy 303.687957 -291.928341) (xy 303.639738 -291.918497) (xy 303.593722 -291.901045)
			(xy 303.551101 -291.876438) (xy 303.51298 -291.845313) (xy 303.480345 -291.808476) (xy 303.454042 -291.76688)
			(xy 303.434751 -291.721604) (xy 303.422974 -291.67382) (xy 303.419014 -291.624766) (xy 303.080166 -291.624766)
			(xy 303.079671 -291.649373) (xy 303.071776 -291.69795) (xy 303.056192 -291.744631) (xy 303.033321 -291.788208)
			(xy 303.003756 -291.827552) (xy 302.968263 -291.861644) (xy 302.92776 -291.8896) (xy 302.883298 -291.910698)
			(xy 302.836027 -291.92439) (xy 302.787172 -291.930322) (xy 302.737997 -291.928341) (xy 302.689778 -291.918497)
			(xy 302.643762 -291.901045) (xy 302.601141 -291.876438) (xy 302.56302 -291.845313) (xy 302.530385 -291.808476)
			(xy 302.504082 -291.76688) (xy 302.484791 -291.721604) (xy 302.473014 -291.67382) (xy 302.469054 -291.624766)
			(xy 302.130206 -291.624766) (xy 302.129711 -291.649373) (xy 302.121816 -291.69795) (xy 302.106232 -291.744631)
			(xy 302.083361 -291.788208) (xy 302.053796 -291.827552) (xy 302.018303 -291.861644) (xy 301.9778 -291.8896)
			(xy 301.933338 -291.910698) (xy 301.886067 -291.92439) (xy 301.837212 -291.930322) (xy 301.788037 -291.928341)
			(xy 301.739818 -291.918497) (xy 301.693802 -291.901045) (xy 301.651181 -291.876438) (xy 301.61306 -291.845313)
			(xy 301.580425 -291.808476) (xy 301.554122 -291.76688) (xy 301.534831 -291.721604) (xy 301.523054 -291.67382)
			(xy 301.519094 -291.624766) (xy 301.179992 -291.624766) (xy 301.179497 -291.649373) (xy 301.171602 -291.69795)
			(xy 301.156018 -291.744631) (xy 301.133147 -291.788208) (xy 301.103582 -291.827552) (xy 301.068089 -291.861644)
			(xy 301.027586 -291.8896) (xy 300.983124 -291.910698) (xy 300.935853 -291.92439) (xy 300.886998 -291.930322)
			(xy 300.837823 -291.928341) (xy 300.789604 -291.918497) (xy 300.743588 -291.901045) (xy 300.700967 -291.876438)
			(xy 300.662846 -291.845313) (xy 300.630211 -291.808476) (xy 300.603908 -291.76688) (xy 300.584617 -291.721604)
			(xy 300.57284 -291.67382) (xy 300.56888 -291.624766) (xy 300.230032 -291.624766) (xy 300.229537 -291.649373)
			(xy 300.221642 -291.69795) (xy 300.206058 -291.744631) (xy 300.183187 -291.788208) (xy 300.153622 -291.827552)
			(xy 300.118129 -291.861644) (xy 300.077626 -291.8896) (xy 300.033164 -291.910698) (xy 299.985893 -291.92439)
			(xy 299.937038 -291.930322) (xy 299.887863 -291.928341) (xy 299.839644 -291.918497) (xy 299.793628 -291.901045)
			(xy 299.751007 -291.876438) (xy 299.712886 -291.845313) (xy 299.680251 -291.808476) (xy 299.653948 -291.76688)
			(xy 299.634657 -291.721604) (xy 299.62288 -291.67382) (xy 299.61892 -291.624766) (xy 299.280072 -291.624766)
			(xy 299.279577 -291.649373) (xy 299.271682 -291.69795) (xy 299.256098 -291.744631) (xy 299.233227 -291.788208)
			(xy 299.203662 -291.827552) (xy 299.168169 -291.861644) (xy 299.127666 -291.8896) (xy 299.083204 -291.910698)
			(xy 299.035933 -291.92439) (xy 298.987078 -291.930322) (xy 298.937903 -291.928341) (xy 298.889684 -291.918497)
			(xy 298.843668 -291.901045) (xy 298.801047 -291.876438) (xy 298.762926 -291.845313) (xy 298.730291 -291.808476)
			(xy 298.703988 -291.76688) (xy 298.684697 -291.721604) (xy 298.67292 -291.67382) (xy 298.66896 -291.624766)
			(xy 298.330112 -291.624766) (xy 298.329617 -291.649373) (xy 298.321722 -291.69795) (xy 298.306138 -291.744631)
			(xy 298.283267 -291.788208) (xy 298.253702 -291.827552) (xy 298.218209 -291.861644) (xy 298.177706 -291.8896)
			(xy 298.133244 -291.910698) (xy 298.085973 -291.92439) (xy 298.037118 -291.930322) (xy 297.987943 -291.928341)
			(xy 297.939724 -291.918497) (xy 297.893708 -291.901045) (xy 297.851087 -291.876438) (xy 297.812966 -291.845313)
			(xy 297.780331 -291.808476) (xy 297.754028 -291.76688) (xy 297.734737 -291.721604) (xy 297.72296 -291.67382)
			(xy 297.719 -291.624766) (xy 297.380152 -291.624766) (xy 297.379657 -291.649373) (xy 297.371762 -291.69795)
			(xy 297.356178 -291.744631) (xy 297.333307 -291.788208) (xy 297.303742 -291.827552) (xy 297.268249 -291.861644)
			(xy 297.227746 -291.8896) (xy 297.183284 -291.910698) (xy 297.136013 -291.92439) (xy 297.087158 -291.930322)
			(xy 297.037983 -291.928341) (xy 296.989764 -291.918497) (xy 296.943748 -291.901045) (xy 296.901127 -291.876438)
			(xy 296.863006 -291.845313) (xy 296.830371 -291.808476) (xy 296.804068 -291.76688) (xy 296.784777 -291.721604)
			(xy 296.773 -291.67382) (xy 296.76904 -291.624766) (xy 296.430192 -291.624766) (xy 296.429697 -291.649373)
			(xy 296.421802 -291.69795) (xy 296.406218 -291.744631) (xy 296.383347 -291.788208) (xy 296.353782 -291.827552)
			(xy 296.318289 -291.861644) (xy 296.277786 -291.8896) (xy 296.233324 -291.910698) (xy 296.186053 -291.92439)
			(xy 296.137198 -291.930322) (xy 296.088023 -291.928341) (xy 296.039804 -291.918497) (xy 295.993788 -291.901045)
			(xy 295.951167 -291.876438) (xy 295.913046 -291.845313) (xy 295.880411 -291.808476) (xy 295.854108 -291.76688)
			(xy 295.834817 -291.721604) (xy 295.82304 -291.67382) (xy 295.81908 -291.624766) (xy 295.480232 -291.624766)
			(xy 295.479737 -291.649373) (xy 295.471842 -291.69795) (xy 295.456258 -291.744631) (xy 295.433387 -291.788208)
			(xy 295.403822 -291.827552) (xy 295.368329 -291.861644) (xy 295.327826 -291.8896) (xy 295.283364 -291.910698)
			(xy 295.236093 -291.92439) (xy 295.187238 -291.930322) (xy 295.138063 -291.928341) (xy 295.089844 -291.918497)
			(xy 295.043828 -291.901045) (xy 295.001207 -291.876438) (xy 294.963086 -291.845313) (xy 294.930451 -291.808476)
			(xy 294.904148 -291.76688) (xy 294.884857 -291.721604) (xy 294.87308 -291.67382) (xy 294.86912 -291.624766)
			(xy 294.530018 -291.624766) (xy 294.529523 -291.649373) (xy 294.521628 -291.69795) (xy 294.506044 -291.744631)
			(xy 294.483173 -291.788208) (xy 294.453608 -291.827552) (xy 294.418115 -291.861644) (xy 294.377612 -291.8896)
			(xy 294.33315 -291.910698) (xy 294.285879 -291.92439) (xy 294.237024 -291.930322) (xy 294.187849 -291.928341)
			(xy 294.13963 -291.918497) (xy 294.093614 -291.901045) (xy 294.050993 -291.876438) (xy 294.012872 -291.845313)
			(xy 293.980237 -291.808476) (xy 293.953934 -291.76688) (xy 293.934643 -291.721604) (xy 293.922866 -291.67382)
			(xy 293.918906 -291.624766) (xy 293.580058 -291.624766) (xy 293.579563 -291.649373) (xy 293.571668 -291.69795)
			(xy 293.556084 -291.744631) (xy 293.533213 -291.788208) (xy 293.503648 -291.827552) (xy 293.468155 -291.861644)
			(xy 293.427652 -291.8896) (xy 293.38319 -291.910698) (xy 293.335919 -291.92439) (xy 293.287064 -291.930322)
			(xy 293.237889 -291.928341) (xy 293.18967 -291.918497) (xy 293.143654 -291.901045) (xy 293.101033 -291.876438)
			(xy 293.062912 -291.845313) (xy 293.030277 -291.808476) (xy 293.003974 -291.76688) (xy 292.984683 -291.721604)
			(xy 292.972906 -291.67382) (xy 292.968946 -291.624766) (xy 292.630098 -291.624766) (xy 292.629603 -291.649373)
			(xy 292.621708 -291.69795) (xy 292.606124 -291.744631) (xy 292.583253 -291.788208) (xy 292.553688 -291.827552)
			(xy 292.518195 -291.861644) (xy 292.477692 -291.8896) (xy 292.43323 -291.910698) (xy 292.385959 -291.92439)
			(xy 292.337104 -291.930322) (xy 292.287929 -291.928341) (xy 292.23971 -291.918497) (xy 292.193694 -291.901045)
			(xy 292.151073 -291.876438) (xy 292.112952 -291.845313) (xy 292.080317 -291.808476) (xy 292.054014 -291.76688)
			(xy 292.034723 -291.721604) (xy 292.022946 -291.67382) (xy 292.018986 -291.624766) (xy 290.730178 -291.624766)
			(xy 290.729683 -291.649373) (xy 290.721788 -291.69795) (xy 290.706204 -291.744631) (xy 290.683333 -291.788208)
			(xy 290.653768 -291.827552) (xy 290.618275 -291.861644) (xy 290.577772 -291.8896) (xy 290.53331 -291.910698)
			(xy 290.486039 -291.92439) (xy 290.437184 -291.930322) (xy 290.388009 -291.928341) (xy 290.33979 -291.918497)
			(xy 290.293774 -291.901045) (xy 290.251153 -291.876438) (xy 290.213032 -291.845313) (xy 290.180397 -291.808476)
			(xy 290.154094 -291.76688) (xy 290.134803 -291.721604) (xy 290.123026 -291.67382) (xy 290.119066 -291.624766)
			(xy 289.780218 -291.624766) (xy 289.779723 -291.649373) (xy 289.771828 -291.69795) (xy 289.756244 -291.744631)
			(xy 289.733373 -291.788208) (xy 289.703808 -291.827552) (xy 289.668315 -291.861644) (xy 289.627812 -291.8896)
			(xy 289.58335 -291.910698) (xy 289.536079 -291.92439) (xy 289.487224 -291.930322) (xy 289.438049 -291.928341)
			(xy 289.38983 -291.918497) (xy 289.343814 -291.901045) (xy 289.301193 -291.876438) (xy 289.263072 -291.845313)
			(xy 289.230437 -291.808476) (xy 289.204134 -291.76688) (xy 289.184843 -291.721604) (xy 289.173066 -291.67382)
			(xy 289.169106 -291.624766) (xy 288.830004 -291.624766) (xy 288.829509 -291.649373) (xy 288.821614 -291.69795)
			(xy 288.80603 -291.744631) (xy 288.783159 -291.788208) (xy 288.753594 -291.827552) (xy 288.718101 -291.861644)
			(xy 288.677598 -291.8896) (xy 288.633136 -291.910698) (xy 288.585865 -291.92439) (xy 288.53701 -291.930322)
			(xy 288.487835 -291.928341) (xy 288.439616 -291.918497) (xy 288.3936 -291.901045) (xy 288.350979 -291.876438)
			(xy 288.312858 -291.845313) (xy 288.280223 -291.808476) (xy 288.25392 -291.76688) (xy 288.234629 -291.721604)
			(xy 288.222852 -291.67382) (xy 288.218892 -291.624766) (xy 287.880044 -291.624766) (xy 287.879549 -291.649373)
			(xy 287.871654 -291.69795) (xy 287.85607 -291.744631) (xy 287.833199 -291.788208) (xy 287.803634 -291.827552)
			(xy 287.768141 -291.861644) (xy 287.727638 -291.8896) (xy 287.683176 -291.910698) (xy 287.635905 -291.92439)
			(xy 287.58705 -291.930322) (xy 287.537875 -291.928341) (xy 287.489656 -291.918497) (xy 287.44364 -291.901045)
			(xy 287.401019 -291.876438) (xy 287.362898 -291.845313) (xy 287.330263 -291.808476) (xy 287.30396 -291.76688)
			(xy 287.284669 -291.721604) (xy 287.272892 -291.67382) (xy 287.268932 -291.624766) (xy 286.930084 -291.624766)
			(xy 286.929589 -291.649373) (xy 286.921694 -291.69795) (xy 286.90611 -291.744631) (xy 286.883239 -291.788208)
			(xy 286.853674 -291.827552) (xy 286.818181 -291.861644) (xy 286.777678 -291.8896) (xy 286.733216 -291.910698)
			(xy 286.685945 -291.92439) (xy 286.63709 -291.930322) (xy 286.587915 -291.928341) (xy 286.539696 -291.918497)
			(xy 286.49368 -291.901045) (xy 286.451059 -291.876438) (xy 286.412938 -291.845313) (xy 286.380303 -291.808476)
			(xy 286.354 -291.76688) (xy 286.334709 -291.721604) (xy 286.322932 -291.67382) (xy 286.318972 -291.624766)
			(xy 285.980124 -291.624766) (xy 285.979629 -291.649373) (xy 285.971734 -291.69795) (xy 285.95615 -291.744631)
			(xy 285.933279 -291.788208) (xy 285.903714 -291.827552) (xy 285.868221 -291.861644) (xy 285.827718 -291.8896)
			(xy 285.783256 -291.910698) (xy 285.735985 -291.92439) (xy 285.68713 -291.930322) (xy 285.637955 -291.928341)
			(xy 285.589736 -291.918497) (xy 285.54372 -291.901045) (xy 285.501099 -291.876438) (xy 285.462978 -291.845313)
			(xy 285.430343 -291.808476) (xy 285.40404 -291.76688) (xy 285.384749 -291.721604) (xy 285.372972 -291.67382)
			(xy 285.369012 -291.624766) (xy 285.030164 -291.624766) (xy 285.029669 -291.649373) (xy 285.021774 -291.69795)
			(xy 285.00619 -291.744631) (xy 284.983319 -291.788208) (xy 284.953754 -291.827552) (xy 284.918261 -291.861644)
			(xy 284.877758 -291.8896) (xy 284.833296 -291.910698) (xy 284.786025 -291.92439) (xy 284.73717 -291.930322)
			(xy 284.687995 -291.928341) (xy 284.639776 -291.918497) (xy 284.59376 -291.901045) (xy 284.551139 -291.876438)
			(xy 284.513018 -291.845313) (xy 284.480383 -291.808476) (xy 284.45408 -291.76688) (xy 284.434789 -291.721604)
			(xy 284.423012 -291.67382) (xy 284.419052 -291.624766) (xy 284.080204 -291.624766) (xy 284.079709 -291.649373)
			(xy 284.071814 -291.69795) (xy 284.05623 -291.744631) (xy 284.033359 -291.788208) (xy 284.003794 -291.827552)
			(xy 283.968301 -291.861644) (xy 283.927798 -291.8896) (xy 283.883336 -291.910698) (xy 283.836065 -291.92439)
			(xy 283.78721 -291.930322) (xy 283.738035 -291.928341) (xy 283.689816 -291.918497) (xy 283.6438 -291.901045)
			(xy 283.601179 -291.876438) (xy 283.563058 -291.845313) (xy 283.530423 -291.808476) (xy 283.50412 -291.76688)
			(xy 283.484829 -291.721604) (xy 283.473052 -291.67382) (xy 283.469092 -291.624766) (xy 283.130244 -291.624766)
			(xy 283.129749 -291.649373) (xy 283.121854 -291.69795) (xy 283.10627 -291.744631) (xy 283.083399 -291.788208)
			(xy 283.053834 -291.827552) (xy 283.018341 -291.861644) (xy 282.977838 -291.8896) (xy 282.933376 -291.910698)
			(xy 282.886105 -291.92439) (xy 282.83725 -291.930322) (xy 282.788075 -291.928341) (xy 282.739856 -291.918497)
			(xy 282.69384 -291.901045) (xy 282.651219 -291.876438) (xy 282.613098 -291.845313) (xy 282.580463 -291.808476)
			(xy 282.55416 -291.76688) (xy 282.534869 -291.721604) (xy 282.523092 -291.67382) (xy 282.519132 -291.624766)
			(xy 282.18003 -291.624766) (xy 282.179535 -291.649373) (xy 282.17164 -291.69795) (xy 282.156056 -291.744631)
			(xy 282.133185 -291.788208) (xy 282.10362 -291.827552) (xy 282.068127 -291.861644) (xy 282.027624 -291.8896)
			(xy 281.983162 -291.910698) (xy 281.935891 -291.92439) (xy 281.887036 -291.930322) (xy 281.837861 -291.928341)
			(xy 281.789642 -291.918497) (xy 281.743626 -291.901045) (xy 281.701005 -291.876438) (xy 281.662884 -291.845313)
			(xy 281.630249 -291.808476) (xy 281.603946 -291.76688) (xy 281.584655 -291.721604) (xy 281.572878 -291.67382)
			(xy 281.568918 -291.624766) (xy 281.23007 -291.624766) (xy 281.229575 -291.649373) (xy 281.22168 -291.69795)
			(xy 281.206096 -291.744631) (xy 281.183225 -291.788208) (xy 281.15366 -291.827552) (xy 281.118167 -291.861644)
			(xy 281.077664 -291.8896) (xy 281.033202 -291.910698) (xy 280.985931 -291.92439) (xy 280.937076 -291.930322)
			(xy 280.887901 -291.928341) (xy 280.839682 -291.918497) (xy 280.793666 -291.901045) (xy 280.751045 -291.876438)
			(xy 280.712924 -291.845313) (xy 280.680289 -291.808476) (xy 280.653986 -291.76688) (xy 280.634695 -291.721604)
			(xy 280.622918 -291.67382) (xy 280.618958 -291.624766) (xy 280.28011 -291.624766) (xy 280.279615 -291.649373)
			(xy 280.27172 -291.69795) (xy 280.256136 -291.744631) (xy 280.233265 -291.788208) (xy 280.2037 -291.827552)
			(xy 280.168207 -291.861644) (xy 280.127704 -291.8896) (xy 280.083242 -291.910698) (xy 280.035971 -291.92439)
			(xy 279.987116 -291.930322) (xy 279.937941 -291.928341) (xy 279.889722 -291.918497) (xy 279.843706 -291.901045)
			(xy 279.801085 -291.876438) (xy 279.762964 -291.845313) (xy 279.730329 -291.808476) (xy 279.704026 -291.76688)
			(xy 279.684735 -291.721604) (xy 279.672958 -291.67382) (xy 279.668998 -291.624766) (xy 279.41397 -291.624766)
			(xy 279.41397 -292.122098) (xy 325.457312 -292.122098) (xy 325.457754 -292.095494) (xy 325.465136 -292.0428)
			(xy 325.479771 -291.991644) (xy 325.501375 -291.943019) (xy 325.529528 -291.897869) (xy 325.563683 -291.85707)
			(xy 325.603177 -291.821415) (xy 325.624952 -291.806122) (xy 325.63639 -291.797731) (xy 325.6546 -291.776003)
			(xy 325.666125 -291.750101) (xy 325.670074 -291.722027) (xy 325.66614 -291.693951) (xy 325.654629 -291.668043)
			(xy 325.63643 -291.646306) (xy 325.624952 -291.637974) (xy 325.603163 -291.622704) (xy 325.563684 -291.587034)
			(xy 325.529542 -291.546226) (xy 325.501398 -291.501072) (xy 325.479799 -291.452447) (xy 325.465163 -291.401293)
			(xy 325.457773 -291.348601) (xy 325.457312 -291.321998) (xy 325.457798 -291.294747) (xy 325.465554 -291.240799)
			(xy 325.480909 -291.188504) (xy 325.503551 -291.138927) (xy 325.533017 -291.093077) (xy 325.568708 -291.051886)
			(xy 325.609899 -291.016195) (xy 325.655749 -290.986729) (xy 325.705326 -290.964087) (xy 325.757621 -290.948732)
			(xy 325.811569 -290.940976) (xy 325.866071 -290.940976) (xy 325.920019 -290.948732) (xy 325.972314 -290.964087)
			(xy 326.021891 -290.986729) (xy 326.067741 -291.016195) (xy 326.108932 -291.051886) (xy 326.144623 -291.093077)
			(xy 326.174089 -291.138927) (xy 326.196731 -291.188504) (xy 326.212086 -291.240799) (xy 326.219842 -291.294747)
			(xy 326.220328 -291.321998) (xy 326.219909 -291.348603) (xy 326.212526 -291.401299) (xy 326.197889 -291.452457)
			(xy 326.176282 -291.501083) (xy 326.148125 -291.546233) (xy 326.113965 -291.587031) (xy 326.074465 -291.622683)
			(xy 326.052688 -291.637974) (xy 326.041162 -291.64625) (xy 326.02296 -291.668007) (xy 326.011447 -291.693934)
			(xy 326.007513 -291.722027) (xy 326.011462 -291.750118) (xy 326.022988 -291.776039) (xy 326.041202 -291.797786)
			(xy 326.052688 -291.806122) (xy 326.074484 -291.821382) (xy 326.113961 -291.857055) (xy 326.148101 -291.897865)
			(xy 326.176243 -291.943021) (xy 326.197842 -291.991648) (xy 326.212477 -292.042803) (xy 326.219867 -292.095494)
			(xy 326.220328 -292.122098) (xy 326.219842 -292.149349) (xy 326.212086 -292.203297) (xy 326.196731 -292.255592)
			(xy 326.174089 -292.305169) (xy 326.144623 -292.351019) (xy 326.108932 -292.39221) (xy 326.067741 -292.427901)
			(xy 326.021891 -292.457367) (xy 325.972314 -292.480009) (xy 325.920019 -292.495364) (xy 325.866071 -292.50312)
			(xy 325.811569 -292.50312) (xy 325.757621 -292.495364) (xy 325.705326 -292.480009) (xy 325.655749 -292.457367)
			(xy 325.609899 -292.427901) (xy 325.568708 -292.39221) (xy 325.533017 -292.351019) (xy 325.503551 -292.305169)
			(xy 325.480909 -292.255592) (xy 325.465554 -292.203297) (xy 325.457798 -292.149349) (xy 325.457312 -292.122098)
			(xy 279.41397 -292.122098) (xy 279.41397 -292.57498) (xy 279.668998 -292.57498) (xy 279.672958 -292.525926)
			(xy 279.684735 -292.478142) (xy 279.704026 -292.432866) (xy 279.730329 -292.39127) (xy 279.762964 -292.354433)
			(xy 279.801085 -292.323308) (xy 279.843706 -292.298701) (xy 279.889722 -292.281249) (xy 279.937941 -292.271405)
			(xy 279.987116 -292.269424) (xy 280.035971 -292.275356) (xy 280.083242 -292.289048) (xy 280.127704 -292.310146)
			(xy 280.168207 -292.338102) (xy 280.2037 -292.372194) (xy 280.233265 -292.411538) (xy 280.256136 -292.455115)
			(xy 280.27172 -292.501796) (xy 280.279615 -292.550373) (xy 280.280105 -292.574726) (xy 280.618958 -292.574726)
			(xy 280.622918 -292.525672) (xy 280.634695 -292.477888) (xy 280.653986 -292.432612) (xy 280.680289 -292.391016)
			(xy 280.712924 -292.354179) (xy 280.751045 -292.323054) (xy 280.793666 -292.298447) (xy 280.839682 -292.280995)
			(xy 280.887901 -292.271151) (xy 280.937076 -292.26917) (xy 280.985931 -292.275102) (xy 281.033202 -292.288794)
			(xy 281.077664 -292.309892) (xy 281.118167 -292.337848) (xy 281.15366 -292.37194) (xy 281.183225 -292.411284)
			(xy 281.206096 -292.454861) (xy 281.22168 -292.501542) (xy 281.229575 -292.550119) (xy 281.23007 -292.574726)
			(xy 281.568918 -292.574726) (xy 281.572878 -292.525672) (xy 281.584655 -292.477888) (xy 281.603946 -292.432612)
			(xy 281.630249 -292.391016) (xy 281.662884 -292.354179) (xy 281.701005 -292.323054) (xy 281.743626 -292.298447)
			(xy 281.789642 -292.280995) (xy 281.837861 -292.271151) (xy 281.887036 -292.26917) (xy 281.935891 -292.275102)
			(xy 281.983162 -292.288794) (xy 282.027624 -292.309892) (xy 282.068127 -292.337848) (xy 282.10362 -292.37194)
			(xy 282.133185 -292.411284) (xy 282.156056 -292.454861) (xy 282.17164 -292.501542) (xy 282.179535 -292.550119)
			(xy 282.18003 -292.574726) (xy 300.56888 -292.574726) (xy 300.57284 -292.525672) (xy 300.584617 -292.477888)
			(xy 300.603908 -292.432612) (xy 300.630211 -292.391016) (xy 300.662846 -292.354179) (xy 300.700967 -292.323054)
			(xy 300.743588 -292.298447) (xy 300.789604 -292.280995) (xy 300.837823 -292.271151) (xy 300.886998 -292.26917)
			(xy 300.935853 -292.275102) (xy 300.983124 -292.288794) (xy 301.027586 -292.309892) (xy 301.068089 -292.337848)
			(xy 301.103582 -292.37194) (xy 301.133147 -292.411284) (xy 301.156018 -292.454861) (xy 301.171602 -292.501542)
			(xy 301.179497 -292.550119) (xy 301.179992 -292.574726) (xy 301.519094 -292.574726) (xy 301.523054 -292.525672)
			(xy 301.534831 -292.477888) (xy 301.554122 -292.432612) (xy 301.580425 -292.391016) (xy 301.61306 -292.354179)
			(xy 301.651181 -292.323054) (xy 301.693802 -292.298447) (xy 301.739818 -292.280995) (xy 301.788037 -292.271151)
			(xy 301.837212 -292.26917) (xy 301.886067 -292.275102) (xy 301.933338 -292.288794) (xy 301.9778 -292.309892)
			(xy 302.018303 -292.337848) (xy 302.053796 -292.37194) (xy 302.083361 -292.411284) (xy 302.106232 -292.454861)
			(xy 302.121816 -292.501542) (xy 302.129711 -292.550119) (xy 302.130206 -292.574726) (xy 302.130201 -292.57498)
			(xy 302.469054 -292.57498) (xy 302.473014 -292.525926) (xy 302.484791 -292.478142) (xy 302.504082 -292.432866)
			(xy 302.530385 -292.39127) (xy 302.56302 -292.354433) (xy 302.601141 -292.323308) (xy 302.643762 -292.298701)
			(xy 302.689778 -292.281249) (xy 302.737997 -292.271405) (xy 302.787172 -292.269424) (xy 302.836027 -292.275356)
			(xy 302.883298 -292.289048) (xy 302.92776 -292.310146) (xy 302.968263 -292.338102) (xy 303.003756 -292.372194)
			(xy 303.033321 -292.411538) (xy 303.056192 -292.455115) (xy 303.071776 -292.501796) (xy 303.079671 -292.550373)
			(xy 303.080161 -292.574726) (xy 303.419014 -292.574726) (xy 303.422974 -292.525672) (xy 303.434751 -292.477888)
			(xy 303.454042 -292.432612) (xy 303.480345 -292.391016) (xy 303.51298 -292.354179) (xy 303.551101 -292.323054)
			(xy 303.593722 -292.298447) (xy 303.639738 -292.280995) (xy 303.687957 -292.271151) (xy 303.737132 -292.26917)
			(xy 303.785987 -292.275102) (xy 303.833258 -292.288794) (xy 303.87772 -292.309892) (xy 303.918223 -292.337848)
			(xy 303.953716 -292.37194) (xy 303.983281 -292.411284) (xy 304.006152 -292.454861) (xy 304.021736 -292.501542)
			(xy 304.029631 -292.550119) (xy 304.030126 -292.574726) (xy 304.368974 -292.574726) (xy 304.372934 -292.525672)
			(xy 304.384711 -292.477888) (xy 304.404002 -292.432612) (xy 304.430305 -292.391016) (xy 304.46294 -292.354179)
			(xy 304.501061 -292.323054) (xy 304.543682 -292.298447) (xy 304.589698 -292.280995) (xy 304.637917 -292.271151)
			(xy 304.687092 -292.26917) (xy 304.735947 -292.275102) (xy 304.783218 -292.288794) (xy 304.82768 -292.309892)
			(xy 304.868183 -292.337848) (xy 304.903676 -292.37194) (xy 304.933241 -292.411284) (xy 304.956112 -292.454861)
			(xy 304.971696 -292.501542) (xy 304.979591 -292.550119) (xy 304.980086 -292.574726) (xy 305.318934 -292.574726)
			(xy 305.322894 -292.525672) (xy 305.334671 -292.477888) (xy 305.353962 -292.432612) (xy 305.380265 -292.391016)
			(xy 305.4129 -292.354179) (xy 305.451021 -292.323054) (xy 305.493642 -292.298447) (xy 305.539658 -292.280995)
			(xy 305.587877 -292.271151) (xy 305.637052 -292.26917) (xy 305.685907 -292.275102) (xy 305.733178 -292.288794)
			(xy 305.77764 -292.309892) (xy 305.818143 -292.337848) (xy 305.853636 -292.37194) (xy 305.883201 -292.411284)
			(xy 305.906072 -292.454861) (xy 305.921656 -292.501542) (xy 305.929551 -292.550119) (xy 305.930046 -292.574726)
			(xy 306.268894 -292.574726) (xy 306.272854 -292.525672) (xy 306.284631 -292.477888) (xy 306.303922 -292.432612)
			(xy 306.330225 -292.391016) (xy 306.36286 -292.354179) (xy 306.400981 -292.323054) (xy 306.443602 -292.298447)
			(xy 306.489618 -292.280995) (xy 306.537837 -292.271151) (xy 306.587012 -292.26917) (xy 306.635867 -292.275102)
			(xy 306.683138 -292.288794) (xy 306.7276 -292.309892) (xy 306.768103 -292.337848) (xy 306.803596 -292.37194)
			(xy 306.833161 -292.411284) (xy 306.856032 -292.454861) (xy 306.871616 -292.501542) (xy 306.879511 -292.550119)
			(xy 306.880006 -292.574726) (xy 307.219108 -292.574726) (xy 307.223068 -292.525672) (xy 307.234845 -292.477888)
			(xy 307.254136 -292.432612) (xy 307.280439 -292.391016) (xy 307.313074 -292.354179) (xy 307.351195 -292.323054)
			(xy 307.393816 -292.298447) (xy 307.439832 -292.280995) (xy 307.488051 -292.271151) (xy 307.537226 -292.26917)
			(xy 307.586081 -292.275102) (xy 307.633352 -292.288794) (xy 307.677814 -292.309892) (xy 307.718317 -292.337848)
			(xy 307.75381 -292.37194) (xy 307.783375 -292.411284) (xy 307.806246 -292.454861) (xy 307.82183 -292.501542)
			(xy 307.829725 -292.550119) (xy 307.83022 -292.574726) (xy 308.169068 -292.574726) (xy 308.173028 -292.525672)
			(xy 308.184805 -292.477888) (xy 308.204096 -292.432612) (xy 308.230399 -292.391016) (xy 308.263034 -292.354179)
			(xy 308.301155 -292.323054) (xy 308.343776 -292.298447) (xy 308.389792 -292.280995) (xy 308.438011 -292.271151)
			(xy 308.487186 -292.26917) (xy 308.536041 -292.275102) (xy 308.583312 -292.288794) (xy 308.627774 -292.309892)
			(xy 308.668277 -292.337848) (xy 308.70377 -292.37194) (xy 308.733335 -292.411284) (xy 308.756206 -292.454861)
			(xy 308.77179 -292.501542) (xy 308.779685 -292.550119) (xy 308.78018 -292.574726) (xy 309.119028 -292.574726)
			(xy 309.122988 -292.525672) (xy 309.134765 -292.477888) (xy 309.154056 -292.432612) (xy 309.180359 -292.391016)
			(xy 309.212994 -292.354179) (xy 309.251115 -292.323054) (xy 309.293736 -292.298447) (xy 309.339752 -292.280995)
			(xy 309.387971 -292.271151) (xy 309.437146 -292.26917) (xy 309.486001 -292.275102) (xy 309.533272 -292.288794)
			(xy 309.577734 -292.309892) (xy 309.618237 -292.337848) (xy 309.65373 -292.37194) (xy 309.683295 -292.411284)
			(xy 309.706166 -292.454861) (xy 309.72175 -292.501542) (xy 309.729645 -292.550119) (xy 309.73014 -292.574726)
			(xy 310.068988 -292.574726) (xy 310.072948 -292.525672) (xy 310.084725 -292.477888) (xy 310.104016 -292.432612)
			(xy 310.130319 -292.391016) (xy 310.162954 -292.354179) (xy 310.201075 -292.323054) (xy 310.243696 -292.298447)
			(xy 310.289712 -292.280995) (xy 310.337931 -292.271151) (xy 310.387106 -292.26917) (xy 310.435961 -292.275102)
			(xy 310.483232 -292.288794) (xy 310.527694 -292.309892) (xy 310.568197 -292.337848) (xy 310.60369 -292.37194)
			(xy 310.633255 -292.411284) (xy 310.656126 -292.454861) (xy 310.67171 -292.501542) (xy 310.679605 -292.550119)
			(xy 310.6801 -292.574726) (xy 311.018948 -292.574726) (xy 311.022908 -292.525672) (xy 311.034685 -292.477888)
			(xy 311.053976 -292.432612) (xy 311.080279 -292.391016) (xy 311.112914 -292.354179) (xy 311.151035 -292.323054)
			(xy 311.193656 -292.298447) (xy 311.239672 -292.280995) (xy 311.287891 -292.271151) (xy 311.337066 -292.26917)
			(xy 311.385921 -292.275102) (xy 311.433192 -292.288794) (xy 311.477654 -292.309892) (xy 311.518157 -292.337848)
			(xy 311.55365 -292.37194) (xy 311.583215 -292.411284) (xy 311.606086 -292.454861) (xy 311.62167 -292.501542)
			(xy 311.629565 -292.550119) (xy 311.63006 -292.574726) (xy 311.968908 -292.574726) (xy 311.972868 -292.525672)
			(xy 311.984645 -292.477888) (xy 312.003936 -292.432612) (xy 312.030239 -292.391016) (xy 312.062874 -292.354179)
			(xy 312.100995 -292.323054) (xy 312.143616 -292.298447) (xy 312.189632 -292.280995) (xy 312.237851 -292.271151)
			(xy 312.287026 -292.26917) (xy 312.335881 -292.275102) (xy 312.383152 -292.288794) (xy 312.427614 -292.309892)
			(xy 312.468117 -292.337848) (xy 312.50361 -292.37194) (xy 312.533175 -292.411284) (xy 312.556046 -292.454861)
			(xy 312.57163 -292.501542) (xy 312.579525 -292.550119) (xy 312.58002 -292.574726) (xy 312.919122 -292.574726)
			(xy 312.923082 -292.525672) (xy 312.934859 -292.477888) (xy 312.95415 -292.432612) (xy 312.980453 -292.391016)
			(xy 313.013088 -292.354179) (xy 313.051209 -292.323054) (xy 313.09383 -292.298447) (xy 313.139846 -292.280995)
			(xy 313.188065 -292.271151) (xy 313.23724 -292.26917) (xy 313.286095 -292.275102) (xy 313.333366 -292.288794)
			(xy 313.377828 -292.309892) (xy 313.418331 -292.337848) (xy 313.453824 -292.37194) (xy 313.483389 -292.411284)
			(xy 313.50626 -292.454861) (xy 313.521844 -292.501542) (xy 313.529739 -292.550119) (xy 313.530234 -292.574726)
			(xy 313.530229 -292.57498) (xy 313.869082 -292.57498) (xy 313.873042 -292.525926) (xy 313.884819 -292.478142)
			(xy 313.90411 -292.432866) (xy 313.930413 -292.39127) (xy 313.963048 -292.354433) (xy 314.001169 -292.323308)
			(xy 314.04379 -292.298701) (xy 314.089806 -292.281249) (xy 314.138025 -292.271405) (xy 314.1872 -292.269424)
			(xy 314.236055 -292.275356) (xy 314.283326 -292.289048) (xy 314.327788 -292.310146) (xy 314.368291 -292.338102)
			(xy 314.403784 -292.372194) (xy 314.433349 -292.411538) (xy 314.45622 -292.455115) (xy 314.471804 -292.501796)
			(xy 314.479699 -292.550373) (xy 314.480194 -292.57498) (xy 314.819042 -292.57498) (xy 314.823002 -292.525926)
			(xy 314.834779 -292.478142) (xy 314.85407 -292.432866) (xy 314.880373 -292.39127) (xy 314.913008 -292.354433)
			(xy 314.951129 -292.323308) (xy 314.99375 -292.298701) (xy 315.039766 -292.281249) (xy 315.087985 -292.271405)
			(xy 315.13716 -292.269424) (xy 315.186015 -292.275356) (xy 315.233286 -292.289048) (xy 315.277748 -292.310146)
			(xy 315.318251 -292.338102) (xy 315.353744 -292.372194) (xy 315.383309 -292.411538) (xy 315.40618 -292.455115)
			(xy 315.421764 -292.501796) (xy 315.429659 -292.550373) (xy 315.430154 -292.57498) (xy 315.429659 -292.599587)
			(xy 315.421764 -292.648164) (xy 315.40618 -292.694845) (xy 315.383309 -292.738422) (xy 315.353744 -292.777766)
			(xy 315.318251 -292.811858) (xy 315.277748 -292.839814) (xy 315.233286 -292.860912) (xy 315.186015 -292.874604)
			(xy 315.13716 -292.880536) (xy 315.087985 -292.878555) (xy 315.039766 -292.868711) (xy 314.99375 -292.851259)
			(xy 314.951129 -292.826652) (xy 314.913008 -292.795527) (xy 314.880373 -292.75869) (xy 314.85407 -292.717094)
			(xy 314.834779 -292.671818) (xy 314.823002 -292.624034) (xy 314.819042 -292.57498) (xy 314.480194 -292.57498)
			(xy 314.479699 -292.599587) (xy 314.471804 -292.648164) (xy 314.45622 -292.694845) (xy 314.433349 -292.738422)
			(xy 314.403784 -292.777766) (xy 314.368291 -292.811858) (xy 314.327788 -292.839814) (xy 314.283326 -292.860912)
			(xy 314.236055 -292.874604) (xy 314.1872 -292.880536) (xy 314.138025 -292.878555) (xy 314.089806 -292.868711)
			(xy 314.04379 -292.851259) (xy 314.001169 -292.826652) (xy 313.963048 -292.795527) (xy 313.930413 -292.75869)
			(xy 313.90411 -292.717094) (xy 313.884819 -292.671818) (xy 313.873042 -292.624034) (xy 313.869082 -292.57498)
			(xy 313.530229 -292.57498) (xy 313.529739 -292.599333) (xy 313.521844 -292.64791) (xy 313.50626 -292.694591)
			(xy 313.483389 -292.738168) (xy 313.453824 -292.777512) (xy 313.418331 -292.811604) (xy 313.377828 -292.83956)
			(xy 313.333366 -292.860658) (xy 313.286095 -292.87435) (xy 313.23724 -292.880282) (xy 313.188065 -292.878301)
			(xy 313.139846 -292.868457) (xy 313.09383 -292.851005) (xy 313.051209 -292.826398) (xy 313.013088 -292.795273)
			(xy 312.980453 -292.758436) (xy 312.95415 -292.71684) (xy 312.934859 -292.671564) (xy 312.923082 -292.62378)
			(xy 312.919122 -292.574726) (xy 312.58002 -292.574726) (xy 312.579525 -292.599333) (xy 312.57163 -292.64791)
			(xy 312.556046 -292.694591) (xy 312.533175 -292.738168) (xy 312.50361 -292.777512) (xy 312.468117 -292.811604)
			(xy 312.427614 -292.83956) (xy 312.383152 -292.860658) (xy 312.335881 -292.87435) (xy 312.287026 -292.880282)
			(xy 312.237851 -292.878301) (xy 312.189632 -292.868457) (xy 312.143616 -292.851005) (xy 312.100995 -292.826398)
			(xy 312.062874 -292.795273) (xy 312.030239 -292.758436) (xy 312.003936 -292.71684) (xy 311.984645 -292.671564)
			(xy 311.972868 -292.62378) (xy 311.968908 -292.574726) (xy 311.63006 -292.574726) (xy 311.629565 -292.599333)
			(xy 311.62167 -292.64791) (xy 311.606086 -292.694591) (xy 311.583215 -292.738168) (xy 311.55365 -292.777512)
			(xy 311.518157 -292.811604) (xy 311.477654 -292.83956) (xy 311.433192 -292.860658) (xy 311.385921 -292.87435)
			(xy 311.337066 -292.880282) (xy 311.287891 -292.878301) (xy 311.239672 -292.868457) (xy 311.193656 -292.851005)
			(xy 311.151035 -292.826398) (xy 311.112914 -292.795273) (xy 311.080279 -292.758436) (xy 311.053976 -292.71684)
			(xy 311.034685 -292.671564) (xy 311.022908 -292.62378) (xy 311.018948 -292.574726) (xy 310.6801 -292.574726)
			(xy 310.679605 -292.599333) (xy 310.67171 -292.64791) (xy 310.656126 -292.694591) (xy 310.633255 -292.738168)
			(xy 310.60369 -292.777512) (xy 310.568197 -292.811604) (xy 310.527694 -292.83956) (xy 310.483232 -292.860658)
			(xy 310.435961 -292.87435) (xy 310.387106 -292.880282) (xy 310.337931 -292.878301) (xy 310.289712 -292.868457)
			(xy 310.243696 -292.851005) (xy 310.201075 -292.826398) (xy 310.162954 -292.795273) (xy 310.130319 -292.758436)
			(xy 310.104016 -292.71684) (xy 310.084725 -292.671564) (xy 310.072948 -292.62378) (xy 310.068988 -292.574726)
			(xy 309.73014 -292.574726) (xy 309.729645 -292.599333) (xy 309.72175 -292.64791) (xy 309.706166 -292.694591)
			(xy 309.683295 -292.738168) (xy 309.65373 -292.777512) (xy 309.618237 -292.811604) (xy 309.577734 -292.83956)
			(xy 309.533272 -292.860658) (xy 309.486001 -292.87435) (xy 309.437146 -292.880282) (xy 309.387971 -292.878301)
			(xy 309.339752 -292.868457) (xy 309.293736 -292.851005) (xy 309.251115 -292.826398) (xy 309.212994 -292.795273)
			(xy 309.180359 -292.758436) (xy 309.154056 -292.71684) (xy 309.134765 -292.671564) (xy 309.122988 -292.62378)
			(xy 309.119028 -292.574726) (xy 308.78018 -292.574726) (xy 308.779685 -292.599333) (xy 308.77179 -292.64791)
			(xy 308.756206 -292.694591) (xy 308.733335 -292.738168) (xy 308.70377 -292.777512) (xy 308.668277 -292.811604)
			(xy 308.627774 -292.83956) (xy 308.583312 -292.860658) (xy 308.536041 -292.87435) (xy 308.487186 -292.880282)
			(xy 308.438011 -292.878301) (xy 308.389792 -292.868457) (xy 308.343776 -292.851005) (xy 308.301155 -292.826398)
			(xy 308.263034 -292.795273) (xy 308.230399 -292.758436) (xy 308.204096 -292.71684) (xy 308.184805 -292.671564)
			(xy 308.173028 -292.62378) (xy 308.169068 -292.574726) (xy 307.83022 -292.574726) (xy 307.829725 -292.599333)
			(xy 307.82183 -292.64791) (xy 307.806246 -292.694591) (xy 307.783375 -292.738168) (xy 307.75381 -292.777512)
			(xy 307.718317 -292.811604) (xy 307.677814 -292.83956) (xy 307.633352 -292.860658) (xy 307.586081 -292.87435)
			(xy 307.537226 -292.880282) (xy 307.488051 -292.878301) (xy 307.439832 -292.868457) (xy 307.393816 -292.851005)
			(xy 307.351195 -292.826398) (xy 307.313074 -292.795273) (xy 307.280439 -292.758436) (xy 307.254136 -292.71684)
			(xy 307.234845 -292.671564) (xy 307.223068 -292.62378) (xy 307.219108 -292.574726) (xy 306.880006 -292.574726)
			(xy 306.879511 -292.599333) (xy 306.871616 -292.64791) (xy 306.856032 -292.694591) (xy 306.833161 -292.738168)
			(xy 306.803596 -292.777512) (xy 306.768103 -292.811604) (xy 306.7276 -292.83956) (xy 306.683138 -292.860658)
			(xy 306.635867 -292.87435) (xy 306.587012 -292.880282) (xy 306.537837 -292.878301) (xy 306.489618 -292.868457)
			(xy 306.443602 -292.851005) (xy 306.400981 -292.826398) (xy 306.36286 -292.795273) (xy 306.330225 -292.758436)
			(xy 306.303922 -292.71684) (xy 306.284631 -292.671564) (xy 306.272854 -292.62378) (xy 306.268894 -292.574726)
			(xy 305.930046 -292.574726) (xy 305.929551 -292.599333) (xy 305.921656 -292.64791) (xy 305.906072 -292.694591)
			(xy 305.883201 -292.738168) (xy 305.853636 -292.777512) (xy 305.818143 -292.811604) (xy 305.77764 -292.83956)
			(xy 305.733178 -292.860658) (xy 305.685907 -292.87435) (xy 305.637052 -292.880282) (xy 305.587877 -292.878301)
			(xy 305.539658 -292.868457) (xy 305.493642 -292.851005) (xy 305.451021 -292.826398) (xy 305.4129 -292.795273)
			(xy 305.380265 -292.758436) (xy 305.353962 -292.71684) (xy 305.334671 -292.671564) (xy 305.322894 -292.62378)
			(xy 305.318934 -292.574726) (xy 304.980086 -292.574726) (xy 304.979591 -292.599333) (xy 304.971696 -292.64791)
			(xy 304.956112 -292.694591) (xy 304.933241 -292.738168) (xy 304.903676 -292.777512) (xy 304.868183 -292.811604)
			(xy 304.82768 -292.83956) (xy 304.783218 -292.860658) (xy 304.735947 -292.87435) (xy 304.687092 -292.880282)
			(xy 304.637917 -292.878301) (xy 304.589698 -292.868457) (xy 304.543682 -292.851005) (xy 304.501061 -292.826398)
			(xy 304.46294 -292.795273) (xy 304.430305 -292.758436) (xy 304.404002 -292.71684) (xy 304.384711 -292.671564)
			(xy 304.372934 -292.62378) (xy 304.368974 -292.574726) (xy 304.030126 -292.574726) (xy 304.029631 -292.599333)
			(xy 304.021736 -292.64791) (xy 304.006152 -292.694591) (xy 303.983281 -292.738168) (xy 303.953716 -292.777512)
			(xy 303.918223 -292.811604) (xy 303.87772 -292.83956) (xy 303.833258 -292.860658) (xy 303.785987 -292.87435)
			(xy 303.737132 -292.880282) (xy 303.687957 -292.878301) (xy 303.639738 -292.868457) (xy 303.593722 -292.851005)
			(xy 303.551101 -292.826398) (xy 303.51298 -292.795273) (xy 303.480345 -292.758436) (xy 303.454042 -292.71684)
			(xy 303.434751 -292.671564) (xy 303.422974 -292.62378) (xy 303.419014 -292.574726) (xy 303.080161 -292.574726)
			(xy 303.080166 -292.57498) (xy 303.079671 -292.599587) (xy 303.071776 -292.648164) (xy 303.056192 -292.694845)
			(xy 303.033321 -292.738422) (xy 303.003756 -292.777766) (xy 302.968263 -292.811858) (xy 302.92776 -292.839814)
			(xy 302.883298 -292.860912) (xy 302.836027 -292.874604) (xy 302.787172 -292.880536) (xy 302.737997 -292.878555)
			(xy 302.689778 -292.868711) (xy 302.643762 -292.851259) (xy 302.601141 -292.826652) (xy 302.56302 -292.795527)
			(xy 302.530385 -292.75869) (xy 302.504082 -292.717094) (xy 302.484791 -292.671818) (xy 302.473014 -292.624034)
			(xy 302.469054 -292.57498) (xy 302.130201 -292.57498) (xy 302.129711 -292.599333) (xy 302.121816 -292.64791)
			(xy 302.106232 -292.694591) (xy 302.083361 -292.738168) (xy 302.053796 -292.777512) (xy 302.018303 -292.811604)
			(xy 301.9778 -292.83956) (xy 301.933338 -292.860658) (xy 301.886067 -292.87435) (xy 301.837212 -292.880282)
			(xy 301.788037 -292.878301) (xy 301.739818 -292.868457) (xy 301.693802 -292.851005) (xy 301.651181 -292.826398)
			(xy 301.61306 -292.795273) (xy 301.580425 -292.758436) (xy 301.554122 -292.71684) (xy 301.534831 -292.671564)
			(xy 301.523054 -292.62378) (xy 301.519094 -292.574726) (xy 301.179992 -292.574726) (xy 301.179497 -292.599333)
			(xy 301.171602 -292.64791) (xy 301.156018 -292.694591) (xy 301.133147 -292.738168) (xy 301.103582 -292.777512)
			(xy 301.068089 -292.811604) (xy 301.027586 -292.83956) (xy 300.983124 -292.860658) (xy 300.935853 -292.87435)
			(xy 300.886998 -292.880282) (xy 300.837823 -292.878301) (xy 300.789604 -292.868457) (xy 300.743588 -292.851005)
			(xy 300.700967 -292.826398) (xy 300.662846 -292.795273) (xy 300.630211 -292.758436) (xy 300.603908 -292.71684)
			(xy 300.584617 -292.671564) (xy 300.57284 -292.62378) (xy 300.56888 -292.574726) (xy 282.18003 -292.574726)
			(xy 282.179535 -292.599333) (xy 282.17164 -292.64791) (xy 282.156056 -292.694591) (xy 282.133185 -292.738168)
			(xy 282.10362 -292.777512) (xy 282.068127 -292.811604) (xy 282.027624 -292.83956) (xy 281.983162 -292.860658)
			(xy 281.935891 -292.87435) (xy 281.887036 -292.880282) (xy 281.837861 -292.878301) (xy 281.789642 -292.868457)
			(xy 281.743626 -292.851005) (xy 281.701005 -292.826398) (xy 281.662884 -292.795273) (xy 281.630249 -292.758436)
			(xy 281.603946 -292.71684) (xy 281.584655 -292.671564) (xy 281.572878 -292.62378) (xy 281.568918 -292.574726)
			(xy 281.23007 -292.574726) (xy 281.229575 -292.599333) (xy 281.22168 -292.64791) (xy 281.206096 -292.694591)
			(xy 281.183225 -292.738168) (xy 281.15366 -292.777512) (xy 281.118167 -292.811604) (xy 281.077664 -292.83956)
			(xy 281.033202 -292.860658) (xy 280.985931 -292.87435) (xy 280.937076 -292.880282) (xy 280.887901 -292.878301)
			(xy 280.839682 -292.868457) (xy 280.793666 -292.851005) (xy 280.751045 -292.826398) (xy 280.712924 -292.795273)
			(xy 280.680289 -292.758436) (xy 280.653986 -292.71684) (xy 280.634695 -292.671564) (xy 280.622918 -292.62378)
			(xy 280.618958 -292.574726) (xy 280.280105 -292.574726) (xy 280.28011 -292.57498) (xy 280.279615 -292.599587)
			(xy 280.27172 -292.648164) (xy 280.256136 -292.694845) (xy 280.233265 -292.738422) (xy 280.2037 -292.777766)
			(xy 280.168207 -292.811858) (xy 280.127704 -292.839814) (xy 280.083242 -292.860912) (xy 280.035971 -292.874604)
			(xy 279.987116 -292.880536) (xy 279.937941 -292.878555) (xy 279.889722 -292.868711) (xy 279.843706 -292.851259)
			(xy 279.801085 -292.826652) (xy 279.762964 -292.795527) (xy 279.730329 -292.75869) (xy 279.704026 -292.717094)
			(xy 279.684735 -292.671818) (xy 279.672958 -292.624034) (xy 279.668998 -292.57498) (xy 279.41397 -292.57498)
			(xy 279.41397 -293.52494) (xy 279.668998 -293.52494) (xy 279.672958 -293.475886) (xy 279.684735 -293.428102)
			(xy 279.704026 -293.382826) (xy 279.730329 -293.34123) (xy 279.762964 -293.304393) (xy 279.801085 -293.273268)
			(xy 279.843706 -293.248661) (xy 279.889722 -293.231209) (xy 279.937941 -293.221365) (xy 279.987116 -293.219384)
			(xy 280.035971 -293.225316) (xy 280.083242 -293.239008) (xy 280.127704 -293.260106) (xy 280.168207 -293.288062)
			(xy 280.2037 -293.322154) (xy 280.233265 -293.361498) (xy 280.256136 -293.405075) (xy 280.27172 -293.451756)
			(xy 280.279615 -293.500333) (xy 280.28011 -293.52494) (xy 280.618958 -293.52494) (xy 280.622918 -293.475886)
			(xy 280.634695 -293.428102) (xy 280.653986 -293.382826) (xy 280.680289 -293.34123) (xy 280.712924 -293.304393)
			(xy 280.751045 -293.273268) (xy 280.793666 -293.248661) (xy 280.839682 -293.231209) (xy 280.887901 -293.221365)
			(xy 280.937076 -293.219384) (xy 280.985931 -293.225316) (xy 281.033202 -293.239008) (xy 281.077664 -293.260106)
			(xy 281.118167 -293.288062) (xy 281.15366 -293.322154) (xy 281.183225 -293.361498) (xy 281.206096 -293.405075)
			(xy 281.22168 -293.451756) (xy 281.229575 -293.500333) (xy 281.23007 -293.52494) (xy 281.568918 -293.52494)
			(xy 281.572878 -293.475886) (xy 281.584655 -293.428102) (xy 281.603946 -293.382826) (xy 281.630249 -293.34123)
			(xy 281.662884 -293.304393) (xy 281.701005 -293.273268) (xy 281.743626 -293.248661) (xy 281.789642 -293.231209)
			(xy 281.837861 -293.221365) (xy 281.887036 -293.219384) (xy 281.935891 -293.225316) (xy 281.983162 -293.239008)
			(xy 282.027624 -293.260106) (xy 282.068127 -293.288062) (xy 282.10362 -293.322154) (xy 282.133185 -293.361498)
			(xy 282.156056 -293.405075) (xy 282.17164 -293.451756) (xy 282.179535 -293.500333) (xy 282.18003 -293.52494)
			(xy 282.519132 -293.52494) (xy 282.523092 -293.475886) (xy 282.534869 -293.428102) (xy 282.55416 -293.382826)
			(xy 282.580463 -293.34123) (xy 282.613098 -293.304393) (xy 282.651219 -293.273268) (xy 282.69384 -293.248661)
			(xy 282.739856 -293.231209) (xy 282.788075 -293.221365) (xy 282.83725 -293.219384) (xy 282.886105 -293.225316)
			(xy 282.933376 -293.239008) (xy 282.977838 -293.260106) (xy 283.018341 -293.288062) (xy 283.053834 -293.322154)
			(xy 283.083399 -293.361498) (xy 283.10627 -293.405075) (xy 283.121854 -293.451756) (xy 283.129749 -293.500333)
			(xy 283.130244 -293.52494) (xy 283.469092 -293.52494) (xy 283.473052 -293.475886) (xy 283.484829 -293.428102)
			(xy 283.50412 -293.382826) (xy 283.530423 -293.34123) (xy 283.563058 -293.304393) (xy 283.601179 -293.273268)
			(xy 283.6438 -293.248661) (xy 283.689816 -293.231209) (xy 283.738035 -293.221365) (xy 283.78721 -293.219384)
			(xy 283.836065 -293.225316) (xy 283.883336 -293.239008) (xy 283.927798 -293.260106) (xy 283.968301 -293.288062)
			(xy 284.003794 -293.322154) (xy 284.033359 -293.361498) (xy 284.05623 -293.405075) (xy 284.071814 -293.451756)
			(xy 284.079709 -293.500333) (xy 284.080204 -293.52494) (xy 284.419052 -293.52494) (xy 284.423012 -293.475886)
			(xy 284.434789 -293.428102) (xy 284.45408 -293.382826) (xy 284.480383 -293.34123) (xy 284.513018 -293.304393)
			(xy 284.551139 -293.273268) (xy 284.59376 -293.248661) (xy 284.639776 -293.231209) (xy 284.687995 -293.221365)
			(xy 284.73717 -293.219384) (xy 284.786025 -293.225316) (xy 284.833296 -293.239008) (xy 284.877758 -293.260106)
			(xy 284.918261 -293.288062) (xy 284.953754 -293.322154) (xy 284.983319 -293.361498) (xy 285.00619 -293.405075)
			(xy 285.021774 -293.451756) (xy 285.029669 -293.500333) (xy 285.030164 -293.52494) (xy 285.369012 -293.52494)
			(xy 285.372972 -293.475886) (xy 285.384749 -293.428102) (xy 285.40404 -293.382826) (xy 285.430343 -293.34123)
			(xy 285.462978 -293.304393) (xy 285.501099 -293.273268) (xy 285.54372 -293.248661) (xy 285.589736 -293.231209)
			(xy 285.637955 -293.221365) (xy 285.68713 -293.219384) (xy 285.735985 -293.225316) (xy 285.783256 -293.239008)
			(xy 285.827718 -293.260106) (xy 285.868221 -293.288062) (xy 285.903714 -293.322154) (xy 285.933279 -293.361498)
			(xy 285.95615 -293.405075) (xy 285.971734 -293.451756) (xy 285.979629 -293.500333) (xy 285.980124 -293.52494)
			(xy 286.318972 -293.52494) (xy 286.322932 -293.475886) (xy 286.334709 -293.428102) (xy 286.354 -293.382826)
			(xy 286.380303 -293.34123) (xy 286.412938 -293.304393) (xy 286.451059 -293.273268) (xy 286.49368 -293.248661)
			(xy 286.539696 -293.231209) (xy 286.587915 -293.221365) (xy 286.63709 -293.219384) (xy 286.685945 -293.225316)
			(xy 286.733216 -293.239008) (xy 286.777678 -293.260106) (xy 286.818181 -293.288062) (xy 286.853674 -293.322154)
			(xy 286.883239 -293.361498) (xy 286.90611 -293.405075) (xy 286.921694 -293.451756) (xy 286.929589 -293.500333)
			(xy 286.930084 -293.52494) (xy 287.268932 -293.52494) (xy 287.272892 -293.475886) (xy 287.284669 -293.428102)
			(xy 287.30396 -293.382826) (xy 287.330263 -293.34123) (xy 287.362898 -293.304393) (xy 287.401019 -293.273268)
			(xy 287.44364 -293.248661) (xy 287.489656 -293.231209) (xy 287.537875 -293.221365) (xy 287.58705 -293.219384)
			(xy 287.635905 -293.225316) (xy 287.683176 -293.239008) (xy 287.727638 -293.260106) (xy 287.768141 -293.288062)
			(xy 287.803634 -293.322154) (xy 287.833199 -293.361498) (xy 287.85607 -293.405075) (xy 287.871654 -293.451756)
			(xy 287.879549 -293.500333) (xy 287.880044 -293.52494) (xy 288.218892 -293.52494) (xy 288.222852 -293.475886)
			(xy 288.234629 -293.428102) (xy 288.25392 -293.382826) (xy 288.280223 -293.34123) (xy 288.312858 -293.304393)
			(xy 288.350979 -293.273268) (xy 288.3936 -293.248661) (xy 288.439616 -293.231209) (xy 288.487835 -293.221365)
			(xy 288.53701 -293.219384) (xy 288.585865 -293.225316) (xy 288.633136 -293.239008) (xy 288.677598 -293.260106)
			(xy 288.718101 -293.288062) (xy 288.753594 -293.322154) (xy 288.783159 -293.361498) (xy 288.80603 -293.405075)
			(xy 288.821614 -293.451756) (xy 288.829509 -293.500333) (xy 288.830004 -293.52494) (xy 289.169106 -293.52494)
			(xy 289.173066 -293.475886) (xy 289.184843 -293.428102) (xy 289.204134 -293.382826) (xy 289.230437 -293.34123)
			(xy 289.263072 -293.304393) (xy 289.301193 -293.273268) (xy 289.343814 -293.248661) (xy 289.38983 -293.231209)
			(xy 289.438049 -293.221365) (xy 289.487224 -293.219384) (xy 289.536079 -293.225316) (xy 289.58335 -293.239008)
			(xy 289.627812 -293.260106) (xy 289.668315 -293.288062) (xy 289.703808 -293.322154) (xy 289.733373 -293.361498)
			(xy 289.756244 -293.405075) (xy 289.771828 -293.451756) (xy 289.779723 -293.500333) (xy 289.780218 -293.52494)
			(xy 290.119066 -293.52494) (xy 290.123026 -293.475886) (xy 290.134803 -293.428102) (xy 290.154094 -293.382826)
			(xy 290.180397 -293.34123) (xy 290.213032 -293.304393) (xy 290.251153 -293.273268) (xy 290.293774 -293.248661)
			(xy 290.33979 -293.231209) (xy 290.388009 -293.221365) (xy 290.437184 -293.219384) (xy 290.486039 -293.225316)
			(xy 290.53331 -293.239008) (xy 290.577772 -293.260106) (xy 290.618275 -293.288062) (xy 290.653768 -293.322154)
			(xy 290.683333 -293.361498) (xy 290.706204 -293.405075) (xy 290.721788 -293.451756) (xy 290.729683 -293.500333)
			(xy 290.730178 -293.52494) (xy 292.018986 -293.52494) (xy 292.022946 -293.475886) (xy 292.034723 -293.428102)
			(xy 292.054014 -293.382826) (xy 292.080317 -293.34123) (xy 292.112952 -293.304393) (xy 292.151073 -293.273268)
			(xy 292.193694 -293.248661) (xy 292.23971 -293.231209) (xy 292.287929 -293.221365) (xy 292.337104 -293.219384)
			(xy 292.385959 -293.225316) (xy 292.43323 -293.239008) (xy 292.477692 -293.260106) (xy 292.518195 -293.288062)
			(xy 292.553688 -293.322154) (xy 292.583253 -293.361498) (xy 292.606124 -293.405075) (xy 292.621708 -293.451756)
			(xy 292.629603 -293.500333) (xy 292.630098 -293.52494) (xy 292.968946 -293.52494) (xy 292.972906 -293.475886)
			(xy 292.984683 -293.428102) (xy 293.003974 -293.382826) (xy 293.030277 -293.34123) (xy 293.062912 -293.304393)
			(xy 293.101033 -293.273268) (xy 293.143654 -293.248661) (xy 293.18967 -293.231209) (xy 293.237889 -293.221365)
			(xy 293.287064 -293.219384) (xy 293.335919 -293.225316) (xy 293.38319 -293.239008) (xy 293.427652 -293.260106)
			(xy 293.468155 -293.288062) (xy 293.503648 -293.322154) (xy 293.533213 -293.361498) (xy 293.556084 -293.405075)
			(xy 293.571668 -293.451756) (xy 293.579563 -293.500333) (xy 293.580058 -293.52494) (xy 293.918906 -293.52494)
			(xy 293.922866 -293.475886) (xy 293.934643 -293.428102) (xy 293.953934 -293.382826) (xy 293.980237 -293.34123)
			(xy 294.012872 -293.304393) (xy 294.050993 -293.273268) (xy 294.093614 -293.248661) (xy 294.13963 -293.231209)
			(xy 294.187849 -293.221365) (xy 294.237024 -293.219384) (xy 294.285879 -293.225316) (xy 294.33315 -293.239008)
			(xy 294.377612 -293.260106) (xy 294.418115 -293.288062) (xy 294.453608 -293.322154) (xy 294.483173 -293.361498)
			(xy 294.506044 -293.405075) (xy 294.521628 -293.451756) (xy 294.529523 -293.500333) (xy 294.530018 -293.52494)
			(xy 294.86912 -293.52494) (xy 294.87308 -293.475886) (xy 294.884857 -293.428102) (xy 294.904148 -293.382826)
			(xy 294.930451 -293.34123) (xy 294.963086 -293.304393) (xy 295.001207 -293.273268) (xy 295.043828 -293.248661)
			(xy 295.089844 -293.231209) (xy 295.138063 -293.221365) (xy 295.187238 -293.219384) (xy 295.236093 -293.225316)
			(xy 295.283364 -293.239008) (xy 295.327826 -293.260106) (xy 295.368329 -293.288062) (xy 295.403822 -293.322154)
			(xy 295.433387 -293.361498) (xy 295.456258 -293.405075) (xy 295.471842 -293.451756) (xy 295.479737 -293.500333)
			(xy 295.480232 -293.52494) (xy 295.81908 -293.52494) (xy 295.82304 -293.475886) (xy 295.834817 -293.428102)
			(xy 295.854108 -293.382826) (xy 295.880411 -293.34123) (xy 295.913046 -293.304393) (xy 295.951167 -293.273268)
			(xy 295.993788 -293.248661) (xy 296.039804 -293.231209) (xy 296.088023 -293.221365) (xy 296.137198 -293.219384)
			(xy 296.186053 -293.225316) (xy 296.233324 -293.239008) (xy 296.277786 -293.260106) (xy 296.318289 -293.288062)
			(xy 296.353782 -293.322154) (xy 296.383347 -293.361498) (xy 296.406218 -293.405075) (xy 296.421802 -293.451756)
			(xy 296.429697 -293.500333) (xy 296.430192 -293.52494) (xy 296.76904 -293.52494) (xy 296.773 -293.475886)
			(xy 296.784777 -293.428102) (xy 296.804068 -293.382826) (xy 296.830371 -293.34123) (xy 296.863006 -293.304393)
			(xy 296.901127 -293.273268) (xy 296.943748 -293.248661) (xy 296.989764 -293.231209) (xy 297.037983 -293.221365)
			(xy 297.087158 -293.219384) (xy 297.136013 -293.225316) (xy 297.183284 -293.239008) (xy 297.227746 -293.260106)
			(xy 297.268249 -293.288062) (xy 297.303742 -293.322154) (xy 297.333307 -293.361498) (xy 297.356178 -293.405075)
			(xy 297.371762 -293.451756) (xy 297.379657 -293.500333) (xy 297.380152 -293.52494) (xy 297.719 -293.52494)
			(xy 297.72296 -293.475886) (xy 297.734737 -293.428102) (xy 297.754028 -293.382826) (xy 297.780331 -293.34123)
			(xy 297.812966 -293.304393) (xy 297.851087 -293.273268) (xy 297.893708 -293.248661) (xy 297.939724 -293.231209)
			(xy 297.987943 -293.221365) (xy 298.037118 -293.219384) (xy 298.085973 -293.225316) (xy 298.133244 -293.239008)
			(xy 298.177706 -293.260106) (xy 298.218209 -293.288062) (xy 298.253702 -293.322154) (xy 298.283267 -293.361498)
			(xy 298.306138 -293.405075) (xy 298.321722 -293.451756) (xy 298.329617 -293.500333) (xy 298.330112 -293.52494)
			(xy 298.66896 -293.52494) (xy 298.67292 -293.475886) (xy 298.684697 -293.428102) (xy 298.703988 -293.382826)
			(xy 298.730291 -293.34123) (xy 298.762926 -293.304393) (xy 298.801047 -293.273268) (xy 298.843668 -293.248661)
			(xy 298.889684 -293.231209) (xy 298.937903 -293.221365) (xy 298.987078 -293.219384) (xy 299.035933 -293.225316)
			(xy 299.083204 -293.239008) (xy 299.127666 -293.260106) (xy 299.168169 -293.288062) (xy 299.203662 -293.322154)
			(xy 299.233227 -293.361498) (xy 299.256098 -293.405075) (xy 299.271682 -293.451756) (xy 299.279577 -293.500333)
			(xy 299.280072 -293.52494) (xy 299.61892 -293.52494) (xy 299.62288 -293.475886) (xy 299.634657 -293.428102)
			(xy 299.653948 -293.382826) (xy 299.680251 -293.34123) (xy 299.712886 -293.304393) (xy 299.751007 -293.273268)
			(xy 299.793628 -293.248661) (xy 299.839644 -293.231209) (xy 299.887863 -293.221365) (xy 299.937038 -293.219384)
			(xy 299.985893 -293.225316) (xy 300.033164 -293.239008) (xy 300.077626 -293.260106) (xy 300.118129 -293.288062)
			(xy 300.153622 -293.322154) (xy 300.183187 -293.361498) (xy 300.206058 -293.405075) (xy 300.221642 -293.451756)
			(xy 300.229537 -293.500333) (xy 300.230032 -293.52494) (xy 300.56888 -293.52494) (xy 300.57284 -293.475886)
			(xy 300.584617 -293.428102) (xy 300.603908 -293.382826) (xy 300.630211 -293.34123) (xy 300.662846 -293.304393)
			(xy 300.700967 -293.273268) (xy 300.743588 -293.248661) (xy 300.789604 -293.231209) (xy 300.837823 -293.221365)
			(xy 300.886998 -293.219384) (xy 300.935853 -293.225316) (xy 300.983124 -293.239008) (xy 301.027586 -293.260106)
			(xy 301.068089 -293.288062) (xy 301.103582 -293.322154) (xy 301.133147 -293.361498) (xy 301.156018 -293.405075)
			(xy 301.171602 -293.451756) (xy 301.179497 -293.500333) (xy 301.179992 -293.52494) (xy 301.519094 -293.52494)
			(xy 301.523054 -293.475886) (xy 301.534831 -293.428102) (xy 301.554122 -293.382826) (xy 301.580425 -293.34123)
			(xy 301.61306 -293.304393) (xy 301.651181 -293.273268) (xy 301.693802 -293.248661) (xy 301.739818 -293.231209)
			(xy 301.788037 -293.221365) (xy 301.837212 -293.219384) (xy 301.886067 -293.225316) (xy 301.933338 -293.239008)
			(xy 301.9778 -293.260106) (xy 302.018303 -293.288062) (xy 302.053796 -293.322154) (xy 302.083361 -293.361498)
			(xy 302.106232 -293.405075) (xy 302.121816 -293.451756) (xy 302.129711 -293.500333) (xy 302.130206 -293.52494)
			(xy 302.469054 -293.52494) (xy 302.473014 -293.475886) (xy 302.484791 -293.428102) (xy 302.504082 -293.382826)
			(xy 302.530385 -293.34123) (xy 302.56302 -293.304393) (xy 302.601141 -293.273268) (xy 302.643762 -293.248661)
			(xy 302.689778 -293.231209) (xy 302.737997 -293.221365) (xy 302.787172 -293.219384) (xy 302.836027 -293.225316)
			(xy 302.883298 -293.239008) (xy 302.92776 -293.260106) (xy 302.968263 -293.288062) (xy 303.003756 -293.322154)
			(xy 303.033321 -293.361498) (xy 303.056192 -293.405075) (xy 303.071776 -293.451756) (xy 303.079671 -293.500333)
			(xy 303.080166 -293.52494) (xy 303.419014 -293.52494) (xy 303.422974 -293.475886) (xy 303.434751 -293.428102)
			(xy 303.454042 -293.382826) (xy 303.480345 -293.34123) (xy 303.51298 -293.304393) (xy 303.551101 -293.273268)
			(xy 303.593722 -293.248661) (xy 303.639738 -293.231209) (xy 303.687957 -293.221365) (xy 303.737132 -293.219384)
			(xy 303.785987 -293.225316) (xy 303.833258 -293.239008) (xy 303.87772 -293.260106) (xy 303.918223 -293.288062)
			(xy 303.953716 -293.322154) (xy 303.983281 -293.361498) (xy 304.006152 -293.405075) (xy 304.021736 -293.451756)
			(xy 304.029631 -293.500333) (xy 304.030126 -293.52494) (xy 304.368974 -293.52494) (xy 304.372934 -293.475886)
			(xy 304.384711 -293.428102) (xy 304.404002 -293.382826) (xy 304.430305 -293.34123) (xy 304.46294 -293.304393)
			(xy 304.501061 -293.273268) (xy 304.543682 -293.248661) (xy 304.589698 -293.231209) (xy 304.637917 -293.221365)
			(xy 304.687092 -293.219384) (xy 304.735947 -293.225316) (xy 304.783218 -293.239008) (xy 304.82768 -293.260106)
			(xy 304.868183 -293.288062) (xy 304.903676 -293.322154) (xy 304.933241 -293.361498) (xy 304.956112 -293.405075)
			(xy 304.971696 -293.451756) (xy 304.979591 -293.500333) (xy 304.980086 -293.52494) (xy 305.318934 -293.52494)
			(xy 305.322894 -293.475886) (xy 305.334671 -293.428102) (xy 305.353962 -293.382826) (xy 305.380265 -293.34123)
			(xy 305.4129 -293.304393) (xy 305.451021 -293.273268) (xy 305.493642 -293.248661) (xy 305.539658 -293.231209)
			(xy 305.587877 -293.221365) (xy 305.637052 -293.219384) (xy 305.685907 -293.225316) (xy 305.733178 -293.239008)
			(xy 305.77764 -293.260106) (xy 305.818143 -293.288062) (xy 305.853636 -293.322154) (xy 305.883201 -293.361498)
			(xy 305.906072 -293.405075) (xy 305.921656 -293.451756) (xy 305.929551 -293.500333) (xy 305.930046 -293.52494)
			(xy 306.269148 -293.52494) (xy 306.273108 -293.475886) (xy 306.284885 -293.428102) (xy 306.304176 -293.382826)
			(xy 306.330479 -293.34123) (xy 306.363114 -293.304393) (xy 306.401235 -293.273268) (xy 306.443856 -293.248661)
			(xy 306.489872 -293.231209) (xy 306.538091 -293.221365) (xy 306.587266 -293.219384) (xy 306.636121 -293.225316)
			(xy 306.683392 -293.239008) (xy 306.727854 -293.260106) (xy 306.768357 -293.288062) (xy 306.80385 -293.322154)
			(xy 306.833415 -293.361498) (xy 306.856286 -293.405075) (xy 306.87187 -293.451756) (xy 306.879765 -293.500333)
			(xy 306.88026 -293.52494) (xy 307.219108 -293.52494) (xy 307.223068 -293.475886) (xy 307.234845 -293.428102)
			(xy 307.254136 -293.382826) (xy 307.280439 -293.34123) (xy 307.313074 -293.304393) (xy 307.351195 -293.273268)
			(xy 307.393816 -293.248661) (xy 307.439832 -293.231209) (xy 307.488051 -293.221365) (xy 307.537226 -293.219384)
			(xy 307.586081 -293.225316) (xy 307.633352 -293.239008) (xy 307.677814 -293.260106) (xy 307.718317 -293.288062)
			(xy 307.75381 -293.322154) (xy 307.783375 -293.361498) (xy 307.806246 -293.405075) (xy 307.82183 -293.451756)
			(xy 307.829725 -293.500333) (xy 307.83022 -293.52494) (xy 308.169068 -293.52494) (xy 308.173028 -293.475886)
			(xy 308.184805 -293.428102) (xy 308.204096 -293.382826) (xy 308.230399 -293.34123) (xy 308.263034 -293.304393)
			(xy 308.301155 -293.273268) (xy 308.343776 -293.248661) (xy 308.389792 -293.231209) (xy 308.438011 -293.221365)
			(xy 308.487186 -293.219384) (xy 308.536041 -293.225316) (xy 308.583312 -293.239008) (xy 308.627774 -293.260106)
			(xy 308.668277 -293.288062) (xy 308.70377 -293.322154) (xy 308.733335 -293.361498) (xy 308.756206 -293.405075)
			(xy 308.77179 -293.451756) (xy 308.779685 -293.500333) (xy 308.78018 -293.52494) (xy 309.119028 -293.52494)
			(xy 309.122988 -293.475886) (xy 309.134765 -293.428102) (xy 309.154056 -293.382826) (xy 309.180359 -293.34123)
			(xy 309.212994 -293.304393) (xy 309.251115 -293.273268) (xy 309.293736 -293.248661) (xy 309.339752 -293.231209)
			(xy 309.387971 -293.221365) (xy 309.437146 -293.219384) (xy 309.486001 -293.225316) (xy 309.533272 -293.239008)
			(xy 309.577734 -293.260106) (xy 309.618237 -293.288062) (xy 309.65373 -293.322154) (xy 309.683295 -293.361498)
			(xy 309.706166 -293.405075) (xy 309.72175 -293.451756) (xy 309.729645 -293.500333) (xy 309.73014 -293.52494)
			(xy 310.068988 -293.52494) (xy 310.072948 -293.475886) (xy 310.084725 -293.428102) (xy 310.104016 -293.382826)
			(xy 310.130319 -293.34123) (xy 310.162954 -293.304393) (xy 310.201075 -293.273268) (xy 310.243696 -293.248661)
			(xy 310.289712 -293.231209) (xy 310.337931 -293.221365) (xy 310.387106 -293.219384) (xy 310.435961 -293.225316)
			(xy 310.483232 -293.239008) (xy 310.527694 -293.260106) (xy 310.568197 -293.288062) (xy 310.60369 -293.322154)
			(xy 310.633255 -293.361498) (xy 310.656126 -293.405075) (xy 310.67171 -293.451756) (xy 310.679605 -293.500333)
			(xy 310.6801 -293.52494) (xy 311.018948 -293.52494) (xy 311.022908 -293.475886) (xy 311.034685 -293.428102)
			(xy 311.053976 -293.382826) (xy 311.080279 -293.34123) (xy 311.112914 -293.304393) (xy 311.151035 -293.273268)
			(xy 311.193656 -293.248661) (xy 311.239672 -293.231209) (xy 311.287891 -293.221365) (xy 311.337066 -293.219384)
			(xy 311.385921 -293.225316) (xy 311.433192 -293.239008) (xy 311.477654 -293.260106) (xy 311.518157 -293.288062)
			(xy 311.55365 -293.322154) (xy 311.583215 -293.361498) (xy 311.606086 -293.405075) (xy 311.62167 -293.451756)
			(xy 311.629565 -293.500333) (xy 311.63006 -293.52494) (xy 311.968908 -293.52494) (xy 311.972868 -293.475886)
			(xy 311.984645 -293.428102) (xy 312.003936 -293.382826) (xy 312.030239 -293.34123) (xy 312.062874 -293.304393)
			(xy 312.100995 -293.273268) (xy 312.143616 -293.248661) (xy 312.189632 -293.231209) (xy 312.237851 -293.221365)
			(xy 312.287026 -293.219384) (xy 312.335881 -293.225316) (xy 312.383152 -293.239008) (xy 312.427614 -293.260106)
			(xy 312.468117 -293.288062) (xy 312.50361 -293.322154) (xy 312.533175 -293.361498) (xy 312.556046 -293.405075)
			(xy 312.57163 -293.451756) (xy 312.579525 -293.500333) (xy 312.58002 -293.52494) (xy 312.919122 -293.52494)
			(xy 312.923082 -293.475886) (xy 312.934859 -293.428102) (xy 312.95415 -293.382826) (xy 312.980453 -293.34123)
			(xy 313.013088 -293.304393) (xy 313.051209 -293.273268) (xy 313.09383 -293.248661) (xy 313.139846 -293.231209)
			(xy 313.188065 -293.221365) (xy 313.23724 -293.219384) (xy 313.286095 -293.225316) (xy 313.333366 -293.239008)
			(xy 313.377828 -293.260106) (xy 313.418331 -293.288062) (xy 313.453824 -293.322154) (xy 313.483389 -293.361498)
			(xy 313.50626 -293.405075) (xy 313.521844 -293.451756) (xy 313.529739 -293.500333) (xy 313.530234 -293.52494)
			(xy 313.869082 -293.52494) (xy 313.873042 -293.475886) (xy 313.884819 -293.428102) (xy 313.90411 -293.382826)
			(xy 313.930413 -293.34123) (xy 313.963048 -293.304393) (xy 314.001169 -293.273268) (xy 314.04379 -293.248661)
			(xy 314.089806 -293.231209) (xy 314.138025 -293.221365) (xy 314.1872 -293.219384) (xy 314.236055 -293.225316)
			(xy 314.283326 -293.239008) (xy 314.327788 -293.260106) (xy 314.368291 -293.288062) (xy 314.403784 -293.322154)
			(xy 314.433349 -293.361498) (xy 314.45622 -293.405075) (xy 314.471804 -293.451756) (xy 314.479699 -293.500333)
			(xy 314.480194 -293.52494) (xy 314.819042 -293.52494) (xy 314.823002 -293.475886) (xy 314.834779 -293.428102)
			(xy 314.85407 -293.382826) (xy 314.880373 -293.34123) (xy 314.913008 -293.304393) (xy 314.951129 -293.273268)
			(xy 314.99375 -293.248661) (xy 315.039766 -293.231209) (xy 315.087985 -293.221365) (xy 315.13716 -293.219384)
			(xy 315.186015 -293.225316) (xy 315.233286 -293.239008) (xy 315.277748 -293.260106) (xy 315.318251 -293.288062)
			(xy 315.353744 -293.322154) (xy 315.383309 -293.361498) (xy 315.40618 -293.405075) (xy 315.421764 -293.451756)
			(xy 315.429659 -293.500333) (xy 315.430154 -293.52494) (xy 315.429659 -293.549547) (xy 315.421764 -293.598124)
			(xy 315.40618 -293.644805) (xy 315.383309 -293.688382) (xy 315.353744 -293.727726) (xy 315.318251 -293.761818)
			(xy 315.277748 -293.789774) (xy 315.233286 -293.810872) (xy 315.186015 -293.824564) (xy 315.13716 -293.830496)
			(xy 315.087985 -293.828515) (xy 315.039766 -293.818671) (xy 314.99375 -293.801219) (xy 314.951129 -293.776612)
			(xy 314.913008 -293.745487) (xy 314.880373 -293.70865) (xy 314.85407 -293.667054) (xy 314.834779 -293.621778)
			(xy 314.823002 -293.573994) (xy 314.819042 -293.52494) (xy 314.480194 -293.52494) (xy 314.479699 -293.549547)
			(xy 314.471804 -293.598124) (xy 314.45622 -293.644805) (xy 314.433349 -293.688382) (xy 314.403784 -293.727726)
			(xy 314.368291 -293.761818) (xy 314.327788 -293.789774) (xy 314.283326 -293.810872) (xy 314.236055 -293.824564)
			(xy 314.1872 -293.830496) (xy 314.138025 -293.828515) (xy 314.089806 -293.818671) (xy 314.04379 -293.801219)
			(xy 314.001169 -293.776612) (xy 313.963048 -293.745487) (xy 313.930413 -293.70865) (xy 313.90411 -293.667054)
			(xy 313.884819 -293.621778) (xy 313.873042 -293.573994) (xy 313.869082 -293.52494) (xy 313.530234 -293.52494)
			(xy 313.529739 -293.549547) (xy 313.521844 -293.598124) (xy 313.50626 -293.644805) (xy 313.483389 -293.688382)
			(xy 313.453824 -293.727726) (xy 313.418331 -293.761818) (xy 313.377828 -293.789774) (xy 313.333366 -293.810872)
			(xy 313.286095 -293.824564) (xy 313.23724 -293.830496) (xy 313.188065 -293.828515) (xy 313.139846 -293.818671)
			(xy 313.09383 -293.801219) (xy 313.051209 -293.776612) (xy 313.013088 -293.745487) (xy 312.980453 -293.70865)
			(xy 312.95415 -293.667054) (xy 312.934859 -293.621778) (xy 312.923082 -293.573994) (xy 312.919122 -293.52494)
			(xy 312.58002 -293.52494) (xy 312.579525 -293.549547) (xy 312.57163 -293.598124) (xy 312.556046 -293.644805)
			(xy 312.533175 -293.688382) (xy 312.50361 -293.727726) (xy 312.468117 -293.761818) (xy 312.427614 -293.789774)
			(xy 312.383152 -293.810872) (xy 312.335881 -293.824564) (xy 312.287026 -293.830496) (xy 312.237851 -293.828515)
			(xy 312.189632 -293.818671) (xy 312.143616 -293.801219) (xy 312.100995 -293.776612) (xy 312.062874 -293.745487)
			(xy 312.030239 -293.70865) (xy 312.003936 -293.667054) (xy 311.984645 -293.621778) (xy 311.972868 -293.573994)
			(xy 311.968908 -293.52494) (xy 311.63006 -293.52494) (xy 311.629565 -293.549547) (xy 311.62167 -293.598124)
			(xy 311.606086 -293.644805) (xy 311.583215 -293.688382) (xy 311.55365 -293.727726) (xy 311.518157 -293.761818)
			(xy 311.477654 -293.789774) (xy 311.433192 -293.810872) (xy 311.385921 -293.824564) (xy 311.337066 -293.830496)
			(xy 311.287891 -293.828515) (xy 311.239672 -293.818671) (xy 311.193656 -293.801219) (xy 311.151035 -293.776612)
			(xy 311.112914 -293.745487) (xy 311.080279 -293.70865) (xy 311.053976 -293.667054) (xy 311.034685 -293.621778)
			(xy 311.022908 -293.573994) (xy 311.018948 -293.52494) (xy 310.6801 -293.52494) (xy 310.679605 -293.549547)
			(xy 310.67171 -293.598124) (xy 310.656126 -293.644805) (xy 310.633255 -293.688382) (xy 310.60369 -293.727726)
			(xy 310.568197 -293.761818) (xy 310.527694 -293.789774) (xy 310.483232 -293.810872) (xy 310.435961 -293.824564)
			(xy 310.387106 -293.830496) (xy 310.337931 -293.828515) (xy 310.289712 -293.818671) (xy 310.243696 -293.801219)
			(xy 310.201075 -293.776612) (xy 310.162954 -293.745487) (xy 310.130319 -293.70865) (xy 310.104016 -293.667054)
			(xy 310.084725 -293.621778) (xy 310.072948 -293.573994) (xy 310.068988 -293.52494) (xy 309.73014 -293.52494)
			(xy 309.729645 -293.549547) (xy 309.72175 -293.598124) (xy 309.706166 -293.644805) (xy 309.683295 -293.688382)
			(xy 309.65373 -293.727726) (xy 309.618237 -293.761818) (xy 309.577734 -293.789774) (xy 309.533272 -293.810872)
			(xy 309.486001 -293.824564) (xy 309.437146 -293.830496) (xy 309.387971 -293.828515) (xy 309.339752 -293.818671)
			(xy 309.293736 -293.801219) (xy 309.251115 -293.776612) (xy 309.212994 -293.745487) (xy 309.180359 -293.70865)
			(xy 309.154056 -293.667054) (xy 309.134765 -293.621778) (xy 309.122988 -293.573994) (xy 309.119028 -293.52494)
			(xy 308.78018 -293.52494) (xy 308.779685 -293.549547) (xy 308.77179 -293.598124) (xy 308.756206 -293.644805)
			(xy 308.733335 -293.688382) (xy 308.70377 -293.727726) (xy 308.668277 -293.761818) (xy 308.627774 -293.789774)
			(xy 308.583312 -293.810872) (xy 308.536041 -293.824564) (xy 308.487186 -293.830496) (xy 308.438011 -293.828515)
			(xy 308.389792 -293.818671) (xy 308.343776 -293.801219) (xy 308.301155 -293.776612) (xy 308.263034 -293.745487)
			(xy 308.230399 -293.70865) (xy 308.204096 -293.667054) (xy 308.184805 -293.621778) (xy 308.173028 -293.573994)
			(xy 308.169068 -293.52494) (xy 307.83022 -293.52494) (xy 307.829725 -293.549547) (xy 307.82183 -293.598124)
			(xy 307.806246 -293.644805) (xy 307.783375 -293.688382) (xy 307.75381 -293.727726) (xy 307.718317 -293.761818)
			(xy 307.677814 -293.789774) (xy 307.633352 -293.810872) (xy 307.586081 -293.824564) (xy 307.537226 -293.830496)
			(xy 307.488051 -293.828515) (xy 307.439832 -293.818671) (xy 307.393816 -293.801219) (xy 307.351195 -293.776612)
			(xy 307.313074 -293.745487) (xy 307.280439 -293.70865) (xy 307.254136 -293.667054) (xy 307.234845 -293.621778)
			(xy 307.223068 -293.573994) (xy 307.219108 -293.52494) (xy 306.88026 -293.52494) (xy 306.879765 -293.549547)
			(xy 306.87187 -293.598124) (xy 306.856286 -293.644805) (xy 306.833415 -293.688382) (xy 306.80385 -293.727726)
			(xy 306.768357 -293.761818) (xy 306.727854 -293.789774) (xy 306.683392 -293.810872) (xy 306.636121 -293.824564)
			(xy 306.587266 -293.830496) (xy 306.538091 -293.828515) (xy 306.489872 -293.818671) (xy 306.443856 -293.801219)
			(xy 306.401235 -293.776612) (xy 306.363114 -293.745487) (xy 306.330479 -293.70865) (xy 306.304176 -293.667054)
			(xy 306.284885 -293.621778) (xy 306.273108 -293.573994) (xy 306.269148 -293.52494) (xy 305.930046 -293.52494)
			(xy 305.929551 -293.549547) (xy 305.921656 -293.598124) (xy 305.906072 -293.644805) (xy 305.883201 -293.688382)
			(xy 305.853636 -293.727726) (xy 305.818143 -293.761818) (xy 305.77764 -293.789774) (xy 305.733178 -293.810872)
			(xy 305.685907 -293.824564) (xy 305.637052 -293.830496) (xy 305.587877 -293.828515) (xy 305.539658 -293.818671)
			(xy 305.493642 -293.801219) (xy 305.451021 -293.776612) (xy 305.4129 -293.745487) (xy 305.380265 -293.70865)
			(xy 305.353962 -293.667054) (xy 305.334671 -293.621778) (xy 305.322894 -293.573994) (xy 305.318934 -293.52494)
			(xy 304.980086 -293.52494) (xy 304.979591 -293.549547) (xy 304.971696 -293.598124) (xy 304.956112 -293.644805)
			(xy 304.933241 -293.688382) (xy 304.903676 -293.727726) (xy 304.868183 -293.761818) (xy 304.82768 -293.789774)
			(xy 304.783218 -293.810872) (xy 304.735947 -293.824564) (xy 304.687092 -293.830496) (xy 304.637917 -293.828515)
			(xy 304.589698 -293.818671) (xy 304.543682 -293.801219) (xy 304.501061 -293.776612) (xy 304.46294 -293.745487)
			(xy 304.430305 -293.70865) (xy 304.404002 -293.667054) (xy 304.384711 -293.621778) (xy 304.372934 -293.573994)
			(xy 304.368974 -293.52494) (xy 304.030126 -293.52494) (xy 304.029631 -293.549547) (xy 304.021736 -293.598124)
			(xy 304.006152 -293.644805) (xy 303.983281 -293.688382) (xy 303.953716 -293.727726) (xy 303.918223 -293.761818)
			(xy 303.87772 -293.789774) (xy 303.833258 -293.810872) (xy 303.785987 -293.824564) (xy 303.737132 -293.830496)
			(xy 303.687957 -293.828515) (xy 303.639738 -293.818671) (xy 303.593722 -293.801219) (xy 303.551101 -293.776612)
			(xy 303.51298 -293.745487) (xy 303.480345 -293.70865) (xy 303.454042 -293.667054) (xy 303.434751 -293.621778)
			(xy 303.422974 -293.573994) (xy 303.419014 -293.52494) (xy 303.080166 -293.52494) (xy 303.079671 -293.549547)
			(xy 303.071776 -293.598124) (xy 303.056192 -293.644805) (xy 303.033321 -293.688382) (xy 303.003756 -293.727726)
			(xy 302.968263 -293.761818) (xy 302.92776 -293.789774) (xy 302.883298 -293.810872) (xy 302.836027 -293.824564)
			(xy 302.787172 -293.830496) (xy 302.737997 -293.828515) (xy 302.689778 -293.818671) (xy 302.643762 -293.801219)
			(xy 302.601141 -293.776612) (xy 302.56302 -293.745487) (xy 302.530385 -293.70865) (xy 302.504082 -293.667054)
			(xy 302.484791 -293.621778) (xy 302.473014 -293.573994) (xy 302.469054 -293.52494) (xy 302.130206 -293.52494)
			(xy 302.129711 -293.549547) (xy 302.121816 -293.598124) (xy 302.106232 -293.644805) (xy 302.083361 -293.688382)
			(xy 302.053796 -293.727726) (xy 302.018303 -293.761818) (xy 301.9778 -293.789774) (xy 301.933338 -293.810872)
			(xy 301.886067 -293.824564) (xy 301.837212 -293.830496) (xy 301.788037 -293.828515) (xy 301.739818 -293.818671)
			(xy 301.693802 -293.801219) (xy 301.651181 -293.776612) (xy 301.61306 -293.745487) (xy 301.580425 -293.70865)
			(xy 301.554122 -293.667054) (xy 301.534831 -293.621778) (xy 301.523054 -293.573994) (xy 301.519094 -293.52494)
			(xy 301.179992 -293.52494) (xy 301.179497 -293.549547) (xy 301.171602 -293.598124) (xy 301.156018 -293.644805)
			(xy 301.133147 -293.688382) (xy 301.103582 -293.727726) (xy 301.068089 -293.761818) (xy 301.027586 -293.789774)
			(xy 300.983124 -293.810872) (xy 300.935853 -293.824564) (xy 300.886998 -293.830496) (xy 300.837823 -293.828515)
			(xy 300.789604 -293.818671) (xy 300.743588 -293.801219) (xy 300.700967 -293.776612) (xy 300.662846 -293.745487)
			(xy 300.630211 -293.70865) (xy 300.603908 -293.667054) (xy 300.584617 -293.621778) (xy 300.57284 -293.573994)
			(xy 300.56888 -293.52494) (xy 300.230032 -293.52494) (xy 300.229537 -293.549547) (xy 300.221642 -293.598124)
			(xy 300.206058 -293.644805) (xy 300.183187 -293.688382) (xy 300.153622 -293.727726) (xy 300.118129 -293.761818)
			(xy 300.077626 -293.789774) (xy 300.033164 -293.810872) (xy 299.985893 -293.824564) (xy 299.937038 -293.830496)
			(xy 299.887863 -293.828515) (xy 299.839644 -293.818671) (xy 299.793628 -293.801219) (xy 299.751007 -293.776612)
			(xy 299.712886 -293.745487) (xy 299.680251 -293.70865) (xy 299.653948 -293.667054) (xy 299.634657 -293.621778)
			(xy 299.62288 -293.573994) (xy 299.61892 -293.52494) (xy 299.280072 -293.52494) (xy 299.279577 -293.549547)
			(xy 299.271682 -293.598124) (xy 299.256098 -293.644805) (xy 299.233227 -293.688382) (xy 299.203662 -293.727726)
			(xy 299.168169 -293.761818) (xy 299.127666 -293.789774) (xy 299.083204 -293.810872) (xy 299.035933 -293.824564)
			(xy 298.987078 -293.830496) (xy 298.937903 -293.828515) (xy 298.889684 -293.818671) (xy 298.843668 -293.801219)
			(xy 298.801047 -293.776612) (xy 298.762926 -293.745487) (xy 298.730291 -293.70865) (xy 298.703988 -293.667054)
			(xy 298.684697 -293.621778) (xy 298.67292 -293.573994) (xy 298.66896 -293.52494) (xy 298.330112 -293.52494)
			(xy 298.329617 -293.549547) (xy 298.321722 -293.598124) (xy 298.306138 -293.644805) (xy 298.283267 -293.688382)
			(xy 298.253702 -293.727726) (xy 298.218209 -293.761818) (xy 298.177706 -293.789774) (xy 298.133244 -293.810872)
			(xy 298.085973 -293.824564) (xy 298.037118 -293.830496) (xy 297.987943 -293.828515) (xy 297.939724 -293.818671)
			(xy 297.893708 -293.801219) (xy 297.851087 -293.776612) (xy 297.812966 -293.745487) (xy 297.780331 -293.70865)
			(xy 297.754028 -293.667054) (xy 297.734737 -293.621778) (xy 297.72296 -293.573994) (xy 297.719 -293.52494)
			(xy 297.380152 -293.52494) (xy 297.379657 -293.549547) (xy 297.371762 -293.598124) (xy 297.356178 -293.644805)
			(xy 297.333307 -293.688382) (xy 297.303742 -293.727726) (xy 297.268249 -293.761818) (xy 297.227746 -293.789774)
			(xy 297.183284 -293.810872) (xy 297.136013 -293.824564) (xy 297.087158 -293.830496) (xy 297.037983 -293.828515)
			(xy 296.989764 -293.818671) (xy 296.943748 -293.801219) (xy 296.901127 -293.776612) (xy 296.863006 -293.745487)
			(xy 296.830371 -293.70865) (xy 296.804068 -293.667054) (xy 296.784777 -293.621778) (xy 296.773 -293.573994)
			(xy 296.76904 -293.52494) (xy 296.430192 -293.52494) (xy 296.429697 -293.549547) (xy 296.421802 -293.598124)
			(xy 296.406218 -293.644805) (xy 296.383347 -293.688382) (xy 296.353782 -293.727726) (xy 296.318289 -293.761818)
			(xy 296.277786 -293.789774) (xy 296.233324 -293.810872) (xy 296.186053 -293.824564) (xy 296.137198 -293.830496)
			(xy 296.088023 -293.828515) (xy 296.039804 -293.818671) (xy 295.993788 -293.801219) (xy 295.951167 -293.776612)
			(xy 295.913046 -293.745487) (xy 295.880411 -293.70865) (xy 295.854108 -293.667054) (xy 295.834817 -293.621778)
			(xy 295.82304 -293.573994) (xy 295.81908 -293.52494) (xy 295.480232 -293.52494) (xy 295.479737 -293.549547)
			(xy 295.471842 -293.598124) (xy 295.456258 -293.644805) (xy 295.433387 -293.688382) (xy 295.403822 -293.727726)
			(xy 295.368329 -293.761818) (xy 295.327826 -293.789774) (xy 295.283364 -293.810872) (xy 295.236093 -293.824564)
			(xy 295.187238 -293.830496) (xy 295.138063 -293.828515) (xy 295.089844 -293.818671) (xy 295.043828 -293.801219)
			(xy 295.001207 -293.776612) (xy 294.963086 -293.745487) (xy 294.930451 -293.70865) (xy 294.904148 -293.667054)
			(xy 294.884857 -293.621778) (xy 294.87308 -293.573994) (xy 294.86912 -293.52494) (xy 294.530018 -293.52494)
			(xy 294.529523 -293.549547) (xy 294.521628 -293.598124) (xy 294.506044 -293.644805) (xy 294.483173 -293.688382)
			(xy 294.453608 -293.727726) (xy 294.418115 -293.761818) (xy 294.377612 -293.789774) (xy 294.33315 -293.810872)
			(xy 294.285879 -293.824564) (xy 294.237024 -293.830496) (xy 294.187849 -293.828515) (xy 294.13963 -293.818671)
			(xy 294.093614 -293.801219) (xy 294.050993 -293.776612) (xy 294.012872 -293.745487) (xy 293.980237 -293.70865)
			(xy 293.953934 -293.667054) (xy 293.934643 -293.621778) (xy 293.922866 -293.573994) (xy 293.918906 -293.52494)
			(xy 293.580058 -293.52494) (xy 293.579563 -293.549547) (xy 293.571668 -293.598124) (xy 293.556084 -293.644805)
			(xy 293.533213 -293.688382) (xy 293.503648 -293.727726) (xy 293.468155 -293.761818) (xy 293.427652 -293.789774)
			(xy 293.38319 -293.810872) (xy 293.335919 -293.824564) (xy 293.287064 -293.830496) (xy 293.237889 -293.828515)
			(xy 293.18967 -293.818671) (xy 293.143654 -293.801219) (xy 293.101033 -293.776612) (xy 293.062912 -293.745487)
			(xy 293.030277 -293.70865) (xy 293.003974 -293.667054) (xy 292.984683 -293.621778) (xy 292.972906 -293.573994)
			(xy 292.968946 -293.52494) (xy 292.630098 -293.52494) (xy 292.629603 -293.549547) (xy 292.621708 -293.598124)
			(xy 292.606124 -293.644805) (xy 292.583253 -293.688382) (xy 292.553688 -293.727726) (xy 292.518195 -293.761818)
			(xy 292.477692 -293.789774) (xy 292.43323 -293.810872) (xy 292.385959 -293.824564) (xy 292.337104 -293.830496)
			(xy 292.287929 -293.828515) (xy 292.23971 -293.818671) (xy 292.193694 -293.801219) (xy 292.151073 -293.776612)
			(xy 292.112952 -293.745487) (xy 292.080317 -293.70865) (xy 292.054014 -293.667054) (xy 292.034723 -293.621778)
			(xy 292.022946 -293.573994) (xy 292.018986 -293.52494) (xy 290.730178 -293.52494) (xy 290.729683 -293.549547)
			(xy 290.721788 -293.598124) (xy 290.706204 -293.644805) (xy 290.683333 -293.688382) (xy 290.653768 -293.727726)
			(xy 290.618275 -293.761818) (xy 290.577772 -293.789774) (xy 290.53331 -293.810872) (xy 290.486039 -293.824564)
			(xy 290.437184 -293.830496) (xy 290.388009 -293.828515) (xy 290.33979 -293.818671) (xy 290.293774 -293.801219)
			(xy 290.251153 -293.776612) (xy 290.213032 -293.745487) (xy 290.180397 -293.70865) (xy 290.154094 -293.667054)
			(xy 290.134803 -293.621778) (xy 290.123026 -293.573994) (xy 290.119066 -293.52494) (xy 289.780218 -293.52494)
			(xy 289.779723 -293.549547) (xy 289.771828 -293.598124) (xy 289.756244 -293.644805) (xy 289.733373 -293.688382)
			(xy 289.703808 -293.727726) (xy 289.668315 -293.761818) (xy 289.627812 -293.789774) (xy 289.58335 -293.810872)
			(xy 289.536079 -293.824564) (xy 289.487224 -293.830496) (xy 289.438049 -293.828515) (xy 289.38983 -293.818671)
			(xy 289.343814 -293.801219) (xy 289.301193 -293.776612) (xy 289.263072 -293.745487) (xy 289.230437 -293.70865)
			(xy 289.204134 -293.667054) (xy 289.184843 -293.621778) (xy 289.173066 -293.573994) (xy 289.169106 -293.52494)
			(xy 288.830004 -293.52494) (xy 288.829509 -293.549547) (xy 288.821614 -293.598124) (xy 288.80603 -293.644805)
			(xy 288.783159 -293.688382) (xy 288.753594 -293.727726) (xy 288.718101 -293.761818) (xy 288.677598 -293.789774)
			(xy 288.633136 -293.810872) (xy 288.585865 -293.824564) (xy 288.53701 -293.830496) (xy 288.487835 -293.828515)
			(xy 288.439616 -293.818671) (xy 288.3936 -293.801219) (xy 288.350979 -293.776612) (xy 288.312858 -293.745487)
			(xy 288.280223 -293.70865) (xy 288.25392 -293.667054) (xy 288.234629 -293.621778) (xy 288.222852 -293.573994)
			(xy 288.218892 -293.52494) (xy 287.880044 -293.52494) (xy 287.879549 -293.549547) (xy 287.871654 -293.598124)
			(xy 287.85607 -293.644805) (xy 287.833199 -293.688382) (xy 287.803634 -293.727726) (xy 287.768141 -293.761818)
			(xy 287.727638 -293.789774) (xy 287.683176 -293.810872) (xy 287.635905 -293.824564) (xy 287.58705 -293.830496)
			(xy 287.537875 -293.828515) (xy 287.489656 -293.818671) (xy 287.44364 -293.801219) (xy 287.401019 -293.776612)
			(xy 287.362898 -293.745487) (xy 287.330263 -293.70865) (xy 287.30396 -293.667054) (xy 287.284669 -293.621778)
			(xy 287.272892 -293.573994) (xy 287.268932 -293.52494) (xy 286.930084 -293.52494) (xy 286.929589 -293.549547)
			(xy 286.921694 -293.598124) (xy 286.90611 -293.644805) (xy 286.883239 -293.688382) (xy 286.853674 -293.727726)
			(xy 286.818181 -293.761818) (xy 286.777678 -293.789774) (xy 286.733216 -293.810872) (xy 286.685945 -293.824564)
			(xy 286.63709 -293.830496) (xy 286.587915 -293.828515) (xy 286.539696 -293.818671) (xy 286.49368 -293.801219)
			(xy 286.451059 -293.776612) (xy 286.412938 -293.745487) (xy 286.380303 -293.70865) (xy 286.354 -293.667054)
			(xy 286.334709 -293.621778) (xy 286.322932 -293.573994) (xy 286.318972 -293.52494) (xy 285.980124 -293.52494)
			(xy 285.979629 -293.549547) (xy 285.971734 -293.598124) (xy 285.95615 -293.644805) (xy 285.933279 -293.688382)
			(xy 285.903714 -293.727726) (xy 285.868221 -293.761818) (xy 285.827718 -293.789774) (xy 285.783256 -293.810872)
			(xy 285.735985 -293.824564) (xy 285.68713 -293.830496) (xy 285.637955 -293.828515) (xy 285.589736 -293.818671)
			(xy 285.54372 -293.801219) (xy 285.501099 -293.776612) (xy 285.462978 -293.745487) (xy 285.430343 -293.70865)
			(xy 285.40404 -293.667054) (xy 285.384749 -293.621778) (xy 285.372972 -293.573994) (xy 285.369012 -293.52494)
			(xy 285.030164 -293.52494) (xy 285.029669 -293.549547) (xy 285.021774 -293.598124) (xy 285.00619 -293.644805)
			(xy 284.983319 -293.688382) (xy 284.953754 -293.727726) (xy 284.918261 -293.761818) (xy 284.877758 -293.789774)
			(xy 284.833296 -293.810872) (xy 284.786025 -293.824564) (xy 284.73717 -293.830496) (xy 284.687995 -293.828515)
			(xy 284.639776 -293.818671) (xy 284.59376 -293.801219) (xy 284.551139 -293.776612) (xy 284.513018 -293.745487)
			(xy 284.480383 -293.70865) (xy 284.45408 -293.667054) (xy 284.434789 -293.621778) (xy 284.423012 -293.573994)
			(xy 284.419052 -293.52494) (xy 284.080204 -293.52494) (xy 284.079709 -293.549547) (xy 284.071814 -293.598124)
			(xy 284.05623 -293.644805) (xy 284.033359 -293.688382) (xy 284.003794 -293.727726) (xy 283.968301 -293.761818)
			(xy 283.927798 -293.789774) (xy 283.883336 -293.810872) (xy 283.836065 -293.824564) (xy 283.78721 -293.830496)
			(xy 283.738035 -293.828515) (xy 283.689816 -293.818671) (xy 283.6438 -293.801219) (xy 283.601179 -293.776612)
			(xy 283.563058 -293.745487) (xy 283.530423 -293.70865) (xy 283.50412 -293.667054) (xy 283.484829 -293.621778)
			(xy 283.473052 -293.573994) (xy 283.469092 -293.52494) (xy 283.130244 -293.52494) (xy 283.129749 -293.549547)
			(xy 283.121854 -293.598124) (xy 283.10627 -293.644805) (xy 283.083399 -293.688382) (xy 283.053834 -293.727726)
			(xy 283.018341 -293.761818) (xy 282.977838 -293.789774) (xy 282.933376 -293.810872) (xy 282.886105 -293.824564)
			(xy 282.83725 -293.830496) (xy 282.788075 -293.828515) (xy 282.739856 -293.818671) (xy 282.69384 -293.801219)
			(xy 282.651219 -293.776612) (xy 282.613098 -293.745487) (xy 282.580463 -293.70865) (xy 282.55416 -293.667054)
			(xy 282.534869 -293.621778) (xy 282.523092 -293.573994) (xy 282.519132 -293.52494) (xy 282.18003 -293.52494)
			(xy 282.179535 -293.549547) (xy 282.17164 -293.598124) (xy 282.156056 -293.644805) (xy 282.133185 -293.688382)
			(xy 282.10362 -293.727726) (xy 282.068127 -293.761818) (xy 282.027624 -293.789774) (xy 281.983162 -293.810872)
			(xy 281.935891 -293.824564) (xy 281.887036 -293.830496) (xy 281.837861 -293.828515) (xy 281.789642 -293.818671)
			(xy 281.743626 -293.801219) (xy 281.701005 -293.776612) (xy 281.662884 -293.745487) (xy 281.630249 -293.70865)
			(xy 281.603946 -293.667054) (xy 281.584655 -293.621778) (xy 281.572878 -293.573994) (xy 281.568918 -293.52494)
			(xy 281.23007 -293.52494) (xy 281.229575 -293.549547) (xy 281.22168 -293.598124) (xy 281.206096 -293.644805)
			(xy 281.183225 -293.688382) (xy 281.15366 -293.727726) (xy 281.118167 -293.761818) (xy 281.077664 -293.789774)
			(xy 281.033202 -293.810872) (xy 280.985931 -293.824564) (xy 280.937076 -293.830496) (xy 280.887901 -293.828515)
			(xy 280.839682 -293.818671) (xy 280.793666 -293.801219) (xy 280.751045 -293.776612) (xy 280.712924 -293.745487)
			(xy 280.680289 -293.70865) (xy 280.653986 -293.667054) (xy 280.634695 -293.621778) (xy 280.622918 -293.573994)
			(xy 280.618958 -293.52494) (xy 280.28011 -293.52494) (xy 280.279615 -293.549547) (xy 280.27172 -293.598124)
			(xy 280.256136 -293.644805) (xy 280.233265 -293.688382) (xy 280.2037 -293.727726) (xy 280.168207 -293.761818)
			(xy 280.127704 -293.789774) (xy 280.083242 -293.810872) (xy 280.035971 -293.824564) (xy 279.987116 -293.830496)
			(xy 279.937941 -293.828515) (xy 279.889722 -293.818671) (xy 279.843706 -293.801219) (xy 279.801085 -293.776612)
			(xy 279.762964 -293.745487) (xy 279.730329 -293.70865) (xy 279.704026 -293.667054) (xy 279.684735 -293.621778)
			(xy 279.672958 -293.573994) (xy 279.668998 -293.52494) (xy 279.41397 -293.52494) (xy 279.41397 -294.4749)
			(xy 279.668998 -294.4749) (xy 279.672958 -294.425846) (xy 279.684735 -294.378062) (xy 279.704026 -294.332786)
			(xy 279.730329 -294.29119) (xy 279.762964 -294.254353) (xy 279.801085 -294.223228) (xy 279.843706 -294.198621)
			(xy 279.889722 -294.181169) (xy 279.937941 -294.171325) (xy 279.987116 -294.169344) (xy 280.035971 -294.175276)
			(xy 280.083242 -294.188968) (xy 280.127704 -294.210066) (xy 280.168207 -294.238022) (xy 280.2037 -294.272114)
			(xy 280.233265 -294.311458) (xy 280.256136 -294.355035) (xy 280.27172 -294.401716) (xy 280.279615 -294.450293)
			(xy 280.28011 -294.4749) (xy 280.618958 -294.4749) (xy 280.622918 -294.425846) (xy 280.634695 -294.378062)
			(xy 280.653986 -294.332786) (xy 280.680289 -294.29119) (xy 280.712924 -294.254353) (xy 280.751045 -294.223228)
			(xy 280.793666 -294.198621) (xy 280.839682 -294.181169) (xy 280.887901 -294.171325) (xy 280.937076 -294.169344)
			(xy 280.985931 -294.175276) (xy 281.033202 -294.188968) (xy 281.077664 -294.210066) (xy 281.118167 -294.238022)
			(xy 281.15366 -294.272114) (xy 281.183225 -294.311458) (xy 281.206096 -294.355035) (xy 281.22168 -294.401716)
			(xy 281.229575 -294.450293) (xy 281.23007 -294.4749) (xy 281.568918 -294.4749) (xy 281.572878 -294.425846)
			(xy 281.584655 -294.378062) (xy 281.603946 -294.332786) (xy 281.630249 -294.29119) (xy 281.662884 -294.254353)
			(xy 281.701005 -294.223228) (xy 281.743626 -294.198621) (xy 281.789642 -294.181169) (xy 281.837861 -294.171325)
			(xy 281.887036 -294.169344) (xy 281.935891 -294.175276) (xy 281.983162 -294.188968) (xy 282.027624 -294.210066)
			(xy 282.068127 -294.238022) (xy 282.10362 -294.272114) (xy 282.133185 -294.311458) (xy 282.156056 -294.355035)
			(xy 282.17164 -294.401716) (xy 282.179535 -294.450293) (xy 282.18003 -294.4749) (xy 282.519132 -294.4749)
			(xy 282.523092 -294.425846) (xy 282.534869 -294.378062) (xy 282.55416 -294.332786) (xy 282.580463 -294.29119)
			(xy 282.613098 -294.254353) (xy 282.651219 -294.223228) (xy 282.69384 -294.198621) (xy 282.739856 -294.181169)
			(xy 282.788075 -294.171325) (xy 282.83725 -294.169344) (xy 282.886105 -294.175276) (xy 282.933376 -294.188968)
			(xy 282.977838 -294.210066) (xy 283.018341 -294.238022) (xy 283.053834 -294.272114) (xy 283.083399 -294.311458)
			(xy 283.10627 -294.355035) (xy 283.121854 -294.401716) (xy 283.129749 -294.450293) (xy 283.130244 -294.4749)
			(xy 283.469092 -294.4749) (xy 283.473052 -294.425846) (xy 283.484829 -294.378062) (xy 283.50412 -294.332786)
			(xy 283.530423 -294.29119) (xy 283.563058 -294.254353) (xy 283.601179 -294.223228) (xy 283.6438 -294.198621)
			(xy 283.689816 -294.181169) (xy 283.738035 -294.171325) (xy 283.78721 -294.169344) (xy 283.836065 -294.175276)
			(xy 283.883336 -294.188968) (xy 283.927798 -294.210066) (xy 283.968301 -294.238022) (xy 284.003794 -294.272114)
			(xy 284.033359 -294.311458) (xy 284.05623 -294.355035) (xy 284.071814 -294.401716) (xy 284.079709 -294.450293)
			(xy 284.080204 -294.4749) (xy 284.419052 -294.4749) (xy 284.423012 -294.425846) (xy 284.434789 -294.378062)
			(xy 284.45408 -294.332786) (xy 284.480383 -294.29119) (xy 284.513018 -294.254353) (xy 284.551139 -294.223228)
			(xy 284.59376 -294.198621) (xy 284.639776 -294.181169) (xy 284.687995 -294.171325) (xy 284.73717 -294.169344)
			(xy 284.786025 -294.175276) (xy 284.833296 -294.188968) (xy 284.877758 -294.210066) (xy 284.918261 -294.238022)
			(xy 284.953754 -294.272114) (xy 284.983319 -294.311458) (xy 285.00619 -294.355035) (xy 285.021774 -294.401716)
			(xy 285.029669 -294.450293) (xy 285.030164 -294.4749) (xy 285.369012 -294.4749) (xy 285.372972 -294.425846)
			(xy 285.384749 -294.378062) (xy 285.40404 -294.332786) (xy 285.430343 -294.29119) (xy 285.462978 -294.254353)
			(xy 285.501099 -294.223228) (xy 285.54372 -294.198621) (xy 285.589736 -294.181169) (xy 285.637955 -294.171325)
			(xy 285.68713 -294.169344) (xy 285.735985 -294.175276) (xy 285.783256 -294.188968) (xy 285.827718 -294.210066)
			(xy 285.868221 -294.238022) (xy 285.903714 -294.272114) (xy 285.933279 -294.311458) (xy 285.95615 -294.355035)
			(xy 285.971734 -294.401716) (xy 285.979629 -294.450293) (xy 285.980124 -294.4749) (xy 286.318972 -294.4749)
			(xy 286.322932 -294.425846) (xy 286.334709 -294.378062) (xy 286.354 -294.332786) (xy 286.380303 -294.29119)
			(xy 286.412938 -294.254353) (xy 286.451059 -294.223228) (xy 286.49368 -294.198621) (xy 286.539696 -294.181169)
			(xy 286.587915 -294.171325) (xy 286.63709 -294.169344) (xy 286.685945 -294.175276) (xy 286.733216 -294.188968)
			(xy 286.777678 -294.210066) (xy 286.818181 -294.238022) (xy 286.853674 -294.272114) (xy 286.883239 -294.311458)
			(xy 286.90611 -294.355035) (xy 286.921694 -294.401716) (xy 286.929589 -294.450293) (xy 286.930084 -294.4749)
			(xy 287.268932 -294.4749) (xy 287.272892 -294.425846) (xy 287.284669 -294.378062) (xy 287.30396 -294.332786)
			(xy 287.330263 -294.29119) (xy 287.362898 -294.254353) (xy 287.401019 -294.223228) (xy 287.44364 -294.198621)
			(xy 287.489656 -294.181169) (xy 287.537875 -294.171325) (xy 287.58705 -294.169344) (xy 287.635905 -294.175276)
			(xy 287.683176 -294.188968) (xy 287.727638 -294.210066) (xy 287.768141 -294.238022) (xy 287.803634 -294.272114)
			(xy 287.833199 -294.311458) (xy 287.85607 -294.355035) (xy 287.871654 -294.401716) (xy 287.879549 -294.450293)
			(xy 287.880044 -294.4749) (xy 288.218892 -294.4749) (xy 288.222852 -294.425846) (xy 288.234629 -294.378062)
			(xy 288.25392 -294.332786) (xy 288.280223 -294.29119) (xy 288.312858 -294.254353) (xy 288.350979 -294.223228)
			(xy 288.3936 -294.198621) (xy 288.439616 -294.181169) (xy 288.487835 -294.171325) (xy 288.53701 -294.169344)
			(xy 288.585865 -294.175276) (xy 288.633136 -294.188968) (xy 288.677598 -294.210066) (xy 288.718101 -294.238022)
			(xy 288.753594 -294.272114) (xy 288.783159 -294.311458) (xy 288.80603 -294.355035) (xy 288.821614 -294.401716)
			(xy 288.829509 -294.450293) (xy 288.830004 -294.4749) (xy 289.169106 -294.4749) (xy 289.173066 -294.425846)
			(xy 289.184843 -294.378062) (xy 289.204134 -294.332786) (xy 289.230437 -294.29119) (xy 289.263072 -294.254353)
			(xy 289.301193 -294.223228) (xy 289.343814 -294.198621) (xy 289.38983 -294.181169) (xy 289.438049 -294.171325)
			(xy 289.487224 -294.169344) (xy 289.536079 -294.175276) (xy 289.58335 -294.188968) (xy 289.627812 -294.210066)
			(xy 289.668315 -294.238022) (xy 289.703808 -294.272114) (xy 289.733373 -294.311458) (xy 289.756244 -294.355035)
			(xy 289.771828 -294.401716) (xy 289.779723 -294.450293) (xy 289.780218 -294.4749) (xy 290.119066 -294.4749)
			(xy 290.123026 -294.425846) (xy 290.134803 -294.378062) (xy 290.154094 -294.332786) (xy 290.180397 -294.29119)
			(xy 290.213032 -294.254353) (xy 290.251153 -294.223228) (xy 290.293774 -294.198621) (xy 290.33979 -294.181169)
			(xy 290.388009 -294.171325) (xy 290.437184 -294.169344) (xy 290.486039 -294.175276) (xy 290.53331 -294.188968)
			(xy 290.577772 -294.210066) (xy 290.618275 -294.238022) (xy 290.653768 -294.272114) (xy 290.683333 -294.311458)
			(xy 290.706204 -294.355035) (xy 290.721788 -294.401716) (xy 290.729683 -294.450293) (xy 290.730178 -294.4749)
			(xy 292.018986 -294.4749) (xy 292.022946 -294.425846) (xy 292.034723 -294.378062) (xy 292.054014 -294.332786)
			(xy 292.080317 -294.29119) (xy 292.112952 -294.254353) (xy 292.151073 -294.223228) (xy 292.193694 -294.198621)
			(xy 292.23971 -294.181169) (xy 292.287929 -294.171325) (xy 292.337104 -294.169344) (xy 292.385959 -294.175276)
			(xy 292.43323 -294.188968) (xy 292.477692 -294.210066) (xy 292.518195 -294.238022) (xy 292.553688 -294.272114)
			(xy 292.583253 -294.311458) (xy 292.606124 -294.355035) (xy 292.621708 -294.401716) (xy 292.629603 -294.450293)
			(xy 292.630098 -294.4749) (xy 292.968946 -294.4749) (xy 292.972906 -294.425846) (xy 292.984683 -294.378062)
			(xy 293.003974 -294.332786) (xy 293.030277 -294.29119) (xy 293.062912 -294.254353) (xy 293.101033 -294.223228)
			(xy 293.143654 -294.198621) (xy 293.18967 -294.181169) (xy 293.237889 -294.171325) (xy 293.287064 -294.169344)
			(xy 293.335919 -294.175276) (xy 293.38319 -294.188968) (xy 293.427652 -294.210066) (xy 293.468155 -294.238022)
			(xy 293.503648 -294.272114) (xy 293.533213 -294.311458) (xy 293.556084 -294.355035) (xy 293.571668 -294.401716)
			(xy 293.579563 -294.450293) (xy 293.580058 -294.4749) (xy 293.918906 -294.4749) (xy 293.922866 -294.425846)
			(xy 293.934643 -294.378062) (xy 293.953934 -294.332786) (xy 293.980237 -294.29119) (xy 294.012872 -294.254353)
			(xy 294.050993 -294.223228) (xy 294.093614 -294.198621) (xy 294.13963 -294.181169) (xy 294.187849 -294.171325)
			(xy 294.237024 -294.169344) (xy 294.285879 -294.175276) (xy 294.33315 -294.188968) (xy 294.377612 -294.210066)
			(xy 294.418115 -294.238022) (xy 294.453608 -294.272114) (xy 294.483173 -294.311458) (xy 294.506044 -294.355035)
			(xy 294.521628 -294.401716) (xy 294.529523 -294.450293) (xy 294.530018 -294.4749) (xy 294.86912 -294.4749)
			(xy 294.87308 -294.425846) (xy 294.884857 -294.378062) (xy 294.904148 -294.332786) (xy 294.930451 -294.29119)
			(xy 294.963086 -294.254353) (xy 295.001207 -294.223228) (xy 295.043828 -294.198621) (xy 295.089844 -294.181169)
			(xy 295.138063 -294.171325) (xy 295.187238 -294.169344) (xy 295.236093 -294.175276) (xy 295.283364 -294.188968)
			(xy 295.327826 -294.210066) (xy 295.368329 -294.238022) (xy 295.403822 -294.272114) (xy 295.433387 -294.311458)
			(xy 295.456258 -294.355035) (xy 295.471842 -294.401716) (xy 295.479737 -294.450293) (xy 295.480232 -294.4749)
			(xy 295.81908 -294.4749) (xy 295.82304 -294.425846) (xy 295.834817 -294.378062) (xy 295.854108 -294.332786)
			(xy 295.880411 -294.29119) (xy 295.913046 -294.254353) (xy 295.951167 -294.223228) (xy 295.993788 -294.198621)
			(xy 296.039804 -294.181169) (xy 296.088023 -294.171325) (xy 296.137198 -294.169344) (xy 296.186053 -294.175276)
			(xy 296.233324 -294.188968) (xy 296.277786 -294.210066) (xy 296.318289 -294.238022) (xy 296.353782 -294.272114)
			(xy 296.383347 -294.311458) (xy 296.406218 -294.355035) (xy 296.421802 -294.401716) (xy 296.429697 -294.450293)
			(xy 296.430192 -294.4749) (xy 296.76904 -294.4749) (xy 296.773 -294.425846) (xy 296.784777 -294.378062)
			(xy 296.804068 -294.332786) (xy 296.830371 -294.29119) (xy 296.863006 -294.254353) (xy 296.901127 -294.223228)
			(xy 296.943748 -294.198621) (xy 296.989764 -294.181169) (xy 297.037983 -294.171325) (xy 297.087158 -294.169344)
			(xy 297.136013 -294.175276) (xy 297.183284 -294.188968) (xy 297.227746 -294.210066) (xy 297.268249 -294.238022)
			(xy 297.303742 -294.272114) (xy 297.333307 -294.311458) (xy 297.356178 -294.355035) (xy 297.371762 -294.401716)
			(xy 297.379657 -294.450293) (xy 297.380152 -294.4749) (xy 297.719 -294.4749) (xy 297.72296 -294.425846)
			(xy 297.734737 -294.378062) (xy 297.754028 -294.332786) (xy 297.780331 -294.29119) (xy 297.812966 -294.254353)
			(xy 297.851087 -294.223228) (xy 297.893708 -294.198621) (xy 297.939724 -294.181169) (xy 297.987943 -294.171325)
			(xy 298.037118 -294.169344) (xy 298.085973 -294.175276) (xy 298.133244 -294.188968) (xy 298.177706 -294.210066)
			(xy 298.218209 -294.238022) (xy 298.253702 -294.272114) (xy 298.283267 -294.311458) (xy 298.306138 -294.355035)
			(xy 298.321722 -294.401716) (xy 298.329617 -294.450293) (xy 298.330112 -294.4749) (xy 301.519094 -294.4749)
			(xy 301.523054 -294.425846) (xy 301.534831 -294.378062) (xy 301.554122 -294.332786) (xy 301.580425 -294.29119)
			(xy 301.61306 -294.254353) (xy 301.651181 -294.223228) (xy 301.693802 -294.198621) (xy 301.739818 -294.181169)
			(xy 301.788037 -294.171325) (xy 301.837212 -294.169344) (xy 301.886067 -294.175276) (xy 301.933338 -294.188968)
			(xy 301.9778 -294.210066) (xy 302.018303 -294.238022) (xy 302.053796 -294.272114) (xy 302.083361 -294.311458)
			(xy 302.106232 -294.355035) (xy 302.121816 -294.401716) (xy 302.129711 -294.450293) (xy 302.130206 -294.4749)
			(xy 302.469054 -294.4749) (xy 302.473014 -294.425846) (xy 302.484791 -294.378062) (xy 302.504082 -294.332786)
			(xy 302.530385 -294.29119) (xy 302.56302 -294.254353) (xy 302.601141 -294.223228) (xy 302.643762 -294.198621)
			(xy 302.689778 -294.181169) (xy 302.737997 -294.171325) (xy 302.787172 -294.169344) (xy 302.836027 -294.175276)
			(xy 302.883298 -294.188968) (xy 302.92776 -294.210066) (xy 302.968263 -294.238022) (xy 303.003756 -294.272114)
			(xy 303.033321 -294.311458) (xy 303.056192 -294.355035) (xy 303.071776 -294.401716) (xy 303.079671 -294.450293)
			(xy 303.080166 -294.4749) (xy 303.419014 -294.4749) (xy 303.422974 -294.425846) (xy 303.434751 -294.378062)
			(xy 303.454042 -294.332786) (xy 303.480345 -294.29119) (xy 303.51298 -294.254353) (xy 303.551101 -294.223228)
			(xy 303.593722 -294.198621) (xy 303.639738 -294.181169) (xy 303.687957 -294.171325) (xy 303.737132 -294.169344)
			(xy 303.785987 -294.175276) (xy 303.833258 -294.188968) (xy 303.87772 -294.210066) (xy 303.918223 -294.238022)
			(xy 303.953716 -294.272114) (xy 303.983281 -294.311458) (xy 304.006152 -294.355035) (xy 304.021736 -294.401716)
			(xy 304.029631 -294.450293) (xy 304.030126 -294.4749) (xy 304.368974 -294.4749) (xy 304.372934 -294.425846)
			(xy 304.384711 -294.378062) (xy 304.404002 -294.332786) (xy 304.430305 -294.29119) (xy 304.46294 -294.254353)
			(xy 304.501061 -294.223228) (xy 304.543682 -294.198621) (xy 304.589698 -294.181169) (xy 304.637917 -294.171325)
			(xy 304.687092 -294.169344) (xy 304.735947 -294.175276) (xy 304.783218 -294.188968) (xy 304.82768 -294.210066)
			(xy 304.868183 -294.238022) (xy 304.903676 -294.272114) (xy 304.933241 -294.311458) (xy 304.956112 -294.355035)
			(xy 304.971696 -294.401716) (xy 304.979591 -294.450293) (xy 304.980086 -294.4749) (xy 305.318934 -294.4749)
			(xy 305.322894 -294.425846) (xy 305.334671 -294.378062) (xy 305.353962 -294.332786) (xy 305.380265 -294.29119)
			(xy 305.4129 -294.254353) (xy 305.451021 -294.223228) (xy 305.493642 -294.198621) (xy 305.539658 -294.181169)
			(xy 305.587877 -294.171325) (xy 305.637052 -294.169344) (xy 305.685907 -294.175276) (xy 305.733178 -294.188968)
			(xy 305.77764 -294.210066) (xy 305.818143 -294.238022) (xy 305.853636 -294.272114) (xy 305.883201 -294.311458)
			(xy 305.906072 -294.355035) (xy 305.921656 -294.401716) (xy 305.929551 -294.450293) (xy 305.930046 -294.4749)
			(xy 306.268894 -294.4749) (xy 306.272854 -294.425846) (xy 306.284631 -294.378062) (xy 306.303922 -294.332786)
			(xy 306.330225 -294.29119) (xy 306.36286 -294.254353) (xy 306.400981 -294.223228) (xy 306.443602 -294.198621)
			(xy 306.489618 -294.181169) (xy 306.537837 -294.171325) (xy 306.587012 -294.169344) (xy 306.635867 -294.175276)
			(xy 306.683138 -294.188968) (xy 306.7276 -294.210066) (xy 306.768103 -294.238022) (xy 306.803596 -294.272114)
			(xy 306.833161 -294.311458) (xy 306.856032 -294.355035) (xy 306.871616 -294.401716) (xy 306.879511 -294.450293)
			(xy 306.880006 -294.4749) (xy 307.219108 -294.4749) (xy 307.223068 -294.425846) (xy 307.234845 -294.378062)
			(xy 307.254136 -294.332786) (xy 307.280439 -294.29119) (xy 307.313074 -294.254353) (xy 307.351195 -294.223228)
			(xy 307.393816 -294.198621) (xy 307.439832 -294.181169) (xy 307.488051 -294.171325) (xy 307.537226 -294.169344)
			(xy 307.586081 -294.175276) (xy 307.633352 -294.188968) (xy 307.677814 -294.210066) (xy 307.718317 -294.238022)
			(xy 307.75381 -294.272114) (xy 307.783375 -294.311458) (xy 307.806246 -294.355035) (xy 307.82183 -294.401716)
			(xy 307.829725 -294.450293) (xy 307.83022 -294.4749) (xy 308.169068 -294.4749) (xy 308.173028 -294.425846)
			(xy 308.184805 -294.378062) (xy 308.204096 -294.332786) (xy 308.230399 -294.29119) (xy 308.263034 -294.254353)
			(xy 308.301155 -294.223228) (xy 308.343776 -294.198621) (xy 308.389792 -294.181169) (xy 308.438011 -294.171325)
			(xy 308.487186 -294.169344) (xy 308.536041 -294.175276) (xy 308.583312 -294.188968) (xy 308.627774 -294.210066)
			(xy 308.668277 -294.238022) (xy 308.70377 -294.272114) (xy 308.733335 -294.311458) (xy 308.756206 -294.355035)
			(xy 308.77179 -294.401716) (xy 308.779685 -294.450293) (xy 308.78018 -294.4749) (xy 309.119028 -294.4749)
			(xy 309.122988 -294.425846) (xy 309.134765 -294.378062) (xy 309.154056 -294.332786) (xy 309.180359 -294.29119)
			(xy 309.212994 -294.254353) (xy 309.251115 -294.223228) (xy 309.293736 -294.198621) (xy 309.339752 -294.181169)
			(xy 309.387971 -294.171325) (xy 309.437146 -294.169344) (xy 309.486001 -294.175276) (xy 309.533272 -294.188968)
			(xy 309.577734 -294.210066) (xy 309.618237 -294.238022) (xy 309.65373 -294.272114) (xy 309.683295 -294.311458)
			(xy 309.706166 -294.355035) (xy 309.72175 -294.401716) (xy 309.729645 -294.450293) (xy 309.73014 -294.4749)
			(xy 310.068988 -294.4749) (xy 310.072948 -294.425846) (xy 310.084725 -294.378062) (xy 310.104016 -294.332786)
			(xy 310.130319 -294.29119) (xy 310.162954 -294.254353) (xy 310.201075 -294.223228) (xy 310.243696 -294.198621)
			(xy 310.289712 -294.181169) (xy 310.337931 -294.171325) (xy 310.387106 -294.169344) (xy 310.435961 -294.175276)
			(xy 310.483232 -294.188968) (xy 310.527694 -294.210066) (xy 310.568197 -294.238022) (xy 310.60369 -294.272114)
			(xy 310.633255 -294.311458) (xy 310.656126 -294.355035) (xy 310.67171 -294.401716) (xy 310.679605 -294.450293)
			(xy 310.6801 -294.4749) (xy 311.018948 -294.4749) (xy 311.022908 -294.425846) (xy 311.034685 -294.378062)
			(xy 311.053976 -294.332786) (xy 311.080279 -294.29119) (xy 311.112914 -294.254353) (xy 311.151035 -294.223228)
			(xy 311.193656 -294.198621) (xy 311.239672 -294.181169) (xy 311.287891 -294.171325) (xy 311.337066 -294.169344)
			(xy 311.385921 -294.175276) (xy 311.433192 -294.188968) (xy 311.477654 -294.210066) (xy 311.518157 -294.238022)
			(xy 311.55365 -294.272114) (xy 311.583215 -294.311458) (xy 311.606086 -294.355035) (xy 311.62167 -294.401716)
			(xy 311.629565 -294.450293) (xy 311.63006 -294.4749) (xy 311.968908 -294.4749) (xy 311.972868 -294.425846)
			(xy 311.984645 -294.378062) (xy 312.003936 -294.332786) (xy 312.030239 -294.29119) (xy 312.062874 -294.254353)
			(xy 312.100995 -294.223228) (xy 312.143616 -294.198621) (xy 312.189632 -294.181169) (xy 312.237851 -294.171325)
			(xy 312.287026 -294.169344) (xy 312.335881 -294.175276) (xy 312.383152 -294.188968) (xy 312.427614 -294.210066)
			(xy 312.468117 -294.238022) (xy 312.50361 -294.272114) (xy 312.533175 -294.311458) (xy 312.556046 -294.355035)
			(xy 312.57163 -294.401716) (xy 312.579525 -294.450293) (xy 312.58002 -294.4749) (xy 312.919122 -294.4749)
			(xy 312.923082 -294.425846) (xy 312.934859 -294.378062) (xy 312.95415 -294.332786) (xy 312.980453 -294.29119)
			(xy 313.013088 -294.254353) (xy 313.051209 -294.223228) (xy 313.09383 -294.198621) (xy 313.139846 -294.181169)
			(xy 313.188065 -294.171325) (xy 313.23724 -294.169344) (xy 313.286095 -294.175276) (xy 313.333366 -294.188968)
			(xy 313.377828 -294.210066) (xy 313.418331 -294.238022) (xy 313.453824 -294.272114) (xy 313.483389 -294.311458)
			(xy 313.50626 -294.355035) (xy 313.521844 -294.401716) (xy 313.529739 -294.450293) (xy 313.530234 -294.4749)
			(xy 313.869082 -294.4749) (xy 313.873042 -294.425846) (xy 313.884819 -294.378062) (xy 313.90411 -294.332786)
			(xy 313.930413 -294.29119) (xy 313.963048 -294.254353) (xy 314.001169 -294.223228) (xy 314.04379 -294.198621)
			(xy 314.089806 -294.181169) (xy 314.138025 -294.171325) (xy 314.1872 -294.169344) (xy 314.236055 -294.175276)
			(xy 314.283326 -294.188968) (xy 314.327788 -294.210066) (xy 314.368291 -294.238022) (xy 314.403784 -294.272114)
			(xy 314.433349 -294.311458) (xy 314.45622 -294.355035) (xy 314.471804 -294.401716) (xy 314.479699 -294.450293)
			(xy 314.480194 -294.4749) (xy 314.819042 -294.4749) (xy 314.823002 -294.425846) (xy 314.834779 -294.378062)
			(xy 314.85407 -294.332786) (xy 314.880373 -294.29119) (xy 314.913008 -294.254353) (xy 314.951129 -294.223228)
			(xy 314.99375 -294.198621) (xy 315.039766 -294.181169) (xy 315.087985 -294.171325) (xy 315.13716 -294.169344)
			(xy 315.186015 -294.175276) (xy 315.233286 -294.188968) (xy 315.277748 -294.210066) (xy 315.318251 -294.238022)
			(xy 315.353744 -294.272114) (xy 315.383309 -294.311458) (xy 315.40618 -294.355035) (xy 315.421764 -294.401716)
			(xy 315.429659 -294.450293) (xy 315.430154 -294.4749) (xy 315.429659 -294.499507) (xy 315.421764 -294.548084)
			(xy 315.40618 -294.594765) (xy 315.383309 -294.638342) (xy 315.370443 -294.655464) (xy 321.363026 -294.655464)
			(xy 321.370781 -294.601508) (xy 321.386135 -294.549205) (xy 321.408778 -294.49962) (xy 321.438246 -294.453761)
			(xy 321.473941 -294.412564) (xy 321.515135 -294.376866) (xy 321.560991 -294.347393) (xy 321.610574 -294.324747)
			(xy 321.662876 -294.309388) (xy 321.716831 -294.301628) (xy 321.744086 -294.301164) (xy 321.769486 -294.301926)
			(xy 321.784217 -294.302451) (xy 321.812948 -294.295898) (xy 321.838614 -294.281417) (xy 321.859079 -294.260214)
			(xy 321.872642 -294.234052) (xy 321.878174 -294.205107) (xy 321.875215 -294.175788) (xy 321.87007 -294.161972)
			(xy 321.860908 -294.13877) (xy 321.848018 -294.090579) (xy 321.841518 -294.041119) (xy 321.841114 -294.016176)
			(xy 321.841604 -293.988927) (xy 321.849363 -293.934985) (xy 321.86472 -293.882696) (xy 321.887361 -293.833124)
			(xy 321.916827 -293.787279) (xy 321.952517 -293.746094) (xy 321.993705 -293.710407) (xy 322.039553 -293.680946)
			(xy 322.089126 -293.658308) (xy 322.141417 -293.642956) (xy 322.19536 -293.635202) (xy 322.249857 -293.635203)
			(xy 322.3038 -293.64296) (xy 322.35609 -293.658314) (xy 322.405663 -293.680954) (xy 322.451509 -293.710418)
			(xy 322.492695 -293.746106) (xy 322.528383 -293.787293) (xy 322.557847 -293.833139) (xy 322.580487 -293.882712)
			(xy 322.595841 -293.935002) (xy 322.602399 -293.980616) (xy 323.480682 -293.980616) (xy 323.484753 -293.924994)
			(xy 323.496879 -293.870557) (xy 323.516802 -293.818466) (xy 323.544098 -293.769831) (xy 323.578184 -293.725688)
			(xy 323.618333 -293.686979) (xy 323.663691 -293.654528) (xy 323.713291 -293.629027) (xy 323.766075 -293.61102)
			(xy 323.820918 -293.60089) (xy 323.876652 -293.598853) (xy 323.932089 -293.604953) (xy 323.986046 -293.619059)
			(xy 324.037375 -293.640871) (xy 324.084981 -293.669925) (xy 324.127849 -293.7056) (xy 324.165066 -293.747137)
			(xy 324.195839 -293.79365) (xy 324.219511 -293.844147) (xy 324.235579 -293.897554) (xy 324.243699 -293.95273)
			(xy 324.244208 -293.980616) (xy 324.243699 -294.008502) (xy 324.235579 -294.063678) (xy 324.219511 -294.117085)
			(xy 324.195839 -294.167582) (xy 324.165066 -294.214095) (xy 324.127849 -294.255632) (xy 324.084981 -294.291307)
			(xy 324.037375 -294.320361) (xy 323.986046 -294.342173) (xy 323.932089 -294.356279) (xy 323.876652 -294.362379)
			(xy 323.820918 -294.360342) (xy 323.766075 -294.350212) (xy 323.713291 -294.332205) (xy 323.663691 -294.306704)
			(xy 323.618333 -294.274253) (xy 323.578184 -294.235544) (xy 323.544098 -294.191401) (xy 323.516802 -294.142766)
			(xy 323.496879 -294.090675) (xy 323.484753 -294.036238) (xy 323.480682 -293.980616) (xy 322.602399 -293.980616)
			(xy 322.603597 -293.988945) (xy 322.603598 -294.043442) (xy 322.595844 -294.097385) (xy 322.580491 -294.149676)
			(xy 322.557853 -294.199249) (xy 322.528391 -294.245096) (xy 322.492704 -294.286284) (xy 322.451519 -294.321974)
			(xy 322.405674 -294.35144) (xy 322.356103 -294.374081) (xy 322.303813 -294.389438) (xy 322.249871 -294.397196)
			(xy 322.222622 -294.397684) (xy 322.197222 -294.396922) (xy 322.182492 -294.396476) (xy 322.153774 -294.403023)
			(xy 322.128118 -294.417493) (xy 322.107658 -294.438682) (xy 322.094094 -294.464828) (xy 322.088555 -294.493757)
			(xy 322.08934 -294.50157) (xy 322.736462 -294.50157) (xy 322.740533 -294.445948) (xy 322.752659 -294.391511)
			(xy 322.772582 -294.33942) (xy 322.799878 -294.290785) (xy 322.833964 -294.246642) (xy 322.874113 -294.207933)
			(xy 322.919471 -294.175482) (xy 322.969071 -294.149981) (xy 323.021855 -294.131974) (xy 323.076698 -294.121844)
			(xy 323.132432 -294.119807) (xy 323.187869 -294.125907) (xy 323.241826 -294.140013) (xy 323.293155 -294.161825)
			(xy 323.340761 -294.190879) (xy 323.383629 -294.226554) (xy 323.420846 -294.268091) (xy 323.451619 -294.314604)
			(xy 323.475291 -294.365101) (xy 323.491359 -294.418508) (xy 323.499479 -294.473684) (xy 323.499988 -294.50157)
			(xy 323.499479 -294.529456) (xy 323.491359 -294.584632) (xy 323.475291 -294.638039) (xy 323.451619 -294.688536)
			(xy 323.420846 -294.735049) (xy 323.383629 -294.776586) (xy 323.340761 -294.812261) (xy 323.293155 -294.841315)
			(xy 323.268396 -294.851836) (xy 334.24698 -294.851836) (xy 334.251051 -294.796214) (xy 334.263177 -294.741777)
			(xy 334.2831 -294.689686) (xy 334.310396 -294.641051) (xy 334.344482 -294.596908) (xy 334.384631 -294.558199)
			(xy 334.429989 -294.525748) (xy 334.479589 -294.500247) (xy 334.532373 -294.48224) (xy 334.587216 -294.47211)
			(xy 334.64295 -294.470073) (xy 334.698387 -294.476173) (xy 334.752344 -294.490279) (xy 334.803673 -294.512091)
			(xy 334.851279 -294.541145) (xy 334.894147 -294.57682) (xy 334.931364 -294.618357) (xy 334.962137 -294.66487)
			(xy 334.985809 -294.715367) (xy 335.001877 -294.768774) (xy 335.009997 -294.82395) (xy 335.010506 -294.851836)
			(xy 349.340676 -294.851836) (xy 349.344747 -294.796214) (xy 349.356873 -294.741777) (xy 349.376796 -294.689686)
			(xy 349.404092 -294.641051) (xy 349.438178 -294.596908) (xy 349.478327 -294.558199) (xy 349.523685 -294.525748)
			(xy 349.573285 -294.500247) (xy 349.626069 -294.48224) (xy 349.680912 -294.47211) (xy 349.736646 -294.470073)
			(xy 349.792083 -294.476173) (xy 349.84604 -294.490279) (xy 349.897369 -294.512091) (xy 349.944975 -294.541145)
			(xy 349.987843 -294.57682) (xy 350.02506 -294.618357) (xy 350.055833 -294.66487) (xy 350.079505 -294.715367)
			(xy 350.095573 -294.768774) (xy 350.103693 -294.82395) (xy 350.104202 -294.851836) (xy 350.103693 -294.879722)
			(xy 350.095573 -294.934898) (xy 350.079505 -294.988305) (xy 350.055833 -295.038802) (xy 350.02506 -295.085315)
			(xy 349.987843 -295.126852) (xy 349.944975 -295.162527) (xy 349.897369 -295.191581) (xy 349.84604 -295.213393)
			(xy 349.792083 -295.227499) (xy 349.736646 -295.233599) (xy 349.680912 -295.231562) (xy 349.626069 -295.221432)
			(xy 349.573285 -295.203425) (xy 349.523685 -295.177924) (xy 349.478327 -295.145473) (xy 349.438178 -295.106764)
			(xy 349.404092 -295.062621) (xy 349.376796 -295.013986) (xy 349.356873 -294.961895) (xy 349.344747 -294.907458)
			(xy 349.340676 -294.851836) (xy 335.010506 -294.851836) (xy 335.009997 -294.879722) (xy 335.001877 -294.934898)
			(xy 334.985809 -294.988305) (xy 334.962137 -295.038802) (xy 334.931364 -295.085315) (xy 334.894147 -295.126852)
			(xy 334.851279 -295.162527) (xy 334.803673 -295.191581) (xy 334.752344 -295.213393) (xy 334.698387 -295.227499)
			(xy 334.64295 -295.233599) (xy 334.587216 -295.231562) (xy 334.532373 -295.221432) (xy 334.479589 -295.203425)
			(xy 334.429989 -295.177924) (xy 334.384631 -295.145473) (xy 334.344482 -295.106764) (xy 334.310396 -295.062621)
			(xy 334.2831 -295.013986) (xy 334.263177 -294.961895) (xy 334.251051 -294.907458) (xy 334.24698 -294.851836)
			(xy 323.268396 -294.851836) (xy 323.241826 -294.863127) (xy 323.187869 -294.877233) (xy 323.132432 -294.883333)
			(xy 323.076698 -294.881296) (xy 323.021855 -294.871166) (xy 322.969071 -294.853159) (xy 322.919471 -294.827658)
			(xy 322.874113 -294.795207) (xy 322.833964 -294.756498) (xy 322.799878 -294.712355) (xy 322.772582 -294.66372)
			(xy 322.752659 -294.611629) (xy 322.740533 -294.557192) (xy 322.736462 -294.50157) (xy 322.08934 -294.50157)
			(xy 322.091501 -294.523064) (xy 322.096638 -294.536876) (xy 322.105784 -294.560084) (xy 322.118681 -294.608272)
			(xy 322.125186 -294.65773) (xy 322.125594 -294.682672) (xy 322.125175 -294.709927) (xy 322.117421 -294.763883)
			(xy 322.102068 -294.816186) (xy 322.079427 -294.865772) (xy 322.04996 -294.911631) (xy 322.014266 -294.952829)
			(xy 321.973072 -294.988529) (xy 321.927217 -295.018002) (xy 321.877634 -295.04065) (xy 321.825333 -295.05601)
			(xy 321.771378 -295.063771) (xy 321.716868 -295.063775) (xy 321.662912 -295.05602) (xy 321.610609 -295.040666)
			(xy 321.561024 -295.018025) (xy 321.515165 -294.988557) (xy 321.473967 -294.952863) (xy 321.438268 -294.911668)
			(xy 321.408795 -294.865813) (xy 321.386149 -294.81623) (xy 321.370789 -294.763929) (xy 321.363028 -294.709974)
			(xy 321.363026 -294.655464) (xy 315.370443 -294.655464) (xy 315.353744 -294.677686) (xy 315.318251 -294.711778)
			(xy 315.277748 -294.739734) (xy 315.233286 -294.760832) (xy 315.186015 -294.774524) (xy 315.13716 -294.780456)
			(xy 315.087985 -294.778475) (xy 315.039766 -294.768631) (xy 314.99375 -294.751179) (xy 314.951129 -294.726572)
			(xy 314.913008 -294.695447) (xy 314.880373 -294.65861) (xy 314.85407 -294.617014) (xy 314.834779 -294.571738)
			(xy 314.823002 -294.523954) (xy 314.819042 -294.4749) (xy 314.480194 -294.4749) (xy 314.479699 -294.499507)
			(xy 314.471804 -294.548084) (xy 314.45622 -294.594765) (xy 314.433349 -294.638342) (xy 314.403784 -294.677686)
			(xy 314.368291 -294.711778) (xy 314.327788 -294.739734) (xy 314.283326 -294.760832) (xy 314.236055 -294.774524)
			(xy 314.1872 -294.780456) (xy 314.138025 -294.778475) (xy 314.089806 -294.768631) (xy 314.04379 -294.751179)
			(xy 314.001169 -294.726572) (xy 313.963048 -294.695447) (xy 313.930413 -294.65861) (xy 313.90411 -294.617014)
			(xy 313.884819 -294.571738) (xy 313.873042 -294.523954) (xy 313.869082 -294.4749) (xy 313.530234 -294.4749)
			(xy 313.529739 -294.499507) (xy 313.521844 -294.548084) (xy 313.50626 -294.594765) (xy 313.483389 -294.638342)
			(xy 313.453824 -294.677686) (xy 313.418331 -294.711778) (xy 313.377828 -294.739734) (xy 313.333366 -294.760832)
			(xy 313.286095 -294.774524) (xy 313.23724 -294.780456) (xy 313.188065 -294.778475) (xy 313.139846 -294.768631)
			(xy 313.09383 -294.751179) (xy 313.051209 -294.726572) (xy 313.013088 -294.695447) (xy 312.980453 -294.65861)
			(xy 312.95415 -294.617014) (xy 312.934859 -294.571738) (xy 312.923082 -294.523954) (xy 312.919122 -294.4749)
			(xy 312.58002 -294.4749) (xy 312.579525 -294.499507) (xy 312.57163 -294.548084) (xy 312.556046 -294.594765)
			(xy 312.533175 -294.638342) (xy 312.50361 -294.677686) (xy 312.468117 -294.711778) (xy 312.427614 -294.739734)
			(xy 312.383152 -294.760832) (xy 312.335881 -294.774524) (xy 312.287026 -294.780456) (xy 312.237851 -294.778475)
			(xy 312.189632 -294.768631) (xy 312.143616 -294.751179) (xy 312.100995 -294.726572) (xy 312.062874 -294.695447)
			(xy 312.030239 -294.65861) (xy 312.003936 -294.617014) (xy 311.984645 -294.571738) (xy 311.972868 -294.523954)
			(xy 311.968908 -294.4749) (xy 311.63006 -294.4749) (xy 311.629565 -294.499507) (xy 311.62167 -294.548084)
			(xy 311.606086 -294.594765) (xy 311.583215 -294.638342) (xy 311.55365 -294.677686) (xy 311.518157 -294.711778)
			(xy 311.477654 -294.739734) (xy 311.433192 -294.760832) (xy 311.385921 -294.774524) (xy 311.337066 -294.780456)
			(xy 311.287891 -294.778475) (xy 311.239672 -294.768631) (xy 311.193656 -294.751179) (xy 311.151035 -294.726572)
			(xy 311.112914 -294.695447) (xy 311.080279 -294.65861) (xy 311.053976 -294.617014) (xy 311.034685 -294.571738)
			(xy 311.022908 -294.523954) (xy 311.018948 -294.4749) (xy 310.6801 -294.4749) (xy 310.679605 -294.499507)
			(xy 310.67171 -294.548084) (xy 310.656126 -294.594765) (xy 310.633255 -294.638342) (xy 310.60369 -294.677686)
			(xy 310.568197 -294.711778) (xy 310.527694 -294.739734) (xy 310.483232 -294.760832) (xy 310.435961 -294.774524)
			(xy 310.387106 -294.780456) (xy 310.337931 -294.778475) (xy 310.289712 -294.768631) (xy 310.243696 -294.751179)
			(xy 310.201075 -294.726572) (xy 310.162954 -294.695447) (xy 310.130319 -294.65861) (xy 310.104016 -294.617014)
			(xy 310.084725 -294.571738) (xy 310.072948 -294.523954) (xy 310.068988 -294.4749) (xy 309.73014 -294.4749)
			(xy 309.729645 -294.499507) (xy 309.72175 -294.548084) (xy 309.706166 -294.594765) (xy 309.683295 -294.638342)
			(xy 309.65373 -294.677686) (xy 309.618237 -294.711778) (xy 309.577734 -294.739734) (xy 309.533272 -294.760832)
			(xy 309.486001 -294.774524) (xy 309.437146 -294.780456) (xy 309.387971 -294.778475) (xy 309.339752 -294.768631)
			(xy 309.293736 -294.751179) (xy 309.251115 -294.726572) (xy 309.212994 -294.695447) (xy 309.180359 -294.65861)
			(xy 309.154056 -294.617014) (xy 309.134765 -294.571738) (xy 309.122988 -294.523954) (xy 309.119028 -294.4749)
			(xy 308.78018 -294.4749) (xy 308.779685 -294.499507) (xy 308.77179 -294.548084) (xy 308.756206 -294.594765)
			(xy 308.733335 -294.638342) (xy 308.70377 -294.677686) (xy 308.668277 -294.711778) (xy 308.627774 -294.739734)
			(xy 308.583312 -294.760832) (xy 308.536041 -294.774524) (xy 308.487186 -294.780456) (xy 308.438011 -294.778475)
			(xy 308.389792 -294.768631) (xy 308.343776 -294.751179) (xy 308.301155 -294.726572) (xy 308.263034 -294.695447)
			(xy 308.230399 -294.65861) (xy 308.204096 -294.617014) (xy 308.184805 -294.571738) (xy 308.173028 -294.523954)
			(xy 308.169068 -294.4749) (xy 307.83022 -294.4749) (xy 307.829725 -294.499507) (xy 307.82183 -294.548084)
			(xy 307.806246 -294.594765) (xy 307.783375 -294.638342) (xy 307.75381 -294.677686) (xy 307.718317 -294.711778)
			(xy 307.677814 -294.739734) (xy 307.633352 -294.760832) (xy 307.586081 -294.774524) (xy 307.537226 -294.780456)
			(xy 307.488051 -294.778475) (xy 307.439832 -294.768631) (xy 307.393816 -294.751179) (xy 307.351195 -294.726572)
			(xy 307.313074 -294.695447) (xy 307.280439 -294.65861) (xy 307.254136 -294.617014) (xy 307.234845 -294.571738)
			(xy 307.223068 -294.523954) (xy 307.219108 -294.4749) (xy 306.880006 -294.4749) (xy 306.879511 -294.499507)
			(xy 306.871616 -294.548084) (xy 306.856032 -294.594765) (xy 306.833161 -294.638342) (xy 306.803596 -294.677686)
			(xy 306.768103 -294.711778) (xy 306.7276 -294.739734) (xy 306.683138 -294.760832) (xy 306.635867 -294.774524)
			(xy 306.587012 -294.780456) (xy 306.537837 -294.778475) (xy 306.489618 -294.768631) (xy 306.443602 -294.751179)
			(xy 306.400981 -294.726572) (xy 306.36286 -294.695447) (xy 306.330225 -294.65861) (xy 306.303922 -294.617014)
			(xy 306.284631 -294.571738) (xy 306.272854 -294.523954) (xy 306.268894 -294.4749) (xy 305.930046 -294.4749)
			(xy 305.929551 -294.499507) (xy 305.921656 -294.548084) (xy 305.906072 -294.594765) (xy 305.883201 -294.638342)
			(xy 305.853636 -294.677686) (xy 305.818143 -294.711778) (xy 305.77764 -294.739734) (xy 305.733178 -294.760832)
			(xy 305.685907 -294.774524) (xy 305.637052 -294.780456) (xy 305.587877 -294.778475) (xy 305.539658 -294.768631)
			(xy 305.493642 -294.751179) (xy 305.451021 -294.726572) (xy 305.4129 -294.695447) (xy 305.380265 -294.65861)
			(xy 305.353962 -294.617014) (xy 305.334671 -294.571738) (xy 305.322894 -294.523954) (xy 305.318934 -294.4749)
			(xy 304.980086 -294.4749) (xy 304.979591 -294.499507) (xy 304.971696 -294.548084) (xy 304.956112 -294.594765)
			(xy 304.933241 -294.638342) (xy 304.903676 -294.677686) (xy 304.868183 -294.711778) (xy 304.82768 -294.739734)
			(xy 304.783218 -294.760832) (xy 304.735947 -294.774524) (xy 304.687092 -294.780456) (xy 304.637917 -294.778475)
			(xy 304.589698 -294.768631) (xy 304.543682 -294.751179) (xy 304.501061 -294.726572) (xy 304.46294 -294.695447)
			(xy 304.430305 -294.65861) (xy 304.404002 -294.617014) (xy 304.384711 -294.571738) (xy 304.372934 -294.523954)
			(xy 304.368974 -294.4749) (xy 304.030126 -294.4749) (xy 304.029631 -294.499507) (xy 304.021736 -294.548084)
			(xy 304.006152 -294.594765) (xy 303.983281 -294.638342) (xy 303.953716 -294.677686) (xy 303.918223 -294.711778)
			(xy 303.87772 -294.739734) (xy 303.833258 -294.760832) (xy 303.785987 -294.774524) (xy 303.737132 -294.780456)
			(xy 303.687957 -294.778475) (xy 303.639738 -294.768631) (xy 303.593722 -294.751179) (xy 303.551101 -294.726572)
			(xy 303.51298 -294.695447) (xy 303.480345 -294.65861) (xy 303.454042 -294.617014) (xy 303.434751 -294.571738)
			(xy 303.422974 -294.523954) (xy 303.419014 -294.4749) (xy 303.080166 -294.4749) (xy 303.079671 -294.499507)
			(xy 303.071776 -294.548084) (xy 303.056192 -294.594765) (xy 303.033321 -294.638342) (xy 303.003756 -294.677686)
			(xy 302.968263 -294.711778) (xy 302.92776 -294.739734) (xy 302.883298 -294.760832) (xy 302.836027 -294.774524)
			(xy 302.787172 -294.780456) (xy 302.737997 -294.778475) (xy 302.689778 -294.768631) (xy 302.643762 -294.751179)
			(xy 302.601141 -294.726572) (xy 302.56302 -294.695447) (xy 302.530385 -294.65861) (xy 302.504082 -294.617014)
			(xy 302.484791 -294.571738) (xy 302.473014 -294.523954) (xy 302.469054 -294.4749) (xy 302.130206 -294.4749)
			(xy 302.129711 -294.499507) (xy 302.121816 -294.548084) (xy 302.106232 -294.594765) (xy 302.083361 -294.638342)
			(xy 302.053796 -294.677686) (xy 302.018303 -294.711778) (xy 301.9778 -294.739734) (xy 301.933338 -294.760832)
			(xy 301.886067 -294.774524) (xy 301.837212 -294.780456) (xy 301.788037 -294.778475) (xy 301.739818 -294.768631)
			(xy 301.693802 -294.751179) (xy 301.651181 -294.726572) (xy 301.61306 -294.695447) (xy 301.580425 -294.65861)
			(xy 301.554122 -294.617014) (xy 301.534831 -294.571738) (xy 301.523054 -294.523954) (xy 301.519094 -294.4749)
			(xy 298.330112 -294.4749) (xy 298.329617 -294.499507) (xy 298.321722 -294.548084) (xy 298.306138 -294.594765)
			(xy 298.283267 -294.638342) (xy 298.253702 -294.677686) (xy 298.218209 -294.711778) (xy 298.177706 -294.739734)
			(xy 298.133244 -294.760832) (xy 298.085973 -294.774524) (xy 298.037118 -294.780456) (xy 297.987943 -294.778475)
			(xy 297.939724 -294.768631) (xy 297.893708 -294.751179) (xy 297.851087 -294.726572) (xy 297.812966 -294.695447)
			(xy 297.780331 -294.65861) (xy 297.754028 -294.617014) (xy 297.734737 -294.571738) (xy 297.72296 -294.523954)
			(xy 297.719 -294.4749) (xy 297.380152 -294.4749) (xy 297.379657 -294.499507) (xy 297.371762 -294.548084)
			(xy 297.356178 -294.594765) (xy 297.333307 -294.638342) (xy 297.303742 -294.677686) (xy 297.268249 -294.711778)
			(xy 297.227746 -294.739734) (xy 297.183284 -294.760832) (xy 297.136013 -294.774524) (xy 297.087158 -294.780456)
			(xy 297.037983 -294.778475) (xy 296.989764 -294.768631) (xy 296.943748 -294.751179) (xy 296.901127 -294.726572)
			(xy 296.863006 -294.695447) (xy 296.830371 -294.65861) (xy 296.804068 -294.617014) (xy 296.784777 -294.571738)
			(xy 296.773 -294.523954) (xy 296.76904 -294.4749) (xy 296.430192 -294.4749) (xy 296.429697 -294.499507)
			(xy 296.421802 -294.548084) (xy 296.406218 -294.594765) (xy 296.383347 -294.638342) (xy 296.353782 -294.677686)
			(xy 296.318289 -294.711778) (xy 296.277786 -294.739734) (xy 296.233324 -294.760832) (xy 296.186053 -294.774524)
			(xy 296.137198 -294.780456) (xy 296.088023 -294.778475) (xy 296.039804 -294.768631) (xy 295.993788 -294.751179)
			(xy 295.951167 -294.726572) (xy 295.913046 -294.695447) (xy 295.880411 -294.65861) (xy 295.854108 -294.617014)
			(xy 295.834817 -294.571738) (xy 295.82304 -294.523954) (xy 295.81908 -294.4749) (xy 295.480232 -294.4749)
			(xy 295.479737 -294.499507) (xy 295.471842 -294.548084) (xy 295.456258 -294.594765) (xy 295.433387 -294.638342)
			(xy 295.403822 -294.677686) (xy 295.368329 -294.711778) (xy 295.327826 -294.739734) (xy 295.283364 -294.760832)
			(xy 295.236093 -294.774524) (xy 295.187238 -294.780456) (xy 295.138063 -294.778475) (xy 295.089844 -294.768631)
			(xy 295.043828 -294.751179) (xy 295.001207 -294.726572) (xy 294.963086 -294.695447) (xy 294.930451 -294.65861)
			(xy 294.904148 -294.617014) (xy 294.884857 -294.571738) (xy 294.87308 -294.523954) (xy 294.86912 -294.4749)
			(xy 294.530018 -294.4749) (xy 294.529523 -294.499507) (xy 294.521628 -294.548084) (xy 294.506044 -294.594765)
			(xy 294.483173 -294.638342) (xy 294.453608 -294.677686) (xy 294.418115 -294.711778) (xy 294.377612 -294.739734)
			(xy 294.33315 -294.760832) (xy 294.285879 -294.774524) (xy 294.237024 -294.780456) (xy 294.187849 -294.778475)
			(xy 294.13963 -294.768631) (xy 294.093614 -294.751179) (xy 294.050993 -294.726572) (xy 294.012872 -294.695447)
			(xy 293.980237 -294.65861) (xy 293.953934 -294.617014) (xy 293.934643 -294.571738) (xy 293.922866 -294.523954)
			(xy 293.918906 -294.4749) (xy 293.580058 -294.4749) (xy 293.579563 -294.499507) (xy 293.571668 -294.548084)
			(xy 293.556084 -294.594765) (xy 293.533213 -294.638342) (xy 293.503648 -294.677686) (xy 293.468155 -294.711778)
			(xy 293.427652 -294.739734) (xy 293.38319 -294.760832) (xy 293.335919 -294.774524) (xy 293.287064 -294.780456)
			(xy 293.237889 -294.778475) (xy 293.18967 -294.768631) (xy 293.143654 -294.751179) (xy 293.101033 -294.726572)
			(xy 293.062912 -294.695447) (xy 293.030277 -294.65861) (xy 293.003974 -294.617014) (xy 292.984683 -294.571738)
			(xy 292.972906 -294.523954) (xy 292.968946 -294.4749) (xy 292.630098 -294.4749) (xy 292.629603 -294.499507)
			(xy 292.621708 -294.548084) (xy 292.606124 -294.594765) (xy 292.583253 -294.638342) (xy 292.553688 -294.677686)
			(xy 292.518195 -294.711778) (xy 292.477692 -294.739734) (xy 292.43323 -294.760832) (xy 292.385959 -294.774524)
			(xy 292.337104 -294.780456) (xy 292.287929 -294.778475) (xy 292.23971 -294.768631) (xy 292.193694 -294.751179)
			(xy 292.151073 -294.726572) (xy 292.112952 -294.695447) (xy 292.080317 -294.65861) (xy 292.054014 -294.617014)
			(xy 292.034723 -294.571738) (xy 292.022946 -294.523954) (xy 292.018986 -294.4749) (xy 290.730178 -294.4749)
			(xy 290.729683 -294.499507) (xy 290.721788 -294.548084) (xy 290.706204 -294.594765) (xy 290.683333 -294.638342)
			(xy 290.653768 -294.677686) (xy 290.618275 -294.711778) (xy 290.577772 -294.739734) (xy 290.53331 -294.760832)
			(xy 290.486039 -294.774524) (xy 290.437184 -294.780456) (xy 290.388009 -294.778475) (xy 290.33979 -294.768631)
			(xy 290.293774 -294.751179) (xy 290.251153 -294.726572) (xy 290.213032 -294.695447) (xy 290.180397 -294.65861)
			(xy 290.154094 -294.617014) (xy 290.134803 -294.571738) (xy 290.123026 -294.523954) (xy 290.119066 -294.4749)
			(xy 289.780218 -294.4749) (xy 289.779723 -294.499507) (xy 289.771828 -294.548084) (xy 289.756244 -294.594765)
			(xy 289.733373 -294.638342) (xy 289.703808 -294.677686) (xy 289.668315 -294.711778) (xy 289.627812 -294.739734)
			(xy 289.58335 -294.760832) (xy 289.536079 -294.774524) (xy 289.487224 -294.780456) (xy 289.438049 -294.778475)
			(xy 289.38983 -294.768631) (xy 289.343814 -294.751179) (xy 289.301193 -294.726572) (xy 289.263072 -294.695447)
			(xy 289.230437 -294.65861) (xy 289.204134 -294.617014) (xy 289.184843 -294.571738) (xy 289.173066 -294.523954)
			(xy 289.169106 -294.4749) (xy 288.830004 -294.4749) (xy 288.829509 -294.499507) (xy 288.821614 -294.548084)
			(xy 288.80603 -294.594765) (xy 288.783159 -294.638342) (xy 288.753594 -294.677686) (xy 288.718101 -294.711778)
			(xy 288.677598 -294.739734) (xy 288.633136 -294.760832) (xy 288.585865 -294.774524) (xy 288.53701 -294.780456)
			(xy 288.487835 -294.778475) (xy 288.439616 -294.768631) (xy 288.3936 -294.751179) (xy 288.350979 -294.726572)
			(xy 288.312858 -294.695447) (xy 288.280223 -294.65861) (xy 288.25392 -294.617014) (xy 288.234629 -294.571738)
			(xy 288.222852 -294.523954) (xy 288.218892 -294.4749) (xy 287.880044 -294.4749) (xy 287.879549 -294.499507)
			(xy 287.871654 -294.548084) (xy 287.85607 -294.594765) (xy 287.833199 -294.638342) (xy 287.803634 -294.677686)
			(xy 287.768141 -294.711778) (xy 287.727638 -294.739734) (xy 287.683176 -294.760832) (xy 287.635905 -294.774524)
			(xy 287.58705 -294.780456) (xy 287.537875 -294.778475) (xy 287.489656 -294.768631) (xy 287.44364 -294.751179)
			(xy 287.401019 -294.726572) (xy 287.362898 -294.695447) (xy 287.330263 -294.65861) (xy 287.30396 -294.617014)
			(xy 287.284669 -294.571738) (xy 287.272892 -294.523954) (xy 287.268932 -294.4749) (xy 286.930084 -294.4749)
			(xy 286.929589 -294.499507) (xy 286.921694 -294.548084) (xy 286.90611 -294.594765) (xy 286.883239 -294.638342)
			(xy 286.853674 -294.677686) (xy 286.818181 -294.711778) (xy 286.777678 -294.739734) (xy 286.733216 -294.760832)
			(xy 286.685945 -294.774524) (xy 286.63709 -294.780456) (xy 286.587915 -294.778475) (xy 286.539696 -294.768631)
			(xy 286.49368 -294.751179) (xy 286.451059 -294.726572) (xy 286.412938 -294.695447) (xy 286.380303 -294.65861)
			(xy 286.354 -294.617014) (xy 286.334709 -294.571738) (xy 286.322932 -294.523954) (xy 286.318972 -294.4749)
			(xy 285.980124 -294.4749) (xy 285.979629 -294.499507) (xy 285.971734 -294.548084) (xy 285.95615 -294.594765)
			(xy 285.933279 -294.638342) (xy 285.903714 -294.677686) (xy 285.868221 -294.711778) (xy 285.827718 -294.739734)
			(xy 285.783256 -294.760832) (xy 285.735985 -294.774524) (xy 285.68713 -294.780456) (xy 285.637955 -294.778475)
			(xy 285.589736 -294.768631) (xy 285.54372 -294.751179) (xy 285.501099 -294.726572) (xy 285.462978 -294.695447)
			(xy 285.430343 -294.65861) (xy 285.40404 -294.617014) (xy 285.384749 -294.571738) (xy 285.372972 -294.523954)
			(xy 285.369012 -294.4749) (xy 285.030164 -294.4749) (xy 285.029669 -294.499507) (xy 285.021774 -294.548084)
			(xy 285.00619 -294.594765) (xy 284.983319 -294.638342) (xy 284.953754 -294.677686) (xy 284.918261 -294.711778)
			(xy 284.877758 -294.739734) (xy 284.833296 -294.760832) (xy 284.786025 -294.774524) (xy 284.73717 -294.780456)
			(xy 284.687995 -294.778475) (xy 284.639776 -294.768631) (xy 284.59376 -294.751179) (xy 284.551139 -294.726572)
			(xy 284.513018 -294.695447) (xy 284.480383 -294.65861) (xy 284.45408 -294.617014) (xy 284.434789 -294.571738)
			(xy 284.423012 -294.523954) (xy 284.419052 -294.4749) (xy 284.080204 -294.4749) (xy 284.079709 -294.499507)
			(xy 284.071814 -294.548084) (xy 284.05623 -294.594765) (xy 284.033359 -294.638342) (xy 284.003794 -294.677686)
			(xy 283.968301 -294.711778) (xy 283.927798 -294.739734) (xy 283.883336 -294.760832) (xy 283.836065 -294.774524)
			(xy 283.78721 -294.780456) (xy 283.738035 -294.778475) (xy 283.689816 -294.768631) (xy 283.6438 -294.751179)
			(xy 283.601179 -294.726572) (xy 283.563058 -294.695447) (xy 283.530423 -294.65861) (xy 283.50412 -294.617014)
			(xy 283.484829 -294.571738) (xy 283.473052 -294.523954) (xy 283.469092 -294.4749) (xy 283.130244 -294.4749)
			(xy 283.129749 -294.499507) (xy 283.121854 -294.548084) (xy 283.10627 -294.594765) (xy 283.083399 -294.638342)
			(xy 283.053834 -294.677686) (xy 283.018341 -294.711778) (xy 282.977838 -294.739734) (xy 282.933376 -294.760832)
			(xy 282.886105 -294.774524) (xy 282.83725 -294.780456) (xy 282.788075 -294.778475) (xy 282.739856 -294.768631)
			(xy 282.69384 -294.751179) (xy 282.651219 -294.726572) (xy 282.613098 -294.695447) (xy 282.580463 -294.65861)
			(xy 282.55416 -294.617014) (xy 282.534869 -294.571738) (xy 282.523092 -294.523954) (xy 282.519132 -294.4749)
			(xy 282.18003 -294.4749) (xy 282.179535 -294.499507) (xy 282.17164 -294.548084) (xy 282.156056 -294.594765)
			(xy 282.133185 -294.638342) (xy 282.10362 -294.677686) (xy 282.068127 -294.711778) (xy 282.027624 -294.739734)
			(xy 281.983162 -294.760832) (xy 281.935891 -294.774524) (xy 281.887036 -294.780456) (xy 281.837861 -294.778475)
			(xy 281.789642 -294.768631) (xy 281.743626 -294.751179) (xy 281.701005 -294.726572) (xy 281.662884 -294.695447)
			(xy 281.630249 -294.65861) (xy 281.603946 -294.617014) (xy 281.584655 -294.571738) (xy 281.572878 -294.523954)
			(xy 281.568918 -294.4749) (xy 281.23007 -294.4749) (xy 281.229575 -294.499507) (xy 281.22168 -294.548084)
			(xy 281.206096 -294.594765) (xy 281.183225 -294.638342) (xy 281.15366 -294.677686) (xy 281.118167 -294.711778)
			(xy 281.077664 -294.739734) (xy 281.033202 -294.760832) (xy 280.985931 -294.774524) (xy 280.937076 -294.780456)
			(xy 280.887901 -294.778475) (xy 280.839682 -294.768631) (xy 280.793666 -294.751179) (xy 280.751045 -294.726572)
			(xy 280.712924 -294.695447) (xy 280.680289 -294.65861) (xy 280.653986 -294.617014) (xy 280.634695 -294.571738)
			(xy 280.622918 -294.523954) (xy 280.618958 -294.4749) (xy 280.28011 -294.4749) (xy 280.279615 -294.499507)
			(xy 280.27172 -294.548084) (xy 280.256136 -294.594765) (xy 280.233265 -294.638342) (xy 280.2037 -294.677686)
			(xy 280.168207 -294.711778) (xy 280.127704 -294.739734) (xy 280.083242 -294.760832) (xy 280.035971 -294.774524)
			(xy 279.987116 -294.780456) (xy 279.937941 -294.778475) (xy 279.889722 -294.768631) (xy 279.843706 -294.751179)
			(xy 279.801085 -294.726572) (xy 279.762964 -294.695447) (xy 279.730329 -294.65861) (xy 279.704026 -294.617014)
			(xy 279.684735 -294.571738) (xy 279.672958 -294.523954) (xy 279.668998 -294.4749) (xy 279.41397 -294.4749)
			(xy 279.41397 -295.355518) (xy 324.815706 -295.355518) (xy 324.819777 -295.299896) (xy 324.831903 -295.245459)
			(xy 324.851826 -295.193368) (xy 324.879122 -295.144733) (xy 324.913208 -295.10059) (xy 324.953357 -295.061881)
			(xy 324.998715 -295.02943) (xy 325.048315 -295.003929) (xy 325.101099 -294.985922) (xy 325.155942 -294.975792)
			(xy 325.211676 -294.973755) (xy 325.267113 -294.979855) (xy 325.32107 -294.993961) (xy 325.372399 -295.015773)
			(xy 325.420005 -295.044827) (xy 325.462873 -295.080502) (xy 325.50009 -295.122039) (xy 325.530863 -295.168552)
			(xy 325.554535 -295.219049) (xy 325.570603 -295.272456) (xy 325.578723 -295.327632) (xy 325.579232 -295.355518)
			(xy 325.578723 -295.383404) (xy 325.570603 -295.43858) (xy 325.554535 -295.491987) (xy 325.530863 -295.542484)
			(xy 325.50009 -295.588997) (xy 325.462873 -295.630534) (xy 325.420005 -295.666209) (xy 325.372399 -295.695263)
			(xy 325.32107 -295.717075) (xy 325.267113 -295.731181) (xy 325.211676 -295.737281) (xy 325.155942 -295.735244)
			(xy 325.101099 -295.725114) (xy 325.048315 -295.707107) (xy 324.998715 -295.681606) (xy 324.953357 -295.649155)
			(xy 324.913208 -295.610446) (xy 324.879122 -295.566303) (xy 324.851826 -295.517668) (xy 324.831903 -295.465577)
			(xy 324.819777 -295.41114) (xy 324.815706 -295.355518) (xy 279.41397 -295.355518) (xy 279.41397 -296.37482)
			(xy 279.668998 -296.37482) (xy 279.672958 -296.325766) (xy 279.684735 -296.277982) (xy 279.704026 -296.232706)
			(xy 279.730329 -296.19111) (xy 279.762964 -296.154273) (xy 279.801085 -296.123148) (xy 279.843706 -296.098541)
			(xy 279.889722 -296.081089) (xy 279.937941 -296.071245) (xy 279.987116 -296.069264) (xy 280.035971 -296.075196)
			(xy 280.083242 -296.088888) (xy 280.127704 -296.109986) (xy 280.168207 -296.137942) (xy 280.2037 -296.172034)
			(xy 280.233265 -296.211378) (xy 280.256136 -296.254955) (xy 280.27172 -296.301636) (xy 280.279615 -296.350213)
			(xy 280.28011 -296.37482) (xy 280.618958 -296.37482) (xy 280.622918 -296.325766) (xy 280.634695 -296.277982)
			(xy 280.653986 -296.232706) (xy 280.680289 -296.19111) (xy 280.712924 -296.154273) (xy 280.751045 -296.123148)
			(xy 280.793666 -296.098541) (xy 280.839682 -296.081089) (xy 280.887901 -296.071245) (xy 280.937076 -296.069264)
			(xy 280.985931 -296.075196) (xy 281.033202 -296.088888) (xy 281.077664 -296.109986) (xy 281.118167 -296.137942)
			(xy 281.15366 -296.172034) (xy 281.183225 -296.211378) (xy 281.206096 -296.254955) (xy 281.22168 -296.301636)
			(xy 281.229575 -296.350213) (xy 281.23007 -296.37482) (xy 281.568918 -296.37482) (xy 281.572878 -296.325766)
			(xy 281.584655 -296.277982) (xy 281.603946 -296.232706) (xy 281.630249 -296.19111) (xy 281.662884 -296.154273)
			(xy 281.701005 -296.123148) (xy 281.743626 -296.098541) (xy 281.789642 -296.081089) (xy 281.837861 -296.071245)
			(xy 281.887036 -296.069264) (xy 281.935891 -296.075196) (xy 281.983162 -296.088888) (xy 282.027624 -296.109986)
			(xy 282.068127 -296.137942) (xy 282.10362 -296.172034) (xy 282.133185 -296.211378) (xy 282.156056 -296.254955)
			(xy 282.17164 -296.301636) (xy 282.179535 -296.350213) (xy 282.18003 -296.37482) (xy 282.519132 -296.37482)
			(xy 282.523092 -296.325766) (xy 282.534869 -296.277982) (xy 282.55416 -296.232706) (xy 282.580463 -296.19111)
			(xy 282.613098 -296.154273) (xy 282.651219 -296.123148) (xy 282.69384 -296.098541) (xy 282.739856 -296.081089)
			(xy 282.788075 -296.071245) (xy 282.83725 -296.069264) (xy 282.886105 -296.075196) (xy 282.933376 -296.088888)
			(xy 282.977838 -296.109986) (xy 283.018341 -296.137942) (xy 283.053834 -296.172034) (xy 283.083399 -296.211378)
			(xy 283.10627 -296.254955) (xy 283.121854 -296.301636) (xy 283.129749 -296.350213) (xy 283.130244 -296.37482)
			(xy 283.469092 -296.37482) (xy 283.473052 -296.325766) (xy 283.484829 -296.277982) (xy 283.50412 -296.232706)
			(xy 283.530423 -296.19111) (xy 283.563058 -296.154273) (xy 283.601179 -296.123148) (xy 283.6438 -296.098541)
			(xy 283.689816 -296.081089) (xy 283.738035 -296.071245) (xy 283.78721 -296.069264) (xy 283.836065 -296.075196)
			(xy 283.883336 -296.088888) (xy 283.927798 -296.109986) (xy 283.968301 -296.137942) (xy 284.003794 -296.172034)
			(xy 284.033359 -296.211378) (xy 284.05623 -296.254955) (xy 284.071814 -296.301636) (xy 284.079709 -296.350213)
			(xy 284.080204 -296.37482) (xy 284.419052 -296.37482) (xy 284.423012 -296.325766) (xy 284.434789 -296.277982)
			(xy 284.45408 -296.232706) (xy 284.480383 -296.19111) (xy 284.513018 -296.154273) (xy 284.551139 -296.123148)
			(xy 284.59376 -296.098541) (xy 284.639776 -296.081089) (xy 284.687995 -296.071245) (xy 284.73717 -296.069264)
			(xy 284.786025 -296.075196) (xy 284.833296 -296.088888) (xy 284.877758 -296.109986) (xy 284.918261 -296.137942)
			(xy 284.953754 -296.172034) (xy 284.983319 -296.211378) (xy 285.00619 -296.254955) (xy 285.021774 -296.301636)
			(xy 285.029669 -296.350213) (xy 285.030164 -296.37482) (xy 285.369012 -296.37482) (xy 285.372972 -296.325766)
			(xy 285.384749 -296.277982) (xy 285.40404 -296.232706) (xy 285.430343 -296.19111) (xy 285.462978 -296.154273)
			(xy 285.501099 -296.123148) (xy 285.54372 -296.098541) (xy 285.589736 -296.081089) (xy 285.637955 -296.071245)
			(xy 285.68713 -296.069264) (xy 285.735985 -296.075196) (xy 285.783256 -296.088888) (xy 285.827718 -296.109986)
			(xy 285.868221 -296.137942) (xy 285.903714 -296.172034) (xy 285.933279 -296.211378) (xy 285.95615 -296.254955)
			(xy 285.971734 -296.301636) (xy 285.979629 -296.350213) (xy 285.980124 -296.37482) (xy 286.318972 -296.37482)
			(xy 286.322932 -296.325766) (xy 286.334709 -296.277982) (xy 286.354 -296.232706) (xy 286.380303 -296.19111)
			(xy 286.412938 -296.154273) (xy 286.451059 -296.123148) (xy 286.49368 -296.098541) (xy 286.539696 -296.081089)
			(xy 286.587915 -296.071245) (xy 286.63709 -296.069264) (xy 286.685945 -296.075196) (xy 286.733216 -296.088888)
			(xy 286.777678 -296.109986) (xy 286.818181 -296.137942) (xy 286.853674 -296.172034) (xy 286.883239 -296.211378)
			(xy 286.90611 -296.254955) (xy 286.921694 -296.301636) (xy 286.929589 -296.350213) (xy 286.930084 -296.37482)
			(xy 287.268932 -296.37482) (xy 287.272892 -296.325766) (xy 287.284669 -296.277982) (xy 287.30396 -296.232706)
			(xy 287.330263 -296.19111) (xy 287.362898 -296.154273) (xy 287.401019 -296.123148) (xy 287.44364 -296.098541)
			(xy 287.489656 -296.081089) (xy 287.537875 -296.071245) (xy 287.58705 -296.069264) (xy 287.635905 -296.075196)
			(xy 287.683176 -296.088888) (xy 287.727638 -296.109986) (xy 287.768141 -296.137942) (xy 287.803634 -296.172034)
			(xy 287.833199 -296.211378) (xy 287.85607 -296.254955) (xy 287.871654 -296.301636) (xy 287.879549 -296.350213)
			(xy 287.880044 -296.37482) (xy 288.219146 -296.37482) (xy 288.223106 -296.325766) (xy 288.234883 -296.277982)
			(xy 288.254174 -296.232706) (xy 288.280477 -296.19111) (xy 288.313112 -296.154273) (xy 288.351233 -296.123148)
			(xy 288.393854 -296.098541) (xy 288.43987 -296.081089) (xy 288.488089 -296.071245) (xy 288.537264 -296.069264)
			(xy 288.586119 -296.075196) (xy 288.63339 -296.088888) (xy 288.677852 -296.109986) (xy 288.718355 -296.137942)
			(xy 288.753848 -296.172034) (xy 288.783413 -296.211378) (xy 288.806284 -296.254955) (xy 288.821868 -296.301636)
			(xy 288.829763 -296.350213) (xy 288.830258 -296.37482) (xy 289.169106 -296.37482) (xy 289.173066 -296.325766)
			(xy 289.184843 -296.277982) (xy 289.204134 -296.232706) (xy 289.230437 -296.19111) (xy 289.263072 -296.154273)
			(xy 289.301193 -296.123148) (xy 289.343814 -296.098541) (xy 289.38983 -296.081089) (xy 289.438049 -296.071245)
			(xy 289.487224 -296.069264) (xy 289.536079 -296.075196) (xy 289.58335 -296.088888) (xy 289.627812 -296.109986)
			(xy 289.668315 -296.137942) (xy 289.703808 -296.172034) (xy 289.733373 -296.211378) (xy 289.756244 -296.254955)
			(xy 289.771828 -296.301636) (xy 289.779723 -296.350213) (xy 289.780218 -296.37482) (xy 290.119066 -296.37482)
			(xy 290.123026 -296.325766) (xy 290.134803 -296.277982) (xy 290.154094 -296.232706) (xy 290.180397 -296.19111)
			(xy 290.213032 -296.154273) (xy 290.251153 -296.123148) (xy 290.293774 -296.098541) (xy 290.33979 -296.081089)
			(xy 290.388009 -296.071245) (xy 290.437184 -296.069264) (xy 290.486039 -296.075196) (xy 290.53331 -296.088888)
			(xy 290.577772 -296.109986) (xy 290.618275 -296.137942) (xy 290.653768 -296.172034) (xy 290.683333 -296.211378)
			(xy 290.706204 -296.254955) (xy 290.721788 -296.301636) (xy 290.729683 -296.350213) (xy 290.730178 -296.37482)
			(xy 292.018986 -296.37482) (xy 292.022946 -296.325766) (xy 292.034723 -296.277982) (xy 292.054014 -296.232706)
			(xy 292.080317 -296.19111) (xy 292.112952 -296.154273) (xy 292.151073 -296.123148) (xy 292.193694 -296.098541)
			(xy 292.23971 -296.081089) (xy 292.287929 -296.071245) (xy 292.337104 -296.069264) (xy 292.385959 -296.075196)
			(xy 292.43323 -296.088888) (xy 292.477692 -296.109986) (xy 292.518195 -296.137942) (xy 292.553688 -296.172034)
			(xy 292.583253 -296.211378) (xy 292.606124 -296.254955) (xy 292.621708 -296.301636) (xy 292.629603 -296.350213)
			(xy 292.630098 -296.37482) (xy 292.968946 -296.37482) (xy 292.972906 -296.325766) (xy 292.984683 -296.277982)
			(xy 293.003974 -296.232706) (xy 293.030277 -296.19111) (xy 293.062912 -296.154273) (xy 293.101033 -296.123148)
			(xy 293.143654 -296.098541) (xy 293.18967 -296.081089) (xy 293.237889 -296.071245) (xy 293.287064 -296.069264)
			(xy 293.335919 -296.075196) (xy 293.38319 -296.088888) (xy 293.427652 -296.109986) (xy 293.468155 -296.137942)
			(xy 293.503648 -296.172034) (xy 293.533213 -296.211378) (xy 293.556084 -296.254955) (xy 293.571668 -296.301636)
			(xy 293.579563 -296.350213) (xy 293.580058 -296.37482) (xy 293.918906 -296.37482) (xy 293.922866 -296.325766)
			(xy 293.934643 -296.277982) (xy 293.953934 -296.232706) (xy 293.980237 -296.19111) (xy 294.012872 -296.154273)
			(xy 294.050993 -296.123148) (xy 294.093614 -296.098541) (xy 294.13963 -296.081089) (xy 294.187849 -296.071245)
			(xy 294.237024 -296.069264) (xy 294.285879 -296.075196) (xy 294.33315 -296.088888) (xy 294.377612 -296.109986)
			(xy 294.418115 -296.137942) (xy 294.453608 -296.172034) (xy 294.483173 -296.211378) (xy 294.506044 -296.254955)
			(xy 294.521628 -296.301636) (xy 294.529523 -296.350213) (xy 294.530018 -296.37482) (xy 294.86912 -296.37482)
			(xy 294.87308 -296.325766) (xy 294.884857 -296.277982) (xy 294.904148 -296.232706) (xy 294.930451 -296.19111)
			(xy 294.963086 -296.154273) (xy 295.001207 -296.123148) (xy 295.043828 -296.098541) (xy 295.089844 -296.081089)
			(xy 295.138063 -296.071245) (xy 295.187238 -296.069264) (xy 295.236093 -296.075196) (xy 295.283364 -296.088888)
			(xy 295.327826 -296.109986) (xy 295.368329 -296.137942) (xy 295.403822 -296.172034) (xy 295.433387 -296.211378)
			(xy 295.456258 -296.254955) (xy 295.471842 -296.301636) (xy 295.479737 -296.350213) (xy 295.480232 -296.37482)
			(xy 295.81908 -296.37482) (xy 295.82304 -296.325766) (xy 295.834817 -296.277982) (xy 295.854108 -296.232706)
			(xy 295.880411 -296.19111) (xy 295.913046 -296.154273) (xy 295.951167 -296.123148) (xy 295.993788 -296.098541)
			(xy 296.039804 -296.081089) (xy 296.088023 -296.071245) (xy 296.137198 -296.069264) (xy 296.186053 -296.075196)
			(xy 296.233324 -296.088888) (xy 296.277786 -296.109986) (xy 296.318289 -296.137942) (xy 296.353782 -296.172034)
			(xy 296.383347 -296.211378) (xy 296.406218 -296.254955) (xy 296.421802 -296.301636) (xy 296.429697 -296.350213)
			(xy 296.430192 -296.37482) (xy 296.76904 -296.37482) (xy 296.773 -296.325766) (xy 296.784777 -296.277982)
			(xy 296.804068 -296.232706) (xy 296.830371 -296.19111) (xy 296.863006 -296.154273) (xy 296.901127 -296.123148)
			(xy 296.943748 -296.098541) (xy 296.989764 -296.081089) (xy 297.037983 -296.071245) (xy 297.087158 -296.069264)
			(xy 297.136013 -296.075196) (xy 297.183284 -296.088888) (xy 297.227746 -296.109986) (xy 297.268249 -296.137942)
			(xy 297.303742 -296.172034) (xy 297.333307 -296.211378) (xy 297.356178 -296.254955) (xy 297.371762 -296.301636)
			(xy 297.379657 -296.350213) (xy 297.380152 -296.37482) (xy 297.719 -296.37482) (xy 297.72296 -296.325766)
			(xy 297.734737 -296.277982) (xy 297.754028 -296.232706) (xy 297.780331 -296.19111) (xy 297.812966 -296.154273)
			(xy 297.851087 -296.123148) (xy 297.893708 -296.098541) (xy 297.939724 -296.081089) (xy 297.987943 -296.071245)
			(xy 298.037118 -296.069264) (xy 298.085973 -296.075196) (xy 298.133244 -296.088888) (xy 298.177706 -296.109986)
			(xy 298.218209 -296.137942) (xy 298.253702 -296.172034) (xy 298.283267 -296.211378) (xy 298.306138 -296.254955)
			(xy 298.321722 -296.301636) (xy 298.329617 -296.350213) (xy 298.330112 -296.37482) (xy 298.66896 -296.37482)
			(xy 298.67292 -296.325766) (xy 298.684697 -296.277982) (xy 298.703988 -296.232706) (xy 298.730291 -296.19111)
			(xy 298.762926 -296.154273) (xy 298.801047 -296.123148) (xy 298.843668 -296.098541) (xy 298.889684 -296.081089)
			(xy 298.937903 -296.071245) (xy 298.987078 -296.069264) (xy 299.035933 -296.075196) (xy 299.083204 -296.088888)
			(xy 299.127666 -296.109986) (xy 299.168169 -296.137942) (xy 299.203662 -296.172034) (xy 299.233227 -296.211378)
			(xy 299.256098 -296.254955) (xy 299.271682 -296.301636) (xy 299.279577 -296.350213) (xy 299.280072 -296.37482)
			(xy 301.519094 -296.37482) (xy 301.523054 -296.325766) (xy 301.534831 -296.277982) (xy 301.554122 -296.232706)
			(xy 301.580425 -296.19111) (xy 301.61306 -296.154273) (xy 301.651181 -296.123148) (xy 301.693802 -296.098541)
			(xy 301.739818 -296.081089) (xy 301.788037 -296.071245) (xy 301.837212 -296.069264) (xy 301.886067 -296.075196)
			(xy 301.933338 -296.088888) (xy 301.9778 -296.109986) (xy 302.018303 -296.137942) (xy 302.053796 -296.172034)
			(xy 302.083361 -296.211378) (xy 302.106232 -296.254955) (xy 302.121816 -296.301636) (xy 302.129711 -296.350213)
			(xy 302.130206 -296.37482) (xy 302.469054 -296.37482) (xy 302.473014 -296.325766) (xy 302.484791 -296.277982)
			(xy 302.504082 -296.232706) (xy 302.530385 -296.19111) (xy 302.56302 -296.154273) (xy 302.601141 -296.123148)
			(xy 302.643762 -296.098541) (xy 302.689778 -296.081089) (xy 302.737997 -296.071245) (xy 302.787172 -296.069264)
			(xy 302.836027 -296.075196) (xy 302.883298 -296.088888) (xy 302.92776 -296.109986) (xy 302.968263 -296.137942)
			(xy 303.003756 -296.172034) (xy 303.033321 -296.211378) (xy 303.056192 -296.254955) (xy 303.071776 -296.301636)
			(xy 303.079671 -296.350213) (xy 303.080166 -296.37482) (xy 303.419014 -296.37482) (xy 303.422974 -296.325766)
			(xy 303.434751 -296.277982) (xy 303.454042 -296.232706) (xy 303.480345 -296.19111) (xy 303.51298 -296.154273)
			(xy 303.551101 -296.123148) (xy 303.593722 -296.098541) (xy 303.639738 -296.081089) (xy 303.687957 -296.071245)
			(xy 303.737132 -296.069264) (xy 303.785987 -296.075196) (xy 303.833258 -296.088888) (xy 303.87772 -296.109986)
			(xy 303.918223 -296.137942) (xy 303.953716 -296.172034) (xy 303.983281 -296.211378) (xy 304.006152 -296.254955)
			(xy 304.021736 -296.301636) (xy 304.029631 -296.350213) (xy 304.030126 -296.37482) (xy 304.368974 -296.37482)
			(xy 304.372934 -296.325766) (xy 304.384711 -296.277982) (xy 304.404002 -296.232706) (xy 304.430305 -296.19111)
			(xy 304.46294 -296.154273) (xy 304.501061 -296.123148) (xy 304.543682 -296.098541) (xy 304.589698 -296.081089)
			(xy 304.637917 -296.071245) (xy 304.687092 -296.069264) (xy 304.735947 -296.075196) (xy 304.783218 -296.088888)
			(xy 304.82768 -296.109986) (xy 304.868183 -296.137942) (xy 304.903676 -296.172034) (xy 304.933241 -296.211378)
			(xy 304.956112 -296.254955) (xy 304.971696 -296.301636) (xy 304.979591 -296.350213) (xy 304.980086 -296.37482)
			(xy 305.318934 -296.37482) (xy 305.322894 -296.325766) (xy 305.334671 -296.277982) (xy 305.353962 -296.232706)
			(xy 305.380265 -296.19111) (xy 305.4129 -296.154273) (xy 305.451021 -296.123148) (xy 305.493642 -296.098541)
			(xy 305.539658 -296.081089) (xy 305.587877 -296.071245) (xy 305.637052 -296.069264) (xy 305.685907 -296.075196)
			(xy 305.733178 -296.088888) (xy 305.77764 -296.109986) (xy 305.818143 -296.137942) (xy 305.853636 -296.172034)
			(xy 305.883201 -296.211378) (xy 305.906072 -296.254955) (xy 305.921656 -296.301636) (xy 305.929551 -296.350213)
			(xy 305.930046 -296.37482) (xy 306.268894 -296.37482) (xy 306.272854 -296.325766) (xy 306.284631 -296.277982)
			(xy 306.303922 -296.232706) (xy 306.330225 -296.19111) (xy 306.36286 -296.154273) (xy 306.400981 -296.123148)
			(xy 306.443602 -296.098541) (xy 306.489618 -296.081089) (xy 306.537837 -296.071245) (xy 306.587012 -296.069264)
			(xy 306.635867 -296.075196) (xy 306.683138 -296.088888) (xy 306.7276 -296.109986) (xy 306.768103 -296.137942)
			(xy 306.803596 -296.172034) (xy 306.833161 -296.211378) (xy 306.856032 -296.254955) (xy 306.871616 -296.301636)
			(xy 306.879511 -296.350213) (xy 306.880006 -296.37482) (xy 307.219108 -296.37482) (xy 307.223068 -296.325766)
			(xy 307.234845 -296.277982) (xy 307.254136 -296.232706) (xy 307.280439 -296.19111) (xy 307.313074 -296.154273)
			(xy 307.351195 -296.123148) (xy 307.393816 -296.098541) (xy 307.439832 -296.081089) (xy 307.488051 -296.071245)
			(xy 307.537226 -296.069264) (xy 307.586081 -296.075196) (xy 307.633352 -296.088888) (xy 307.677814 -296.109986)
			(xy 307.718317 -296.137942) (xy 307.75381 -296.172034) (xy 307.783375 -296.211378) (xy 307.806246 -296.254955)
			(xy 307.82183 -296.301636) (xy 307.829725 -296.350213) (xy 307.83022 -296.37482) (xy 308.169068 -296.37482)
			(xy 308.173028 -296.325766) (xy 308.184805 -296.277982) (xy 308.204096 -296.232706) (xy 308.230399 -296.19111)
			(xy 308.263034 -296.154273) (xy 308.301155 -296.123148) (xy 308.343776 -296.098541) (xy 308.389792 -296.081089)
			(xy 308.438011 -296.071245) (xy 308.487186 -296.069264) (xy 308.536041 -296.075196) (xy 308.583312 -296.088888)
			(xy 308.627774 -296.109986) (xy 308.668277 -296.137942) (xy 308.70377 -296.172034) (xy 308.733335 -296.211378)
			(xy 308.756206 -296.254955) (xy 308.77179 -296.301636) (xy 308.779685 -296.350213) (xy 308.78018 -296.37482)
			(xy 309.119028 -296.37482) (xy 309.122988 -296.325766) (xy 309.134765 -296.277982) (xy 309.154056 -296.232706)
			(xy 309.180359 -296.19111) (xy 309.212994 -296.154273) (xy 309.251115 -296.123148) (xy 309.293736 -296.098541)
			(xy 309.339752 -296.081089) (xy 309.387971 -296.071245) (xy 309.437146 -296.069264) (xy 309.486001 -296.075196)
			(xy 309.533272 -296.088888) (xy 309.577734 -296.109986) (xy 309.618237 -296.137942) (xy 309.65373 -296.172034)
			(xy 309.683295 -296.211378) (xy 309.706166 -296.254955) (xy 309.72175 -296.301636) (xy 309.729645 -296.350213)
			(xy 309.73014 -296.37482) (xy 310.068988 -296.37482) (xy 310.072948 -296.325766) (xy 310.084725 -296.277982)
			(xy 310.104016 -296.232706) (xy 310.130319 -296.19111) (xy 310.162954 -296.154273) (xy 310.201075 -296.123148)
			(xy 310.243696 -296.098541) (xy 310.289712 -296.081089) (xy 310.337931 -296.071245) (xy 310.387106 -296.069264)
			(xy 310.435961 -296.075196) (xy 310.483232 -296.088888) (xy 310.527694 -296.109986) (xy 310.568197 -296.137942)
			(xy 310.60369 -296.172034) (xy 310.633255 -296.211378) (xy 310.656126 -296.254955) (xy 310.67171 -296.301636)
			(xy 310.679605 -296.350213) (xy 310.6801 -296.37482) (xy 311.018948 -296.37482) (xy 311.022908 -296.325766)
			(xy 311.034685 -296.277982) (xy 311.053976 -296.232706) (xy 311.080279 -296.19111) (xy 311.112914 -296.154273)
			(xy 311.151035 -296.123148) (xy 311.193656 -296.098541) (xy 311.239672 -296.081089) (xy 311.287891 -296.071245)
			(xy 311.337066 -296.069264) (xy 311.385921 -296.075196) (xy 311.433192 -296.088888) (xy 311.477654 -296.109986)
			(xy 311.518157 -296.137942) (xy 311.55365 -296.172034) (xy 311.583215 -296.211378) (xy 311.606086 -296.254955)
			(xy 311.62167 -296.301636) (xy 311.629565 -296.350213) (xy 311.63006 -296.37482) (xy 311.968908 -296.37482)
			(xy 311.972868 -296.325766) (xy 311.984645 -296.277982) (xy 312.003936 -296.232706) (xy 312.030239 -296.19111)
			(xy 312.062874 -296.154273) (xy 312.100995 -296.123148) (xy 312.143616 -296.098541) (xy 312.189632 -296.081089)
			(xy 312.237851 -296.071245) (xy 312.287026 -296.069264) (xy 312.335881 -296.075196) (xy 312.383152 -296.088888)
			(xy 312.427614 -296.109986) (xy 312.468117 -296.137942) (xy 312.50361 -296.172034) (xy 312.533175 -296.211378)
			(xy 312.556046 -296.254955) (xy 312.57163 -296.301636) (xy 312.579525 -296.350213) (xy 312.58002 -296.37482)
			(xy 312.919122 -296.37482) (xy 312.923082 -296.325766) (xy 312.934859 -296.277982) (xy 312.95415 -296.232706)
			(xy 312.980453 -296.19111) (xy 313.013088 -296.154273) (xy 313.051209 -296.123148) (xy 313.09383 -296.098541)
			(xy 313.139846 -296.081089) (xy 313.188065 -296.071245) (xy 313.23724 -296.069264) (xy 313.286095 -296.075196)
			(xy 313.333366 -296.088888) (xy 313.377828 -296.109986) (xy 313.418331 -296.137942) (xy 313.453824 -296.172034)
			(xy 313.483389 -296.211378) (xy 313.50626 -296.254955) (xy 313.521844 -296.301636) (xy 313.529739 -296.350213)
			(xy 313.530234 -296.37482) (xy 313.869082 -296.37482) (xy 313.873042 -296.325766) (xy 313.884819 -296.277982)
			(xy 313.90411 -296.232706) (xy 313.930413 -296.19111) (xy 313.963048 -296.154273) (xy 314.001169 -296.123148)
			(xy 314.04379 -296.098541) (xy 314.089806 -296.081089) (xy 314.138025 -296.071245) (xy 314.1872 -296.069264)
			(xy 314.236055 -296.075196) (xy 314.283326 -296.088888) (xy 314.327788 -296.109986) (xy 314.368291 -296.137942)
			(xy 314.403784 -296.172034) (xy 314.433349 -296.211378) (xy 314.45622 -296.254955) (xy 314.471804 -296.301636)
			(xy 314.479699 -296.350213) (xy 314.480194 -296.37482) (xy 314.819042 -296.37482) (xy 314.823002 -296.325766)
			(xy 314.834779 -296.277982) (xy 314.85407 -296.232706) (xy 314.880373 -296.19111) (xy 314.913008 -296.154273)
			(xy 314.951129 -296.123148) (xy 314.99375 -296.098541) (xy 315.039766 -296.081089) (xy 315.087985 -296.071245)
			(xy 315.13716 -296.069264) (xy 315.186015 -296.075196) (xy 315.233286 -296.088888) (xy 315.277748 -296.109986)
			(xy 315.318251 -296.137942) (xy 315.353744 -296.172034) (xy 315.360113 -296.18051) (xy 316.956184 -296.18051)
			(xy 316.960255 -296.124888) (xy 316.972381 -296.070451) (xy 316.992304 -296.01836) (xy 317.0196 -295.969725)
			(xy 317.053686 -295.925582) (xy 317.093835 -295.886873) (xy 317.139193 -295.854422) (xy 317.188793 -295.828921)
			(xy 317.241577 -295.810914) (xy 317.29642 -295.800784) (xy 317.352154 -295.798747) (xy 317.407591 -295.804847)
			(xy 317.461548 -295.818953) (xy 317.512877 -295.840765) (xy 317.560483 -295.869819) (xy 317.603351 -295.905494)
			(xy 317.640568 -295.947031) (xy 317.671341 -295.993544) (xy 317.695013 -296.044041) (xy 317.711081 -296.097448)
			(xy 317.719201 -296.152624) (xy 317.71971 -296.18051) (xy 317.719201 -296.208396) (xy 317.711081 -296.263572)
			(xy 317.695013 -296.316979) (xy 317.671341 -296.367476) (xy 317.640568 -296.413989) (xy 317.603351 -296.455526)
			(xy 317.560483 -296.491201) (xy 317.512877 -296.520255) (xy 317.461548 -296.542067) (xy 317.407591 -296.556173)
			(xy 317.352154 -296.562273) (xy 317.29642 -296.560236) (xy 317.241577 -296.550106) (xy 317.188793 -296.532099)
			(xy 317.139193 -296.506598) (xy 317.093835 -296.474147) (xy 317.053686 -296.435438) (xy 317.0196 -296.391295)
			(xy 316.992304 -296.34266) (xy 316.972381 -296.290569) (xy 316.960255 -296.236132) (xy 316.956184 -296.18051)
			(xy 315.360113 -296.18051) (xy 315.383309 -296.211378) (xy 315.40618 -296.254955) (xy 315.421764 -296.301636)
			(xy 315.429659 -296.350213) (xy 315.430154 -296.37482) (xy 315.429659 -296.399427) (xy 315.421764 -296.448004)
			(xy 315.40618 -296.494685) (xy 315.383309 -296.538262) (xy 315.353744 -296.577606) (xy 315.318251 -296.611698)
			(xy 315.31626 -296.613072) (xy 321.462398 -296.613072) (xy 321.466469 -296.55745) (xy 321.478595 -296.503013)
			(xy 321.498518 -296.450922) (xy 321.525814 -296.402287) (xy 321.5599 -296.358144) (xy 321.600049 -296.319435)
			(xy 321.645407 -296.286984) (xy 321.695007 -296.261483) (xy 321.747791 -296.243476) (xy 321.802634 -296.233346)
			(xy 321.858368 -296.231309) (xy 321.913805 -296.237409) (xy 321.967762 -296.251515) (xy 322.019091 -296.273327)
			(xy 322.066697 -296.302381) (xy 322.109565 -296.338056) (xy 322.146782 -296.379593) (xy 322.177555 -296.426106)
			(xy 322.201227 -296.476603) (xy 322.217295 -296.53001) (xy 322.225415 -296.585186) (xy 322.225924 -296.613072)
			(xy 322.737224 -296.613072) (xy 322.741295 -296.55745) (xy 322.753421 -296.503013) (xy 322.773344 -296.450922)
			(xy 322.80064 -296.402287) (xy 322.834726 -296.358144) (xy 322.874875 -296.319435) (xy 322.920233 -296.286984)
			(xy 322.969833 -296.261483) (xy 323.022617 -296.243476) (xy 323.07746 -296.233346) (xy 323.133194 -296.231309)
			(xy 323.188631 -296.237409) (xy 323.242588 -296.251515) (xy 323.293917 -296.273327) (xy 323.341523 -296.302381)
			(xy 323.384391 -296.338056) (xy 323.421608 -296.379593) (xy 323.452381 -296.426106) (xy 323.476053 -296.476603)
			(xy 323.492121 -296.53001) (xy 323.500241 -296.585186) (xy 323.50075 -296.613072) (xy 323.500241 -296.640958)
			(xy 323.492121 -296.696134) (xy 323.476053 -296.749541) (xy 323.452381 -296.800038) (xy 323.421608 -296.846551)
			(xy 323.384391 -296.888088) (xy 323.341523 -296.923763) (xy 323.293917 -296.952817) (xy 323.242588 -296.974629)
			(xy 323.188631 -296.988735) (xy 323.133194 -296.994835) (xy 323.07746 -296.992798) (xy 323.022617 -296.982668)
			(xy 322.969833 -296.964661) (xy 322.920233 -296.93916) (xy 322.874875 -296.906709) (xy 322.834726 -296.868)
			(xy 322.80064 -296.823857) (xy 322.773344 -296.775222) (xy 322.753421 -296.723131) (xy 322.741295 -296.668694)
			(xy 322.737224 -296.613072) (xy 322.225924 -296.613072) (xy 322.225415 -296.640958) (xy 322.217295 -296.696134)
			(xy 322.201227 -296.749541) (xy 322.177555 -296.800038) (xy 322.146782 -296.846551) (xy 322.109565 -296.888088)
			(xy 322.066697 -296.923763) (xy 322.019091 -296.952817) (xy 321.967762 -296.974629) (xy 321.913805 -296.988735)
			(xy 321.858368 -296.994835) (xy 321.802634 -296.992798) (xy 321.747791 -296.982668) (xy 321.695007 -296.964661)
			(xy 321.645407 -296.93916) (xy 321.600049 -296.906709) (xy 321.5599 -296.868) (xy 321.525814 -296.823857)
			(xy 321.498518 -296.775222) (xy 321.478595 -296.723131) (xy 321.466469 -296.668694) (xy 321.462398 -296.613072)
			(xy 315.31626 -296.613072) (xy 315.277748 -296.639654) (xy 315.233286 -296.660752) (xy 315.186015 -296.674444)
			(xy 315.13716 -296.680376) (xy 315.087985 -296.678395) (xy 315.039766 -296.668551) (xy 314.99375 -296.651099)
			(xy 314.951129 -296.626492) (xy 314.913008 -296.595367) (xy 314.880373 -296.55853) (xy 314.85407 -296.516934)
			(xy 314.834779 -296.471658) (xy 314.823002 -296.423874) (xy 314.819042 -296.37482) (xy 314.480194 -296.37482)
			(xy 314.479699 -296.399427) (xy 314.471804 -296.448004) (xy 314.45622 -296.494685) (xy 314.433349 -296.538262)
			(xy 314.403784 -296.577606) (xy 314.368291 -296.611698) (xy 314.327788 -296.639654) (xy 314.283326 -296.660752)
			(xy 314.236055 -296.674444) (xy 314.1872 -296.680376) (xy 314.138025 -296.678395) (xy 314.089806 -296.668551)
			(xy 314.04379 -296.651099) (xy 314.001169 -296.626492) (xy 313.963048 -296.595367) (xy 313.930413 -296.55853)
			(xy 313.90411 -296.516934) (xy 313.884819 -296.471658) (xy 313.873042 -296.423874) (xy 313.869082 -296.37482)
			(xy 313.530234 -296.37482) (xy 313.529739 -296.399427) (xy 313.521844 -296.448004) (xy 313.50626 -296.494685)
			(xy 313.483389 -296.538262) (xy 313.453824 -296.577606) (xy 313.418331 -296.611698) (xy 313.377828 -296.639654)
			(xy 313.333366 -296.660752) (xy 313.286095 -296.674444) (xy 313.23724 -296.680376) (xy 313.188065 -296.678395)
			(xy 313.139846 -296.668551) (xy 313.09383 -296.651099) (xy 313.051209 -296.626492) (xy 313.013088 -296.595367)
			(xy 312.980453 -296.55853) (xy 312.95415 -296.516934) (xy 312.934859 -296.471658) (xy 312.923082 -296.423874)
			(xy 312.919122 -296.37482) (xy 312.58002 -296.37482) (xy 312.579525 -296.399427) (xy 312.57163 -296.448004)
			(xy 312.556046 -296.494685) (xy 312.533175 -296.538262) (xy 312.50361 -296.577606) (xy 312.468117 -296.611698)
			(xy 312.427614 -296.639654) (xy 312.383152 -296.660752) (xy 312.335881 -296.674444) (xy 312.287026 -296.680376)
			(xy 312.237851 -296.678395) (xy 312.189632 -296.668551) (xy 312.143616 -296.651099) (xy 312.100995 -296.626492)
			(xy 312.062874 -296.595367) (xy 312.030239 -296.55853) (xy 312.003936 -296.516934) (xy 311.984645 -296.471658)
			(xy 311.972868 -296.423874) (xy 311.968908 -296.37482) (xy 311.63006 -296.37482) (xy 311.629565 -296.399427)
			(xy 311.62167 -296.448004) (xy 311.606086 -296.494685) (xy 311.583215 -296.538262) (xy 311.55365 -296.577606)
			(xy 311.518157 -296.611698) (xy 311.477654 -296.639654) (xy 311.433192 -296.660752) (xy 311.385921 -296.674444)
			(xy 311.337066 -296.680376) (xy 311.287891 -296.678395) (xy 311.239672 -296.668551) (xy 311.193656 -296.651099)
			(xy 311.151035 -296.626492) (xy 311.112914 -296.595367) (xy 311.080279 -296.55853) (xy 311.053976 -296.516934)
			(xy 311.034685 -296.471658) (xy 311.022908 -296.423874) (xy 311.018948 -296.37482) (xy 310.6801 -296.37482)
			(xy 310.679605 -296.399427) (xy 310.67171 -296.448004) (xy 310.656126 -296.494685) (xy 310.633255 -296.538262)
			(xy 310.60369 -296.577606) (xy 310.568197 -296.611698) (xy 310.527694 -296.639654) (xy 310.483232 -296.660752)
			(xy 310.435961 -296.674444) (xy 310.387106 -296.680376) (xy 310.337931 -296.678395) (xy 310.289712 -296.668551)
			(xy 310.243696 -296.651099) (xy 310.201075 -296.626492) (xy 310.162954 -296.595367) (xy 310.130319 -296.55853)
			(xy 310.104016 -296.516934) (xy 310.084725 -296.471658) (xy 310.072948 -296.423874) (xy 310.068988 -296.37482)
			(xy 309.73014 -296.37482) (xy 309.729645 -296.399427) (xy 309.72175 -296.448004) (xy 309.706166 -296.494685)
			(xy 309.683295 -296.538262) (xy 309.65373 -296.577606) (xy 309.618237 -296.611698) (xy 309.577734 -296.639654)
			(xy 309.533272 -296.660752) (xy 309.486001 -296.674444) (xy 309.437146 -296.680376) (xy 309.387971 -296.678395)
			(xy 309.339752 -296.668551) (xy 309.293736 -296.651099) (xy 309.251115 -296.626492) (xy 309.212994 -296.595367)
			(xy 309.180359 -296.55853) (xy 309.154056 -296.516934) (xy 309.134765 -296.471658) (xy 309.122988 -296.423874)
			(xy 309.119028 -296.37482) (xy 308.78018 -296.37482) (xy 308.779685 -296.399427) (xy 308.77179 -296.448004)
			(xy 308.756206 -296.494685) (xy 308.733335 -296.538262) (xy 308.70377 -296.577606) (xy 308.668277 -296.611698)
			(xy 308.627774 -296.639654) (xy 308.583312 -296.660752) (xy 308.536041 -296.674444) (xy 308.487186 -296.680376)
			(xy 308.438011 -296.678395) (xy 308.389792 -296.668551) (xy 308.343776 -296.651099) (xy 308.301155 -296.626492)
			(xy 308.263034 -296.595367) (xy 308.230399 -296.55853) (xy 308.204096 -296.516934) (xy 308.184805 -296.471658)
			(xy 308.173028 -296.423874) (xy 308.169068 -296.37482) (xy 307.83022 -296.37482) (xy 307.829725 -296.399427)
			(xy 307.82183 -296.448004) (xy 307.806246 -296.494685) (xy 307.783375 -296.538262) (xy 307.75381 -296.577606)
			(xy 307.718317 -296.611698) (xy 307.677814 -296.639654) (xy 307.633352 -296.660752) (xy 307.586081 -296.674444)
			(xy 307.537226 -296.680376) (xy 307.488051 -296.678395) (xy 307.439832 -296.668551) (xy 307.393816 -296.651099)
			(xy 307.351195 -296.626492) (xy 307.313074 -296.595367) (xy 307.280439 -296.55853) (xy 307.254136 -296.516934)
			(xy 307.234845 -296.471658) (xy 307.223068 -296.423874) (xy 307.219108 -296.37482) (xy 306.880006 -296.37482)
			(xy 306.879511 -296.399427) (xy 306.871616 -296.448004) (xy 306.856032 -296.494685) (xy 306.833161 -296.538262)
			(xy 306.803596 -296.577606) (xy 306.768103 -296.611698) (xy 306.7276 -296.639654) (xy 306.683138 -296.660752)
			(xy 306.635867 -296.674444) (xy 306.587012 -296.680376) (xy 306.537837 -296.678395) (xy 306.489618 -296.668551)
			(xy 306.443602 -296.651099) (xy 306.400981 -296.626492) (xy 306.36286 -296.595367) (xy 306.330225 -296.55853)
			(xy 306.303922 -296.516934) (xy 306.284631 -296.471658) (xy 306.272854 -296.423874) (xy 306.268894 -296.37482)
			(xy 305.930046 -296.37482) (xy 305.929551 -296.399427) (xy 305.921656 -296.448004) (xy 305.906072 -296.494685)
			(xy 305.883201 -296.538262) (xy 305.853636 -296.577606) (xy 305.818143 -296.611698) (xy 305.77764 -296.639654)
			(xy 305.733178 -296.660752) (xy 305.685907 -296.674444) (xy 305.637052 -296.680376) (xy 305.587877 -296.678395)
			(xy 305.539658 -296.668551) (xy 305.493642 -296.651099) (xy 305.451021 -296.626492) (xy 305.4129 -296.595367)
			(xy 305.380265 -296.55853) (xy 305.353962 -296.516934) (xy 305.334671 -296.471658) (xy 305.322894 -296.423874)
			(xy 305.318934 -296.37482) (xy 304.980086 -296.37482) (xy 304.979591 -296.399427) (xy 304.971696 -296.448004)
			(xy 304.956112 -296.494685) (xy 304.933241 -296.538262) (xy 304.903676 -296.577606) (xy 304.868183 -296.611698)
			(xy 304.82768 -296.639654) (xy 304.783218 -296.660752) (xy 304.735947 -296.674444) (xy 304.687092 -296.680376)
			(xy 304.637917 -296.678395) (xy 304.589698 -296.668551) (xy 304.543682 -296.651099) (xy 304.501061 -296.626492)
			(xy 304.46294 -296.595367) (xy 304.430305 -296.55853) (xy 304.404002 -296.516934) (xy 304.384711 -296.471658)
			(xy 304.372934 -296.423874) (xy 304.368974 -296.37482) (xy 304.030126 -296.37482) (xy 304.029631 -296.399427)
			(xy 304.021736 -296.448004) (xy 304.006152 -296.494685) (xy 303.983281 -296.538262) (xy 303.953716 -296.577606)
			(xy 303.918223 -296.611698) (xy 303.87772 -296.639654) (xy 303.833258 -296.660752) (xy 303.785987 -296.674444)
			(xy 303.737132 -296.680376) (xy 303.687957 -296.678395) (xy 303.639738 -296.668551) (xy 303.593722 -296.651099)
			(xy 303.551101 -296.626492) (xy 303.51298 -296.595367) (xy 303.480345 -296.55853) (xy 303.454042 -296.516934)
			(xy 303.434751 -296.471658) (xy 303.422974 -296.423874) (xy 303.419014 -296.37482) (xy 303.080166 -296.37482)
			(xy 303.079671 -296.399427) (xy 303.071776 -296.448004) (xy 303.056192 -296.494685) (xy 303.033321 -296.538262)
			(xy 303.003756 -296.577606) (xy 302.968263 -296.611698) (xy 302.92776 -296.639654) (xy 302.883298 -296.660752)
			(xy 302.836027 -296.674444) (xy 302.787172 -296.680376) (xy 302.737997 -296.678395) (xy 302.689778 -296.668551)
			(xy 302.643762 -296.651099) (xy 302.601141 -296.626492) (xy 302.56302 -296.595367) (xy 302.530385 -296.55853)
			(xy 302.504082 -296.516934) (xy 302.484791 -296.471658) (xy 302.473014 -296.423874) (xy 302.469054 -296.37482)
			(xy 302.130206 -296.37482) (xy 302.129711 -296.399427) (xy 302.121816 -296.448004) (xy 302.106232 -296.494685)
			(xy 302.083361 -296.538262) (xy 302.053796 -296.577606) (xy 302.018303 -296.611698) (xy 301.9778 -296.639654)
			(xy 301.933338 -296.660752) (xy 301.886067 -296.674444) (xy 301.837212 -296.680376) (xy 301.788037 -296.678395)
			(xy 301.739818 -296.668551) (xy 301.693802 -296.651099) (xy 301.651181 -296.626492) (xy 301.61306 -296.595367)
			(xy 301.580425 -296.55853) (xy 301.554122 -296.516934) (xy 301.534831 -296.471658) (xy 301.523054 -296.423874)
			(xy 301.519094 -296.37482) (xy 299.280072 -296.37482) (xy 299.279577 -296.399427) (xy 299.271682 -296.448004)
			(xy 299.256098 -296.494685) (xy 299.233227 -296.538262) (xy 299.203662 -296.577606) (xy 299.168169 -296.611698)
			(xy 299.127666 -296.639654) (xy 299.083204 -296.660752) (xy 299.035933 -296.674444) (xy 298.987078 -296.680376)
			(xy 298.937903 -296.678395) (xy 298.889684 -296.668551) (xy 298.843668 -296.651099) (xy 298.801047 -296.626492)
			(xy 298.762926 -296.595367) (xy 298.730291 -296.55853) (xy 298.703988 -296.516934) (xy 298.684697 -296.471658)
			(xy 298.67292 -296.423874) (xy 298.66896 -296.37482) (xy 298.330112 -296.37482) (xy 298.329617 -296.399427)
			(xy 298.321722 -296.448004) (xy 298.306138 -296.494685) (xy 298.283267 -296.538262) (xy 298.253702 -296.577606)
			(xy 298.218209 -296.611698) (xy 298.177706 -296.639654) (xy 298.133244 -296.660752) (xy 298.085973 -296.674444)
			(xy 298.037118 -296.680376) (xy 297.987943 -296.678395) (xy 297.939724 -296.668551) (xy 297.893708 -296.651099)
			(xy 297.851087 -296.626492) (xy 297.812966 -296.595367) (xy 297.780331 -296.55853) (xy 297.754028 -296.516934)
			(xy 297.734737 -296.471658) (xy 297.72296 -296.423874) (xy 297.719 -296.37482) (xy 297.380152 -296.37482)
			(xy 297.379657 -296.399427) (xy 297.371762 -296.448004) (xy 297.356178 -296.494685) (xy 297.333307 -296.538262)
			(xy 297.303742 -296.577606) (xy 297.268249 -296.611698) (xy 297.227746 -296.639654) (xy 297.183284 -296.660752)
			(xy 297.136013 -296.674444) (xy 297.087158 -296.680376) (xy 297.037983 -296.678395) (xy 296.989764 -296.668551)
			(xy 296.943748 -296.651099) (xy 296.901127 -296.626492) (xy 296.863006 -296.595367) (xy 296.830371 -296.55853)
			(xy 296.804068 -296.516934) (xy 296.784777 -296.471658) (xy 296.773 -296.423874) (xy 296.76904 -296.37482)
			(xy 296.430192 -296.37482) (xy 296.429697 -296.399427) (xy 296.421802 -296.448004) (xy 296.406218 -296.494685)
			(xy 296.383347 -296.538262) (xy 296.353782 -296.577606) (xy 296.318289 -296.611698) (xy 296.277786 -296.639654)
			(xy 296.233324 -296.660752) (xy 296.186053 -296.674444) (xy 296.137198 -296.680376) (xy 296.088023 -296.678395)
			(xy 296.039804 -296.668551) (xy 295.993788 -296.651099) (xy 295.951167 -296.626492) (xy 295.913046 -296.595367)
			(xy 295.880411 -296.55853) (xy 295.854108 -296.516934) (xy 295.834817 -296.471658) (xy 295.82304 -296.423874)
			(xy 295.81908 -296.37482) (xy 295.480232 -296.37482) (xy 295.479737 -296.399427) (xy 295.471842 -296.448004)
			(xy 295.456258 -296.494685) (xy 295.433387 -296.538262) (xy 295.403822 -296.577606) (xy 295.368329 -296.611698)
			(xy 295.327826 -296.639654) (xy 295.283364 -296.660752) (xy 295.236093 -296.674444) (xy 295.187238 -296.680376)
			(xy 295.138063 -296.678395) (xy 295.089844 -296.668551) (xy 295.043828 -296.651099) (xy 295.001207 -296.626492)
			(xy 294.963086 -296.595367) (xy 294.930451 -296.55853) (xy 294.904148 -296.516934) (xy 294.884857 -296.471658)
			(xy 294.87308 -296.423874) (xy 294.86912 -296.37482) (xy 294.530018 -296.37482) (xy 294.529523 -296.399427)
			(xy 294.521628 -296.448004) (xy 294.506044 -296.494685) (xy 294.483173 -296.538262) (xy 294.453608 -296.577606)
			(xy 294.418115 -296.611698) (xy 294.377612 -296.639654) (xy 294.33315 -296.660752) (xy 294.285879 -296.674444)
			(xy 294.237024 -296.680376) (xy 294.187849 -296.678395) (xy 294.13963 -296.668551) (xy 294.093614 -296.651099)
			(xy 294.050993 -296.626492) (xy 294.012872 -296.595367) (xy 293.980237 -296.55853) (xy 293.953934 -296.516934)
			(xy 293.934643 -296.471658) (xy 293.922866 -296.423874) (xy 293.918906 -296.37482) (xy 293.580058 -296.37482)
			(xy 293.579563 -296.399427) (xy 293.571668 -296.448004) (xy 293.556084 -296.494685) (xy 293.533213 -296.538262)
			(xy 293.503648 -296.577606) (xy 293.468155 -296.611698) (xy 293.427652 -296.639654) (xy 293.38319 -296.660752)
			(xy 293.335919 -296.674444) (xy 293.287064 -296.680376) (xy 293.237889 -296.678395) (xy 293.18967 -296.668551)
			(xy 293.143654 -296.651099) (xy 293.101033 -296.626492) (xy 293.062912 -296.595367) (xy 293.030277 -296.55853)
			(xy 293.003974 -296.516934) (xy 292.984683 -296.471658) (xy 292.972906 -296.423874) (xy 292.968946 -296.37482)
			(xy 292.630098 -296.37482) (xy 292.629603 -296.399427) (xy 292.621708 -296.448004) (xy 292.606124 -296.494685)
			(xy 292.583253 -296.538262) (xy 292.553688 -296.577606) (xy 292.518195 -296.611698) (xy 292.477692 -296.639654)
			(xy 292.43323 -296.660752) (xy 292.385959 -296.674444) (xy 292.337104 -296.680376) (xy 292.287929 -296.678395)
			(xy 292.23971 -296.668551) (xy 292.193694 -296.651099) (xy 292.151073 -296.626492) (xy 292.112952 -296.595367)
			(xy 292.080317 -296.55853) (xy 292.054014 -296.516934) (xy 292.034723 -296.471658) (xy 292.022946 -296.423874)
			(xy 292.018986 -296.37482) (xy 290.730178 -296.37482) (xy 290.729683 -296.399427) (xy 290.721788 -296.448004)
			(xy 290.706204 -296.494685) (xy 290.683333 -296.538262) (xy 290.653768 -296.577606) (xy 290.618275 -296.611698)
			(xy 290.577772 -296.639654) (xy 290.53331 -296.660752) (xy 290.486039 -296.674444) (xy 290.437184 -296.680376)
			(xy 290.388009 -296.678395) (xy 290.33979 -296.668551) (xy 290.293774 -296.651099) (xy 290.251153 -296.626492)
			(xy 290.213032 -296.595367) (xy 290.180397 -296.55853) (xy 290.154094 -296.516934) (xy 290.134803 -296.471658)
			(xy 290.123026 -296.423874) (xy 290.119066 -296.37482) (xy 289.780218 -296.37482) (xy 289.779723 -296.399427)
			(xy 289.771828 -296.448004) (xy 289.756244 -296.494685) (xy 289.733373 -296.538262) (xy 289.703808 -296.577606)
			(xy 289.668315 -296.611698) (xy 289.627812 -296.639654) (xy 289.58335 -296.660752) (xy 289.536079 -296.674444)
			(xy 289.487224 -296.680376) (xy 289.438049 -296.678395) (xy 289.38983 -296.668551) (xy 289.343814 -296.651099)
			(xy 289.301193 -296.626492) (xy 289.263072 -296.595367) (xy 289.230437 -296.55853) (xy 289.204134 -296.516934)
			(xy 289.184843 -296.471658) (xy 289.173066 -296.423874) (xy 289.169106 -296.37482) (xy 288.830258 -296.37482)
			(xy 288.829763 -296.399427) (xy 288.821868 -296.448004) (xy 288.806284 -296.494685) (xy 288.783413 -296.538262)
			(xy 288.753848 -296.577606) (xy 288.718355 -296.611698) (xy 288.677852 -296.639654) (xy 288.63339 -296.660752)
			(xy 288.586119 -296.674444) (xy 288.537264 -296.680376) (xy 288.488089 -296.678395) (xy 288.43987 -296.668551)
			(xy 288.393854 -296.651099) (xy 288.351233 -296.626492) (xy 288.313112 -296.595367) (xy 288.280477 -296.55853)
			(xy 288.254174 -296.516934) (xy 288.234883 -296.471658) (xy 288.223106 -296.423874) (xy 288.219146 -296.37482)
			(xy 287.880044 -296.37482) (xy 287.879549 -296.399427) (xy 287.871654 -296.448004) (xy 287.85607 -296.494685)
			(xy 287.833199 -296.538262) (xy 287.803634 -296.577606) (xy 287.768141 -296.611698) (xy 287.727638 -296.639654)
			(xy 287.683176 -296.660752) (xy 287.635905 -296.674444) (xy 287.58705 -296.680376) (xy 287.537875 -296.678395)
			(xy 287.489656 -296.668551) (xy 287.44364 -296.651099) (xy 287.401019 -296.626492) (xy 287.362898 -296.595367)
			(xy 287.330263 -296.55853) (xy 287.30396 -296.516934) (xy 287.284669 -296.471658) (xy 287.272892 -296.423874)
			(xy 287.268932 -296.37482) (xy 286.930084 -296.37482) (xy 286.929589 -296.399427) (xy 286.921694 -296.448004)
			(xy 286.90611 -296.494685) (xy 286.883239 -296.538262) (xy 286.853674 -296.577606) (xy 286.818181 -296.611698)
			(xy 286.777678 -296.639654) (xy 286.733216 -296.660752) (xy 286.685945 -296.674444) (xy 286.63709 -296.680376)
			(xy 286.587915 -296.678395) (xy 286.539696 -296.668551) (xy 286.49368 -296.651099) (xy 286.451059 -296.626492)
			(xy 286.412938 -296.595367) (xy 286.380303 -296.55853) (xy 286.354 -296.516934) (xy 286.334709 -296.471658)
			(xy 286.322932 -296.423874) (xy 286.318972 -296.37482) (xy 285.980124 -296.37482) (xy 285.979629 -296.399427)
			(xy 285.971734 -296.448004) (xy 285.95615 -296.494685) (xy 285.933279 -296.538262) (xy 285.903714 -296.577606)
			(xy 285.868221 -296.611698) (xy 285.827718 -296.639654) (xy 285.783256 -296.660752) (xy 285.735985 -296.674444)
			(xy 285.68713 -296.680376) (xy 285.637955 -296.678395) (xy 285.589736 -296.668551) (xy 285.54372 -296.651099)
			(xy 285.501099 -296.626492) (xy 285.462978 -296.595367) (xy 285.430343 -296.55853) (xy 285.40404 -296.516934)
			(xy 285.384749 -296.471658) (xy 285.372972 -296.423874) (xy 285.369012 -296.37482) (xy 285.030164 -296.37482)
			(xy 285.029669 -296.399427) (xy 285.021774 -296.448004) (xy 285.00619 -296.494685) (xy 284.983319 -296.538262)
			(xy 284.953754 -296.577606) (xy 284.918261 -296.611698) (xy 284.877758 -296.639654) (xy 284.833296 -296.660752)
			(xy 284.786025 -296.674444) (xy 284.73717 -296.680376) (xy 284.687995 -296.678395) (xy 284.639776 -296.668551)
			(xy 284.59376 -296.651099) (xy 284.551139 -296.626492) (xy 284.513018 -296.595367) (xy 284.480383 -296.55853)
			(xy 284.45408 -296.516934) (xy 284.434789 -296.471658) (xy 284.423012 -296.423874) (xy 284.419052 -296.37482)
			(xy 284.080204 -296.37482) (xy 284.079709 -296.399427) (xy 284.071814 -296.448004) (xy 284.05623 -296.494685)
			(xy 284.033359 -296.538262) (xy 284.003794 -296.577606) (xy 283.968301 -296.611698) (xy 283.927798 -296.639654)
			(xy 283.883336 -296.660752) (xy 283.836065 -296.674444) (xy 283.78721 -296.680376) (xy 283.738035 -296.678395)
			(xy 283.689816 -296.668551) (xy 283.6438 -296.651099) (xy 283.601179 -296.626492) (xy 283.563058 -296.595367)
			(xy 283.530423 -296.55853) (xy 283.50412 -296.516934) (xy 283.484829 -296.471658) (xy 283.473052 -296.423874)
			(xy 283.469092 -296.37482) (xy 283.130244 -296.37482) (xy 283.129749 -296.399427) (xy 283.121854 -296.448004)
			(xy 283.10627 -296.494685) (xy 283.083399 -296.538262) (xy 283.053834 -296.577606) (xy 283.018341 -296.611698)
			(xy 282.977838 -296.639654) (xy 282.933376 -296.660752) (xy 282.886105 -296.674444) (xy 282.83725 -296.680376)
			(xy 282.788075 -296.678395) (xy 282.739856 -296.668551) (xy 282.69384 -296.651099) (xy 282.651219 -296.626492)
			(xy 282.613098 -296.595367) (xy 282.580463 -296.55853) (xy 282.55416 -296.516934) (xy 282.534869 -296.471658)
			(xy 282.523092 -296.423874) (xy 282.519132 -296.37482) (xy 282.18003 -296.37482) (xy 282.179535 -296.399427)
			(xy 282.17164 -296.448004) (xy 282.156056 -296.494685) (xy 282.133185 -296.538262) (xy 282.10362 -296.577606)
			(xy 282.068127 -296.611698) (xy 282.027624 -296.639654) (xy 281.983162 -296.660752) (xy 281.935891 -296.674444)
			(xy 281.887036 -296.680376) (xy 281.837861 -296.678395) (xy 281.789642 -296.668551) (xy 281.743626 -296.651099)
			(xy 281.701005 -296.626492) (xy 281.662884 -296.595367) (xy 281.630249 -296.55853) (xy 281.603946 -296.516934)
			(xy 281.584655 -296.471658) (xy 281.572878 -296.423874) (xy 281.568918 -296.37482) (xy 281.23007 -296.37482)
			(xy 281.229575 -296.399427) (xy 281.22168 -296.448004) (xy 281.206096 -296.494685) (xy 281.183225 -296.538262)
			(xy 281.15366 -296.577606) (xy 281.118167 -296.611698) (xy 281.077664 -296.639654) (xy 281.033202 -296.660752)
			(xy 280.985931 -296.674444) (xy 280.937076 -296.680376) (xy 280.887901 -296.678395) (xy 280.839682 -296.668551)
			(xy 280.793666 -296.651099) (xy 280.751045 -296.626492) (xy 280.712924 -296.595367) (xy 280.680289 -296.55853)
			(xy 280.653986 -296.516934) (xy 280.634695 -296.471658) (xy 280.622918 -296.423874) (xy 280.618958 -296.37482)
			(xy 280.28011 -296.37482) (xy 280.279615 -296.399427) (xy 280.27172 -296.448004) (xy 280.256136 -296.494685)
			(xy 280.233265 -296.538262) (xy 280.2037 -296.577606) (xy 280.168207 -296.611698) (xy 280.127704 -296.639654)
			(xy 280.083242 -296.660752) (xy 280.035971 -296.674444) (xy 279.987116 -296.680376) (xy 279.937941 -296.678395)
			(xy 279.889722 -296.668551) (xy 279.843706 -296.651099) (xy 279.801085 -296.626492) (xy 279.762964 -296.595367)
			(xy 279.730329 -296.55853) (xy 279.704026 -296.516934) (xy 279.684735 -296.471658) (xy 279.672958 -296.423874)
			(xy 279.668998 -296.37482) (xy 279.41397 -296.37482) (xy 279.41397 -297.32478) (xy 279.668998 -297.32478)
			(xy 279.672958 -297.275726) (xy 279.684735 -297.227942) (xy 279.704026 -297.182666) (xy 279.730329 -297.14107)
			(xy 279.762964 -297.104233) (xy 279.801085 -297.073108) (xy 279.843706 -297.048501) (xy 279.889722 -297.031049)
			(xy 279.937941 -297.021205) (xy 279.987116 -297.019224) (xy 280.035971 -297.025156) (xy 280.083242 -297.038848)
			(xy 280.127704 -297.059946) (xy 280.168207 -297.087902) (xy 280.2037 -297.121994) (xy 280.233265 -297.161338)
			(xy 280.256136 -297.204915) (xy 280.27172 -297.251596) (xy 280.279615 -297.300173) (xy 280.28011 -297.32478)
			(xy 280.618958 -297.32478) (xy 280.622918 -297.275726) (xy 280.634695 -297.227942) (xy 280.653986 -297.182666)
			(xy 280.680289 -297.14107) (xy 280.712924 -297.104233) (xy 280.751045 -297.073108) (xy 280.793666 -297.048501)
			(xy 280.839682 -297.031049) (xy 280.887901 -297.021205) (xy 280.937076 -297.019224) (xy 280.985931 -297.025156)
			(xy 281.033202 -297.038848) (xy 281.077664 -297.059946) (xy 281.118167 -297.087902) (xy 281.15366 -297.121994)
			(xy 281.183225 -297.161338) (xy 281.206096 -297.204915) (xy 281.22168 -297.251596) (xy 281.229575 -297.300173)
			(xy 281.23007 -297.32478) (xy 281.568918 -297.32478) (xy 281.572878 -297.275726) (xy 281.584655 -297.227942)
			(xy 281.603946 -297.182666) (xy 281.630249 -297.14107) (xy 281.662884 -297.104233) (xy 281.701005 -297.073108)
			(xy 281.743626 -297.048501) (xy 281.789642 -297.031049) (xy 281.837861 -297.021205) (xy 281.887036 -297.019224)
			(xy 281.935891 -297.025156) (xy 281.983162 -297.038848) (xy 282.027624 -297.059946) (xy 282.068127 -297.087902)
			(xy 282.10362 -297.121994) (xy 282.133185 -297.161338) (xy 282.156056 -297.204915) (xy 282.17164 -297.251596)
			(xy 282.179535 -297.300173) (xy 282.18003 -297.32478) (xy 282.519132 -297.32478) (xy 282.523092 -297.275726)
			(xy 282.534869 -297.227942) (xy 282.55416 -297.182666) (xy 282.580463 -297.14107) (xy 282.613098 -297.104233)
			(xy 282.651219 -297.073108) (xy 282.69384 -297.048501) (xy 282.739856 -297.031049) (xy 282.788075 -297.021205)
			(xy 282.83725 -297.019224) (xy 282.886105 -297.025156) (xy 282.933376 -297.038848) (xy 282.977838 -297.059946)
			(xy 283.018341 -297.087902) (xy 283.053834 -297.121994) (xy 283.083399 -297.161338) (xy 283.10627 -297.204915)
			(xy 283.121854 -297.251596) (xy 283.129749 -297.300173) (xy 283.130244 -297.32478) (xy 283.469092 -297.32478)
			(xy 283.473052 -297.275726) (xy 283.484829 -297.227942) (xy 283.50412 -297.182666) (xy 283.530423 -297.14107)
			(xy 283.563058 -297.104233) (xy 283.601179 -297.073108) (xy 283.6438 -297.048501) (xy 283.689816 -297.031049)
			(xy 283.738035 -297.021205) (xy 283.78721 -297.019224) (xy 283.836065 -297.025156) (xy 283.883336 -297.038848)
			(xy 283.927798 -297.059946) (xy 283.968301 -297.087902) (xy 284.003794 -297.121994) (xy 284.033359 -297.161338)
			(xy 284.05623 -297.204915) (xy 284.071814 -297.251596) (xy 284.079709 -297.300173) (xy 284.080204 -297.32478)
			(xy 284.419052 -297.32478) (xy 284.423012 -297.275726) (xy 284.434789 -297.227942) (xy 284.45408 -297.182666)
			(xy 284.480383 -297.14107) (xy 284.513018 -297.104233) (xy 284.551139 -297.073108) (xy 284.59376 -297.048501)
			(xy 284.639776 -297.031049) (xy 284.687995 -297.021205) (xy 284.73717 -297.019224) (xy 284.786025 -297.025156)
			(xy 284.833296 -297.038848) (xy 284.877758 -297.059946) (xy 284.918261 -297.087902) (xy 284.953754 -297.121994)
			(xy 284.983319 -297.161338) (xy 285.00619 -297.204915) (xy 285.021774 -297.251596) (xy 285.029669 -297.300173)
			(xy 285.030164 -297.32478) (xy 285.369012 -297.32478) (xy 285.372972 -297.275726) (xy 285.384749 -297.227942)
			(xy 285.40404 -297.182666) (xy 285.430343 -297.14107) (xy 285.462978 -297.104233) (xy 285.501099 -297.073108)
			(xy 285.54372 -297.048501) (xy 285.589736 -297.031049) (xy 285.637955 -297.021205) (xy 285.68713 -297.019224)
			(xy 285.735985 -297.025156) (xy 285.783256 -297.038848) (xy 285.827718 -297.059946) (xy 285.868221 -297.087902)
			(xy 285.903714 -297.121994) (xy 285.933279 -297.161338) (xy 285.95615 -297.204915) (xy 285.971734 -297.251596)
			(xy 285.979629 -297.300173) (xy 285.980124 -297.32478) (xy 286.318972 -297.32478) (xy 286.322932 -297.275726)
			(xy 286.334709 -297.227942) (xy 286.354 -297.182666) (xy 286.380303 -297.14107) (xy 286.412938 -297.104233)
			(xy 286.451059 -297.073108) (xy 286.49368 -297.048501) (xy 286.539696 -297.031049) (xy 286.587915 -297.021205)
			(xy 286.63709 -297.019224) (xy 286.685945 -297.025156) (xy 286.733216 -297.038848) (xy 286.777678 -297.059946)
			(xy 286.818181 -297.087902) (xy 286.853674 -297.121994) (xy 286.883239 -297.161338) (xy 286.90611 -297.204915)
			(xy 286.921694 -297.251596) (xy 286.929589 -297.300173) (xy 286.930084 -297.32478) (xy 287.268932 -297.32478)
			(xy 287.272892 -297.275726) (xy 287.284669 -297.227942) (xy 287.30396 -297.182666) (xy 287.330263 -297.14107)
			(xy 287.362898 -297.104233) (xy 287.401019 -297.073108) (xy 287.44364 -297.048501) (xy 287.489656 -297.031049)
			(xy 287.537875 -297.021205) (xy 287.58705 -297.019224) (xy 287.635905 -297.025156) (xy 287.683176 -297.038848)
			(xy 287.727638 -297.059946) (xy 287.768141 -297.087902) (xy 287.803634 -297.121994) (xy 287.833199 -297.161338)
			(xy 287.85607 -297.204915) (xy 287.871654 -297.251596) (xy 287.879549 -297.300173) (xy 287.880044 -297.32478)
			(xy 288.218892 -297.32478) (xy 288.222852 -297.275726) (xy 288.234629 -297.227942) (xy 288.25392 -297.182666)
			(xy 288.280223 -297.14107) (xy 288.312858 -297.104233) (xy 288.350979 -297.073108) (xy 288.3936 -297.048501)
			(xy 288.439616 -297.031049) (xy 288.487835 -297.021205) (xy 288.53701 -297.019224) (xy 288.585865 -297.025156)
			(xy 288.633136 -297.038848) (xy 288.677598 -297.059946) (xy 288.718101 -297.087902) (xy 288.753594 -297.121994)
			(xy 288.783159 -297.161338) (xy 288.80603 -297.204915) (xy 288.821614 -297.251596) (xy 288.829509 -297.300173)
			(xy 288.830004 -297.32478) (xy 289.169106 -297.32478) (xy 289.173066 -297.275726) (xy 289.184843 -297.227942)
			(xy 289.204134 -297.182666) (xy 289.230437 -297.14107) (xy 289.263072 -297.104233) (xy 289.301193 -297.073108)
			(xy 289.343814 -297.048501) (xy 289.38983 -297.031049) (xy 289.438049 -297.021205) (xy 289.487224 -297.019224)
			(xy 289.536079 -297.025156) (xy 289.58335 -297.038848) (xy 289.627812 -297.059946) (xy 289.668315 -297.087902)
			(xy 289.703808 -297.121994) (xy 289.733373 -297.161338) (xy 289.756244 -297.204915) (xy 289.771828 -297.251596)
			(xy 289.779723 -297.300173) (xy 289.780218 -297.32478) (xy 290.119066 -297.32478) (xy 290.123026 -297.275726)
			(xy 290.134803 -297.227942) (xy 290.154094 -297.182666) (xy 290.180397 -297.14107) (xy 290.213032 -297.104233)
			(xy 290.251153 -297.073108) (xy 290.293774 -297.048501) (xy 290.33979 -297.031049) (xy 290.388009 -297.021205)
			(xy 290.437184 -297.019224) (xy 290.486039 -297.025156) (xy 290.53331 -297.038848) (xy 290.577772 -297.059946)
			(xy 290.618275 -297.087902) (xy 290.653768 -297.121994) (xy 290.683333 -297.161338) (xy 290.706204 -297.204915)
			(xy 290.721788 -297.251596) (xy 290.729683 -297.300173) (xy 290.730178 -297.32478) (xy 292.018986 -297.32478)
			(xy 292.022946 -297.275726) (xy 292.034723 -297.227942) (xy 292.054014 -297.182666) (xy 292.080317 -297.14107)
			(xy 292.112952 -297.104233) (xy 292.151073 -297.073108) (xy 292.193694 -297.048501) (xy 292.23971 -297.031049)
			(xy 292.287929 -297.021205) (xy 292.337104 -297.019224) (xy 292.385959 -297.025156) (xy 292.43323 -297.038848)
			(xy 292.477692 -297.059946) (xy 292.518195 -297.087902) (xy 292.553688 -297.121994) (xy 292.583253 -297.161338)
			(xy 292.606124 -297.204915) (xy 292.621708 -297.251596) (xy 292.629603 -297.300173) (xy 292.630098 -297.32478)
			(xy 292.968946 -297.32478) (xy 292.972906 -297.275726) (xy 292.984683 -297.227942) (xy 293.003974 -297.182666)
			(xy 293.030277 -297.14107) (xy 293.062912 -297.104233) (xy 293.101033 -297.073108) (xy 293.143654 -297.048501)
			(xy 293.18967 -297.031049) (xy 293.237889 -297.021205) (xy 293.287064 -297.019224) (xy 293.335919 -297.025156)
			(xy 293.38319 -297.038848) (xy 293.427652 -297.059946) (xy 293.468155 -297.087902) (xy 293.503648 -297.121994)
			(xy 293.533213 -297.161338) (xy 293.556084 -297.204915) (xy 293.571668 -297.251596) (xy 293.579563 -297.300173)
			(xy 293.580058 -297.32478) (xy 293.918906 -297.32478) (xy 293.922866 -297.275726) (xy 293.934643 -297.227942)
			(xy 293.953934 -297.182666) (xy 293.980237 -297.14107) (xy 294.012872 -297.104233) (xy 294.050993 -297.073108)
			(xy 294.093614 -297.048501) (xy 294.13963 -297.031049) (xy 294.187849 -297.021205) (xy 294.237024 -297.019224)
			(xy 294.285879 -297.025156) (xy 294.33315 -297.038848) (xy 294.377612 -297.059946) (xy 294.418115 -297.087902)
			(xy 294.453608 -297.121994) (xy 294.483173 -297.161338) (xy 294.506044 -297.204915) (xy 294.521628 -297.251596)
			(xy 294.529523 -297.300173) (xy 294.530018 -297.32478) (xy 294.86912 -297.32478) (xy 294.87308 -297.275726)
			(xy 294.884857 -297.227942) (xy 294.904148 -297.182666) (xy 294.930451 -297.14107) (xy 294.963086 -297.104233)
			(xy 295.001207 -297.073108) (xy 295.043828 -297.048501) (xy 295.089844 -297.031049) (xy 295.138063 -297.021205)
			(xy 295.187238 -297.019224) (xy 295.236093 -297.025156) (xy 295.283364 -297.038848) (xy 295.327826 -297.059946)
			(xy 295.368329 -297.087902) (xy 295.403822 -297.121994) (xy 295.433387 -297.161338) (xy 295.456258 -297.204915)
			(xy 295.471842 -297.251596) (xy 295.479737 -297.300173) (xy 295.480232 -297.32478) (xy 295.81908 -297.32478)
			(xy 295.82304 -297.275726) (xy 295.834817 -297.227942) (xy 295.854108 -297.182666) (xy 295.880411 -297.14107)
			(xy 295.913046 -297.104233) (xy 295.951167 -297.073108) (xy 295.993788 -297.048501) (xy 296.039804 -297.031049)
			(xy 296.088023 -297.021205) (xy 296.137198 -297.019224) (xy 296.186053 -297.025156) (xy 296.233324 -297.038848)
			(xy 296.277786 -297.059946) (xy 296.318289 -297.087902) (xy 296.353782 -297.121994) (xy 296.383347 -297.161338)
			(xy 296.406218 -297.204915) (xy 296.421802 -297.251596) (xy 296.429697 -297.300173) (xy 296.430192 -297.32478)
			(xy 296.76904 -297.32478) (xy 296.773 -297.275726) (xy 296.784777 -297.227942) (xy 296.804068 -297.182666)
			(xy 296.830371 -297.14107) (xy 296.863006 -297.104233) (xy 296.901127 -297.073108) (xy 296.943748 -297.048501)
			(xy 296.989764 -297.031049) (xy 297.037983 -297.021205) (xy 297.087158 -297.019224) (xy 297.136013 -297.025156)
			(xy 297.183284 -297.038848) (xy 297.227746 -297.059946) (xy 297.268249 -297.087902) (xy 297.303742 -297.121994)
			(xy 297.333307 -297.161338) (xy 297.356178 -297.204915) (xy 297.371762 -297.251596) (xy 297.379657 -297.300173)
			(xy 297.380152 -297.32478) (xy 297.719 -297.32478) (xy 297.72296 -297.275726) (xy 297.734737 -297.227942)
			(xy 297.754028 -297.182666) (xy 297.780331 -297.14107) (xy 297.812966 -297.104233) (xy 297.851087 -297.073108)
			(xy 297.893708 -297.048501) (xy 297.939724 -297.031049) (xy 297.987943 -297.021205) (xy 298.037118 -297.019224)
			(xy 298.085973 -297.025156) (xy 298.133244 -297.038848) (xy 298.177706 -297.059946) (xy 298.218209 -297.087902)
			(xy 298.253702 -297.121994) (xy 298.283267 -297.161338) (xy 298.306138 -297.204915) (xy 298.321722 -297.251596)
			(xy 298.329617 -297.300173) (xy 298.330112 -297.32478) (xy 301.519094 -297.32478) (xy 301.523054 -297.275726)
			(xy 301.534831 -297.227942) (xy 301.554122 -297.182666) (xy 301.580425 -297.14107) (xy 301.61306 -297.104233)
			(xy 301.651181 -297.073108) (xy 301.693802 -297.048501) (xy 301.739818 -297.031049) (xy 301.788037 -297.021205)
			(xy 301.837212 -297.019224) (xy 301.886067 -297.025156) (xy 301.933338 -297.038848) (xy 301.9778 -297.059946)
			(xy 302.018303 -297.087902) (xy 302.053796 -297.121994) (xy 302.083361 -297.161338) (xy 302.106232 -297.204915)
			(xy 302.121816 -297.251596) (xy 302.129711 -297.300173) (xy 302.130206 -297.32478) (xy 302.469054 -297.32478)
			(xy 302.473014 -297.275726) (xy 302.484791 -297.227942) (xy 302.504082 -297.182666) (xy 302.530385 -297.14107)
			(xy 302.56302 -297.104233) (xy 302.601141 -297.073108) (xy 302.643762 -297.048501) (xy 302.689778 -297.031049)
			(xy 302.737997 -297.021205) (xy 302.787172 -297.019224) (xy 302.836027 -297.025156) (xy 302.883298 -297.038848)
			(xy 302.92776 -297.059946) (xy 302.968263 -297.087902) (xy 303.003756 -297.121994) (xy 303.033321 -297.161338)
			(xy 303.056192 -297.204915) (xy 303.071776 -297.251596) (xy 303.079671 -297.300173) (xy 303.080166 -297.32478)
			(xy 303.419014 -297.32478) (xy 303.422974 -297.275726) (xy 303.434751 -297.227942) (xy 303.454042 -297.182666)
			(xy 303.480345 -297.14107) (xy 303.51298 -297.104233) (xy 303.551101 -297.073108) (xy 303.593722 -297.048501)
			(xy 303.639738 -297.031049) (xy 303.687957 -297.021205) (xy 303.737132 -297.019224) (xy 303.785987 -297.025156)
			(xy 303.833258 -297.038848) (xy 303.87772 -297.059946) (xy 303.918223 -297.087902) (xy 303.953716 -297.121994)
			(xy 303.983281 -297.161338) (xy 304.006152 -297.204915) (xy 304.021736 -297.251596) (xy 304.029631 -297.300173)
			(xy 304.030126 -297.32478) (xy 304.368974 -297.32478) (xy 304.372934 -297.275726) (xy 304.384711 -297.227942)
			(xy 304.404002 -297.182666) (xy 304.430305 -297.14107) (xy 304.46294 -297.104233) (xy 304.501061 -297.073108)
			(xy 304.543682 -297.048501) (xy 304.589698 -297.031049) (xy 304.637917 -297.021205) (xy 304.687092 -297.019224)
			(xy 304.735947 -297.025156) (xy 304.783218 -297.038848) (xy 304.82768 -297.059946) (xy 304.868183 -297.087902)
			(xy 304.903676 -297.121994) (xy 304.933241 -297.161338) (xy 304.956112 -297.204915) (xy 304.971696 -297.251596)
			(xy 304.979591 -297.300173) (xy 304.980086 -297.32478) (xy 305.318934 -297.32478) (xy 305.322894 -297.275726)
			(xy 305.334671 -297.227942) (xy 305.353962 -297.182666) (xy 305.380265 -297.14107) (xy 305.4129 -297.104233)
			(xy 305.451021 -297.073108) (xy 305.493642 -297.048501) (xy 305.539658 -297.031049) (xy 305.587877 -297.021205)
			(xy 305.637052 -297.019224) (xy 305.685907 -297.025156) (xy 305.733178 -297.038848) (xy 305.77764 -297.059946)
			(xy 305.818143 -297.087902) (xy 305.853636 -297.121994) (xy 305.883201 -297.161338) (xy 305.906072 -297.204915)
			(xy 305.921656 -297.251596) (xy 305.929551 -297.300173) (xy 305.930046 -297.32478) (xy 306.269148 -297.32478)
			(xy 306.273108 -297.275726) (xy 306.284885 -297.227942) (xy 306.304176 -297.182666) (xy 306.330479 -297.14107)
			(xy 306.363114 -297.104233) (xy 306.401235 -297.073108) (xy 306.443856 -297.048501) (xy 306.489872 -297.031049)
			(xy 306.538091 -297.021205) (xy 306.587266 -297.019224) (xy 306.636121 -297.025156) (xy 306.683392 -297.038848)
			(xy 306.727854 -297.059946) (xy 306.768357 -297.087902) (xy 306.80385 -297.121994) (xy 306.833415 -297.161338)
			(xy 306.856286 -297.204915) (xy 306.87187 -297.251596) (xy 306.879765 -297.300173) (xy 306.88026 -297.32478)
			(xy 307.219108 -297.32478) (xy 307.223068 -297.275726) (xy 307.234845 -297.227942) (xy 307.254136 -297.182666)
			(xy 307.280439 -297.14107) (xy 307.313074 -297.104233) (xy 307.351195 -297.073108) (xy 307.393816 -297.048501)
			(xy 307.439832 -297.031049) (xy 307.488051 -297.021205) (xy 307.537226 -297.019224) (xy 307.586081 -297.025156)
			(xy 307.633352 -297.038848) (xy 307.677814 -297.059946) (xy 307.718317 -297.087902) (xy 307.75381 -297.121994)
			(xy 307.783375 -297.161338) (xy 307.806246 -297.204915) (xy 307.82183 -297.251596) (xy 307.829725 -297.300173)
			(xy 307.83022 -297.32478) (xy 308.169068 -297.32478) (xy 308.173028 -297.275726) (xy 308.184805 -297.227942)
			(xy 308.204096 -297.182666) (xy 308.230399 -297.14107) (xy 308.263034 -297.104233) (xy 308.301155 -297.073108)
			(xy 308.343776 -297.048501) (xy 308.389792 -297.031049) (xy 308.438011 -297.021205) (xy 308.487186 -297.019224)
			(xy 308.536041 -297.025156) (xy 308.583312 -297.038848) (xy 308.627774 -297.059946) (xy 308.668277 -297.087902)
			(xy 308.70377 -297.121994) (xy 308.733335 -297.161338) (xy 308.756206 -297.204915) (xy 308.77179 -297.251596)
			(xy 308.779685 -297.300173) (xy 308.78018 -297.32478) (xy 309.119028 -297.32478) (xy 309.122988 -297.275726)
			(xy 309.134765 -297.227942) (xy 309.154056 -297.182666) (xy 309.180359 -297.14107) (xy 309.212994 -297.104233)
			(xy 309.251115 -297.073108) (xy 309.293736 -297.048501) (xy 309.339752 -297.031049) (xy 309.387971 -297.021205)
			(xy 309.437146 -297.019224) (xy 309.486001 -297.025156) (xy 309.533272 -297.038848) (xy 309.577734 -297.059946)
			(xy 309.618237 -297.087902) (xy 309.65373 -297.121994) (xy 309.683295 -297.161338) (xy 309.706166 -297.204915)
			(xy 309.72175 -297.251596) (xy 309.729645 -297.300173) (xy 309.73014 -297.32478) (xy 310.068988 -297.32478)
			(xy 310.072948 -297.275726) (xy 310.084725 -297.227942) (xy 310.104016 -297.182666) (xy 310.130319 -297.14107)
			(xy 310.162954 -297.104233) (xy 310.201075 -297.073108) (xy 310.243696 -297.048501) (xy 310.289712 -297.031049)
			(xy 310.337931 -297.021205) (xy 310.387106 -297.019224) (xy 310.435961 -297.025156) (xy 310.483232 -297.038848)
			(xy 310.527694 -297.059946) (xy 310.568197 -297.087902) (xy 310.60369 -297.121994) (xy 310.633255 -297.161338)
			(xy 310.656126 -297.204915) (xy 310.67171 -297.251596) (xy 310.679605 -297.300173) (xy 310.6801 -297.32478)
			(xy 311.018948 -297.32478) (xy 311.022908 -297.275726) (xy 311.034685 -297.227942) (xy 311.053976 -297.182666)
			(xy 311.080279 -297.14107) (xy 311.112914 -297.104233) (xy 311.151035 -297.073108) (xy 311.193656 -297.048501)
			(xy 311.239672 -297.031049) (xy 311.287891 -297.021205) (xy 311.337066 -297.019224) (xy 311.385921 -297.025156)
			(xy 311.433192 -297.038848) (xy 311.477654 -297.059946) (xy 311.518157 -297.087902) (xy 311.55365 -297.121994)
			(xy 311.583215 -297.161338) (xy 311.606086 -297.204915) (xy 311.62167 -297.251596) (xy 311.629565 -297.300173)
			(xy 311.63006 -297.32478) (xy 311.968908 -297.32478) (xy 311.972868 -297.275726) (xy 311.984645 -297.227942)
			(xy 312.003936 -297.182666) (xy 312.030239 -297.14107) (xy 312.062874 -297.104233) (xy 312.100995 -297.073108)
			(xy 312.143616 -297.048501) (xy 312.189632 -297.031049) (xy 312.237851 -297.021205) (xy 312.287026 -297.019224)
			(xy 312.335881 -297.025156) (xy 312.383152 -297.038848) (xy 312.427614 -297.059946) (xy 312.468117 -297.087902)
			(xy 312.50361 -297.121994) (xy 312.533175 -297.161338) (xy 312.556046 -297.204915) (xy 312.57163 -297.251596)
			(xy 312.579525 -297.300173) (xy 312.58002 -297.32478) (xy 312.919122 -297.32478) (xy 312.923082 -297.275726)
			(xy 312.934859 -297.227942) (xy 312.95415 -297.182666) (xy 312.980453 -297.14107) (xy 313.013088 -297.104233)
			(xy 313.051209 -297.073108) (xy 313.09383 -297.048501) (xy 313.139846 -297.031049) (xy 313.188065 -297.021205)
			(xy 313.23724 -297.019224) (xy 313.286095 -297.025156) (xy 313.333366 -297.038848) (xy 313.377828 -297.059946)
			(xy 313.418331 -297.087902) (xy 313.453824 -297.121994) (xy 313.483389 -297.161338) (xy 313.50626 -297.204915)
			(xy 313.521844 -297.251596) (xy 313.529739 -297.300173) (xy 313.530234 -297.32478) (xy 313.869082 -297.32478)
			(xy 313.873042 -297.275726) (xy 313.884819 -297.227942) (xy 313.90411 -297.182666) (xy 313.930413 -297.14107)
			(xy 313.963048 -297.104233) (xy 314.001169 -297.073108) (xy 314.04379 -297.048501) (xy 314.089806 -297.031049)
			(xy 314.138025 -297.021205) (xy 314.1872 -297.019224) (xy 314.236055 -297.025156) (xy 314.283326 -297.038848)
			(xy 314.327788 -297.059946) (xy 314.368291 -297.087902) (xy 314.403784 -297.121994) (xy 314.433349 -297.161338)
			(xy 314.45622 -297.204915) (xy 314.471804 -297.251596) (xy 314.479699 -297.300173) (xy 314.480194 -297.32478)
			(xy 314.819042 -297.32478) (xy 314.823002 -297.275726) (xy 314.834779 -297.227942) (xy 314.85407 -297.182666)
			(xy 314.880373 -297.14107) (xy 314.913008 -297.104233) (xy 314.951129 -297.073108) (xy 314.99375 -297.048501)
			(xy 315.039766 -297.031049) (xy 315.087985 -297.021205) (xy 315.13716 -297.019224) (xy 315.186015 -297.025156)
			(xy 315.233286 -297.038848) (xy 315.277748 -297.059946) (xy 315.318251 -297.087902) (xy 315.353744 -297.121994)
			(xy 315.383309 -297.161338) (xy 315.40618 -297.204915) (xy 315.421764 -297.251596) (xy 315.429659 -297.300173)
			(xy 315.430154 -297.32478) (xy 315.429659 -297.349387) (xy 315.421764 -297.397964) (xy 315.40618 -297.444645)
			(xy 315.383309 -297.488222) (xy 315.353744 -297.527566) (xy 315.318251 -297.561658) (xy 315.277748 -297.589614)
			(xy 315.233286 -297.610712) (xy 315.186015 -297.624404) (xy 315.13716 -297.630336) (xy 315.087985 -297.628355)
			(xy 315.039766 -297.618511) (xy 314.99375 -297.601059) (xy 314.951129 -297.576452) (xy 314.913008 -297.545327)
			(xy 314.880373 -297.50849) (xy 314.85407 -297.466894) (xy 314.834779 -297.421618) (xy 314.823002 -297.373834)
			(xy 314.819042 -297.32478) (xy 314.480194 -297.32478) (xy 314.479699 -297.349387) (xy 314.471804 -297.397964)
			(xy 314.45622 -297.444645) (xy 314.433349 -297.488222) (xy 314.403784 -297.527566) (xy 314.368291 -297.561658)
			(xy 314.327788 -297.589614) (xy 314.283326 -297.610712) (xy 314.236055 -297.624404) (xy 314.1872 -297.630336)
			(xy 314.138025 -297.628355) (xy 314.089806 -297.618511) (xy 314.04379 -297.601059) (xy 314.001169 -297.576452)
			(xy 313.963048 -297.545327) (xy 313.930413 -297.50849) (xy 313.90411 -297.466894) (xy 313.884819 -297.421618)
			(xy 313.873042 -297.373834) (xy 313.869082 -297.32478) (xy 313.530234 -297.32478) (xy 313.529739 -297.349387)
			(xy 313.521844 -297.397964) (xy 313.50626 -297.444645) (xy 313.483389 -297.488222) (xy 313.453824 -297.527566)
			(xy 313.418331 -297.561658) (xy 313.377828 -297.589614) (xy 313.333366 -297.610712) (xy 313.286095 -297.624404)
			(xy 313.23724 -297.630336) (xy 313.188065 -297.628355) (xy 313.139846 -297.618511) (xy 313.09383 -297.601059)
			(xy 313.051209 -297.576452) (xy 313.013088 -297.545327) (xy 312.980453 -297.50849) (xy 312.95415 -297.466894)
			(xy 312.934859 -297.421618) (xy 312.923082 -297.373834) (xy 312.919122 -297.32478) (xy 312.58002 -297.32478)
			(xy 312.579525 -297.349387) (xy 312.57163 -297.397964) (xy 312.556046 -297.444645) (xy 312.533175 -297.488222)
			(xy 312.50361 -297.527566) (xy 312.468117 -297.561658) (xy 312.427614 -297.589614) (xy 312.383152 -297.610712)
			(xy 312.335881 -297.624404) (xy 312.287026 -297.630336) (xy 312.237851 -297.628355) (xy 312.189632 -297.618511)
			(xy 312.143616 -297.601059) (xy 312.100995 -297.576452) (xy 312.062874 -297.545327) (xy 312.030239 -297.50849)
			(xy 312.003936 -297.466894) (xy 311.984645 -297.421618) (xy 311.972868 -297.373834) (xy 311.968908 -297.32478)
			(xy 311.63006 -297.32478) (xy 311.629565 -297.349387) (xy 311.62167 -297.397964) (xy 311.606086 -297.444645)
			(xy 311.583215 -297.488222) (xy 311.55365 -297.527566) (xy 311.518157 -297.561658) (xy 311.477654 -297.589614)
			(xy 311.433192 -297.610712) (xy 311.385921 -297.624404) (xy 311.337066 -297.630336) (xy 311.287891 -297.628355)
			(xy 311.239672 -297.618511) (xy 311.193656 -297.601059) (xy 311.151035 -297.576452) (xy 311.112914 -297.545327)
			(xy 311.080279 -297.50849) (xy 311.053976 -297.466894) (xy 311.034685 -297.421618) (xy 311.022908 -297.373834)
			(xy 311.018948 -297.32478) (xy 310.6801 -297.32478) (xy 310.679605 -297.349387) (xy 310.67171 -297.397964)
			(xy 310.656126 -297.444645) (xy 310.633255 -297.488222) (xy 310.60369 -297.527566) (xy 310.568197 -297.561658)
			(xy 310.527694 -297.589614) (xy 310.483232 -297.610712) (xy 310.435961 -297.624404) (xy 310.387106 -297.630336)
			(xy 310.337931 -297.628355) (xy 310.289712 -297.618511) (xy 310.243696 -297.601059) (xy 310.201075 -297.576452)
			(xy 310.162954 -297.545327) (xy 310.130319 -297.50849) (xy 310.104016 -297.466894) (xy 310.084725 -297.421618)
			(xy 310.072948 -297.373834) (xy 310.068988 -297.32478) (xy 309.73014 -297.32478) (xy 309.729645 -297.349387)
			(xy 309.72175 -297.397964) (xy 309.706166 -297.444645) (xy 309.683295 -297.488222) (xy 309.65373 -297.527566)
			(xy 309.618237 -297.561658) (xy 309.577734 -297.589614) (xy 309.533272 -297.610712) (xy 309.486001 -297.624404)
			(xy 309.437146 -297.630336) (xy 309.387971 -297.628355) (xy 309.339752 -297.618511) (xy 309.293736 -297.601059)
			(xy 309.251115 -297.576452) (xy 309.212994 -297.545327) (xy 309.180359 -297.50849) (xy 309.154056 -297.466894)
			(xy 309.134765 -297.421618) (xy 309.122988 -297.373834) (xy 309.119028 -297.32478) (xy 308.78018 -297.32478)
			(xy 308.779685 -297.349387) (xy 308.77179 -297.397964) (xy 308.756206 -297.444645) (xy 308.733335 -297.488222)
			(xy 308.70377 -297.527566) (xy 308.668277 -297.561658) (xy 308.627774 -297.589614) (xy 308.583312 -297.610712)
			(xy 308.536041 -297.624404) (xy 308.487186 -297.630336) (xy 308.438011 -297.628355) (xy 308.389792 -297.618511)
			(xy 308.343776 -297.601059) (xy 308.301155 -297.576452) (xy 308.263034 -297.545327) (xy 308.230399 -297.50849)
			(xy 308.204096 -297.466894) (xy 308.184805 -297.421618) (xy 308.173028 -297.373834) (xy 308.169068 -297.32478)
			(xy 307.83022 -297.32478) (xy 307.829725 -297.349387) (xy 307.82183 -297.397964) (xy 307.806246 -297.444645)
			(xy 307.783375 -297.488222) (xy 307.75381 -297.527566) (xy 307.718317 -297.561658) (xy 307.677814 -297.589614)
			(xy 307.633352 -297.610712) (xy 307.586081 -297.624404) (xy 307.537226 -297.630336) (xy 307.488051 -297.628355)
			(xy 307.439832 -297.618511) (xy 307.393816 -297.601059) (xy 307.351195 -297.576452) (xy 307.313074 -297.545327)
			(xy 307.280439 -297.50849) (xy 307.254136 -297.466894) (xy 307.234845 -297.421618) (xy 307.223068 -297.373834)
			(xy 307.219108 -297.32478) (xy 306.88026 -297.32478) (xy 306.879765 -297.349387) (xy 306.87187 -297.397964)
			(xy 306.856286 -297.444645) (xy 306.833415 -297.488222) (xy 306.80385 -297.527566) (xy 306.768357 -297.561658)
			(xy 306.727854 -297.589614) (xy 306.683392 -297.610712) (xy 306.636121 -297.624404) (xy 306.587266 -297.630336)
			(xy 306.538091 -297.628355) (xy 306.489872 -297.618511) (xy 306.443856 -297.601059) (xy 306.401235 -297.576452)
			(xy 306.363114 -297.545327) (xy 306.330479 -297.50849) (xy 306.304176 -297.466894) (xy 306.284885 -297.421618)
			(xy 306.273108 -297.373834) (xy 306.269148 -297.32478) (xy 305.930046 -297.32478) (xy 305.929551 -297.349387)
			(xy 305.921656 -297.397964) (xy 305.906072 -297.444645) (xy 305.883201 -297.488222) (xy 305.853636 -297.527566)
			(xy 305.818143 -297.561658) (xy 305.77764 -297.589614) (xy 305.733178 -297.610712) (xy 305.685907 -297.624404)
			(xy 305.637052 -297.630336) (xy 305.587877 -297.628355) (xy 305.539658 -297.618511) (xy 305.493642 -297.601059)
			(xy 305.451021 -297.576452) (xy 305.4129 -297.545327) (xy 305.380265 -297.50849) (xy 305.353962 -297.466894)
			(xy 305.334671 -297.421618) (xy 305.322894 -297.373834) (xy 305.318934 -297.32478) (xy 304.980086 -297.32478)
			(xy 304.979591 -297.349387) (xy 304.971696 -297.397964) (xy 304.956112 -297.444645) (xy 304.933241 -297.488222)
			(xy 304.903676 -297.527566) (xy 304.868183 -297.561658) (xy 304.82768 -297.589614) (xy 304.783218 -297.610712)
			(xy 304.735947 -297.624404) (xy 304.687092 -297.630336) (xy 304.637917 -297.628355) (xy 304.589698 -297.618511)
			(xy 304.543682 -297.601059) (xy 304.501061 -297.576452) (xy 304.46294 -297.545327) (xy 304.430305 -297.50849)
			(xy 304.404002 -297.466894) (xy 304.384711 -297.421618) (xy 304.372934 -297.373834) (xy 304.368974 -297.32478)
			(xy 304.030126 -297.32478) (xy 304.029631 -297.349387) (xy 304.021736 -297.397964) (xy 304.006152 -297.444645)
			(xy 303.983281 -297.488222) (xy 303.953716 -297.527566) (xy 303.918223 -297.561658) (xy 303.87772 -297.589614)
			(xy 303.833258 -297.610712) (xy 303.785987 -297.624404) (xy 303.737132 -297.630336) (xy 303.687957 -297.628355)
			(xy 303.639738 -297.618511) (xy 303.593722 -297.601059) (xy 303.551101 -297.576452) (xy 303.51298 -297.545327)
			(xy 303.480345 -297.50849) (xy 303.454042 -297.466894) (xy 303.434751 -297.421618) (xy 303.422974 -297.373834)
			(xy 303.419014 -297.32478) (xy 303.080166 -297.32478) (xy 303.079671 -297.349387) (xy 303.071776 -297.397964)
			(xy 303.056192 -297.444645) (xy 303.033321 -297.488222) (xy 303.003756 -297.527566) (xy 302.968263 -297.561658)
			(xy 302.92776 -297.589614) (xy 302.883298 -297.610712) (xy 302.836027 -297.624404) (xy 302.787172 -297.630336)
			(xy 302.737997 -297.628355) (xy 302.689778 -297.618511) (xy 302.643762 -297.601059) (xy 302.601141 -297.576452)
			(xy 302.56302 -297.545327) (xy 302.530385 -297.50849) (xy 302.504082 -297.466894) (xy 302.484791 -297.421618)
			(xy 302.473014 -297.373834) (xy 302.469054 -297.32478) (xy 302.130206 -297.32478) (xy 302.129711 -297.349387)
			(xy 302.121816 -297.397964) (xy 302.106232 -297.444645) (xy 302.083361 -297.488222) (xy 302.053796 -297.527566)
			(xy 302.018303 -297.561658) (xy 301.9778 -297.589614) (xy 301.933338 -297.610712) (xy 301.886067 -297.624404)
			(xy 301.837212 -297.630336) (xy 301.788037 -297.628355) (xy 301.739818 -297.618511) (xy 301.693802 -297.601059)
			(xy 301.651181 -297.576452) (xy 301.61306 -297.545327) (xy 301.580425 -297.50849) (xy 301.554122 -297.466894)
			(xy 301.534831 -297.421618) (xy 301.523054 -297.373834) (xy 301.519094 -297.32478) (xy 298.330112 -297.32478)
			(xy 298.329617 -297.349387) (xy 298.321722 -297.397964) (xy 298.306138 -297.444645) (xy 298.283267 -297.488222)
			(xy 298.253702 -297.527566) (xy 298.218209 -297.561658) (xy 298.177706 -297.589614) (xy 298.133244 -297.610712)
			(xy 298.085973 -297.624404) (xy 298.037118 -297.630336) (xy 297.987943 -297.628355) (xy 297.939724 -297.618511)
			(xy 297.893708 -297.601059) (xy 297.851087 -297.576452) (xy 297.812966 -297.545327) (xy 297.780331 -297.50849)
			(xy 297.754028 -297.466894) (xy 297.734737 -297.421618) (xy 297.72296 -297.373834) (xy 297.719 -297.32478)
			(xy 297.380152 -297.32478) (xy 297.379657 -297.349387) (xy 297.371762 -297.397964) (xy 297.356178 -297.444645)
			(xy 297.333307 -297.488222) (xy 297.303742 -297.527566) (xy 297.268249 -297.561658) (xy 297.227746 -297.589614)
			(xy 297.183284 -297.610712) (xy 297.136013 -297.624404) (xy 297.087158 -297.630336) (xy 297.037983 -297.628355)
			(xy 296.989764 -297.618511) (xy 296.943748 -297.601059) (xy 296.901127 -297.576452) (xy 296.863006 -297.545327)
			(xy 296.830371 -297.50849) (xy 296.804068 -297.466894) (xy 296.784777 -297.421618) (xy 296.773 -297.373834)
			(xy 296.76904 -297.32478) (xy 296.430192 -297.32478) (xy 296.429697 -297.349387) (xy 296.421802 -297.397964)
			(xy 296.406218 -297.444645) (xy 296.383347 -297.488222) (xy 296.353782 -297.527566) (xy 296.318289 -297.561658)
			(xy 296.277786 -297.589614) (xy 296.233324 -297.610712) (xy 296.186053 -297.624404) (xy 296.137198 -297.630336)
			(xy 296.088023 -297.628355) (xy 296.039804 -297.618511) (xy 295.993788 -297.601059) (xy 295.951167 -297.576452)
			(xy 295.913046 -297.545327) (xy 295.880411 -297.50849) (xy 295.854108 -297.466894) (xy 295.834817 -297.421618)
			(xy 295.82304 -297.373834) (xy 295.81908 -297.32478) (xy 295.480232 -297.32478) (xy 295.479737 -297.349387)
			(xy 295.471842 -297.397964) (xy 295.456258 -297.444645) (xy 295.433387 -297.488222) (xy 295.403822 -297.527566)
			(xy 295.368329 -297.561658) (xy 295.327826 -297.589614) (xy 295.283364 -297.610712) (xy 295.236093 -297.624404)
			(xy 295.187238 -297.630336) (xy 295.138063 -297.628355) (xy 295.089844 -297.618511) (xy 295.043828 -297.601059)
			(xy 295.001207 -297.576452) (xy 294.963086 -297.545327) (xy 294.930451 -297.50849) (xy 294.904148 -297.466894)
			(xy 294.884857 -297.421618) (xy 294.87308 -297.373834) (xy 294.86912 -297.32478) (xy 294.530018 -297.32478)
			(xy 294.529523 -297.349387) (xy 294.521628 -297.397964) (xy 294.506044 -297.444645) (xy 294.483173 -297.488222)
			(xy 294.453608 -297.527566) (xy 294.418115 -297.561658) (xy 294.377612 -297.589614) (xy 294.33315 -297.610712)
			(xy 294.285879 -297.624404) (xy 294.237024 -297.630336) (xy 294.187849 -297.628355) (xy 294.13963 -297.618511)
			(xy 294.093614 -297.601059) (xy 294.050993 -297.576452) (xy 294.012872 -297.545327) (xy 293.980237 -297.50849)
			(xy 293.953934 -297.466894) (xy 293.934643 -297.421618) (xy 293.922866 -297.373834) (xy 293.918906 -297.32478)
			(xy 293.580058 -297.32478) (xy 293.579563 -297.349387) (xy 293.571668 -297.397964) (xy 293.556084 -297.444645)
			(xy 293.533213 -297.488222) (xy 293.503648 -297.527566) (xy 293.468155 -297.561658) (xy 293.427652 -297.589614)
			(xy 293.38319 -297.610712) (xy 293.335919 -297.624404) (xy 293.287064 -297.630336) (xy 293.237889 -297.628355)
			(xy 293.18967 -297.618511) (xy 293.143654 -297.601059) (xy 293.101033 -297.576452) (xy 293.062912 -297.545327)
			(xy 293.030277 -297.50849) (xy 293.003974 -297.466894) (xy 292.984683 -297.421618) (xy 292.972906 -297.373834)
			(xy 292.968946 -297.32478) (xy 292.630098 -297.32478) (xy 292.629603 -297.349387) (xy 292.621708 -297.397964)
			(xy 292.606124 -297.444645) (xy 292.583253 -297.488222) (xy 292.553688 -297.527566) (xy 292.518195 -297.561658)
			(xy 292.477692 -297.589614) (xy 292.43323 -297.610712) (xy 292.385959 -297.624404) (xy 292.337104 -297.630336)
			(xy 292.287929 -297.628355) (xy 292.23971 -297.618511) (xy 292.193694 -297.601059) (xy 292.151073 -297.576452)
			(xy 292.112952 -297.545327) (xy 292.080317 -297.50849) (xy 292.054014 -297.466894) (xy 292.034723 -297.421618)
			(xy 292.022946 -297.373834) (xy 292.018986 -297.32478) (xy 290.730178 -297.32478) (xy 290.729683 -297.349387)
			(xy 290.721788 -297.397964) (xy 290.706204 -297.444645) (xy 290.683333 -297.488222) (xy 290.653768 -297.527566)
			(xy 290.618275 -297.561658) (xy 290.577772 -297.589614) (xy 290.53331 -297.610712) (xy 290.486039 -297.624404)
			(xy 290.437184 -297.630336) (xy 290.388009 -297.628355) (xy 290.33979 -297.618511) (xy 290.293774 -297.601059)
			(xy 290.251153 -297.576452) (xy 290.213032 -297.545327) (xy 290.180397 -297.50849) (xy 290.154094 -297.466894)
			(xy 290.134803 -297.421618) (xy 290.123026 -297.373834) (xy 290.119066 -297.32478) (xy 289.780218 -297.32478)
			(xy 289.779723 -297.349387) (xy 289.771828 -297.397964) (xy 289.756244 -297.444645) (xy 289.733373 -297.488222)
			(xy 289.703808 -297.527566) (xy 289.668315 -297.561658) (xy 289.627812 -297.589614) (xy 289.58335 -297.610712)
			(xy 289.536079 -297.624404) (xy 289.487224 -297.630336) (xy 289.438049 -297.628355) (xy 289.38983 -297.618511)
			(xy 289.343814 -297.601059) (xy 289.301193 -297.576452) (xy 289.263072 -297.545327) (xy 289.230437 -297.50849)
			(xy 289.204134 -297.466894) (xy 289.184843 -297.421618) (xy 289.173066 -297.373834) (xy 289.169106 -297.32478)
			(xy 288.830004 -297.32478) (xy 288.829509 -297.349387) (xy 288.821614 -297.397964) (xy 288.80603 -297.444645)
			(xy 288.783159 -297.488222) (xy 288.753594 -297.527566) (xy 288.718101 -297.561658) (xy 288.677598 -297.589614)
			(xy 288.633136 -297.610712) (xy 288.585865 -297.624404) (xy 288.53701 -297.630336) (xy 288.487835 -297.628355)
			(xy 288.439616 -297.618511) (xy 288.3936 -297.601059) (xy 288.350979 -297.576452) (xy 288.312858 -297.545327)
			(xy 288.280223 -297.50849) (xy 288.25392 -297.466894) (xy 288.234629 -297.421618) (xy 288.222852 -297.373834)
			(xy 288.218892 -297.32478) (xy 287.880044 -297.32478) (xy 287.879549 -297.349387) (xy 287.871654 -297.397964)
			(xy 287.85607 -297.444645) (xy 287.833199 -297.488222) (xy 287.803634 -297.527566) (xy 287.768141 -297.561658)
			(xy 287.727638 -297.589614) (xy 287.683176 -297.610712) (xy 287.635905 -297.624404) (xy 287.58705 -297.630336)
			(xy 287.537875 -297.628355) (xy 287.489656 -297.618511) (xy 287.44364 -297.601059) (xy 287.401019 -297.576452)
			(xy 287.362898 -297.545327) (xy 287.330263 -297.50849) (xy 287.30396 -297.466894) (xy 287.284669 -297.421618)
			(xy 287.272892 -297.373834) (xy 287.268932 -297.32478) (xy 286.930084 -297.32478) (xy 286.929589 -297.349387)
			(xy 286.921694 -297.397964) (xy 286.90611 -297.444645) (xy 286.883239 -297.488222) (xy 286.853674 -297.527566)
			(xy 286.818181 -297.561658) (xy 286.777678 -297.589614) (xy 286.733216 -297.610712) (xy 286.685945 -297.624404)
			(xy 286.63709 -297.630336) (xy 286.587915 -297.628355) (xy 286.539696 -297.618511) (xy 286.49368 -297.601059)
			(xy 286.451059 -297.576452) (xy 286.412938 -297.545327) (xy 286.380303 -297.50849) (xy 286.354 -297.466894)
			(xy 286.334709 -297.421618) (xy 286.322932 -297.373834) (xy 286.318972 -297.32478) (xy 285.980124 -297.32478)
			(xy 285.979629 -297.349387) (xy 285.971734 -297.397964) (xy 285.95615 -297.444645) (xy 285.933279 -297.488222)
			(xy 285.903714 -297.527566) (xy 285.868221 -297.561658) (xy 285.827718 -297.589614) (xy 285.783256 -297.610712)
			(xy 285.735985 -297.624404) (xy 285.68713 -297.630336) (xy 285.637955 -297.628355) (xy 285.589736 -297.618511)
			(xy 285.54372 -297.601059) (xy 285.501099 -297.576452) (xy 285.462978 -297.545327) (xy 285.430343 -297.50849)
			(xy 285.40404 -297.466894) (xy 285.384749 -297.421618) (xy 285.372972 -297.373834) (xy 285.369012 -297.32478)
			(xy 285.030164 -297.32478) (xy 285.029669 -297.349387) (xy 285.021774 -297.397964) (xy 285.00619 -297.444645)
			(xy 284.983319 -297.488222) (xy 284.953754 -297.527566) (xy 284.918261 -297.561658) (xy 284.877758 -297.589614)
			(xy 284.833296 -297.610712) (xy 284.786025 -297.624404) (xy 284.73717 -297.630336) (xy 284.687995 -297.628355)
			(xy 284.639776 -297.618511) (xy 284.59376 -297.601059) (xy 284.551139 -297.576452) (xy 284.513018 -297.545327)
			(xy 284.480383 -297.50849) (xy 284.45408 -297.466894) (xy 284.434789 -297.421618) (xy 284.423012 -297.373834)
			(xy 284.419052 -297.32478) (xy 284.080204 -297.32478) (xy 284.079709 -297.349387) (xy 284.071814 -297.397964)
			(xy 284.05623 -297.444645) (xy 284.033359 -297.488222) (xy 284.003794 -297.527566) (xy 283.968301 -297.561658)
			(xy 283.927798 -297.589614) (xy 283.883336 -297.610712) (xy 283.836065 -297.624404) (xy 283.78721 -297.630336)
			(xy 283.738035 -297.628355) (xy 283.689816 -297.618511) (xy 283.6438 -297.601059) (xy 283.601179 -297.576452)
			(xy 283.563058 -297.545327) (xy 283.530423 -297.50849) (xy 283.50412 -297.466894) (xy 283.484829 -297.421618)
			(xy 283.473052 -297.373834) (xy 283.469092 -297.32478) (xy 283.130244 -297.32478) (xy 283.129749 -297.349387)
			(xy 283.121854 -297.397964) (xy 283.10627 -297.444645) (xy 283.083399 -297.488222) (xy 283.053834 -297.527566)
			(xy 283.018341 -297.561658) (xy 282.977838 -297.589614) (xy 282.933376 -297.610712) (xy 282.886105 -297.624404)
			(xy 282.83725 -297.630336) (xy 282.788075 -297.628355) (xy 282.739856 -297.618511) (xy 282.69384 -297.601059)
			(xy 282.651219 -297.576452) (xy 282.613098 -297.545327) (xy 282.580463 -297.50849) (xy 282.55416 -297.466894)
			(xy 282.534869 -297.421618) (xy 282.523092 -297.373834) (xy 282.519132 -297.32478) (xy 282.18003 -297.32478)
			(xy 282.179535 -297.349387) (xy 282.17164 -297.397964) (xy 282.156056 -297.444645) (xy 282.133185 -297.488222)
			(xy 282.10362 -297.527566) (xy 282.068127 -297.561658) (xy 282.027624 -297.589614) (xy 281.983162 -297.610712)
			(xy 281.935891 -297.624404) (xy 281.887036 -297.630336) (xy 281.837861 -297.628355) (xy 281.789642 -297.618511)
			(xy 281.743626 -297.601059) (xy 281.701005 -297.576452) (xy 281.662884 -297.545327) (xy 281.630249 -297.50849)
			(xy 281.603946 -297.466894) (xy 281.584655 -297.421618) (xy 281.572878 -297.373834) (xy 281.568918 -297.32478)
			(xy 281.23007 -297.32478) (xy 281.229575 -297.349387) (xy 281.22168 -297.397964) (xy 281.206096 -297.444645)
			(xy 281.183225 -297.488222) (xy 281.15366 -297.527566) (xy 281.118167 -297.561658) (xy 281.077664 -297.589614)
			(xy 281.033202 -297.610712) (xy 280.985931 -297.624404) (xy 280.937076 -297.630336) (xy 280.887901 -297.628355)
			(xy 280.839682 -297.618511) (xy 280.793666 -297.601059) (xy 280.751045 -297.576452) (xy 280.712924 -297.545327)
			(xy 280.680289 -297.50849) (xy 280.653986 -297.466894) (xy 280.634695 -297.421618) (xy 280.622918 -297.373834)
			(xy 280.618958 -297.32478) (xy 280.28011 -297.32478) (xy 280.279615 -297.349387) (xy 280.27172 -297.397964)
			(xy 280.256136 -297.444645) (xy 280.233265 -297.488222) (xy 280.2037 -297.527566) (xy 280.168207 -297.561658)
			(xy 280.127704 -297.589614) (xy 280.083242 -297.610712) (xy 280.035971 -297.624404) (xy 279.987116 -297.630336)
			(xy 279.937941 -297.628355) (xy 279.889722 -297.618511) (xy 279.843706 -297.601059) (xy 279.801085 -297.576452)
			(xy 279.762964 -297.545327) (xy 279.730329 -297.50849) (xy 279.704026 -297.466894) (xy 279.684735 -297.421618)
			(xy 279.672958 -297.373834) (xy 279.668998 -297.32478) (xy 279.41397 -297.32478) (xy 279.41397 -297.95851)
			(xy 316.956184 -297.95851) (xy 316.960255 -297.902888) (xy 316.972381 -297.848451) (xy 316.992304 -297.79636)
			(xy 317.0196 -297.747725) (xy 317.053686 -297.703582) (xy 317.093835 -297.664873) (xy 317.139193 -297.632422)
			(xy 317.188793 -297.606921) (xy 317.241577 -297.588914) (xy 317.29642 -297.578784) (xy 317.352154 -297.576747)
			(xy 317.407591 -297.582847) (xy 317.461548 -297.596953) (xy 317.512877 -297.618765) (xy 317.560483 -297.647819)
			(xy 317.603351 -297.683494) (xy 317.609209 -297.690032) (xy 318.499488 -297.690032) (xy 318.503559 -297.63441)
			(xy 318.515685 -297.579973) (xy 318.535608 -297.527882) (xy 318.562904 -297.479247) (xy 318.59699 -297.435104)
			(xy 318.637139 -297.396395) (xy 318.682497 -297.363944) (xy 318.732097 -297.338443) (xy 318.784881 -297.320436)
			(xy 318.839724 -297.310306) (xy 318.895458 -297.308269) (xy 318.950895 -297.314369) (xy 319.004852 -297.328475)
			(xy 319.056181 -297.350287) (xy 319.096376 -297.374818) (xy 324.815706 -297.374818) (xy 324.819777 -297.319196)
			(xy 324.831903 -297.264759) (xy 324.851826 -297.212668) (xy 324.879122 -297.164033) (xy 324.913208 -297.11989)
			(xy 324.953357 -297.081181) (xy 324.998715 -297.04873) (xy 325.048315 -297.023229) (xy 325.101099 -297.005222)
			(xy 325.155942 -296.995092) (xy 325.211676 -296.993055) (xy 325.267113 -296.999155) (xy 325.32107 -297.013261)
			(xy 325.372399 -297.035073) (xy 325.420005 -297.064127) (xy 325.462873 -297.099802) (xy 325.50009 -297.141339)
			(xy 325.530863 -297.187852) (xy 325.554535 -297.238349) (xy 325.570603 -297.291756) (xy 325.578723 -297.346932)
			(xy 325.579232 -297.374818) (xy 325.578723 -297.402704) (xy 325.570603 -297.45788) (xy 325.554535 -297.511287)
			(xy 325.530863 -297.561784) (xy 325.50009 -297.608297) (xy 325.462873 -297.649834) (xy 325.420005 -297.685509)
			(xy 325.372399 -297.714563) (xy 325.32107 -297.736375) (xy 325.267113 -297.750481) (xy 325.211676 -297.756581)
			(xy 325.155942 -297.754544) (xy 325.101099 -297.744414) (xy 325.048315 -297.726407) (xy 324.998715 -297.700906)
			(xy 324.953357 -297.668455) (xy 324.913208 -297.629746) (xy 324.879122 -297.585603) (xy 324.851826 -297.536968)
			(xy 324.831903 -297.484877) (xy 324.819777 -297.43044) (xy 324.815706 -297.374818) (xy 319.096376 -297.374818)
			(xy 319.103787 -297.379341) (xy 319.146655 -297.415016) (xy 319.183872 -297.456553) (xy 319.214645 -297.503066)
			(xy 319.238317 -297.553563) (xy 319.254385 -297.60697) (xy 319.262505 -297.662146) (xy 319.263014 -297.690032)
			(xy 319.262505 -297.717918) (xy 319.254385 -297.773094) (xy 319.238317 -297.826501) (xy 319.214645 -297.876998)
			(xy 319.183872 -297.923511) (xy 319.146655 -297.965048) (xy 319.103787 -298.000723) (xy 319.056181 -298.029777)
			(xy 319.004852 -298.051589) (xy 318.950895 -298.065695) (xy 318.895458 -298.071795) (xy 318.839724 -298.069758)
			(xy 318.784881 -298.059628) (xy 318.732097 -298.041621) (xy 318.682497 -298.01612) (xy 318.637139 -297.983669)
			(xy 318.59699 -297.94496) (xy 318.562904 -297.900817) (xy 318.535608 -297.852182) (xy 318.515685 -297.800091)
			(xy 318.503559 -297.745654) (xy 318.499488 -297.690032) (xy 317.609209 -297.690032) (xy 317.640568 -297.725031)
			(xy 317.671341 -297.771544) (xy 317.695013 -297.822041) (xy 317.711081 -297.875448) (xy 317.719201 -297.930624)
			(xy 317.71971 -297.95851) (xy 317.719201 -297.986396) (xy 317.711081 -298.041572) (xy 317.695013 -298.094979)
			(xy 317.671341 -298.145476) (xy 317.640568 -298.191989) (xy 317.603351 -298.233526) (xy 317.560483 -298.269201)
			(xy 317.512877 -298.298255) (xy 317.461548 -298.320067) (xy 317.407591 -298.334173) (xy 317.352154 -298.340273)
			(xy 317.29642 -298.338236) (xy 317.241577 -298.328106) (xy 317.188793 -298.310099) (xy 317.139193 -298.284598)
			(xy 317.093835 -298.252147) (xy 317.053686 -298.213438) (xy 317.0196 -298.169295) (xy 316.992304 -298.12066)
			(xy 316.972381 -298.068569) (xy 316.960255 -298.014132) (xy 316.956184 -297.95851) (xy 279.41397 -297.95851)
			(xy 279.41397 -298.27474) (xy 279.668998 -298.27474) (xy 279.672958 -298.225686) (xy 279.684735 -298.177902)
			(xy 279.704026 -298.132626) (xy 279.730329 -298.09103) (xy 279.762964 -298.054193) (xy 279.801085 -298.023068)
			(xy 279.843706 -297.998461) (xy 279.889722 -297.981009) (xy 279.937941 -297.971165) (xy 279.987116 -297.969184)
			(xy 280.035971 -297.975116) (xy 280.083242 -297.988808) (xy 280.127704 -298.009906) (xy 280.168207 -298.037862)
			(xy 280.2037 -298.071954) (xy 280.233265 -298.111298) (xy 280.256136 -298.154875) (xy 280.27172 -298.201556)
			(xy 280.279615 -298.250133) (xy 280.28011 -298.27474) (xy 280.618958 -298.27474) (xy 280.622918 -298.225686)
			(xy 280.634695 -298.177902) (xy 280.653986 -298.132626) (xy 280.680289 -298.09103) (xy 280.712924 -298.054193)
			(xy 280.751045 -298.023068) (xy 280.793666 -297.998461) (xy 280.839682 -297.981009) (xy 280.887901 -297.971165)
			(xy 280.937076 -297.969184) (xy 280.985931 -297.975116) (xy 281.033202 -297.988808) (xy 281.077664 -298.009906)
			(xy 281.118167 -298.037862) (xy 281.15366 -298.071954) (xy 281.183225 -298.111298) (xy 281.206096 -298.154875)
			(xy 281.22168 -298.201556) (xy 281.229575 -298.250133) (xy 281.23007 -298.27474) (xy 281.568918 -298.27474)
			(xy 281.572878 -298.225686) (xy 281.584655 -298.177902) (xy 281.603946 -298.132626) (xy 281.630249 -298.09103)
			(xy 281.662884 -298.054193) (xy 281.701005 -298.023068) (xy 281.743626 -297.998461) (xy 281.789642 -297.981009)
			(xy 281.837861 -297.971165) (xy 281.887036 -297.969184) (xy 281.935891 -297.975116) (xy 281.983162 -297.988808)
			(xy 282.027624 -298.009906) (xy 282.068127 -298.037862) (xy 282.10362 -298.071954) (xy 282.133185 -298.111298)
			(xy 282.156056 -298.154875) (xy 282.17164 -298.201556) (xy 282.179535 -298.250133) (xy 282.18003 -298.27474)
			(xy 282.519132 -298.27474) (xy 282.523092 -298.225686) (xy 282.534869 -298.177902) (xy 282.55416 -298.132626)
			(xy 282.580463 -298.09103) (xy 282.613098 -298.054193) (xy 282.651219 -298.023068) (xy 282.69384 -297.998461)
			(xy 282.739856 -297.981009) (xy 282.788075 -297.971165) (xy 282.83725 -297.969184) (xy 282.886105 -297.975116)
			(xy 282.933376 -297.988808) (xy 282.977838 -298.009906) (xy 283.018341 -298.037862) (xy 283.053834 -298.071954)
			(xy 283.083399 -298.111298) (xy 283.10627 -298.154875) (xy 283.121854 -298.201556) (xy 283.129749 -298.250133)
			(xy 283.130244 -298.27474) (xy 283.469092 -298.27474) (xy 283.473052 -298.225686) (xy 283.484829 -298.177902)
			(xy 283.50412 -298.132626) (xy 283.530423 -298.09103) (xy 283.563058 -298.054193) (xy 283.601179 -298.023068)
			(xy 283.6438 -297.998461) (xy 283.689816 -297.981009) (xy 283.738035 -297.971165) (xy 283.78721 -297.969184)
			(xy 283.836065 -297.975116) (xy 283.883336 -297.988808) (xy 283.927798 -298.009906) (xy 283.968301 -298.037862)
			(xy 284.003794 -298.071954) (xy 284.033359 -298.111298) (xy 284.05623 -298.154875) (xy 284.071814 -298.201556)
			(xy 284.079709 -298.250133) (xy 284.080204 -298.27474) (xy 284.419052 -298.27474) (xy 284.423012 -298.225686)
			(xy 284.434789 -298.177902) (xy 284.45408 -298.132626) (xy 284.480383 -298.09103) (xy 284.513018 -298.054193)
			(xy 284.551139 -298.023068) (xy 284.59376 -297.998461) (xy 284.639776 -297.981009) (xy 284.687995 -297.971165)
			(xy 284.73717 -297.969184) (xy 284.786025 -297.975116) (xy 284.833296 -297.988808) (xy 284.877758 -298.009906)
			(xy 284.918261 -298.037862) (xy 284.953754 -298.071954) (xy 284.983319 -298.111298) (xy 285.00619 -298.154875)
			(xy 285.021774 -298.201556) (xy 285.029669 -298.250133) (xy 285.030164 -298.27474) (xy 285.369012 -298.27474)
			(xy 285.372972 -298.225686) (xy 285.384749 -298.177902) (xy 285.40404 -298.132626) (xy 285.430343 -298.09103)
			(xy 285.462978 -298.054193) (xy 285.501099 -298.023068) (xy 285.54372 -297.998461) (xy 285.589736 -297.981009)
			(xy 285.637955 -297.971165) (xy 285.68713 -297.969184) (xy 285.735985 -297.975116) (xy 285.783256 -297.988808)
			(xy 285.827718 -298.009906) (xy 285.868221 -298.037862) (xy 285.903714 -298.071954) (xy 285.933279 -298.111298)
			(xy 285.95615 -298.154875) (xy 285.971734 -298.201556) (xy 285.979629 -298.250133) (xy 285.980124 -298.27474)
			(xy 286.318972 -298.27474) (xy 286.322932 -298.225686) (xy 286.334709 -298.177902) (xy 286.354 -298.132626)
			(xy 286.380303 -298.09103) (xy 286.412938 -298.054193) (xy 286.451059 -298.023068) (xy 286.49368 -297.998461)
			(xy 286.539696 -297.981009) (xy 286.587915 -297.971165) (xy 286.63709 -297.969184) (xy 286.685945 -297.975116)
			(xy 286.733216 -297.988808) (xy 286.777678 -298.009906) (xy 286.818181 -298.037862) (xy 286.853674 -298.071954)
			(xy 286.883239 -298.111298) (xy 286.90611 -298.154875) (xy 286.921694 -298.201556) (xy 286.929589 -298.250133)
			(xy 286.930084 -298.27474) (xy 287.268932 -298.27474) (xy 287.272892 -298.225686) (xy 287.284669 -298.177902)
			(xy 287.30396 -298.132626) (xy 287.330263 -298.09103) (xy 287.362898 -298.054193) (xy 287.401019 -298.023068)
			(xy 287.44364 -297.998461) (xy 287.489656 -297.981009) (xy 287.537875 -297.971165) (xy 287.58705 -297.969184)
			(xy 287.635905 -297.975116) (xy 287.683176 -297.988808) (xy 287.727638 -298.009906) (xy 287.768141 -298.037862)
			(xy 287.803634 -298.071954) (xy 287.833199 -298.111298) (xy 287.85607 -298.154875) (xy 287.871654 -298.201556)
			(xy 287.879549 -298.250133) (xy 287.880044 -298.27474) (xy 288.218892 -298.27474) (xy 288.222852 -298.225686)
			(xy 288.234629 -298.177902) (xy 288.25392 -298.132626) (xy 288.280223 -298.09103) (xy 288.312858 -298.054193)
			(xy 288.350979 -298.023068) (xy 288.3936 -297.998461) (xy 288.439616 -297.981009) (xy 288.487835 -297.971165)
			(xy 288.53701 -297.969184) (xy 288.585865 -297.975116) (xy 288.633136 -297.988808) (xy 288.677598 -298.009906)
			(xy 288.718101 -298.037862) (xy 288.753594 -298.071954) (xy 288.783159 -298.111298) (xy 288.80603 -298.154875)
			(xy 288.821614 -298.201556) (xy 288.829509 -298.250133) (xy 288.830004 -298.27474) (xy 289.169106 -298.27474)
			(xy 289.173066 -298.225686) (xy 289.184843 -298.177902) (xy 289.204134 -298.132626) (xy 289.230437 -298.09103)
			(xy 289.263072 -298.054193) (xy 289.301193 -298.023068) (xy 289.343814 -297.998461) (xy 289.38983 -297.981009)
			(xy 289.438049 -297.971165) (xy 289.487224 -297.969184) (xy 289.536079 -297.975116) (xy 289.58335 -297.988808)
			(xy 289.627812 -298.009906) (xy 289.668315 -298.037862) (xy 289.703808 -298.071954) (xy 289.733373 -298.111298)
			(xy 289.756244 -298.154875) (xy 289.771828 -298.201556) (xy 289.779723 -298.250133) (xy 289.780218 -298.27474)
			(xy 290.119066 -298.27474) (xy 290.123026 -298.225686) (xy 290.134803 -298.177902) (xy 290.154094 -298.132626)
			(xy 290.180397 -298.09103) (xy 290.213032 -298.054193) (xy 290.251153 -298.023068) (xy 290.293774 -297.998461)
			(xy 290.33979 -297.981009) (xy 290.388009 -297.971165) (xy 290.437184 -297.969184) (xy 290.486039 -297.975116)
			(xy 290.53331 -297.988808) (xy 290.577772 -298.009906) (xy 290.618275 -298.037862) (xy 290.653768 -298.071954)
			(xy 290.683333 -298.111298) (xy 290.706204 -298.154875) (xy 290.721788 -298.201556) (xy 290.729683 -298.250133)
			(xy 290.730178 -298.27474) (xy 292.018986 -298.27474) (xy 292.022946 -298.225686) (xy 292.034723 -298.177902)
			(xy 292.054014 -298.132626) (xy 292.080317 -298.09103) (xy 292.112952 -298.054193) (xy 292.151073 -298.023068)
			(xy 292.193694 -297.998461) (xy 292.23971 -297.981009) (xy 292.287929 -297.971165) (xy 292.337104 -297.969184)
			(xy 292.385959 -297.975116) (xy 292.43323 -297.988808) (xy 292.477692 -298.009906) (xy 292.518195 -298.037862)
			(xy 292.553688 -298.071954) (xy 292.583253 -298.111298) (xy 292.606124 -298.154875) (xy 292.621708 -298.201556)
			(xy 292.629603 -298.250133) (xy 292.630098 -298.27474) (xy 292.968946 -298.27474) (xy 292.972906 -298.225686)
			(xy 292.984683 -298.177902) (xy 293.003974 -298.132626) (xy 293.030277 -298.09103) (xy 293.062912 -298.054193)
			(xy 293.101033 -298.023068) (xy 293.143654 -297.998461) (xy 293.18967 -297.981009) (xy 293.237889 -297.971165)
			(xy 293.287064 -297.969184) (xy 293.335919 -297.975116) (xy 293.38319 -297.988808) (xy 293.427652 -298.009906)
			(xy 293.468155 -298.037862) (xy 293.503648 -298.071954) (xy 293.533213 -298.111298) (xy 293.556084 -298.154875)
			(xy 293.571668 -298.201556) (xy 293.579563 -298.250133) (xy 293.580058 -298.27474) (xy 293.918906 -298.27474)
			(xy 293.922866 -298.225686) (xy 293.934643 -298.177902) (xy 293.953934 -298.132626) (xy 293.980237 -298.09103)
			(xy 294.012872 -298.054193) (xy 294.050993 -298.023068) (xy 294.093614 -297.998461) (xy 294.13963 -297.981009)
			(xy 294.187849 -297.971165) (xy 294.237024 -297.969184) (xy 294.285879 -297.975116) (xy 294.33315 -297.988808)
			(xy 294.377612 -298.009906) (xy 294.418115 -298.037862) (xy 294.453608 -298.071954) (xy 294.483173 -298.111298)
			(xy 294.506044 -298.154875) (xy 294.521628 -298.201556) (xy 294.529523 -298.250133) (xy 294.530018 -298.27474)
			(xy 294.86912 -298.27474) (xy 294.87308 -298.225686) (xy 294.884857 -298.177902) (xy 294.904148 -298.132626)
			(xy 294.930451 -298.09103) (xy 294.963086 -298.054193) (xy 295.001207 -298.023068) (xy 295.043828 -297.998461)
			(xy 295.089844 -297.981009) (xy 295.138063 -297.971165) (xy 295.187238 -297.969184) (xy 295.236093 -297.975116)
			(xy 295.283364 -297.988808) (xy 295.327826 -298.009906) (xy 295.368329 -298.037862) (xy 295.403822 -298.071954)
			(xy 295.433387 -298.111298) (xy 295.456258 -298.154875) (xy 295.471842 -298.201556) (xy 295.479737 -298.250133)
			(xy 295.480232 -298.27474) (xy 295.81908 -298.27474) (xy 295.82304 -298.225686) (xy 295.834817 -298.177902)
			(xy 295.854108 -298.132626) (xy 295.880411 -298.09103) (xy 295.913046 -298.054193) (xy 295.951167 -298.023068)
			(xy 295.993788 -297.998461) (xy 296.039804 -297.981009) (xy 296.088023 -297.971165) (xy 296.137198 -297.969184)
			(xy 296.186053 -297.975116) (xy 296.233324 -297.988808) (xy 296.277786 -298.009906) (xy 296.318289 -298.037862)
			(xy 296.353782 -298.071954) (xy 296.383347 -298.111298) (xy 296.406218 -298.154875) (xy 296.421802 -298.201556)
			(xy 296.429697 -298.250133) (xy 296.430192 -298.27474) (xy 296.76904 -298.27474) (xy 296.773 -298.225686)
			(xy 296.784777 -298.177902) (xy 296.804068 -298.132626) (xy 296.830371 -298.09103) (xy 296.863006 -298.054193)
			(xy 296.901127 -298.023068) (xy 296.943748 -297.998461) (xy 296.989764 -297.981009) (xy 297.037983 -297.971165)
			(xy 297.087158 -297.969184) (xy 297.136013 -297.975116) (xy 297.183284 -297.988808) (xy 297.227746 -298.009906)
			(xy 297.268249 -298.037862) (xy 297.303742 -298.071954) (xy 297.333307 -298.111298) (xy 297.356178 -298.154875)
			(xy 297.371762 -298.201556) (xy 297.379657 -298.250133) (xy 297.380152 -298.27474) (xy 297.719 -298.27474)
			(xy 297.72296 -298.225686) (xy 297.734737 -298.177902) (xy 297.754028 -298.132626) (xy 297.780331 -298.09103)
			(xy 297.812966 -298.054193) (xy 297.851087 -298.023068) (xy 297.893708 -297.998461) (xy 297.939724 -297.981009)
			(xy 297.987943 -297.971165) (xy 298.037118 -297.969184) (xy 298.085973 -297.975116) (xy 298.133244 -297.988808)
			(xy 298.177706 -298.009906) (xy 298.218209 -298.037862) (xy 298.253702 -298.071954) (xy 298.283267 -298.111298)
			(xy 298.306138 -298.154875) (xy 298.321722 -298.201556) (xy 298.329617 -298.250133) (xy 298.330112 -298.27474)
			(xy 298.66896 -298.27474) (xy 298.67292 -298.225686) (xy 298.684697 -298.177902) (xy 298.703988 -298.132626)
			(xy 298.730291 -298.09103) (xy 298.762926 -298.054193) (xy 298.801047 -298.023068) (xy 298.843668 -297.998461)
			(xy 298.889684 -297.981009) (xy 298.937903 -297.971165) (xy 298.987078 -297.969184) (xy 299.035933 -297.975116)
			(xy 299.083204 -297.988808) (xy 299.127666 -298.009906) (xy 299.168169 -298.037862) (xy 299.203662 -298.071954)
			(xy 299.233227 -298.111298) (xy 299.256098 -298.154875) (xy 299.271682 -298.201556) (xy 299.279577 -298.250133)
			(xy 299.280072 -298.27474) (xy 299.61892 -298.27474) (xy 299.62288 -298.225686) (xy 299.634657 -298.177902)
			(xy 299.653948 -298.132626) (xy 299.680251 -298.09103) (xy 299.712886 -298.054193) (xy 299.751007 -298.023068)
			(xy 299.793628 -297.998461) (xy 299.839644 -297.981009) (xy 299.887863 -297.971165) (xy 299.937038 -297.969184)
			(xy 299.985893 -297.975116) (xy 300.033164 -297.988808) (xy 300.077626 -298.009906) (xy 300.118129 -298.037862)
			(xy 300.153622 -298.071954) (xy 300.183187 -298.111298) (xy 300.206058 -298.154875) (xy 300.221642 -298.201556)
			(xy 300.229537 -298.250133) (xy 300.230032 -298.27474) (xy 300.56888 -298.27474) (xy 300.57284 -298.225686)
			(xy 300.584617 -298.177902) (xy 300.603908 -298.132626) (xy 300.630211 -298.09103) (xy 300.662846 -298.054193)
			(xy 300.700967 -298.023068) (xy 300.743588 -297.998461) (xy 300.789604 -297.981009) (xy 300.837823 -297.971165)
			(xy 300.886998 -297.969184) (xy 300.935853 -297.975116) (xy 300.983124 -297.988808) (xy 301.027586 -298.009906)
			(xy 301.068089 -298.037862) (xy 301.103582 -298.071954) (xy 301.133147 -298.111298) (xy 301.156018 -298.154875)
			(xy 301.171602 -298.201556) (xy 301.179497 -298.250133) (xy 301.179992 -298.27474) (xy 301.519094 -298.27474)
			(xy 301.523054 -298.225686) (xy 301.534831 -298.177902) (xy 301.554122 -298.132626) (xy 301.580425 -298.09103)
			(xy 301.61306 -298.054193) (xy 301.651181 -298.023068) (xy 301.693802 -297.998461) (xy 301.739818 -297.981009)
			(xy 301.788037 -297.971165) (xy 301.837212 -297.969184) (xy 301.886067 -297.975116) (xy 301.933338 -297.988808)
			(xy 301.9778 -298.009906) (xy 302.018303 -298.037862) (xy 302.053796 -298.071954) (xy 302.083361 -298.111298)
			(xy 302.106232 -298.154875) (xy 302.121816 -298.201556) (xy 302.129711 -298.250133) (xy 302.130206 -298.27474)
			(xy 302.469054 -298.27474) (xy 302.473014 -298.225686) (xy 302.484791 -298.177902) (xy 302.504082 -298.132626)
			(xy 302.530385 -298.09103) (xy 302.56302 -298.054193) (xy 302.601141 -298.023068) (xy 302.643762 -297.998461)
			(xy 302.689778 -297.981009) (xy 302.737997 -297.971165) (xy 302.787172 -297.969184) (xy 302.836027 -297.975116)
			(xy 302.883298 -297.988808) (xy 302.92776 -298.009906) (xy 302.968263 -298.037862) (xy 303.003756 -298.071954)
			(xy 303.033321 -298.111298) (xy 303.056192 -298.154875) (xy 303.071776 -298.201556) (xy 303.079671 -298.250133)
			(xy 303.080166 -298.27474) (xy 303.419014 -298.27474) (xy 303.422974 -298.225686) (xy 303.434751 -298.177902)
			(xy 303.454042 -298.132626) (xy 303.480345 -298.09103) (xy 303.51298 -298.054193) (xy 303.551101 -298.023068)
			(xy 303.593722 -297.998461) (xy 303.639738 -297.981009) (xy 303.687957 -297.971165) (xy 303.737132 -297.969184)
			(xy 303.785987 -297.975116) (xy 303.833258 -297.988808) (xy 303.87772 -298.009906) (xy 303.918223 -298.037862)
			(xy 303.953716 -298.071954) (xy 303.983281 -298.111298) (xy 304.006152 -298.154875) (xy 304.021736 -298.201556)
			(xy 304.029631 -298.250133) (xy 304.030126 -298.27474) (xy 304.368974 -298.27474) (xy 304.372934 -298.225686)
			(xy 304.384711 -298.177902) (xy 304.404002 -298.132626) (xy 304.430305 -298.09103) (xy 304.46294 -298.054193)
			(xy 304.501061 -298.023068) (xy 304.543682 -297.998461) (xy 304.589698 -297.981009) (xy 304.637917 -297.971165)
			(xy 304.687092 -297.969184) (xy 304.735947 -297.975116) (xy 304.783218 -297.988808) (xy 304.82768 -298.009906)
			(xy 304.868183 -298.037862) (xy 304.903676 -298.071954) (xy 304.933241 -298.111298) (xy 304.956112 -298.154875)
			(xy 304.971696 -298.201556) (xy 304.979591 -298.250133) (xy 304.980086 -298.27474) (xy 305.318934 -298.27474)
			(xy 305.322894 -298.225686) (xy 305.334671 -298.177902) (xy 305.353962 -298.132626) (xy 305.380265 -298.09103)
			(xy 305.4129 -298.054193) (xy 305.451021 -298.023068) (xy 305.493642 -297.998461) (xy 305.539658 -297.981009)
			(xy 305.587877 -297.971165) (xy 305.637052 -297.969184) (xy 305.685907 -297.975116) (xy 305.733178 -297.988808)
			(xy 305.77764 -298.009906) (xy 305.818143 -298.037862) (xy 305.853636 -298.071954) (xy 305.883201 -298.111298)
			(xy 305.906072 -298.154875) (xy 305.921656 -298.201556) (xy 305.929551 -298.250133) (xy 305.930046 -298.27474)
			(xy 306.268894 -298.27474) (xy 306.272854 -298.225686) (xy 306.284631 -298.177902) (xy 306.303922 -298.132626)
			(xy 306.330225 -298.09103) (xy 306.36286 -298.054193) (xy 306.400981 -298.023068) (xy 306.443602 -297.998461)
			(xy 306.489618 -297.981009) (xy 306.537837 -297.971165) (xy 306.587012 -297.969184) (xy 306.635867 -297.975116)
			(xy 306.683138 -297.988808) (xy 306.7276 -298.009906) (xy 306.768103 -298.037862) (xy 306.803596 -298.071954)
			(xy 306.833161 -298.111298) (xy 306.856032 -298.154875) (xy 306.871616 -298.201556) (xy 306.879511 -298.250133)
			(xy 306.880006 -298.27474) (xy 307.219108 -298.27474) (xy 307.223068 -298.225686) (xy 307.234845 -298.177902)
			(xy 307.254136 -298.132626) (xy 307.280439 -298.09103) (xy 307.313074 -298.054193) (xy 307.351195 -298.023068)
			(xy 307.393816 -297.998461) (xy 307.439832 -297.981009) (xy 307.488051 -297.971165) (xy 307.537226 -297.969184)
			(xy 307.586081 -297.975116) (xy 307.633352 -297.988808) (xy 307.677814 -298.009906) (xy 307.718317 -298.037862)
			(xy 307.75381 -298.071954) (xy 307.783375 -298.111298) (xy 307.806246 -298.154875) (xy 307.82183 -298.201556)
			(xy 307.829725 -298.250133) (xy 307.83022 -298.27474) (xy 308.169068 -298.27474) (xy 308.173028 -298.225686)
			(xy 308.184805 -298.177902) (xy 308.204096 -298.132626) (xy 308.230399 -298.09103) (xy 308.263034 -298.054193)
			(xy 308.301155 -298.023068) (xy 308.343776 -297.998461) (xy 308.389792 -297.981009) (xy 308.438011 -297.971165)
			(xy 308.487186 -297.969184) (xy 308.536041 -297.975116) (xy 308.583312 -297.988808) (xy 308.627774 -298.009906)
			(xy 308.668277 -298.037862) (xy 308.70377 -298.071954) (xy 308.733335 -298.111298) (xy 308.756206 -298.154875)
			(xy 308.77179 -298.201556) (xy 308.779685 -298.250133) (xy 308.78018 -298.27474) (xy 309.119028 -298.27474)
			(xy 309.122988 -298.225686) (xy 309.134765 -298.177902) (xy 309.154056 -298.132626) (xy 309.180359 -298.09103)
			(xy 309.212994 -298.054193) (xy 309.251115 -298.023068) (xy 309.293736 -297.998461) (xy 309.339752 -297.981009)
			(xy 309.387971 -297.971165) (xy 309.437146 -297.969184) (xy 309.486001 -297.975116) (xy 309.533272 -297.988808)
			(xy 309.577734 -298.009906) (xy 309.618237 -298.037862) (xy 309.65373 -298.071954) (xy 309.683295 -298.111298)
			(xy 309.706166 -298.154875) (xy 309.72175 -298.201556) (xy 309.729645 -298.250133) (xy 309.73014 -298.27474)
			(xy 310.068988 -298.27474) (xy 310.072948 -298.225686) (xy 310.084725 -298.177902) (xy 310.104016 -298.132626)
			(xy 310.130319 -298.09103) (xy 310.162954 -298.054193) (xy 310.201075 -298.023068) (xy 310.243696 -297.998461)
			(xy 310.289712 -297.981009) (xy 310.337931 -297.971165) (xy 310.387106 -297.969184) (xy 310.435961 -297.975116)
			(xy 310.483232 -297.988808) (xy 310.527694 -298.009906) (xy 310.568197 -298.037862) (xy 310.60369 -298.071954)
			(xy 310.633255 -298.111298) (xy 310.656126 -298.154875) (xy 310.67171 -298.201556) (xy 310.679605 -298.250133)
			(xy 310.6801 -298.27474) (xy 311.018948 -298.27474) (xy 311.022908 -298.225686) (xy 311.034685 -298.177902)
			(xy 311.053976 -298.132626) (xy 311.080279 -298.09103) (xy 311.112914 -298.054193) (xy 311.151035 -298.023068)
			(xy 311.193656 -297.998461) (xy 311.239672 -297.981009) (xy 311.287891 -297.971165) (xy 311.337066 -297.969184)
			(xy 311.385921 -297.975116) (xy 311.433192 -297.988808) (xy 311.477654 -298.009906) (xy 311.518157 -298.037862)
			(xy 311.55365 -298.071954) (xy 311.583215 -298.111298) (xy 311.606086 -298.154875) (xy 311.62167 -298.201556)
			(xy 311.629565 -298.250133) (xy 311.63006 -298.27474) (xy 311.968908 -298.27474) (xy 311.972868 -298.225686)
			(xy 311.984645 -298.177902) (xy 312.003936 -298.132626) (xy 312.030239 -298.09103) (xy 312.062874 -298.054193)
			(xy 312.100995 -298.023068) (xy 312.143616 -297.998461) (xy 312.189632 -297.981009) (xy 312.237851 -297.971165)
			(xy 312.287026 -297.969184) (xy 312.335881 -297.975116) (xy 312.383152 -297.988808) (xy 312.427614 -298.009906)
			(xy 312.468117 -298.037862) (xy 312.50361 -298.071954) (xy 312.533175 -298.111298) (xy 312.556046 -298.154875)
			(xy 312.57163 -298.201556) (xy 312.579525 -298.250133) (xy 312.58002 -298.27474) (xy 312.919122 -298.27474)
			(xy 312.923082 -298.225686) (xy 312.934859 -298.177902) (xy 312.95415 -298.132626) (xy 312.980453 -298.09103)
			(xy 313.013088 -298.054193) (xy 313.051209 -298.023068) (xy 313.09383 -297.998461) (xy 313.139846 -297.981009)
			(xy 313.188065 -297.971165) (xy 313.23724 -297.969184) (xy 313.286095 -297.975116) (xy 313.333366 -297.988808)
			(xy 313.377828 -298.009906) (xy 313.418331 -298.037862) (xy 313.453824 -298.071954) (xy 313.483389 -298.111298)
			(xy 313.50626 -298.154875) (xy 313.521844 -298.201556) (xy 313.529739 -298.250133) (xy 313.530234 -298.27474)
			(xy 313.869082 -298.27474) (xy 313.873042 -298.225686) (xy 313.884819 -298.177902) (xy 313.90411 -298.132626)
			(xy 313.930413 -298.09103) (xy 313.963048 -298.054193) (xy 314.001169 -298.023068) (xy 314.04379 -297.998461)
			(xy 314.089806 -297.981009) (xy 314.138025 -297.971165) (xy 314.1872 -297.969184) (xy 314.236055 -297.975116)
			(xy 314.283326 -297.988808) (xy 314.327788 -298.009906) (xy 314.368291 -298.037862) (xy 314.403784 -298.071954)
			(xy 314.433349 -298.111298) (xy 314.45622 -298.154875) (xy 314.471804 -298.201556) (xy 314.479699 -298.250133)
			(xy 314.480194 -298.27474) (xy 314.819042 -298.27474) (xy 314.823002 -298.225686) (xy 314.834779 -298.177902)
			(xy 314.85407 -298.132626) (xy 314.880373 -298.09103) (xy 314.913008 -298.054193) (xy 314.951129 -298.023068)
			(xy 314.99375 -297.998461) (xy 315.039766 -297.981009) (xy 315.087985 -297.971165) (xy 315.13716 -297.969184)
			(xy 315.186015 -297.975116) (xy 315.233286 -297.988808) (xy 315.277748 -298.009906) (xy 315.318251 -298.037862)
			(xy 315.353744 -298.071954) (xy 315.383309 -298.111298) (xy 315.40618 -298.154875) (xy 315.421764 -298.201556)
			(xy 315.429659 -298.250133) (xy 315.430154 -298.27474) (xy 315.429659 -298.299347) (xy 315.421764 -298.347924)
			(xy 315.40618 -298.394605) (xy 315.383309 -298.438182) (xy 315.353744 -298.477526) (xy 315.318251 -298.511618)
			(xy 315.277748 -298.539574) (xy 315.233286 -298.560672) (xy 315.186015 -298.574364) (xy 315.13716 -298.580296)
			(xy 315.087985 -298.578315) (xy 315.039766 -298.568471) (xy 314.99375 -298.551019) (xy 314.951129 -298.526412)
			(xy 314.913008 -298.495287) (xy 314.880373 -298.45845) (xy 314.85407 -298.416854) (xy 314.834779 -298.371578)
			(xy 314.823002 -298.323794) (xy 314.819042 -298.27474) (xy 314.480194 -298.27474) (xy 314.479699 -298.299347)
			(xy 314.471804 -298.347924) (xy 314.45622 -298.394605) (xy 314.433349 -298.438182) (xy 314.403784 -298.477526)
			(xy 314.368291 -298.511618) (xy 314.327788 -298.539574) (xy 314.283326 -298.560672) (xy 314.236055 -298.574364)
			(xy 314.1872 -298.580296) (xy 314.138025 -298.578315) (xy 314.089806 -298.568471) (xy 314.04379 -298.551019)
			(xy 314.001169 -298.526412) (xy 313.963048 -298.495287) (xy 313.930413 -298.45845) (xy 313.90411 -298.416854)
			(xy 313.884819 -298.371578) (xy 313.873042 -298.323794) (xy 313.869082 -298.27474) (xy 313.530234 -298.27474)
			(xy 313.529739 -298.299347) (xy 313.521844 -298.347924) (xy 313.50626 -298.394605) (xy 313.483389 -298.438182)
			(xy 313.453824 -298.477526) (xy 313.418331 -298.511618) (xy 313.377828 -298.539574) (xy 313.333366 -298.560672)
			(xy 313.286095 -298.574364) (xy 313.23724 -298.580296) (xy 313.188065 -298.578315) (xy 313.139846 -298.568471)
			(xy 313.09383 -298.551019) (xy 313.051209 -298.526412) (xy 313.013088 -298.495287) (xy 312.980453 -298.45845)
			(xy 312.95415 -298.416854) (xy 312.934859 -298.371578) (xy 312.923082 -298.323794) (xy 312.919122 -298.27474)
			(xy 312.58002 -298.27474) (xy 312.579525 -298.299347) (xy 312.57163 -298.347924) (xy 312.556046 -298.394605)
			(xy 312.533175 -298.438182) (xy 312.50361 -298.477526) (xy 312.468117 -298.511618) (xy 312.427614 -298.539574)
			(xy 312.383152 -298.560672) (xy 312.335881 -298.574364) (xy 312.287026 -298.580296) (xy 312.237851 -298.578315)
			(xy 312.189632 -298.568471) (xy 312.143616 -298.551019) (xy 312.100995 -298.526412) (xy 312.062874 -298.495287)
			(xy 312.030239 -298.45845) (xy 312.003936 -298.416854) (xy 311.984645 -298.371578) (xy 311.972868 -298.323794)
			(xy 311.968908 -298.27474) (xy 311.63006 -298.27474) (xy 311.629565 -298.299347) (xy 311.62167 -298.347924)
			(xy 311.606086 -298.394605) (xy 311.583215 -298.438182) (xy 311.55365 -298.477526) (xy 311.518157 -298.511618)
			(xy 311.477654 -298.539574) (xy 311.433192 -298.560672) (xy 311.385921 -298.574364) (xy 311.337066 -298.580296)
			(xy 311.287891 -298.578315) (xy 311.239672 -298.568471) (xy 311.193656 -298.551019) (xy 311.151035 -298.526412)
			(xy 311.112914 -298.495287) (xy 311.080279 -298.45845) (xy 311.053976 -298.416854) (xy 311.034685 -298.371578)
			(xy 311.022908 -298.323794) (xy 311.018948 -298.27474) (xy 310.6801 -298.27474) (xy 310.679605 -298.299347)
			(xy 310.67171 -298.347924) (xy 310.656126 -298.394605) (xy 310.633255 -298.438182) (xy 310.60369 -298.477526)
			(xy 310.568197 -298.511618) (xy 310.527694 -298.539574) (xy 310.483232 -298.560672) (xy 310.435961 -298.574364)
			(xy 310.387106 -298.580296) (xy 310.337931 -298.578315) (xy 310.289712 -298.568471) (xy 310.243696 -298.551019)
			(xy 310.201075 -298.526412) (xy 310.162954 -298.495287) (xy 310.130319 -298.45845) (xy 310.104016 -298.416854)
			(xy 310.084725 -298.371578) (xy 310.072948 -298.323794) (xy 310.068988 -298.27474) (xy 309.73014 -298.27474)
			(xy 309.729645 -298.299347) (xy 309.72175 -298.347924) (xy 309.706166 -298.394605) (xy 309.683295 -298.438182)
			(xy 309.65373 -298.477526) (xy 309.618237 -298.511618) (xy 309.577734 -298.539574) (xy 309.533272 -298.560672)
			(xy 309.486001 -298.574364) (xy 309.437146 -298.580296) (xy 309.387971 -298.578315) (xy 309.339752 -298.568471)
			(xy 309.293736 -298.551019) (xy 309.251115 -298.526412) (xy 309.212994 -298.495287) (xy 309.180359 -298.45845)
			(xy 309.154056 -298.416854) (xy 309.134765 -298.371578) (xy 309.122988 -298.323794) (xy 309.119028 -298.27474)
			(xy 308.78018 -298.27474) (xy 308.779685 -298.299347) (xy 308.77179 -298.347924) (xy 308.756206 -298.394605)
			(xy 308.733335 -298.438182) (xy 308.70377 -298.477526) (xy 308.668277 -298.511618) (xy 308.627774 -298.539574)
			(xy 308.583312 -298.560672) (xy 308.536041 -298.574364) (xy 308.487186 -298.580296) (xy 308.438011 -298.578315)
			(xy 308.389792 -298.568471) (xy 308.343776 -298.551019) (xy 308.301155 -298.526412) (xy 308.263034 -298.495287)
			(xy 308.230399 -298.45845) (xy 308.204096 -298.416854) (xy 308.184805 -298.371578) (xy 308.173028 -298.323794)
			(xy 308.169068 -298.27474) (xy 307.83022 -298.27474) (xy 307.829725 -298.299347) (xy 307.82183 -298.347924)
			(xy 307.806246 -298.394605) (xy 307.783375 -298.438182) (xy 307.75381 -298.477526) (xy 307.718317 -298.511618)
			(xy 307.677814 -298.539574) (xy 307.633352 -298.560672) (xy 307.586081 -298.574364) (xy 307.537226 -298.580296)
			(xy 307.488051 -298.578315) (xy 307.439832 -298.568471) (xy 307.393816 -298.551019) (xy 307.351195 -298.526412)
			(xy 307.313074 -298.495287) (xy 307.280439 -298.45845) (xy 307.254136 -298.416854) (xy 307.234845 -298.371578)
			(xy 307.223068 -298.323794) (xy 307.219108 -298.27474) (xy 306.880006 -298.27474) (xy 306.879511 -298.299347)
			(xy 306.871616 -298.347924) (xy 306.856032 -298.394605) (xy 306.833161 -298.438182) (xy 306.803596 -298.477526)
			(xy 306.768103 -298.511618) (xy 306.7276 -298.539574) (xy 306.683138 -298.560672) (xy 306.635867 -298.574364)
			(xy 306.587012 -298.580296) (xy 306.537837 -298.578315) (xy 306.489618 -298.568471) (xy 306.443602 -298.551019)
			(xy 306.400981 -298.526412) (xy 306.36286 -298.495287) (xy 306.330225 -298.45845) (xy 306.303922 -298.416854)
			(xy 306.284631 -298.371578) (xy 306.272854 -298.323794) (xy 306.268894 -298.27474) (xy 305.930046 -298.27474)
			(xy 305.929551 -298.299347) (xy 305.921656 -298.347924) (xy 305.906072 -298.394605) (xy 305.883201 -298.438182)
			(xy 305.853636 -298.477526) (xy 305.818143 -298.511618) (xy 305.77764 -298.539574) (xy 305.733178 -298.560672)
			(xy 305.685907 -298.574364) (xy 305.637052 -298.580296) (xy 305.587877 -298.578315) (xy 305.539658 -298.568471)
			(xy 305.493642 -298.551019) (xy 305.451021 -298.526412) (xy 305.4129 -298.495287) (xy 305.380265 -298.45845)
			(xy 305.353962 -298.416854) (xy 305.334671 -298.371578) (xy 305.322894 -298.323794) (xy 305.318934 -298.27474)
			(xy 304.980086 -298.27474) (xy 304.979591 -298.299347) (xy 304.971696 -298.347924) (xy 304.956112 -298.394605)
			(xy 304.933241 -298.438182) (xy 304.903676 -298.477526) (xy 304.868183 -298.511618) (xy 304.82768 -298.539574)
			(xy 304.783218 -298.560672) (xy 304.735947 -298.574364) (xy 304.687092 -298.580296) (xy 304.637917 -298.578315)
			(xy 304.589698 -298.568471) (xy 304.543682 -298.551019) (xy 304.501061 -298.526412) (xy 304.46294 -298.495287)
			(xy 304.430305 -298.45845) (xy 304.404002 -298.416854) (xy 304.384711 -298.371578) (xy 304.372934 -298.323794)
			(xy 304.368974 -298.27474) (xy 304.030126 -298.27474) (xy 304.029631 -298.299347) (xy 304.021736 -298.347924)
			(xy 304.006152 -298.394605) (xy 303.983281 -298.438182) (xy 303.953716 -298.477526) (xy 303.918223 -298.511618)
			(xy 303.87772 -298.539574) (xy 303.833258 -298.560672) (xy 303.785987 -298.574364) (xy 303.737132 -298.580296)
			(xy 303.687957 -298.578315) (xy 303.639738 -298.568471) (xy 303.593722 -298.551019) (xy 303.551101 -298.526412)
			(xy 303.51298 -298.495287) (xy 303.480345 -298.45845) (xy 303.454042 -298.416854) (xy 303.434751 -298.371578)
			(xy 303.422974 -298.323794) (xy 303.419014 -298.27474) (xy 303.080166 -298.27474) (xy 303.079671 -298.299347)
			(xy 303.071776 -298.347924) (xy 303.056192 -298.394605) (xy 303.033321 -298.438182) (xy 303.003756 -298.477526)
			(xy 302.968263 -298.511618) (xy 302.92776 -298.539574) (xy 302.883298 -298.560672) (xy 302.836027 -298.574364)
			(xy 302.787172 -298.580296) (xy 302.737997 -298.578315) (xy 302.689778 -298.568471) (xy 302.643762 -298.551019)
			(xy 302.601141 -298.526412) (xy 302.56302 -298.495287) (xy 302.530385 -298.45845) (xy 302.504082 -298.416854)
			(xy 302.484791 -298.371578) (xy 302.473014 -298.323794) (xy 302.469054 -298.27474) (xy 302.130206 -298.27474)
			(xy 302.129711 -298.299347) (xy 302.121816 -298.347924) (xy 302.106232 -298.394605) (xy 302.083361 -298.438182)
			(xy 302.053796 -298.477526) (xy 302.018303 -298.511618) (xy 301.9778 -298.539574) (xy 301.933338 -298.560672)
			(xy 301.886067 -298.574364) (xy 301.837212 -298.580296) (xy 301.788037 -298.578315) (xy 301.739818 -298.568471)
			(xy 301.693802 -298.551019) (xy 301.651181 -298.526412) (xy 301.61306 -298.495287) (xy 301.580425 -298.45845)
			(xy 301.554122 -298.416854) (xy 301.534831 -298.371578) (xy 301.523054 -298.323794) (xy 301.519094 -298.27474)
			(xy 301.179992 -298.27474) (xy 301.179497 -298.299347) (xy 301.171602 -298.347924) (xy 301.156018 -298.394605)
			(xy 301.133147 -298.438182) (xy 301.103582 -298.477526) (xy 301.068089 -298.511618) (xy 301.027586 -298.539574)
			(xy 300.983124 -298.560672) (xy 300.935853 -298.574364) (xy 300.886998 -298.580296) (xy 300.837823 -298.578315)
			(xy 300.789604 -298.568471) (xy 300.743588 -298.551019) (xy 300.700967 -298.526412) (xy 300.662846 -298.495287)
			(xy 300.630211 -298.45845) (xy 300.603908 -298.416854) (xy 300.584617 -298.371578) (xy 300.57284 -298.323794)
			(xy 300.56888 -298.27474) (xy 300.230032 -298.27474) (xy 300.229537 -298.299347) (xy 300.221642 -298.347924)
			(xy 300.206058 -298.394605) (xy 300.183187 -298.438182) (xy 300.153622 -298.477526) (xy 300.118129 -298.511618)
			(xy 300.077626 -298.539574) (xy 300.033164 -298.560672) (xy 299.985893 -298.574364) (xy 299.937038 -298.580296)
			(xy 299.887863 -298.578315) (xy 299.839644 -298.568471) (xy 299.793628 -298.551019) (xy 299.751007 -298.526412)
			(xy 299.712886 -298.495287) (xy 299.680251 -298.45845) (xy 299.653948 -298.416854) (xy 299.634657 -298.371578)
			(xy 299.62288 -298.323794) (xy 299.61892 -298.27474) (xy 299.280072 -298.27474) (xy 299.279577 -298.299347)
			(xy 299.271682 -298.347924) (xy 299.256098 -298.394605) (xy 299.233227 -298.438182) (xy 299.203662 -298.477526)
			(xy 299.168169 -298.511618) (xy 299.127666 -298.539574) (xy 299.083204 -298.560672) (xy 299.035933 -298.574364)
			(xy 298.987078 -298.580296) (xy 298.937903 -298.578315) (xy 298.889684 -298.568471) (xy 298.843668 -298.551019)
			(xy 298.801047 -298.526412) (xy 298.762926 -298.495287) (xy 298.730291 -298.45845) (xy 298.703988 -298.416854)
			(xy 298.684697 -298.371578) (xy 298.67292 -298.323794) (xy 298.66896 -298.27474) (xy 298.330112 -298.27474)
			(xy 298.329617 -298.299347) (xy 298.321722 -298.347924) (xy 298.306138 -298.394605) (xy 298.283267 -298.438182)
			(xy 298.253702 -298.477526) (xy 298.218209 -298.511618) (xy 298.177706 -298.539574) (xy 298.133244 -298.560672)
			(xy 298.085973 -298.574364) (xy 298.037118 -298.580296) (xy 297.987943 -298.578315) (xy 297.939724 -298.568471)
			(xy 297.893708 -298.551019) (xy 297.851087 -298.526412) (xy 297.812966 -298.495287) (xy 297.780331 -298.45845)
			(xy 297.754028 -298.416854) (xy 297.734737 -298.371578) (xy 297.72296 -298.323794) (xy 297.719 -298.27474)
			(xy 297.380152 -298.27474) (xy 297.379657 -298.299347) (xy 297.371762 -298.347924) (xy 297.356178 -298.394605)
			(xy 297.333307 -298.438182) (xy 297.303742 -298.477526) (xy 297.268249 -298.511618) (xy 297.227746 -298.539574)
			(xy 297.183284 -298.560672) (xy 297.136013 -298.574364) (xy 297.087158 -298.580296) (xy 297.037983 -298.578315)
			(xy 296.989764 -298.568471) (xy 296.943748 -298.551019) (xy 296.901127 -298.526412) (xy 296.863006 -298.495287)
			(xy 296.830371 -298.45845) (xy 296.804068 -298.416854) (xy 296.784777 -298.371578) (xy 296.773 -298.323794)
			(xy 296.76904 -298.27474) (xy 296.430192 -298.27474) (xy 296.429697 -298.299347) (xy 296.421802 -298.347924)
			(xy 296.406218 -298.394605) (xy 296.383347 -298.438182) (xy 296.353782 -298.477526) (xy 296.318289 -298.511618)
			(xy 296.277786 -298.539574) (xy 296.233324 -298.560672) (xy 296.186053 -298.574364) (xy 296.137198 -298.580296)
			(xy 296.088023 -298.578315) (xy 296.039804 -298.568471) (xy 295.993788 -298.551019) (xy 295.951167 -298.526412)
			(xy 295.913046 -298.495287) (xy 295.880411 -298.45845) (xy 295.854108 -298.416854) (xy 295.834817 -298.371578)
			(xy 295.82304 -298.323794) (xy 295.81908 -298.27474) (xy 295.480232 -298.27474) (xy 295.479737 -298.299347)
			(xy 295.471842 -298.347924) (xy 295.456258 -298.394605) (xy 295.433387 -298.438182) (xy 295.403822 -298.477526)
			(xy 295.368329 -298.511618) (xy 295.327826 -298.539574) (xy 295.283364 -298.560672) (xy 295.236093 -298.574364)
			(xy 295.187238 -298.580296) (xy 295.138063 -298.578315) (xy 295.089844 -298.568471) (xy 295.043828 -298.551019)
			(xy 295.001207 -298.526412) (xy 294.963086 -298.495287) (xy 294.930451 -298.45845) (xy 294.904148 -298.416854)
			(xy 294.884857 -298.371578) (xy 294.87308 -298.323794) (xy 294.86912 -298.27474) (xy 294.530018 -298.27474)
			(xy 294.529523 -298.299347) (xy 294.521628 -298.347924) (xy 294.506044 -298.394605) (xy 294.483173 -298.438182)
			(xy 294.453608 -298.477526) (xy 294.418115 -298.511618) (xy 294.377612 -298.539574) (xy 294.33315 -298.560672)
			(xy 294.285879 -298.574364) (xy 294.237024 -298.580296) (xy 294.187849 -298.578315) (xy 294.13963 -298.568471)
			(xy 294.093614 -298.551019) (xy 294.050993 -298.526412) (xy 294.012872 -298.495287) (xy 293.980237 -298.45845)
			(xy 293.953934 -298.416854) (xy 293.934643 -298.371578) (xy 293.922866 -298.323794) (xy 293.918906 -298.27474)
			(xy 293.580058 -298.27474) (xy 293.579563 -298.299347) (xy 293.571668 -298.347924) (xy 293.556084 -298.394605)
			(xy 293.533213 -298.438182) (xy 293.503648 -298.477526) (xy 293.468155 -298.511618) (xy 293.427652 -298.539574)
			(xy 293.38319 -298.560672) (xy 293.335919 -298.574364) (xy 293.287064 -298.580296) (xy 293.237889 -298.578315)
			(xy 293.18967 -298.568471) (xy 293.143654 -298.551019) (xy 293.101033 -298.526412) (xy 293.062912 -298.495287)
			(xy 293.030277 -298.45845) (xy 293.003974 -298.416854) (xy 292.984683 -298.371578) (xy 292.972906 -298.323794)
			(xy 292.968946 -298.27474) (xy 292.630098 -298.27474) (xy 292.629603 -298.299347) (xy 292.621708 -298.347924)
			(xy 292.606124 -298.394605) (xy 292.583253 -298.438182) (xy 292.553688 -298.477526) (xy 292.518195 -298.511618)
			(xy 292.477692 -298.539574) (xy 292.43323 -298.560672) (xy 292.385959 -298.574364) (xy 292.337104 -298.580296)
			(xy 292.287929 -298.578315) (xy 292.23971 -298.568471) (xy 292.193694 -298.551019) (xy 292.151073 -298.526412)
			(xy 292.112952 -298.495287) (xy 292.080317 -298.45845) (xy 292.054014 -298.416854) (xy 292.034723 -298.371578)
			(xy 292.022946 -298.323794) (xy 292.018986 -298.27474) (xy 290.730178 -298.27474) (xy 290.729683 -298.299347)
			(xy 290.721788 -298.347924) (xy 290.706204 -298.394605) (xy 290.683333 -298.438182) (xy 290.653768 -298.477526)
			(xy 290.618275 -298.511618) (xy 290.577772 -298.539574) (xy 290.53331 -298.560672) (xy 290.486039 -298.574364)
			(xy 290.437184 -298.580296) (xy 290.388009 -298.578315) (xy 290.33979 -298.568471) (xy 290.293774 -298.551019)
			(xy 290.251153 -298.526412) (xy 290.213032 -298.495287) (xy 290.180397 -298.45845) (xy 290.154094 -298.416854)
			(xy 290.134803 -298.371578) (xy 290.123026 -298.323794) (xy 290.119066 -298.27474) (xy 289.780218 -298.27474)
			(xy 289.779723 -298.299347) (xy 289.771828 -298.347924) (xy 289.756244 -298.394605) (xy 289.733373 -298.438182)
			(xy 289.703808 -298.477526) (xy 289.668315 -298.511618) (xy 289.627812 -298.539574) (xy 289.58335 -298.560672)
			(xy 289.536079 -298.574364) (xy 289.487224 -298.580296) (xy 289.438049 -298.578315) (xy 289.38983 -298.568471)
			(xy 289.343814 -298.551019) (xy 289.301193 -298.526412) (xy 289.263072 -298.495287) (xy 289.230437 -298.45845)
			(xy 289.204134 -298.416854) (xy 289.184843 -298.371578) (xy 289.173066 -298.323794) (xy 289.169106 -298.27474)
			(xy 288.830004 -298.27474) (xy 288.829509 -298.299347) (xy 288.821614 -298.347924) (xy 288.80603 -298.394605)
			(xy 288.783159 -298.438182) (xy 288.753594 -298.477526) (xy 288.718101 -298.511618) (xy 288.677598 -298.539574)
			(xy 288.633136 -298.560672) (xy 288.585865 -298.574364) (xy 288.53701 -298.580296) (xy 288.487835 -298.578315)
			(xy 288.439616 -298.568471) (xy 288.3936 -298.551019) (xy 288.350979 -298.526412) (xy 288.312858 -298.495287)
			(xy 288.280223 -298.45845) (xy 288.25392 -298.416854) (xy 288.234629 -298.371578) (xy 288.222852 -298.323794)
			(xy 288.218892 -298.27474) (xy 287.880044 -298.27474) (xy 287.879549 -298.299347) (xy 287.871654 -298.347924)
			(xy 287.85607 -298.394605) (xy 287.833199 -298.438182) (xy 287.803634 -298.477526) (xy 287.768141 -298.511618)
			(xy 287.727638 -298.539574) (xy 287.683176 -298.560672) (xy 287.635905 -298.574364) (xy 287.58705 -298.580296)
			(xy 287.537875 -298.578315) (xy 287.489656 -298.568471) (xy 287.44364 -298.551019) (xy 287.401019 -298.526412)
			(xy 287.362898 -298.495287) (xy 287.330263 -298.45845) (xy 287.30396 -298.416854) (xy 287.284669 -298.371578)
			(xy 287.272892 -298.323794) (xy 287.268932 -298.27474) (xy 286.930084 -298.27474) (xy 286.929589 -298.299347)
			(xy 286.921694 -298.347924) (xy 286.90611 -298.394605) (xy 286.883239 -298.438182) (xy 286.853674 -298.477526)
			(xy 286.818181 -298.511618) (xy 286.777678 -298.539574) (xy 286.733216 -298.560672) (xy 286.685945 -298.574364)
			(xy 286.63709 -298.580296) (xy 286.587915 -298.578315) (xy 286.539696 -298.568471) (xy 286.49368 -298.551019)
			(xy 286.451059 -298.526412) (xy 286.412938 -298.495287) (xy 286.380303 -298.45845) (xy 286.354 -298.416854)
			(xy 286.334709 -298.371578) (xy 286.322932 -298.323794) (xy 286.318972 -298.27474) (xy 285.980124 -298.27474)
			(xy 285.979629 -298.299347) (xy 285.971734 -298.347924) (xy 285.95615 -298.394605) (xy 285.933279 -298.438182)
			(xy 285.903714 -298.477526) (xy 285.868221 -298.511618) (xy 285.827718 -298.539574) (xy 285.783256 -298.560672)
			(xy 285.735985 -298.574364) (xy 285.68713 -298.580296) (xy 285.637955 -298.578315) (xy 285.589736 -298.568471)
			(xy 285.54372 -298.551019) (xy 285.501099 -298.526412) (xy 285.462978 -298.495287) (xy 285.430343 -298.45845)
			(xy 285.40404 -298.416854) (xy 285.384749 -298.371578) (xy 285.372972 -298.323794) (xy 285.369012 -298.27474)
			(xy 285.030164 -298.27474) (xy 285.029669 -298.299347) (xy 285.021774 -298.347924) (xy 285.00619 -298.394605)
			(xy 284.983319 -298.438182) (xy 284.953754 -298.477526) (xy 284.918261 -298.511618) (xy 284.877758 -298.539574)
			(xy 284.833296 -298.560672) (xy 284.786025 -298.574364) (xy 284.73717 -298.580296) (xy 284.687995 -298.578315)
			(xy 284.639776 -298.568471) (xy 284.59376 -298.551019) (xy 284.551139 -298.526412) (xy 284.513018 -298.495287)
			(xy 284.480383 -298.45845) (xy 284.45408 -298.416854) (xy 284.434789 -298.371578) (xy 284.423012 -298.323794)
			(xy 284.419052 -298.27474) (xy 284.080204 -298.27474) (xy 284.079709 -298.299347) (xy 284.071814 -298.347924)
			(xy 284.05623 -298.394605) (xy 284.033359 -298.438182) (xy 284.003794 -298.477526) (xy 283.968301 -298.511618)
			(xy 283.927798 -298.539574) (xy 283.883336 -298.560672) (xy 283.836065 -298.574364) (xy 283.78721 -298.580296)
			(xy 283.738035 -298.578315) (xy 283.689816 -298.568471) (xy 283.6438 -298.551019) (xy 283.601179 -298.526412)
			(xy 283.563058 -298.495287) (xy 283.530423 -298.45845) (xy 283.50412 -298.416854) (xy 283.484829 -298.371578)
			(xy 283.473052 -298.323794) (xy 283.469092 -298.27474) (xy 283.130244 -298.27474) (xy 283.129749 -298.299347)
			(xy 283.121854 -298.347924) (xy 283.10627 -298.394605) (xy 283.083399 -298.438182) (xy 283.053834 -298.477526)
			(xy 283.018341 -298.511618) (xy 282.977838 -298.539574) (xy 282.933376 -298.560672) (xy 282.886105 -298.574364)
			(xy 282.83725 -298.580296) (xy 282.788075 -298.578315) (xy 282.739856 -298.568471) (xy 282.69384 -298.551019)
			(xy 282.651219 -298.526412) (xy 282.613098 -298.495287) (xy 282.580463 -298.45845) (xy 282.55416 -298.416854)
			(xy 282.534869 -298.371578) (xy 282.523092 -298.323794) (xy 282.519132 -298.27474) (xy 282.18003 -298.27474)
			(xy 282.179535 -298.299347) (xy 282.17164 -298.347924) (xy 282.156056 -298.394605) (xy 282.133185 -298.438182)
			(xy 282.10362 -298.477526) (xy 282.068127 -298.511618) (xy 282.027624 -298.539574) (xy 281.983162 -298.560672)
			(xy 281.935891 -298.574364) (xy 281.887036 -298.580296) (xy 281.837861 -298.578315) (xy 281.789642 -298.568471)
			(xy 281.743626 -298.551019) (xy 281.701005 -298.526412) (xy 281.662884 -298.495287) (xy 281.630249 -298.45845)
			(xy 281.603946 -298.416854) (xy 281.584655 -298.371578) (xy 281.572878 -298.323794) (xy 281.568918 -298.27474)
			(xy 281.23007 -298.27474) (xy 281.229575 -298.299347) (xy 281.22168 -298.347924) (xy 281.206096 -298.394605)
			(xy 281.183225 -298.438182) (xy 281.15366 -298.477526) (xy 281.118167 -298.511618) (xy 281.077664 -298.539574)
			(xy 281.033202 -298.560672) (xy 280.985931 -298.574364) (xy 280.937076 -298.580296) (xy 280.887901 -298.578315)
			(xy 280.839682 -298.568471) (xy 280.793666 -298.551019) (xy 280.751045 -298.526412) (xy 280.712924 -298.495287)
			(xy 280.680289 -298.45845) (xy 280.653986 -298.416854) (xy 280.634695 -298.371578) (xy 280.622918 -298.323794)
			(xy 280.618958 -298.27474) (xy 280.28011 -298.27474) (xy 280.279615 -298.299347) (xy 280.27172 -298.347924)
			(xy 280.256136 -298.394605) (xy 280.233265 -298.438182) (xy 280.2037 -298.477526) (xy 280.168207 -298.511618)
			(xy 280.127704 -298.539574) (xy 280.083242 -298.560672) (xy 280.035971 -298.574364) (xy 279.987116 -298.580296)
			(xy 279.937941 -298.578315) (xy 279.889722 -298.568471) (xy 279.843706 -298.551019) (xy 279.801085 -298.526412)
			(xy 279.762964 -298.495287) (xy 279.730329 -298.45845) (xy 279.704026 -298.416854) (xy 279.684735 -298.371578)
			(xy 279.672958 -298.323794) (xy 279.668998 -298.27474) (xy 279.41397 -298.27474) (xy 279.41397 -298.700698)
			(xy 318.697354 -298.700698) (xy 318.701425 -298.645076) (xy 318.713551 -298.590639) (xy 318.733474 -298.538548)
			(xy 318.76077 -298.489913) (xy 318.794856 -298.44577) (xy 318.835005 -298.407061) (xy 318.880363 -298.37461)
			(xy 318.929963 -298.349109) (xy 318.982747 -298.331102) (xy 319.03759 -298.320972) (xy 319.093324 -298.318935)
			(xy 319.148761 -298.325035) (xy 319.202718 -298.339141) (xy 319.254047 -298.360953) (xy 319.301653 -298.390007)
			(xy 319.338337 -298.420536) (xy 335.694782 -298.420536) (xy 335.695249 -298.393166) (xy 335.703064 -298.338986)
			(xy 335.718551 -298.286482) (xy 335.741393 -298.236735) (xy 335.77112 -298.190769) (xy 335.788762 -298.169838)
			(xy 335.794858 -298.162726) (xy 335.801208 -298.145708) (xy 335.801208 -298.060364) (xy 335.794858 -298.043346)
			(xy 335.788762 -298.036234) (xy 335.771155 -298.015273) (xy 335.741426 -297.969311) (xy 335.718577 -297.91957)
			(xy 335.703076 -297.867072) (xy 335.695243 -297.812896) (xy 335.695239 -297.758158) (xy 335.703064 -297.703981)
			(xy 335.718558 -297.651481) (xy 335.7414 -297.601736) (xy 335.771122 -297.55577) (xy 335.788762 -297.534838)
			(xy 335.794858 -297.527726) (xy 335.801208 -297.510708) (xy 335.801208 -297.425364) (xy 335.794858 -297.408346)
			(xy 335.788762 -297.401234) (xy 335.771155 -297.380273) (xy 335.741426 -297.334311) (xy 335.718577 -297.28457)
			(xy 335.703076 -297.232072) (xy 335.695243 -297.177896) (xy 335.695239 -297.123158) (xy 335.703064 -297.068981)
			(xy 335.718558 -297.016481) (xy 335.7414 -296.966736) (xy 335.771122 -296.92077) (xy 335.788762 -296.899838)
			(xy 335.794858 -296.892726) (xy 335.801208 -296.875708) (xy 335.801208 -296.790364) (xy 335.794858 -296.773346)
			(xy 335.788762 -296.766234) (xy 335.771155 -296.745273) (xy 335.741426 -296.699311) (xy 335.718577 -296.64957)
			(xy 335.703076 -296.597072) (xy 335.695243 -296.542896) (xy 335.695239 -296.488158) (xy 335.703064 -296.433981)
			(xy 335.718558 -296.381481) (xy 335.7414 -296.331736) (xy 335.771122 -296.28577) (xy 335.788762 -296.264838)
			(xy 335.794858 -296.257726) (xy 335.801208 -296.240708) (xy 335.801208 -296.155364) (xy 335.794858 -296.138346)
			(xy 335.788762 -296.131234) (xy 335.771155 -296.110273) (xy 335.741426 -296.064311) (xy 335.718577 -296.01457)
			(xy 335.703076 -295.962072) (xy 335.695243 -295.907896) (xy 335.695239 -295.853158) (xy 335.703064 -295.798981)
			(xy 335.718558 -295.746481) (xy 335.7414 -295.696736) (xy 335.771122 -295.65077) (xy 335.788762 -295.629838)
			(xy 335.794858 -295.622726) (xy 335.801208 -295.605708) (xy 335.801208 -295.520364) (xy 335.794858 -295.503346)
			(xy 335.788762 -295.496234) (xy 335.771119 -295.475305) (xy 335.741409 -295.429331) (xy 335.718574 -295.379582)
			(xy 335.703084 -295.327081) (xy 335.695256 -295.272905) (xy 335.694782 -295.245536) (xy 335.695289 -295.218284)
			(xy 335.703041 -295.164336) (xy 335.718392 -295.112039) (xy 335.741029 -295.06246) (xy 335.770492 -295.016607)
			(xy 335.806182 -294.975414) (xy 335.84737 -294.93972) (xy 335.893219 -294.910251) (xy 335.942796 -294.887608)
			(xy 335.995091 -294.87225) (xy 336.049039 -294.864492) (xy 336.07629 -294.864028) (xy 336.10366 -294.864493)
			(xy 336.15784 -294.87231) (xy 336.210343 -294.887799) (xy 336.26009 -294.910641) (xy 336.306057 -294.940366)
			(xy 336.326988 -294.958008) (xy 336.3341 -294.964104) (xy 336.351118 -294.970454) (xy 336.436462 -294.970454)
			(xy 336.45348 -294.964104) (xy 336.460592 -294.958008) (xy 336.481517 -294.94036) (xy 336.527492 -294.91065)
			(xy 336.577241 -294.887815) (xy 336.629743 -294.872326) (xy 336.68392 -294.864501) (xy 336.71129 -294.864028)
			(xy 336.738544 -294.864465) (xy 336.792498 -294.872221) (xy 336.844799 -294.887578) (xy 336.894381 -294.910222)
			(xy 336.940236 -294.939692) (xy 336.98143 -294.975389) (xy 337.017123 -295.016585) (xy 337.046591 -295.062442)
			(xy 337.069231 -295.112026) (xy 337.084584 -295.164327) (xy 337.092337 -295.218282) (xy 337.092798 -295.245536)
			(xy 337.092354 -295.272907) (xy 337.084531 -295.327087) (xy 337.069036 -295.37959) (xy 337.04619 -295.429337)
			(xy 337.016461 -295.475303) (xy 336.998818 -295.496234) (xy 336.992722 -295.503346) (xy 336.986372 -295.520364)
			(xy 336.986372 -295.605708) (xy 336.992722 -295.622726) (xy 336.998818 -295.629838) (xy 337.016492 -295.650743)
			(xy 337.046212 -295.696717) (xy 337.069052 -295.746468) (xy 337.084544 -295.798974) (xy 337.092368 -295.853155)
			(xy 337.092364 -295.907899) (xy 337.084532 -295.962079) (xy 337.069033 -296.014583) (xy 337.046186 -296.064331)
			(xy 337.016459 -296.1103) (xy 336.998818 -296.131234) (xy 336.992722 -296.138346) (xy 336.986372 -296.155364)
			(xy 336.986372 -296.240708) (xy 336.992722 -296.257726) (xy 336.998818 -296.264838) (xy 337.016492 -296.285743)
			(xy 337.046212 -296.331717) (xy 337.069052 -296.381468) (xy 337.084544 -296.433974) (xy 337.092368 -296.488155)
			(xy 337.092364 -296.542899) (xy 337.084532 -296.597079) (xy 337.069033 -296.649583) (xy 337.046186 -296.699331)
			(xy 337.016459 -296.7453) (xy 336.998818 -296.766234) (xy 336.992722 -296.773346) (xy 336.986372 -296.790364)
			(xy 336.986372 -296.875708) (xy 336.992722 -296.892726) (xy 336.998818 -296.899838) (xy 337.016492 -296.920743)
			(xy 337.046212 -296.966717) (xy 337.069052 -297.016468) (xy 337.084544 -297.068974) (xy 337.092368 -297.123155)
			(xy 337.092364 -297.177899) (xy 337.084532 -297.232079) (xy 337.069033 -297.284583) (xy 337.046186 -297.334331)
			(xy 337.016459 -297.3803) (xy 336.998818 -297.401234) (xy 336.992722 -297.408346) (xy 336.986372 -297.425364)
			(xy 336.986372 -297.510708) (xy 336.992722 -297.527726) (xy 336.998818 -297.534838) (xy 337.016492 -297.555743)
			(xy 337.046212 -297.601717) (xy 337.069052 -297.651468) (xy 337.084544 -297.703974) (xy 337.092368 -297.758155)
			(xy 337.092364 -297.812899) (xy 337.084532 -297.867079) (xy 337.069033 -297.919583) (xy 337.046186 -297.969331)
			(xy 337.016459 -298.0153) (xy 336.998818 -298.036234) (xy 336.992722 -298.043346) (xy 336.986372 -298.060364)
			(xy 336.986372 -298.145708) (xy 336.992722 -298.162726) (xy 336.998818 -298.169838) (xy 337.016444 -298.19078)
			(xy 337.046157 -298.236751) (xy 337.068996 -298.286496) (xy 337.08449 -298.338994) (xy 337.092322 -298.393168)
			(xy 337.092798 -298.420536) (xy 340.335362 -298.420536) (xy 340.335834 -298.393166) (xy 340.343648 -298.338986)
			(xy 340.359135 -298.286483) (xy 340.381976 -298.236736) (xy 340.4117 -298.190769) (xy 340.429342 -298.169838)
			(xy 340.435438 -298.162726) (xy 340.441788 -298.145708) (xy 340.441788 -298.060364) (xy 340.435438 -298.043346)
			(xy 340.429342 -298.036234) (xy 340.411736 -298.015273) (xy 340.382009 -297.969311) (xy 340.35916 -297.919569)
			(xy 340.34366 -297.867071) (xy 340.335828 -297.812896) (xy 340.335824 -297.758158) (xy 340.343649 -297.703982)
			(xy 340.359141 -297.651482) (xy 340.381982 -297.601737) (xy 340.411703 -297.55577) (xy 340.429342 -297.534838)
			(xy 340.435438 -297.527726) (xy 340.441788 -297.510708) (xy 340.441788 -297.425364) (xy 340.435438 -297.408346)
			(xy 340.429342 -297.401234) (xy 340.411736 -297.380273) (xy 340.382009 -297.334311) (xy 340.35916 -297.284569)
			(xy 340.34366 -297.232071) (xy 340.335828 -297.177896) (xy 340.335824 -297.123158) (xy 340.343649 -297.068982)
			(xy 340.359141 -297.016482) (xy 340.381982 -296.966737) (xy 340.411703 -296.92077) (xy 340.429342 -296.899838)
			(xy 340.435438 -296.892726) (xy 340.441788 -296.875708) (xy 340.441788 -296.790364) (xy 340.435438 -296.773346)
			(xy 340.429342 -296.766234) (xy 340.411736 -296.745273) (xy 340.382009 -296.699311) (xy 340.35916 -296.649569)
			(xy 340.34366 -296.597071) (xy 340.335828 -296.542896) (xy 340.335824 -296.488158) (xy 340.343649 -296.433982)
			(xy 340.359141 -296.381482) (xy 340.381982 -296.331737) (xy 340.411703 -296.28577) (xy 340.429342 -296.264838)
			(xy 340.435438 -296.257726) (xy 340.441788 -296.240708) (xy 340.441788 -296.155364) (xy 340.435438 -296.138346)
			(xy 340.429342 -296.131234) (xy 340.411736 -296.110273) (xy 340.382009 -296.064311) (xy 340.35916 -296.014569)
			(xy 340.34366 -295.962071) (xy 340.335828 -295.907896) (xy 340.335824 -295.853158) (xy 340.343649 -295.798982)
			(xy 340.359141 -295.746482) (xy 340.381982 -295.696737) (xy 340.411703 -295.65077) (xy 340.429342 -295.629838)
			(xy 340.435438 -295.622726) (xy 340.441788 -295.605708) (xy 340.441788 -295.520364) (xy 340.435438 -295.503346)
			(xy 340.429342 -295.496234) (xy 340.411712 -295.475295) (xy 340.381997 -295.429324) (xy 340.359159 -295.379579)
			(xy 340.343666 -295.32708) (xy 340.335836 -295.272905) (xy 340.335362 -295.245536) (xy 340.335889 -295.218285)
			(xy 340.34364 -295.164338) (xy 340.35899 -295.112043) (xy 340.381626 -295.062465) (xy 340.411088 -295.016614)
			(xy 340.446775 -294.975421) (xy 340.487961 -294.939727) (xy 340.533807 -294.910258) (xy 340.583382 -294.887613)
			(xy 340.635674 -294.872254) (xy 340.689619 -294.864493) (xy 340.71687 -294.864028) (xy 340.74424 -294.864505)
			(xy 340.798419 -294.872319) (xy 340.850922 -294.887805) (xy 340.900669 -294.910645) (xy 340.946636 -294.940367)
			(xy 340.967568 -294.958008) (xy 340.97468 -294.964104) (xy 340.991698 -294.970454) (xy 341.077042 -294.970454)
			(xy 341.09406 -294.964104) (xy 341.101172 -294.958008) (xy 341.122105 -294.94037) (xy 341.168077 -294.910658)
			(xy 341.217825 -294.887821) (xy 341.270325 -294.87233) (xy 341.324501 -294.864502) (xy 341.35187 -294.864028)
			(xy 341.379124 -294.864483) (xy 341.433077 -294.872237) (xy 341.485377 -294.887591) (xy 341.534959 -294.910233)
			(xy 341.580814 -294.939701) (xy 341.622008 -294.975396) (xy 341.657703 -295.01659) (xy 341.68717 -295.062446)
			(xy 341.709811 -295.112029) (xy 341.725164 -295.164329) (xy 341.732917 -295.218282) (xy 341.733378 -295.245536)
			(xy 341.732938 -295.272907) (xy 341.725115 -295.327088) (xy 341.70962 -295.379591) (xy 341.686772 -295.429338)
			(xy 341.657042 -295.475303) (xy 341.639398 -295.496234) (xy 341.633302 -295.503346) (xy 341.626952 -295.520364)
			(xy 341.626952 -295.605708) (xy 341.633302 -295.622726) (xy 341.639398 -295.629838) (xy 341.657073 -295.650743)
			(xy 341.686794 -295.696716) (xy 341.709636 -295.746467) (xy 341.725128 -295.798973) (xy 341.732953 -295.853155)
			(xy 341.732949 -295.907899) (xy 341.725117 -295.96208) (xy 341.709617 -296.014584) (xy 341.686768 -296.064332)
			(xy 341.65704 -296.110301) (xy 341.639398 -296.131234) (xy 341.633302 -296.138346) (xy 341.626952 -296.155364)
			(xy 341.626952 -296.240708) (xy 341.633302 -296.257726) (xy 341.639398 -296.264838) (xy 341.657073 -296.285743)
			(xy 341.686794 -296.331716) (xy 341.709636 -296.381467) (xy 341.725128 -296.433973) (xy 341.732953 -296.488155)
			(xy 341.732949 -296.542899) (xy 341.725117 -296.59708) (xy 341.709617 -296.649584) (xy 341.686768 -296.699332)
			(xy 341.65704 -296.745301) (xy 341.639398 -296.766234) (xy 341.633302 -296.773346) (xy 341.626952 -296.790364)
			(xy 341.626952 -296.875708) (xy 341.633302 -296.892726) (xy 341.639398 -296.899838) (xy 341.657073 -296.920743)
			(xy 341.686794 -296.966716) (xy 341.709636 -297.016467) (xy 341.725128 -297.068973) (xy 341.732953 -297.123155)
			(xy 341.732949 -297.177899) (xy 341.725117 -297.23208) (xy 341.709617 -297.284584) (xy 341.686768 -297.334332)
			(xy 341.65704 -297.380301) (xy 341.639398 -297.401234) (xy 341.633302 -297.408346) (xy 341.626952 -297.425364)
			(xy 341.626952 -297.510708) (xy 341.633302 -297.527726) (xy 341.639398 -297.534838) (xy 341.657073 -297.555743)
			(xy 341.686794 -297.601716) (xy 341.709636 -297.651467) (xy 341.725128 -297.703973) (xy 341.732953 -297.758155)
			(xy 341.732949 -297.812899) (xy 341.725117 -297.86708) (xy 341.709617 -297.919584) (xy 341.686768 -297.969332)
			(xy 341.65704 -298.015301) (xy 341.639398 -298.036234) (xy 341.633302 -298.043346) (xy 341.626952 -298.060364)
			(xy 341.626952 -298.145708) (xy 341.633302 -298.162726) (xy 341.639398 -298.169838) (xy 341.657021 -298.190783)
			(xy 341.686735 -298.236752) (xy 341.709575 -298.286496) (xy 341.725069 -298.338994) (xy 341.732902 -298.393168)
			(xy 341.733378 -298.420536) (xy 342.763094 -298.420536) (xy 342.763583 -298.393167) (xy 342.771395 -298.338989)
			(xy 342.786879 -298.286486) (xy 342.809716 -298.236739) (xy 342.839435 -298.190771) (xy 342.857074 -298.169838)
			(xy 342.86317 -298.162726) (xy 342.86952 -298.145708) (xy 342.86952 -298.060364) (xy 342.86317 -298.043346)
			(xy 342.857074 -298.036234) (xy 342.839467 -298.015274) (xy 342.809737 -297.969312) (xy 342.786886 -297.91957)
			(xy 342.771385 -297.867072) (xy 342.763552 -297.812897) (xy 342.763548 -297.758158) (xy 342.771374 -297.703981)
			(xy 342.786867 -297.65148) (xy 342.809711 -297.601736) (xy 342.839434 -297.55577) (xy 342.857074 -297.534838)
			(xy 342.86317 -297.527726) (xy 342.86952 -297.510708) (xy 342.86952 -297.425364) (xy 342.86317 -297.408346)
			(xy 342.857074 -297.401234) (xy 342.839467 -297.380274) (xy 342.809737 -297.334312) (xy 342.786886 -297.28457)
			(xy 342.771385 -297.232072) (xy 342.763552 -297.177897) (xy 342.763548 -297.123158) (xy 342.771374 -297.068981)
			(xy 342.786867 -297.01648) (xy 342.809711 -296.966736) (xy 342.839434 -296.92077) (xy 342.857074 -296.899838)
			(xy 342.86317 -296.892726) (xy 342.86952 -296.875708) (xy 342.86952 -296.790364) (xy 342.86317 -296.773346)
			(xy 342.857074 -296.766234) (xy 342.839467 -296.745274) (xy 342.809737 -296.699312) (xy 342.786886 -296.64957)
			(xy 342.771385 -296.597072) (xy 342.763552 -296.542897) (xy 342.763548 -296.488158) (xy 342.771374 -296.433981)
			(xy 342.786867 -296.38148) (xy 342.809711 -296.331736) (xy 342.839434 -296.28577) (xy 342.857074 -296.264838)
			(xy 342.86317 -296.257726) (xy 342.86952 -296.240708) (xy 342.86952 -296.155364) (xy 342.86317 -296.138346)
			(xy 342.857074 -296.131234) (xy 342.839467 -296.110274) (xy 342.809737 -296.064312) (xy 342.786886 -296.01457)
			(xy 342.771385 -295.962072) (xy 342.763552 -295.907897) (xy 342.763548 -295.853158) (xy 342.771374 -295.798981)
			(xy 342.786867 -295.74648) (xy 342.809711 -295.696736) (xy 342.839434 -295.65077) (xy 342.857074 -295.629838)
			(xy 342.86317 -295.622726) (xy 342.86952 -295.605708) (xy 342.86952 -295.520364) (xy 342.86317 -295.503346)
			(xy 342.857074 -295.496234) (xy 342.839433 -295.475303) (xy 342.809723 -295.42933) (xy 342.786887 -295.379582)
			(xy 342.771397 -295.327081) (xy 342.763568 -295.272905) (xy 342.763094 -295.245536) (xy 342.763589 -295.218284)
			(xy 342.771341 -295.164334) (xy 342.786692 -295.112037) (xy 342.809331 -295.062457) (xy 342.838795 -295.016603)
			(xy 342.874486 -294.97541) (xy 342.915676 -294.939716) (xy 342.961527 -294.910247) (xy 343.011105 -294.887604)
			(xy 343.063401 -294.872248) (xy 343.11735 -294.864491) (xy 343.144602 -294.864028) (xy 343.171973 -294.864486)
			(xy 343.226152 -294.872305) (xy 343.278656 -294.887795) (xy 343.328403 -294.910639) (xy 343.374369 -294.940366)
			(xy 343.3953 -294.958008) (xy 343.402412 -294.964104) (xy 343.41943 -294.970454) (xy 343.504774 -294.970454)
			(xy 343.521792 -294.964104) (xy 343.528904 -294.958008) (xy 343.549825 -294.940355) (xy 343.595801 -294.910645)
			(xy 343.645551 -294.887811) (xy 343.698054 -294.872324) (xy 343.752232 -294.8645) (xy 343.779602 -294.864028)
			(xy 343.806857 -294.864454) (xy 343.860811 -294.872212) (xy 343.913111 -294.88757) (xy 343.962694 -294.910215)
			(xy 344.008549 -294.939687) (xy 344.049742 -294.975385) (xy 344.085436 -295.016582) (xy 344.114903 -295.062439)
			(xy 344.137543 -295.112024) (xy 344.152896 -295.164326) (xy 344.160649 -295.218281) (xy 344.16111 -295.245536)
			(xy 344.160663 -295.272907) (xy 344.15284 -295.327087) (xy 344.137346 -295.37959) (xy 344.114501 -295.429336)
			(xy 344.084773 -295.475303) (xy 344.06713 -295.496234) (xy 344.061034 -295.503346) (xy 344.054684 -295.520364)
			(xy 344.054684 -295.605708) (xy 344.061034 -295.622726) (xy 344.06713 -295.629838) (xy 344.084808 -295.650741)
			(xy 344.114534 -295.696713) (xy 344.13738 -295.746464) (xy 344.152876 -295.798971) (xy 344.160702 -295.853154)
			(xy 344.160698 -295.9079) (xy 344.152864 -295.962082) (xy 344.137361 -296.014587) (xy 344.114508 -296.064334)
			(xy 344.084775 -296.110302) (xy 344.06713 -296.131234) (xy 344.061034 -296.138346) (xy 344.054684 -296.155364)
			(xy 344.054684 -296.240708) (xy 344.061034 -296.257726) (xy 344.06713 -296.264838) (xy 344.084808 -296.285741)
			(xy 344.114534 -296.331713) (xy 344.13738 -296.381464) (xy 344.152876 -296.433971) (xy 344.160702 -296.488154)
			(xy 344.160698 -296.5429) (xy 344.152864 -296.597082) (xy 344.137361 -296.649587) (xy 344.114508 -296.699334)
			(xy 344.084775 -296.745302) (xy 344.06713 -296.766234) (xy 344.061034 -296.773346) (xy 344.054684 -296.790364)
			(xy 344.054684 -296.875708) (xy 344.061034 -296.892726) (xy 344.06713 -296.899838) (xy 344.084808 -296.920741)
			(xy 344.114534 -296.966713) (xy 344.13738 -297.016464) (xy 344.152876 -297.068971) (xy 344.160702 -297.123154)
			(xy 344.160698 -297.1779) (xy 344.152864 -297.232082) (xy 344.137361 -297.284587) (xy 344.114508 -297.334334)
			(xy 344.084775 -297.380302) (xy 344.06713 -297.401234) (xy 344.061034 -297.408346) (xy 344.054684 -297.425364)
			(xy 344.054684 -297.510708) (xy 344.061034 -297.527726) (xy 344.06713 -297.534838) (xy 344.084808 -297.555741)
			(xy 344.114534 -297.601713) (xy 344.13738 -297.651464) (xy 344.152876 -297.703971) (xy 344.160702 -297.758154)
			(xy 344.160698 -297.8129) (xy 344.152864 -297.867082) (xy 344.137361 -297.919587) (xy 344.114508 -297.969334)
			(xy 344.084775 -298.015302) (xy 344.06713 -298.036234) (xy 344.061034 -298.043346) (xy 344.054684 -298.060364)
			(xy 344.054684 -298.145708) (xy 344.061034 -298.162726) (xy 344.06713 -298.169838) (xy 344.084758 -298.190779)
			(xy 344.114471 -298.23675) (xy 344.137308 -298.286495) (xy 344.152802 -298.338994) (xy 344.160634 -298.393168)
			(xy 344.16111 -298.420536) (xy 347.403674 -298.420536) (xy 347.404143 -298.393166) (xy 347.411957 -298.338986)
			(xy 347.427445 -298.286482) (xy 347.450286 -298.236735) (xy 347.480012 -298.190769) (xy 347.497654 -298.169838)
			(xy 347.50375 -298.162726) (xy 347.5101 -298.145708) (xy 347.5101 -298.060364) (xy 347.50375 -298.043346)
			(xy 347.497654 -298.036234) (xy 347.480047 -298.015273) (xy 347.450319 -297.969311) (xy 347.42747 -297.91957)
			(xy 347.41197 -297.867071) (xy 347.404137 -297.812896) (xy 347.404133 -297.758158) (xy 347.411958 -297.703982)
			(xy 347.427451 -297.651481) (xy 347.450293 -297.601737) (xy 347.480015 -297.55577) (xy 347.497654 -297.534838)
			(xy 347.50375 -297.527726) (xy 347.5101 -297.510708) (xy 347.5101 -297.425364) (xy 347.50375 -297.408346)
			(xy 347.497654 -297.401234) (xy 347.480047 -297.380273) (xy 347.450319 -297.334311) (xy 347.42747 -297.28457)
			(xy 347.41197 -297.232071) (xy 347.404137 -297.177896) (xy 347.404133 -297.123158) (xy 347.411958 -297.068982)
			(xy 347.427451 -297.016481) (xy 347.450293 -296.966737) (xy 347.480015 -296.92077) (xy 347.497654 -296.899838)
			(xy 347.50375 -296.892726) (xy 347.5101 -296.875708) (xy 347.5101 -296.790364) (xy 347.50375 -296.773346)
			(xy 347.497654 -296.766234) (xy 347.480047 -296.745273) (xy 347.450319 -296.699311) (xy 347.42747 -296.64957)
			(xy 347.41197 -296.597071) (xy 347.404137 -296.542896) (xy 347.404133 -296.488158) (xy 347.411958 -296.433982)
			(xy 347.427451 -296.381481) (xy 347.450293 -296.331737) (xy 347.480015 -296.28577) (xy 347.497654 -296.264838)
			(xy 347.50375 -296.257726) (xy 347.5101 -296.240708) (xy 347.5101 -296.155364) (xy 347.50375 -296.138346)
			(xy 347.497654 -296.131234) (xy 347.480047 -296.110273) (xy 347.450319 -296.064311) (xy 347.42747 -296.01457)
			(xy 347.41197 -295.962071) (xy 347.404137 -295.907896) (xy 347.404133 -295.853158) (xy 347.411958 -295.798982)
			(xy 347.427451 -295.746481) (xy 347.450293 -295.696737) (xy 347.480015 -295.65077) (xy 347.497654 -295.629838)
			(xy 347.50375 -295.622726) (xy 347.5101 -295.605708) (xy 347.5101 -295.520364) (xy 347.50375 -295.503346)
			(xy 347.497654 -295.496234) (xy 347.480026 -295.475293) (xy 347.45031 -295.429323) (xy 347.427472 -295.379578)
			(xy 347.411978 -295.327079) (xy 347.404148 -295.272905) (xy 347.403674 -295.245536) (xy 347.404189 -295.218285)
			(xy 347.41194 -295.164337) (xy 347.427291 -295.112041) (xy 347.449928 -295.062462) (xy 347.47939 -295.01661)
			(xy 347.515079 -294.975417) (xy 347.556266 -294.939723) (xy 347.602115 -294.910254) (xy 347.65169 -294.88761)
			(xy 347.703984 -294.872252) (xy 347.757931 -294.864493) (xy 347.785182 -294.864028) (xy 347.812552 -294.864498)
			(xy 347.866731 -294.872314) (xy 347.919235 -294.887802) (xy 347.968982 -294.910643) (xy 348.014948 -294.940367)
			(xy 348.03588 -294.958008) (xy 348.042992 -294.964104) (xy 348.06001 -294.970454) (xy 348.145354 -294.970454)
			(xy 348.162372 -294.964104) (xy 348.169484 -294.958008) (xy 348.190412 -294.940364) (xy 348.236386 -294.910653)
			(xy 348.286134 -294.887818) (xy 348.338636 -294.872328) (xy 348.392813 -294.864501) (xy 348.420182 -294.864028)
			(xy 348.447436 -294.864472) (xy 348.50139 -294.872228) (xy 348.55369 -294.887583) (xy 348.603272 -294.910226)
			(xy 348.649127 -294.939696) (xy 348.690321 -294.975392) (xy 348.726015 -295.016587) (xy 348.755482 -295.062443)
			(xy 348.778123 -295.112027) (xy 348.793476 -295.164328) (xy 348.801229 -295.218282) (xy 348.80169 -295.245536)
			(xy 348.801247 -295.272907) (xy 348.793424 -295.327087) (xy 348.77793 -295.379591) (xy 348.755083 -295.429337)
			(xy 348.725353 -295.475303) (xy 348.70771 -295.496234) (xy 348.701614 -295.503346) (xy 348.695264 -295.520364)
			(xy 348.695264 -295.605708) (xy 348.701614 -295.622726) (xy 348.70771 -295.629838) (xy 348.725384 -295.650743)
			(xy 348.755105 -295.696716) (xy 348.777946 -295.746468) (xy 348.793438 -295.798974) (xy 348.801262 -295.853155)
			(xy 348.801258 -295.907899) (xy 348.793426 -295.96208) (xy 348.777927 -296.014583) (xy 348.755079 -296.064331)
			(xy 348.725352 -296.1103) (xy 348.70771 -296.131234) (xy 348.701614 -296.138346) (xy 348.695264 -296.155364)
			(xy 348.695264 -296.240708) (xy 348.701614 -296.257726) (xy 348.70771 -296.264838) (xy 348.725384 -296.285743)
			(xy 348.755105 -296.331716) (xy 348.777946 -296.381468) (xy 348.793438 -296.433974) (xy 348.801262 -296.488155)
			(xy 348.801258 -296.542899) (xy 348.793426 -296.59708) (xy 348.777927 -296.649583) (xy 348.755079 -296.699331)
			(xy 348.725352 -296.7453) (xy 348.70771 -296.766234) (xy 348.701614 -296.773346) (xy 348.695264 -296.790364)
			(xy 348.695264 -296.875708) (xy 348.701614 -296.892726) (xy 348.70771 -296.899838) (xy 348.725384 -296.920743)
			(xy 348.755105 -296.966716) (xy 348.777946 -297.016468) (xy 348.793438 -297.068974) (xy 348.801262 -297.123155)
			(xy 348.801258 -297.177899) (xy 348.793426 -297.23208) (xy 348.777927 -297.284583) (xy 348.755079 -297.334331)
			(xy 348.725352 -297.3803) (xy 348.70771 -297.401234) (xy 348.701614 -297.408346) (xy 348.695264 -297.425364)
			(xy 348.695264 -297.510708) (xy 348.701614 -297.527726) (xy 348.70771 -297.534838) (xy 348.725384 -297.555743)
			(xy 348.755105 -297.601716) (xy 348.777946 -297.651468) (xy 348.793438 -297.703974) (xy 348.801262 -297.758155)
			(xy 348.801258 -297.812899) (xy 348.793426 -297.86708) (xy 348.777927 -297.919583) (xy 348.755079 -297.969331)
			(xy 348.725352 -298.0153) (xy 348.70771 -298.036234) (xy 348.701614 -298.043346) (xy 348.695264 -298.060364)
			(xy 348.695264 -298.145708) (xy 348.701614 -298.162726) (xy 348.70771 -298.169838) (xy 348.725335 -298.190781)
			(xy 348.755049 -298.236751) (xy 348.777887 -298.286496) (xy 348.793382 -298.338994) (xy 348.801214 -298.393168)
			(xy 348.80169 -298.420536) (xy 348.801256 -298.447789) (xy 348.793494 -298.501739) (xy 348.778133 -298.554036)
			(xy 348.755486 -298.603615) (xy 348.726015 -298.649466) (xy 348.690318 -298.690656) (xy 348.649123 -298.726347)
			(xy 348.603267 -298.755812) (xy 348.553686 -298.778452) (xy 348.501387 -298.793805) (xy 348.447435 -298.801559)
			(xy 348.420182 -298.802044) (xy 348.392811 -298.801602) (xy 348.33863 -298.793781) (xy 348.286126 -298.778287)
			(xy 348.23638 -298.755439) (xy 348.190414 -298.725708) (xy 348.169484 -298.708064) (xy 348.162372 -298.701968)
			(xy 348.145354 -298.695618) (xy 348.06001 -298.695618) (xy 348.042992 -298.701968) (xy 348.03588 -298.708064)
			(xy 348.014924 -298.725673) (xy 347.968958 -298.755391) (xy 347.919217 -298.778233) (xy 347.866721 -298.793731)
			(xy 347.81255 -298.801566) (xy 347.785182 -298.802044) (xy 347.757932 -298.801539) (xy 347.703987 -298.793781)
			(xy 347.651695 -298.778425) (xy 347.60212 -298.755785) (xy 347.556271 -298.72632) (xy 347.515082 -298.690631)
			(xy 347.479391 -298.649443) (xy 347.449924 -298.603596) (xy 347.427281 -298.554022) (xy 347.411923 -298.501731)
			(xy 347.404162 -298.447786) (xy 347.403674 -298.420536) (xy 344.16111 -298.420536) (xy 344.160656 -298.447788)
			(xy 344.152894 -298.501737) (xy 344.137535 -298.554032) (xy 344.11489 -298.603609) (xy 344.08542 -298.649459)
			(xy 344.049725 -298.690649) (xy 344.008532 -298.72634) (xy 343.962679 -298.755806) (xy 343.9131 -298.778447)
			(xy 343.860804 -298.793802) (xy 343.806854 -298.801558) (xy 343.779602 -298.802044) (xy 343.752231 -298.80159)
			(xy 343.698051 -298.793772) (xy 343.645547 -298.77828) (xy 343.595801 -298.755436) (xy 343.549835 -298.725707)
			(xy 343.528904 -298.708064) (xy 343.521792 -298.701968) (xy 343.504774 -298.695618) (xy 343.41943 -298.695618)
			(xy 343.402412 -298.701968) (xy 343.3953 -298.708064) (xy 343.374374 -298.725711) (xy 343.3284 -298.755423)
			(xy 343.278651 -298.778258) (xy 343.226149 -298.793747) (xy 343.171972 -298.801572) (xy 343.144602 -298.802044)
			(xy 343.117352 -298.80152) (xy 343.063408 -298.793765) (xy 343.011116 -298.778412) (xy 342.961541 -298.755774)
			(xy 342.915693 -298.726311) (xy 342.874503 -298.690624) (xy 342.838812 -298.649438) (xy 342.809344 -298.603592)
			(xy 342.786701 -298.55402) (xy 342.771343 -298.501729) (xy 342.763582 -298.447786) (xy 342.763094 -298.420536)
			(xy 341.733378 -298.420536) (xy 341.732956 -298.44779) (xy 341.725193 -298.501741) (xy 341.709832 -298.554039)
			(xy 341.687185 -298.603618) (xy 341.657712 -298.64947) (xy 341.622014 -298.69066) (xy 341.580817 -298.726351)
			(xy 341.53496 -298.755816) (xy 341.485377 -298.778455) (xy 341.433076 -298.793807) (xy 341.379124 -298.80156)
			(xy 341.35187 -298.802044) (xy 341.324498 -298.801609) (xy 341.270318 -298.793786) (xy 341.217814 -298.77829)
			(xy 341.168067 -298.755441) (xy 341.122102 -298.725709) (xy 341.101172 -298.708064) (xy 341.09406 -298.701968)
			(xy 341.077042 -298.695618) (xy 340.991698 -298.695618) (xy 340.97468 -298.701968) (xy 340.967568 -298.708064)
			(xy 340.946616 -298.725679) (xy 340.90065 -298.755396) (xy 340.850907 -298.778237) (xy 340.798411 -298.793733)
			(xy 340.744238 -298.801567) (xy 340.71687 -298.802044) (xy 340.68962 -298.80155) (xy 340.635674 -298.793791)
			(xy 340.583382 -298.778433) (xy 340.533807 -298.755791) (xy 340.487958 -298.726325) (xy 340.446769 -298.690635)
			(xy 340.411078 -298.649447) (xy 340.381611 -298.603599) (xy 340.358969 -298.554024) (xy 340.343611 -298.501732)
			(xy 340.33585 -298.447786) (xy 340.335362 -298.420536) (xy 337.092798 -298.420536) (xy 337.092356 -298.447789)
			(xy 337.084594 -298.501738) (xy 337.069234 -298.554035) (xy 337.046588 -298.603613) (xy 337.017117 -298.649463)
			(xy 336.981421 -298.690653) (xy 336.940226 -298.726344) (xy 336.894372 -298.75581) (xy 336.844791 -298.77845)
			(xy 336.792493 -298.793804) (xy 336.738543 -298.801559) (xy 336.71129 -298.802044) (xy 336.683919 -298.801597)
			(xy 336.629738 -298.793777) (xy 336.577235 -298.778284) (xy 336.527488 -298.755438) (xy 336.481523 -298.725708)
			(xy 336.460592 -298.708064) (xy 336.45348 -298.701968) (xy 336.436462 -298.695618) (xy 336.351118 -298.695618)
			(xy 336.3341 -298.701968) (xy 336.326988 -298.708064) (xy 336.306029 -298.72567) (xy 336.260064 -298.755388)
			(xy 336.210324 -298.778231) (xy 336.157829 -298.79373) (xy 336.103657 -298.801566) (xy 336.07629 -298.802044)
			(xy 336.04904 -298.801532) (xy 335.995095 -298.793775) (xy 335.942803 -298.77842) (xy 335.893228 -298.75578)
			(xy 335.84738 -298.726316) (xy 335.806191 -298.690628) (xy 335.770499 -298.649441) (xy 335.741032 -298.603595)
			(xy 335.718389 -298.554021) (xy 335.703031 -298.50173) (xy 335.69527 -298.447786) (xy 335.694782 -298.420536)
			(xy 319.338337 -298.420536) (xy 319.344521 -298.425682) (xy 319.381738 -298.467219) (xy 319.412511 -298.513732)
			(xy 319.436183 -298.564229) (xy 319.452251 -298.617636) (xy 319.460371 -298.672812) (xy 319.46088 -298.700698)
			(xy 319.460371 -298.728584) (xy 319.452251 -298.78376) (xy 319.436183 -298.837167) (xy 319.412511 -298.887664)
			(xy 319.381738 -298.934177) (xy 319.344521 -298.975714) (xy 319.301653 -299.011389) (xy 319.254047 -299.040443)
			(xy 319.202718 -299.062255) (xy 319.148761 -299.076361) (xy 319.093324 -299.082461) (xy 319.03759 -299.080424)
			(xy 318.982747 -299.070294) (xy 318.929963 -299.052287) (xy 318.880363 -299.026786) (xy 318.835005 -298.994335)
			(xy 318.794856 -298.955626) (xy 318.76077 -298.911483) (xy 318.733474 -298.862848) (xy 318.713551 -298.810757)
			(xy 318.701425 -298.75632) (xy 318.697354 -298.700698) (xy 279.41397 -298.700698) (xy 279.41397 -299.224954)
			(xy 279.668998 -299.224954) (xy 279.672958 -299.1759) (xy 279.684735 -299.128116) (xy 279.704026 -299.08284)
			(xy 279.730329 -299.041244) (xy 279.762964 -299.004407) (xy 279.801085 -298.973282) (xy 279.843706 -298.948675)
			(xy 279.889722 -298.931223) (xy 279.937941 -298.921379) (xy 279.987116 -298.919398) (xy 280.035971 -298.92533)
			(xy 280.083242 -298.939022) (xy 280.127704 -298.96012) (xy 280.168207 -298.988076) (xy 280.2037 -299.022168)
			(xy 280.233265 -299.061512) (xy 280.256136 -299.105089) (xy 280.27172 -299.15177) (xy 280.279615 -299.200347)
			(xy 280.28011 -299.224954) (xy 280.618958 -299.224954) (xy 280.622918 -299.1759) (xy 280.634695 -299.128116)
			(xy 280.653986 -299.08284) (xy 280.680289 -299.041244) (xy 280.712924 -299.004407) (xy 280.751045 -298.973282)
			(xy 280.793666 -298.948675) (xy 280.839682 -298.931223) (xy 280.887901 -298.921379) (xy 280.937076 -298.919398)
			(xy 280.985931 -298.92533) (xy 281.033202 -298.939022) (xy 281.077664 -298.96012) (xy 281.118167 -298.988076)
			(xy 281.15366 -299.022168) (xy 281.183225 -299.061512) (xy 281.206096 -299.105089) (xy 281.22168 -299.15177)
			(xy 281.229575 -299.200347) (xy 281.23007 -299.224954) (xy 281.568918 -299.224954) (xy 281.572878 -299.1759)
			(xy 281.584655 -299.128116) (xy 281.603946 -299.08284) (xy 281.630249 -299.041244) (xy 281.662884 -299.004407)
			(xy 281.701005 -298.973282) (xy 281.743626 -298.948675) (xy 281.789642 -298.931223) (xy 281.837861 -298.921379)
			(xy 281.887036 -298.919398) (xy 281.935891 -298.92533) (xy 281.983162 -298.939022) (xy 282.027624 -298.96012)
			(xy 282.068127 -298.988076) (xy 282.10362 -299.022168) (xy 282.133185 -299.061512) (xy 282.156056 -299.105089)
			(xy 282.17164 -299.15177) (xy 282.179535 -299.200347) (xy 282.18003 -299.224954) (xy 300.56888 -299.224954)
			(xy 300.57284 -299.1759) (xy 300.584617 -299.128116) (xy 300.603908 -299.08284) (xy 300.630211 -299.041244)
			(xy 300.662846 -299.004407) (xy 300.700967 -298.973282) (xy 300.743588 -298.948675) (xy 300.789604 -298.931223)
			(xy 300.837823 -298.921379) (xy 300.886998 -298.919398) (xy 300.935853 -298.92533) (xy 300.983124 -298.939022)
			(xy 301.027586 -298.96012) (xy 301.068089 -298.988076) (xy 301.103582 -299.022168) (xy 301.133147 -299.061512)
			(xy 301.156018 -299.105089) (xy 301.171602 -299.15177) (xy 301.179497 -299.200347) (xy 301.179992 -299.224954)
			(xy 301.519094 -299.224954) (xy 301.523054 -299.1759) (xy 301.534831 -299.128116) (xy 301.554122 -299.08284)
			(xy 301.580425 -299.041244) (xy 301.61306 -299.004407) (xy 301.651181 -298.973282) (xy 301.693802 -298.948675)
			(xy 301.739818 -298.931223) (xy 301.788037 -298.921379) (xy 301.837212 -298.919398) (xy 301.886067 -298.92533)
			(xy 301.933338 -298.939022) (xy 301.9778 -298.96012) (xy 302.018303 -298.988076) (xy 302.053796 -299.022168)
			(xy 302.083361 -299.061512) (xy 302.106232 -299.105089) (xy 302.121816 -299.15177) (xy 302.129711 -299.200347)
			(xy 302.130206 -299.224954) (xy 302.469054 -299.224954) (xy 302.473014 -299.1759) (xy 302.484791 -299.128116)
			(xy 302.504082 -299.08284) (xy 302.530385 -299.041244) (xy 302.56302 -299.004407) (xy 302.601141 -298.973282)
			(xy 302.643762 -298.948675) (xy 302.689778 -298.931223) (xy 302.737997 -298.921379) (xy 302.787172 -298.919398)
			(xy 302.836027 -298.92533) (xy 302.883298 -298.939022) (xy 302.92776 -298.96012) (xy 302.968263 -298.988076)
			(xy 303.003756 -299.022168) (xy 303.033321 -299.061512) (xy 303.056192 -299.105089) (xy 303.071776 -299.15177)
			(xy 303.079671 -299.200347) (xy 303.080166 -299.224954) (xy 303.419014 -299.224954) (xy 303.422974 -299.1759)
			(xy 303.434751 -299.128116) (xy 303.454042 -299.08284) (xy 303.480345 -299.041244) (xy 303.51298 -299.004407)
			(xy 303.551101 -298.973282) (xy 303.593722 -298.948675) (xy 303.639738 -298.931223) (xy 303.687957 -298.921379)
			(xy 303.737132 -298.919398) (xy 303.785987 -298.92533) (xy 303.833258 -298.939022) (xy 303.87772 -298.96012)
			(xy 303.918223 -298.988076) (xy 303.953716 -299.022168) (xy 303.983281 -299.061512) (xy 304.006152 -299.105089)
			(xy 304.021736 -299.15177) (xy 304.029631 -299.200347) (xy 304.030126 -299.224954) (xy 304.368974 -299.224954)
			(xy 304.372934 -299.1759) (xy 304.384711 -299.128116) (xy 304.404002 -299.08284) (xy 304.430305 -299.041244)
			(xy 304.46294 -299.004407) (xy 304.501061 -298.973282) (xy 304.543682 -298.948675) (xy 304.589698 -298.931223)
			(xy 304.637917 -298.921379) (xy 304.687092 -298.919398) (xy 304.735947 -298.92533) (xy 304.783218 -298.939022)
			(xy 304.82768 -298.96012) (xy 304.868183 -298.988076) (xy 304.903676 -299.022168) (xy 304.933241 -299.061512)
			(xy 304.956112 -299.105089) (xy 304.971696 -299.15177) (xy 304.979591 -299.200347) (xy 304.980086 -299.224954)
			(xy 305.318934 -299.224954) (xy 305.322894 -299.1759) (xy 305.334671 -299.128116) (xy 305.353962 -299.08284)
			(xy 305.380265 -299.041244) (xy 305.4129 -299.004407) (xy 305.451021 -298.973282) (xy 305.493642 -298.948675)
			(xy 305.539658 -298.931223) (xy 305.587877 -298.921379) (xy 305.637052 -298.919398) (xy 305.685907 -298.92533)
			(xy 305.733178 -298.939022) (xy 305.77764 -298.96012) (xy 305.818143 -298.988076) (xy 305.853636 -299.022168)
			(xy 305.883201 -299.061512) (xy 305.906072 -299.105089) (xy 305.921656 -299.15177) (xy 305.929551 -299.200347)
			(xy 305.930046 -299.224954) (xy 308.169068 -299.224954) (xy 308.173028 -299.1759) (xy 308.184805 -299.128116)
			(xy 308.204096 -299.08284) (xy 308.230399 -299.041244) (xy 308.263034 -299.004407) (xy 308.301155 -298.973282)
			(xy 308.343776 -298.948675) (xy 308.389792 -298.931223) (xy 308.438011 -298.921379) (xy 308.487186 -298.919398)
			(xy 308.536041 -298.92533) (xy 308.583312 -298.939022) (xy 308.627774 -298.96012) (xy 308.668277 -298.988076)
			(xy 308.70377 -299.022168) (xy 308.733335 -299.061512) (xy 308.756206 -299.105089) (xy 308.77179 -299.15177)
			(xy 308.779685 -299.200347) (xy 308.78018 -299.224954) (xy 309.119028 -299.224954) (xy 309.122988 -299.1759)
			(xy 309.134765 -299.128116) (xy 309.154056 -299.08284) (xy 309.180359 -299.041244) (xy 309.212994 -299.004407)
			(xy 309.251115 -298.973282) (xy 309.293736 -298.948675) (xy 309.339752 -298.931223) (xy 309.387971 -298.921379)
			(xy 309.437146 -298.919398) (xy 309.486001 -298.92533) (xy 309.533272 -298.939022) (xy 309.577734 -298.96012)
			(xy 309.618237 -298.988076) (xy 309.65373 -299.022168) (xy 309.683295 -299.061512) (xy 309.706166 -299.105089)
			(xy 309.72175 -299.15177) (xy 309.729645 -299.200347) (xy 309.73014 -299.224954) (xy 310.068988 -299.224954)
			(xy 310.072948 -299.1759) (xy 310.084725 -299.128116) (xy 310.104016 -299.08284) (xy 310.130319 -299.041244)
			(xy 310.162954 -299.004407) (xy 310.201075 -298.973282) (xy 310.243696 -298.948675) (xy 310.289712 -298.931223)
			(xy 310.337931 -298.921379) (xy 310.387106 -298.919398) (xy 310.435961 -298.92533) (xy 310.483232 -298.939022)
			(xy 310.527694 -298.96012) (xy 310.568197 -298.988076) (xy 310.60369 -299.022168) (xy 310.633255 -299.061512)
			(xy 310.656126 -299.105089) (xy 310.67171 -299.15177) (xy 310.679605 -299.200347) (xy 310.6801 -299.224954)
			(xy 311.018948 -299.224954) (xy 311.022908 -299.1759) (xy 311.034685 -299.128116) (xy 311.053976 -299.08284)
			(xy 311.080279 -299.041244) (xy 311.112914 -299.004407) (xy 311.151035 -298.973282) (xy 311.193656 -298.948675)
			(xy 311.239672 -298.931223) (xy 311.287891 -298.921379) (xy 311.337066 -298.919398) (xy 311.385921 -298.92533)
			(xy 311.433192 -298.939022) (xy 311.477654 -298.96012) (xy 311.518157 -298.988076) (xy 311.55365 -299.022168)
			(xy 311.583215 -299.061512) (xy 311.606086 -299.105089) (xy 311.62167 -299.15177) (xy 311.629565 -299.200347)
			(xy 311.63006 -299.224954) (xy 311.968908 -299.224954) (xy 311.972868 -299.1759) (xy 311.984645 -299.128116)
			(xy 312.003936 -299.08284) (xy 312.030239 -299.041244) (xy 312.062874 -299.004407) (xy 312.100995 -298.973282)
			(xy 312.143616 -298.948675) (xy 312.189632 -298.931223) (xy 312.237851 -298.921379) (xy 312.287026 -298.919398)
			(xy 312.335881 -298.92533) (xy 312.383152 -298.939022) (xy 312.427614 -298.96012) (xy 312.468117 -298.988076)
			(xy 312.50361 -299.022168) (xy 312.533175 -299.061512) (xy 312.556046 -299.105089) (xy 312.57163 -299.15177)
			(xy 312.579525 -299.200347) (xy 312.58002 -299.224954) (xy 312.919122 -299.224954) (xy 312.923082 -299.1759)
			(xy 312.934859 -299.128116) (xy 312.95415 -299.08284) (xy 312.980453 -299.041244) (xy 313.013088 -299.004407)
			(xy 313.051209 -298.973282) (xy 313.09383 -298.948675) (xy 313.139846 -298.931223) (xy 313.188065 -298.921379)
			(xy 313.23724 -298.919398) (xy 313.286095 -298.92533) (xy 313.333366 -298.939022) (xy 313.377828 -298.96012)
			(xy 313.418331 -298.988076) (xy 313.453824 -299.022168) (xy 313.483389 -299.061512) (xy 313.50626 -299.105089)
			(xy 313.521844 -299.15177) (xy 313.529739 -299.200347) (xy 313.530234 -299.224954) (xy 313.869082 -299.224954)
			(xy 313.873042 -299.1759) (xy 313.884819 -299.128116) (xy 313.90411 -299.08284) (xy 313.930413 -299.041244)
			(xy 313.963048 -299.004407) (xy 314.001169 -298.973282) (xy 314.04379 -298.948675) (xy 314.089806 -298.931223)
			(xy 314.138025 -298.921379) (xy 314.1872 -298.919398) (xy 314.236055 -298.92533) (xy 314.283326 -298.939022)
			(xy 314.327788 -298.96012) (xy 314.368291 -298.988076) (xy 314.403784 -299.022168) (xy 314.433349 -299.061512)
			(xy 314.45622 -299.105089) (xy 314.471804 -299.15177) (xy 314.479699 -299.200347) (xy 314.480194 -299.224954)
			(xy 314.819042 -299.224954) (xy 314.823002 -299.1759) (xy 314.834779 -299.128116) (xy 314.85407 -299.08284)
			(xy 314.880373 -299.041244) (xy 314.913008 -299.004407) (xy 314.951129 -298.973282) (xy 314.99375 -298.948675)
			(xy 315.039766 -298.931223) (xy 315.087985 -298.921379) (xy 315.13716 -298.919398) (xy 315.186015 -298.92533)
			(xy 315.233286 -298.939022) (xy 315.277748 -298.96012) (xy 315.318251 -298.988076) (xy 315.353744 -299.022168)
			(xy 315.383309 -299.061512) (xy 315.40618 -299.105089) (xy 315.421764 -299.15177) (xy 315.429659 -299.200347)
			(xy 315.430154 -299.224954) (xy 315.429659 -299.249561) (xy 315.425856 -299.27296) (xy 322.514466 -299.27296)
			(xy 322.518537 -299.217338) (xy 322.530663 -299.162901) (xy 322.550586 -299.11081) (xy 322.577882 -299.062175)
			(xy 322.611968 -299.018032) (xy 322.652117 -298.979323) (xy 322.697475 -298.946872) (xy 322.747075 -298.921371)
			(xy 322.799859 -298.903364) (xy 322.854702 -298.893234) (xy 322.910436 -298.891197) (xy 322.965873 -298.897297)
			(xy 323.01983 -298.911403) (xy 323.071159 -298.933215) (xy 323.118765 -298.962269) (xy 323.161633 -298.997944)
			(xy 323.19885 -299.039481) (xy 323.229623 -299.085994) (xy 323.253295 -299.136491) (xy 323.269363 -299.189898)
			(xy 323.277483 -299.245074) (xy 323.277992 -299.27296) (xy 323.277483 -299.300846) (xy 323.269363 -299.356022)
			(xy 323.253295 -299.409429) (xy 323.229623 -299.459926) (xy 323.19885 -299.506439) (xy 323.161633 -299.547976)
			(xy 323.118765 -299.583651) (xy 323.071159 -299.612705) (xy 323.01983 -299.634517) (xy 322.965873 -299.648623)
			(xy 322.910436 -299.654723) (xy 322.854702 -299.652686) (xy 322.799859 -299.642556) (xy 322.747075 -299.624549)
			(xy 322.697475 -299.599048) (xy 322.652117 -299.566597) (xy 322.611968 -299.527888) (xy 322.577882 -299.483745)
			(xy 322.550586 -299.43511) (xy 322.530663 -299.383019) (xy 322.518537 -299.328582) (xy 322.514466 -299.27296)
			(xy 315.425856 -299.27296) (xy 315.421764 -299.298138) (xy 315.40618 -299.344819) (xy 315.383309 -299.388396)
			(xy 315.353744 -299.42774) (xy 315.318251 -299.461832) (xy 315.277748 -299.489788) (xy 315.233286 -299.510886)
			(xy 315.186015 -299.524578) (xy 315.13716 -299.53051) (xy 315.087985 -299.528529) (xy 315.039766 -299.518685)
			(xy 314.99375 -299.501233) (xy 314.951129 -299.476626) (xy 314.913008 -299.445501) (xy 314.880373 -299.408664)
			(xy 314.85407 -299.367068) (xy 314.834779 -299.321792) (xy 314.823002 -299.274008) (xy 314.819042 -299.224954)
			(xy 314.480194 -299.224954) (xy 314.479699 -299.249561) (xy 314.471804 -299.298138) (xy 314.45622 -299.344819)
			(xy 314.433349 -299.388396) (xy 314.403784 -299.42774) (xy 314.368291 -299.461832) (xy 314.327788 -299.489788)
			(xy 314.283326 -299.510886) (xy 314.236055 -299.524578) (xy 314.1872 -299.53051) (xy 314.138025 -299.528529)
			(xy 314.089806 -299.518685) (xy 314.04379 -299.501233) (xy 314.001169 -299.476626) (xy 313.963048 -299.445501)
			(xy 313.930413 -299.408664) (xy 313.90411 -299.367068) (xy 313.884819 -299.321792) (xy 313.873042 -299.274008)
			(xy 313.869082 -299.224954) (xy 313.530234 -299.224954) (xy 313.529739 -299.249561) (xy 313.521844 -299.298138)
			(xy 313.50626 -299.344819) (xy 313.483389 -299.388396) (xy 313.453824 -299.42774) (xy 313.418331 -299.461832)
			(xy 313.377828 -299.489788) (xy 313.333366 -299.510886) (xy 313.286095 -299.524578) (xy 313.23724 -299.53051)
			(xy 313.188065 -299.528529) (xy 313.139846 -299.518685) (xy 313.09383 -299.501233) (xy 313.051209 -299.476626)
			(xy 313.013088 -299.445501) (xy 312.980453 -299.408664) (xy 312.95415 -299.367068) (xy 312.934859 -299.321792)
			(xy 312.923082 -299.274008) (xy 312.919122 -299.224954) (xy 312.58002 -299.224954) (xy 312.579525 -299.249561)
			(xy 312.57163 -299.298138) (xy 312.556046 -299.344819) (xy 312.533175 -299.388396) (xy 312.50361 -299.42774)
			(xy 312.468117 -299.461832) (xy 312.427614 -299.489788) (xy 312.383152 -299.510886) (xy 312.335881 -299.524578)
			(xy 312.287026 -299.53051) (xy 312.237851 -299.528529) (xy 312.189632 -299.518685) (xy 312.143616 -299.501233)
			(xy 312.100995 -299.476626) (xy 312.062874 -299.445501) (xy 312.030239 -299.408664) (xy 312.003936 -299.367068)
			(xy 311.984645 -299.321792) (xy 311.972868 -299.274008) (xy 311.968908 -299.224954) (xy 311.63006 -299.224954)
			(xy 311.629565 -299.249561) (xy 311.62167 -299.298138) (xy 311.606086 -299.344819) (xy 311.583215 -299.388396)
			(xy 311.55365 -299.42774) (xy 311.518157 -299.461832) (xy 311.477654 -299.489788) (xy 311.433192 -299.510886)
			(xy 311.385921 -299.524578) (xy 311.337066 -299.53051) (xy 311.287891 -299.528529) (xy 311.239672 -299.518685)
			(xy 311.193656 -299.501233) (xy 311.151035 -299.476626) (xy 311.112914 -299.445501) (xy 311.080279 -299.408664)
			(xy 311.053976 -299.367068) (xy 311.034685 -299.321792) (xy 311.022908 -299.274008) (xy 311.018948 -299.224954)
			(xy 310.6801 -299.224954) (xy 310.679605 -299.249561) (xy 310.67171 -299.298138) (xy 310.656126 -299.344819)
			(xy 310.633255 -299.388396) (xy 310.60369 -299.42774) (xy 310.568197 -299.461832) (xy 310.527694 -299.489788)
			(xy 310.483232 -299.510886) (xy 310.435961 -299.524578) (xy 310.387106 -299.53051) (xy 310.337931 -299.528529)
			(xy 310.289712 -299.518685) (xy 310.243696 -299.501233) (xy 310.201075 -299.476626) (xy 310.162954 -299.445501)
			(xy 310.130319 -299.408664) (xy 310.104016 -299.367068) (xy 310.084725 -299.321792) (xy 310.072948 -299.274008)
			(xy 310.068988 -299.224954) (xy 309.73014 -299.224954) (xy 309.729645 -299.249561) (xy 309.72175 -299.298138)
			(xy 309.706166 -299.344819) (xy 309.683295 -299.388396) (xy 309.65373 -299.42774) (xy 309.618237 -299.461832)
			(xy 309.577734 -299.489788) (xy 309.533272 -299.510886) (xy 309.486001 -299.524578) (xy 309.437146 -299.53051)
			(xy 309.387971 -299.528529) (xy 309.339752 -299.518685) (xy 309.293736 -299.501233) (xy 309.251115 -299.476626)
			(xy 309.212994 -299.445501) (xy 309.180359 -299.408664) (xy 309.154056 -299.367068) (xy 309.134765 -299.321792)
			(xy 309.122988 -299.274008) (xy 309.119028 -299.224954) (xy 308.78018 -299.224954) (xy 308.779685 -299.249561)
			(xy 308.77179 -299.298138) (xy 308.756206 -299.344819) (xy 308.733335 -299.388396) (xy 308.70377 -299.42774)
			(xy 308.668277 -299.461832) (xy 308.627774 -299.489788) (xy 308.583312 -299.510886) (xy 308.536041 -299.524578)
			(xy 308.487186 -299.53051) (xy 308.438011 -299.528529) (xy 308.389792 -299.518685) (xy 308.343776 -299.501233)
			(xy 308.301155 -299.476626) (xy 308.263034 -299.445501) (xy 308.230399 -299.408664) (xy 308.204096 -299.367068)
			(xy 308.184805 -299.321792) (xy 308.173028 -299.274008) (xy 308.169068 -299.224954) (xy 305.930046 -299.224954)
			(xy 305.929551 -299.249561) (xy 305.921656 -299.298138) (xy 305.906072 -299.344819) (xy 305.883201 -299.388396)
			(xy 305.853636 -299.42774) (xy 305.818143 -299.461832) (xy 305.77764 -299.489788) (xy 305.733178 -299.510886)
			(xy 305.685907 -299.524578) (xy 305.637052 -299.53051) (xy 305.587877 -299.528529) (xy 305.539658 -299.518685)
			(xy 305.493642 -299.501233) (xy 305.451021 -299.476626) (xy 305.4129 -299.445501) (xy 305.380265 -299.408664)
			(xy 305.353962 -299.367068) (xy 305.334671 -299.321792) (xy 305.322894 -299.274008) (xy 305.318934 -299.224954)
			(xy 304.980086 -299.224954) (xy 304.979591 -299.249561) (xy 304.971696 -299.298138) (xy 304.956112 -299.344819)
			(xy 304.933241 -299.388396) (xy 304.903676 -299.42774) (xy 304.868183 -299.461832) (xy 304.82768 -299.489788)
			(xy 304.783218 -299.510886) (xy 304.735947 -299.524578) (xy 304.687092 -299.53051) (xy 304.637917 -299.528529)
			(xy 304.589698 -299.518685) (xy 304.543682 -299.501233) (xy 304.501061 -299.476626) (xy 304.46294 -299.445501)
			(xy 304.430305 -299.408664) (xy 304.404002 -299.367068) (xy 304.384711 -299.321792) (xy 304.372934 -299.274008)
			(xy 304.368974 -299.224954) (xy 304.030126 -299.224954) (xy 304.029631 -299.249561) (xy 304.021736 -299.298138)
			(xy 304.006152 -299.344819) (xy 303.983281 -299.388396) (xy 303.953716 -299.42774) (xy 303.918223 -299.461832)
			(xy 303.87772 -299.489788) (xy 303.833258 -299.510886) (xy 303.785987 -299.524578) (xy 303.737132 -299.53051)
			(xy 303.687957 -299.528529) (xy 303.639738 -299.518685) (xy 303.593722 -299.501233) (xy 303.551101 -299.476626)
			(xy 303.51298 -299.445501) (xy 303.480345 -299.408664) (xy 303.454042 -299.367068) (xy 303.434751 -299.321792)
			(xy 303.422974 -299.274008) (xy 303.419014 -299.224954) (xy 303.080166 -299.224954) (xy 303.079671 -299.249561)
			(xy 303.071776 -299.298138) (xy 303.056192 -299.344819) (xy 303.033321 -299.388396) (xy 303.003756 -299.42774)
			(xy 302.968263 -299.461832) (xy 302.92776 -299.489788) (xy 302.883298 -299.510886) (xy 302.836027 -299.524578)
			(xy 302.787172 -299.53051) (xy 302.737997 -299.528529) (xy 302.689778 -299.518685) (xy 302.643762 -299.501233)
			(xy 302.601141 -299.476626) (xy 302.56302 -299.445501) (xy 302.530385 -299.408664) (xy 302.504082 -299.367068)
			(xy 302.484791 -299.321792) (xy 302.473014 -299.274008) (xy 302.469054 -299.224954) (xy 302.130206 -299.224954)
			(xy 302.129711 -299.249561) (xy 302.121816 -299.298138) (xy 302.106232 -299.344819) (xy 302.083361 -299.388396)
			(xy 302.053796 -299.42774) (xy 302.018303 -299.461832) (xy 301.9778 -299.489788) (xy 301.933338 -299.510886)
			(xy 301.886067 -299.524578) (xy 301.837212 -299.53051) (xy 301.788037 -299.528529) (xy 301.739818 -299.518685)
			(xy 301.693802 -299.501233) (xy 301.651181 -299.476626) (xy 301.61306 -299.445501) (xy 301.580425 -299.408664)
			(xy 301.554122 -299.367068) (xy 301.534831 -299.321792) (xy 301.523054 -299.274008) (xy 301.519094 -299.224954)
			(xy 301.179992 -299.224954) (xy 301.179497 -299.249561) (xy 301.171602 -299.298138) (xy 301.156018 -299.344819)
			(xy 301.133147 -299.388396) (xy 301.103582 -299.42774) (xy 301.068089 -299.461832) (xy 301.027586 -299.489788)
			(xy 300.983124 -299.510886) (xy 300.935853 -299.524578) (xy 300.886998 -299.53051) (xy 300.837823 -299.528529)
			(xy 300.789604 -299.518685) (xy 300.743588 -299.501233) (xy 300.700967 -299.476626) (xy 300.662846 -299.445501)
			(xy 300.630211 -299.408664) (xy 300.603908 -299.367068) (xy 300.584617 -299.321792) (xy 300.57284 -299.274008)
			(xy 300.56888 -299.224954) (xy 282.18003 -299.224954) (xy 282.179535 -299.249561) (xy 282.17164 -299.298138)
			(xy 282.156056 -299.344819) (xy 282.133185 -299.388396) (xy 282.10362 -299.42774) (xy 282.068127 -299.461832)
			(xy 282.027624 -299.489788) (xy 281.983162 -299.510886) (xy 281.935891 -299.524578) (xy 281.887036 -299.53051)
			(xy 281.837861 -299.528529) (xy 281.789642 -299.518685) (xy 281.743626 -299.501233) (xy 281.701005 -299.476626)
			(xy 281.662884 -299.445501) (xy 281.630249 -299.408664) (xy 281.603946 -299.367068) (xy 281.584655 -299.321792)
			(xy 281.572878 -299.274008) (xy 281.568918 -299.224954) (xy 281.23007 -299.224954) (xy 281.229575 -299.249561)
			(xy 281.22168 -299.298138) (xy 281.206096 -299.344819) (xy 281.183225 -299.388396) (xy 281.15366 -299.42774)
			(xy 281.118167 -299.461832) (xy 281.077664 -299.489788) (xy 281.033202 -299.510886) (xy 280.985931 -299.524578)
			(xy 280.937076 -299.53051) (xy 280.887901 -299.528529) (xy 280.839682 -299.518685) (xy 280.793666 -299.501233)
			(xy 280.751045 -299.476626) (xy 280.712924 -299.445501) (xy 280.680289 -299.408664) (xy 280.653986 -299.367068)
			(xy 280.634695 -299.321792) (xy 280.622918 -299.274008) (xy 280.618958 -299.224954) (xy 280.28011 -299.224954)
			(xy 280.279615 -299.249561) (xy 280.27172 -299.298138) (xy 280.256136 -299.344819) (xy 280.233265 -299.388396)
			(xy 280.2037 -299.42774) (xy 280.168207 -299.461832) (xy 280.127704 -299.489788) (xy 280.083242 -299.510886)
			(xy 280.035971 -299.524578) (xy 279.987116 -299.53051) (xy 279.937941 -299.528529) (xy 279.889722 -299.518685)
			(xy 279.843706 -299.501233) (xy 279.801085 -299.476626) (xy 279.762964 -299.445501) (xy 279.730329 -299.408664)
			(xy 279.704026 -299.367068) (xy 279.684735 -299.321792) (xy 279.672958 -299.274008) (xy 279.668998 -299.224954)
			(xy 279.41397 -299.224954) (xy 279.41397 -299.76445) (xy 320.241674 -299.76445) (xy 320.245745 -299.708828)
			(xy 320.257871 -299.654391) (xy 320.277794 -299.6023) (xy 320.30509 -299.553665) (xy 320.339176 -299.509522)
			(xy 320.379325 -299.470813) (xy 320.424683 -299.438362) (xy 320.474283 -299.412861) (xy 320.527067 -299.394854)
			(xy 320.58191 -299.384724) (xy 320.637644 -299.382687) (xy 320.693081 -299.388787) (xy 320.747038 -299.402893)
			(xy 320.798367 -299.424705) (xy 320.845973 -299.453759) (xy 320.888841 -299.489434) (xy 320.926058 -299.530971)
			(xy 320.956831 -299.577484) (xy 320.980503 -299.627981) (xy 320.996571 -299.681388) (xy 321.004691 -299.736564)
			(xy 321.0052 -299.76445) (xy 321.004922 -299.77969) (xy 324.838312 -299.77969) (xy 324.842383 -299.724068)
			(xy 324.854509 -299.669631) (xy 324.874432 -299.61754) (xy 324.901728 -299.568905) (xy 324.935814 -299.524762)
			(xy 324.975963 -299.486053) (xy 325.021321 -299.453602) (xy 325.070921 -299.428101) (xy 325.123705 -299.410094)
			(xy 325.178548 -299.399964) (xy 325.234282 -299.397927) (xy 325.289719 -299.404027) (xy 325.343676 -299.418133)
			(xy 325.395005 -299.439945) (xy 325.442611 -299.468999) (xy 325.485479 -299.504674) (xy 325.522696 -299.546211)
			(xy 325.553469 -299.592724) (xy 325.577141 -299.643221) (xy 325.593209 -299.696628) (xy 325.601329 -299.751804)
			(xy 325.601838 -299.77969) (xy 325.601329 -299.807576) (xy 325.593209 -299.862752) (xy 325.577141 -299.916159)
			(xy 325.553469 -299.966656) (xy 325.522696 -300.013169) (xy 325.485479 -300.054706) (xy 325.442611 -300.090381)
			(xy 325.395005 -300.119435) (xy 325.343676 -300.141247) (xy 325.289719 -300.155353) (xy 325.234282 -300.161453)
			(xy 325.178548 -300.159416) (xy 325.123705 -300.149286) (xy 325.070921 -300.131279) (xy 325.021321 -300.105778)
			(xy 324.975963 -300.073327) (xy 324.935814 -300.034618) (xy 324.901728 -299.990475) (xy 324.874432 -299.94184)
			(xy 324.854509 -299.889749) (xy 324.842383 -299.835312) (xy 324.838312 -299.77969) (xy 321.004922 -299.77969)
			(xy 321.004691 -299.792336) (xy 320.996571 -299.847512) (xy 320.980503 -299.900919) (xy 320.956831 -299.951416)
			(xy 320.926058 -299.997929) (xy 320.888841 -300.039466) (xy 320.845973 -300.075141) (xy 320.798367 -300.104195)
			(xy 320.747038 -300.126007) (xy 320.693081 -300.140113) (xy 320.637644 -300.146213) (xy 320.58191 -300.144176)
			(xy 320.527067 -300.134046) (xy 320.474283 -300.116039) (xy 320.424683 -300.090538) (xy 320.379325 -300.058087)
			(xy 320.339176 -300.019378) (xy 320.30509 -299.975235) (xy 320.277794 -299.9266) (xy 320.257871 -299.874509)
			(xy 320.245745 -299.820072) (xy 320.241674 -299.76445) (xy 279.41397 -299.76445) (xy 279.41397 -300.174914)
			(xy 279.668998 -300.174914) (xy 279.672958 -300.12586) (xy 279.684735 -300.078076) (xy 279.704026 -300.0328)
			(xy 279.730329 -299.991204) (xy 279.762964 -299.954367) (xy 279.801085 -299.923242) (xy 279.843706 -299.898635)
			(xy 279.889722 -299.881183) (xy 279.937941 -299.871339) (xy 279.987116 -299.869358) (xy 280.035971 -299.87529)
			(xy 280.083242 -299.888982) (xy 280.127704 -299.91008) (xy 280.168207 -299.938036) (xy 280.2037 -299.972128)
			(xy 280.233265 -300.011472) (xy 280.256136 -300.055049) (xy 280.27172 -300.10173) (xy 280.279615 -300.150307)
			(xy 280.28011 -300.174914) (xy 280.618958 -300.174914) (xy 280.622918 -300.12586) (xy 280.634695 -300.078076)
			(xy 280.653986 -300.0328) (xy 280.680289 -299.991204) (xy 280.712924 -299.954367) (xy 280.751045 -299.923242)
			(xy 280.793666 -299.898635) (xy 280.839682 -299.881183) (xy 280.887901 -299.871339) (xy 280.937076 -299.869358)
			(xy 280.985931 -299.87529) (xy 281.033202 -299.888982) (xy 281.077664 -299.91008) (xy 281.118167 -299.938036)
			(xy 281.15366 -299.972128) (xy 281.183225 -300.011472) (xy 281.206096 -300.055049) (xy 281.22168 -300.10173)
			(xy 281.229575 -300.150307) (xy 281.23007 -300.174914) (xy 281.568918 -300.174914) (xy 281.572878 -300.12586)
			(xy 281.584655 -300.078076) (xy 281.603946 -300.0328) (xy 281.630249 -299.991204) (xy 281.662884 -299.954367)
			(xy 281.701005 -299.923242) (xy 281.743626 -299.898635) (xy 281.789642 -299.881183) (xy 281.837861 -299.871339)
			(xy 281.887036 -299.869358) (xy 281.935891 -299.87529) (xy 281.983162 -299.888982) (xy 282.027624 -299.91008)
			(xy 282.068127 -299.938036) (xy 282.10362 -299.972128) (xy 282.133185 -300.011472) (xy 282.156056 -300.055049)
			(xy 282.17164 -300.10173) (xy 282.179535 -300.150307) (xy 282.18003 -300.174914) (xy 282.519132 -300.174914)
			(xy 282.523092 -300.12586) (xy 282.534869 -300.078076) (xy 282.55416 -300.0328) (xy 282.580463 -299.991204)
			(xy 282.613098 -299.954367) (xy 282.651219 -299.923242) (xy 282.69384 -299.898635) (xy 282.739856 -299.881183)
			(xy 282.788075 -299.871339) (xy 282.83725 -299.869358) (xy 282.886105 -299.87529) (xy 282.933376 -299.888982)
			(xy 282.977838 -299.91008) (xy 283.018341 -299.938036) (xy 283.053834 -299.972128) (xy 283.083399 -300.011472)
			(xy 283.10627 -300.055049) (xy 283.121854 -300.10173) (xy 283.129749 -300.150307) (xy 283.130244 -300.174914)
			(xy 283.469092 -300.174914) (xy 283.473052 -300.12586) (xy 283.484829 -300.078076) (xy 283.50412 -300.0328)
			(xy 283.530423 -299.991204) (xy 283.563058 -299.954367) (xy 283.601179 -299.923242) (xy 283.6438 -299.898635)
			(xy 283.689816 -299.881183) (xy 283.738035 -299.871339) (xy 283.78721 -299.869358) (xy 283.836065 -299.87529)
			(xy 283.883336 -299.888982) (xy 283.927798 -299.91008) (xy 283.968301 -299.938036) (xy 284.003794 -299.972128)
			(xy 284.033359 -300.011472) (xy 284.05623 -300.055049) (xy 284.071814 -300.10173) (xy 284.079709 -300.150307)
			(xy 284.080204 -300.174914) (xy 284.419052 -300.174914) (xy 284.423012 -300.12586) (xy 284.434789 -300.078076)
			(xy 284.45408 -300.0328) (xy 284.480383 -299.991204) (xy 284.513018 -299.954367) (xy 284.551139 -299.923242)
			(xy 284.59376 -299.898635) (xy 284.639776 -299.881183) (xy 284.687995 -299.871339) (xy 284.73717 -299.869358)
			(xy 284.786025 -299.87529) (xy 284.833296 -299.888982) (xy 284.877758 -299.91008) (xy 284.918261 -299.938036)
			(xy 284.953754 -299.972128) (xy 284.983319 -300.011472) (xy 285.00619 -300.055049) (xy 285.021774 -300.10173)
			(xy 285.029669 -300.150307) (xy 285.030164 -300.174914) (xy 285.369012 -300.174914) (xy 285.372972 -300.12586)
			(xy 285.384749 -300.078076) (xy 285.40404 -300.0328) (xy 285.430343 -299.991204) (xy 285.462978 -299.954367)
			(xy 285.501099 -299.923242) (xy 285.54372 -299.898635) (xy 285.589736 -299.881183) (xy 285.637955 -299.871339)
			(xy 285.68713 -299.869358) (xy 285.735985 -299.87529) (xy 285.783256 -299.888982) (xy 285.827718 -299.91008)
			(xy 285.868221 -299.938036) (xy 285.903714 -299.972128) (xy 285.933279 -300.011472) (xy 285.95615 -300.055049)
			(xy 285.971734 -300.10173) (xy 285.979629 -300.150307) (xy 285.980124 -300.174914) (xy 286.318972 -300.174914)
			(xy 286.322932 -300.12586) (xy 286.334709 -300.078076) (xy 286.354 -300.0328) (xy 286.380303 -299.991204)
			(xy 286.412938 -299.954367) (xy 286.451059 -299.923242) (xy 286.49368 -299.898635) (xy 286.539696 -299.881183)
			(xy 286.587915 -299.871339) (xy 286.63709 -299.869358) (xy 286.685945 -299.87529) (xy 286.733216 -299.888982)
			(xy 286.777678 -299.91008) (xy 286.818181 -299.938036) (xy 286.853674 -299.972128) (xy 286.883239 -300.011472)
			(xy 286.90611 -300.055049) (xy 286.921694 -300.10173) (xy 286.929589 -300.150307) (xy 286.930084 -300.174914)
			(xy 287.268932 -300.174914) (xy 287.272892 -300.12586) (xy 287.284669 -300.078076) (xy 287.30396 -300.0328)
			(xy 287.330263 -299.991204) (xy 287.362898 -299.954367) (xy 287.401019 -299.923242) (xy 287.44364 -299.898635)
			(xy 287.489656 -299.881183) (xy 287.537875 -299.871339) (xy 287.58705 -299.869358) (xy 287.635905 -299.87529)
			(xy 287.683176 -299.888982) (xy 287.727638 -299.91008) (xy 287.768141 -299.938036) (xy 287.803634 -299.972128)
			(xy 287.833199 -300.011472) (xy 287.85607 -300.055049) (xy 287.871654 -300.10173) (xy 287.879549 -300.150307)
			(xy 287.880044 -300.174914) (xy 288.218892 -300.174914) (xy 288.222852 -300.12586) (xy 288.234629 -300.078076)
			(xy 288.25392 -300.0328) (xy 288.280223 -299.991204) (xy 288.312858 -299.954367) (xy 288.350979 -299.923242)
			(xy 288.3936 -299.898635) (xy 288.439616 -299.881183) (xy 288.487835 -299.871339) (xy 288.53701 -299.869358)
			(xy 288.585865 -299.87529) (xy 288.633136 -299.888982) (xy 288.677598 -299.91008) (xy 288.718101 -299.938036)
			(xy 288.753594 -299.972128) (xy 288.783159 -300.011472) (xy 288.80603 -300.055049) (xy 288.821614 -300.10173)
			(xy 288.829509 -300.150307) (xy 288.830004 -300.174914) (xy 289.169106 -300.174914) (xy 289.173066 -300.12586)
			(xy 289.184843 -300.078076) (xy 289.204134 -300.0328) (xy 289.230437 -299.991204) (xy 289.263072 -299.954367)
			(xy 289.301193 -299.923242) (xy 289.343814 -299.898635) (xy 289.38983 -299.881183) (xy 289.438049 -299.871339)
			(xy 289.487224 -299.869358) (xy 289.536079 -299.87529) (xy 289.58335 -299.888982) (xy 289.627812 -299.91008)
			(xy 289.668315 -299.938036) (xy 289.703808 -299.972128) (xy 289.733373 -300.011472) (xy 289.756244 -300.055049)
			(xy 289.771828 -300.10173) (xy 289.779723 -300.150307) (xy 289.780218 -300.174914) (xy 290.119066 -300.174914)
			(xy 290.123026 -300.12586) (xy 290.134803 -300.078076) (xy 290.154094 -300.0328) (xy 290.180397 -299.991204)
			(xy 290.213032 -299.954367) (xy 290.251153 -299.923242) (xy 290.293774 -299.898635) (xy 290.33979 -299.881183)
			(xy 290.388009 -299.871339) (xy 290.437184 -299.869358) (xy 290.486039 -299.87529) (xy 290.53331 -299.888982)
			(xy 290.577772 -299.91008) (xy 290.618275 -299.938036) (xy 290.653768 -299.972128) (xy 290.683333 -300.011472)
			(xy 290.706204 -300.055049) (xy 290.721788 -300.10173) (xy 290.729683 -300.150307) (xy 290.730178 -300.174914)
			(xy 292.018986 -300.174914) (xy 292.022946 -300.12586) (xy 292.034723 -300.078076) (xy 292.054014 -300.0328)
			(xy 292.080317 -299.991204) (xy 292.112952 -299.954367) (xy 292.151073 -299.923242) (xy 292.193694 -299.898635)
			(xy 292.23971 -299.881183) (xy 292.287929 -299.871339) (xy 292.337104 -299.869358) (xy 292.385959 -299.87529)
			(xy 292.43323 -299.888982) (xy 292.477692 -299.91008) (xy 292.518195 -299.938036) (xy 292.553688 -299.972128)
			(xy 292.583253 -300.011472) (xy 292.606124 -300.055049) (xy 292.621708 -300.10173) (xy 292.629603 -300.150307)
			(xy 292.630098 -300.174914) (xy 292.968946 -300.174914) (xy 292.972906 -300.12586) (xy 292.984683 -300.078076)
			(xy 293.003974 -300.0328) (xy 293.030277 -299.991204) (xy 293.062912 -299.954367) (xy 293.101033 -299.923242)
			(xy 293.143654 -299.898635) (xy 293.18967 -299.881183) (xy 293.237889 -299.871339) (xy 293.287064 -299.869358)
			(xy 293.335919 -299.87529) (xy 293.38319 -299.888982) (xy 293.427652 -299.91008) (xy 293.468155 -299.938036)
			(xy 293.503648 -299.972128) (xy 293.533213 -300.011472) (xy 293.556084 -300.055049) (xy 293.571668 -300.10173)
			(xy 293.579563 -300.150307) (xy 293.580058 -300.174914) (xy 293.918906 -300.174914) (xy 293.922866 -300.12586)
			(xy 293.934643 -300.078076) (xy 293.953934 -300.0328) (xy 293.980237 -299.991204) (xy 294.012872 -299.954367)
			(xy 294.050993 -299.923242) (xy 294.093614 -299.898635) (xy 294.13963 -299.881183) (xy 294.187849 -299.871339)
			(xy 294.237024 -299.869358) (xy 294.285879 -299.87529) (xy 294.33315 -299.888982) (xy 294.377612 -299.91008)
			(xy 294.418115 -299.938036) (xy 294.453608 -299.972128) (xy 294.483173 -300.011472) (xy 294.506044 -300.055049)
			(xy 294.521628 -300.10173) (xy 294.529523 -300.150307) (xy 294.530018 -300.174914) (xy 294.86912 -300.174914)
			(xy 294.87308 -300.12586) (xy 294.884857 -300.078076) (xy 294.904148 -300.0328) (xy 294.930451 -299.991204)
			(xy 294.963086 -299.954367) (xy 295.001207 -299.923242) (xy 295.043828 -299.898635) (xy 295.089844 -299.881183)
			(xy 295.138063 -299.871339) (xy 295.187238 -299.869358) (xy 295.236093 -299.87529) (xy 295.283364 -299.888982)
			(xy 295.327826 -299.91008) (xy 295.368329 -299.938036) (xy 295.403822 -299.972128) (xy 295.433387 -300.011472)
			(xy 295.456258 -300.055049) (xy 295.471842 -300.10173) (xy 295.479737 -300.150307) (xy 295.480232 -300.174914)
			(xy 295.81908 -300.174914) (xy 295.82304 -300.12586) (xy 295.834817 -300.078076) (xy 295.854108 -300.0328)
			(xy 295.880411 -299.991204) (xy 295.913046 -299.954367) (xy 295.951167 -299.923242) (xy 295.993788 -299.898635)
			(xy 296.039804 -299.881183) (xy 296.088023 -299.871339) (xy 296.137198 -299.869358) (xy 296.186053 -299.87529)
			(xy 296.233324 -299.888982) (xy 296.277786 -299.91008) (xy 296.318289 -299.938036) (xy 296.353782 -299.972128)
			(xy 296.383347 -300.011472) (xy 296.406218 -300.055049) (xy 296.421802 -300.10173) (xy 296.429697 -300.150307)
			(xy 296.430192 -300.174914) (xy 296.76904 -300.174914) (xy 296.773 -300.12586) (xy 296.784777 -300.078076)
			(xy 296.804068 -300.0328) (xy 296.830371 -299.991204) (xy 296.863006 -299.954367) (xy 296.901127 -299.923242)
			(xy 296.943748 -299.898635) (xy 296.989764 -299.881183) (xy 297.037983 -299.871339) (xy 297.087158 -299.869358)
			(xy 297.136013 -299.87529) (xy 297.183284 -299.888982) (xy 297.227746 -299.91008) (xy 297.268249 -299.938036)
			(xy 297.303742 -299.972128) (xy 297.333307 -300.011472) (xy 297.356178 -300.055049) (xy 297.371762 -300.10173)
			(xy 297.379657 -300.150307) (xy 297.380152 -300.174914) (xy 297.719 -300.174914) (xy 297.72296 -300.12586)
			(xy 297.734737 -300.078076) (xy 297.754028 -300.0328) (xy 297.780331 -299.991204) (xy 297.812966 -299.954367)
			(xy 297.851087 -299.923242) (xy 297.893708 -299.898635) (xy 297.939724 -299.881183) (xy 297.987943 -299.871339)
			(xy 298.037118 -299.869358) (xy 298.085973 -299.87529) (xy 298.133244 -299.888982) (xy 298.177706 -299.91008)
			(xy 298.218209 -299.938036) (xy 298.253702 -299.972128) (xy 298.283267 -300.011472) (xy 298.306138 -300.055049)
			(xy 298.321722 -300.10173) (xy 298.329617 -300.150307) (xy 298.330112 -300.174914) (xy 298.66896 -300.174914)
			(xy 298.67292 -300.12586) (xy 298.684697 -300.078076) (xy 298.703988 -300.0328) (xy 298.730291 -299.991204)
			(xy 298.762926 -299.954367) (xy 298.801047 -299.923242) (xy 298.843668 -299.898635) (xy 298.889684 -299.881183)
			(xy 298.937903 -299.871339) (xy 298.987078 -299.869358) (xy 299.035933 -299.87529) (xy 299.083204 -299.888982)
			(xy 299.127666 -299.91008) (xy 299.168169 -299.938036) (xy 299.203662 -299.972128) (xy 299.233227 -300.011472)
			(xy 299.256098 -300.055049) (xy 299.271682 -300.10173) (xy 299.279577 -300.150307) (xy 299.280072 -300.174914)
			(xy 299.61892 -300.174914) (xy 299.62288 -300.12586) (xy 299.634657 -300.078076) (xy 299.653948 -300.0328)
			(xy 299.680251 -299.991204) (xy 299.712886 -299.954367) (xy 299.751007 -299.923242) (xy 299.793628 -299.898635)
			(xy 299.839644 -299.881183) (xy 299.887863 -299.871339) (xy 299.937038 -299.869358) (xy 299.985893 -299.87529)
			(xy 300.033164 -299.888982) (xy 300.077626 -299.91008) (xy 300.118129 -299.938036) (xy 300.153622 -299.972128)
			(xy 300.183187 -300.011472) (xy 300.206058 -300.055049) (xy 300.221642 -300.10173) (xy 300.229537 -300.150307)
			(xy 300.230032 -300.174914) (xy 300.56888 -300.174914) (xy 300.57284 -300.12586) (xy 300.584617 -300.078076)
			(xy 300.603908 -300.0328) (xy 300.630211 -299.991204) (xy 300.662846 -299.954367) (xy 300.700967 -299.923242)
			(xy 300.743588 -299.898635) (xy 300.789604 -299.881183) (xy 300.837823 -299.871339) (xy 300.886998 -299.869358)
			(xy 300.935853 -299.87529) (xy 300.983124 -299.888982) (xy 301.027586 -299.91008) (xy 301.068089 -299.938036)
			(xy 301.103582 -299.972128) (xy 301.133147 -300.011472) (xy 301.156018 -300.055049) (xy 301.171602 -300.10173)
			(xy 301.179497 -300.150307) (xy 301.179992 -300.174914) (xy 301.519094 -300.174914) (xy 301.523054 -300.12586)
			(xy 301.534831 -300.078076) (xy 301.554122 -300.0328) (xy 301.580425 -299.991204) (xy 301.61306 -299.954367)
			(xy 301.651181 -299.923242) (xy 301.693802 -299.898635) (xy 301.739818 -299.881183) (xy 301.788037 -299.871339)
			(xy 301.837212 -299.869358) (xy 301.886067 -299.87529) (xy 301.933338 -299.888982) (xy 301.9778 -299.91008)
			(xy 302.018303 -299.938036) (xy 302.053796 -299.972128) (xy 302.083361 -300.011472) (xy 302.106232 -300.055049)
			(xy 302.121816 -300.10173) (xy 302.129711 -300.150307) (xy 302.130206 -300.174914) (xy 302.469054 -300.174914)
			(xy 302.473014 -300.12586) (xy 302.484791 -300.078076) (xy 302.504082 -300.0328) (xy 302.530385 -299.991204)
			(xy 302.56302 -299.954367) (xy 302.601141 -299.923242) (xy 302.643762 -299.898635) (xy 302.689778 -299.881183)
			(xy 302.737997 -299.871339) (xy 302.787172 -299.869358) (xy 302.836027 -299.87529) (xy 302.883298 -299.888982)
			(xy 302.92776 -299.91008) (xy 302.968263 -299.938036) (xy 303.003756 -299.972128) (xy 303.033321 -300.011472)
			(xy 303.056192 -300.055049) (xy 303.071776 -300.10173) (xy 303.079671 -300.150307) (xy 303.080166 -300.174914)
			(xy 303.079671 -300.199521) (xy 303.071776 -300.248098) (xy 303.056192 -300.294779) (xy 303.033321 -300.338356)
			(xy 303.003756 -300.3777) (xy 302.968263 -300.411792) (xy 302.92776 -300.439748) (xy 302.883298 -300.460846)
			(xy 302.836027 -300.474538) (xy 302.787172 -300.48047) (xy 302.737997 -300.478489) (xy 302.689778 -300.468645)
			(xy 302.643762 -300.451193) (xy 302.601141 -300.426586) (xy 302.56302 -300.395461) (xy 302.530385 -300.358624)
			(xy 302.504082 -300.317028) (xy 302.484791 -300.271752) (xy 302.473014 -300.223968) (xy 302.469054 -300.174914)
			(xy 302.130206 -300.174914) (xy 302.129711 -300.199521) (xy 302.121816 -300.248098) (xy 302.106232 -300.294779)
			(xy 302.083361 -300.338356) (xy 302.053796 -300.3777) (xy 302.018303 -300.411792) (xy 301.9778 -300.439748)
			(xy 301.933338 -300.460846) (xy 301.886067 -300.474538) (xy 301.837212 -300.48047) (xy 301.788037 -300.478489)
			(xy 301.739818 -300.468645) (xy 301.693802 -300.451193) (xy 301.651181 -300.426586) (xy 301.61306 -300.395461)
			(xy 301.580425 -300.358624) (xy 301.554122 -300.317028) (xy 301.534831 -300.271752) (xy 301.523054 -300.223968)
			(xy 301.519094 -300.174914) (xy 301.179992 -300.174914) (xy 301.179497 -300.199521) (xy 301.171602 -300.248098)
			(xy 301.156018 -300.294779) (xy 301.133147 -300.338356) (xy 301.103582 -300.3777) (xy 301.068089 -300.411792)
			(xy 301.027586 -300.439748) (xy 300.983124 -300.460846) (xy 300.935853 -300.474538) (xy 300.886998 -300.48047)
			(xy 300.837823 -300.478489) (xy 300.789604 -300.468645) (xy 300.743588 -300.451193) (xy 300.700967 -300.426586)
			(xy 300.662846 -300.395461) (xy 300.630211 -300.358624) (xy 300.603908 -300.317028) (xy 300.584617 -300.271752)
			(xy 300.57284 -300.223968) (xy 300.56888 -300.174914) (xy 300.230032 -300.174914) (xy 300.229537 -300.199521)
			(xy 300.221642 -300.248098) (xy 300.206058 -300.294779) (xy 300.183187 -300.338356) (xy 300.153622 -300.3777)
			(xy 300.118129 -300.411792) (xy 300.077626 -300.439748) (xy 300.033164 -300.460846) (xy 299.985893 -300.474538)
			(xy 299.937038 -300.48047) (xy 299.887863 -300.478489) (xy 299.839644 -300.468645) (xy 299.793628 -300.451193)
			(xy 299.751007 -300.426586) (xy 299.712886 -300.395461) (xy 299.680251 -300.358624) (xy 299.653948 -300.317028)
			(xy 299.634657 -300.271752) (xy 299.62288 -300.223968) (xy 299.61892 -300.174914) (xy 299.280072 -300.174914)
			(xy 299.279577 -300.199521) (xy 299.271682 -300.248098) (xy 299.256098 -300.294779) (xy 299.233227 -300.338356)
			(xy 299.203662 -300.3777) (xy 299.168169 -300.411792) (xy 299.127666 -300.439748) (xy 299.083204 -300.460846)
			(xy 299.035933 -300.474538) (xy 298.987078 -300.48047) (xy 298.937903 -300.478489) (xy 298.889684 -300.468645)
			(xy 298.843668 -300.451193) (xy 298.801047 -300.426586) (xy 298.762926 -300.395461) (xy 298.730291 -300.358624)
			(xy 298.703988 -300.317028) (xy 298.684697 -300.271752) (xy 298.67292 -300.223968) (xy 298.66896 -300.174914)
			(xy 298.330112 -300.174914) (xy 298.329617 -300.199521) (xy 298.321722 -300.248098) (xy 298.306138 -300.294779)
			(xy 298.283267 -300.338356) (xy 298.253702 -300.3777) (xy 298.218209 -300.411792) (xy 298.177706 -300.439748)
			(xy 298.133244 -300.460846) (xy 298.085973 -300.474538) (xy 298.037118 -300.48047) (xy 297.987943 -300.478489)
			(xy 297.939724 -300.468645) (xy 297.893708 -300.451193) (xy 297.851087 -300.426586) (xy 297.812966 -300.395461)
			(xy 297.780331 -300.358624) (xy 297.754028 -300.317028) (xy 297.734737 -300.271752) (xy 297.72296 -300.223968)
			(xy 297.719 -300.174914) (xy 297.380152 -300.174914) (xy 297.379657 -300.199521) (xy 297.371762 -300.248098)
			(xy 297.356178 -300.294779) (xy 297.333307 -300.338356) (xy 297.303742 -300.3777) (xy 297.268249 -300.411792)
			(xy 297.227746 -300.439748) (xy 297.183284 -300.460846) (xy 297.136013 -300.474538) (xy 297.087158 -300.48047)
			(xy 297.037983 -300.478489) (xy 296.989764 -300.468645) (xy 296.943748 -300.451193) (xy 296.901127 -300.426586)
			(xy 296.863006 -300.395461) (xy 296.830371 -300.358624) (xy 296.804068 -300.317028) (xy 296.784777 -300.271752)
			(xy 296.773 -300.223968) (xy 296.76904 -300.174914) (xy 296.430192 -300.174914) (xy 296.429697 -300.199521)
			(xy 296.421802 -300.248098) (xy 296.406218 -300.294779) (xy 296.383347 -300.338356) (xy 296.353782 -300.3777)
			(xy 296.318289 -300.411792) (xy 296.277786 -300.439748) (xy 296.233324 -300.460846) (xy 296.186053 -300.474538)
			(xy 296.137198 -300.48047) (xy 296.088023 -300.478489) (xy 296.039804 -300.468645) (xy 295.993788 -300.451193)
			(xy 295.951167 -300.426586) (xy 295.913046 -300.395461) (xy 295.880411 -300.358624) (xy 295.854108 -300.317028)
			(xy 295.834817 -300.271752) (xy 295.82304 -300.223968) (xy 295.81908 -300.174914) (xy 295.480232 -300.174914)
			(xy 295.479737 -300.199521) (xy 295.471842 -300.248098) (xy 295.456258 -300.294779) (xy 295.433387 -300.338356)
			(xy 295.403822 -300.3777) (xy 295.368329 -300.411792) (xy 295.327826 -300.439748) (xy 295.283364 -300.460846)
			(xy 295.236093 -300.474538) (xy 295.187238 -300.48047) (xy 295.138063 -300.478489) (xy 295.089844 -300.468645)
			(xy 295.043828 -300.451193) (xy 295.001207 -300.426586) (xy 294.963086 -300.395461) (xy 294.930451 -300.358624)
			(xy 294.904148 -300.317028) (xy 294.884857 -300.271752) (xy 294.87308 -300.223968) (xy 294.86912 -300.174914)
			(xy 294.530018 -300.174914) (xy 294.529523 -300.199521) (xy 294.521628 -300.248098) (xy 294.506044 -300.294779)
			(xy 294.483173 -300.338356) (xy 294.453608 -300.3777) (xy 294.418115 -300.411792) (xy 294.377612 -300.439748)
			(xy 294.33315 -300.460846) (xy 294.285879 -300.474538) (xy 294.237024 -300.48047) (xy 294.187849 -300.478489)
			(xy 294.13963 -300.468645) (xy 294.093614 -300.451193) (xy 294.050993 -300.426586) (xy 294.012872 -300.395461)
			(xy 293.980237 -300.358624) (xy 293.953934 -300.317028) (xy 293.934643 -300.271752) (xy 293.922866 -300.223968)
			(xy 293.918906 -300.174914) (xy 293.580058 -300.174914) (xy 293.579563 -300.199521) (xy 293.571668 -300.248098)
			(xy 293.556084 -300.294779) (xy 293.533213 -300.338356) (xy 293.503648 -300.3777) (xy 293.468155 -300.411792)
			(xy 293.427652 -300.439748) (xy 293.38319 -300.460846) (xy 293.335919 -300.474538) (xy 293.287064 -300.48047)
			(xy 293.237889 -300.478489) (xy 293.18967 -300.468645) (xy 293.143654 -300.451193) (xy 293.101033 -300.426586)
			(xy 293.062912 -300.395461) (xy 293.030277 -300.358624) (xy 293.003974 -300.317028) (xy 292.984683 -300.271752)
			(xy 292.972906 -300.223968) (xy 292.968946 -300.174914) (xy 292.630098 -300.174914) (xy 292.629603 -300.199521)
			(xy 292.621708 -300.248098) (xy 292.606124 -300.294779) (xy 292.583253 -300.338356) (xy 292.553688 -300.3777)
			(xy 292.518195 -300.411792) (xy 292.477692 -300.439748) (xy 292.43323 -300.460846) (xy 292.385959 -300.474538)
			(xy 292.337104 -300.48047) (xy 292.287929 -300.478489) (xy 292.23971 -300.468645) (xy 292.193694 -300.451193)
			(xy 292.151073 -300.426586) (xy 292.112952 -300.395461) (xy 292.080317 -300.358624) (xy 292.054014 -300.317028)
			(xy 292.034723 -300.271752) (xy 292.022946 -300.223968) (xy 292.018986 -300.174914) (xy 290.730178 -300.174914)
			(xy 290.729683 -300.199521) (xy 290.721788 -300.248098) (xy 290.706204 -300.294779) (xy 290.683333 -300.338356)
			(xy 290.653768 -300.3777) (xy 290.618275 -300.411792) (xy 290.577772 -300.439748) (xy 290.53331 -300.460846)
			(xy 290.486039 -300.474538) (xy 290.437184 -300.48047) (xy 290.388009 -300.478489) (xy 290.33979 -300.468645)
			(xy 290.293774 -300.451193) (xy 290.251153 -300.426586) (xy 290.213032 -300.395461) (xy 290.180397 -300.358624)
			(xy 290.154094 -300.317028) (xy 290.134803 -300.271752) (xy 290.123026 -300.223968) (xy 290.119066 -300.174914)
			(xy 289.780218 -300.174914) (xy 289.779723 -300.199521) (xy 289.771828 -300.248098) (xy 289.756244 -300.294779)
			(xy 289.733373 -300.338356) (xy 289.703808 -300.3777) (xy 289.668315 -300.411792) (xy 289.627812 -300.439748)
			(xy 289.58335 -300.460846) (xy 289.536079 -300.474538) (xy 289.487224 -300.48047) (xy 289.438049 -300.478489)
			(xy 289.38983 -300.468645) (xy 289.343814 -300.451193) (xy 289.301193 -300.426586) (xy 289.263072 -300.395461)
			(xy 289.230437 -300.358624) (xy 289.204134 -300.317028) (xy 289.184843 -300.271752) (xy 289.173066 -300.223968)
			(xy 289.169106 -300.174914) (xy 288.830004 -300.174914) (xy 288.829509 -300.199521) (xy 288.821614 -300.248098)
			(xy 288.80603 -300.294779) (xy 288.783159 -300.338356) (xy 288.753594 -300.3777) (xy 288.718101 -300.411792)
			(xy 288.677598 -300.439748) (xy 288.633136 -300.460846) (xy 288.585865 -300.474538) (xy 288.53701 -300.48047)
			(xy 288.487835 -300.478489) (xy 288.439616 -300.468645) (xy 288.3936 -300.451193) (xy 288.350979 -300.426586)
			(xy 288.312858 -300.395461) (xy 288.280223 -300.358624) (xy 288.25392 -300.317028) (xy 288.234629 -300.271752)
			(xy 288.222852 -300.223968) (xy 288.218892 -300.174914) (xy 287.880044 -300.174914) (xy 287.879549 -300.199521)
			(xy 287.871654 -300.248098) (xy 287.85607 -300.294779) (xy 287.833199 -300.338356) (xy 287.803634 -300.3777)
			(xy 287.768141 -300.411792) (xy 287.727638 -300.439748) (xy 287.683176 -300.460846) (xy 287.635905 -300.474538)
			(xy 287.58705 -300.48047) (xy 287.537875 -300.478489) (xy 287.489656 -300.468645) (xy 287.44364 -300.451193)
			(xy 287.401019 -300.426586) (xy 287.362898 -300.395461) (xy 287.330263 -300.358624) (xy 287.30396 -300.317028)
			(xy 287.284669 -300.271752) (xy 287.272892 -300.223968) (xy 287.268932 -300.174914) (xy 286.930084 -300.174914)
			(xy 286.929589 -300.199521) (xy 286.921694 -300.248098) (xy 286.90611 -300.294779) (xy 286.883239 -300.338356)
			(xy 286.853674 -300.3777) (xy 286.818181 -300.411792) (xy 286.777678 -300.439748) (xy 286.733216 -300.460846)
			(xy 286.685945 -300.474538) (xy 286.63709 -300.48047) (xy 286.587915 -300.478489) (xy 286.539696 -300.468645)
			(xy 286.49368 -300.451193) (xy 286.451059 -300.426586) (xy 286.412938 -300.395461) (xy 286.380303 -300.358624)
			(xy 286.354 -300.317028) (xy 286.334709 -300.271752) (xy 286.322932 -300.223968) (xy 286.318972 -300.174914)
			(xy 285.980124 -300.174914) (xy 285.979629 -300.199521) (xy 285.971734 -300.248098) (xy 285.95615 -300.294779)
			(xy 285.933279 -300.338356) (xy 285.903714 -300.3777) (xy 285.868221 -300.411792) (xy 285.827718 -300.439748)
			(xy 285.783256 -300.460846) (xy 285.735985 -300.474538) (xy 285.68713 -300.48047) (xy 285.637955 -300.478489)
			(xy 285.589736 -300.468645) (xy 285.54372 -300.451193) (xy 285.501099 -300.426586) (xy 285.462978 -300.395461)
			(xy 285.430343 -300.358624) (xy 285.40404 -300.317028) (xy 285.384749 -300.271752) (xy 285.372972 -300.223968)
			(xy 285.369012 -300.174914) (xy 285.030164 -300.174914) (xy 285.029669 -300.199521) (xy 285.021774 -300.248098)
			(xy 285.00619 -300.294779) (xy 284.983319 -300.338356) (xy 284.953754 -300.3777) (xy 284.918261 -300.411792)
			(xy 284.877758 -300.439748) (xy 284.833296 -300.460846) (xy 284.786025 -300.474538) (xy 284.73717 -300.48047)
			(xy 284.687995 -300.478489) (xy 284.639776 -300.468645) (xy 284.59376 -300.451193) (xy 284.551139 -300.426586)
			(xy 284.513018 -300.395461) (xy 284.480383 -300.358624) (xy 284.45408 -300.317028) (xy 284.434789 -300.271752)
			(xy 284.423012 -300.223968) (xy 284.419052 -300.174914) (xy 284.080204 -300.174914) (xy 284.079709 -300.199521)
			(xy 284.071814 -300.248098) (xy 284.05623 -300.294779) (xy 284.033359 -300.338356) (xy 284.003794 -300.3777)
			(xy 283.968301 -300.411792) (xy 283.927798 -300.439748) (xy 283.883336 -300.460846) (xy 283.836065 -300.474538)
			(xy 283.78721 -300.48047) (xy 283.738035 -300.478489) (xy 283.689816 -300.468645) (xy 283.6438 -300.451193)
			(xy 283.601179 -300.426586) (xy 283.563058 -300.395461) (xy 283.530423 -300.358624) (xy 283.50412 -300.317028)
			(xy 283.484829 -300.271752) (xy 283.473052 -300.223968) (xy 283.469092 -300.174914) (xy 283.130244 -300.174914)
			(xy 283.129749 -300.199521) (xy 283.121854 -300.248098) (xy 283.10627 -300.294779) (xy 283.083399 -300.338356)
			(xy 283.053834 -300.3777) (xy 283.018341 -300.411792) (xy 282.977838 -300.439748) (xy 282.933376 -300.460846)
			(xy 282.886105 -300.474538) (xy 282.83725 -300.48047) (xy 282.788075 -300.478489) (xy 282.739856 -300.468645)
			(xy 282.69384 -300.451193) (xy 282.651219 -300.426586) (xy 282.613098 -300.395461) (xy 282.580463 -300.358624)
			(xy 282.55416 -300.317028) (xy 282.534869 -300.271752) (xy 282.523092 -300.223968) (xy 282.519132 -300.174914)
			(xy 282.18003 -300.174914) (xy 282.179535 -300.199521) (xy 282.17164 -300.248098) (xy 282.156056 -300.294779)
			(xy 282.133185 -300.338356) (xy 282.10362 -300.3777) (xy 282.068127 -300.411792) (xy 282.027624 -300.439748)
			(xy 281.983162 -300.460846) (xy 281.935891 -300.474538) (xy 281.887036 -300.48047) (xy 281.837861 -300.478489)
			(xy 281.789642 -300.468645) (xy 281.743626 -300.451193) (xy 281.701005 -300.426586) (xy 281.662884 -300.395461)
			(xy 281.630249 -300.358624) (xy 281.603946 -300.317028) (xy 281.584655 -300.271752) (xy 281.572878 -300.223968)
			(xy 281.568918 -300.174914) (xy 281.23007 -300.174914) (xy 281.229575 -300.199521) (xy 281.22168 -300.248098)
			(xy 281.206096 -300.294779) (xy 281.183225 -300.338356) (xy 281.15366 -300.3777) (xy 281.118167 -300.411792)
			(xy 281.077664 -300.439748) (xy 281.033202 -300.460846) (xy 280.985931 -300.474538) (xy 280.937076 -300.48047)
			(xy 280.887901 -300.478489) (xy 280.839682 -300.468645) (xy 280.793666 -300.451193) (xy 280.751045 -300.426586)
			(xy 280.712924 -300.395461) (xy 280.680289 -300.358624) (xy 280.653986 -300.317028) (xy 280.634695 -300.271752)
			(xy 280.622918 -300.223968) (xy 280.618958 -300.174914) (xy 280.28011 -300.174914) (xy 280.279615 -300.199521)
			(xy 280.27172 -300.248098) (xy 280.256136 -300.294779) (xy 280.233265 -300.338356) (xy 280.2037 -300.3777)
			(xy 280.168207 -300.411792) (xy 280.127704 -300.439748) (xy 280.083242 -300.460846) (xy 280.035971 -300.474538)
			(xy 279.987116 -300.48047) (xy 279.937941 -300.478489) (xy 279.889722 -300.468645) (xy 279.843706 -300.451193)
			(xy 279.801085 -300.426586) (xy 279.762964 -300.395461) (xy 279.730329 -300.358624) (xy 279.704026 -300.317028)
			(xy 279.684735 -300.271752) (xy 279.672958 -300.223968) (xy 279.668998 -300.174914) (xy 279.41397 -300.174914)
			(xy 279.41397 -301.124874) (xy 279.668998 -301.124874) (xy 279.672958 -301.07582) (xy 279.684735 -301.028036)
			(xy 279.704026 -300.98276) (xy 279.730329 -300.941164) (xy 279.762964 -300.904327) (xy 279.801085 -300.873202)
			(xy 279.843706 -300.848595) (xy 279.889722 -300.831143) (xy 279.937941 -300.821299) (xy 279.987116 -300.819318)
			(xy 280.035971 -300.82525) (xy 280.083242 -300.838942) (xy 280.127704 -300.86004) (xy 280.168207 -300.887996)
			(xy 280.2037 -300.922088) (xy 280.233265 -300.961432) (xy 280.256136 -301.005009) (xy 280.27172 -301.05169)
			(xy 280.279615 -301.100267) (xy 280.28011 -301.124874) (xy 280.618958 -301.124874) (xy 280.622918 -301.07582)
			(xy 280.634695 -301.028036) (xy 280.653986 -300.98276) (xy 280.680289 -300.941164) (xy 280.712924 -300.904327)
			(xy 280.751045 -300.873202) (xy 280.793666 -300.848595) (xy 280.839682 -300.831143) (xy 280.887901 -300.821299)
			(xy 280.937076 -300.819318) (xy 280.985931 -300.82525) (xy 281.033202 -300.838942) (xy 281.077664 -300.86004)
			(xy 281.118167 -300.887996) (xy 281.15366 -300.922088) (xy 281.183225 -300.961432) (xy 281.206096 -301.005009)
			(xy 281.22168 -301.05169) (xy 281.229575 -301.100267) (xy 281.23007 -301.124874) (xy 281.568918 -301.124874)
			(xy 281.572878 -301.07582) (xy 281.584655 -301.028036) (xy 281.603946 -300.98276) (xy 281.630249 -300.941164)
			(xy 281.662884 -300.904327) (xy 281.701005 -300.873202) (xy 281.743626 -300.848595) (xy 281.789642 -300.831143)
			(xy 281.837861 -300.821299) (xy 281.887036 -300.819318) (xy 281.935891 -300.82525) (xy 281.983162 -300.838942)
			(xy 282.027624 -300.86004) (xy 282.068127 -300.887996) (xy 282.10362 -300.922088) (xy 282.133185 -300.961432)
			(xy 282.156056 -301.005009) (xy 282.17164 -301.05169) (xy 282.179535 -301.100267) (xy 282.18003 -301.124874)
			(xy 300.56888 -301.124874) (xy 300.57284 -301.07582) (xy 300.584617 -301.028036) (xy 300.603908 -300.98276)
			(xy 300.630211 -300.941164) (xy 300.662846 -300.904327) (xy 300.700967 -300.873202) (xy 300.743588 -300.848595)
			(xy 300.789604 -300.831143) (xy 300.837823 -300.821299) (xy 300.886998 -300.819318) (xy 300.935853 -300.82525)
			(xy 300.983124 -300.838942) (xy 301.027586 -300.86004) (xy 301.068089 -300.887996) (xy 301.103582 -300.922088)
			(xy 301.133147 -300.961432) (xy 301.156018 -301.005009) (xy 301.171602 -301.05169) (xy 301.179497 -301.100267)
			(xy 301.179992 -301.124874) (xy 301.519094 -301.124874) (xy 301.523054 -301.07582) (xy 301.534831 -301.028036)
			(xy 301.554122 -300.98276) (xy 301.580425 -300.941164) (xy 301.61306 -300.904327) (xy 301.651181 -300.873202)
			(xy 301.693802 -300.848595) (xy 301.739818 -300.831143) (xy 301.788037 -300.821299) (xy 301.837212 -300.819318)
			(xy 301.886067 -300.82525) (xy 301.933338 -300.838942) (xy 301.9778 -300.86004) (xy 302.018303 -300.887996)
			(xy 302.053796 -300.922088) (xy 302.083361 -300.961432) (xy 302.106232 -301.005009) (xy 302.121816 -301.05169)
			(xy 302.129711 -301.100267) (xy 302.130206 -301.124874) (xy 302.129711 -301.149481) (xy 302.121816 -301.198058)
			(xy 302.106232 -301.244739) (xy 302.083361 -301.288316) (xy 302.053796 -301.32766) (xy 302.018303 -301.361752)
			(xy 301.9778 -301.389708) (xy 301.933338 -301.410806) (xy 301.886067 -301.424498) (xy 301.837212 -301.43043)
			(xy 301.788037 -301.428449) (xy 301.739818 -301.418605) (xy 301.693802 -301.401153) (xy 301.651181 -301.376546)
			(xy 301.61306 -301.345421) (xy 301.580425 -301.308584) (xy 301.554122 -301.266988) (xy 301.534831 -301.221712)
			(xy 301.523054 -301.173928) (xy 301.519094 -301.124874) (xy 301.179992 -301.124874) (xy 301.179497 -301.149481)
			(xy 301.171602 -301.198058) (xy 301.156018 -301.244739) (xy 301.133147 -301.288316) (xy 301.103582 -301.32766)
			(xy 301.068089 -301.361752) (xy 301.027586 -301.389708) (xy 300.983124 -301.410806) (xy 300.935853 -301.424498)
			(xy 300.886998 -301.43043) (xy 300.837823 -301.428449) (xy 300.789604 -301.418605) (xy 300.743588 -301.401153)
			(xy 300.700967 -301.376546) (xy 300.662846 -301.345421) (xy 300.630211 -301.308584) (xy 300.603908 -301.266988)
			(xy 300.584617 -301.221712) (xy 300.57284 -301.173928) (xy 300.56888 -301.124874) (xy 282.18003 -301.124874)
			(xy 282.179535 -301.149481) (xy 282.17164 -301.198058) (xy 282.156056 -301.244739) (xy 282.133185 -301.288316)
			(xy 282.10362 -301.32766) (xy 282.068127 -301.361752) (xy 282.027624 -301.389708) (xy 281.983162 -301.410806)
			(xy 281.935891 -301.424498) (xy 281.887036 -301.43043) (xy 281.837861 -301.428449) (xy 281.789642 -301.418605)
			(xy 281.743626 -301.401153) (xy 281.701005 -301.376546) (xy 281.662884 -301.345421) (xy 281.630249 -301.308584)
			(xy 281.603946 -301.266988) (xy 281.584655 -301.221712) (xy 281.572878 -301.173928) (xy 281.568918 -301.124874)
			(xy 281.23007 -301.124874) (xy 281.229575 -301.149481) (xy 281.22168 -301.198058) (xy 281.206096 -301.244739)
			(xy 281.183225 -301.288316) (xy 281.15366 -301.32766) (xy 281.118167 -301.361752) (xy 281.077664 -301.389708)
			(xy 281.033202 -301.410806) (xy 280.985931 -301.424498) (xy 280.937076 -301.43043) (xy 280.887901 -301.428449)
			(xy 280.839682 -301.418605) (xy 280.793666 -301.401153) (xy 280.751045 -301.376546) (xy 280.712924 -301.345421)
			(xy 280.680289 -301.308584) (xy 280.653986 -301.266988) (xy 280.634695 -301.221712) (xy 280.622918 -301.173928)
			(xy 280.618958 -301.124874) (xy 280.28011 -301.124874) (xy 280.279615 -301.149481) (xy 280.27172 -301.198058)
			(xy 280.256136 -301.244739) (xy 280.233265 -301.288316) (xy 280.2037 -301.32766) (xy 280.168207 -301.361752)
			(xy 280.127704 -301.389708) (xy 280.083242 -301.410806) (xy 280.035971 -301.424498) (xy 279.987116 -301.43043)
			(xy 279.937941 -301.428449) (xy 279.889722 -301.418605) (xy 279.843706 -301.401153) (xy 279.801085 -301.376546)
			(xy 279.762964 -301.345421) (xy 279.730329 -301.308584) (xy 279.704026 -301.266988) (xy 279.684735 -301.221712)
			(xy 279.672958 -301.173928) (xy 279.668998 -301.124874) (xy 279.41397 -301.124874) (xy 279.41397 -302.074834)
			(xy 281.568918 -302.074834) (xy 281.572878 -302.02578) (xy 281.584655 -301.977996) (xy 281.603946 -301.93272)
			(xy 281.630249 -301.891124) (xy 281.662884 -301.854287) (xy 281.701005 -301.823162) (xy 281.743626 -301.798555)
			(xy 281.789642 -301.781103) (xy 281.837861 -301.771259) (xy 281.887036 -301.769278) (xy 281.935891 -301.77521)
			(xy 281.983162 -301.788902) (xy 282.027624 -301.81) (xy 282.068127 -301.837956) (xy 282.10362 -301.872048)
			(xy 282.133185 -301.911392) (xy 282.156056 -301.954969) (xy 282.17164 -302.00165) (xy 282.179535 -302.050227)
			(xy 282.18003 -302.074834) (xy 282.519132 -302.074834) (xy 282.523092 -302.02578) (xy 282.534869 -301.977996)
			(xy 282.55416 -301.93272) (xy 282.580463 -301.891124) (xy 282.613098 -301.854287) (xy 282.651219 -301.823162)
			(xy 282.69384 -301.798555) (xy 282.739856 -301.781103) (xy 282.788075 -301.771259) (xy 282.83725 -301.769278)
			(xy 282.886105 -301.77521) (xy 282.933376 -301.788902) (xy 282.977838 -301.81) (xy 283.018341 -301.837956)
			(xy 283.053834 -301.872048) (xy 283.083399 -301.911392) (xy 283.10627 -301.954969) (xy 283.121854 -302.00165)
			(xy 283.129749 -302.050227) (xy 283.130244 -302.074834) (xy 283.469092 -302.074834) (xy 283.473052 -302.02578)
			(xy 283.484829 -301.977996) (xy 283.50412 -301.93272) (xy 283.530423 -301.891124) (xy 283.563058 -301.854287)
			(xy 283.601179 -301.823162) (xy 283.6438 -301.798555) (xy 283.689816 -301.781103) (xy 283.738035 -301.771259)
			(xy 283.78721 -301.769278) (xy 283.836065 -301.77521) (xy 283.883336 -301.788902) (xy 283.927798 -301.81)
			(xy 283.968301 -301.837956) (xy 284.003794 -301.872048) (xy 284.033359 -301.911392) (xy 284.05623 -301.954969)
			(xy 284.071814 -302.00165) (xy 284.079709 -302.050227) (xy 284.080204 -302.074834) (xy 284.419052 -302.074834)
			(xy 284.423012 -302.02578) (xy 284.434789 -301.977996) (xy 284.45408 -301.93272) (xy 284.480383 -301.891124)
			(xy 284.513018 -301.854287) (xy 284.551139 -301.823162) (xy 284.59376 -301.798555) (xy 284.639776 -301.781103)
			(xy 284.687995 -301.771259) (xy 284.73717 -301.769278) (xy 284.786025 -301.77521) (xy 284.833296 -301.788902)
			(xy 284.877758 -301.81) (xy 284.918261 -301.837956) (xy 284.953754 -301.872048) (xy 284.983319 -301.911392)
			(xy 285.00619 -301.954969) (xy 285.021774 -302.00165) (xy 285.029669 -302.050227) (xy 285.030164 -302.074834)
			(xy 285.369012 -302.074834) (xy 285.372972 -302.02578) (xy 285.384749 -301.977996) (xy 285.40404 -301.93272)
			(xy 285.430343 -301.891124) (xy 285.462978 -301.854287) (xy 285.501099 -301.823162) (xy 285.54372 -301.798555)
			(xy 285.589736 -301.781103) (xy 285.637955 -301.771259) (xy 285.68713 -301.769278) (xy 285.735985 -301.77521)
			(xy 285.783256 -301.788902) (xy 285.827718 -301.81) (xy 285.868221 -301.837956) (xy 285.903714 -301.872048)
			(xy 285.933279 -301.911392) (xy 285.95615 -301.954969) (xy 285.971734 -302.00165) (xy 285.979629 -302.050227)
			(xy 285.980124 -302.074834) (xy 286.318972 -302.074834) (xy 286.322932 -302.02578) (xy 286.334709 -301.977996)
			(xy 286.354 -301.93272) (xy 286.380303 -301.891124) (xy 286.412938 -301.854287) (xy 286.451059 -301.823162)
			(xy 286.49368 -301.798555) (xy 286.539696 -301.781103) (xy 286.587915 -301.771259) (xy 286.63709 -301.769278)
			(xy 286.685945 -301.77521) (xy 286.733216 -301.788902) (xy 286.777678 -301.81) (xy 286.818181 -301.837956)
			(xy 286.853674 -301.872048) (xy 286.883239 -301.911392) (xy 286.90611 -301.954969) (xy 286.921694 -302.00165)
			(xy 286.929589 -302.050227) (xy 286.930084 -302.074834) (xy 287.268932 -302.074834) (xy 287.272892 -302.02578)
			(xy 287.284669 -301.977996) (xy 287.30396 -301.93272) (xy 287.330263 -301.891124) (xy 287.362898 -301.854287)
			(xy 287.401019 -301.823162) (xy 287.44364 -301.798555) (xy 287.489656 -301.781103) (xy 287.537875 -301.771259)
			(xy 287.58705 -301.769278) (xy 287.635905 -301.77521) (xy 287.683176 -301.788902) (xy 287.727638 -301.81)
			(xy 287.768141 -301.837956) (xy 287.803634 -301.872048) (xy 287.833199 -301.911392) (xy 287.85607 -301.954969)
			(xy 287.871654 -302.00165) (xy 287.879549 -302.050227) (xy 287.880044 -302.074834) (xy 288.218892 -302.074834)
			(xy 288.222852 -302.02578) (xy 288.234629 -301.977996) (xy 288.25392 -301.93272) (xy 288.280223 -301.891124)
			(xy 288.312858 -301.854287) (xy 288.350979 -301.823162) (xy 288.3936 -301.798555) (xy 288.439616 -301.781103)
			(xy 288.487835 -301.771259) (xy 288.53701 -301.769278) (xy 288.585865 -301.77521) (xy 288.633136 -301.788902)
			(xy 288.677598 -301.81) (xy 288.718101 -301.837956) (xy 288.753594 -301.872048) (xy 288.783159 -301.911392)
			(xy 288.80603 -301.954969) (xy 288.821614 -302.00165) (xy 288.829509 -302.050227) (xy 288.830004 -302.074834)
			(xy 289.169106 -302.074834) (xy 289.173066 -302.02578) (xy 289.184843 -301.977996) (xy 289.204134 -301.93272)
			(xy 289.230437 -301.891124) (xy 289.263072 -301.854287) (xy 289.301193 -301.823162) (xy 289.343814 -301.798555)
			(xy 289.38983 -301.781103) (xy 289.438049 -301.771259) (xy 289.487224 -301.769278) (xy 289.536079 -301.77521)
			(xy 289.58335 -301.788902) (xy 289.627812 -301.81) (xy 289.668315 -301.837956) (xy 289.703808 -301.872048)
			(xy 289.733373 -301.911392) (xy 289.756244 -301.954969) (xy 289.771828 -302.00165) (xy 289.779723 -302.050227)
			(xy 289.780218 -302.074834) (xy 290.119066 -302.074834) (xy 290.123026 -302.02578) (xy 290.134803 -301.977996)
			(xy 290.154094 -301.93272) (xy 290.180397 -301.891124) (xy 290.213032 -301.854287) (xy 290.251153 -301.823162)
			(xy 290.293774 -301.798555) (xy 290.33979 -301.781103) (xy 290.388009 -301.771259) (xy 290.437184 -301.769278)
			(xy 290.486039 -301.77521) (xy 290.53331 -301.788902) (xy 290.577772 -301.81) (xy 290.618275 -301.837956)
			(xy 290.653768 -301.872048) (xy 290.683333 -301.911392) (xy 290.706204 -301.954969) (xy 290.721788 -302.00165)
			(xy 290.729683 -302.050227) (xy 290.730178 -302.074834) (xy 292.018986 -302.074834) (xy 292.022946 -302.02578)
			(xy 292.034723 -301.977996) (xy 292.054014 -301.93272) (xy 292.080317 -301.891124) (xy 292.112952 -301.854287)
			(xy 292.151073 -301.823162) (xy 292.193694 -301.798555) (xy 292.23971 -301.781103) (xy 292.287929 -301.771259)
			(xy 292.337104 -301.769278) (xy 292.385959 -301.77521) (xy 292.43323 -301.788902) (xy 292.477692 -301.81)
			(xy 292.518195 -301.837956) (xy 292.553688 -301.872048) (xy 292.583253 -301.911392) (xy 292.606124 -301.954969)
			(xy 292.621708 -302.00165) (xy 292.629603 -302.050227) (xy 292.630098 -302.074834) (xy 292.968946 -302.074834)
			(xy 292.972906 -302.02578) (xy 292.984683 -301.977996) (xy 293.003974 -301.93272) (xy 293.030277 -301.891124)
			(xy 293.062912 -301.854287) (xy 293.101033 -301.823162) (xy 293.143654 -301.798555) (xy 293.18967 -301.781103)
			(xy 293.237889 -301.771259) (xy 293.287064 -301.769278) (xy 293.335919 -301.77521) (xy 293.38319 -301.788902)
			(xy 293.427652 -301.81) (xy 293.468155 -301.837956) (xy 293.503648 -301.872048) (xy 293.533213 -301.911392)
			(xy 293.556084 -301.954969) (xy 293.571668 -302.00165) (xy 293.579563 -302.050227) (xy 293.580058 -302.074834)
			(xy 293.918906 -302.074834) (xy 293.922866 -302.02578) (xy 293.934643 -301.977996) (xy 293.953934 -301.93272)
			(xy 293.980237 -301.891124) (xy 294.012872 -301.854287) (xy 294.050993 -301.823162) (xy 294.093614 -301.798555)
			(xy 294.13963 -301.781103) (xy 294.187849 -301.771259) (xy 294.237024 -301.769278) (xy 294.285879 -301.77521)
			(xy 294.33315 -301.788902) (xy 294.377612 -301.81) (xy 294.418115 -301.837956) (xy 294.453608 -301.872048)
			(xy 294.483173 -301.911392) (xy 294.506044 -301.954969) (xy 294.521628 -302.00165) (xy 294.529523 -302.050227)
			(xy 294.530018 -302.074834) (xy 294.86912 -302.074834) (xy 294.87308 -302.02578) (xy 294.884857 -301.977996)
			(xy 294.904148 -301.93272) (xy 294.930451 -301.891124) (xy 294.963086 -301.854287) (xy 295.001207 -301.823162)
			(xy 295.043828 -301.798555) (xy 295.089844 -301.781103) (xy 295.138063 -301.771259) (xy 295.187238 -301.769278)
			(xy 295.236093 -301.77521) (xy 295.283364 -301.788902) (xy 295.327826 -301.81) (xy 295.368329 -301.837956)
			(xy 295.403822 -301.872048) (xy 295.433387 -301.911392) (xy 295.456258 -301.954969) (xy 295.471842 -302.00165)
			(xy 295.479737 -302.050227) (xy 295.480232 -302.074834) (xy 295.81908 -302.074834) (xy 295.82304 -302.02578)
			(xy 295.834817 -301.977996) (xy 295.854108 -301.93272) (xy 295.880411 -301.891124) (xy 295.913046 -301.854287)
			(xy 295.951167 -301.823162) (xy 295.993788 -301.798555) (xy 296.039804 -301.781103) (xy 296.088023 -301.771259)
			(xy 296.137198 -301.769278) (xy 296.186053 -301.77521) (xy 296.233324 -301.788902) (xy 296.277786 -301.81)
			(xy 296.318289 -301.837956) (xy 296.353782 -301.872048) (xy 296.383347 -301.911392) (xy 296.406218 -301.954969)
			(xy 296.421802 -302.00165) (xy 296.429697 -302.050227) (xy 296.430192 -302.074834) (xy 296.76904 -302.074834)
			(xy 296.773 -302.02578) (xy 296.784777 -301.977996) (xy 296.804068 -301.93272) (xy 296.830371 -301.891124)
			(xy 296.863006 -301.854287) (xy 296.901127 -301.823162) (xy 296.943748 -301.798555) (xy 296.989764 -301.781103)
			(xy 297.037983 -301.771259) (xy 297.087158 -301.769278) (xy 297.136013 -301.77521) (xy 297.183284 -301.788902)
			(xy 297.227746 -301.81) (xy 297.268249 -301.837956) (xy 297.303742 -301.872048) (xy 297.333307 -301.911392)
			(xy 297.356178 -301.954969) (xy 297.371762 -302.00165) (xy 297.379657 -302.050227) (xy 297.380152 -302.074834)
			(xy 297.719 -302.074834) (xy 297.72296 -302.02578) (xy 297.734737 -301.977996) (xy 297.754028 -301.93272)
			(xy 297.780331 -301.891124) (xy 297.812966 -301.854287) (xy 297.851087 -301.823162) (xy 297.893708 -301.798555)
			(xy 297.939724 -301.781103) (xy 297.987943 -301.771259) (xy 298.037118 -301.769278) (xy 298.085973 -301.77521)
			(xy 298.133244 -301.788902) (xy 298.177706 -301.81) (xy 298.218209 -301.837956) (xy 298.253702 -301.872048)
			(xy 298.283267 -301.911392) (xy 298.306138 -301.954969) (xy 298.321722 -302.00165) (xy 298.329617 -302.050227)
			(xy 298.330112 -302.074834) (xy 298.66896 -302.074834) (xy 298.67292 -302.02578) (xy 298.684697 -301.977996)
			(xy 298.703988 -301.93272) (xy 298.730291 -301.891124) (xy 298.762926 -301.854287) (xy 298.801047 -301.823162)
			(xy 298.843668 -301.798555) (xy 298.889684 -301.781103) (xy 298.937903 -301.771259) (xy 298.987078 -301.769278)
			(xy 299.035933 -301.77521) (xy 299.083204 -301.788902) (xy 299.127666 -301.81) (xy 299.168169 -301.837956)
			(xy 299.203662 -301.872048) (xy 299.233227 -301.911392) (xy 299.256098 -301.954969) (xy 299.271682 -302.00165)
			(xy 299.279577 -302.050227) (xy 299.280072 -302.074834) (xy 299.61892 -302.074834) (xy 299.62288 -302.02578)
			(xy 299.634657 -301.977996) (xy 299.653948 -301.93272) (xy 299.680251 -301.891124) (xy 299.712886 -301.854287)
			(xy 299.751007 -301.823162) (xy 299.793628 -301.798555) (xy 299.839644 -301.781103) (xy 299.887863 -301.771259)
			(xy 299.937038 -301.769278) (xy 299.985893 -301.77521) (xy 300.033164 -301.788902) (xy 300.077626 -301.81)
			(xy 300.118129 -301.837956) (xy 300.153622 -301.872048) (xy 300.183187 -301.911392) (xy 300.206058 -301.954969)
			(xy 300.221642 -302.00165) (xy 300.229537 -302.050227) (xy 300.230032 -302.074834) (xy 300.56888 -302.074834)
			(xy 300.57284 -302.02578) (xy 300.584617 -301.977996) (xy 300.603908 -301.93272) (xy 300.630211 -301.891124)
			(xy 300.662846 -301.854287) (xy 300.700967 -301.823162) (xy 300.743588 -301.798555) (xy 300.789604 -301.781103)
			(xy 300.837823 -301.771259) (xy 300.886998 -301.769278) (xy 300.935853 -301.77521) (xy 300.983124 -301.788902)
			(xy 301.027586 -301.81) (xy 301.068089 -301.837956) (xy 301.103582 -301.872048) (xy 301.133147 -301.911392)
			(xy 301.156018 -301.954969) (xy 301.171602 -302.00165) (xy 301.179497 -302.050227) (xy 301.179992 -302.074834)
			(xy 301.179497 -302.099441) (xy 301.171602 -302.148018) (xy 301.156018 -302.194699) (xy 301.133147 -302.238276)
			(xy 301.103582 -302.27762) (xy 301.068089 -302.311712) (xy 301.027586 -302.339668) (xy 300.983124 -302.360766)
			(xy 300.935853 -302.374458) (xy 300.886998 -302.38039) (xy 300.837823 -302.378409) (xy 300.789604 -302.368565)
			(xy 300.743588 -302.351113) (xy 300.700967 -302.326506) (xy 300.662846 -302.295381) (xy 300.630211 -302.258544)
			(xy 300.603908 -302.216948) (xy 300.584617 -302.171672) (xy 300.57284 -302.123888) (xy 300.56888 -302.074834)
			(xy 300.230032 -302.074834) (xy 300.229537 -302.099441) (xy 300.221642 -302.148018) (xy 300.206058 -302.194699)
			(xy 300.183187 -302.238276) (xy 300.153622 -302.27762) (xy 300.118129 -302.311712) (xy 300.077626 -302.339668)
			(xy 300.033164 -302.360766) (xy 299.985893 -302.374458) (xy 299.937038 -302.38039) (xy 299.887863 -302.378409)
			(xy 299.839644 -302.368565) (xy 299.793628 -302.351113) (xy 299.751007 -302.326506) (xy 299.712886 -302.295381)
			(xy 299.680251 -302.258544) (xy 299.653948 -302.216948) (xy 299.634657 -302.171672) (xy 299.62288 -302.123888)
			(xy 299.61892 -302.074834) (xy 299.280072 -302.074834) (xy 299.279577 -302.099441) (xy 299.271682 -302.148018)
			(xy 299.256098 -302.194699) (xy 299.233227 -302.238276) (xy 299.203662 -302.27762) (xy 299.168169 -302.311712)
			(xy 299.127666 -302.339668) (xy 299.083204 -302.360766) (xy 299.035933 -302.374458) (xy 298.987078 -302.38039)
			(xy 298.937903 -302.378409) (xy 298.889684 -302.368565) (xy 298.843668 -302.351113) (xy 298.801047 -302.326506)
			(xy 298.762926 -302.295381) (xy 298.730291 -302.258544) (xy 298.703988 -302.216948) (xy 298.684697 -302.171672)
			(xy 298.67292 -302.123888) (xy 298.66896 -302.074834) (xy 298.330112 -302.074834) (xy 298.329617 -302.099441)
			(xy 298.321722 -302.148018) (xy 298.306138 -302.194699) (xy 298.283267 -302.238276) (xy 298.253702 -302.27762)
			(xy 298.218209 -302.311712) (xy 298.177706 -302.339668) (xy 298.133244 -302.360766) (xy 298.085973 -302.374458)
			(xy 298.037118 -302.38039) (xy 297.987943 -302.378409) (xy 297.939724 -302.368565) (xy 297.893708 -302.351113)
			(xy 297.851087 -302.326506) (xy 297.812966 -302.295381) (xy 297.780331 -302.258544) (xy 297.754028 -302.216948)
			(xy 297.734737 -302.171672) (xy 297.72296 -302.123888) (xy 297.719 -302.074834) (xy 297.380152 -302.074834)
			(xy 297.379657 -302.099441) (xy 297.371762 -302.148018) (xy 297.356178 -302.194699) (xy 297.333307 -302.238276)
			(xy 297.303742 -302.27762) (xy 297.268249 -302.311712) (xy 297.227746 -302.339668) (xy 297.183284 -302.360766)
			(xy 297.136013 -302.374458) (xy 297.087158 -302.38039) (xy 297.037983 -302.378409) (xy 296.989764 -302.368565)
			(xy 296.943748 -302.351113) (xy 296.901127 -302.326506) (xy 296.863006 -302.295381) (xy 296.830371 -302.258544)
			(xy 296.804068 -302.216948) (xy 296.784777 -302.171672) (xy 296.773 -302.123888) (xy 296.76904 -302.074834)
			(xy 296.430192 -302.074834) (xy 296.429697 -302.099441) (xy 296.421802 -302.148018) (xy 296.406218 -302.194699)
			(xy 296.383347 -302.238276) (xy 296.353782 -302.27762) (xy 296.318289 -302.311712) (xy 296.277786 -302.339668)
			(xy 296.233324 -302.360766) (xy 296.186053 -302.374458) (xy 296.137198 -302.38039) (xy 296.088023 -302.378409)
			(xy 296.039804 -302.368565) (xy 295.993788 -302.351113) (xy 295.951167 -302.326506) (xy 295.913046 -302.295381)
			(xy 295.880411 -302.258544) (xy 295.854108 -302.216948) (xy 295.834817 -302.171672) (xy 295.82304 -302.123888)
			(xy 295.81908 -302.074834) (xy 295.480232 -302.074834) (xy 295.479737 -302.099441) (xy 295.471842 -302.148018)
			(xy 295.456258 -302.194699) (xy 295.433387 -302.238276) (xy 295.403822 -302.27762) (xy 295.368329 -302.311712)
			(xy 295.327826 -302.339668) (xy 295.283364 -302.360766) (xy 295.236093 -302.374458) (xy 295.187238 -302.38039)
			(xy 295.138063 -302.378409) (xy 295.089844 -302.368565) (xy 295.043828 -302.351113) (xy 295.001207 -302.326506)
			(xy 294.963086 -302.295381) (xy 294.930451 -302.258544) (xy 294.904148 -302.216948) (xy 294.884857 -302.171672)
			(xy 294.87308 -302.123888) (xy 294.86912 -302.074834) (xy 294.530018 -302.074834) (xy 294.529523 -302.099441)
			(xy 294.521628 -302.148018) (xy 294.506044 -302.194699) (xy 294.483173 -302.238276) (xy 294.453608 -302.27762)
			(xy 294.418115 -302.311712) (xy 294.377612 -302.339668) (xy 294.33315 -302.360766) (xy 294.285879 -302.374458)
			(xy 294.237024 -302.38039) (xy 294.187849 -302.378409) (xy 294.13963 -302.368565) (xy 294.093614 -302.351113)
			(xy 294.050993 -302.326506) (xy 294.012872 -302.295381) (xy 293.980237 -302.258544) (xy 293.953934 -302.216948)
			(xy 293.934643 -302.171672) (xy 293.922866 -302.123888) (xy 293.918906 -302.074834) (xy 293.580058 -302.074834)
			(xy 293.579563 -302.099441) (xy 293.571668 -302.148018) (xy 293.556084 -302.194699) (xy 293.533213 -302.238276)
			(xy 293.503648 -302.27762) (xy 293.468155 -302.311712) (xy 293.427652 -302.339668) (xy 293.38319 -302.360766)
			(xy 293.335919 -302.374458) (xy 293.287064 -302.38039) (xy 293.237889 -302.378409) (xy 293.18967 -302.368565)
			(xy 293.143654 -302.351113) (xy 293.101033 -302.326506) (xy 293.062912 -302.295381) (xy 293.030277 -302.258544)
			(xy 293.003974 -302.216948) (xy 292.984683 -302.171672) (xy 292.972906 -302.123888) (xy 292.968946 -302.074834)
			(xy 292.630098 -302.074834) (xy 292.629603 -302.099441) (xy 292.621708 -302.148018) (xy 292.606124 -302.194699)
			(xy 292.583253 -302.238276) (xy 292.553688 -302.27762) (xy 292.518195 -302.311712) (xy 292.477692 -302.339668)
			(xy 292.43323 -302.360766) (xy 292.385959 -302.374458) (xy 292.337104 -302.38039) (xy 292.287929 -302.378409)
			(xy 292.23971 -302.368565) (xy 292.193694 -302.351113) (xy 292.151073 -302.326506) (xy 292.112952 -302.295381)
			(xy 292.080317 -302.258544) (xy 292.054014 -302.216948) (xy 292.034723 -302.171672) (xy 292.022946 -302.123888)
			(xy 292.018986 -302.074834) (xy 290.730178 -302.074834) (xy 290.729683 -302.099441) (xy 290.721788 -302.148018)
			(xy 290.706204 -302.194699) (xy 290.683333 -302.238276) (xy 290.653768 -302.27762) (xy 290.618275 -302.311712)
			(xy 290.577772 -302.339668) (xy 290.53331 -302.360766) (xy 290.486039 -302.374458) (xy 290.437184 -302.38039)
			(xy 290.388009 -302.378409) (xy 290.33979 -302.368565) (xy 290.293774 -302.351113) (xy 290.251153 -302.326506)
			(xy 290.213032 -302.295381) (xy 290.180397 -302.258544) (xy 290.154094 -302.216948) (xy 290.134803 -302.171672)
			(xy 290.123026 -302.123888) (xy 290.119066 -302.074834) (xy 289.780218 -302.074834) (xy 289.779723 -302.099441)
			(xy 289.771828 -302.148018) (xy 289.756244 -302.194699) (xy 289.733373 -302.238276) (xy 289.703808 -302.27762)
			(xy 289.668315 -302.311712) (xy 289.627812 -302.339668) (xy 289.58335 -302.360766) (xy 289.536079 -302.374458)
			(xy 289.487224 -302.38039) (xy 289.438049 -302.378409) (xy 289.38983 -302.368565) (xy 289.343814 -302.351113)
			(xy 289.301193 -302.326506) (xy 289.263072 -302.295381) (xy 289.230437 -302.258544) (xy 289.204134 -302.216948)
			(xy 289.184843 -302.171672) (xy 289.173066 -302.123888) (xy 289.169106 -302.074834) (xy 288.830004 -302.074834)
			(xy 288.829509 -302.099441) (xy 288.821614 -302.148018) (xy 288.80603 -302.194699) (xy 288.783159 -302.238276)
			(xy 288.753594 -302.27762) (xy 288.718101 -302.311712) (xy 288.677598 -302.339668) (xy 288.633136 -302.360766)
			(xy 288.585865 -302.374458) (xy 288.53701 -302.38039) (xy 288.487835 -302.378409) (xy 288.439616 -302.368565)
			(xy 288.3936 -302.351113) (xy 288.350979 -302.326506) (xy 288.312858 -302.295381) (xy 288.280223 -302.258544)
			(xy 288.25392 -302.216948) (xy 288.234629 -302.171672) (xy 288.222852 -302.123888) (xy 288.218892 -302.074834)
			(xy 287.880044 -302.074834) (xy 287.879549 -302.099441) (xy 287.871654 -302.148018) (xy 287.85607 -302.194699)
			(xy 287.833199 -302.238276) (xy 287.803634 -302.27762) (xy 287.768141 -302.311712) (xy 287.727638 -302.339668)
			(xy 287.683176 -302.360766) (xy 287.635905 -302.374458) (xy 287.58705 -302.38039) (xy 287.537875 -302.378409)
			(xy 287.489656 -302.368565) (xy 287.44364 -302.351113) (xy 287.401019 -302.326506) (xy 287.362898 -302.295381)
			(xy 287.330263 -302.258544) (xy 287.30396 -302.216948) (xy 287.284669 -302.171672) (xy 287.272892 -302.123888)
			(xy 287.268932 -302.074834) (xy 286.930084 -302.074834) (xy 286.929589 -302.099441) (xy 286.921694 -302.148018)
			(xy 286.90611 -302.194699) (xy 286.883239 -302.238276) (xy 286.853674 -302.27762) (xy 286.818181 -302.311712)
			(xy 286.777678 -302.339668) (xy 286.733216 -302.360766) (xy 286.685945 -302.374458) (xy 286.63709 -302.38039)
			(xy 286.587915 -302.378409) (xy 286.539696 -302.368565) (xy 286.49368 -302.351113) (xy 286.451059 -302.326506)
			(xy 286.412938 -302.295381) (xy 286.380303 -302.258544) (xy 286.354 -302.216948) (xy 286.334709 -302.171672)
			(xy 286.322932 -302.123888) (xy 286.318972 -302.074834) (xy 285.980124 -302.074834) (xy 285.979629 -302.099441)
			(xy 285.971734 -302.148018) (xy 285.95615 -302.194699) (xy 285.933279 -302.238276) (xy 285.903714 -302.27762)
			(xy 285.868221 -302.311712) (xy 285.827718 -302.339668) (xy 285.783256 -302.360766) (xy 285.735985 -302.374458)
			(xy 285.68713 -302.38039) (xy 285.637955 -302.378409) (xy 285.589736 -302.368565) (xy 285.54372 -302.351113)
			(xy 285.501099 -302.326506) (xy 285.462978 -302.295381) (xy 285.430343 -302.258544) (xy 285.40404 -302.216948)
			(xy 285.384749 -302.171672) (xy 285.372972 -302.123888) (xy 285.369012 -302.074834) (xy 285.030164 -302.074834)
			(xy 285.029669 -302.099441) (xy 285.021774 -302.148018) (xy 285.00619 -302.194699) (xy 284.983319 -302.238276)
			(xy 284.953754 -302.27762) (xy 284.918261 -302.311712) (xy 284.877758 -302.339668) (xy 284.833296 -302.360766)
			(xy 284.786025 -302.374458) (xy 284.73717 -302.38039) (xy 284.687995 -302.378409) (xy 284.639776 -302.368565)
			(xy 284.59376 -302.351113) (xy 284.551139 -302.326506) (xy 284.513018 -302.295381) (xy 284.480383 -302.258544)
			(xy 284.45408 -302.216948) (xy 284.434789 -302.171672) (xy 284.423012 -302.123888) (xy 284.419052 -302.074834)
			(xy 284.080204 -302.074834) (xy 284.079709 -302.099441) (xy 284.071814 -302.148018) (xy 284.05623 -302.194699)
			(xy 284.033359 -302.238276) (xy 284.003794 -302.27762) (xy 283.968301 -302.311712) (xy 283.927798 -302.339668)
			(xy 283.883336 -302.360766) (xy 283.836065 -302.374458) (xy 283.78721 -302.38039) (xy 283.738035 -302.378409)
			(xy 283.689816 -302.368565) (xy 283.6438 -302.351113) (xy 283.601179 -302.326506) (xy 283.563058 -302.295381)
			(xy 283.530423 -302.258544) (xy 283.50412 -302.216948) (xy 283.484829 -302.171672) (xy 283.473052 -302.123888)
			(xy 283.469092 -302.074834) (xy 283.130244 -302.074834) (xy 283.129749 -302.099441) (xy 283.121854 -302.148018)
			(xy 283.10627 -302.194699) (xy 283.083399 -302.238276) (xy 283.053834 -302.27762) (xy 283.018341 -302.311712)
			(xy 282.977838 -302.339668) (xy 282.933376 -302.360766) (xy 282.886105 -302.374458) (xy 282.83725 -302.38039)
			(xy 282.788075 -302.378409) (xy 282.739856 -302.368565) (xy 282.69384 -302.351113) (xy 282.651219 -302.326506)
			(xy 282.613098 -302.295381) (xy 282.580463 -302.258544) (xy 282.55416 -302.216948) (xy 282.534869 -302.171672)
			(xy 282.523092 -302.123888) (xy 282.519132 -302.074834) (xy 282.18003 -302.074834) (xy 282.179535 -302.099441)
			(xy 282.17164 -302.148018) (xy 282.156056 -302.194699) (xy 282.133185 -302.238276) (xy 282.10362 -302.27762)
			(xy 282.068127 -302.311712) (xy 282.027624 -302.339668) (xy 281.983162 -302.360766) (xy 281.935891 -302.374458)
			(xy 281.887036 -302.38039) (xy 281.837861 -302.378409) (xy 281.789642 -302.368565) (xy 281.743626 -302.351113)
			(xy 281.701005 -302.326506) (xy 281.662884 -302.295381) (xy 281.630249 -302.258544) (xy 281.603946 -302.216948)
			(xy 281.584655 -302.171672) (xy 281.572878 -302.123888) (xy 281.568918 -302.074834) (xy 279.41397 -302.074834)
			(xy 279.41397 -303.024794) (xy 279.668998 -303.024794) (xy 279.672958 -302.97574) (xy 279.684735 -302.927956)
			(xy 279.704026 -302.88268) (xy 279.730329 -302.841084) (xy 279.762964 -302.804247) (xy 279.801085 -302.773122)
			(xy 279.843706 -302.748515) (xy 279.889722 -302.731063) (xy 279.937941 -302.721219) (xy 279.987116 -302.719238)
			(xy 280.035971 -302.72517) (xy 280.083242 -302.738862) (xy 280.127704 -302.75996) (xy 280.168207 -302.787916)
			(xy 280.2037 -302.822008) (xy 280.233265 -302.861352) (xy 280.256136 -302.904929) (xy 280.27172 -302.95161)
			(xy 280.279615 -303.000187) (xy 280.28011 -303.024794) (xy 280.618958 -303.024794) (xy 280.622918 -302.97574)
			(xy 280.634695 -302.927956) (xy 280.653986 -302.88268) (xy 280.680289 -302.841084) (xy 280.712924 -302.804247)
			(xy 280.751045 -302.773122) (xy 280.793666 -302.748515) (xy 280.839682 -302.731063) (xy 280.887901 -302.721219)
			(xy 280.937076 -302.719238) (xy 280.985931 -302.72517) (xy 281.033202 -302.738862) (xy 281.077664 -302.75996)
			(xy 281.118167 -302.787916) (xy 281.15366 -302.822008) (xy 281.183225 -302.861352) (xy 281.206096 -302.904929)
			(xy 281.22168 -302.95161) (xy 281.229575 -303.000187) (xy 281.23007 -303.024794) (xy 281.568918 -303.024794)
			(xy 281.572878 -302.97574) (xy 281.584655 -302.927956) (xy 281.603946 -302.88268) (xy 281.630249 -302.841084)
			(xy 281.662884 -302.804247) (xy 281.701005 -302.773122) (xy 281.743626 -302.748515) (xy 281.789642 -302.731063)
			(xy 281.837861 -302.721219) (xy 281.887036 -302.719238) (xy 281.935891 -302.72517) (xy 281.983162 -302.738862)
			(xy 282.027624 -302.75996) (xy 282.068127 -302.787916) (xy 282.10362 -302.822008) (xy 282.133185 -302.861352)
			(xy 282.156056 -302.904929) (xy 282.17164 -302.95161) (xy 282.179535 -303.000187) (xy 282.18003 -303.024794)
			(xy 282.519132 -303.024794) (xy 282.523092 -302.97574) (xy 282.534869 -302.927956) (xy 282.55416 -302.88268)
			(xy 282.580463 -302.841084) (xy 282.613098 -302.804247) (xy 282.651219 -302.773122) (xy 282.69384 -302.748515)
			(xy 282.739856 -302.731063) (xy 282.788075 -302.721219) (xy 282.83725 -302.719238) (xy 282.886105 -302.72517)
			(xy 282.933376 -302.738862) (xy 282.977838 -302.75996) (xy 283.018341 -302.787916) (xy 283.053834 -302.822008)
			(xy 283.083399 -302.861352) (xy 283.10627 -302.904929) (xy 283.121854 -302.95161) (xy 283.129749 -303.000187)
			(xy 283.130244 -303.024794) (xy 283.469092 -303.024794) (xy 283.473052 -302.97574) (xy 283.484829 -302.927956)
			(xy 283.50412 -302.88268) (xy 283.530423 -302.841084) (xy 283.563058 -302.804247) (xy 283.601179 -302.773122)
			(xy 283.6438 -302.748515) (xy 283.689816 -302.731063) (xy 283.738035 -302.721219) (xy 283.78721 -302.719238)
			(xy 283.836065 -302.72517) (xy 283.883336 -302.738862) (xy 283.927798 -302.75996) (xy 283.968301 -302.787916)
			(xy 284.003794 -302.822008) (xy 284.033359 -302.861352) (xy 284.05623 -302.904929) (xy 284.071814 -302.95161)
			(xy 284.079709 -303.000187) (xy 284.080204 -303.024794) (xy 284.419052 -303.024794) (xy 284.423012 -302.97574)
			(xy 284.434789 -302.927956) (xy 284.45408 -302.88268) (xy 284.480383 -302.841084) (xy 284.513018 -302.804247)
			(xy 284.551139 -302.773122) (xy 284.59376 -302.748515) (xy 284.639776 -302.731063) (xy 284.687995 -302.721219)
			(xy 284.73717 -302.719238) (xy 284.786025 -302.72517) (xy 284.833296 -302.738862) (xy 284.877758 -302.75996)
			(xy 284.918261 -302.787916) (xy 284.953754 -302.822008) (xy 284.983319 -302.861352) (xy 285.00619 -302.904929)
			(xy 285.021774 -302.95161) (xy 285.029669 -303.000187) (xy 285.030164 -303.024794) (xy 285.369012 -303.024794)
			(xy 285.372972 -302.97574) (xy 285.384749 -302.927956) (xy 285.40404 -302.88268) (xy 285.430343 -302.841084)
			(xy 285.462978 -302.804247) (xy 285.501099 -302.773122) (xy 285.54372 -302.748515) (xy 285.589736 -302.731063)
			(xy 285.637955 -302.721219) (xy 285.68713 -302.719238) (xy 285.735985 -302.72517) (xy 285.783256 -302.738862)
			(xy 285.827718 -302.75996) (xy 285.868221 -302.787916) (xy 285.903714 -302.822008) (xy 285.933279 -302.861352)
			(xy 285.95615 -302.904929) (xy 285.971734 -302.95161) (xy 285.979629 -303.000187) (xy 285.980124 -303.024794)
			(xy 286.318972 -303.024794) (xy 286.322932 -302.97574) (xy 286.334709 -302.927956) (xy 286.354 -302.88268)
			(xy 286.380303 -302.841084) (xy 286.412938 -302.804247) (xy 286.451059 -302.773122) (xy 286.49368 -302.748515)
			(xy 286.539696 -302.731063) (xy 286.587915 -302.721219) (xy 286.63709 -302.719238) (xy 286.685945 -302.72517)
			(xy 286.733216 -302.738862) (xy 286.777678 -302.75996) (xy 286.818181 -302.787916) (xy 286.853674 -302.822008)
			(xy 286.883239 -302.861352) (xy 286.90611 -302.904929) (xy 286.921694 -302.95161) (xy 286.929589 -303.000187)
			(xy 286.930084 -303.024794) (xy 287.268932 -303.024794) (xy 287.272892 -302.97574) (xy 287.284669 -302.927956)
			(xy 287.30396 -302.88268) (xy 287.330263 -302.841084) (xy 287.362898 -302.804247) (xy 287.401019 -302.773122)
			(xy 287.44364 -302.748515) (xy 287.489656 -302.731063) (xy 287.537875 -302.721219) (xy 287.58705 -302.719238)
			(xy 287.635905 -302.72517) (xy 287.683176 -302.738862) (xy 287.727638 -302.75996) (xy 287.768141 -302.787916)
			(xy 287.803634 -302.822008) (xy 287.833199 -302.861352) (xy 287.85607 -302.904929) (xy 287.871654 -302.95161)
			(xy 287.879549 -303.000187) (xy 287.880044 -303.024794) (xy 288.218892 -303.024794) (xy 288.222852 -302.97574)
			(xy 288.234629 -302.927956) (xy 288.25392 -302.88268) (xy 288.280223 -302.841084) (xy 288.312858 -302.804247)
			(xy 288.350979 -302.773122) (xy 288.3936 -302.748515) (xy 288.439616 -302.731063) (xy 288.487835 -302.721219)
			(xy 288.53701 -302.719238) (xy 288.585865 -302.72517) (xy 288.633136 -302.738862) (xy 288.677598 -302.75996)
			(xy 288.718101 -302.787916) (xy 288.753594 -302.822008) (xy 288.783159 -302.861352) (xy 288.80603 -302.904929)
			(xy 288.821614 -302.95161) (xy 288.829509 -303.000187) (xy 288.830004 -303.024794) (xy 289.169106 -303.024794)
			(xy 289.173066 -302.97574) (xy 289.184843 -302.927956) (xy 289.204134 -302.88268) (xy 289.230437 -302.841084)
			(xy 289.263072 -302.804247) (xy 289.301193 -302.773122) (xy 289.343814 -302.748515) (xy 289.38983 -302.731063)
			(xy 289.438049 -302.721219) (xy 289.487224 -302.719238) (xy 289.536079 -302.72517) (xy 289.58335 -302.738862)
			(xy 289.627812 -302.75996) (xy 289.668315 -302.787916) (xy 289.703808 -302.822008) (xy 289.733373 -302.861352)
			(xy 289.756244 -302.904929) (xy 289.771828 -302.95161) (xy 289.779723 -303.000187) (xy 289.780218 -303.024794)
			(xy 290.119066 -303.024794) (xy 290.123026 -302.97574) (xy 290.134803 -302.927956) (xy 290.154094 -302.88268)
			(xy 290.180397 -302.841084) (xy 290.213032 -302.804247) (xy 290.251153 -302.773122) (xy 290.293774 -302.748515)
			(xy 290.33979 -302.731063) (xy 290.388009 -302.721219) (xy 290.437184 -302.719238) (xy 290.486039 -302.72517)
			(xy 290.53331 -302.738862) (xy 290.577772 -302.75996) (xy 290.618275 -302.787916) (xy 290.653768 -302.822008)
			(xy 290.683333 -302.861352) (xy 290.706204 -302.904929) (xy 290.721788 -302.95161) (xy 290.729683 -303.000187)
			(xy 290.730178 -303.024794) (xy 292.018986 -303.024794) (xy 292.022946 -302.97574) (xy 292.034723 -302.927956)
			(xy 292.054014 -302.88268) (xy 292.080317 -302.841084) (xy 292.112952 -302.804247) (xy 292.151073 -302.773122)
			(xy 292.193694 -302.748515) (xy 292.23971 -302.731063) (xy 292.287929 -302.721219) (xy 292.337104 -302.719238)
			(xy 292.385959 -302.72517) (xy 292.43323 -302.738862) (xy 292.477692 -302.75996) (xy 292.518195 -302.787916)
			(xy 292.553688 -302.822008) (xy 292.583253 -302.861352) (xy 292.606124 -302.904929) (xy 292.621708 -302.95161)
			(xy 292.629603 -303.000187) (xy 292.630098 -303.024794) (xy 292.968946 -303.024794) (xy 292.972906 -302.97574)
			(xy 292.984683 -302.927956) (xy 293.003974 -302.88268) (xy 293.030277 -302.841084) (xy 293.062912 -302.804247)
			(xy 293.101033 -302.773122) (xy 293.143654 -302.748515) (xy 293.18967 -302.731063) (xy 293.237889 -302.721219)
			(xy 293.287064 -302.719238) (xy 293.335919 -302.72517) (xy 293.38319 -302.738862) (xy 293.427652 -302.75996)
			(xy 293.468155 -302.787916) (xy 293.503648 -302.822008) (xy 293.533213 -302.861352) (xy 293.556084 -302.904929)
			(xy 293.571668 -302.95161) (xy 293.579563 -303.000187) (xy 293.580058 -303.024794) (xy 293.918906 -303.024794)
			(xy 293.922866 -302.97574) (xy 293.934643 -302.927956) (xy 293.953934 -302.88268) (xy 293.980237 -302.841084)
			(xy 294.012872 -302.804247) (xy 294.050993 -302.773122) (xy 294.093614 -302.748515) (xy 294.13963 -302.731063)
			(xy 294.187849 -302.721219) (xy 294.237024 -302.719238) (xy 294.285879 -302.72517) (xy 294.33315 -302.738862)
			(xy 294.377612 -302.75996) (xy 294.418115 -302.787916) (xy 294.453608 -302.822008) (xy 294.483173 -302.861352)
			(xy 294.506044 -302.904929) (xy 294.521628 -302.95161) (xy 294.529523 -303.000187) (xy 294.530018 -303.024794)
			(xy 294.86912 -303.024794) (xy 294.87308 -302.97574) (xy 294.884857 -302.927956) (xy 294.904148 -302.88268)
			(xy 294.930451 -302.841084) (xy 294.963086 -302.804247) (xy 295.001207 -302.773122) (xy 295.043828 -302.748515)
			(xy 295.089844 -302.731063) (xy 295.138063 -302.721219) (xy 295.187238 -302.719238) (xy 295.236093 -302.72517)
			(xy 295.283364 -302.738862) (xy 295.327826 -302.75996) (xy 295.368329 -302.787916) (xy 295.403822 -302.822008)
			(xy 295.433387 -302.861352) (xy 295.456258 -302.904929) (xy 295.471842 -302.95161) (xy 295.479737 -303.000187)
			(xy 295.480232 -303.024794) (xy 295.81908 -303.024794) (xy 295.82304 -302.97574) (xy 295.834817 -302.927956)
			(xy 295.854108 -302.88268) (xy 295.880411 -302.841084) (xy 295.913046 -302.804247) (xy 295.951167 -302.773122)
			(xy 295.993788 -302.748515) (xy 296.039804 -302.731063) (xy 296.088023 -302.721219) (xy 296.137198 -302.719238)
			(xy 296.186053 -302.72517) (xy 296.233324 -302.738862) (xy 296.277786 -302.75996) (xy 296.318289 -302.787916)
			(xy 296.353782 -302.822008) (xy 296.383347 -302.861352) (xy 296.406218 -302.904929) (xy 296.421802 -302.95161)
			(xy 296.429697 -303.000187) (xy 296.430192 -303.024794) (xy 296.76904 -303.024794) (xy 296.773 -302.97574)
			(xy 296.784777 -302.927956) (xy 296.804068 -302.88268) (xy 296.830371 -302.841084) (xy 296.863006 -302.804247)
			(xy 296.901127 -302.773122) (xy 296.943748 -302.748515) (xy 296.989764 -302.731063) (xy 297.037983 -302.721219)
			(xy 297.087158 -302.719238) (xy 297.136013 -302.72517) (xy 297.183284 -302.738862) (xy 297.227746 -302.75996)
			(xy 297.268249 -302.787916) (xy 297.303742 -302.822008) (xy 297.333307 -302.861352) (xy 297.356178 -302.904929)
			(xy 297.371762 -302.95161) (xy 297.379657 -303.000187) (xy 297.380152 -303.024794) (xy 297.719 -303.024794)
			(xy 297.72296 -302.97574) (xy 297.734737 -302.927956) (xy 297.754028 -302.88268) (xy 297.780331 -302.841084)
			(xy 297.812966 -302.804247) (xy 297.851087 -302.773122) (xy 297.893708 -302.748515) (xy 297.939724 -302.731063)
			(xy 297.987943 -302.721219) (xy 298.037118 -302.719238) (xy 298.085973 -302.72517) (xy 298.133244 -302.738862)
			(xy 298.177706 -302.75996) (xy 298.218209 -302.787916) (xy 298.253702 -302.822008) (xy 298.283267 -302.861352)
			(xy 298.306138 -302.904929) (xy 298.321722 -302.95161) (xy 298.329617 -303.000187) (xy 298.330112 -303.024794)
			(xy 298.66896 -303.024794) (xy 298.67292 -302.97574) (xy 298.684697 -302.927956) (xy 298.703988 -302.88268)
			(xy 298.730291 -302.841084) (xy 298.762926 -302.804247) (xy 298.801047 -302.773122) (xy 298.843668 -302.748515)
			(xy 298.889684 -302.731063) (xy 298.937903 -302.721219) (xy 298.987078 -302.719238) (xy 299.035933 -302.72517)
			(xy 299.083204 -302.738862) (xy 299.127666 -302.75996) (xy 299.168169 -302.787916) (xy 299.203662 -302.822008)
			(xy 299.233227 -302.861352) (xy 299.256098 -302.904929) (xy 299.271682 -302.95161) (xy 299.279577 -303.000187)
			(xy 299.280072 -303.024794) (xy 299.61892 -303.024794) (xy 299.62288 -302.97574) (xy 299.634657 -302.927956)
			(xy 299.653948 -302.88268) (xy 299.680251 -302.841084) (xy 299.712886 -302.804247) (xy 299.751007 -302.773122)
			(xy 299.793628 -302.748515) (xy 299.839644 -302.731063) (xy 299.887863 -302.721219) (xy 299.937038 -302.719238)
			(xy 299.985893 -302.72517) (xy 300.033164 -302.738862) (xy 300.077626 -302.75996) (xy 300.118129 -302.787916)
			(xy 300.153622 -302.822008) (xy 300.183187 -302.861352) (xy 300.206058 -302.904929) (xy 300.221642 -302.95161)
			(xy 300.229537 -303.000187) (xy 300.230032 -303.024794) (xy 300.56888 -303.024794) (xy 300.57284 -302.97574)
			(xy 300.584617 -302.927956) (xy 300.603908 -302.88268) (xy 300.630211 -302.841084) (xy 300.662846 -302.804247)
			(xy 300.700967 -302.773122) (xy 300.743588 -302.748515) (xy 300.789604 -302.731063) (xy 300.837823 -302.721219)
			(xy 300.886998 -302.719238) (xy 300.935853 -302.72517) (xy 300.983124 -302.738862) (xy 301.027586 -302.75996)
			(xy 301.068089 -302.787916) (xy 301.103582 -302.822008) (xy 301.133147 -302.861352) (xy 301.156018 -302.904929)
			(xy 301.171602 -302.95161) (xy 301.179497 -303.000187) (xy 301.179992 -303.024794) (xy 301.179497 -303.049401)
			(xy 301.171602 -303.097978) (xy 301.156018 -303.144659) (xy 301.133147 -303.188236) (xy 301.103582 -303.22758)
			(xy 301.068089 -303.261672) (xy 301.027586 -303.289628) (xy 300.983124 -303.310726) (xy 300.935853 -303.324418)
			(xy 300.886998 -303.33035) (xy 300.837823 -303.328369) (xy 300.789604 -303.318525) (xy 300.743588 -303.301073)
			(xy 300.700967 -303.276466) (xy 300.662846 -303.245341) (xy 300.630211 -303.208504) (xy 300.603908 -303.166908)
			(xy 300.584617 -303.121632) (xy 300.57284 -303.073848) (xy 300.56888 -303.024794) (xy 300.230032 -303.024794)
			(xy 300.229537 -303.049401) (xy 300.221642 -303.097978) (xy 300.206058 -303.144659) (xy 300.183187 -303.188236)
			(xy 300.153622 -303.22758) (xy 300.118129 -303.261672) (xy 300.077626 -303.289628) (xy 300.033164 -303.310726)
			(xy 299.985893 -303.324418) (xy 299.937038 -303.33035) (xy 299.887863 -303.328369) (xy 299.839644 -303.318525)
			(xy 299.793628 -303.301073) (xy 299.751007 -303.276466) (xy 299.712886 -303.245341) (xy 299.680251 -303.208504)
			(xy 299.653948 -303.166908) (xy 299.634657 -303.121632) (xy 299.62288 -303.073848) (xy 299.61892 -303.024794)
			(xy 299.280072 -303.024794) (xy 299.279577 -303.049401) (xy 299.271682 -303.097978) (xy 299.256098 -303.144659)
			(xy 299.233227 -303.188236) (xy 299.203662 -303.22758) (xy 299.168169 -303.261672) (xy 299.127666 -303.289628)
			(xy 299.083204 -303.310726) (xy 299.035933 -303.324418) (xy 298.987078 -303.33035) (xy 298.937903 -303.328369)
			(xy 298.889684 -303.318525) (xy 298.843668 -303.301073) (xy 298.801047 -303.276466) (xy 298.762926 -303.245341)
			(xy 298.730291 -303.208504) (xy 298.703988 -303.166908) (xy 298.684697 -303.121632) (xy 298.67292 -303.073848)
			(xy 298.66896 -303.024794) (xy 298.330112 -303.024794) (xy 298.329617 -303.049401) (xy 298.321722 -303.097978)
			(xy 298.306138 -303.144659) (xy 298.283267 -303.188236) (xy 298.253702 -303.22758) (xy 298.218209 -303.261672)
			(xy 298.177706 -303.289628) (xy 298.133244 -303.310726) (xy 298.085973 -303.324418) (xy 298.037118 -303.33035)
			(xy 297.987943 -303.328369) (xy 297.939724 -303.318525) (xy 297.893708 -303.301073) (xy 297.851087 -303.276466)
			(xy 297.812966 -303.245341) (xy 297.780331 -303.208504) (xy 297.754028 -303.166908) (xy 297.734737 -303.121632)
			(xy 297.72296 -303.073848) (xy 297.719 -303.024794) (xy 297.380152 -303.024794) (xy 297.379657 -303.049401)
			(xy 297.371762 -303.097978) (xy 297.356178 -303.144659) (xy 297.333307 -303.188236) (xy 297.303742 -303.22758)
			(xy 297.268249 -303.261672) (xy 297.227746 -303.289628) (xy 297.183284 -303.310726) (xy 297.136013 -303.324418)
			(xy 297.087158 -303.33035) (xy 297.037983 -303.328369) (xy 296.989764 -303.318525) (xy 296.943748 -303.301073)
			(xy 296.901127 -303.276466) (xy 296.863006 -303.245341) (xy 296.830371 -303.208504) (xy 296.804068 -303.166908)
			(xy 296.784777 -303.121632) (xy 296.773 -303.073848) (xy 296.76904 -303.024794) (xy 296.430192 -303.024794)
			(xy 296.429697 -303.049401) (xy 296.421802 -303.097978) (xy 296.406218 -303.144659) (xy 296.383347 -303.188236)
			(xy 296.353782 -303.22758) (xy 296.318289 -303.261672) (xy 296.277786 -303.289628) (xy 296.233324 -303.310726)
			(xy 296.186053 -303.324418) (xy 296.137198 -303.33035) (xy 296.088023 -303.328369) (xy 296.039804 -303.318525)
			(xy 295.993788 -303.301073) (xy 295.951167 -303.276466) (xy 295.913046 -303.245341) (xy 295.880411 -303.208504)
			(xy 295.854108 -303.166908) (xy 295.834817 -303.121632) (xy 295.82304 -303.073848) (xy 295.81908 -303.024794)
			(xy 295.480232 -303.024794) (xy 295.479737 -303.049401) (xy 295.471842 -303.097978) (xy 295.456258 -303.144659)
			(xy 295.433387 -303.188236) (xy 295.403822 -303.22758) (xy 295.368329 -303.261672) (xy 295.327826 -303.289628)
			(xy 295.283364 -303.310726) (xy 295.236093 -303.324418) (xy 295.187238 -303.33035) (xy 295.138063 -303.328369)
			(xy 295.089844 -303.318525) (xy 295.043828 -303.301073) (xy 295.001207 -303.276466) (xy 294.963086 -303.245341)
			(xy 294.930451 -303.208504) (xy 294.904148 -303.166908) (xy 294.884857 -303.121632) (xy 294.87308 -303.073848)
			(xy 294.86912 -303.024794) (xy 294.530018 -303.024794) (xy 294.529523 -303.049401) (xy 294.521628 -303.097978)
			(xy 294.506044 -303.144659) (xy 294.483173 -303.188236) (xy 294.453608 -303.22758) (xy 294.418115 -303.261672)
			(xy 294.377612 -303.289628) (xy 294.33315 -303.310726) (xy 294.285879 -303.324418) (xy 294.237024 -303.33035)
			(xy 294.187849 -303.328369) (xy 294.13963 -303.318525) (xy 294.093614 -303.301073) (xy 294.050993 -303.276466)
			(xy 294.012872 -303.245341) (xy 293.980237 -303.208504) (xy 293.953934 -303.166908) (xy 293.934643 -303.121632)
			(xy 293.922866 -303.073848) (xy 293.918906 -303.024794) (xy 293.580058 -303.024794) (xy 293.579563 -303.049401)
			(xy 293.571668 -303.097978) (xy 293.556084 -303.144659) (xy 293.533213 -303.188236) (xy 293.503648 -303.22758)
			(xy 293.468155 -303.261672) (xy 293.427652 -303.289628) (xy 293.38319 -303.310726) (xy 293.335919 -303.324418)
			(xy 293.287064 -303.33035) (xy 293.237889 -303.328369) (xy 293.18967 -303.318525) (xy 293.143654 -303.301073)
			(xy 293.101033 -303.276466) (xy 293.062912 -303.245341) (xy 293.030277 -303.208504) (xy 293.003974 -303.166908)
			(xy 292.984683 -303.121632) (xy 292.972906 -303.073848) (xy 292.968946 -303.024794) (xy 292.630098 -303.024794)
			(xy 292.629603 -303.049401) (xy 292.621708 -303.097978) (xy 292.606124 -303.144659) (xy 292.583253 -303.188236)
			(xy 292.553688 -303.22758) (xy 292.518195 -303.261672) (xy 292.477692 -303.289628) (xy 292.43323 -303.310726)
			(xy 292.385959 -303.324418) (xy 292.337104 -303.33035) (xy 292.287929 -303.328369) (xy 292.23971 -303.318525)
			(xy 292.193694 -303.301073) (xy 292.151073 -303.276466) (xy 292.112952 -303.245341) (xy 292.080317 -303.208504)
			(xy 292.054014 -303.166908) (xy 292.034723 -303.121632) (xy 292.022946 -303.073848) (xy 292.018986 -303.024794)
			(xy 290.730178 -303.024794) (xy 290.729683 -303.049401) (xy 290.721788 -303.097978) (xy 290.706204 -303.144659)
			(xy 290.683333 -303.188236) (xy 290.653768 -303.22758) (xy 290.618275 -303.261672) (xy 290.577772 -303.289628)
			(xy 290.53331 -303.310726) (xy 290.486039 -303.324418) (xy 290.437184 -303.33035) (xy 290.388009 -303.328369)
			(xy 290.33979 -303.318525) (xy 290.293774 -303.301073) (xy 290.251153 -303.276466) (xy 290.213032 -303.245341)
			(xy 290.180397 -303.208504) (xy 290.154094 -303.166908) (xy 290.134803 -303.121632) (xy 290.123026 -303.073848)
			(xy 290.119066 -303.024794) (xy 289.780218 -303.024794) (xy 289.779723 -303.049401) (xy 289.771828 -303.097978)
			(xy 289.756244 -303.144659) (xy 289.733373 -303.188236) (xy 289.703808 -303.22758) (xy 289.668315 -303.261672)
			(xy 289.627812 -303.289628) (xy 289.58335 -303.310726) (xy 289.536079 -303.324418) (xy 289.487224 -303.33035)
			(xy 289.438049 -303.328369) (xy 289.38983 -303.318525) (xy 289.343814 -303.301073) (xy 289.301193 -303.276466)
			(xy 289.263072 -303.245341) (xy 289.230437 -303.208504) (xy 289.204134 -303.166908) (xy 289.184843 -303.121632)
			(xy 289.173066 -303.073848) (xy 289.169106 -303.024794) (xy 288.830004 -303.024794) (xy 288.829509 -303.049401)
			(xy 288.821614 -303.097978) (xy 288.80603 -303.144659) (xy 288.783159 -303.188236) (xy 288.753594 -303.22758)
			(xy 288.718101 -303.261672) (xy 288.677598 -303.289628) (xy 288.633136 -303.310726) (xy 288.585865 -303.324418)
			(xy 288.53701 -303.33035) (xy 288.487835 -303.328369) (xy 288.439616 -303.318525) (xy 288.3936 -303.301073)
			(xy 288.350979 -303.276466) (xy 288.312858 -303.245341) (xy 288.280223 -303.208504) (xy 288.25392 -303.166908)
			(xy 288.234629 -303.121632) (xy 288.222852 -303.073848) (xy 288.218892 -303.024794) (xy 287.880044 -303.024794)
			(xy 287.879549 -303.049401) (xy 287.871654 -303.097978) (xy 287.85607 -303.144659) (xy 287.833199 -303.188236)
			(xy 287.803634 -303.22758) (xy 287.768141 -303.261672) (xy 287.727638 -303.289628) (xy 287.683176 -303.310726)
			(xy 287.635905 -303.324418) (xy 287.58705 -303.33035) (xy 287.537875 -303.328369) (xy 287.489656 -303.318525)
			(xy 287.44364 -303.301073) (xy 287.401019 -303.276466) (xy 287.362898 -303.245341) (xy 287.330263 -303.208504)
			(xy 287.30396 -303.166908) (xy 287.284669 -303.121632) (xy 287.272892 -303.073848) (xy 287.268932 -303.024794)
			(xy 286.930084 -303.024794) (xy 286.929589 -303.049401) (xy 286.921694 -303.097978) (xy 286.90611 -303.144659)
			(xy 286.883239 -303.188236) (xy 286.853674 -303.22758) (xy 286.818181 -303.261672) (xy 286.777678 -303.289628)
			(xy 286.733216 -303.310726) (xy 286.685945 -303.324418) (xy 286.63709 -303.33035) (xy 286.587915 -303.328369)
			(xy 286.539696 -303.318525) (xy 286.49368 -303.301073) (xy 286.451059 -303.276466) (xy 286.412938 -303.245341)
			(xy 286.380303 -303.208504) (xy 286.354 -303.166908) (xy 286.334709 -303.121632) (xy 286.322932 -303.073848)
			(xy 286.318972 -303.024794) (xy 285.980124 -303.024794) (xy 285.979629 -303.049401) (xy 285.971734 -303.097978)
			(xy 285.95615 -303.144659) (xy 285.933279 -303.188236) (xy 285.903714 -303.22758) (xy 285.868221 -303.261672)
			(xy 285.827718 -303.289628) (xy 285.783256 -303.310726) (xy 285.735985 -303.324418) (xy 285.68713 -303.33035)
			(xy 285.637955 -303.328369) (xy 285.589736 -303.318525) (xy 285.54372 -303.301073) (xy 285.501099 -303.276466)
			(xy 285.462978 -303.245341) (xy 285.430343 -303.208504) (xy 285.40404 -303.166908) (xy 285.384749 -303.121632)
			(xy 285.372972 -303.073848) (xy 285.369012 -303.024794) (xy 285.030164 -303.024794) (xy 285.029669 -303.049401)
			(xy 285.021774 -303.097978) (xy 285.00619 -303.144659) (xy 284.983319 -303.188236) (xy 284.953754 -303.22758)
			(xy 284.918261 -303.261672) (xy 284.877758 -303.289628) (xy 284.833296 -303.310726) (xy 284.786025 -303.324418)
			(xy 284.73717 -303.33035) (xy 284.687995 -303.328369) (xy 284.639776 -303.318525) (xy 284.59376 -303.301073)
			(xy 284.551139 -303.276466) (xy 284.513018 -303.245341) (xy 284.480383 -303.208504) (xy 284.45408 -303.166908)
			(xy 284.434789 -303.121632) (xy 284.423012 -303.073848) (xy 284.419052 -303.024794) (xy 284.080204 -303.024794)
			(xy 284.079709 -303.049401) (xy 284.071814 -303.097978) (xy 284.05623 -303.144659) (xy 284.033359 -303.188236)
			(xy 284.003794 -303.22758) (xy 283.968301 -303.261672) (xy 283.927798 -303.289628) (xy 283.883336 -303.310726)
			(xy 283.836065 -303.324418) (xy 283.78721 -303.33035) (xy 283.738035 -303.328369) (xy 283.689816 -303.318525)
			(xy 283.6438 -303.301073) (xy 283.601179 -303.276466) (xy 283.563058 -303.245341) (xy 283.530423 -303.208504)
			(xy 283.50412 -303.166908) (xy 283.484829 -303.121632) (xy 283.473052 -303.073848) (xy 283.469092 -303.024794)
			(xy 283.130244 -303.024794) (xy 283.129749 -303.049401) (xy 283.121854 -303.097978) (xy 283.10627 -303.144659)
			(xy 283.083399 -303.188236) (xy 283.053834 -303.22758) (xy 283.018341 -303.261672) (xy 282.977838 -303.289628)
			(xy 282.933376 -303.310726) (xy 282.886105 -303.324418) (xy 282.83725 -303.33035) (xy 282.788075 -303.328369)
			(xy 282.739856 -303.318525) (xy 282.69384 -303.301073) (xy 282.651219 -303.276466) (xy 282.613098 -303.245341)
			(xy 282.580463 -303.208504) (xy 282.55416 -303.166908) (xy 282.534869 -303.121632) (xy 282.523092 -303.073848)
			(xy 282.519132 -303.024794) (xy 282.18003 -303.024794) (xy 282.179535 -303.049401) (xy 282.17164 -303.097978)
			(xy 282.156056 -303.144659) (xy 282.133185 -303.188236) (xy 282.10362 -303.22758) (xy 282.068127 -303.261672)
			(xy 282.027624 -303.289628) (xy 281.983162 -303.310726) (xy 281.935891 -303.324418) (xy 281.887036 -303.33035)
			(xy 281.837861 -303.328369) (xy 281.789642 -303.318525) (xy 281.743626 -303.301073) (xy 281.701005 -303.276466)
			(xy 281.662884 -303.245341) (xy 281.630249 -303.208504) (xy 281.603946 -303.166908) (xy 281.584655 -303.121632)
			(xy 281.572878 -303.073848) (xy 281.568918 -303.024794) (xy 281.23007 -303.024794) (xy 281.229575 -303.049401)
			(xy 281.22168 -303.097978) (xy 281.206096 -303.144659) (xy 281.183225 -303.188236) (xy 281.15366 -303.22758)
			(xy 281.118167 -303.261672) (xy 281.077664 -303.289628) (xy 281.033202 -303.310726) (xy 280.985931 -303.324418)
			(xy 280.937076 -303.33035) (xy 280.887901 -303.328369) (xy 280.839682 -303.318525) (xy 280.793666 -303.301073)
			(xy 280.751045 -303.276466) (xy 280.712924 -303.245341) (xy 280.680289 -303.208504) (xy 280.653986 -303.166908)
			(xy 280.634695 -303.121632) (xy 280.622918 -303.073848) (xy 280.618958 -303.024794) (xy 280.28011 -303.024794)
			(xy 280.279615 -303.049401) (xy 280.27172 -303.097978) (xy 280.256136 -303.144659) (xy 280.233265 -303.188236)
			(xy 280.2037 -303.22758) (xy 280.168207 -303.261672) (xy 280.127704 -303.289628) (xy 280.083242 -303.310726)
			(xy 280.035971 -303.324418) (xy 279.987116 -303.33035) (xy 279.937941 -303.328369) (xy 279.889722 -303.318525)
			(xy 279.843706 -303.301073) (xy 279.801085 -303.276466) (xy 279.762964 -303.245341) (xy 279.730329 -303.208504)
			(xy 279.704026 -303.166908) (xy 279.684735 -303.121632) (xy 279.672958 -303.073848) (xy 279.668998 -303.024794)
			(xy 279.41397 -303.024794) (xy 279.41397 -303.928526) (xy 279.414431 -303.938403) (xy 279.421873 -303.956702)
			(xy 279.428448 -303.964086) (xy 279.428702 -303.96434) (xy 279.496266 -304.031904) (xy 279.497536 -304.033174)
			(xy 279.49779 -304.033174) (xy 279.505042 -304.03937) (xy 279.522777 -304.046353) (xy 279.541838 -304.046388)
			(xy 279.550876 -304.043334) (xy 279.651714 -304.00371) (xy 279.66924 -303.979072) (xy 279.669748 -303.963832)
			(xy 279.671211 -303.937818) (xy 279.68189 -303.886824) (xy 279.701067 -303.838382) (xy 279.728185 -303.793896)
			(xy 279.762459 -303.754657) (xy 279.802893 -303.721802) (xy 279.848316 -303.696284) (xy 279.897411 -303.678844)
			(xy 279.948752 -303.669987) (xy 279.974802 -303.669446) (xy 279.998794 -303.669917) (xy 280.046189 -303.677423)
			(xy 280.091825 -303.69225) (xy 280.134581 -303.714033) (xy 280.173403 -303.742235) (xy 280.207336 -303.776163)
			(xy 280.235544 -303.814981) (xy 280.257333 -303.857734) (xy 280.272167 -303.903369) (xy 280.27968 -303.950762)
			(xy 280.28011 -303.974754) (xy 280.28011 -303.984914) (xy 280.278604 -304.012428) (xy 280.266928 -304.066273)
			(xy 280.245797 -304.117157) (xy 280.231342 -304.140616) (xy 280.227278 -304.146712) (xy 280.222452 -304.16119)
			(xy 280.222452 -304.161698) (xy 280.22042 -304.16754) (xy 280.219404 -304.179732) (xy 280.220674 -304.186336)
			(xy 280.22138 -304.190373) (xy 280.223926 -304.198163) (xy 280.225754 -304.20183) (xy 280.266394 -304.278284)
			(xy 280.271048 -304.286246) (xy 280.284879 -304.298424) (xy 280.302136 -304.304889) (xy 280.311352 -304.305208)
			(xy 280.588212 -304.305208) (xy 280.59744 -304.304805) (xy 280.614693 -304.298251) (xy 280.628496 -304.286)
			(xy 280.63317 -304.27803) (xy 280.67254 -304.203862) (xy 280.675842 -304.196242) (xy 280.676858 -304.193194)
			(xy 280.679153 -304.185495) (xy 280.67927 -304.169438) (xy 280.677112 -304.161698) (xy 280.672286 -304.146712)
			(xy 280.668222 -304.140616) (xy 280.656641 -304.121993) (xy 280.638345 -304.082137) (xy 280.625919 -304.04008)
			(xy 280.619616 -303.996681) (xy 280.6192 -303.974754) (xy 280.619708 -303.960784) (xy 280.62047 -303.950624)
			(xy 280.62297 -303.925428) (xy 280.635246 -303.87631) (xy 280.655456 -303.829888) (xy 280.683044 -303.787436)
			(xy 280.717256 -303.750114) (xy 280.757155 -303.718946) (xy 280.801647 -303.694785) (xy 280.849515 -303.678293)
			(xy 280.899447 -303.66992) (xy 280.924762 -303.669446) (xy 280.948756 -303.669914) (xy 280.996155 -303.677415)
			(xy 281.041798 -303.692238) (xy 281.084559 -303.714019) (xy 281.123386 -303.742221) (xy 281.157324 -303.77615)
			(xy 281.185537 -303.814969) (xy 281.20733 -303.857725) (xy 281.222166 -303.903363) (xy 281.22968 -303.95076)
			(xy 281.23007 -303.974754) (xy 281.23007 -303.984914) (xy 281.228563 -304.012427) (xy 281.216886 -304.066272)
			(xy 281.195752 -304.117154) (xy 281.181302 -304.140616) (xy 281.177238 -304.146712) (xy 281.172412 -304.16119)
			(xy 281.172412 -304.161698) (xy 281.17038 -304.16754) (xy 281.169364 -304.179732) (xy 281.170634 -304.186336)
			(xy 281.171341 -304.190373) (xy 281.173889 -304.198161) (xy 281.175714 -304.20183) (xy 281.216354 -304.278284)
			(xy 281.221011 -304.28624) (xy 281.234845 -304.298401) (xy 281.2521 -304.304846) (xy 281.261312 -304.305208)
			(xy 281.538172 -304.305208) (xy 281.547404 -304.304812) (xy 281.564668 -304.298266) (xy 281.578483 -304.286017)
			(xy 281.58313 -304.27803) (xy 281.6225 -304.203862) (xy 281.625802 -304.196242) (xy 281.626818 -304.193194)
			(xy 281.629114 -304.185495) (xy 281.629232 -304.169437) (xy 281.627072 -304.161698) (xy 281.622246 -304.146712)
			(xy 281.618182 -304.140616) (xy 281.606599 -304.121993) (xy 281.5883 -304.082138) (xy 281.575871 -304.040081)
			(xy 281.569567 -303.996681) (xy 281.56916 -303.974754) (xy 281.569668 -303.960784) (xy 281.57043 -303.950624)
			(xy 281.57293 -303.92543) (xy 281.585208 -303.876316) (xy 281.605418 -303.829899) (xy 281.633008 -303.787452)
			(xy 281.667221 -303.750136) (xy 281.70712 -303.718975) (xy 281.751612 -303.694822) (xy 281.799479 -303.678338)
			(xy 281.849409 -303.669975) (xy 281.874722 -303.669446) (xy 281.898713 -303.669918) (xy 281.946105 -303.677427)
			(xy 281.991739 -303.692256) (xy 282.034492 -303.71404) (xy 282.073312 -303.742242) (xy 282.107242 -303.77617)
			(xy 282.135448 -303.814987) (xy 282.157235 -303.857739) (xy 282.172068 -303.903371) (xy 282.17958 -303.950763)
			(xy 282.18003 -303.974754) (xy 282.18003 -303.984914) (xy 282.178523 -304.012427) (xy 282.166845 -304.066271)
			(xy 282.145708 -304.117152) (xy 282.131262 -304.140616) (xy 282.127198 -304.146712) (xy 282.122372 -304.16119)
			(xy 282.122372 -304.161698) (xy 282.12034 -304.16754) (xy 282.119324 -304.179732) (xy 282.120594 -304.186336)
			(xy 282.1213 -304.190373) (xy 282.123847 -304.198162) (xy 282.125674 -304.20183) (xy 282.166314 -304.278284)
			(xy 282.17097 -304.286244) (xy 282.184801 -304.298416) (xy 282.202058 -304.304874) (xy 282.211272 -304.305208)
			(xy 282.488386 -304.305208) (xy 282.497616 -304.30481) (xy 282.514877 -304.298261) (xy 282.528687 -304.286011)
			(xy 282.533344 -304.27803) (xy 282.572714 -304.203862) (xy 282.576016 -304.196242) (xy 282.577032 -304.193194)
			(xy 282.579328 -304.185495) (xy 282.579445 -304.169438) (xy 282.577286 -304.161698) (xy 282.57246 -304.146712)
			(xy 282.568396 -304.140616) (xy 282.556816 -304.121992) (xy 282.538522 -304.082136) (xy 282.526096 -304.040079)
			(xy 282.519794 -303.996681) (xy 282.519374 -303.974754) (xy 282.519882 -303.960784) (xy 282.520644 -303.950624)
			(xy 282.523144 -303.92543) (xy 282.535422 -303.876317) (xy 282.555632 -303.829902) (xy 282.583222 -303.787455)
			(xy 282.617436 -303.750142) (xy 282.657335 -303.718982) (xy 282.701827 -303.69483) (xy 282.749694 -303.678349)
			(xy 282.799624 -303.669988) (xy 282.824936 -303.669446) (xy 282.848927 -303.669919) (xy 282.896317 -303.67743)
			(xy 282.941949 -303.69226) (xy 282.9847 -303.714044) (xy 283.023517 -303.742247) (xy 283.057446 -303.776175)
			(xy 283.08565 -303.814992) (xy 283.107437 -303.857742) (xy 283.122268 -303.903374) (xy 283.12978 -303.950763)
			(xy 283.130244 -303.974754) (xy 283.130244 -303.984914) (xy 283.128737 -304.012427) (xy 283.117059 -304.066272)
			(xy 283.095924 -304.117153) (xy 283.081476 -304.140616) (xy 283.077412 -304.146712) (xy 283.072586 -304.16119)
			(xy 283.072586 -304.161698) (xy 283.070554 -304.16754) (xy 283.069538 -304.179732) (xy 283.070808 -304.186336)
			(xy 283.071515 -304.190373) (xy 283.074062 -304.198162) (xy 283.075888 -304.20183) (xy 283.116528 -304.278284)
			(xy 283.121184 -304.286242) (xy 283.135017 -304.298411) (xy 283.152272 -304.304865) (xy 283.161486 -304.305208)
			(xy 283.438346 -304.305208) (xy 283.44758 -304.304816) (xy 283.464851 -304.298276) (xy 283.478674 -304.286029)
			(xy 283.483304 -304.27803) (xy 283.522674 -304.203862) (xy 283.525976 -304.196242) (xy 283.526992 -304.193194)
			(xy 283.529289 -304.185495) (xy 283.529407 -304.169437) (xy 283.527246 -304.161698) (xy 283.52242 -304.146712)
			(xy 283.518356 -304.140616) (xy 283.506774 -304.121993) (xy 283.488476 -304.082138) (xy 283.476049 -304.040081)
			(xy 283.469745 -303.996681) (xy 283.469334 -303.974754) (xy 283.469842 -303.960784) (xy 283.470604 -303.950624)
			(xy 283.473104 -303.925429) (xy 283.485381 -303.876313) (xy 283.505591 -303.829894) (xy 283.53318 -303.787445)
			(xy 283.567393 -303.750127) (xy 283.607292 -303.718963) (xy 283.651784 -303.694806) (xy 283.699651 -303.678318)
			(xy 283.749583 -303.669951) (xy 283.774896 -303.669446) (xy 283.798889 -303.669916) (xy 283.846284 -303.677422)
			(xy 283.891921 -303.692248) (xy 283.934678 -303.714031) (xy 283.973501 -303.742233) (xy 284.007434 -303.776161)
			(xy 284.035643 -303.81498) (xy 284.057433 -303.857733) (xy 284.072267 -303.903368) (xy 284.07978 -303.950761)
			(xy 284.080204 -303.974754) (xy 284.080204 -303.984914) (xy 284.078698 -304.012427) (xy 284.067022 -304.066273)
			(xy 284.04589 -304.117156) (xy 284.031436 -304.140616) (xy 284.027372 -304.146712) (xy 284.022546 -304.16119)
			(xy 284.022546 -304.161698) (xy 284.020514 -304.16754) (xy 284.019498 -304.179732) (xy 284.020768 -304.186336)
			(xy 284.021474 -304.190373) (xy 284.024019 -304.198163) (xy 284.025848 -304.20183) (xy 284.066488 -304.278284)
			(xy 284.071142 -304.286247) (xy 284.084973 -304.298426) (xy 284.10223 -304.304893) (xy 284.111446 -304.305208)
			(xy 284.388306 -304.305208) (xy 284.397535 -304.304806) (xy 284.414789 -304.298253) (xy 284.428594 -304.286002)
			(xy 284.433264 -304.27803) (xy 284.472634 -304.203862) (xy 284.475936 -304.196242) (xy 284.476952 -304.193194)
			(xy 284.479247 -304.185495) (xy 284.479365 -304.169438) (xy 284.477206 -304.161698) (xy 284.47238 -304.146712)
			(xy 284.468316 -304.140616) (xy 284.456735 -304.121993) (xy 284.43844 -304.082137) (xy 284.426014 -304.04008)
			(xy 284.419711 -303.996681) (xy 284.419294 -303.974754) (xy 284.419802 -303.960784) (xy 284.420564 -303.950624)
			(xy 284.423064 -303.925428) (xy 284.43534 -303.876309) (xy 284.45555 -303.829887) (xy 284.483138 -303.787434)
			(xy 284.51735 -303.750112) (xy 284.557248 -303.718944) (xy 284.601741 -303.694782) (xy 284.649609 -303.678288)
			(xy 284.699541 -303.669915) (xy 284.724856 -303.669446) (xy 284.748851 -303.669913) (xy 284.796251 -303.677414)
			(xy 284.841893 -303.692237) (xy 284.884655 -303.714017) (xy 284.923484 -303.742219) (xy 284.957423 -303.776148)
			(xy 284.985636 -303.814968) (xy 285.007429 -303.857723) (xy 285.022265 -303.903362) (xy 285.02978 -303.950759)
			(xy 285.030164 -303.974754) (xy 285.030164 -303.984914) (xy 285.028657 -304.012427) (xy 285.01698 -304.066272)
			(xy 284.995846 -304.117154) (xy 284.981396 -304.140616) (xy 284.977332 -304.146712) (xy 284.972506 -304.16119)
			(xy 284.972506 -304.161698) (xy 284.970474 -304.16754) (xy 284.969458 -304.179732) (xy 284.970728 -304.186336)
			(xy 284.971435 -304.190373) (xy 284.973983 -304.198161) (xy 284.975808 -304.20183) (xy 285.016448 -304.278284)
			(xy 285.021105 -304.28624) (xy 285.034939 -304.298403) (xy 285.052194 -304.30485) (xy 285.061406 -304.305208)
			(xy 285.338266 -304.305208) (xy 285.347498 -304.304813) (xy 285.364764 -304.298268) (xy 285.378581 -304.28602)
			(xy 285.383224 -304.27803) (xy 285.422594 -304.203862) (xy 285.425896 -304.196242) (xy 285.426912 -304.193194)
			(xy 285.429208 -304.185495) (xy 285.429326 -304.169437) (xy 285.427166 -304.161698) (xy 285.42234 -304.146712)
			(xy 285.418276 -304.140616) (xy 285.406694 -304.121993) (xy 285.388395 -304.082138) (xy 285.375966 -304.040081)
			(xy 285.369662 -303.996681) (xy 285.369254 -303.974754) (xy 285.369762 -303.960784) (xy 285.370524 -303.950624)
			(xy 285.373024 -303.92543) (xy 285.385301 -303.876315) (xy 285.405512 -303.829898) (xy 285.433101 -303.78745)
			(xy 285.467314 -303.750134) (xy 285.507213 -303.718972) (xy 285.551706 -303.694818) (xy 285.599573 -303.678333)
			(xy 285.649503 -303.66997) (xy 285.674816 -303.669446) (xy 285.698808 -303.669918) (xy 285.7462 -303.677426)
			(xy 285.791835 -303.692254) (xy 285.834589 -303.714037) (xy 285.873409 -303.74224) (xy 285.90734 -303.776168)
			(xy 285.935547 -303.814986) (xy 285.957335 -303.857737) (xy 285.972167 -303.903371) (xy 285.97968 -303.950762)
			(xy 285.980124 -303.974754) (xy 285.980124 -303.984914) (xy 285.978617 -304.012427) (xy 285.966938 -304.066271)
			(xy 285.945802 -304.117152) (xy 285.931356 -304.140616) (xy 285.927292 -304.146712) (xy 285.922466 -304.16119)
			(xy 285.922466 -304.161698) (xy 285.920434 -304.16754) (xy 285.919418 -304.179732) (xy 285.920688 -304.186336)
			(xy 285.921394 -304.190373) (xy 285.92394 -304.198162) (xy 285.925768 -304.20183) (xy 285.966408 -304.278284)
			(xy 285.971063 -304.286244) (xy 285.984895 -304.298418) (xy 286.002151 -304.304879) (xy 286.011366 -304.305208)
			(xy 286.288226 -304.305208) (xy 286.297453 -304.304803) (xy 286.314702 -304.298246) (xy 286.328501 -304.285993)
			(xy 286.333184 -304.27803) (xy 286.372554 -304.203862) (xy 286.375856 -304.196242) (xy 286.376872 -304.193194)
			(xy 286.379169 -304.185495) (xy 286.379287 -304.169437) (xy 286.377126 -304.161698) (xy 286.3723 -304.146712)
			(xy 286.368236 -304.140616) (xy 286.356655 -304.121993) (xy 286.338358 -304.082137) (xy 286.325932 -304.04008)
			(xy 286.319628 -303.996681) (xy 286.319214 -303.974754) (xy 286.319722 -303.960784) (xy 286.320484 -303.950624)
			(xy 286.322984 -303.925429) (xy 286.335261 -303.876311) (xy 286.35547 -303.829891) (xy 286.383059 -303.78744)
			(xy 286.417271 -303.75012) (xy 286.45717 -303.718953) (xy 286.501662 -303.694794) (xy 286.54953 -303.678303)
			(xy 286.599462 -303.669933) (xy 286.624776 -303.669446) (xy 286.64877 -303.669915) (xy 286.696167 -303.677418)
			(xy 286.741807 -303.692242) (xy 286.784567 -303.714024) (xy 286.823392 -303.742226) (xy 286.857328 -303.776154)
			(xy 286.885539 -303.814974) (xy 286.907331 -303.857728) (xy 286.922166 -303.903365) (xy 286.92968 -303.95076)
			(xy 286.930084 -303.974754) (xy 286.930084 -303.984914) (xy 286.928577 -304.012427) (xy 286.916901 -304.066273)
			(xy 286.895768 -304.117155) (xy 286.881316 -304.140616) (xy 286.877252 -304.146712) (xy 286.872426 -304.16119)
			(xy 286.872426 -304.161698) (xy 286.870394 -304.16754) (xy 286.869378 -304.179732) (xy 286.870648 -304.186336)
			(xy 286.871354 -304.190373) (xy 286.873898 -304.198163) (xy 286.875728 -304.20183) (xy 286.916368 -304.278284)
			(xy 286.921021 -304.286249) (xy 286.934851 -304.298434) (xy 286.952109 -304.304908) (xy 286.961326 -304.305208)
			(xy 287.238186 -304.305208) (xy 287.247416 -304.30481) (xy 287.264677 -304.298261) (xy 287.278487 -304.286011)
			(xy 287.283144 -304.27803) (xy 287.322514 -304.203862) (xy 287.325816 -304.196242) (xy 287.326832 -304.193194)
			(xy 287.329128 -304.185495) (xy 287.329245 -304.169438) (xy 287.327086 -304.161698) (xy 287.32226 -304.146712)
			(xy 287.318196 -304.140616) (xy 287.306616 -304.121992) (xy 287.288322 -304.082136) (xy 287.275896 -304.040079)
			(xy 287.269594 -303.996681) (xy 287.269174 -303.974754) (xy 287.269682 -303.960784) (xy 287.270444 -303.950624)
			(xy 287.272944 -303.92543) (xy 287.285222 -303.876317) (xy 287.305432 -303.829902) (xy 287.333022 -303.787455)
			(xy 287.367236 -303.750142) (xy 287.407135 -303.718982) (xy 287.451627 -303.69483) (xy 287.499494 -303.678349)
			(xy 287.549424 -303.669988) (xy 287.574736 -303.669446) (xy 287.598727 -303.669919) (xy 287.646117 -303.67743)
			(xy 287.691749 -303.69226) (xy 287.7345 -303.714044) (xy 287.773317 -303.742247) (xy 287.807246 -303.776175)
			(xy 287.83545 -303.814992) (xy 287.857237 -303.857742) (xy 287.872068 -303.903374) (xy 287.87958 -303.950763)
			(xy 287.880044 -303.974754) (xy 287.880044 -303.984914) (xy 287.878537 -304.012427) (xy 287.866859 -304.066272)
			(xy 287.845724 -304.117153) (xy 287.831276 -304.140616) (xy 287.827212 -304.146712) (xy 287.822386 -304.16119)
			(xy 287.822386 -304.161698) (xy 287.820354 -304.16754) (xy 287.819338 -304.179732) (xy 287.820608 -304.186336)
			(xy 287.821315 -304.190373) (xy 287.823862 -304.198162) (xy 287.825688 -304.20183) (xy 287.866328 -304.278284)
			(xy 287.870984 -304.286242) (xy 287.884817 -304.298411) (xy 287.902072 -304.304865) (xy 287.911286 -304.305208)
			(xy 288.188146 -304.305208) (xy 288.19738 -304.304816) (xy 288.214651 -304.298276) (xy 288.228474 -304.286029)
			(xy 288.233104 -304.27803) (xy 288.272474 -304.203862) (xy 288.275776 -304.196242) (xy 288.276792 -304.193194)
			(xy 288.279089 -304.185495) (xy 288.279207 -304.169437) (xy 288.277046 -304.161698) (xy 288.27222 -304.146712)
			(xy 288.268156 -304.140616) (xy 288.256574 -304.121993) (xy 288.238276 -304.082138) (xy 288.225849 -304.040081)
			(xy 288.219545 -303.996681) (xy 288.219134 -303.974754) (xy 288.219642 -303.960784) (xy 288.220404 -303.950624)
			(xy 288.222904 -303.925429) (xy 288.235181 -303.876313) (xy 288.255391 -303.829894) (xy 288.28298 -303.787445)
			(xy 288.317193 -303.750127) (xy 288.357092 -303.718963) (xy 288.401584 -303.694806) (xy 288.449451 -303.678318)
			(xy 288.499383 -303.669951) (xy 288.524696 -303.669446) (xy 288.548689 -303.669916) (xy 288.596084 -303.677422)
			(xy 288.641721 -303.692248) (xy 288.684478 -303.714031) (xy 288.723301 -303.742233) (xy 288.757234 -303.776161)
			(xy 288.785443 -303.81498) (xy 288.807233 -303.857733) (xy 288.822067 -303.903368) (xy 288.82958 -303.950761)
			(xy 288.830004 -303.974754) (xy 288.830004 -303.984914) (xy 288.828498 -304.012427) (xy 288.816822 -304.066273)
			(xy 288.79569 -304.117156) (xy 288.781236 -304.140616) (xy 288.777172 -304.146712) (xy 288.772346 -304.16119)
			(xy 288.772346 -304.161698) (xy 288.770314 -304.16754) (xy 288.769298 -304.179732) (xy 288.770568 -304.186336)
			(xy 288.771274 -304.190373) (xy 288.773819 -304.198163) (xy 288.775648 -304.20183) (xy 288.816288 -304.278284)
			(xy 288.820942 -304.286247) (xy 288.834773 -304.298426) (xy 288.85203 -304.304893) (xy 288.861246 -304.305208)
			(xy 289.13836 -304.305208) (xy 289.147593 -304.304814) (xy 289.16486 -304.298271) (xy 289.178678 -304.286022)
			(xy 289.183318 -304.27803) (xy 289.222688 -304.203862) (xy 289.22599 -304.196242) (xy 289.227006 -304.193194)
			(xy 289.229303 -304.185495) (xy 289.22942 -304.169437) (xy 289.22726 -304.161698) (xy 289.222434 -304.146712)
			(xy 289.21837 -304.140616) (xy 289.206788 -304.121993) (xy 289.188489 -304.082138) (xy 289.176061 -304.040081)
			(xy 289.169757 -303.996681) (xy 289.169348 -303.974754) (xy 289.169856 -303.960784) (xy 289.170618 -303.950624)
			(xy 289.173118 -303.92543) (xy 289.185395 -303.876314) (xy 289.205606 -303.829897) (xy 289.233195 -303.787449)
			(xy 289.267408 -303.750132) (xy 289.307307 -303.718969) (xy 289.351799 -303.694815) (xy 289.399666 -303.678329)
			(xy 289.449597 -303.669964) (xy 289.47491 -303.669446) (xy 289.498902 -303.669917) (xy 289.546295 -303.677424)
			(xy 289.591931 -303.692252) (xy 289.634685 -303.714035) (xy 289.673507 -303.742238) (xy 289.707438 -303.776166)
			(xy 289.735646 -303.814984) (xy 289.757434 -303.857736) (xy 289.772267 -303.90337) (xy 289.77978 -303.950762)
			(xy 289.780218 -303.974754) (xy 289.780218 -303.984914) (xy 289.778712 -304.012428) (xy 289.767037 -304.066273)
			(xy 289.745905 -304.117157) (xy 289.73145 -304.140616) (xy 289.727386 -304.146712) (xy 289.72256 -304.16119)
			(xy 289.72256 -304.161698) (xy 289.720528 -304.16754) (xy 289.719512 -304.179732) (xy 289.720782 -304.186336)
			(xy 289.721488 -304.190373) (xy 289.724034 -304.198162) (xy 289.725862 -304.20183) (xy 289.766502 -304.278284)
			(xy 289.771157 -304.286245) (xy 289.784988 -304.29842) (xy 289.802245 -304.304883) (xy 289.81146 -304.305208)
			(xy 290.08832 -304.305208) (xy 290.097547 -304.304804) (xy 290.114798 -304.298248) (xy 290.128599 -304.285996)
			(xy 290.133278 -304.27803) (xy 290.172648 -304.203862) (xy 290.17595 -304.196242) (xy 290.176966 -304.193194)
			(xy 290.17926 -304.185495) (xy 290.179378 -304.169438) (xy 290.17722 -304.161698) (xy 290.172394 -304.146712)
			(xy 290.16833 -304.140616) (xy 290.156749 -304.121993) (xy 290.138452 -304.082137) (xy 290.126026 -304.04008)
			(xy 290.119723 -303.996681) (xy 290.119308 -303.974754) (xy 290.119816 -303.960784) (xy 290.120578 -303.950624)
			(xy 290.123078 -303.925428) (xy 290.135355 -303.87631) (xy 290.155564 -303.82989) (xy 290.183153 -303.787438)
			(xy 290.217365 -303.750117) (xy 290.257263 -303.71895) (xy 290.301756 -303.69479) (xy 290.349624 -303.678299)
			(xy 290.399556 -303.669927) (xy 290.42487 -303.669446) (xy 290.448864 -303.669914) (xy 290.496262 -303.677416)
			(xy 290.541903 -303.692241) (xy 290.584663 -303.714022) (xy 290.62349 -303.742224) (xy 290.657427 -303.776152)
			(xy 290.685638 -303.814972) (xy 290.70743 -303.857727) (xy 290.722266 -303.903364) (xy 290.72978 -303.95076)
			(xy 290.730178 -303.974754) (xy 290.730178 -303.984914) (xy 290.728671 -304.012427) (xy 290.716995 -304.066272)
			(xy 290.695861 -304.117155) (xy 290.68141 -304.140616) (xy 290.677346 -304.146712) (xy 290.67252 -304.16119)
			(xy 290.67252 -304.161698) (xy 290.670488 -304.16754) (xy 290.669472 -304.179732) (xy 290.670742 -304.186336)
			(xy 290.671448 -304.190373) (xy 290.673992 -304.198163) (xy 290.675822 -304.20183) (xy 290.716462 -304.278284)
			(xy 290.72112 -304.286238) (xy 290.734954 -304.298397) (xy 290.752208 -304.30484) (xy 290.76142 -304.305208)
			(xy 291.98824 -304.305208) (xy 291.997475 -304.304817) (xy 292.014748 -304.298278) (xy 292.028572 -304.286031)
			(xy 292.033198 -304.27803) (xy 292.072568 -304.203862) (xy 292.07587 -304.196242) (xy 292.076886 -304.193194)
			(xy 292.079183 -304.185495) (xy 292.079301 -304.169437) (xy 292.07714 -304.161698) (xy 292.072314 -304.146712)
			(xy 292.06825 -304.140616) (xy 292.056668 -304.121993) (xy 292.038371 -304.082138) (xy 292.025944 -304.04008)
			(xy 292.01964 -303.996681) (xy 292.019228 -303.974754) (xy 292.019736 -303.960784) (xy 292.020498 -303.950624)
			(xy 292.022998 -303.925429) (xy 292.035275 -303.876312) (xy 292.055485 -303.829893) (xy 292.083074 -303.787443)
			(xy 292.117286 -303.750125) (xy 292.157185 -303.71896) (xy 292.201678 -303.694802) (xy 292.249545 -303.678314)
			(xy 292.299476 -303.669946) (xy 292.32479 -303.669446) (xy 292.348783 -303.669916) (xy 292.396179 -303.67742)
			(xy 292.441817 -303.692246) (xy 292.484574 -303.714029) (xy 292.523398 -303.742231) (xy 292.557333 -303.776159)
			(xy 292.585542 -303.814978) (xy 292.607332 -303.857731) (xy 292.622167 -303.903367) (xy 292.62968 -303.950761)
			(xy 292.630098 -303.974754) (xy 292.630098 -303.984914) (xy 292.628592 -304.012427) (xy 292.616916 -304.066273)
			(xy 292.595783 -304.117156) (xy 292.58133 -304.140616) (xy 292.577266 -304.146712) (xy 292.57244 -304.16119)
			(xy 292.57244 -304.161698) (xy 292.570408 -304.16754) (xy 292.569392 -304.179732) (xy 292.570662 -304.186336)
			(xy 292.571368 -304.190373) (xy 292.573913 -304.198163) (xy 292.575742 -304.20183) (xy 292.616382 -304.278284)
			(xy 292.621036 -304.286248) (xy 292.634866 -304.298428) (xy 292.652124 -304.304898) (xy 292.66134 -304.305208)
			(xy 292.9382 -304.305208) (xy 292.947429 -304.304807) (xy 292.964685 -304.298255) (xy 292.978492 -304.286005)
			(xy 292.983158 -304.27803) (xy 293.022528 -304.203862) (xy 293.02583 -304.196242) (xy 293.026846 -304.193194)
			(xy 293.029141 -304.185495) (xy 293.029259 -304.169438) (xy 293.0271 -304.161698) (xy 293.022274 -304.146712)
			(xy 293.01821 -304.140616) (xy 293.006629 -304.121993) (xy 292.988334 -304.082137) (xy 292.975909 -304.04008)
			(xy 292.969606 -303.996681) (xy 292.969188 -303.974754) (xy 292.969696 -303.960784) (xy 292.970458 -303.950624)
			(xy 292.972958 -303.925428) (xy 292.985234 -303.876308) (xy 293.005443 -303.829886) (xy 293.033032 -303.787433)
			(xy 293.067243 -303.75011) (xy 293.107142 -303.718941) (xy 293.151634 -303.694778) (xy 293.199502 -303.678283)
			(xy 293.249435 -303.669909) (xy 293.27475 -303.669446) (xy 293.29874 -303.66992) (xy 293.346128 -303.677432)
			(xy 293.391759 -303.692264) (xy 293.434508 -303.714049) (xy 293.473323 -303.742253) (xy 293.50725 -303.77618)
			(xy 293.535453 -303.814996) (xy 293.557238 -303.857745) (xy 293.572069 -303.903376) (xy 293.57958 -303.950764)
			(xy 293.580058 -303.974754) (xy 293.580058 -303.984914) (xy 293.578551 -304.012427) (xy 293.566874 -304.066272)
			(xy 293.545739 -304.117154) (xy 293.53129 -304.140616) (xy 293.527226 -304.146712) (xy 293.5224 -304.16119)
			(xy 293.5224 -304.161698) (xy 293.520368 -304.16754) (xy 293.519352 -304.179732) (xy 293.520622 -304.186336)
			(xy 293.521329 -304.190373) (xy 293.523876 -304.198161) (xy 293.525702 -304.20183) (xy 293.566342 -304.278284)
			(xy 293.570999 -304.286241) (xy 293.584832 -304.298405) (xy 293.602087 -304.304855) (xy 293.6113 -304.305208)
			(xy 293.88816 -304.305208) (xy 293.897393 -304.304814) (xy 293.91466 -304.298271) (xy 293.928478 -304.286022)
			(xy 293.933118 -304.27803) (xy 293.972488 -304.203862) (xy 293.97579 -304.196242) (xy 293.976806 -304.193194)
			(xy 293.979103 -304.185495) (xy 293.97922 -304.169437) (xy 293.97706 -304.161698) (xy 293.972234 -304.146712)
			(xy 293.96817 -304.140616) (xy 293.956588 -304.121993) (xy 293.938289 -304.082138) (xy 293.925861 -304.040081)
			(xy 293.919557 -303.996681) (xy 293.919148 -303.974754) (xy 293.919656 -303.960784) (xy 293.920418 -303.950624)
			(xy 293.922918 -303.92543) (xy 293.935195 -303.876314) (xy 293.955406 -303.829897) (xy 293.982995 -303.787449)
			(xy 294.017208 -303.750132) (xy 294.057107 -303.718969) (xy 294.101599 -303.694815) (xy 294.149466 -303.678329)
			(xy 294.199397 -303.669964) (xy 294.22471 -303.669446) (xy 294.248702 -303.669917) (xy 294.296095 -303.677424)
			(xy 294.341731 -303.692252) (xy 294.384485 -303.714035) (xy 294.423307 -303.742238) (xy 294.457238 -303.776166)
			(xy 294.485446 -303.814984) (xy 294.507234 -303.857736) (xy 294.522067 -303.90337) (xy 294.52958 -303.950762)
			(xy 294.530018 -303.974754) (xy 294.530018 -303.984914) (xy 294.528512 -304.012428) (xy 294.516837 -304.066273)
			(xy 294.495705 -304.117157) (xy 294.48125 -304.140616) (xy 294.477186 -304.146712) (xy 294.47236 -304.16119)
			(xy 294.47236 -304.161698) (xy 294.470328 -304.16754) (xy 294.469312 -304.179732) (xy 294.470582 -304.186336)
			(xy 294.471288 -304.190373) (xy 294.473834 -304.198162) (xy 294.475662 -304.20183) (xy 294.516302 -304.278284)
			(xy 294.520957 -304.286245) (xy 294.534788 -304.29842) (xy 294.552045 -304.304883) (xy 294.56126 -304.305208)
			(xy 294.838374 -304.305208) (xy 294.847606 -304.304812) (xy 294.864869 -304.298265) (xy 294.878683 -304.286016)
			(xy 294.883332 -304.27803) (xy 294.922702 -304.203862) (xy 294.926004 -304.196242) (xy 294.92702 -304.193194)
			(xy 294.929316 -304.185495) (xy 294.929434 -304.169437) (xy 294.927274 -304.161698) (xy 294.922448 -304.146712)
			(xy 294.918384 -304.140616) (xy 294.906801 -304.121993) (xy 294.888502 -304.082138) (xy 294.876073 -304.040081)
			(xy 294.869769 -303.996681) (xy 294.869362 -303.974754) (xy 294.86987 -303.960784) (xy 294.870632 -303.950624)
			(xy 294.873132 -303.92543) (xy 294.88541 -303.876316) (xy 294.90562 -303.829899) (xy 294.93321 -303.787452)
			(xy 294.967423 -303.750137) (xy 295.007322 -303.718976) (xy 295.051814 -303.694823) (xy 295.099681 -303.678339)
			(xy 295.149611 -303.669977) (xy 295.174924 -303.669446) (xy 295.198915 -303.669918) (xy 295.246307 -303.677427)
			(xy 295.291941 -303.692256) (xy 295.334693 -303.71404) (xy 295.373512 -303.742243) (xy 295.407442 -303.776171)
			(xy 295.435648 -303.814988) (xy 295.457435 -303.857739) (xy 295.472268 -303.903372) (xy 295.47978 -303.950763)
			(xy 295.480232 -303.974754) (xy 295.480232 -303.984914) (xy 295.478725 -304.012427) (xy 295.467047 -304.066271)
			(xy 295.445911 -304.117152) (xy 295.431464 -304.140616) (xy 295.4274 -304.146712) (xy 295.422574 -304.16119)
			(xy 295.422574 -304.161698) (xy 295.420542 -304.16754) (xy 295.419526 -304.179732) (xy 295.420796 -304.186336)
			(xy 295.421502 -304.190373) (xy 295.424049 -304.198162) (xy 295.425876 -304.20183) (xy 295.466516 -304.278284)
			(xy 295.471172 -304.286244) (xy 295.485004 -304.298415) (xy 295.50226 -304.304873) (xy 295.511474 -304.305208)
			(xy 295.788334 -304.305208) (xy 295.79756 -304.304802) (xy 295.814807 -304.298242) (xy 295.828604 -304.28599)
			(xy 295.833292 -304.27803) (xy 295.872662 -304.203862) (xy 295.875964 -304.196242) (xy 295.87698 -304.193194)
			(xy 295.879277 -304.185495) (xy 295.879395 -304.169437) (xy 295.877234 -304.161698) (xy 295.872408 -304.146712)
			(xy 295.868344 -304.140616) (xy 295.856763 -304.121993) (xy 295.838466 -304.082137) (xy 295.826038 -304.04008)
			(xy 295.819735 -303.996681) (xy 295.819322 -303.974754) (xy 295.81983 -303.960784) (xy 295.820592 -303.950624)
			(xy 295.823092 -303.925429) (xy 295.835369 -303.876312) (xy 295.855579 -303.829892) (xy 295.883167 -303.787442)
			(xy 295.91738 -303.750123) (xy 295.957279 -303.718957) (xy 296.001771 -303.694799) (xy 296.049639 -303.678309)
			(xy 296.09957 -303.66994) (xy 296.124884 -303.669446) (xy 296.148877 -303.669915) (xy 296.196274 -303.677419)
			(xy 296.241913 -303.692245) (xy 296.284671 -303.714027) (xy 296.323496 -303.742229) (xy 296.357431 -303.776157)
			(xy 296.385641 -303.814976) (xy 296.407432 -303.85773) (xy 296.422266 -303.903366) (xy 296.42978 -303.950761)
			(xy 296.430192 -303.974754) (xy 296.430192 -303.984914) (xy 296.428685 -304.012427) (xy 296.417009 -304.066273)
			(xy 296.395876 -304.117156) (xy 296.381424 -304.140616) (xy 296.37736 -304.146712) (xy 296.372534 -304.16119)
			(xy 296.372534 -304.161698) (xy 296.370502 -304.16754) (xy 296.369486 -304.179732) (xy 296.370756 -304.186336)
			(xy 296.371462 -304.190373) (xy 296.374006 -304.198163) (xy 296.375836 -304.20183) (xy 296.416476 -304.278284)
			(xy 296.42113 -304.286248) (xy 296.43496 -304.298431) (xy 296.452217 -304.304902) (xy 296.461434 -304.305208)
			(xy 296.738294 -304.305208) (xy 296.747524 -304.304808) (xy 296.764782 -304.298258) (xy 296.77859 -304.286007)
			(xy 296.783252 -304.27803) (xy 296.822622 -304.203862) (xy 296.825924 -304.196242) (xy 296.82694 -304.193194)
			(xy 296.829235 -304.185495) (xy 296.829353 -304.169438) (xy 296.827194 -304.161698) (xy 296.822368 -304.146712)
			(xy 296.818304 -304.140616) (xy 296.806724 -304.121993) (xy 296.788429 -304.082137) (xy 296.776003 -304.04008)
			(xy 296.769701 -303.996681) (xy 296.769282 -303.974754) (xy 296.76979 -303.960784) (xy 296.770552 -303.950624)
			(xy 296.773052 -303.925427) (xy 296.785328 -303.876308) (xy 296.805537 -303.829885) (xy 296.833125 -303.787431)
			(xy 296.867337 -303.750108) (xy 296.907235 -303.718938) (xy 296.951728 -303.694774) (xy 296.999596 -303.678279)
			(xy 297.049529 -303.669904) (xy 297.074844 -303.669446) (xy 297.098834 -303.66992) (xy 297.146223 -303.677431)
			(xy 297.191854 -303.692262) (xy 297.234604 -303.714047) (xy 297.273421 -303.74225) (xy 297.307348 -303.776178)
			(xy 297.335552 -303.814994) (xy 297.357337 -303.857744) (xy 297.372168 -303.903375) (xy 297.37968 -303.950764)
			(xy 297.380152 -303.974754) (xy 297.380152 -303.984914) (xy 297.378645 -304.012427) (xy 297.366968 -304.066272)
			(xy 297.345833 -304.117153) (xy 297.331384 -304.140616) (xy 297.32732 -304.146712) (xy 297.322494 -304.16119)
			(xy 297.322494 -304.161698) (xy 297.320462 -304.16754) (xy 297.319446 -304.179732) (xy 297.320716 -304.186336)
			(xy 297.321423 -304.190373) (xy 297.32397 -304.198161) (xy 297.325796 -304.20183) (xy 297.366436 -304.278284)
			(xy 297.371092 -304.286241) (xy 297.384925 -304.298408) (xy 297.402181 -304.304859) (xy 297.411394 -304.305208)
			(xy 297.688254 -304.305208) (xy 297.697488 -304.304815) (xy 297.714756 -304.298273) (xy 297.728576 -304.286025)
			(xy 297.733212 -304.27803) (xy 297.772582 -304.203862) (xy 297.775884 -304.196242) (xy 297.7769 -304.193194)
			(xy 297.779196 -304.185495) (xy 297.779314 -304.169437) (xy 297.777154 -304.161698) (xy 297.772328 -304.146712)
			(xy 297.768264 -304.140616) (xy 297.756682 -304.121993) (xy 297.738384 -304.082138) (xy 297.725956 -304.040081)
			(xy 297.719652 -303.996681) (xy 297.719242 -303.974754) (xy 297.71975 -303.960784) (xy 297.720512 -303.950624)
			(xy 297.723012 -303.925429) (xy 297.735289 -303.876314) (xy 297.755499 -303.829896) (xy 297.783089 -303.787447)
			(xy 297.817301 -303.75013) (xy 297.8572 -303.718967) (xy 297.901693 -303.694811) (xy 297.94956 -303.678324)
			(xy 297.999491 -303.669959) (xy 298.024804 -303.669446) (xy 298.048796 -303.669917) (xy 298.09619 -303.677423)
			(xy 298.141827 -303.69225) (xy 298.184582 -303.714033) (xy 298.223404 -303.742236) (xy 298.257337 -303.776164)
			(xy 298.285545 -303.814982) (xy 298.307334 -303.857734) (xy 298.322167 -303.903369) (xy 298.32968 -303.950762)
			(xy 298.330112 -303.974754) (xy 298.330112 -303.984914) (xy 298.328606 -304.012428) (xy 298.31693 -304.066273)
			(xy 298.295799 -304.117157) (xy 298.281344 -304.140616) (xy 298.27728 -304.146712) (xy 298.272454 -304.16119)
			(xy 298.272454 -304.161698) (xy 298.270422 -304.16754) (xy 298.269406 -304.179732) (xy 298.270676 -304.186336)
			(xy 298.271382 -304.190373) (xy 298.273928 -304.198163) (xy 298.275756 -304.20183) (xy 298.316396 -304.278284)
			(xy 298.321051 -304.286246) (xy 298.334882 -304.298423) (xy 298.352138 -304.304887) (xy 298.361354 -304.305208)
			(xy 298.638214 -304.305208) (xy 298.647442 -304.304805) (xy 298.664694 -304.29825) (xy 298.678497 -304.285999)
			(xy 298.683172 -304.27803) (xy 298.722542 -304.203862) (xy 298.725844 -304.196242) (xy 298.72686 -304.193194)
			(xy 298.729154 -304.185495) (xy 298.729272 -304.169438) (xy 298.727114 -304.161698) (xy 298.722288 -304.146712)
			(xy 298.718224 -304.140616) (xy 298.706643 -304.121993) (xy 298.688347 -304.082137) (xy 298.675921 -304.04008)
			(xy 298.669618 -303.996681) (xy 298.669202 -303.974754) (xy 298.66971 -303.960784) (xy 298.670472 -303.950624)
			(xy 298.672972 -303.925428) (xy 298.685248 -303.87631) (xy 298.705458 -303.829889) (xy 298.733046 -303.787436)
			(xy 298.767258 -303.750115) (xy 298.807157 -303.718947) (xy 298.851649 -303.694786) (xy 298.899517 -303.678294)
			(xy 298.94945 -303.669922) (xy 298.974764 -303.669446) (xy 298.998758 -303.669914) (xy 299.046157 -303.677415)
			(xy 299.091799 -303.692239) (xy 299.13456 -303.71402) (xy 299.173387 -303.742222) (xy 299.207325 -303.77615)
			(xy 299.235537 -303.81497) (xy 299.25733 -303.857725) (xy 299.272166 -303.903363) (xy 299.27968 -303.95076)
			(xy 299.280072 -303.974754) (xy 299.280072 -303.984914) (xy 299.278565 -304.012427) (xy 299.266888 -304.066272)
			(xy 299.245754 -304.117154) (xy 299.231304 -304.140616) (xy 299.22724 -304.146712) (xy 299.222414 -304.16119)
			(xy 299.222414 -304.161698) (xy 299.220382 -304.16754) (xy 299.219366 -304.179732) (xy 299.220636 -304.186336)
			(xy 299.221342 -304.190373) (xy 299.223885 -304.198164) (xy 299.225716 -304.20183) (xy 299.266356 -304.278284)
			(xy 299.271013 -304.286239) (xy 299.284847 -304.2984) (xy 299.302102 -304.304845) (xy 299.311314 -304.305208)
			(xy 299.588174 -304.305208) (xy 299.597406 -304.304812) (xy 299.614669 -304.298265) (xy 299.628483 -304.286016)
			(xy 299.633132 -304.27803) (xy 299.672502 -304.203862) (xy 299.675804 -304.196242) (xy 299.67682 -304.193194)
			(xy 299.679116 -304.185495) (xy 299.679234 -304.169437) (xy 299.677074 -304.161698) (xy 299.672248 -304.146712)
			(xy 299.668184 -304.140616) (xy 299.656601 -304.121993) (xy 299.638302 -304.082138) (xy 299.625873 -304.040081)
			(xy 299.619569 -303.996681) (xy 299.619162 -303.974754) (xy 299.61967 -303.960784) (xy 299.620432 -303.950624)
			(xy 299.622932 -303.92543) (xy 299.63521 -303.876316) (xy 299.65542 -303.829899) (xy 299.68301 -303.787452)
			(xy 299.717223 -303.750137) (xy 299.757122 -303.718976) (xy 299.801614 -303.694823) (xy 299.849481 -303.678339)
			(xy 299.899411 -303.669977) (xy 299.924724 -303.669446) (xy 299.948715 -303.669918) (xy 299.996107 -303.677427)
			(xy 300.041741 -303.692256) (xy 300.084493 -303.71404) (xy 300.123312 -303.742243) (xy 300.157242 -303.776171)
			(xy 300.185448 -303.814988) (xy 300.207235 -303.857739) (xy 300.222068 -303.903372) (xy 300.22958 -303.950763)
			(xy 300.230032 -303.974754) (xy 300.230032 -303.984914) (xy 300.228525 -304.012427) (xy 300.216847 -304.066271)
			(xy 300.195711 -304.117152) (xy 300.181264 -304.140616) (xy 300.1772 -304.146712) (xy 300.172374 -304.16119)
			(xy 300.172374 -304.161698) (xy 300.170342 -304.16754) (xy 300.169326 -304.179732) (xy 300.170596 -304.186336)
			(xy 300.171302 -304.190373) (xy 300.173849 -304.198162) (xy 300.175676 -304.20183) (xy 300.216316 -304.278284)
			(xy 300.220972 -304.286244) (xy 300.234804 -304.298415) (xy 300.25206 -304.304873) (xy 300.261274 -304.305208)
			(xy 300.560994 -304.305208) (xy 300.585124 -304.290476) (xy 300.591728 -304.277776) (xy 300.639988 -304.185066)
			(xy 300.637956 -304.157126) (xy 300.629828 -304.145188) (xy 300.616775 -304.125822) (xy 300.59608 -304.083959)
			(xy 300.582008 -304.039431) (xy 300.574886 -303.993278) (xy 300.574456 -303.969928) (xy 300.574924 -303.945934)
			(xy 300.582427 -303.898537) (xy 300.597251 -303.852897) (xy 300.619033 -303.810138) (xy 300.647235 -303.771312)
			(xy 300.681164 -303.737377) (xy 300.719983 -303.709166) (xy 300.762738 -303.687376) (xy 300.808375 -303.672542)
			(xy 300.85577 -303.66503) (xy 300.879764 -303.66462) (xy 300.903538 -303.665078) (xy 300.950511 -303.672458)
			(xy 300.995773 -303.687029) (xy 301.038229 -303.708439) (xy 301.076853 -303.736171) (xy 301.110713 -303.769554)
			(xy 301.138989 -303.807782) (xy 301.160998 -303.849931) (xy 301.176209 -303.894981) (xy 301.184253 -303.941845)
			(xy 301.185072 -303.96561) (xy 301.185072 -303.970436) (xy 301.184659 -303.992865) (xy 301.178062 -304.037236)
			(xy 301.165045 -304.080164) (xy 301.145887 -304.120726) (xy 301.133764 -304.1396) (xy 301.13351 -304.139854)
			(xy 301.1297 -304.145696) (xy 301.124366 -304.161952) (xy 301.121775 -304.171728) (xy 301.123481 -304.191861)
			(xy 301.127668 -304.201068) (xy 301.1678 -304.277776) (xy 301.171589 -304.28451) (xy 301.182452 -304.295488)
			(xy 301.189136 -304.299366) (xy 301.200312 -304.305208) (xy 301.488348 -304.305208) (xy 301.497582 -304.304816)
			(xy 301.514853 -304.298275) (xy 301.528674 -304.286028) (xy 301.533306 -304.27803) (xy 301.572676 -304.203862)
			(xy 301.575978 -304.196242) (xy 301.576994 -304.193194) (xy 301.579291 -304.185495) (xy 301.579408 -304.169437)
			(xy 301.577248 -304.161698) (xy 301.572422 -304.146712) (xy 301.568358 -304.140616) (xy 301.556776 -304.121993)
			(xy 301.538478 -304.082138) (xy 301.526051 -304.040081) (xy 301.519747 -303.996681) (xy 301.519336 -303.974754)
			(xy 301.519844 -303.960784) (xy 301.520606 -303.950624) (xy 301.523226 -303.924545) (xy 301.53624 -303.873776)
			(xy 301.557723 -303.82597) (xy 301.587046 -303.78253) (xy 301.623348 -303.744727) (xy 301.665566 -303.713671)
			(xy 301.688754 -303.70145) (xy 301.696374 -303.69764) (xy 301.710598 -303.683416) (xy 301.711106 -303.682908)
			(xy 301.717687 -303.675527) (xy 301.725131 -303.657227) (xy 301.725584 -303.647348) (xy 301.725584 -303.39284)
			(xy 301.725233 -303.383582) (xy 301.71872 -303.366254) (xy 301.712884 -303.359058) (xy 301.692056 -303.33569)
			(xy 301.692818 -303.330864) (xy 301.670974 -303.29251) (xy 301.662846 -303.283874) (xy 301.657766 -303.280318)
			(xy 301.638045 -303.26685) (xy 301.602655 -303.234789) (xy 301.572683 -303.197613) (xy 301.548859 -303.156227)
			(xy 301.531763 -303.111639) (xy 301.521811 -303.064934) (xy 301.519245 -303.017249) (xy 301.524129 -302.969746)
			(xy 301.536342 -302.923581) (xy 301.555589 -302.879878) (xy 301.581399 -302.839701) (xy 301.613145 -302.804028)
			(xy 301.63135 -302.788574) (xy 301.648464 -302.775029) (xy 301.685819 -302.75246) (xy 301.705772 -302.743616)
			(xy 301.716186 -302.739298) (xy 301.746412 -302.706024) (xy 301.749714 -302.694848) (xy 301.758823 -302.665973)
			(xy 301.782287 -302.610154) (xy 301.81148 -302.557106) (xy 301.828454 -302.532034) (xy 301.828708 -302.53178)
			(xy 301.835363 -302.520971) (xy 301.838173 -302.495775) (xy 301.834042 -302.483774) (xy 301.797466 -302.393096)
			(xy 301.777908 -302.37684) (xy 301.765208 -302.3743) (xy 301.739576 -302.368643) (xy 301.690608 -302.349746)
			(xy 301.645593 -302.322756) (xy 301.605855 -302.288467) (xy 301.572564 -302.247888) (xy 301.546702 -302.202216)
			(xy 301.529029 -302.152794) (xy 301.520066 -302.101078) (xy 301.51959 -302.074834) (xy 301.520112 -302.049579)
			(xy 301.528425 -301.999757) (xy 301.544826 -301.951983) (xy 301.568867 -301.90756) (xy 301.599891 -301.8677)
			(xy 301.637053 -301.83349) (xy 301.679339 -301.805864) (xy 301.725595 -301.785574) (xy 301.77456 -301.773174)
			(xy 301.824898 -301.769003) (xy 301.875236 -301.773174) (xy 301.924201 -301.785574) (xy 301.970457 -301.805864)
			(xy 302.012743 -301.83349) (xy 302.049905 -301.8677) (xy 302.080929 -301.90756) (xy 302.10497 -301.951983)
			(xy 302.121371 -301.999757) (xy 302.129684 -302.049579) (xy 302.130206 -302.074834) (xy 302.129698 -302.09109)
			(xy 302.129698 -302.095662) (xy 302.130116 -302.105712) (xy 302.137814 -302.124279) (xy 302.152047 -302.13847)
			(xy 302.161194 -302.142652) (xy 302.175164 -302.148494) (xy 302.20539 -302.142398) (xy 302.273462 -302.074072)
			(xy 302.295595 -302.052541) (xy 302.343704 -302.013829) (xy 302.395675 -301.980481) (xy 302.450912 -301.952879)
			(xy 302.47971 -301.941738) (xy 302.487076 -301.938944) (xy 302.51146 -301.920148) (xy 302.516286 -301.912528)
			(xy 302.529045 -301.893026) (xy 302.559531 -301.857781) (xy 302.595023 -301.827581) (xy 302.634694 -301.80313)
			(xy 302.655986 -301.793656) (xy 302.66547 -301.788621) (xy 302.679404 -301.772309) (xy 302.68291 -301.76216)
			(xy 302.693622 -301.728238) (xy 302.722272 -301.663122) (xy 302.758724 -301.602032) (xy 302.802423 -301.545896)
			(xy 302.827182 -301.520352) (xy 302.831246 -301.516288) (xy 302.83794 -301.508845) (xy 302.845537 -301.490348)
			(xy 302.845517 -301.470351) (xy 302.842168 -301.460916) (xy 302.836326 -301.446692) (xy 302.810926 -301.429674)
			(xy 302.791114 -301.429674) (xy 302.774858 -301.430182) (xy 302.75004 -301.429693) (xy 302.70106 -301.421656)
			(xy 302.654025 -301.405802) (xy 302.610175 -301.382548) (xy 302.570664 -301.352505) (xy 302.536533 -301.316467)
			(xy 302.508682 -301.275382) (xy 302.487845 -301.230333) (xy 302.47457 -301.182506) (xy 302.469207 -301.133161)
			(xy 302.471897 -301.083599) (xy 302.482569 -301.035125) (xy 302.500943 -300.989016) (xy 302.526535 -300.946487)
			(xy 302.558669 -300.908658) (xy 302.5965 -300.876525) (xy 302.63903 -300.850936) (xy 302.68514 -300.832565)
			(xy 302.733615 -300.821895) (xy 302.783177 -300.819207) (xy 302.832522 -300.824573) (xy 302.880348 -300.83785)
			(xy 302.925396 -300.85869) (xy 302.96648 -300.886543) (xy 303.002516 -300.920676) (xy 303.032556 -300.960188)
			(xy 303.055808 -301.00404) (xy 303.07166 -301.051076) (xy 303.079694 -301.100056) (xy 303.080166 -301.124874)
			(xy 303.079658 -301.14113) (xy 303.079658 -301.145702) (xy 303.0802 -301.155686) (xy 303.087932 -301.174103)
			(xy 303.102108 -301.188176) (xy 303.111154 -301.192438) (xy 303.125378 -301.198534) (xy 303.15535 -301.192438)
			(xy 303.227486 -301.120048) (xy 303.249393 -301.09869) (xy 303.296976 -301.060224) (xy 303.348362 -301.027009)
			(xy 303.402974 -300.999418) (xy 303.431448 -300.988222) (xy 303.431702 -300.988222) (xy 303.439576 -300.985174)
			(xy 303.464722 -300.964854) (xy 303.46904 -300.957996) (xy 303.481803 -300.93921) (xy 303.511989 -300.905279)
			(xy 303.546867 -300.876192) (xy 303.585667 -300.852589) (xy 303.606454 -300.843442) (xy 303.611538 -300.841173)
			(xy 303.620639 -300.834765) (xy 303.624488 -300.830742) (xy 303.647094 -300.80585) (xy 303.650396 -300.794674)
			(xy 303.663179 -300.754858) (xy 303.698626 -300.679122) (xy 303.721008 -300.643798) (xy 303.722786 -300.641258)
			(xy 303.72304 -300.64075) (xy 303.728882 -300.631606) (xy 303.734216 -300.61408) (xy 303.736042 -300.607564)
			(xy 303.736554 -300.594047) (xy 303.735232 -300.58741) (xy 303.734216 -300.583346) (xy 303.69764 -300.493176)
			(xy 303.678082 -300.47692) (xy 303.665382 -300.47438) (xy 303.639736 -300.468735) (xy 303.590739 -300.449859)
			(xy 303.545691 -300.422882) (xy 303.505921 -300.388598) (xy 303.472599 -300.348018) (xy 303.446709 -300.302337)
			(xy 303.429011 -300.252902) (xy 303.420029 -300.201168) (xy 303.41951 -300.174914) (xy 303.419955 -300.150921)
			(xy 303.42746 -300.103525) (xy 303.442288 -300.057886) (xy 303.464073 -300.015129) (xy 303.492278 -299.976307)
			(xy 303.52621 -299.942376) (xy 303.565033 -299.914171) (xy 303.60779 -299.892386) (xy 303.653428 -299.877559)
			(xy 303.700825 -299.870055) (xy 303.724818 -299.869606) (xy 303.750658 -299.870156) (xy 303.801597 -299.878871)
			(xy 303.850344 -299.896033) (xy 303.895508 -299.921153) (xy 303.935801 -299.953513) (xy 303.970075 -299.992192)
			(xy 303.997353 -300.036086) (xy 304.016856 -300.083944) (xy 304.028028 -300.134402) (xy 304.029872 -300.160182)
			(xy 304.030813 -300.169961) (xy 304.039069 -300.187767) (xy 304.053389 -300.201191) (xy 304.062384 -300.20514)
			(xy 304.082704 -300.213014) (xy 304.093064 -300.217115) (xy 304.115321 -300.216987) (xy 304.12563 -300.21276)
			(xy 304.14214 -300.206664) (xy 304.148998 -300.200822) (xy 304.171997 -300.181593) (xy 304.221307 -300.147491)
			(xy 304.273897 -300.118704) (xy 304.329196 -300.095543) (xy 304.357786 -300.086522) (xy 304.358548 -300.086268)
			(xy 304.373026 -300.081442) (xy 304.389028 -300.06671) (xy 304.393346 -300.05655) (xy 304.396648 -300.04893)
			(xy 304.39995 -300.041818) (xy 304.39995 -300.04131) (xy 304.411081 -300.019581) (xy 304.439186 -299.979663)
			(xy 304.473275 -299.944716) (xy 304.512484 -299.91563) (xy 304.555815 -299.893141) (xy 304.602169 -299.877823)
			(xy 304.650368 -299.870064) (xy 304.674778 -299.869606) (xy 304.698616 -299.870064) (xy 304.745713 -299.877477)
			(xy 304.791083 -299.892125) (xy 304.833622 -299.913653) (xy 304.872295 -299.941535) (xy 304.90616 -299.975094)
			(xy 304.934393 -300.013512) (xy 304.945796 -300.034452) (xy 304.9524 -300.047152) (xy 304.97653 -300.061884)
			(xy 305.322986 -300.061884) (xy 305.347116 -300.047152) (xy 305.35372 -300.034452) (xy 305.366001 -300.011902)
			(xy 305.396921 -299.970911) (xy 305.434264 -299.935671) (xy 305.476976 -299.907175) (xy 305.523853 -299.886227)
			(xy 305.573574 -299.873417) (xy 305.624738 -299.869107) (xy 305.675902 -299.873417) (xy 305.725623 -299.886227)
			(xy 305.7725 -299.907175) (xy 305.815212 -299.935671) (xy 305.852555 -299.970911) (xy 305.883475 -300.011902)
			(xy 305.895756 -300.034452) (xy 305.90236 -300.047152) (xy 305.92649 -300.061884) (xy 306.272946 -300.061884)
			(xy 306.297076 -300.047152) (xy 306.30368 -300.034452) (xy 306.315961 -300.011902) (xy 306.346881 -299.970911)
			(xy 306.384224 -299.935671) (xy 306.426936 -299.907175) (xy 306.473813 -299.886227) (xy 306.523534 -299.873417)
			(xy 306.574698 -299.869107) (xy 306.625862 -299.873417) (xy 306.675583 -299.886227) (xy 306.72246 -299.907175)
			(xy 306.765172 -299.935671) (xy 306.802515 -299.970911) (xy 306.833435 -300.011902) (xy 306.845716 -300.034452)
			(xy 306.85232 -300.047152) (xy 306.87645 -300.061884) (xy 307.22316 -300.061884) (xy 307.24729 -300.047152)
			(xy 307.253894 -300.034452) (xy 307.266175 -300.011902) (xy 307.297095 -299.970911) (xy 307.334438 -299.935671)
			(xy 307.37715 -299.907175) (xy 307.424027 -299.886227) (xy 307.473748 -299.873417) (xy 307.524912 -299.869107)
			(xy 307.576076 -299.873417) (xy 307.625797 -299.886227) (xy 307.672674 -299.907175) (xy 307.715386 -299.935671)
			(xy 307.752729 -299.970911) (xy 307.783649 -300.011902) (xy 307.79593 -300.034452) (xy 307.802534 -300.047152)
			(xy 307.826664 -300.061884) (xy 308.17312 -300.061884) (xy 308.19725 -300.047152) (xy 308.203854 -300.034452)
			(xy 308.216135 -300.011902) (xy 308.247055 -299.970911) (xy 308.284398 -299.935671) (xy 308.32711 -299.907175)
			(xy 308.373987 -299.886227) (xy 308.423708 -299.873417) (xy 308.474872 -299.869107) (xy 308.526036 -299.873417)
			(xy 308.575757 -299.886227) (xy 308.622634 -299.907175) (xy 308.665346 -299.935671) (xy 308.702689 -299.970911)
			(xy 308.733609 -300.011902) (xy 308.74589 -300.034452) (xy 308.752494 -300.047152) (xy 308.776624 -300.061884)
			(xy 309.12308 -300.061884) (xy 309.14721 -300.047152) (xy 309.153814 -300.034452) (xy 309.166095 -300.011902)
			(xy 309.197015 -299.970911) (xy 309.234358 -299.935671) (xy 309.27707 -299.907175) (xy 309.323947 -299.886227)
			(xy 309.373668 -299.873417) (xy 309.424832 -299.869107) (xy 309.475996 -299.873417) (xy 309.525717 -299.886227)
			(xy 309.572594 -299.907175) (xy 309.615306 -299.935671) (xy 309.652649 -299.970911) (xy 309.683569 -300.011902)
			(xy 309.69585 -300.034452) (xy 309.702454 -300.047152) (xy 309.726584 -300.061884) (xy 310.07304 -300.061884)
			(xy 310.09717 -300.047152) (xy 310.103774 -300.034452) (xy 310.116055 -300.011902) (xy 310.146975 -299.970911)
			(xy 310.184318 -299.935671) (xy 310.22703 -299.907175) (xy 310.273907 -299.886227) (xy 310.323628 -299.873417)
			(xy 310.374792 -299.869107) (xy 310.425956 -299.873417) (xy 310.475677 -299.886227) (xy 310.522554 -299.907175)
			(xy 310.565266 -299.935671) (xy 310.602609 -299.970911) (xy 310.633529 -300.011902) (xy 310.64581 -300.034452)
			(xy 310.652414 -300.047152) (xy 310.676544 -300.061884) (xy 311.023 -300.061884) (xy 311.04713 -300.047152)
			(xy 311.053734 -300.034452) (xy 311.066015 -300.011902) (xy 311.096935 -299.970911) (xy 311.134278 -299.935671)
			(xy 311.17699 -299.907175) (xy 311.223867 -299.886227) (xy 311.273588 -299.873417) (xy 311.324752 -299.869107)
			(xy 311.375916 -299.873417) (xy 311.425637 -299.886227) (xy 311.472514 -299.907175) (xy 311.515226 -299.935671)
			(xy 311.552569 -299.970911) (xy 311.583489 -300.011902) (xy 311.59577 -300.034452) (xy 311.602374 -300.047152)
			(xy 311.626504 -300.061884) (xy 311.97296 -300.061884) (xy 311.99709 -300.047152) (xy 312.003694 -300.034452)
			(xy 312.015975 -300.011902) (xy 312.046895 -299.970911) (xy 312.084238 -299.935671) (xy 312.12695 -299.907175)
			(xy 312.173827 -299.886227) (xy 312.223548 -299.873417) (xy 312.274712 -299.869107) (xy 312.325876 -299.873417)
			(xy 312.375597 -299.886227) (xy 312.422474 -299.907175) (xy 312.465186 -299.935671) (xy 312.502529 -299.970911)
			(xy 312.533449 -300.011902) (xy 312.54573 -300.034452) (xy 312.552334 -300.047152) (xy 312.576464 -300.061884)
			(xy 312.923174 -300.061884) (xy 312.947304 -300.047152) (xy 312.953908 -300.034452) (xy 312.966189 -300.011902)
			(xy 312.997109 -299.970911) (xy 313.034452 -299.935671) (xy 313.077164 -299.907175) (xy 313.124041 -299.886227)
			(xy 313.173762 -299.873417) (xy 313.224926 -299.869107) (xy 313.27609 -299.873417) (xy 313.325811 -299.886227)
			(xy 313.372688 -299.907175) (xy 313.4154 -299.935671) (xy 313.452743 -299.970911) (xy 313.483663 -300.011902)
			(xy 313.495944 -300.034452) (xy 313.502548 -300.047152) (xy 313.526678 -300.061884) (xy 313.873134 -300.061884)
			(xy 313.897264 -300.047152) (xy 313.903868 -300.034452) (xy 313.916149 -300.011902) (xy 313.947069 -299.970911)
			(xy 313.984412 -299.935671) (xy 314.027124 -299.907175) (xy 314.074001 -299.886227) (xy 314.123722 -299.873417)
			(xy 314.174886 -299.869107) (xy 314.22605 -299.873417) (xy 314.275771 -299.886227) (xy 314.322648 -299.907175)
			(xy 314.36536 -299.935671) (xy 314.402703 -299.970911) (xy 314.433623 -300.011902) (xy 314.445904 -300.034452)
			(xy 314.452508 -300.047152) (xy 314.476638 -300.061884) (xy 314.823094 -300.061884) (xy 314.847224 -300.047152)
			(xy 314.853828 -300.034452) (xy 314.866109 -300.011902) (xy 314.897029 -299.970911) (xy 314.934372 -299.935671)
			(xy 314.977084 -299.907175) (xy 315.023961 -299.886227) (xy 315.073682 -299.873417) (xy 315.124846 -299.869107)
			(xy 315.17601 -299.873417) (xy 315.225731 -299.886227) (xy 315.272608 -299.907175) (xy 315.31532 -299.935671)
			(xy 315.352663 -299.970911) (xy 315.383583 -300.011902) (xy 315.395864 -300.034452) (xy 315.402468 -300.047152)
			(xy 315.426598 -300.061884) (xy 318.42964 -300.061884) (xy 318.461907 -300.062353) (xy 318.526033 -300.069604)
			(xy 318.588947 -300.083977) (xy 318.64986 -300.105292) (xy 318.708009 -300.133282) (xy 318.762665 -300.167596)
			(xy 318.813143 -300.207804) (xy 318.836294 -300.230286) (xy 319.648078 -301.04207) (xy 322.517006 -301.04207)
			(xy 322.521077 -300.986448) (xy 322.533203 -300.932011) (xy 322.553126 -300.87992) (xy 322.580422 -300.831285)
			(xy 322.614508 -300.787142) (xy 322.654657 -300.748433) (xy 322.700015 -300.715982) (xy 322.749615 -300.690481)
			(xy 322.802399 -300.672474) (xy 322.857242 -300.662344) (xy 322.912976 -300.660307) (xy 322.968413 -300.666407)
			(xy 323.02237 -300.680513) (xy 323.073699 -300.702325) (xy 323.121305 -300.731379) (xy 323.164173 -300.767054)
			(xy 323.20139 -300.808591) (xy 323.232163 -300.855104) (xy 323.255835 -300.905601) (xy 323.271903 -300.959008)
			(xy 323.280023 -301.014184) (xy 323.280532 -301.04207) (xy 323.280379 -301.050452) (xy 324.89089 -301.050452)
			(xy 324.894961 -300.99483) (xy 324.907087 -300.940393) (xy 324.92701 -300.888302) (xy 324.954306 -300.839667)
			(xy 324.988392 -300.795524) (xy 325.028541 -300.756815) (xy 325.073899 -300.724364) (xy 325.123499 -300.698863)
			(xy 325.176283 -300.680856) (xy 325.231126 -300.670726) (xy 325.28686 -300.668689) (xy 325.342297 -300.674789)
			(xy 325.396254 -300.688895) (xy 325.447583 -300.710707) (xy 325.495189 -300.739761) (xy 325.538057 -300.775436)
			(xy 325.575274 -300.816973) (xy 325.606047 -300.863486) (xy 325.629719 -300.913983) (xy 325.645787 -300.96739)
			(xy 325.653907 -301.022566) (xy 325.654416 -301.050452) (xy 325.653907 -301.078338) (xy 325.645787 -301.133514)
			(xy 325.629719 -301.186921) (xy 325.606047 -301.237418) (xy 325.575274 -301.283931) (xy 325.538057 -301.325468)
			(xy 325.495189 -301.361143) (xy 325.447583 -301.390197) (xy 325.396254 -301.412009) (xy 325.350058 -301.424086)
			(xy 335.023714 -301.424086) (xy 335.024168 -301.396715) (xy 335.031989 -301.342536) (xy 335.04748 -301.290032)
			(xy 335.070325 -301.240286) (xy 335.100052 -301.194319) (xy 335.117694 -301.173388) (xy 335.12379 -301.166276)
			(xy 335.13014 -301.149258) (xy 335.13014 -301.063914) (xy 335.12379 -301.046896) (xy 335.117694 -301.039784)
			(xy 335.100041 -301.018862) (xy 335.070319 -300.972891) (xy 335.047477 -300.923143) (xy 335.031983 -300.87064)
			(xy 335.024156 -300.81646) (xy 335.024158 -300.761719) (xy 335.031987 -300.70754) (xy 335.047484 -300.655037)
			(xy 335.070329 -300.60529) (xy 335.100054 -300.559321) (xy 335.117694 -300.538388) (xy 335.12379 -300.531276)
			(xy 335.13014 -300.514258) (xy 335.13014 -300.428914) (xy 335.12379 -300.411896) (xy 335.117694 -300.404784)
			(xy 335.100041 -300.383862) (xy 335.070319 -300.337891) (xy 335.047477 -300.288143) (xy 335.031983 -300.23564)
			(xy 335.024156 -300.18146) (xy 335.024158 -300.126719) (xy 335.031987 -300.07254) (xy 335.047484 -300.020037)
			(xy 335.070329 -299.97029) (xy 335.100054 -299.924321) (xy 335.117694 -299.903388) (xy 335.12379 -299.896276)
			(xy 335.13014 -299.879258) (xy 335.13014 -299.793914) (xy 335.12379 -299.776896) (xy 335.117694 -299.769784)
			(xy 335.10008 -299.748832) (xy 335.070365 -299.702864) (xy 335.047524 -299.653122) (xy 335.032027 -299.600626)
			(xy 335.024192 -299.546454) (xy 335.023714 -299.519086) (xy 335.0242 -299.491835) (xy 335.031956 -299.437887)
			(xy 335.047311 -299.385592) (xy 335.069953 -299.336015) (xy 335.099419 -299.290165) (xy 335.13511 -299.248974)
			(xy 335.176301 -299.213283) (xy 335.222151 -299.183817) (xy 335.271728 -299.161175) (xy 335.324023 -299.14582)
			(xy 335.377971 -299.138064) (xy 335.432473 -299.138064) (xy 335.486421 -299.14582) (xy 335.538716 -299.161175)
			(xy 335.588293 -299.183817) (xy 335.634143 -299.213283) (xy 335.675334 -299.248974) (xy 335.711025 -299.290165)
			(xy 335.740491 -299.336015) (xy 335.763133 -299.385592) (xy 335.778488 -299.437887) (xy 335.786244 -299.491835)
			(xy 335.78673 -299.519086) (xy 335.786273 -299.546457) (xy 335.778455 -299.600637) (xy 335.762965 -299.653141)
			(xy 335.740121 -299.702888) (xy 335.710393 -299.748853) (xy 335.69275 -299.769784) (xy 335.686654 -299.776896)
			(xy 335.680304 -299.793914) (xy 335.680304 -299.879258) (xy 335.686654 -299.896276) (xy 335.69275 -299.903388)
			(xy 335.710378 -299.924331) (xy 335.740105 -299.970297) (xy 335.762953 -300.020041) (xy 335.778451 -300.072542)
			(xy 335.786281 -300.126719) (xy 335.786283 -300.18146) (xy 335.778455 -300.235638) (xy 335.76296 -300.288139)
			(xy 335.740115 -300.337885) (xy 335.710391 -300.383852) (xy 335.69275 -300.404784) (xy 335.686654 -300.411896)
			(xy 335.680304 -300.428914) (xy 335.680304 -300.514258) (xy 335.686654 -300.531276) (xy 335.69275 -300.538388)
			(xy 335.710378 -300.559331) (xy 335.740105 -300.605297) (xy 335.762953 -300.655041) (xy 335.778451 -300.707542)
			(xy 335.786281 -300.761719) (xy 335.786283 -300.81646) (xy 335.778455 -300.870638) (xy 335.76296 -300.923139)
			(xy 335.740115 -300.972885) (xy 335.710391 -301.018852) (xy 335.69275 -301.039784) (xy 335.686654 -301.046896)
			(xy 335.680304 -301.063914) (xy 335.680304 -301.149258) (xy 335.686654 -301.166276) (xy 335.69275 -301.173388)
			(xy 335.710389 -301.19432) (xy 335.740103 -301.240292) (xy 335.762939 -301.29004) (xy 335.77843 -301.342541)
			(xy 335.786257 -301.396717) (xy 335.78673 -301.424086) (xy 335.786244 -301.451337) (xy 335.78242 -301.477934)
			(xy 338.655914 -301.477934) (xy 338.656397 -301.450564) (xy 338.66421 -301.396386) (xy 338.679695 -301.343883)
			(xy 338.702533 -301.294136) (xy 338.732254 -301.248168) (xy 338.749894 -301.227236) (xy 338.75599 -301.220124)
			(xy 338.76234 -301.203106) (xy 338.76234 -301.117762) (xy 338.75599 -301.100744) (xy 338.749894 -301.093632)
			(xy 338.732288 -301.072672) (xy 338.702564 -301.026708) (xy 338.679719 -300.976966) (xy 338.664222 -300.924468)
			(xy 338.65639 -300.870294) (xy 338.656387 -300.815557) (xy 338.664211 -300.761382) (xy 338.679701 -300.708882)
			(xy 338.70254 -300.659137) (xy 338.732257 -300.613169) (xy 338.749894 -300.592236) (xy 338.75599 -300.585124)
			(xy 338.76234 -300.568106) (xy 338.76234 -300.482762) (xy 338.75599 -300.465744) (xy 338.749894 -300.458632)
			(xy 338.732288 -300.437672) (xy 338.702564 -300.391708) (xy 338.679719 -300.341966) (xy 338.664222 -300.289468)
			(xy 338.65639 -300.235294) (xy 338.656387 -300.180557) (xy 338.664211 -300.126382) (xy 338.679701 -300.073882)
			(xy 338.70254 -300.024137) (xy 338.732257 -299.978169) (xy 338.749894 -299.957236) (xy 338.75599 -299.950124)
			(xy 338.76234 -299.933106) (xy 338.76234 -299.847762) (xy 338.75599 -299.830744) (xy 338.749894 -299.823632)
			(xy 338.732256 -299.802699) (xy 338.702544 -299.756727) (xy 338.679708 -299.706979) (xy 338.664217 -299.654479)
			(xy 338.656388 -299.600303) (xy 338.655914 -299.572934) (xy 338.6564 -299.545683) (xy 338.664156 -299.491735)
			(xy 338.679511 -299.43944) (xy 338.702153 -299.389863) (xy 338.731619 -299.344013) (xy 338.76731 -299.302822)
			(xy 338.808501 -299.267131) (xy 338.854351 -299.237665) (xy 338.903928 -299.215023) (xy 338.956223 -299.199668)
			(xy 339.010171 -299.191912) (xy 339.064673 -299.191912) (xy 339.118621 -299.199668) (xy 339.170916 -299.215023)
			(xy 339.220493 -299.237665) (xy 339.266343 -299.267131) (xy 339.307534 -299.302822) (xy 339.343225 -299.344013)
			(xy 339.372691 -299.389863) (xy 339.395333 -299.43944) (xy 339.410688 -299.491735) (xy 339.418444 -299.545683)
			(xy 339.41893 -299.572934) (xy 339.418501 -299.600306) (xy 339.410677 -299.654487) (xy 339.39518 -299.706991)
			(xy 339.37233 -299.756738) (xy 339.342596 -299.802702) (xy 339.32495 -299.823632) (xy 339.318854 -299.830744)
			(xy 339.312504 -299.847762) (xy 339.312504 -299.933106) (xy 339.318854 -299.950124) (xy 339.32495 -299.957236)
			(xy 339.342625 -299.978141) (xy 339.37235 -300.024113) (xy 339.395195 -300.073864) (xy 339.41069 -300.12637)
			(xy 339.418515 -300.180553) (xy 339.418512 -300.235298) (xy 339.410679 -300.28948) (xy 339.395177 -300.341984)
			(xy 339.372325 -300.391732) (xy 339.342594 -300.4377) (xy 339.32495 -300.458632) (xy 339.318854 -300.465744)
			(xy 339.312504 -300.482762) (xy 339.312504 -300.568106) (xy 339.318854 -300.585124) (xy 339.32495 -300.592236)
			(xy 339.342625 -300.613141) (xy 339.37235 -300.659113) (xy 339.395195 -300.708864) (xy 339.41069 -300.76137)
			(xy 339.418515 -300.815553) (xy 339.418512 -300.870298) (xy 339.410679 -300.92448) (xy 339.395177 -300.976984)
			(xy 339.372325 -301.026732) (xy 339.342594 -301.0727) (xy 339.32495 -301.093632) (xy 339.318854 -301.100744)
			(xy 339.312504 -301.117762) (xy 339.312504 -301.203106) (xy 339.318854 -301.220124) (xy 339.32495 -301.227236)
			(xy 339.342565 -301.248188) (xy 339.372282 -301.294154) (xy 339.395123 -301.343897) (xy 339.41062 -301.396393)
			(xy 339.414624 -301.424086) (xy 341.863934 -301.424086) (xy 341.864384 -301.396715) (xy 341.872204 -301.342535)
			(xy 341.887697 -301.290031) (xy 341.910542 -301.240285) (xy 341.940271 -301.194319) (xy 341.957914 -301.173388)
			(xy 341.96401 -301.166276) (xy 341.97036 -301.149258) (xy 341.97036 -301.063914) (xy 341.96401 -301.046896)
			(xy 341.957914 -301.039784) (xy 341.94026 -301.018862) (xy 341.910537 -300.972892) (xy 341.887693 -300.923144)
			(xy 341.872199 -300.87064) (xy 341.864372 -300.816461) (xy 341.864373 -300.761718) (xy 341.872203 -300.707539)
			(xy 341.887701 -300.655036) (xy 341.910547 -300.605289) (xy 341.940273 -300.559321) (xy 341.957914 -300.538388)
			(xy 341.96401 -300.531276) (xy 341.97036 -300.514258) (xy 341.97036 -300.428914) (xy 341.96401 -300.411896)
			(xy 341.957914 -300.404784) (xy 341.94026 -300.383862) (xy 341.910537 -300.337892) (xy 341.887693 -300.288144)
			(xy 341.872199 -300.23564) (xy 341.864372 -300.181461) (xy 341.864373 -300.126718) (xy 341.872203 -300.072539)
			(xy 341.887701 -300.020036) (xy 341.910547 -299.970289) (xy 341.940273 -299.924321) (xy 341.957914 -299.903388)
			(xy 341.96401 -299.896276) (xy 341.97036 -299.879258) (xy 341.97036 -299.793914) (xy 341.96401 -299.776896)
			(xy 341.957914 -299.769784) (xy 341.940303 -299.748829) (xy 341.910586 -299.702863) (xy 341.887745 -299.653121)
			(xy 341.872247 -299.600625) (xy 341.864412 -299.546454) (xy 341.863934 -299.519086) (xy 341.86442 -299.491835)
			(xy 341.872176 -299.437887) (xy 341.887531 -299.385592) (xy 341.910173 -299.336015) (xy 341.939639 -299.290165)
			(xy 341.97533 -299.248974) (xy 342.016521 -299.213283) (xy 342.062371 -299.183817) (xy 342.111948 -299.161175)
			(xy 342.164243 -299.14582) (xy 342.218191 -299.138064) (xy 342.272693 -299.138064) (xy 342.326641 -299.14582)
			(xy 342.378936 -299.161175) (xy 342.428513 -299.183817) (xy 342.474363 -299.213283) (xy 342.515554 -299.248974)
			(xy 342.551245 -299.290165) (xy 342.580711 -299.336015) (xy 342.603353 -299.385592) (xy 342.618708 -299.437887)
			(xy 342.626464 -299.491835) (xy 342.62695 -299.519086) (xy 342.626488 -299.546457) (xy 342.618671 -299.600636)
			(xy 342.603182 -299.65314) (xy 342.580339 -299.702887) (xy 342.550612 -299.748853) (xy 342.53297 -299.769784)
			(xy 342.526874 -299.776896) (xy 342.520524 -299.793914) (xy 342.520524 -299.879258) (xy 342.526874 -299.896276)
			(xy 342.53297 -299.903388) (xy 342.550597 -299.924332) (xy 342.580323 -299.970298) (xy 342.603169 -300.020042)
			(xy 342.618667 -300.072542) (xy 342.626497 -300.126719) (xy 342.626498 -300.181459) (xy 342.618671 -300.235637)
			(xy 342.603176 -300.288138) (xy 342.580333 -300.337884) (xy 342.55061 -300.383851) (xy 342.53297 -300.404784)
			(xy 342.526874 -300.411896) (xy 342.520524 -300.428914) (xy 342.520524 -300.514258) (xy 342.526874 -300.531276)
			(xy 342.53297 -300.538388) (xy 342.550597 -300.559332) (xy 342.580323 -300.605298) (xy 342.603169 -300.655042)
			(xy 342.618667 -300.707542) (xy 342.626497 -300.761719) (xy 342.626498 -300.816459) (xy 342.618671 -300.870637)
			(xy 342.603176 -300.923138) (xy 342.580333 -300.972884) (xy 342.55061 -301.018851) (xy 342.53297 -301.039784)
			(xy 342.526874 -301.046896) (xy 342.520524 -301.063914) (xy 342.520524 -301.149258) (xy 342.526874 -301.166276)
			(xy 342.53297 -301.173388) (xy 342.550612 -301.194318) (xy 342.580325 -301.240291) (xy 342.60316 -301.290039)
			(xy 342.618651 -301.34254) (xy 342.626477 -301.396717) (xy 342.62695 -301.424086) (xy 342.626464 -301.451337)
			(xy 342.62264 -301.477934) (xy 345.496134 -301.477934) (xy 345.496612 -301.450564) (xy 345.504425 -301.396385)
			(xy 345.519911 -301.343882) (xy 345.542751 -301.294135) (xy 345.572473 -301.248168) (xy 345.590114 -301.227236)
			(xy 345.59621 -301.220124) (xy 345.60256 -301.203106) (xy 345.60256 -301.117762) (xy 345.59621 -301.100744)
			(xy 345.590114 -301.093632) (xy 345.572507 -301.072672) (xy 345.542782 -301.026709) (xy 345.519935 -300.976967)
			(xy 345.504437 -300.924469) (xy 345.496606 -300.870294) (xy 345.496602 -300.815557) (xy 345.504426 -300.761381)
			(xy 345.519917 -300.708881) (xy 345.542757 -300.659136) (xy 345.572476 -300.613169) (xy 345.590114 -300.592236)
			(xy 345.59621 -300.585124) (xy 345.60256 -300.568106) (xy 345.60256 -300.482762) (xy 345.59621 -300.465744)
			(xy 345.590114 -300.458632) (xy 345.572507 -300.437672) (xy 345.542782 -300.391709) (xy 345.519935 -300.341967)
			(xy 345.504437 -300.289469) (xy 345.496606 -300.235294) (xy 345.496602 -300.180557) (xy 345.504426 -300.126381)
			(xy 345.519917 -300.073881) (xy 345.542757 -300.024136) (xy 345.572476 -299.978169) (xy 345.590114 -299.957236)
			(xy 345.59621 -299.950124) (xy 345.60256 -299.933106) (xy 345.60256 -299.847762) (xy 345.59621 -299.830744)
			(xy 345.590114 -299.823632) (xy 345.572479 -299.802697) (xy 345.542766 -299.756725) (xy 345.519929 -299.706978)
			(xy 345.504437 -299.654478) (xy 345.496608 -299.600303) (xy 345.496134 -299.572934) (xy 345.49662 -299.545683)
			(xy 345.504376 -299.491735) (xy 345.519731 -299.43944) (xy 345.542373 -299.389863) (xy 345.571839 -299.344013)
			(xy 345.60753 -299.302822) (xy 345.648721 -299.267131) (xy 345.694571 -299.237665) (xy 345.744148 -299.215023)
			(xy 345.796443 -299.199668) (xy 345.850391 -299.191912) (xy 345.904893 -299.191912) (xy 345.958841 -299.199668)
			(xy 346.011136 -299.215023) (xy 346.060713 -299.237665) (xy 346.106563 -299.267131) (xy 346.147754 -299.302822)
			(xy 346.183445 -299.344013) (xy 346.212911 -299.389863) (xy 346.235553 -299.43944) (xy 346.250908 -299.491735)
			(xy 346.258664 -299.545683) (xy 346.25915 -299.572934) (xy 346.258716 -299.600306) (xy 346.250892 -299.654486)
			(xy 346.235396 -299.70699) (xy 346.212547 -299.756737) (xy 346.182815 -299.802702) (xy 346.16517 -299.823632)
			(xy 346.159074 -299.830744) (xy 346.152724 -299.847762) (xy 346.152724 -299.933106) (xy 346.159074 -299.950124)
			(xy 346.16517 -299.957236) (xy 346.182844 -299.978142) (xy 346.212568 -300.024114) (xy 346.235411 -300.073865)
			(xy 346.250905 -300.126371) (xy 346.258731 -300.180553) (xy 346.258727 -300.235298) (xy 346.250894 -300.289479)
			(xy 346.235393 -300.341983) (xy 346.212543 -300.391731) (xy 346.182813 -300.437699) (xy 346.16517 -300.458632)
			(xy 346.159074 -300.465744) (xy 346.152724 -300.482762) (xy 346.152724 -300.568106) (xy 346.159074 -300.585124)
			(xy 346.16517 -300.592236) (xy 346.182844 -300.613142) (xy 346.212568 -300.659114) (xy 346.235411 -300.708865)
			(xy 346.250905 -300.761371) (xy 346.258731 -300.815553) (xy 346.258727 -300.870298) (xy 346.250894 -300.924479)
			(xy 346.235393 -300.976983) (xy 346.212543 -301.026731) (xy 346.182813 -301.072699) (xy 346.16517 -301.093632)
			(xy 346.159074 -301.100744) (xy 346.152724 -301.117762) (xy 346.152724 -301.203106) (xy 346.159074 -301.220124)
			(xy 346.16517 -301.227236) (xy 346.182788 -301.248185) (xy 346.212504 -301.294153) (xy 346.235344 -301.343896)
			(xy 346.25084 -301.396393) (xy 346.258674 -301.450566) (xy 346.25915 -301.477934) (xy 346.258664 -301.505185)
			(xy 346.250908 -301.559133) (xy 346.235553 -301.611428) (xy 346.212911 -301.661005) (xy 346.183445 -301.706855)
			(xy 346.147754 -301.748046) (xy 346.106563 -301.783737) (xy 346.060713 -301.813203) (xy 346.011136 -301.835845)
			(xy 345.958841 -301.8512) (xy 345.904893 -301.858956) (xy 345.850391 -301.858956) (xy 345.796443 -301.8512)
			(xy 345.744148 -301.835845) (xy 345.694571 -301.813203) (xy 345.648721 -301.783737) (xy 345.60753 -301.748046)
			(xy 345.571839 -301.706855) (xy 345.542373 -301.661005) (xy 345.519731 -301.611428) (xy 345.504376 -301.559133)
			(xy 345.49662 -301.505185) (xy 345.496134 -301.477934) (xy 342.62264 -301.477934) (xy 342.618708 -301.505285)
			(xy 342.603353 -301.55758) (xy 342.580711 -301.607157) (xy 342.551245 -301.653007) (xy 342.515554 -301.694198)
			(xy 342.474363 -301.729889) (xy 342.428513 -301.759355) (xy 342.378936 -301.781997) (xy 342.326641 -301.797352)
			(xy 342.272693 -301.805108) (xy 342.218191 -301.805108) (xy 342.164243 -301.797352) (xy 342.111948 -301.781997)
			(xy 342.062371 -301.759355) (xy 342.016521 -301.729889) (xy 341.97533 -301.694198) (xy 341.939639 -301.653007)
			(xy 341.910173 -301.607157) (xy 341.887531 -301.55758) (xy 341.872176 -301.505285) (xy 341.86442 -301.451337)
			(xy 341.863934 -301.424086) (xy 339.414624 -301.424086) (xy 339.418453 -301.450566) (xy 339.41893 -301.477934)
			(xy 339.418444 -301.505185) (xy 339.410688 -301.559133) (xy 339.395333 -301.611428) (xy 339.372691 -301.661005)
			(xy 339.343225 -301.706855) (xy 339.307534 -301.748046) (xy 339.266343 -301.783737) (xy 339.220493 -301.813203)
			(xy 339.170916 -301.835845) (xy 339.118621 -301.8512) (xy 339.064673 -301.858956) (xy 339.010171 -301.858956)
			(xy 338.956223 -301.8512) (xy 338.903928 -301.835845) (xy 338.854351 -301.813203) (xy 338.808501 -301.783737)
			(xy 338.76731 -301.748046) (xy 338.731619 -301.706855) (xy 338.702153 -301.661005) (xy 338.679511 -301.611428)
			(xy 338.664156 -301.559133) (xy 338.6564 -301.505185) (xy 338.655914 -301.477934) (xy 335.78242 -301.477934)
			(xy 335.778488 -301.505285) (xy 335.763133 -301.55758) (xy 335.740491 -301.607157) (xy 335.711025 -301.653007)
			(xy 335.675334 -301.694198) (xy 335.634143 -301.729889) (xy 335.588293 -301.759355) (xy 335.538716 -301.781997)
			(xy 335.486421 -301.797352) (xy 335.432473 -301.805108) (xy 335.377971 -301.805108) (xy 335.324023 -301.797352)
			(xy 335.271728 -301.781997) (xy 335.222151 -301.759355) (xy 335.176301 -301.729889) (xy 335.13511 -301.694198)
			(xy 335.099419 -301.653007) (xy 335.069953 -301.607157) (xy 335.047311 -301.55758) (xy 335.031956 -301.505285)
			(xy 335.0242 -301.451337) (xy 335.023714 -301.424086) (xy 325.350058 -301.424086) (xy 325.342297 -301.426115)
			(xy 325.28686 -301.432215) (xy 325.231126 -301.430178) (xy 325.176283 -301.420048) (xy 325.123499 -301.402041)
			(xy 325.073899 -301.37654) (xy 325.028541 -301.344089) (xy 324.988392 -301.30538) (xy 324.954306 -301.261237)
			(xy 324.92701 -301.212602) (xy 324.907087 -301.160511) (xy 324.894961 -301.106074) (xy 324.89089 -301.050452)
			(xy 323.280379 -301.050452) (xy 323.280023 -301.069956) (xy 323.271903 -301.125132) (xy 323.255835 -301.178539)
			(xy 323.232163 -301.229036) (xy 323.20139 -301.275549) (xy 323.164173 -301.317086) (xy 323.121305 -301.352761)
			(xy 323.073699 -301.381815) (xy 323.02237 -301.403627) (xy 322.968413 -301.417733) (xy 322.912976 -301.423833)
			(xy 322.857242 -301.421796) (xy 322.802399 -301.411666) (xy 322.749615 -301.393659) (xy 322.700015 -301.368158)
			(xy 322.654657 -301.335707) (xy 322.614508 -301.296998) (xy 322.580422 -301.252855) (xy 322.553126 -301.20422)
			(xy 322.533203 -301.152129) (xy 322.521077 -301.097692) (xy 322.517006 -301.04207) (xy 319.648078 -301.04207)
			(xy 320.15303 -301.547022) (xy 320.159898 -301.553367) (xy 320.176939 -301.561022) (xy 320.195594 -301.562006)
			(xy 320.204592 -301.559468) (xy 320.28765 -301.532544) (xy 320.297195 -301.529001) (xy 320.312651 -301.515774)
			(xy 320.317622 -301.50689) (xy 320.324734 -301.49292) (xy 320.326004 -301.485554) (xy 320.33113 -301.459437)
			(xy 320.347666 -301.408849) (xy 320.371074 -301.361051) (xy 320.4009 -301.316971) (xy 320.436564 -301.277466)
			(xy 320.477375 -301.243304) (xy 320.522539 -301.215147) (xy 320.571179 -301.193542) (xy 320.62235 -301.17891)
			(xy 320.675059 -301.171534) (xy 320.70167 -301.171102) (xy 320.728924 -301.171563) (xy 320.782876 -301.179317)
			(xy 320.835176 -301.19467) (xy 320.884759 -301.21731) (xy 320.930615 -301.246776) (xy 320.97181 -301.282469)
			(xy 321.007506 -301.323661) (xy 321.036976 -301.369515) (xy 321.05962 -301.419095) (xy 321.074977 -301.471394)
			(xy 321.082735 -301.525346) (xy 321.082735 -301.556928) (xy 323.713092 -301.556928) (xy 323.717163 -301.501306)
			(xy 323.729289 -301.446869) (xy 323.749212 -301.394778) (xy 323.776508 -301.346143) (xy 323.810594 -301.302)
			(xy 323.850743 -301.263291) (xy 323.896101 -301.23084) (xy 323.945701 -301.205339) (xy 323.998485 -301.187332)
			(xy 324.053328 -301.177202) (xy 324.109062 -301.175165) (xy 324.164499 -301.181265) (xy 324.218456 -301.195371)
			(xy 324.269785 -301.217183) (xy 324.317391 -301.246237) (xy 324.360259 -301.281912) (xy 324.397476 -301.323449)
			(xy 324.428249 -301.369962) (xy 324.451921 -301.420459) (xy 324.467989 -301.473866) (xy 324.476109 -301.529042)
			(xy 324.476618 -301.556928) (xy 324.476109 -301.584814) (xy 324.467989 -301.63999) (xy 324.451921 -301.693397)
			(xy 324.428249 -301.743894) (xy 324.397476 -301.790407) (xy 324.360259 -301.831944) (xy 324.317391 -301.867619)
			(xy 324.269785 -301.896673) (xy 324.218456 -301.918485) (xy 324.164499 -301.932591) (xy 324.109062 -301.938691)
			(xy 324.053328 -301.936654) (xy 323.998485 -301.926524) (xy 323.945701 -301.908517) (xy 323.896101 -301.883016)
			(xy 323.850743 -301.850565) (xy 323.810594 -301.811856) (xy 323.776508 -301.767713) (xy 323.749212 -301.719078)
			(xy 323.729289 -301.666987) (xy 323.717163 -301.61255) (xy 323.713092 -301.556928) (xy 321.082735 -301.556928)
			(xy 321.082735 -301.579853) (xy 321.074977 -301.633806) (xy 321.05962 -301.686105) (xy 321.036976 -301.735685)
			(xy 321.007506 -301.781539) (xy 320.97181 -301.822731) (xy 320.930615 -301.858424) (xy 320.884759 -301.88789)
			(xy 320.835176 -301.91053) (xy 320.782876 -301.925883) (xy 320.728924 -301.933637) (xy 320.70167 -301.934118)
			(xy 320.672835 -301.933589) (xy 320.615821 -301.924911) (xy 320.588132 -301.916846) (xy 320.580766 -301.91456)
			(xy 320.558414 -301.91456) (xy 320.542158 -301.920402) (xy 320.5353 -301.92599) (xy 320.46037 -301.98695)
			(xy 320.450718 -302.010826) (xy 320.452242 -302.02378) (xy 320.453987 -302.039916) (xy 320.45589 -302.07232)
			(xy 320.456052 -302.08855) (xy 320.456052 -302.183546) (xy 320.456203 -302.189414) (xy 320.458897 -302.200836)
			(xy 320.461386 -302.206152) (xy 320.473324 -302.230282) (xy 320.479928 -302.238918) (xy 320.484246 -302.24222)
			(xy 320.505828 -302.260464) (xy 320.543901 -302.302225) (xy 320.575406 -302.349139) (xy 320.599657 -302.400182)
			(xy 320.616125 -302.45424) (xy 320.624451 -302.510134) (xy 320.624452 -302.566645) (xy 320.61613 -302.62254)
			(xy 320.599664 -302.676599) (xy 320.575416 -302.727644) (xy 320.543913 -302.774559) (xy 320.505843 -302.816322)
			(xy 320.484246 -302.834548) (xy 320.479928 -302.83785) (xy 320.473324 -302.846486) (xy 320.461386 -302.870616)
			(xy 320.458923 -302.875941) (xy 320.456225 -302.887357) (xy 320.456052 -302.893222) (xy 320.456052 -303.026826)
			(xy 320.819524 -303.026826) (xy 320.823595 -302.971204) (xy 320.835721 -302.916767) (xy 320.855644 -302.864676)
			(xy 320.88294 -302.816041) (xy 320.917026 -302.771898) (xy 320.957175 -302.733189) (xy 321.002533 -302.700738)
			(xy 321.052133 -302.675237) (xy 321.104917 -302.65723) (xy 321.15976 -302.6471) (xy 321.215494 -302.645063)
			(xy 321.270931 -302.651163) (xy 321.324888 -302.665269) (xy 321.376217 -302.687081) (xy 321.423823 -302.716135)
			(xy 321.466691 -302.75181) (xy 321.503908 -302.793347) (xy 321.534681 -302.83986) (xy 321.558353 -302.890357)
			(xy 321.574421 -302.943764) (xy 321.582541 -302.99894) (xy 321.58305 -303.026826) (xy 321.835524 -303.026826)
			(xy 321.839595 -302.971204) (xy 321.851721 -302.916767) (xy 321.871644 -302.864676) (xy 321.89894 -302.816041)
			(xy 321.933026 -302.771898) (xy 321.973175 -302.733189) (xy 322.018533 -302.700738) (xy 322.068133 -302.675237)
			(xy 322.120917 -302.65723) (xy 322.17576 -302.6471) (xy 322.231494 -302.645063) (xy 322.286931 -302.651163)
			(xy 322.340888 -302.665269) (xy 322.392217 -302.687081) (xy 322.439823 -302.716135) (xy 322.482691 -302.75181)
			(xy 322.519908 -302.793347) (xy 322.550681 -302.83986) (xy 322.574353 -302.890357) (xy 322.590421 -302.943764)
			(xy 322.598541 -302.99894) (xy 322.59905 -303.026826) (xy 322.851524 -303.026826) (xy 322.855595 -302.971204)
			(xy 322.867721 -302.916767) (xy 322.887644 -302.864676) (xy 322.91494 -302.816041) (xy 322.949026 -302.771898)
			(xy 322.989175 -302.733189) (xy 323.034533 -302.700738) (xy 323.084133 -302.675237) (xy 323.136917 -302.65723)
			(xy 323.19176 -302.6471) (xy 323.247494 -302.645063) (xy 323.302931 -302.651163) (xy 323.356888 -302.665269)
			(xy 323.408217 -302.687081) (xy 323.455823 -302.716135) (xy 323.498691 -302.75181) (xy 323.535908 -302.793347)
			(xy 323.566681 -302.83986) (xy 323.590353 -302.890357) (xy 323.606421 -302.943764) (xy 323.614541 -302.99894)
			(xy 323.61505 -303.026826) (xy 323.867524 -303.026826) (xy 323.871595 -302.971204) (xy 323.883721 -302.916767)
			(xy 323.903644 -302.864676) (xy 323.93094 -302.816041) (xy 323.965026 -302.771898) (xy 324.005175 -302.733189)
			(xy 324.050533 -302.700738) (xy 324.100133 -302.675237) (xy 324.152917 -302.65723) (xy 324.20776 -302.6471)
			(xy 324.263494 -302.645063) (xy 324.318931 -302.651163) (xy 324.372888 -302.665269) (xy 324.424217 -302.687081)
			(xy 324.471823 -302.716135) (xy 324.514691 -302.75181) (xy 324.551908 -302.793347) (xy 324.582681 -302.83986)
			(xy 324.606353 -302.890357) (xy 324.622421 -302.943764) (xy 324.630541 -302.99894) (xy 324.63105 -303.026826)
			(xy 324.883524 -303.026826) (xy 324.887595 -302.971204) (xy 324.899721 -302.916767) (xy 324.919644 -302.864676)
			(xy 324.94694 -302.816041) (xy 324.981026 -302.771898) (xy 325.021175 -302.733189) (xy 325.066533 -302.700738)
			(xy 325.116133 -302.675237) (xy 325.168917 -302.65723) (xy 325.22376 -302.6471) (xy 325.279494 -302.645063)
			(xy 325.334931 -302.651163) (xy 325.388888 -302.665269) (xy 325.440217 -302.687081) (xy 325.487823 -302.716135)
			(xy 325.530691 -302.75181) (xy 325.567908 -302.793347) (xy 325.598681 -302.83986) (xy 325.622353 -302.890357)
			(xy 325.632997 -302.925734) (xy 334.435704 -302.925734) (xy 334.436189 -302.898364) (xy 334.444002 -302.844186)
			(xy 334.459487 -302.791683) (xy 334.482324 -302.741936) (xy 334.512045 -302.695968) (xy 334.529684 -302.675036)
			(xy 334.53578 -302.667924) (xy 334.54213 -302.650906) (xy 334.54213 -302.565562) (xy 334.53578 -302.548544)
			(xy 334.529684 -302.541432) (xy 334.512044 -302.520501) (xy 334.482333 -302.474527) (xy 334.459497 -302.42478)
			(xy 334.444006 -302.372279) (xy 334.436178 -302.318103) (xy 334.435704 -302.290734) (xy 334.43619 -302.263483)
			(xy 334.443946 -302.209535) (xy 334.459301 -302.15724) (xy 334.481943 -302.107663) (xy 334.511409 -302.061813)
			(xy 334.5471 -302.020622) (xy 334.588291 -301.984931) (xy 334.634141 -301.955465) (xy 334.683718 -301.932823)
			(xy 334.736013 -301.917468) (xy 334.789961 -301.909712) (xy 334.844463 -301.909712) (xy 334.898411 -301.917468)
			(xy 334.950706 -301.932823) (xy 335.000283 -301.955465) (xy 335.046133 -301.984931) (xy 335.087324 -302.020622)
			(xy 335.123015 -302.061813) (xy 335.152481 -302.107663) (xy 335.175123 -302.15724) (xy 335.190478 -302.209535)
			(xy 335.198234 -302.263483) (xy 335.19872 -302.290734) (xy 335.198293 -302.318106) (xy 335.190469 -302.372287)
			(xy 335.174972 -302.424792) (xy 335.152121 -302.474538) (xy 335.122386 -302.520502) (xy 335.10474 -302.541432)
			(xy 335.098644 -302.548544) (xy 335.092294 -302.565562) (xy 335.092294 -302.650906) (xy 335.098644 -302.667924)
			(xy 335.10474 -302.675036) (xy 335.122369 -302.695976) (xy 335.152081 -302.741947) (xy 335.174919 -302.791693)
			(xy 335.190412 -302.844191) (xy 335.198244 -302.898365) (xy 335.19872 -302.925734) (xy 337.855814 -302.925734)
			(xy 337.856297 -302.898364) (xy 337.86411 -302.844186) (xy 337.879595 -302.791683) (xy 337.902433 -302.741936)
			(xy 337.932154 -302.695968) (xy 337.949794 -302.675036) (xy 337.95589 -302.667924) (xy 337.96224 -302.650906)
			(xy 337.96224 -302.565562) (xy 337.95589 -302.548544) (xy 337.949794 -302.541432) (xy 337.932156 -302.520499)
			(xy 337.902444 -302.474527) (xy 337.879608 -302.424779) (xy 337.864117 -302.372279) (xy 337.856288 -302.318103)
			(xy 337.855814 -302.290734) (xy 337.8563 -302.263483) (xy 337.864056 -302.209535) (xy 337.879411 -302.15724)
			(xy 337.902053 -302.107663) (xy 337.931519 -302.061813) (xy 337.96721 -302.020622) (xy 338.008401 -301.984931)
			(xy 338.054251 -301.955465) (xy 338.103828 -301.932823) (xy 338.156123 -301.917468) (xy 338.210071 -301.909712)
			(xy 338.264573 -301.909712) (xy 338.318521 -301.917468) (xy 338.370816 -301.932823) (xy 338.420393 -301.955465)
			(xy 338.466243 -301.984931) (xy 338.507434 -302.020622) (xy 338.543125 -302.061813) (xy 338.572591 -302.107663)
			(xy 338.595233 -302.15724) (xy 338.610588 -302.209535) (xy 338.618344 -302.263483) (xy 338.61883 -302.290734)
			(xy 338.618401 -302.318106) (xy 338.610577 -302.372287) (xy 338.59508 -302.424791) (xy 338.57223 -302.474538)
			(xy 338.542496 -302.520502) (xy 338.52485 -302.541432) (xy 338.518754 -302.548544) (xy 338.512404 -302.565562)
			(xy 338.512404 -302.650906) (xy 338.518754 -302.667924) (xy 338.52485 -302.675036) (xy 338.542465 -302.695988)
			(xy 338.572182 -302.741954) (xy 338.595023 -302.791697) (xy 338.61052 -302.844193) (xy 338.618353 -302.898366)
			(xy 338.61883 -302.925734) (xy 339.243924 -302.925734) (xy 339.244404 -302.898364) (xy 339.252218 -302.844185)
			(xy 339.267703 -302.791682) (xy 339.290542 -302.741935) (xy 339.320264 -302.695968) (xy 339.337904 -302.675036)
			(xy 339.344 -302.667924) (xy 339.35035 -302.650906) (xy 339.35035 -302.565562) (xy 339.344 -302.548544)
			(xy 339.337904 -302.541432) (xy 339.320267 -302.520498) (xy 339.290555 -302.474526) (xy 339.267718 -302.424779)
			(xy 339.252227 -302.372279) (xy 339.244398 -302.318103) (xy 339.243924 -302.290734) (xy 339.24441 -302.263483)
			(xy 339.252166 -302.209535) (xy 339.267521 -302.15724) (xy 339.290163 -302.107663) (xy 339.319629 -302.061813)
			(xy 339.35532 -302.020622) (xy 339.396511 -301.984931) (xy 339.442361 -301.955465) (xy 339.491938 -301.932823)
			(xy 339.544233 -301.917468) (xy 339.598181 -301.909712) (xy 339.652683 -301.909712) (xy 339.706631 -301.917468)
			(xy 339.758926 -301.932823) (xy 339.808503 -301.955465) (xy 339.854353 -301.984931) (xy 339.895544 -302.020622)
			(xy 339.931235 -302.061813) (xy 339.960701 -302.107663) (xy 339.983343 -302.15724) (xy 339.998698 -302.209535)
			(xy 340.006454 -302.263483) (xy 340.00694 -302.290734) (xy 340.006508 -302.318106) (xy 339.998685 -302.372287)
			(xy 339.983188 -302.424791) (xy 339.960338 -302.474537) (xy 339.930605 -302.520502) (xy 339.91296 -302.541432)
			(xy 339.906864 -302.548544) (xy 339.900514 -302.565562) (xy 339.900514 -302.650906) (xy 339.906864 -302.667924)
			(xy 339.91296 -302.675036) (xy 339.930576 -302.695987) (xy 339.960293 -302.741954) (xy 339.983134 -302.791696)
			(xy 339.99863 -302.844193) (xy 340.006463 -302.898366) (xy 340.00694 -302.925734) (xy 341.275924 -302.925734)
			(xy 341.276404 -302.898364) (xy 341.284218 -302.844185) (xy 341.299703 -302.791682) (xy 341.322542 -302.741935)
			(xy 341.352264 -302.695968) (xy 341.369904 -302.675036) (xy 341.376 -302.667924) (xy 341.38235 -302.650906)
			(xy 341.38235 -302.565562) (xy 341.376 -302.548544) (xy 341.369904 -302.541432) (xy 341.352267 -302.520498)
			(xy 341.322555 -302.474526) (xy 341.299718 -302.424779) (xy 341.284227 -302.372279) (xy 341.276398 -302.318103)
			(xy 341.275924 -302.290734) (xy 341.27641 -302.263483) (xy 341.284166 -302.209535) (xy 341.299521 -302.15724)
			(xy 341.322163 -302.107663) (xy 341.351629 -302.061813) (xy 341.38732 -302.020622) (xy 341.428511 -301.984931)
			(xy 341.474361 -301.955465) (xy 341.523938 -301.932823) (xy 341.576233 -301.917468) (xy 341.630181 -301.909712)
			(xy 341.684683 -301.909712) (xy 341.738631 -301.917468) (xy 341.790926 -301.932823) (xy 341.840503 -301.955465)
			(xy 341.886353 -301.984931) (xy 341.927544 -302.020622) (xy 341.963235 -302.061813) (xy 341.992701 -302.107663)
			(xy 342.015343 -302.15724) (xy 342.030698 -302.209535) (xy 342.038454 -302.263483) (xy 342.03894 -302.290734)
			(xy 342.038508 -302.318106) (xy 342.030685 -302.372287) (xy 342.015188 -302.424791) (xy 341.992338 -302.474537)
			(xy 341.962605 -302.520502) (xy 341.94496 -302.541432) (xy 341.938864 -302.548544) (xy 341.932514 -302.565562)
			(xy 341.932514 -302.650906) (xy 341.938864 -302.667924) (xy 341.94496 -302.675036) (xy 341.962576 -302.695987)
			(xy 341.992293 -302.741954) (xy 342.015134 -302.791696) (xy 342.03063 -302.844193) (xy 342.038463 -302.898366)
			(xy 342.03894 -302.925734) (xy 346.084144 -302.925734) (xy 346.084619 -302.898364) (xy 346.092433 -302.844185)
			(xy 346.10792 -302.791681) (xy 346.13076 -302.741934) (xy 346.160483 -302.695968) (xy 346.178124 -302.675036)
			(xy 346.18422 -302.667924) (xy 346.19057 -302.650906) (xy 346.19057 -302.565562) (xy 346.18422 -302.548544)
			(xy 346.178124 -302.541432) (xy 346.16049 -302.520496) (xy 346.130777 -302.474524) (xy 346.107939 -302.424778)
			(xy 346.092447 -302.372278) (xy 346.084618 -302.318103) (xy 346.084144 -302.290734) (xy 346.08463 -302.263483)
			(xy 346.092386 -302.209535) (xy 346.107741 -302.15724) (xy 346.130383 -302.107663) (xy 346.159849 -302.061813)
			(xy 346.19554 -302.020622) (xy 346.236731 -301.984931) (xy 346.282581 -301.955465) (xy 346.332158 -301.932823)
			(xy 346.384453 -301.917468) (xy 346.438401 -301.909712) (xy 346.492903 -301.909712) (xy 346.546851 -301.917468)
			(xy 346.599146 -301.932823) (xy 346.648723 -301.955465) (xy 346.694573 -301.984931) (xy 346.735764 -302.020622)
			(xy 346.771455 -302.061813) (xy 346.800921 -302.107663) (xy 346.823563 -302.15724) (xy 346.838918 -302.209535)
			(xy 346.846674 -302.263483) (xy 346.84716 -302.290734) (xy 346.846724 -302.318105) (xy 346.8389 -302.372286)
			(xy 346.823405 -302.42479) (xy 346.800556 -302.474536) (xy 346.770825 -302.520502) (xy 346.75318 -302.541432)
			(xy 346.747084 -302.548544) (xy 346.740734 -302.565562) (xy 346.740734 -302.650906) (xy 346.747084 -302.667924)
			(xy 346.75318 -302.675036) (xy 346.770799 -302.695984) (xy 346.800515 -302.741952) (xy 346.823355 -302.791696)
			(xy 346.838851 -302.844193) (xy 346.846684 -302.898366) (xy 346.84716 -302.925734) (xy 346.846674 -302.952985)
			(xy 346.838918 -303.006933) (xy 346.823563 -303.059228) (xy 346.800921 -303.108805) (xy 346.779823 -303.141634)
			(xy 348.984568 -303.141634) (xy 348.988639 -303.086012) (xy 349.000765 -303.031575) (xy 349.020688 -302.979484)
			(xy 349.047984 -302.930849) (xy 349.08207 -302.886706) (xy 349.122219 -302.847997) (xy 349.167577 -302.815546)
			(xy 349.217177 -302.790045) (xy 349.269961 -302.772038) (xy 349.324804 -302.761908) (xy 349.380538 -302.759871)
			(xy 349.435975 -302.765971) (xy 349.489932 -302.780077) (xy 349.541261 -302.801889) (xy 349.588867 -302.830943)
			(xy 349.631735 -302.866618) (xy 349.668952 -302.908155) (xy 349.699725 -302.954668) (xy 349.723397 -303.005165)
			(xy 349.739465 -303.058572) (xy 349.747585 -303.113748) (xy 349.748094 -303.141634) (xy 349.747585 -303.16952)
			(xy 349.739465 -303.224696) (xy 349.723397 -303.278103) (xy 349.699725 -303.3286) (xy 349.668952 -303.375113)
			(xy 349.631735 -303.41665) (xy 349.588867 -303.452325) (xy 349.541261 -303.481379) (xy 349.489932 -303.503191)
			(xy 349.435975 -303.517297) (xy 349.380538 -303.523397) (xy 349.324804 -303.52136) (xy 349.269961 -303.51123)
			(xy 349.217177 -303.493223) (xy 349.167577 -303.467722) (xy 349.122219 -303.435271) (xy 349.08207 -303.396562)
			(xy 349.047984 -303.352419) (xy 349.020688 -303.303784) (xy 349.000765 -303.251693) (xy 348.988639 -303.197256)
			(xy 348.984568 -303.141634) (xy 346.779823 -303.141634) (xy 346.771455 -303.154655) (xy 346.735764 -303.195846)
			(xy 346.694573 -303.231537) (xy 346.648723 -303.261003) (xy 346.599146 -303.283645) (xy 346.546851 -303.299)
			(xy 346.492903 -303.306756) (xy 346.438401 -303.306756) (xy 346.384453 -303.299) (xy 346.332158 -303.283645)
			(xy 346.282581 -303.261003) (xy 346.236731 -303.231537) (xy 346.19554 -303.195846) (xy 346.159849 -303.154655)
			(xy 346.130383 -303.108805) (xy 346.107741 -303.059228) (xy 346.092386 -303.006933) (xy 346.08463 -302.952985)
			(xy 346.084144 -302.925734) (xy 342.03894 -302.925734) (xy 342.038454 -302.952985) (xy 342.030698 -303.006933)
			(xy 342.015343 -303.059228) (xy 341.992701 -303.108805) (xy 341.963235 -303.154655) (xy 341.927544 -303.195846)
			(xy 341.886353 -303.231537) (xy 341.840503 -303.261003) (xy 341.790926 -303.283645) (xy 341.738631 -303.299)
			(xy 341.684683 -303.306756) (xy 341.630181 -303.306756) (xy 341.576233 -303.299) (xy 341.523938 -303.283645)
			(xy 341.474361 -303.261003) (xy 341.428511 -303.231537) (xy 341.38732 -303.195846) (xy 341.351629 -303.154655)
			(xy 341.322163 -303.108805) (xy 341.299521 -303.059228) (xy 341.284166 -303.006933) (xy 341.27641 -302.952985)
			(xy 341.275924 -302.925734) (xy 340.00694 -302.925734) (xy 340.006454 -302.952985) (xy 339.998698 -303.006933)
			(xy 339.983343 -303.059228) (xy 339.960701 -303.108805) (xy 339.931235 -303.154655) (xy 339.895544 -303.195846)
			(xy 339.854353 -303.231537) (xy 339.808503 -303.261003) (xy 339.758926 -303.283645) (xy 339.706631 -303.299)
			(xy 339.652683 -303.306756) (xy 339.598181 -303.306756) (xy 339.544233 -303.299) (xy 339.491938 -303.283645)
			(xy 339.442361 -303.261003) (xy 339.396511 -303.231537) (xy 339.35532 -303.195846) (xy 339.319629 -303.154655)
			(xy 339.290163 -303.108805) (xy 339.267521 -303.059228) (xy 339.252166 -303.006933) (xy 339.24441 -302.952985)
			(xy 339.243924 -302.925734) (xy 338.61883 -302.925734) (xy 338.618344 -302.952985) (xy 338.610588 -303.006933)
			(xy 338.595233 -303.059228) (xy 338.572591 -303.108805) (xy 338.543125 -303.154655) (xy 338.507434 -303.195846)
			(xy 338.466243 -303.231537) (xy 338.420393 -303.261003) (xy 338.370816 -303.283645) (xy 338.318521 -303.299)
			(xy 338.264573 -303.306756) (xy 338.210071 -303.306756) (xy 338.156123 -303.299) (xy 338.103828 -303.283645)
			(xy 338.054251 -303.261003) (xy 338.008401 -303.231537) (xy 337.96721 -303.195846) (xy 337.931519 -303.154655)
			(xy 337.902053 -303.108805) (xy 337.879411 -303.059228) (xy 337.864056 -303.006933) (xy 337.8563 -302.952985)
			(xy 337.855814 -302.925734) (xy 335.19872 -302.925734) (xy 335.198234 -302.952985) (xy 335.190478 -303.006933)
			(xy 335.175123 -303.059228) (xy 335.152481 -303.108805) (xy 335.123015 -303.154655) (xy 335.087324 -303.195846)
			(xy 335.046133 -303.231537) (xy 335.000283 -303.261003) (xy 334.950706 -303.283645) (xy 334.898411 -303.299)
			(xy 334.844463 -303.306756) (xy 334.789961 -303.306756) (xy 334.736013 -303.299) (xy 334.683718 -303.283645)
			(xy 334.634141 -303.261003) (xy 334.588291 -303.231537) (xy 334.5471 -303.195846) (xy 334.511409 -303.154655)
			(xy 334.481943 -303.108805) (xy 334.459301 -303.059228) (xy 334.443946 -303.006933) (xy 334.43619 -302.952985)
			(xy 334.435704 -302.925734) (xy 325.632997 -302.925734) (xy 325.638421 -302.943764) (xy 325.646541 -302.99894)
			(xy 325.64705 -303.026826) (xy 325.646541 -303.054712) (xy 325.638421 -303.109888) (xy 325.622353 -303.163295)
			(xy 325.598681 -303.213792) (xy 325.567908 -303.260305) (xy 325.530691 -303.301842) (xy 325.487823 -303.337517)
			(xy 325.440217 -303.366571) (xy 325.388888 -303.388383) (xy 325.334931 -303.402489) (xy 325.279494 -303.408589)
			(xy 325.22376 -303.406552) (xy 325.168917 -303.396422) (xy 325.116133 -303.378415) (xy 325.066533 -303.352914)
			(xy 325.021175 -303.320463) (xy 324.981026 -303.281754) (xy 324.94694 -303.237611) (xy 324.919644 -303.188976)
			(xy 324.899721 -303.136885) (xy 324.887595 -303.082448) (xy 324.883524 -303.026826) (xy 324.63105 -303.026826)
			(xy 324.630541 -303.054712) (xy 324.622421 -303.109888) (xy 324.606353 -303.163295) (xy 324.582681 -303.213792)
			(xy 324.551908 -303.260305) (xy 324.514691 -303.301842) (xy 324.471823 -303.337517) (xy 324.424217 -303.366571)
			(xy 324.372888 -303.388383) (xy 324.318931 -303.402489) (xy 324.263494 -303.408589) (xy 324.20776 -303.406552)
			(xy 324.152917 -303.396422) (xy 324.100133 -303.378415) (xy 324.050533 -303.352914) (xy 324.005175 -303.320463)
			(xy 323.965026 -303.281754) (xy 323.93094 -303.237611) (xy 323.903644 -303.188976) (xy 323.883721 -303.136885)
			(xy 323.871595 -303.082448) (xy 323.867524 -303.026826) (xy 323.61505 -303.026826) (xy 323.614541 -303.054712)
			(xy 323.606421 -303.109888) (xy 323.590353 -303.163295) (xy 323.566681 -303.213792) (xy 323.535908 -303.260305)
			(xy 323.498691 -303.301842) (xy 323.455823 -303.337517) (xy 323.408217 -303.366571) (xy 323.356888 -303.388383)
			(xy 323.302931 -303.402489) (xy 323.247494 -303.408589) (xy 323.19176 -303.406552) (xy 323.136917 -303.396422)
			(xy 323.084133 -303.378415) (xy 323.034533 -303.352914) (xy 322.989175 -303.320463) (xy 322.949026 -303.281754)
			(xy 322.91494 -303.237611) (xy 322.887644 -303.188976) (xy 322.867721 -303.136885) (xy 322.855595 -303.082448)
			(xy 322.851524 -303.026826) (xy 322.59905 -303.026826) (xy 322.598541 -303.054712) (xy 322.590421 -303.109888)
			(xy 322.574353 -303.163295) (xy 322.550681 -303.213792) (xy 322.519908 -303.260305) (xy 322.482691 -303.301842)
			(xy 322.439823 -303.337517) (xy 322.392217 -303.366571) (xy 322.340888 -303.388383) (xy 322.286931 -303.402489)
			(xy 322.231494 -303.408589) (xy 322.17576 -303.406552) (xy 322.120917 -303.396422) (xy 322.068133 -303.378415)
			(xy 322.018533 -303.352914) (xy 321.973175 -303.320463) (xy 321.933026 -303.281754) (xy 321.89894 -303.237611)
			(xy 321.871644 -303.188976) (xy 321.851721 -303.136885) (xy 321.839595 -303.082448) (xy 321.835524 -303.026826)
			(xy 321.58305 -303.026826) (xy 321.582541 -303.054712) (xy 321.574421 -303.109888) (xy 321.558353 -303.163295)
			(xy 321.534681 -303.213792) (xy 321.503908 -303.260305) (xy 321.466691 -303.301842) (xy 321.423823 -303.337517)
			(xy 321.376217 -303.366571) (xy 321.324888 -303.388383) (xy 321.270931 -303.402489) (xy 321.215494 -303.408589)
			(xy 321.15976 -303.406552) (xy 321.104917 -303.396422) (xy 321.052133 -303.378415) (xy 321.002533 -303.352914)
			(xy 320.957175 -303.320463) (xy 320.917026 -303.281754) (xy 320.88294 -303.237611) (xy 320.855644 -303.188976)
			(xy 320.835721 -303.136885) (xy 320.823595 -303.082448) (xy 320.819524 -303.026826) (xy 320.456052 -303.026826)
			(xy 320.456052 -303.963324) (xy 320.455558 -303.996716) (xy 320.447801 -304.063048) (xy 320.432417 -304.128036)
			(xy 320.409614 -304.190807) (xy 320.395092 -304.22088) (xy 320.392298 -304.226468) (xy 320.38925 -304.23993)
			(xy 320.38925 -304.240438) (xy 320.387218 -304.249582) (xy 320.389504 -304.267616) (xy 320.438526 -304.358294)
			(xy 320.4591 -304.37201) (xy 320.4718 -304.373534) (xy 320.498408 -304.376884) (xy 320.550387 -304.390086)
			(xy 320.600008 -304.410429) (xy 320.646295 -304.437514) (xy 320.688337 -304.470809) (xy 320.725308 -304.509657)
			(xy 320.756481 -304.553296) (xy 320.781241 -304.600867) (xy 320.79057 -304.62601) (xy 320.793618 -304.634646)
			(xy 320.810382 -304.654966) (xy 320.813629 -304.65866) (xy 320.821304 -304.664805) (xy 320.825622 -304.667158)
			(xy 320.957448 -304.73777) (xy 320.968526 -304.742939) (xy 320.992931 -304.743316) (xy 321.004184 -304.738532)
			(xy 321.007486 -304.736754) (xy 321.00901 -304.735992) (xy 321.031045 -304.723525) (xy 321.077706 -304.703879)
			(xy 321.126556 -304.69058) (xy 321.176736 -304.683861) (xy 321.20205 -304.683414) (xy 321.230999 -304.683954)
			(xy 321.288231 -304.692709) (xy 321.343484 -304.710009) (xy 321.395489 -304.735457) (xy 321.443053 -304.76847)
			(xy 321.485084 -304.80829) (xy 321.520616 -304.854002) (xy 321.548835 -304.904557) (xy 321.569093 -304.958796)
			(xy 321.580924 -305.015472) (xy 321.58305 -305.044348) (xy 321.583812 -305.05781) (xy 321.598036 -305.080162)
			(xy 321.764914 -305.169316) (xy 321.773951 -305.173591) (xy 321.793827 -305.175545) (xy 321.812937 -305.169745)
			(xy 321.828374 -305.157074) (xy 321.833494 -305.148488) (xy 321.837304 -305.141376) (xy 321.840098 -305.125628)
			(xy 321.839082 -305.1175) (xy 321.837407 -305.104548) (xy 321.835626 -305.07849) (xy 321.835526 -305.06543)
			(xy 321.835526 -305.064922) (xy 321.836012 -305.037671) (xy 321.843768 -304.983723) (xy 321.859123 -304.931428)
			(xy 321.881765 -304.881851) (xy 321.911231 -304.836001) (xy 321.946922 -304.79481) (xy 321.988113 -304.759119)
			(xy 322.033963 -304.729653) (xy 322.08354 -304.707011) (xy 322.135835 -304.691656) (xy 322.189783 -304.6839)
			(xy 322.244285 -304.6839) (xy 322.298233 -304.691656) (xy 322.350528 -304.707011) (xy 322.400105 -304.729653)
			(xy 322.445955 -304.759119) (xy 322.487146 -304.79481) (xy 322.522837 -304.836001) (xy 322.552303 -304.881851)
			(xy 322.574945 -304.931428) (xy 322.5903 -304.983723) (xy 322.598056 -305.037671) (xy 322.598542 -305.064922)
			(xy 322.843396 -305.064922) (xy 322.847467 -305.0093) (xy 322.859593 -304.954863) (xy 322.879516 -304.902772)
			(xy 322.906812 -304.854137) (xy 322.940898 -304.809994) (xy 322.981047 -304.771285) (xy 323.026405 -304.738834)
			(xy 323.076005 -304.713333) (xy 323.128789 -304.695326) (xy 323.183632 -304.685196) (xy 323.239366 -304.683159)
			(xy 323.294803 -304.689259) (xy 323.34876 -304.703365) (xy 323.400089 -304.725177) (xy 323.447695 -304.754231)
			(xy 323.490563 -304.789906) (xy 323.52778 -304.831443) (xy 323.558553 -304.877956) (xy 323.582225 -304.928453)
			(xy 323.598293 -304.98186) (xy 323.606413 -305.037036) (xy 323.606903 -305.063906) (xy 323.868032 -305.063906)
			(xy 323.872103 -305.008284) (xy 323.884229 -304.953847) (xy 323.904152 -304.901756) (xy 323.931448 -304.853121)
			(xy 323.965534 -304.808978) (xy 324.005683 -304.770269) (xy 324.051041 -304.737818) (xy 324.100641 -304.712317)
			(xy 324.153425 -304.69431) (xy 324.208268 -304.68418) (xy 324.264002 -304.682143) (xy 324.319439 -304.688243)
			(xy 324.373396 -304.702349) (xy 324.424725 -304.724161) (xy 324.472331 -304.753215) (xy 324.515199 -304.78889)
			(xy 324.552416 -304.830427) (xy 324.583189 -304.87694) (xy 324.606861 -304.927437) (xy 324.622929 -304.980844)
			(xy 324.631049 -305.03602) (xy 324.631233 -305.046126) (xy 324.884032 -305.046126) (xy 324.888103 -304.990504)
			(xy 324.900229 -304.936067) (xy 324.920152 -304.883976) (xy 324.947448 -304.835341) (xy 324.981534 -304.791198)
			(xy 325.021683 -304.752489) (xy 325.067041 -304.720038) (xy 325.116641 -304.694537) (xy 325.169425 -304.67653)
			(xy 325.224268 -304.6664) (xy 325.280002 -304.664363) (xy 325.335439 -304.670463) (xy 325.389396 -304.684569)
			(xy 325.440725 -304.706381) (xy 325.488331 -304.735435) (xy 325.531199 -304.77111) (xy 325.568416 -304.812647)
			(xy 325.599189 -304.85916) (xy 325.622861 -304.909657) (xy 325.638929 -304.963064) (xy 325.645621 -305.008534)
			(xy 334.435704 -305.008534) (xy 334.436189 -304.981164) (xy 334.444002 -304.926986) (xy 334.459487 -304.874483)
			(xy 334.482324 -304.824736) (xy 334.512045 -304.778768) (xy 334.529684 -304.757836) (xy 334.53578 -304.750724)
			(xy 334.54213 -304.733706) (xy 334.54213 -304.648362) (xy 334.53578 -304.631344) (xy 334.529684 -304.624232)
			(xy 334.512044 -304.603301) (xy 334.482333 -304.557327) (xy 334.459497 -304.50758) (xy 334.444006 -304.455079)
			(xy 334.436178 -304.400903) (xy 334.435704 -304.373534) (xy 334.43619 -304.346283) (xy 334.443946 -304.292335)
			(xy 334.459301 -304.24004) (xy 334.481943 -304.190463) (xy 334.511409 -304.144613) (xy 334.5471 -304.103422)
			(xy 334.588291 -304.067731) (xy 334.634141 -304.038265) (xy 334.683718 -304.015623) (xy 334.736013 -304.000268)
			(xy 334.789961 -303.992512) (xy 334.844463 -303.992512) (xy 334.898411 -304.000268) (xy 334.950706 -304.015623)
			(xy 335.000283 -304.038265) (xy 335.046133 -304.067731) (xy 335.087324 -304.103422) (xy 335.123015 -304.144613)
			(xy 335.152481 -304.190463) (xy 335.175123 -304.24004) (xy 335.190478 -304.292335) (xy 335.198234 -304.346283)
			(xy 335.19872 -304.373534) (xy 335.198293 -304.400906) (xy 335.190469 -304.455087) (xy 335.174972 -304.507592)
			(xy 335.152121 -304.557338) (xy 335.122386 -304.603302) (xy 335.10474 -304.624232) (xy 335.098644 -304.631344)
			(xy 335.092294 -304.648362) (xy 335.092294 -304.733706) (xy 335.098644 -304.750724) (xy 335.10474 -304.757836)
			(xy 335.122369 -304.778776) (xy 335.152081 -304.824747) (xy 335.174919 -304.874493) (xy 335.190412 -304.926991)
			(xy 335.198244 -304.981165) (xy 335.19872 -305.008534) (xy 337.855814 -305.008534) (xy 337.856297 -304.981164)
			(xy 337.86411 -304.926986) (xy 337.879595 -304.874483) (xy 337.902433 -304.824736) (xy 337.932154 -304.778768)
			(xy 337.949794 -304.757836) (xy 337.95589 -304.750724) (xy 337.96224 -304.733706) (xy 337.96224 -304.648362)
			(xy 337.95589 -304.631344) (xy 337.949794 -304.624232) (xy 337.932156 -304.603299) (xy 337.902444 -304.557327)
			(xy 337.879608 -304.507579) (xy 337.864117 -304.455079) (xy 337.856288 -304.400903) (xy 337.855814 -304.373534)
			(xy 337.8563 -304.346283) (xy 337.864056 -304.292335) (xy 337.879411 -304.24004) (xy 337.902053 -304.190463)
			(xy 337.931519 -304.144613) (xy 337.96721 -304.103422) (xy 338.008401 -304.067731) (xy 338.054251 -304.038265)
			(xy 338.103828 -304.015623) (xy 338.156123 -304.000268) (xy 338.210071 -303.992512) (xy 338.264573 -303.992512)
			(xy 338.318521 -304.000268) (xy 338.370816 -304.015623) (xy 338.420393 -304.038265) (xy 338.466243 -304.067731)
			(xy 338.507434 -304.103422) (xy 338.543125 -304.144613) (xy 338.572591 -304.190463) (xy 338.595233 -304.24004)
			(xy 338.610588 -304.292335) (xy 338.618344 -304.346283) (xy 338.61883 -304.373534) (xy 338.618401 -304.400906)
			(xy 338.610577 -304.455087) (xy 338.59508 -304.507591) (xy 338.57223 -304.557338) (xy 338.542496 -304.603302)
			(xy 338.52485 -304.624232) (xy 338.518754 -304.631344) (xy 338.512404 -304.648362) (xy 338.512404 -304.733706)
			(xy 338.518754 -304.750724) (xy 338.52485 -304.757836) (xy 338.542465 -304.778788) (xy 338.572182 -304.824754)
			(xy 338.595023 -304.874497) (xy 338.61052 -304.926993) (xy 338.618353 -304.981166) (xy 338.61883 -305.008534)
			(xy 339.243924 -305.008534) (xy 339.244404 -304.981164) (xy 339.252218 -304.926985) (xy 339.267703 -304.874482)
			(xy 339.290542 -304.824735) (xy 339.320264 -304.778768) (xy 339.337904 -304.757836) (xy 339.344 -304.750724)
			(xy 339.35035 -304.733706) (xy 339.35035 -304.648362) (xy 339.344 -304.631344) (xy 339.337904 -304.624232)
			(xy 339.320267 -304.603298) (xy 339.290555 -304.557326) (xy 339.267718 -304.507579) (xy 339.252227 -304.455079)
			(xy 339.244398 -304.400903) (xy 339.243924 -304.373534) (xy 339.24441 -304.346283) (xy 339.252166 -304.292335)
			(xy 339.267521 -304.24004) (xy 339.290163 -304.190463) (xy 339.319629 -304.144613) (xy 339.35532 -304.103422)
			(xy 339.396511 -304.067731) (xy 339.442361 -304.038265) (xy 339.491938 -304.015623) (xy 339.544233 -304.000268)
			(xy 339.598181 -303.992512) (xy 339.652683 -303.992512) (xy 339.706631 -304.000268) (xy 339.758926 -304.015623)
			(xy 339.808503 -304.038265) (xy 339.854353 -304.067731) (xy 339.895544 -304.103422) (xy 339.931235 -304.144613)
			(xy 339.960701 -304.190463) (xy 339.983343 -304.24004) (xy 339.998698 -304.292335) (xy 340.006454 -304.346283)
			(xy 340.00694 -304.373534) (xy 340.006508 -304.400906) (xy 339.998685 -304.455087) (xy 339.983188 -304.507591)
			(xy 339.960338 -304.557337) (xy 339.930605 -304.603302) (xy 339.91296 -304.624232) (xy 339.906864 -304.631344)
			(xy 339.900514 -304.648362) (xy 339.900514 -304.733706) (xy 339.906864 -304.750724) (xy 339.91296 -304.757836)
			(xy 339.930576 -304.778787) (xy 339.960293 -304.824754) (xy 339.983134 -304.874496) (xy 339.99863 -304.926993)
			(xy 340.006463 -304.981166) (xy 340.00694 -305.008534) (xy 341.275924 -305.008534) (xy 341.276404 -304.981164)
			(xy 341.284218 -304.926985) (xy 341.299703 -304.874482) (xy 341.322542 -304.824735) (xy 341.352264 -304.778768)
			(xy 341.369904 -304.757836) (xy 341.376 -304.750724) (xy 341.38235 -304.733706) (xy 341.38235 -304.648362)
			(xy 341.376 -304.631344) (xy 341.369904 -304.624232) (xy 341.352267 -304.603298) (xy 341.322555 -304.557326)
			(xy 341.299718 -304.507579) (xy 341.284227 -304.455079) (xy 341.276398 -304.400903) (xy 341.275924 -304.373534)
			(xy 341.27641 -304.346283) (xy 341.284166 -304.292335) (xy 341.299521 -304.24004) (xy 341.322163 -304.190463)
			(xy 341.351629 -304.144613) (xy 341.38732 -304.103422) (xy 341.428511 -304.067731) (xy 341.474361 -304.038265)
			(xy 341.523938 -304.015623) (xy 341.576233 -304.000268) (xy 341.630181 -303.992512) (xy 341.684683 -303.992512)
			(xy 341.738631 -304.000268) (xy 341.790926 -304.015623) (xy 341.840503 -304.038265) (xy 341.886353 -304.067731)
			(xy 341.927544 -304.103422) (xy 341.963235 -304.144613) (xy 341.992701 -304.190463) (xy 342.015343 -304.24004)
			(xy 342.030698 -304.292335) (xy 342.038454 -304.346283) (xy 342.03894 -304.373534) (xy 342.038508 -304.400906)
			(xy 342.030685 -304.455087) (xy 342.015188 -304.507591) (xy 341.992338 -304.557337) (xy 341.962605 -304.603302)
			(xy 341.94496 -304.624232) (xy 341.938864 -304.631344) (xy 341.932514 -304.648362) (xy 341.932514 -304.733706)
			(xy 341.938864 -304.750724) (xy 341.94496 -304.757836) (xy 341.962576 -304.778787) (xy 341.992293 -304.824754)
			(xy 342.015134 -304.874496) (xy 342.03063 -304.926993) (xy 342.038463 -304.981166) (xy 342.03894 -305.008534)
			(xy 346.084144 -305.008534) (xy 346.084619 -304.981164) (xy 346.092433 -304.926985) (xy 346.10792 -304.874481)
			(xy 346.13076 -304.824734) (xy 346.160483 -304.778768) (xy 346.178124 -304.757836) (xy 346.18422 -304.750724)
			(xy 346.19057 -304.733706) (xy 346.19057 -304.648362) (xy 346.18422 -304.631344) (xy 346.178124 -304.624232)
			(xy 346.16049 -304.603296) (xy 346.130777 -304.557324) (xy 346.107939 -304.507578) (xy 346.092447 -304.455078)
			(xy 346.084618 -304.400903) (xy 346.084144 -304.373534) (xy 346.08463 -304.346283) (xy 346.092386 -304.292335)
			(xy 346.107741 -304.24004) (xy 346.130383 -304.190463) (xy 346.159849 -304.144613) (xy 346.19554 -304.103422)
			(xy 346.236731 -304.067731) (xy 346.282581 -304.038265) (xy 346.332158 -304.015623) (xy 346.384453 -304.000268)
			(xy 346.438401 -303.992512) (xy 346.492903 -303.992512) (xy 346.546851 -304.000268) (xy 346.599146 -304.015623)
			(xy 346.648723 -304.038265) (xy 346.694573 -304.067731) (xy 346.735764 -304.103422) (xy 346.771455 -304.144613)
			(xy 346.779823 -304.157634) (xy 348.984568 -304.157634) (xy 348.988639 -304.102012) (xy 349.000765 -304.047575)
			(xy 349.020688 -303.995484) (xy 349.047984 -303.946849) (xy 349.08207 -303.902706) (xy 349.122219 -303.863997)
			(xy 349.167577 -303.831546) (xy 349.217177 -303.806045) (xy 349.269961 -303.788038) (xy 349.324804 -303.777908)
			(xy 349.380538 -303.775871) (xy 349.435975 -303.781971) (xy 349.489932 -303.796077) (xy 349.541261 -303.817889)
			(xy 349.588867 -303.846943) (xy 349.631735 -303.882618) (xy 349.668952 -303.924155) (xy 349.699725 -303.970668)
			(xy 349.723397 -304.021165) (xy 349.739465 -304.074572) (xy 349.747585 -304.129748) (xy 349.748094 -304.157634)
			(xy 349.747585 -304.18552) (xy 349.739465 -304.240696) (xy 349.723397 -304.294103) (xy 349.699725 -304.3446)
			(xy 349.668952 -304.391113) (xy 349.631735 -304.43265) (xy 349.588867 -304.468325) (xy 349.541261 -304.497379)
			(xy 349.489932 -304.519191) (xy 349.435975 -304.533297) (xy 349.380538 -304.539397) (xy 349.324804 -304.53736)
			(xy 349.269961 -304.52723) (xy 349.217177 -304.509223) (xy 349.167577 -304.483722) (xy 349.122219 -304.451271)
			(xy 349.08207 -304.412562) (xy 349.047984 -304.368419) (xy 349.020688 -304.319784) (xy 349.000765 -304.267693)
			(xy 348.988639 -304.213256) (xy 348.984568 -304.157634) (xy 346.779823 -304.157634) (xy 346.800921 -304.190463)
			(xy 346.823563 -304.24004) (xy 346.838918 -304.292335) (xy 346.846674 -304.346283) (xy 346.84716 -304.373534)
			(xy 346.846724 -304.400905) (xy 346.8389 -304.455086) (xy 346.823405 -304.50759) (xy 346.800556 -304.557336)
			(xy 346.770825 -304.603302) (xy 346.75318 -304.624232) (xy 346.747084 -304.631344) (xy 346.740734 -304.648362)
			(xy 346.740734 -304.733706) (xy 346.747084 -304.750724) (xy 346.75318 -304.757836) (xy 346.770799 -304.778784)
			(xy 346.800515 -304.824752) (xy 346.823355 -304.874496) (xy 346.838851 -304.926993) (xy 346.846684 -304.981166)
			(xy 346.84716 -305.008534) (xy 346.846674 -305.035785) (xy 346.838918 -305.089733) (xy 346.823563 -305.142028)
			(xy 346.800921 -305.191605) (xy 346.771455 -305.237455) (xy 346.735764 -305.278646) (xy 346.694573 -305.314337)
			(xy 346.648723 -305.343803) (xy 346.599146 -305.366445) (xy 346.546851 -305.3818) (xy 346.492903 -305.389556)
			(xy 346.438401 -305.389556) (xy 346.384453 -305.3818) (xy 346.332158 -305.366445) (xy 346.282581 -305.343803)
			(xy 346.236731 -305.314337) (xy 346.19554 -305.278646) (xy 346.159849 -305.237455) (xy 346.130383 -305.191605)
			(xy 346.107741 -305.142028) (xy 346.092386 -305.089733) (xy 346.08463 -305.035785) (xy 346.084144 -305.008534)
			(xy 342.03894 -305.008534) (xy 342.038454 -305.035785) (xy 342.030698 -305.089733) (xy 342.015343 -305.142028)
			(xy 341.992701 -305.191605) (xy 341.963235 -305.237455) (xy 341.927544 -305.278646) (xy 341.886353 -305.314337)
			(xy 341.840503 -305.343803) (xy 341.790926 -305.366445) (xy 341.738631 -305.3818) (xy 341.684683 -305.389556)
			(xy 341.630181 -305.389556) (xy 341.576233 -305.3818) (xy 341.523938 -305.366445) (xy 341.474361 -305.343803)
			(xy 341.428511 -305.314337) (xy 341.38732 -305.278646) (xy 341.351629 -305.237455) (xy 341.322163 -305.191605)
			(xy 341.299521 -305.142028) (xy 341.284166 -305.089733) (xy 341.27641 -305.035785) (xy 341.275924 -305.008534)
			(xy 340.00694 -305.008534) (xy 340.006454 -305.035785) (xy 339.998698 -305.089733) (xy 339.983343 -305.142028)
			(xy 339.960701 -305.191605) (xy 339.931235 -305.237455) (xy 339.895544 -305.278646) (xy 339.854353 -305.314337)
			(xy 339.808503 -305.343803) (xy 339.758926 -305.366445) (xy 339.706631 -305.3818) (xy 339.652683 -305.389556)
			(xy 339.598181 -305.389556) (xy 339.544233 -305.3818) (xy 339.491938 -305.366445) (xy 339.442361 -305.343803)
			(xy 339.396511 -305.314337) (xy 339.35532 -305.278646) (xy 339.319629 -305.237455) (xy 339.290163 -305.191605)
			(xy 339.267521 -305.142028) (xy 339.252166 -305.089733) (xy 339.24441 -305.035785) (xy 339.243924 -305.008534)
			(xy 338.61883 -305.008534) (xy 338.618344 -305.035785) (xy 338.610588 -305.089733) (xy 338.595233 -305.142028)
			(xy 338.572591 -305.191605) (xy 338.543125 -305.237455) (xy 338.507434 -305.278646) (xy 338.466243 -305.314337)
			(xy 338.420393 -305.343803) (xy 338.370816 -305.366445) (xy 338.318521 -305.3818) (xy 338.264573 -305.389556)
			(xy 338.210071 -305.389556) (xy 338.156123 -305.3818) (xy 338.103828 -305.366445) (xy 338.054251 -305.343803)
			(xy 338.008401 -305.314337) (xy 337.96721 -305.278646) (xy 337.931519 -305.237455) (xy 337.902053 -305.191605)
			(xy 337.879411 -305.142028) (xy 337.864056 -305.089733) (xy 337.8563 -305.035785) (xy 337.855814 -305.008534)
			(xy 335.19872 -305.008534) (xy 335.198234 -305.035785) (xy 335.190478 -305.089733) (xy 335.175123 -305.142028)
			(xy 335.152481 -305.191605) (xy 335.123015 -305.237455) (xy 335.087324 -305.278646) (xy 335.046133 -305.314337)
			(xy 335.000283 -305.343803) (xy 334.950706 -305.366445) (xy 334.898411 -305.3818) (xy 334.844463 -305.389556)
			(xy 334.789961 -305.389556) (xy 334.736013 -305.3818) (xy 334.683718 -305.366445) (xy 334.634141 -305.343803)
			(xy 334.588291 -305.314337) (xy 334.5471 -305.278646) (xy 334.511409 -305.237455) (xy 334.481943 -305.191605)
			(xy 334.459301 -305.142028) (xy 334.443946 -305.089733) (xy 334.43619 -305.035785) (xy 334.435704 -305.008534)
			(xy 325.645621 -305.008534) (xy 325.647049 -305.01824) (xy 325.647558 -305.046126) (xy 325.647049 -305.074012)
			(xy 325.638929 -305.129188) (xy 325.622861 -305.182595) (xy 325.599189 -305.233092) (xy 325.568416 -305.279605)
			(xy 325.531199 -305.321142) (xy 325.488331 -305.356817) (xy 325.440725 -305.385871) (xy 325.389396 -305.407683)
			(xy 325.335439 -305.421789) (xy 325.280002 -305.427889) (xy 325.224268 -305.425852) (xy 325.169425 -305.415722)
			(xy 325.116641 -305.397715) (xy 325.067041 -305.372214) (xy 325.021683 -305.339763) (xy 324.981534 -305.301054)
			(xy 324.947448 -305.256911) (xy 324.920152 -305.208276) (xy 324.900229 -305.156185) (xy 324.888103 -305.101748)
			(xy 324.884032 -305.046126) (xy 324.631233 -305.046126) (xy 324.631558 -305.063906) (xy 324.631049 -305.091792)
			(xy 324.622929 -305.146968) (xy 324.606861 -305.200375) (xy 324.583189 -305.250872) (xy 324.552416 -305.297385)
			(xy 324.515199 -305.338922) (xy 324.472331 -305.374597) (xy 324.424725 -305.403651) (xy 324.373396 -305.425463)
			(xy 324.319439 -305.439569) (xy 324.264002 -305.445669) (xy 324.208268 -305.443632) (xy 324.153425 -305.433502)
			(xy 324.100641 -305.415495) (xy 324.051041 -305.389994) (xy 324.005683 -305.357543) (xy 323.965534 -305.318834)
			(xy 323.931448 -305.274691) (xy 323.904152 -305.226056) (xy 323.884229 -305.173965) (xy 323.872103 -305.119528)
			(xy 323.868032 -305.063906) (xy 323.606903 -305.063906) (xy 323.606922 -305.064922) (xy 323.606413 -305.092808)
			(xy 323.598293 -305.147984) (xy 323.582225 -305.201391) (xy 323.558553 -305.251888) (xy 323.52778 -305.298401)
			(xy 323.490563 -305.339938) (xy 323.447695 -305.375613) (xy 323.400089 -305.404667) (xy 323.34876 -305.426479)
			(xy 323.294803 -305.440585) (xy 323.239366 -305.446685) (xy 323.183632 -305.444648) (xy 323.128789 -305.434518)
			(xy 323.076005 -305.416511) (xy 323.026405 -305.39101) (xy 322.981047 -305.358559) (xy 322.940898 -305.31985)
			(xy 322.906812 -305.275707) (xy 322.879516 -305.227072) (xy 322.859593 -305.174981) (xy 322.847467 -305.120544)
			(xy 322.843396 -305.064922) (xy 322.598542 -305.064922) (xy 322.598099 -305.091324) (xy 322.590822 -305.143625)
			(xy 322.576397 -305.194421) (xy 322.5551 -305.242741) (xy 322.527338 -305.287659) (xy 322.493643 -305.328315)
			(xy 322.45466 -305.363933) (xy 322.411134 -305.39383) (xy 322.387722 -305.406044) (xy 322.380356 -305.409854)
			(xy 322.370958 -305.419252) (xy 322.362943 -305.428123) (xy 322.355404 -305.450778) (xy 322.35648 -305.462686)
			(xy 322.358258 -305.47437) (xy 322.372228 -305.493928) (xy 322.936616 -305.79568) (xy 322.95084 -305.803554)
			(xy 322.951094 -305.803554) (xy 323.060314 -305.861974) (xy 323.063569 -305.86381) (xy 323.069564 -305.868269)
			(xy 323.072252 -305.870864) (xy 323.158866 -305.957478) (xy 323.159374 -305.957986) (xy 323.171566 -305.970178)
			(xy 324.285679 -307.084222) (xy 324.914258 -307.084222) (xy 324.918329 -307.0286) (xy 324.930455 -306.974163)
			(xy 324.950378 -306.922072) (xy 324.977674 -306.873437) (xy 325.01176 -306.829294) (xy 325.051909 -306.790585)
			(xy 325.097267 -306.758134) (xy 325.146867 -306.732633) (xy 325.199651 -306.714626) (xy 325.254494 -306.704496)
			(xy 325.310228 -306.702459) (xy 325.365665 -306.708559) (xy 325.419622 -306.722665) (xy 325.470951 -306.744477)
			(xy 325.518557 -306.773531) (xy 325.561425 -306.809206) (xy 325.598642 -306.850743) (xy 325.629415 -306.897256)
			(xy 325.653087 -306.947753) (xy 325.669155 -307.00116) (xy 325.677275 -307.056336) (xy 325.677784 -307.084222)
			(xy 325.677275 -307.112108) (xy 325.669155 -307.167284) (xy 325.653087 -307.220691) (xy 325.629415 -307.271188)
			(xy 325.598642 -307.317701) (xy 325.561425 -307.359238) (xy 325.518557 -307.394913) (xy 325.470951 -307.423967)
			(xy 325.419622 -307.445779) (xy 325.365665 -307.459885) (xy 325.310228 -307.465985) (xy 325.254494 -307.463948)
			(xy 325.199651 -307.453818) (xy 325.146867 -307.435811) (xy 325.097267 -307.41031) (xy 325.051909 -307.377859)
			(xy 325.01176 -307.33915) (xy 324.977674 -307.295007) (xy 324.950378 -307.246372) (xy 324.930455 -307.194281)
			(xy 324.918329 -307.139844) (xy 324.914258 -307.084222) (xy 324.285679 -307.084222) (xy 325.025373 -307.82387)
			(xy 335.023714 -307.82387) (xy 335.024159 -307.796499) (xy 335.031981 -307.742319) (xy 335.047475 -307.689815)
			(xy 335.070322 -307.640069) (xy 335.100051 -307.594103) (xy 335.117694 -307.573172) (xy 335.12379 -307.56606)
			(xy 335.13014 -307.549042) (xy 335.13014 -307.463698) (xy 335.12379 -307.44668) (xy 335.117694 -307.439568)
			(xy 335.100025 -307.418658) (xy 335.070304 -307.372686) (xy 335.047463 -307.322936) (xy 335.03197 -307.27043)
			(xy 335.024145 -307.216249) (xy 335.024148 -307.161506) (xy 335.03198 -307.107326) (xy 335.047479 -307.054822)
			(xy 335.070326 -307.005075) (xy 335.100053 -306.959105) (xy 335.117694 -306.938172) (xy 335.12379 -306.93106)
			(xy 335.13014 -306.914042) (xy 335.13014 -306.828698) (xy 335.12379 -306.81168) (xy 335.117694 -306.804568)
			(xy 335.100025 -306.783658) (xy 335.070304 -306.737686) (xy 335.047463 -306.687936) (xy 335.03197 -306.63543)
			(xy 335.024145 -306.581249) (xy 335.024148 -306.526506) (xy 335.03198 -306.472326) (xy 335.047479 -306.419822)
			(xy 335.070326 -306.370075) (xy 335.100053 -306.324105) (xy 335.117694 -306.303172) (xy 335.12379 -306.29606)
			(xy 335.13014 -306.279042) (xy 335.13014 -306.193698) (xy 335.12379 -306.17668) (xy 335.117694 -306.169568)
			(xy 335.100072 -306.148622) (xy 335.070358 -306.102653) (xy 335.047519 -306.052909) (xy 335.032024 -306.000411)
			(xy 335.024191 -305.946238) (xy 335.023714 -305.91887) (xy 335.0242 -305.891619) (xy 335.031956 -305.837671)
			(xy 335.047311 -305.785376) (xy 335.069953 -305.735799) (xy 335.099419 -305.689949) (xy 335.13511 -305.648758)
			(xy 335.176301 -305.613067) (xy 335.222151 -305.583601) (xy 335.271728 -305.560959) (xy 335.324023 -305.545604)
			(xy 335.377971 -305.537848) (xy 335.432473 -305.537848) (xy 335.486421 -305.545604) (xy 335.538716 -305.560959)
			(xy 335.588293 -305.583601) (xy 335.634143 -305.613067) (xy 335.675334 -305.648758) (xy 335.711025 -305.689949)
			(xy 335.740491 -305.735799) (xy 335.763133 -305.785376) (xy 335.778488 -305.837671) (xy 335.786244 -305.891619)
			(xy 335.78673 -305.91887) (xy 335.786263 -305.94624) (xy 335.778448 -306.00042) (xy 335.76296 -306.052924)
			(xy 335.740118 -306.102671) (xy 335.710392 -306.148637) (xy 335.69275 -306.169568) (xy 335.686654 -306.17668)
			(xy 335.680304 -306.193698) (xy 335.680304 -306.279042) (xy 335.686654 -306.29606) (xy 335.69275 -306.303172)
			(xy 335.710362 -306.324128) (xy 335.74009 -306.370091) (xy 335.762939 -306.419834) (xy 335.778438 -306.472332)
			(xy 335.78627 -306.526508) (xy 335.786273 -306.581247) (xy 335.778448 -306.635424) (xy 335.762954 -306.687924)
			(xy 335.740112 -306.737669) (xy 335.71039 -306.783636) (xy 335.69275 -306.804568) (xy 335.686654 -306.81168)
			(xy 335.680304 -306.828698) (xy 335.680304 -306.914042) (xy 335.686654 -306.93106) (xy 335.69275 -306.938172)
			(xy 335.710362 -306.959128) (xy 335.74009 -307.005091) (xy 335.762939 -307.054834) (xy 335.778438 -307.107332)
			(xy 335.78627 -307.161508) (xy 335.786273 -307.216247) (xy 335.778448 -307.270424) (xy 335.762954 -307.322924)
			(xy 335.740112 -307.372669) (xy 335.71039 -307.418636) (xy 335.69275 -307.439568) (xy 335.686654 -307.44668)
			(xy 335.680304 -307.463698) (xy 335.680304 -307.549042) (xy 335.686654 -307.56606) (xy 335.69275 -307.573172)
			(xy 335.710382 -307.59411) (xy 335.740096 -307.640081) (xy 335.762934 -307.689826) (xy 335.778427 -307.742326)
			(xy 335.786256 -307.796501) (xy 335.78673 -307.82387) (xy 335.786244 -307.851121) (xy 335.78242 -307.877718)
			(xy 338.655914 -307.877718) (xy 338.656387 -307.850348) (xy 338.664203 -307.796169) (xy 338.67969 -307.743666)
			(xy 338.70253 -307.693919) (xy 338.732253 -307.647952) (xy 338.749894 -307.62702) (xy 338.75599 -307.619908)
			(xy 338.76234 -307.60289) (xy 338.76234 -307.517546) (xy 338.75599 -307.500528) (xy 338.749894 -307.493416)
			(xy 338.732272 -307.472468) (xy 338.702549 -307.426502) (xy 338.679705 -307.376758) (xy 338.664209 -307.324259)
			(xy 338.656379 -307.270083) (xy 338.656377 -307.215344) (xy 338.664203 -307.161168) (xy 338.679695 -307.108667)
			(xy 338.702536 -307.058921) (xy 338.732256 -307.012953) (xy 338.749894 -306.99202) (xy 338.75599 -306.984908)
			(xy 338.76234 -306.96789) (xy 338.76234 -306.882546) (xy 338.75599 -306.865528) (xy 338.749894 -306.858416)
			(xy 338.732272 -306.837468) (xy 338.702549 -306.791502) (xy 338.679705 -306.741758) (xy 338.664209 -306.689259)
			(xy 338.656379 -306.635083) (xy 338.656377 -306.580344) (xy 338.664203 -306.526168) (xy 338.679695 -306.473667)
			(xy 338.702536 -306.423921) (xy 338.732256 -306.377953) (xy 338.749894 -306.35702) (xy 338.75599 -306.349908)
			(xy 338.76234 -306.33289) (xy 338.76234 -306.247546) (xy 338.75599 -306.230528) (xy 338.749894 -306.223416)
			(xy 338.732248 -306.20249) (xy 338.702537 -306.156515) (xy 338.679703 -306.106766) (xy 338.664213 -306.054264)
			(xy 338.656387 -306.000088) (xy 338.655914 -305.972718) (xy 338.6564 -305.945467) (xy 338.664156 -305.891519)
			(xy 338.679511 -305.839224) (xy 338.702153 -305.789647) (xy 338.731619 -305.743797) (xy 338.76731 -305.702606)
			(xy 338.808501 -305.666915) (xy 338.854351 -305.637449) (xy 338.903928 -305.614807) (xy 338.956223 -305.599452)
			(xy 339.010171 -305.591696) (xy 339.064673 -305.591696) (xy 339.118621 -305.599452) (xy 339.170916 -305.614807)
			(xy 339.220493 -305.637449) (xy 339.266343 -305.666915) (xy 339.307534 -305.702606) (xy 339.343225 -305.743797)
			(xy 339.372691 -305.789647) (xy 339.395333 -305.839224) (xy 339.410688 -305.891519) (xy 339.418444 -305.945467)
			(xy 339.41893 -305.972718) (xy 339.418492 -306.000089) (xy 339.41067 -306.05427) (xy 339.395175 -306.106774)
			(xy 339.372327 -306.156521) (xy 339.342595 -306.202486) (xy 339.32495 -306.223416) (xy 339.318854 -306.230528)
			(xy 339.312504 -306.247546) (xy 339.312504 -306.33289) (xy 339.318854 -306.349908) (xy 339.32495 -306.35702)
			(xy 339.342609 -306.377938) (xy 339.372335 -306.423908) (xy 339.395181 -306.473656) (xy 339.410677 -306.526161)
			(xy 339.418504 -306.580342) (xy 339.418502 -306.635085) (xy 339.410671 -306.689266) (xy 339.395171 -306.741769)
			(xy 339.372322 -306.791516) (xy 339.342593 -306.837484) (xy 339.32495 -306.858416) (xy 339.318854 -306.865528)
			(xy 339.312504 -306.882546) (xy 339.312504 -306.96789) (xy 339.318854 -306.984908) (xy 339.32495 -306.99202)
			(xy 339.342609 -307.012938) (xy 339.372335 -307.058908) (xy 339.395181 -307.108656) (xy 339.410677 -307.161161)
			(xy 339.418504 -307.215342) (xy 339.418502 -307.270085) (xy 339.410671 -307.324266) (xy 339.395171 -307.376769)
			(xy 339.372322 -307.426516) (xy 339.342593 -307.472484) (xy 339.32495 -307.493416) (xy 339.318854 -307.500528)
			(xy 339.312504 -307.517546) (xy 339.312504 -307.60289) (xy 339.318854 -307.619908) (xy 339.32495 -307.62702)
			(xy 339.342557 -307.647978) (xy 339.372276 -307.693943) (xy 339.395118 -307.743684) (xy 339.410617 -307.796179)
			(xy 339.414622 -307.82387) (xy 341.863934 -307.82387) (xy 341.864374 -307.796499) (xy 341.872197 -307.742318)
			(xy 341.887692 -307.689814) (xy 341.910539 -307.640068) (xy 341.94027 -307.594103) (xy 341.957914 -307.573172)
			(xy 341.96401 -307.56606) (xy 341.97036 -307.549042) (xy 341.97036 -307.463698) (xy 341.96401 -307.44668)
			(xy 341.957914 -307.439568) (xy 341.940244 -307.418659) (xy 341.910522 -307.372687) (xy 341.887679 -307.322936)
			(xy 341.872186 -307.270431) (xy 341.86436 -307.216249) (xy 341.864363 -307.161506) (xy 341.872195 -307.107325)
			(xy 341.887695 -307.054821) (xy 341.910544 -307.005074) (xy 341.940272 -306.959105) (xy 341.957914 -306.938172)
			(xy 341.96401 -306.93106) (xy 341.97036 -306.914042) (xy 341.97036 -306.828698) (xy 341.96401 -306.81168)
			(xy 341.957914 -306.804568) (xy 341.940244 -306.783659) (xy 341.910522 -306.737687) (xy 341.887679 -306.687936)
			(xy 341.872186 -306.635431) (xy 341.86436 -306.581249) (xy 341.864363 -306.526506) (xy 341.872195 -306.472325)
			(xy 341.887695 -306.419821) (xy 341.910544 -306.370074) (xy 341.940272 -306.324105) (xy 341.957914 -306.303172)
			(xy 341.96401 -306.29606) (xy 341.97036 -306.279042) (xy 341.97036 -306.193698) (xy 341.96401 -306.17668)
			(xy 341.957914 -306.169568) (xy 341.940296 -306.148619) (xy 341.91058 -306.102651) (xy 341.88774 -306.052908)
			(xy 341.872244 -306.000411) (xy 341.864411 -305.946238) (xy 341.863934 -305.91887) (xy 341.86442 -305.891619)
			(xy 341.872176 -305.837671) (xy 341.887531 -305.785376) (xy 341.910173 -305.735799) (xy 341.939639 -305.689949)
			(xy 341.97533 -305.648758) (xy 342.016521 -305.613067) (xy 342.062371 -305.583601) (xy 342.111948 -305.560959)
			(xy 342.164243 -305.545604) (xy 342.218191 -305.537848) (xy 342.272693 -305.537848) (xy 342.326641 -305.545604)
			(xy 342.378936 -305.560959) (xy 342.428513 -305.583601) (xy 342.474363 -305.613067) (xy 342.515554 -305.648758)
			(xy 342.551245 -305.689949) (xy 342.580711 -305.735799) (xy 342.603353 -305.785376) (xy 342.618708 -305.837671)
			(xy 342.626464 -305.891619) (xy 342.62695 -305.91887) (xy 342.626479 -305.94624) (xy 342.618664 -306.00042)
			(xy 342.603177 -306.052923) (xy 342.580336 -306.10267) (xy 342.550611 -306.148637) (xy 342.53297 -306.169568)
			(xy 342.526874 -306.17668) (xy 342.520524 -306.193698) (xy 342.520524 -306.279042) (xy 342.526874 -306.29606)
			(xy 342.53297 -306.303172) (xy 342.550581 -306.324128) (xy 342.580308 -306.370092) (xy 342.603155 -306.419834)
			(xy 342.618654 -306.472333) (xy 342.626485 -306.526508) (xy 342.626488 -306.581247) (xy 342.618663 -306.635423)
			(xy 342.603171 -306.687923) (xy 342.580329 -306.737668) (xy 342.550609 -306.783635) (xy 342.53297 -306.804568)
			(xy 342.526874 -306.81168) (xy 342.520524 -306.828698) (xy 342.520524 -306.914042) (xy 342.526874 -306.93106)
			(xy 342.53297 -306.938172) (xy 342.550581 -306.959128) (xy 342.580308 -307.005092) (xy 342.603155 -307.054834)
			(xy 342.618654 -307.107333) (xy 342.626485 -307.161508) (xy 342.626488 -307.216247) (xy 342.618663 -307.270423)
			(xy 342.603171 -307.322923) (xy 342.580329 -307.372668) (xy 342.550609 -307.418635) (xy 342.53297 -307.439568)
			(xy 342.526874 -307.44668) (xy 342.520524 -307.463698) (xy 342.520524 -307.549042) (xy 342.526874 -307.56606)
			(xy 342.53297 -307.573172) (xy 342.550605 -307.594108) (xy 342.580318 -307.640079) (xy 342.603156 -307.689826)
			(xy 342.618648 -307.742326) (xy 342.626476 -307.796501) (xy 342.62695 -307.82387) (xy 342.626464 -307.851121)
			(xy 342.62264 -307.877718) (xy 345.496134 -307.877718) (xy 345.496602 -307.850348) (xy 345.504418 -307.796168)
			(xy 345.519906 -307.743665) (xy 345.542748 -307.693918) (xy 345.572473 -307.647951) (xy 345.590114 -307.62702)
			(xy 345.59621 -307.619908) (xy 345.60256 -307.60289) (xy 345.60256 -307.517546) (xy 345.59621 -307.500528)
			(xy 345.590114 -307.493416) (xy 345.572491 -307.472469) (xy 345.542767 -307.426503) (xy 345.519921 -307.376759)
			(xy 345.504424 -307.324259) (xy 345.496594 -307.270083) (xy 345.496592 -307.215344) (xy 345.504418 -307.161167)
			(xy 345.519912 -307.108666) (xy 345.542754 -307.058921) (xy 345.572475 -307.012953) (xy 345.590114 -306.99202)
			(xy 345.59621 -306.984908) (xy 345.60256 -306.96789) (xy 345.60256 -306.882546) (xy 345.59621 -306.865528)
			(xy 345.590114 -306.858416) (xy 345.572491 -306.837469) (xy 345.542767 -306.791503) (xy 345.519921 -306.741759)
			(xy 345.504424 -306.689259) (xy 345.496594 -306.635083) (xy 345.496592 -306.580344) (xy 345.504418 -306.526167)
			(xy 345.519912 -306.473666) (xy 345.542754 -306.423921) (xy 345.572475 -306.377953) (xy 345.590114 -306.35702)
			(xy 345.59621 -306.349908) (xy 345.60256 -306.33289) (xy 345.60256 -306.247546) (xy 345.59621 -306.230528)
			(xy 345.590114 -306.223416) (xy 345.572471 -306.202487) (xy 345.542759 -306.156514) (xy 345.519924 -306.106765)
			(xy 345.504434 -306.054264) (xy 345.496607 -306.000087) (xy 345.496134 -305.972718) (xy 345.49662 -305.945467)
			(xy 345.504376 -305.891519) (xy 345.519731 -305.839224) (xy 345.542373 -305.789647) (xy 345.571839 -305.743797)
			(xy 345.60753 -305.702606) (xy 345.648721 -305.666915) (xy 345.694571 -305.637449) (xy 345.744148 -305.614807)
			(xy 345.796443 -305.599452) (xy 345.850391 -305.591696) (xy 345.904893 -305.591696) (xy 345.958841 -305.599452)
			(xy 346.011136 -305.614807) (xy 346.060713 -305.637449) (xy 346.106563 -305.666915) (xy 346.147754 -305.702606)
			(xy 346.183445 -305.743797) (xy 346.212911 -305.789647) (xy 346.235553 -305.839224) (xy 346.250908 -305.891519)
			(xy 346.258664 -305.945467) (xy 346.25915 -305.972718) (xy 346.258707 -306.000089) (xy 346.250885 -306.05427)
			(xy 346.235392 -306.106774) (xy 346.212544 -306.15652) (xy 346.182814 -306.202486) (xy 346.16517 -306.223416)
			(xy 346.159074 -306.230528) (xy 346.152724 -306.247546) (xy 346.152724 -306.33289) (xy 346.159074 -306.349908)
			(xy 346.16517 -306.35702) (xy 346.182828 -306.377938) (xy 346.212553 -306.423909) (xy 346.235397 -306.473657)
			(xy 346.250892 -306.526161) (xy 346.258719 -306.580342) (xy 346.258717 -306.635085) (xy 346.250886 -306.689265)
			(xy 346.235388 -306.741768) (xy 346.21254 -306.791515) (xy 346.182812 -306.837483) (xy 346.16517 -306.858416)
			(xy 346.159074 -306.865528) (xy 346.152724 -306.882546) (xy 346.152724 -306.96789) (xy 346.159074 -306.984908)
			(xy 346.16517 -306.99202) (xy 346.182828 -307.012938) (xy 346.212553 -307.058909) (xy 346.235397 -307.108657)
			(xy 346.250892 -307.161161) (xy 346.258719 -307.215342) (xy 346.258717 -307.270085) (xy 346.250886 -307.324265)
			(xy 346.235388 -307.376768) (xy 346.21254 -307.426515) (xy 346.182812 -307.472483) (xy 346.16517 -307.493416)
			(xy 346.159074 -307.500528) (xy 346.152724 -307.517546) (xy 346.152724 -307.60289) (xy 346.159074 -307.619908)
			(xy 346.16517 -307.62702) (xy 346.18278 -307.647975) (xy 346.212498 -307.693941) (xy 346.23534 -307.743683)
			(xy 346.250837 -307.796178) (xy 346.258672 -307.85035) (xy 346.25915 -307.877718) (xy 346.258664 -307.904969)
			(xy 346.250908 -307.958917) (xy 346.235553 -308.011212) (xy 346.212911 -308.060789) (xy 346.183445 -308.106639)
			(xy 346.147754 -308.14783) (xy 346.106563 -308.183521) (xy 346.060713 -308.212987) (xy 346.011136 -308.235629)
			(xy 345.958841 -308.250984) (xy 345.904893 -308.25874) (xy 345.850391 -308.25874) (xy 345.796443 -308.250984)
			(xy 345.744148 -308.235629) (xy 345.694571 -308.212987) (xy 345.648721 -308.183521) (xy 345.60753 -308.14783)
			(xy 345.571839 -308.106639) (xy 345.542373 -308.060789) (xy 345.519731 -308.011212) (xy 345.504376 -307.958917)
			(xy 345.49662 -307.904969) (xy 345.496134 -307.877718) (xy 342.62264 -307.877718) (xy 342.618708 -307.905069)
			(xy 342.603353 -307.957364) (xy 342.580711 -308.006941) (xy 342.551245 -308.052791) (xy 342.515554 -308.093982)
			(xy 342.474363 -308.129673) (xy 342.428513 -308.159139) (xy 342.378936 -308.181781) (xy 342.326641 -308.197136)
			(xy 342.272693 -308.204892) (xy 342.218191 -308.204892) (xy 342.164243 -308.197136) (xy 342.111948 -308.181781)
			(xy 342.062371 -308.159139) (xy 342.016521 -308.129673) (xy 341.97533 -308.093982) (xy 341.939639 -308.052791)
			(xy 341.910173 -308.006941) (xy 341.887531 -307.957364) (xy 341.872176 -307.905069) (xy 341.86442 -307.851121)
			(xy 341.863934 -307.82387) (xy 339.414622 -307.82387) (xy 339.418452 -307.85035) (xy 339.41893 -307.877718)
			(xy 339.418444 -307.904969) (xy 339.410688 -307.958917) (xy 339.395333 -308.011212) (xy 339.372691 -308.060789)
			(xy 339.343225 -308.106639) (xy 339.307534 -308.14783) (xy 339.266343 -308.183521) (xy 339.220493 -308.212987)
			(xy 339.170916 -308.235629) (xy 339.118621 -308.250984) (xy 339.064673 -308.25874) (xy 339.010171 -308.25874)
			(xy 338.956223 -308.250984) (xy 338.903928 -308.235629) (xy 338.854351 -308.212987) (xy 338.808501 -308.183521)
			(xy 338.76731 -308.14783) (xy 338.731619 -308.106639) (xy 338.702153 -308.060789) (xy 338.679511 -308.011212)
			(xy 338.664156 -307.958917) (xy 338.6564 -307.904969) (xy 338.655914 -307.877718) (xy 335.78242 -307.877718)
			(xy 335.778488 -307.905069) (xy 335.763133 -307.957364) (xy 335.740491 -308.006941) (xy 335.711025 -308.052791)
			(xy 335.675334 -308.093982) (xy 335.634143 -308.129673) (xy 335.588293 -308.159139) (xy 335.538716 -308.181781)
			(xy 335.486421 -308.197136) (xy 335.432473 -308.204892) (xy 335.377971 -308.204892) (xy 335.324023 -308.197136)
			(xy 335.271728 -308.181781) (xy 335.222151 -308.159139) (xy 335.176301 -308.129673) (xy 335.13511 -308.093982)
			(xy 335.099419 -308.052791) (xy 335.069953 -308.006941) (xy 335.047311 -307.957364) (xy 335.031956 -307.905069)
			(xy 335.0242 -307.851121) (xy 335.023714 -307.82387) (xy 325.025373 -307.82387) (xy 327.259188 -310.057546)
			(xy 327.264776 -310.064658) (xy 327.29043 -310.104282) (xy 327.291192 -310.105552) (xy 327.317354 -310.14289)
			(xy 327.384054 -310.242712) (xy 332.67218 -310.242712) (xy 332.676251 -310.18709) (xy 332.688377 -310.132653)
			(xy 332.7083 -310.080562) (xy 332.735596 -310.031927) (xy 332.769682 -309.987784) (xy 332.809831 -309.949075)
			(xy 332.855189 -309.916624) (xy 332.904789 -309.891123) (xy 332.957573 -309.873116) (xy 333.012416 -309.862986)
			(xy 333.06815 -309.860949) (xy 333.123587 -309.867049) (xy 333.177544 -309.881155) (xy 333.228873 -309.902967)
			(xy 333.276479 -309.932021) (xy 333.319347 -309.967696) (xy 333.356564 -310.009233) (xy 333.387337 -310.055746)
			(xy 333.411009 -310.106243) (xy 333.427077 -310.15965) (xy 333.435197 -310.214826) (xy 333.435706 -310.242712)
			(xy 333.68818 -310.242712) (xy 333.692251 -310.18709) (xy 333.704377 -310.132653) (xy 333.7243 -310.080562)
			(xy 333.751596 -310.031927) (xy 333.785682 -309.987784) (xy 333.825831 -309.949075) (xy 333.871189 -309.916624)
			(xy 333.920789 -309.891123) (xy 333.973573 -309.873116) (xy 334.028416 -309.862986) (xy 334.08415 -309.860949)
			(xy 334.139587 -309.867049) (xy 334.193544 -309.881155) (xy 334.244873 -309.902967) (xy 334.292479 -309.932021)
			(xy 334.335347 -309.967696) (xy 334.372564 -310.009233) (xy 334.403337 -310.055746) (xy 334.427009 -310.106243)
			(xy 334.443077 -310.15965) (xy 334.451197 -310.214826) (xy 334.451706 -310.242712) (xy 334.70418 -310.242712)
			(xy 334.708251 -310.18709) (xy 334.720377 -310.132653) (xy 334.7403 -310.080562) (xy 334.767596 -310.031927)
			(xy 334.801682 -309.987784) (xy 334.841831 -309.949075) (xy 334.887189 -309.916624) (xy 334.936789 -309.891123)
			(xy 334.989573 -309.873116) (xy 335.044416 -309.862986) (xy 335.10015 -309.860949) (xy 335.155587 -309.867049)
			(xy 335.209544 -309.881155) (xy 335.260873 -309.902967) (xy 335.308479 -309.932021) (xy 335.351347 -309.967696)
			(xy 335.388564 -310.009233) (xy 335.419337 -310.055746) (xy 335.443009 -310.106243) (xy 335.459077 -310.15965)
			(xy 335.467197 -310.214826) (xy 335.467706 -310.242712) (xy 335.72018 -310.242712) (xy 335.724251 -310.18709)
			(xy 335.736377 -310.132653) (xy 335.7563 -310.080562) (xy 335.783596 -310.031927) (xy 335.817682 -309.987784)
			(xy 335.857831 -309.949075) (xy 335.903189 -309.916624) (xy 335.952789 -309.891123) (xy 336.005573 -309.873116)
			(xy 336.060416 -309.862986) (xy 336.11615 -309.860949) (xy 336.171587 -309.867049) (xy 336.225544 -309.881155)
			(xy 336.276873 -309.902967) (xy 336.324479 -309.932021) (xy 336.367347 -309.967696) (xy 336.404564 -310.009233)
			(xy 336.435337 -310.055746) (xy 336.459009 -310.106243) (xy 336.475077 -310.15965) (xy 336.483197 -310.214826)
			(xy 336.483706 -310.242712) (xy 336.73618 -310.242712) (xy 336.740251 -310.18709) (xy 336.752377 -310.132653)
			(xy 336.7723 -310.080562) (xy 336.799596 -310.031927) (xy 336.833682 -309.987784) (xy 336.873831 -309.949075)
			(xy 336.919189 -309.916624) (xy 336.968789 -309.891123) (xy 337.021573 -309.873116) (xy 337.076416 -309.862986)
			(xy 337.13215 -309.860949) (xy 337.187587 -309.867049) (xy 337.241544 -309.881155) (xy 337.292873 -309.902967)
			(xy 337.340479 -309.932021) (xy 337.383347 -309.967696) (xy 337.420564 -310.009233) (xy 337.451337 -310.055746)
			(xy 337.475009 -310.106243) (xy 337.491077 -310.15965) (xy 337.499197 -310.214826) (xy 337.499706 -310.242712)
			(xy 337.75218 -310.242712) (xy 337.756251 -310.18709) (xy 337.768377 -310.132653) (xy 337.7883 -310.080562)
			(xy 337.815596 -310.031927) (xy 337.849682 -309.987784) (xy 337.889831 -309.949075) (xy 337.935189 -309.916624)
			(xy 337.984789 -309.891123) (xy 338.037573 -309.873116) (xy 338.092416 -309.862986) (xy 338.14815 -309.860949)
			(xy 338.203587 -309.867049) (xy 338.257544 -309.881155) (xy 338.308873 -309.902967) (xy 338.356479 -309.932021)
			(xy 338.399347 -309.967696) (xy 338.436564 -310.009233) (xy 338.467337 -310.055746) (xy 338.491009 -310.106243)
			(xy 338.507077 -310.15965) (xy 338.515197 -310.214826) (xy 338.515706 -310.242712) (xy 338.76818 -310.242712)
			(xy 338.772251 -310.18709) (xy 338.784377 -310.132653) (xy 338.8043 -310.080562) (xy 338.831596 -310.031927)
			(xy 338.865682 -309.987784) (xy 338.905831 -309.949075) (xy 338.951189 -309.916624) (xy 339.000789 -309.891123)
			(xy 339.053573 -309.873116) (xy 339.108416 -309.862986) (xy 339.16415 -309.860949) (xy 339.219587 -309.867049)
			(xy 339.273544 -309.881155) (xy 339.324873 -309.902967) (xy 339.372479 -309.932021) (xy 339.415347 -309.967696)
			(xy 339.452564 -310.009233) (xy 339.483337 -310.055746) (xy 339.507009 -310.106243) (xy 339.523077 -310.15965)
			(xy 339.531197 -310.214826) (xy 339.531706 -310.242712) (xy 339.78418 -310.242712) (xy 339.788251 -310.18709)
			(xy 339.800377 -310.132653) (xy 339.8203 -310.080562) (xy 339.847596 -310.031927) (xy 339.881682 -309.987784)
			(xy 339.921831 -309.949075) (xy 339.967189 -309.916624) (xy 340.016789 -309.891123) (xy 340.069573 -309.873116)
			(xy 340.124416 -309.862986) (xy 340.18015 -309.860949) (xy 340.235587 -309.867049) (xy 340.289544 -309.881155)
			(xy 340.340873 -309.902967) (xy 340.388479 -309.932021) (xy 340.431347 -309.967696) (xy 340.468564 -310.009233)
			(xy 340.499337 -310.055746) (xy 340.523009 -310.106243) (xy 340.539077 -310.15965) (xy 340.547197 -310.214826)
			(xy 340.547706 -310.242712) (xy 340.80018 -310.242712) (xy 340.804251 -310.18709) (xy 340.816377 -310.132653)
			(xy 340.8363 -310.080562) (xy 340.863596 -310.031927) (xy 340.897682 -309.987784) (xy 340.937831 -309.949075)
			(xy 340.983189 -309.916624) (xy 341.032789 -309.891123) (xy 341.085573 -309.873116) (xy 341.140416 -309.862986)
			(xy 341.19615 -309.860949) (xy 341.251587 -309.867049) (xy 341.305544 -309.881155) (xy 341.356873 -309.902967)
			(xy 341.404479 -309.932021) (xy 341.447347 -309.967696) (xy 341.484564 -310.009233) (xy 341.515337 -310.055746)
			(xy 341.539009 -310.106243) (xy 341.555077 -310.15965) (xy 341.563197 -310.214826) (xy 341.563706 -310.242712)
			(xy 341.81618 -310.242712) (xy 341.820251 -310.18709) (xy 341.832377 -310.132653) (xy 341.8523 -310.080562)
			(xy 341.879596 -310.031927) (xy 341.913682 -309.987784) (xy 341.953831 -309.949075) (xy 341.999189 -309.916624)
			(xy 342.048789 -309.891123) (xy 342.101573 -309.873116) (xy 342.156416 -309.862986) (xy 342.21215 -309.860949)
			(xy 342.267587 -309.867049) (xy 342.321544 -309.881155) (xy 342.372873 -309.902967) (xy 342.420479 -309.932021)
			(xy 342.463347 -309.967696) (xy 342.500564 -310.009233) (xy 342.531337 -310.055746) (xy 342.555009 -310.106243)
			(xy 342.571077 -310.15965) (xy 342.579197 -310.214826) (xy 342.579706 -310.242712) (xy 342.579197 -310.270598)
			(xy 342.571077 -310.325774) (xy 342.555009 -310.379181) (xy 342.531337 -310.429678) (xy 342.500564 -310.476191)
			(xy 342.463347 -310.517728) (xy 342.420479 -310.553403) (xy 342.372873 -310.582457) (xy 342.321544 -310.604269)
			(xy 342.267587 -310.618375) (xy 342.21215 -310.624475) (xy 342.156416 -310.622438) (xy 342.101573 -310.612308)
			(xy 342.048789 -310.594301) (xy 341.999189 -310.5688) (xy 341.953831 -310.536349) (xy 341.913682 -310.49764)
			(xy 341.879596 -310.453497) (xy 341.8523 -310.404862) (xy 341.832377 -310.352771) (xy 341.820251 -310.298334)
			(xy 341.81618 -310.242712) (xy 341.563706 -310.242712) (xy 341.563197 -310.270598) (xy 341.555077 -310.325774)
			(xy 341.539009 -310.379181) (xy 341.515337 -310.429678) (xy 341.484564 -310.476191) (xy 341.447347 -310.517728)
			(xy 341.404479 -310.553403) (xy 341.356873 -310.582457) (xy 341.305544 -310.604269) (xy 341.251587 -310.618375)
			(xy 341.19615 -310.624475) (xy 341.140416 -310.622438) (xy 341.085573 -310.612308) (xy 341.032789 -310.594301)
			(xy 340.983189 -310.5688) (xy 340.937831 -310.536349) (xy 340.897682 -310.49764) (xy 340.863596 -310.453497)
			(xy 340.8363 -310.404862) (xy 340.816377 -310.352771) (xy 340.804251 -310.298334) (xy 340.80018 -310.242712)
			(xy 340.547706 -310.242712) (xy 340.547197 -310.270598) (xy 340.539077 -310.325774) (xy 340.523009 -310.379181)
			(xy 340.499337 -310.429678) (xy 340.468564 -310.476191) (xy 340.431347 -310.517728) (xy 340.388479 -310.553403)
			(xy 340.340873 -310.582457) (xy 340.289544 -310.604269) (xy 340.235587 -310.618375) (xy 340.18015 -310.624475)
			(xy 340.124416 -310.622438) (xy 340.069573 -310.612308) (xy 340.016789 -310.594301) (xy 339.967189 -310.5688)
			(xy 339.921831 -310.536349) (xy 339.881682 -310.49764) (xy 339.847596 -310.453497) (xy 339.8203 -310.404862)
			(xy 339.800377 -310.352771) (xy 339.788251 -310.298334) (xy 339.78418 -310.242712) (xy 339.531706 -310.242712)
			(xy 339.531197 -310.270598) (xy 339.523077 -310.325774) (xy 339.507009 -310.379181) (xy 339.483337 -310.429678)
			(xy 339.452564 -310.476191) (xy 339.415347 -310.517728) (xy 339.372479 -310.553403) (xy 339.324873 -310.582457)
			(xy 339.273544 -310.604269) (xy 339.219587 -310.618375) (xy 339.16415 -310.624475) (xy 339.108416 -310.622438)
			(xy 339.053573 -310.612308) (xy 339.000789 -310.594301) (xy 338.951189 -310.5688) (xy 338.905831 -310.536349)
			(xy 338.865682 -310.49764) (xy 338.831596 -310.453497) (xy 338.8043 -310.404862) (xy 338.784377 -310.352771)
			(xy 338.772251 -310.298334) (xy 338.76818 -310.242712) (xy 338.515706 -310.242712) (xy 338.515197 -310.270598)
			(xy 338.507077 -310.325774) (xy 338.491009 -310.379181) (xy 338.467337 -310.429678) (xy 338.436564 -310.476191)
			(xy 338.399347 -310.517728) (xy 338.356479 -310.553403) (xy 338.308873 -310.582457) (xy 338.257544 -310.604269)
			(xy 338.203587 -310.618375) (xy 338.14815 -310.624475) (xy 338.092416 -310.622438) (xy 338.037573 -310.612308)
			(xy 337.984789 -310.594301) (xy 337.935189 -310.5688) (xy 337.889831 -310.536349) (xy 337.849682 -310.49764)
			(xy 337.815596 -310.453497) (xy 337.7883 -310.404862) (xy 337.768377 -310.352771) (xy 337.756251 -310.298334)
			(xy 337.75218 -310.242712) (xy 337.499706 -310.242712) (xy 337.499197 -310.270598) (xy 337.491077 -310.325774)
			(xy 337.475009 -310.379181) (xy 337.451337 -310.429678) (xy 337.420564 -310.476191) (xy 337.383347 -310.517728)
			(xy 337.340479 -310.553403) (xy 337.292873 -310.582457) (xy 337.241544 -310.604269) (xy 337.187587 -310.618375)
			(xy 337.13215 -310.624475) (xy 337.076416 -310.622438) (xy 337.021573 -310.612308) (xy 336.968789 -310.594301)
			(xy 336.919189 -310.5688) (xy 336.873831 -310.536349) (xy 336.833682 -310.49764) (xy 336.799596 -310.453497)
			(xy 336.7723 -310.404862) (xy 336.752377 -310.352771) (xy 336.740251 -310.298334) (xy 336.73618 -310.242712)
			(xy 336.483706 -310.242712) (xy 336.483197 -310.270598) (xy 336.475077 -310.325774) (xy 336.459009 -310.379181)
			(xy 336.435337 -310.429678) (xy 336.404564 -310.476191) (xy 336.367347 -310.517728) (xy 336.324479 -310.553403)
			(xy 336.276873 -310.582457) (xy 336.225544 -310.604269) (xy 336.171587 -310.618375) (xy 336.11615 -310.624475)
			(xy 336.060416 -310.622438) (xy 336.005573 -310.612308) (xy 335.952789 -310.594301) (xy 335.903189 -310.5688)
			(xy 335.857831 -310.536349) (xy 335.817682 -310.49764) (xy 335.783596 -310.453497) (xy 335.7563 -310.404862)
			(xy 335.736377 -310.352771) (xy 335.724251 -310.298334) (xy 335.72018 -310.242712) (xy 335.467706 -310.242712)
			(xy 335.467197 -310.270598) (xy 335.459077 -310.325774) (xy 335.443009 -310.379181) (xy 335.419337 -310.429678)
			(xy 335.388564 -310.476191) (xy 335.351347 -310.517728) (xy 335.308479 -310.553403) (xy 335.260873 -310.582457)
			(xy 335.209544 -310.604269) (xy 335.155587 -310.618375) (xy 335.10015 -310.624475) (xy 335.044416 -310.622438)
			(xy 334.989573 -310.612308) (xy 334.936789 -310.594301) (xy 334.887189 -310.5688) (xy 334.841831 -310.536349)
			(xy 334.801682 -310.49764) (xy 334.767596 -310.453497) (xy 334.7403 -310.404862) (xy 334.720377 -310.352771)
			(xy 334.708251 -310.298334) (xy 334.70418 -310.242712) (xy 334.451706 -310.242712) (xy 334.451197 -310.270598)
			(xy 334.443077 -310.325774) (xy 334.427009 -310.379181) (xy 334.403337 -310.429678) (xy 334.372564 -310.476191)
			(xy 334.335347 -310.517728) (xy 334.292479 -310.553403) (xy 334.244873 -310.582457) (xy 334.193544 -310.604269)
			(xy 334.139587 -310.618375) (xy 334.08415 -310.624475) (xy 334.028416 -310.622438) (xy 333.973573 -310.612308)
			(xy 333.920789 -310.594301) (xy 333.871189 -310.5688) (xy 333.825831 -310.536349) (xy 333.785682 -310.49764)
			(xy 333.751596 -310.453497) (xy 333.7243 -310.404862) (xy 333.704377 -310.352771) (xy 333.692251 -310.298334)
			(xy 333.68818 -310.242712) (xy 333.435706 -310.242712) (xy 333.435197 -310.270598) (xy 333.427077 -310.325774)
			(xy 333.411009 -310.379181) (xy 333.387337 -310.429678) (xy 333.356564 -310.476191) (xy 333.319347 -310.517728)
			(xy 333.276479 -310.553403) (xy 333.228873 -310.582457) (xy 333.177544 -310.604269) (xy 333.123587 -310.618375)
			(xy 333.06815 -310.624475) (xy 333.012416 -310.622438) (xy 332.957573 -310.612308) (xy 332.904789 -310.594301)
			(xy 332.855189 -310.5688) (xy 332.809831 -310.536349) (xy 332.769682 -310.49764) (xy 332.735596 -310.453497)
			(xy 332.7083 -310.404862) (xy 332.688377 -310.352771) (xy 332.676251 -310.298334) (xy 332.67218 -310.242712)
			(xy 327.384054 -310.242712) (xy 328.062937 -311.258712) (xy 332.67218 -311.258712) (xy 332.676251 -311.20309)
			(xy 332.688377 -311.148653) (xy 332.7083 -311.096562) (xy 332.735596 -311.047927) (xy 332.769682 -311.003784)
			(xy 332.809831 -310.965075) (xy 332.855189 -310.932624) (xy 332.904789 -310.907123) (xy 332.957573 -310.889116)
			(xy 333.012416 -310.878986) (xy 333.06815 -310.876949) (xy 333.123587 -310.883049) (xy 333.177544 -310.897155)
			(xy 333.228873 -310.918967) (xy 333.276479 -310.948021) (xy 333.319347 -310.983696) (xy 333.356564 -311.025233)
			(xy 333.387337 -311.071746) (xy 333.411009 -311.122243) (xy 333.427077 -311.17565) (xy 333.435197 -311.230826)
			(xy 333.435706 -311.258712) (xy 333.68818 -311.258712) (xy 333.692251 -311.20309) (xy 333.704377 -311.148653)
			(xy 333.7243 -311.096562) (xy 333.751596 -311.047927) (xy 333.785682 -311.003784) (xy 333.825831 -310.965075)
			(xy 333.871189 -310.932624) (xy 333.920789 -310.907123) (xy 333.973573 -310.889116) (xy 334.028416 -310.878986)
			(xy 334.08415 -310.876949) (xy 334.139587 -310.883049) (xy 334.193544 -310.897155) (xy 334.244873 -310.918967)
			(xy 334.292479 -310.948021) (xy 334.335347 -310.983696) (xy 334.372564 -311.025233) (xy 334.403337 -311.071746)
			(xy 334.427009 -311.122243) (xy 334.443077 -311.17565) (xy 334.451197 -311.230826) (xy 334.451706 -311.258712)
			(xy 334.70418 -311.258712) (xy 334.708251 -311.20309) (xy 334.720377 -311.148653) (xy 334.7403 -311.096562)
			(xy 334.767596 -311.047927) (xy 334.801682 -311.003784) (xy 334.841831 -310.965075) (xy 334.887189 -310.932624)
			(xy 334.936789 -310.907123) (xy 334.989573 -310.889116) (xy 335.044416 -310.878986) (xy 335.10015 -310.876949)
			(xy 335.155587 -310.883049) (xy 335.209544 -310.897155) (xy 335.260873 -310.918967) (xy 335.308479 -310.948021)
			(xy 335.351347 -310.983696) (xy 335.388564 -311.025233) (xy 335.419337 -311.071746) (xy 335.443009 -311.122243)
			(xy 335.459077 -311.17565) (xy 335.467197 -311.230826) (xy 335.467706 -311.258712) (xy 335.72018 -311.258712)
			(xy 335.724251 -311.20309) (xy 335.736377 -311.148653) (xy 335.7563 -311.096562) (xy 335.783596 -311.047927)
			(xy 335.817682 -311.003784) (xy 335.857831 -310.965075) (xy 335.903189 -310.932624) (xy 335.952789 -310.907123)
			(xy 336.005573 -310.889116) (xy 336.060416 -310.878986) (xy 336.11615 -310.876949) (xy 336.171587 -310.883049)
			(xy 336.225544 -310.897155) (xy 336.276873 -310.918967) (xy 336.324479 -310.948021) (xy 336.367347 -310.983696)
			(xy 336.404564 -311.025233) (xy 336.435337 -311.071746) (xy 336.459009 -311.122243) (xy 336.475077 -311.17565)
			(xy 336.483197 -311.230826) (xy 336.483706 -311.258712) (xy 336.73618 -311.258712) (xy 336.740251 -311.20309)
			(xy 336.752377 -311.148653) (xy 336.7723 -311.096562) (xy 336.799596 -311.047927) (xy 336.833682 -311.003784)
			(xy 336.873831 -310.965075) (xy 336.919189 -310.932624) (xy 336.968789 -310.907123) (xy 337.021573 -310.889116)
			(xy 337.076416 -310.878986) (xy 337.13215 -310.876949) (xy 337.187587 -310.883049) (xy 337.241544 -310.897155)
			(xy 337.292873 -310.918967) (xy 337.340479 -310.948021) (xy 337.383347 -310.983696) (xy 337.420564 -311.025233)
			(xy 337.451337 -311.071746) (xy 337.475009 -311.122243) (xy 337.491077 -311.17565) (xy 337.499197 -311.230826)
			(xy 337.499706 -311.258712) (xy 337.75218 -311.258712) (xy 337.756251 -311.20309) (xy 337.768377 -311.148653)
			(xy 337.7883 -311.096562) (xy 337.815596 -311.047927) (xy 337.849682 -311.003784) (xy 337.889831 -310.965075)
			(xy 337.935189 -310.932624) (xy 337.984789 -310.907123) (xy 338.037573 -310.889116) (xy 338.092416 -310.878986)
			(xy 338.14815 -310.876949) (xy 338.203587 -310.883049) (xy 338.257544 -310.897155) (xy 338.308873 -310.918967)
			(xy 338.356479 -310.948021) (xy 338.399347 -310.983696) (xy 338.436564 -311.025233) (xy 338.467337 -311.071746)
			(xy 338.491009 -311.122243) (xy 338.507077 -311.17565) (xy 338.515197 -311.230826) (xy 338.515706 -311.258712)
			(xy 338.76818 -311.258712) (xy 338.772251 -311.20309) (xy 338.784377 -311.148653) (xy 338.8043 -311.096562)
			(xy 338.831596 -311.047927) (xy 338.865682 -311.003784) (xy 338.905831 -310.965075) (xy 338.951189 -310.932624)
			(xy 339.000789 -310.907123) (xy 339.053573 -310.889116) (xy 339.108416 -310.878986) (xy 339.16415 -310.876949)
			(xy 339.219587 -310.883049) (xy 339.273544 -310.897155) (xy 339.324873 -310.918967) (xy 339.372479 -310.948021)
			(xy 339.415347 -310.983696) (xy 339.452564 -311.025233) (xy 339.483337 -311.071746) (xy 339.507009 -311.122243)
			(xy 339.523077 -311.17565) (xy 339.531197 -311.230826) (xy 339.531706 -311.258712) (xy 339.78418 -311.258712)
			(xy 339.788251 -311.20309) (xy 339.800377 -311.148653) (xy 339.8203 -311.096562) (xy 339.847596 -311.047927)
			(xy 339.881682 -311.003784) (xy 339.921831 -310.965075) (xy 339.967189 -310.932624) (xy 340.016789 -310.907123)
			(xy 340.069573 -310.889116) (xy 340.124416 -310.878986) (xy 340.18015 -310.876949) (xy 340.235587 -310.883049)
			(xy 340.289544 -310.897155) (xy 340.340873 -310.918967) (xy 340.388479 -310.948021) (xy 340.431347 -310.983696)
			(xy 340.468564 -311.025233) (xy 340.499337 -311.071746) (xy 340.523009 -311.122243) (xy 340.539077 -311.17565)
			(xy 340.547197 -311.230826) (xy 340.547706 -311.258712) (xy 340.547197 -311.286598) (xy 340.539077 -311.341774)
			(xy 340.523009 -311.395181) (xy 340.499337 -311.445678) (xy 340.468564 -311.492191) (xy 340.431347 -311.533728)
			(xy 340.388479 -311.569403) (xy 340.340873 -311.598457) (xy 340.289544 -311.620269) (xy 340.235587 -311.634375)
			(xy 340.18015 -311.640475) (xy 340.124416 -311.638438) (xy 340.069573 -311.628308) (xy 340.016789 -311.610301)
			(xy 339.967189 -311.5848) (xy 339.921831 -311.552349) (xy 339.881682 -311.51364) (xy 339.847596 -311.469497)
			(xy 339.8203 -311.420862) (xy 339.800377 -311.368771) (xy 339.788251 -311.314334) (xy 339.78418 -311.258712)
			(xy 339.531706 -311.258712) (xy 339.531197 -311.286598) (xy 339.523077 -311.341774) (xy 339.507009 -311.395181)
			(xy 339.483337 -311.445678) (xy 339.452564 -311.492191) (xy 339.415347 -311.533728) (xy 339.372479 -311.569403)
			(xy 339.324873 -311.598457) (xy 339.273544 -311.620269) (xy 339.219587 -311.634375) (xy 339.16415 -311.640475)
			(xy 339.108416 -311.638438) (xy 339.053573 -311.628308) (xy 339.000789 -311.610301) (xy 338.951189 -311.5848)
			(xy 338.905831 -311.552349) (xy 338.865682 -311.51364) (xy 338.831596 -311.469497) (xy 338.8043 -311.420862)
			(xy 338.784377 -311.368771) (xy 338.772251 -311.314334) (xy 338.76818 -311.258712) (xy 338.515706 -311.258712)
			(xy 338.515197 -311.286598) (xy 338.507077 -311.341774) (xy 338.491009 -311.395181) (xy 338.467337 -311.445678)
			(xy 338.436564 -311.492191) (xy 338.399347 -311.533728) (xy 338.356479 -311.569403) (xy 338.308873 -311.598457)
			(xy 338.257544 -311.620269) (xy 338.203587 -311.634375) (xy 338.14815 -311.640475) (xy 338.092416 -311.638438)
			(xy 338.037573 -311.628308) (xy 337.984789 -311.610301) (xy 337.935189 -311.5848) (xy 337.889831 -311.552349)
			(xy 337.849682 -311.51364) (xy 337.815596 -311.469497) (xy 337.7883 -311.420862) (xy 337.768377 -311.368771)
			(xy 337.756251 -311.314334) (xy 337.75218 -311.258712) (xy 337.499706 -311.258712) (xy 337.499197 -311.286598)
			(xy 337.491077 -311.341774) (xy 337.475009 -311.395181) (xy 337.451337 -311.445678) (xy 337.420564 -311.492191)
			(xy 337.383347 -311.533728) (xy 337.340479 -311.569403) (xy 337.292873 -311.598457) (xy 337.241544 -311.620269)
			(xy 337.187587 -311.634375) (xy 337.13215 -311.640475) (xy 337.076416 -311.638438) (xy 337.021573 -311.628308)
			(xy 336.968789 -311.610301) (xy 336.919189 -311.5848) (xy 336.873831 -311.552349) (xy 336.833682 -311.51364)
			(xy 336.799596 -311.469497) (xy 336.7723 -311.420862) (xy 336.752377 -311.368771) (xy 336.740251 -311.314334)
			(xy 336.73618 -311.258712) (xy 336.483706 -311.258712) (xy 336.483197 -311.286598) (xy 336.475077 -311.341774)
			(xy 336.459009 -311.395181) (xy 336.435337 -311.445678) (xy 336.404564 -311.492191) (xy 336.367347 -311.533728)
			(xy 336.324479 -311.569403) (xy 336.276873 -311.598457) (xy 336.225544 -311.620269) (xy 336.171587 -311.634375)
			(xy 336.11615 -311.640475) (xy 336.060416 -311.638438) (xy 336.005573 -311.628308) (xy 335.952789 -311.610301)
			(xy 335.903189 -311.5848) (xy 335.857831 -311.552349) (xy 335.817682 -311.51364) (xy 335.783596 -311.469497)
			(xy 335.7563 -311.420862) (xy 335.736377 -311.368771) (xy 335.724251 -311.314334) (xy 335.72018 -311.258712)
			(xy 335.467706 -311.258712) (xy 335.467197 -311.286598) (xy 335.459077 -311.341774) (xy 335.443009 -311.395181)
			(xy 335.419337 -311.445678) (xy 335.388564 -311.492191) (xy 335.351347 -311.533728) (xy 335.308479 -311.569403)
			(xy 335.260873 -311.598457) (xy 335.209544 -311.620269) (xy 335.155587 -311.634375) (xy 335.10015 -311.640475)
			(xy 335.044416 -311.638438) (xy 334.989573 -311.628308) (xy 334.936789 -311.610301) (xy 334.887189 -311.5848)
			(xy 334.841831 -311.552349) (xy 334.801682 -311.51364) (xy 334.767596 -311.469497) (xy 334.7403 -311.420862)
			(xy 334.720377 -311.368771) (xy 334.708251 -311.314334) (xy 334.70418 -311.258712) (xy 334.451706 -311.258712)
			(xy 334.451197 -311.286598) (xy 334.443077 -311.341774) (xy 334.427009 -311.395181) (xy 334.403337 -311.445678)
			(xy 334.372564 -311.492191) (xy 334.335347 -311.533728) (xy 334.292479 -311.569403) (xy 334.244873 -311.598457)
			(xy 334.193544 -311.620269) (xy 334.139587 -311.634375) (xy 334.08415 -311.640475) (xy 334.028416 -311.638438)
			(xy 333.973573 -311.628308) (xy 333.920789 -311.610301) (xy 333.871189 -311.5848) (xy 333.825831 -311.552349)
			(xy 333.785682 -311.51364) (xy 333.751596 -311.469497) (xy 333.7243 -311.420862) (xy 333.704377 -311.368771)
			(xy 333.692251 -311.314334) (xy 333.68818 -311.258712) (xy 333.435706 -311.258712) (xy 333.435197 -311.286598)
			(xy 333.427077 -311.341774) (xy 333.411009 -311.395181) (xy 333.387337 -311.445678) (xy 333.356564 -311.492191)
			(xy 333.319347 -311.533728) (xy 333.276479 -311.569403) (xy 333.228873 -311.598457) (xy 333.177544 -311.620269)
			(xy 333.123587 -311.634375) (xy 333.06815 -311.640475) (xy 333.012416 -311.638438) (xy 332.957573 -311.628308)
			(xy 332.904789 -311.610301) (xy 332.855189 -311.5848) (xy 332.809831 -311.552349) (xy 332.769682 -311.51364)
			(xy 332.735596 -311.469497) (xy 332.7083 -311.420862) (xy 332.688377 -311.368771) (xy 332.676251 -311.314334)
			(xy 332.67218 -311.258712) (xy 328.062937 -311.258712) (xy 328.741819 -312.274712) (xy 332.67218 -312.274712)
			(xy 332.676251 -312.21909) (xy 332.688377 -312.164653) (xy 332.7083 -312.112562) (xy 332.735596 -312.063927)
			(xy 332.769682 -312.019784) (xy 332.809831 -311.981075) (xy 332.855189 -311.948624) (xy 332.904789 -311.923123)
			(xy 332.957573 -311.905116) (xy 333.012416 -311.894986) (xy 333.06815 -311.892949) (xy 333.123587 -311.899049)
			(xy 333.177544 -311.913155) (xy 333.228873 -311.934967) (xy 333.276479 -311.964021) (xy 333.319347 -311.999696)
			(xy 333.356564 -312.041233) (xy 333.387337 -312.087746) (xy 333.411009 -312.138243) (xy 333.427077 -312.19165)
			(xy 333.435197 -312.246826) (xy 333.435706 -312.274712) (xy 333.68818 -312.274712) (xy 333.692251 -312.21909)
			(xy 333.704377 -312.164653) (xy 333.7243 -312.112562) (xy 333.751596 -312.063927) (xy 333.785682 -312.019784)
			(xy 333.825831 -311.981075) (xy 333.871189 -311.948624) (xy 333.920789 -311.923123) (xy 333.973573 -311.905116)
			(xy 334.028416 -311.894986) (xy 334.08415 -311.892949) (xy 334.139587 -311.899049) (xy 334.193544 -311.913155)
			(xy 334.244873 -311.934967) (xy 334.292479 -311.964021) (xy 334.335347 -311.999696) (xy 334.372564 -312.041233)
			(xy 334.403337 -312.087746) (xy 334.427009 -312.138243) (xy 334.443077 -312.19165) (xy 334.451197 -312.246826)
			(xy 334.451706 -312.274712) (xy 334.70418 -312.274712) (xy 334.708251 -312.21909) (xy 334.720377 -312.164653)
			(xy 334.7403 -312.112562) (xy 334.767596 -312.063927) (xy 334.801682 -312.019784) (xy 334.841831 -311.981075)
			(xy 334.887189 -311.948624) (xy 334.936789 -311.923123) (xy 334.989573 -311.905116) (xy 335.044416 -311.894986)
			(xy 335.10015 -311.892949) (xy 335.155587 -311.899049) (xy 335.209544 -311.913155) (xy 335.260873 -311.934967)
			(xy 335.308479 -311.964021) (xy 335.351347 -311.999696) (xy 335.388564 -312.041233) (xy 335.419337 -312.087746)
			(xy 335.443009 -312.138243) (xy 335.459077 -312.19165) (xy 335.467197 -312.246826) (xy 335.467706 -312.274712)
			(xy 335.72018 -312.274712) (xy 335.724251 -312.21909) (xy 335.736377 -312.164653) (xy 335.7563 -312.112562)
			(xy 335.783596 -312.063927) (xy 335.817682 -312.019784) (xy 335.857831 -311.981075) (xy 335.903189 -311.948624)
			(xy 335.952789 -311.923123) (xy 336.005573 -311.905116) (xy 336.060416 -311.894986) (xy 336.11615 -311.892949)
			(xy 336.171587 -311.899049) (xy 336.225544 -311.913155) (xy 336.276873 -311.934967) (xy 336.324479 -311.964021)
			(xy 336.367347 -311.999696) (xy 336.404564 -312.041233) (xy 336.435337 -312.087746) (xy 336.459009 -312.138243)
			(xy 336.475077 -312.19165) (xy 336.483197 -312.246826) (xy 336.483706 -312.274712) (xy 336.73618 -312.274712)
			(xy 336.740251 -312.21909) (xy 336.752377 -312.164653) (xy 336.7723 -312.112562) (xy 336.799596 -312.063927)
			(xy 336.833682 -312.019784) (xy 336.873831 -311.981075) (xy 336.919189 -311.948624) (xy 336.968789 -311.923123)
			(xy 337.021573 -311.905116) (xy 337.076416 -311.894986) (xy 337.13215 -311.892949) (xy 337.187587 -311.899049)
			(xy 337.241544 -311.913155) (xy 337.292873 -311.934967) (xy 337.340479 -311.964021) (xy 337.383347 -311.999696)
			(xy 337.420564 -312.041233) (xy 337.451337 -312.087746) (xy 337.475009 -312.138243) (xy 337.491077 -312.19165)
			(xy 337.499197 -312.246826) (xy 337.499706 -312.274712) (xy 337.75218 -312.274712) (xy 337.756251 -312.21909)
			(xy 337.768377 -312.164653) (xy 337.7883 -312.112562) (xy 337.815596 -312.063927) (xy 337.849682 -312.019784)
			(xy 337.889831 -311.981075) (xy 337.935189 -311.948624) (xy 337.984789 -311.923123) (xy 338.037573 -311.905116)
			(xy 338.092416 -311.894986) (xy 338.14815 -311.892949) (xy 338.203587 -311.899049) (xy 338.257544 -311.913155)
			(xy 338.308873 -311.934967) (xy 338.356479 -311.964021) (xy 338.399347 -311.999696) (xy 338.436564 -312.041233)
			(xy 338.467337 -312.087746) (xy 338.491009 -312.138243) (xy 338.507077 -312.19165) (xy 338.515197 -312.246826)
			(xy 338.515706 -312.274712) (xy 338.76818 -312.274712) (xy 338.772251 -312.21909) (xy 338.784377 -312.164653)
			(xy 338.8043 -312.112562) (xy 338.831596 -312.063927) (xy 338.865682 -312.019784) (xy 338.905831 -311.981075)
			(xy 338.951189 -311.948624) (xy 339.000789 -311.923123) (xy 339.053573 -311.905116) (xy 339.108416 -311.894986)
			(xy 339.16415 -311.892949) (xy 339.219587 -311.899049) (xy 339.273544 -311.913155) (xy 339.324873 -311.934967)
			(xy 339.372479 -311.964021) (xy 339.415347 -311.999696) (xy 339.452564 -312.041233) (xy 339.483337 -312.087746)
			(xy 339.507009 -312.138243) (xy 339.523077 -312.19165) (xy 339.531197 -312.246826) (xy 339.531706 -312.274712)
			(xy 339.78418 -312.274712) (xy 339.788251 -312.21909) (xy 339.800377 -312.164653) (xy 339.8203 -312.112562)
			(xy 339.847596 -312.063927) (xy 339.881682 -312.019784) (xy 339.921831 -311.981075) (xy 339.967189 -311.948624)
			(xy 340.016789 -311.923123) (xy 340.069573 -311.905116) (xy 340.124416 -311.894986) (xy 340.18015 -311.892949)
			(xy 340.235587 -311.899049) (xy 340.289544 -311.913155) (xy 340.340873 -311.934967) (xy 340.388479 -311.964021)
			(xy 340.431347 -311.999696) (xy 340.468564 -312.041233) (xy 340.499337 -312.087746) (xy 340.523009 -312.138243)
			(xy 340.539077 -312.19165) (xy 340.547197 -312.246826) (xy 340.547706 -312.274712) (xy 340.80018 -312.274712)
			(xy 340.804251 -312.21909) (xy 340.816377 -312.164653) (xy 340.8363 -312.112562) (xy 340.863596 -312.063927)
			(xy 340.897682 -312.019784) (xy 340.937831 -311.981075) (xy 340.983189 -311.948624) (xy 341.032789 -311.923123)
			(xy 341.085573 -311.905116) (xy 341.140416 -311.894986) (xy 341.19615 -311.892949) (xy 341.251587 -311.899049)
			(xy 341.305544 -311.913155) (xy 341.356873 -311.934967) (xy 341.404479 -311.964021) (xy 341.447347 -311.999696)
			(xy 341.484564 -312.041233) (xy 341.515337 -312.087746) (xy 341.539009 -312.138243) (xy 341.555077 -312.19165)
			(xy 341.563197 -312.246826) (xy 341.563706 -312.274712) (xy 341.81618 -312.274712) (xy 341.820251 -312.21909)
			(xy 341.832377 -312.164653) (xy 341.8523 -312.112562) (xy 341.879596 -312.063927) (xy 341.913682 -312.019784)
			(xy 341.953831 -311.981075) (xy 341.999189 -311.948624) (xy 342.048789 -311.923123) (xy 342.101573 -311.905116)
			(xy 342.156416 -311.894986) (xy 342.21215 -311.892949) (xy 342.267587 -311.899049) (xy 342.321544 -311.913155)
			(xy 342.372873 -311.934967) (xy 342.420479 -311.964021) (xy 342.463347 -311.999696) (xy 342.500564 -312.041233)
			(xy 342.531337 -312.087746) (xy 342.555009 -312.138243) (xy 342.571077 -312.19165) (xy 342.579197 -312.246826)
			(xy 342.579706 -312.274712) (xy 342.579197 -312.302598) (xy 342.571077 -312.357774) (xy 342.555009 -312.411181)
			(xy 342.531337 -312.461678) (xy 342.500564 -312.508191) (xy 342.463347 -312.549728) (xy 342.420479 -312.585403)
			(xy 342.372873 -312.614457) (xy 342.321544 -312.636269) (xy 342.267587 -312.650375) (xy 342.21215 -312.656475)
			(xy 342.156416 -312.654438) (xy 342.101573 -312.644308) (xy 342.048789 -312.626301) (xy 341.999189 -312.6008)
			(xy 341.953831 -312.568349) (xy 341.913682 -312.52964) (xy 341.879596 -312.485497) (xy 341.8523 -312.436862)
			(xy 341.832377 -312.384771) (xy 341.820251 -312.330334) (xy 341.81618 -312.274712) (xy 341.563706 -312.274712)
			(xy 341.563197 -312.302598) (xy 341.555077 -312.357774) (xy 341.539009 -312.411181) (xy 341.515337 -312.461678)
			(xy 341.484564 -312.508191) (xy 341.447347 -312.549728) (xy 341.404479 -312.585403) (xy 341.356873 -312.614457)
			(xy 341.305544 -312.636269) (xy 341.251587 -312.650375) (xy 341.19615 -312.656475) (xy 341.140416 -312.654438)
			(xy 341.085573 -312.644308) (xy 341.032789 -312.626301) (xy 340.983189 -312.6008) (xy 340.937831 -312.568349)
			(xy 340.897682 -312.52964) (xy 340.863596 -312.485497) (xy 340.8363 -312.436862) (xy 340.816377 -312.384771)
			(xy 340.804251 -312.330334) (xy 340.80018 -312.274712) (xy 340.547706 -312.274712) (xy 340.547197 -312.302598)
			(xy 340.539077 -312.357774) (xy 340.523009 -312.411181) (xy 340.499337 -312.461678) (xy 340.468564 -312.508191)
			(xy 340.431347 -312.549728) (xy 340.388479 -312.585403) (xy 340.340873 -312.614457) (xy 340.289544 -312.636269)
			(xy 340.235587 -312.650375) (xy 340.18015 -312.656475) (xy 340.124416 -312.654438) (xy 340.069573 -312.644308)
			(xy 340.016789 -312.626301) (xy 339.967189 -312.6008) (xy 339.921831 -312.568349) (xy 339.881682 -312.52964)
			(xy 339.847596 -312.485497) (xy 339.8203 -312.436862) (xy 339.800377 -312.384771) (xy 339.788251 -312.330334)
			(xy 339.78418 -312.274712) (xy 339.531706 -312.274712) (xy 339.531197 -312.302598) (xy 339.523077 -312.357774)
			(xy 339.507009 -312.411181) (xy 339.483337 -312.461678) (xy 339.452564 -312.508191) (xy 339.415347 -312.549728)
			(xy 339.372479 -312.585403) (xy 339.324873 -312.614457) (xy 339.273544 -312.636269) (xy 339.219587 -312.650375)
			(xy 339.16415 -312.656475) (xy 339.108416 -312.654438) (xy 339.053573 -312.644308) (xy 339.000789 -312.626301)
			(xy 338.951189 -312.6008) (xy 338.905831 -312.568349) (xy 338.865682 -312.52964) (xy 338.831596 -312.485497)
			(xy 338.8043 -312.436862) (xy 338.784377 -312.384771) (xy 338.772251 -312.330334) (xy 338.76818 -312.274712)
			(xy 338.515706 -312.274712) (xy 338.515197 -312.302598) (xy 338.507077 -312.357774) (xy 338.491009 -312.411181)
			(xy 338.467337 -312.461678) (xy 338.436564 -312.508191) (xy 338.399347 -312.549728) (xy 338.356479 -312.585403)
			(xy 338.308873 -312.614457) (xy 338.257544 -312.636269) (xy 338.203587 -312.650375) (xy 338.14815 -312.656475)
			(xy 338.092416 -312.654438) (xy 338.037573 -312.644308) (xy 337.984789 -312.626301) (xy 337.935189 -312.6008)
			(xy 337.889831 -312.568349) (xy 337.849682 -312.52964) (xy 337.815596 -312.485497) (xy 337.7883 -312.436862)
			(xy 337.768377 -312.384771) (xy 337.756251 -312.330334) (xy 337.75218 -312.274712) (xy 337.499706 -312.274712)
			(xy 337.499197 -312.302598) (xy 337.491077 -312.357774) (xy 337.475009 -312.411181) (xy 337.451337 -312.461678)
			(xy 337.420564 -312.508191) (xy 337.383347 -312.549728) (xy 337.340479 -312.585403) (xy 337.292873 -312.614457)
			(xy 337.241544 -312.636269) (xy 337.187587 -312.650375) (xy 337.13215 -312.656475) (xy 337.076416 -312.654438)
			(xy 337.021573 -312.644308) (xy 336.968789 -312.626301) (xy 336.919189 -312.6008) (xy 336.873831 -312.568349)
			(xy 336.833682 -312.52964) (xy 336.799596 -312.485497) (xy 336.7723 -312.436862) (xy 336.752377 -312.384771)
			(xy 336.740251 -312.330334) (xy 336.73618 -312.274712) (xy 336.483706 -312.274712) (xy 336.483197 -312.302598)
			(xy 336.475077 -312.357774) (xy 336.459009 -312.411181) (xy 336.435337 -312.461678) (xy 336.404564 -312.508191)
			(xy 336.367347 -312.549728) (xy 336.324479 -312.585403) (xy 336.276873 -312.614457) (xy 336.225544 -312.636269)
			(xy 336.171587 -312.650375) (xy 336.11615 -312.656475) (xy 336.060416 -312.654438) (xy 336.005573 -312.644308)
			(xy 335.952789 -312.626301) (xy 335.903189 -312.6008) (xy 335.857831 -312.568349) (xy 335.817682 -312.52964)
			(xy 335.783596 -312.485497) (xy 335.7563 -312.436862) (xy 335.736377 -312.384771) (xy 335.724251 -312.330334)
			(xy 335.72018 -312.274712) (xy 335.467706 -312.274712) (xy 335.467197 -312.302598) (xy 335.459077 -312.357774)
			(xy 335.443009 -312.411181) (xy 335.419337 -312.461678) (xy 335.388564 -312.508191) (xy 335.351347 -312.549728)
			(xy 335.308479 -312.585403) (xy 335.260873 -312.614457) (xy 335.209544 -312.636269) (xy 335.155587 -312.650375)
			(xy 335.10015 -312.656475) (xy 335.044416 -312.654438) (xy 334.989573 -312.644308) (xy 334.936789 -312.626301)
			(xy 334.887189 -312.6008) (xy 334.841831 -312.568349) (xy 334.801682 -312.52964) (xy 334.767596 -312.485497)
			(xy 334.7403 -312.436862) (xy 334.720377 -312.384771) (xy 334.708251 -312.330334) (xy 334.70418 -312.274712)
			(xy 334.451706 -312.274712) (xy 334.451197 -312.302598) (xy 334.443077 -312.357774) (xy 334.427009 -312.411181)
			(xy 334.403337 -312.461678) (xy 334.372564 -312.508191) (xy 334.335347 -312.549728) (xy 334.292479 -312.585403)
			(xy 334.244873 -312.614457) (xy 334.193544 -312.636269) (xy 334.139587 -312.650375) (xy 334.08415 -312.656475)
			(xy 334.028416 -312.654438) (xy 333.973573 -312.644308) (xy 333.920789 -312.626301) (xy 333.871189 -312.6008)
			(xy 333.825831 -312.568349) (xy 333.785682 -312.52964) (xy 333.751596 -312.485497) (xy 333.7243 -312.436862)
			(xy 333.704377 -312.384771) (xy 333.692251 -312.330334) (xy 333.68818 -312.274712) (xy 333.435706 -312.274712)
			(xy 333.435197 -312.302598) (xy 333.427077 -312.357774) (xy 333.411009 -312.411181) (xy 333.387337 -312.461678)
			(xy 333.356564 -312.508191) (xy 333.319347 -312.549728) (xy 333.276479 -312.585403) (xy 333.228873 -312.614457)
			(xy 333.177544 -312.636269) (xy 333.123587 -312.650375) (xy 333.06815 -312.656475) (xy 333.012416 -312.654438)
			(xy 332.957573 -312.644308) (xy 332.904789 -312.626301) (xy 332.855189 -312.6008) (xy 332.809831 -312.568349)
			(xy 332.769682 -312.52964) (xy 332.735596 -312.485497) (xy 332.7083 -312.436862) (xy 332.688377 -312.384771)
			(xy 332.676251 -312.330334) (xy 332.67218 -312.274712) (xy 328.741819 -312.274712) (xy 329.420701 -313.290712)
			(xy 332.67218 -313.290712) (xy 332.676251 -313.23509) (xy 332.688377 -313.180653) (xy 332.7083 -313.128562)
			(xy 332.735596 -313.079927) (xy 332.769682 -313.035784) (xy 332.809831 -312.997075) (xy 332.855189 -312.964624)
			(xy 332.904789 -312.939123) (xy 332.957573 -312.921116) (xy 333.012416 -312.910986) (xy 333.06815 -312.908949)
			(xy 333.123587 -312.915049) (xy 333.177544 -312.929155) (xy 333.228873 -312.950967) (xy 333.276479 -312.980021)
			(xy 333.319347 -313.015696) (xy 333.356564 -313.057233) (xy 333.387337 -313.103746) (xy 333.411009 -313.154243)
			(xy 333.427077 -313.20765) (xy 333.435197 -313.262826) (xy 333.435706 -313.290712) (xy 333.68818 -313.290712)
			(xy 333.692251 -313.23509) (xy 333.704377 -313.180653) (xy 333.7243 -313.128562) (xy 333.751596 -313.079927)
			(xy 333.785682 -313.035784) (xy 333.825831 -312.997075) (xy 333.871189 -312.964624) (xy 333.920789 -312.939123)
			(xy 333.973573 -312.921116) (xy 334.028416 -312.910986) (xy 334.08415 -312.908949) (xy 334.139587 -312.915049)
			(xy 334.193544 -312.929155) (xy 334.244873 -312.950967) (xy 334.292479 -312.980021) (xy 334.335347 -313.015696)
			(xy 334.372564 -313.057233) (xy 334.403337 -313.103746) (xy 334.427009 -313.154243) (xy 334.443077 -313.20765)
			(xy 334.451197 -313.262826) (xy 334.451706 -313.290712) (xy 334.70418 -313.290712) (xy 334.708251 -313.23509)
			(xy 334.720377 -313.180653) (xy 334.7403 -313.128562) (xy 334.767596 -313.079927) (xy 334.801682 -313.035784)
			(xy 334.841831 -312.997075) (xy 334.887189 -312.964624) (xy 334.936789 -312.939123) (xy 334.989573 -312.921116)
			(xy 335.044416 -312.910986) (xy 335.10015 -312.908949) (xy 335.155587 -312.915049) (xy 335.209544 -312.929155)
			(xy 335.260873 -312.950967) (xy 335.308479 -312.980021) (xy 335.351347 -313.015696) (xy 335.388564 -313.057233)
			(xy 335.419337 -313.103746) (xy 335.443009 -313.154243) (xy 335.459077 -313.20765) (xy 335.467197 -313.262826)
			(xy 335.467706 -313.290712) (xy 335.72018 -313.290712) (xy 335.724251 -313.23509) (xy 335.736377 -313.180653)
			(xy 335.7563 -313.128562) (xy 335.783596 -313.079927) (xy 335.817682 -313.035784) (xy 335.857831 -312.997075)
			(xy 335.903189 -312.964624) (xy 335.952789 -312.939123) (xy 336.005573 -312.921116) (xy 336.060416 -312.910986)
			(xy 336.11615 -312.908949) (xy 336.171587 -312.915049) (xy 336.225544 -312.929155) (xy 336.276873 -312.950967)
			(xy 336.324479 -312.980021) (xy 336.367347 -313.015696) (xy 336.404564 -313.057233) (xy 336.435337 -313.103746)
			(xy 336.459009 -313.154243) (xy 336.475077 -313.20765) (xy 336.483197 -313.262826) (xy 336.483706 -313.290712)
			(xy 336.73618 -313.290712) (xy 336.740251 -313.23509) (xy 336.752377 -313.180653) (xy 336.7723 -313.128562)
			(xy 336.799596 -313.079927) (xy 336.833682 -313.035784) (xy 336.873831 -312.997075) (xy 336.919189 -312.964624)
			(xy 336.968789 -312.939123) (xy 337.021573 -312.921116) (xy 337.076416 -312.910986) (xy 337.13215 -312.908949)
			(xy 337.187587 -312.915049) (xy 337.241544 -312.929155) (xy 337.292873 -312.950967) (xy 337.340479 -312.980021)
			(xy 337.383347 -313.015696) (xy 337.420564 -313.057233) (xy 337.451337 -313.103746) (xy 337.475009 -313.154243)
			(xy 337.491077 -313.20765) (xy 337.499197 -313.262826) (xy 337.499706 -313.290712) (xy 337.75218 -313.290712)
			(xy 337.756251 -313.23509) (xy 337.768377 -313.180653) (xy 337.7883 -313.128562) (xy 337.815596 -313.079927)
			(xy 337.849682 -313.035784) (xy 337.889831 -312.997075) (xy 337.935189 -312.964624) (xy 337.984789 -312.939123)
			(xy 338.037573 -312.921116) (xy 338.092416 -312.910986) (xy 338.14815 -312.908949) (xy 338.203587 -312.915049)
			(xy 338.257544 -312.929155) (xy 338.308873 -312.950967) (xy 338.356479 -312.980021) (xy 338.399347 -313.015696)
			(xy 338.436564 -313.057233) (xy 338.467337 -313.103746) (xy 338.491009 -313.154243) (xy 338.507077 -313.20765)
			(xy 338.515197 -313.262826) (xy 338.515706 -313.290712) (xy 338.76818 -313.290712) (xy 338.772251 -313.23509)
			(xy 338.784377 -313.180653) (xy 338.8043 -313.128562) (xy 338.831596 -313.079927) (xy 338.865682 -313.035784)
			(xy 338.905831 -312.997075) (xy 338.951189 -312.964624) (xy 339.000789 -312.939123) (xy 339.053573 -312.921116)
			(xy 339.108416 -312.910986) (xy 339.16415 -312.908949) (xy 339.219587 -312.915049) (xy 339.273544 -312.929155)
			(xy 339.324873 -312.950967) (xy 339.372479 -312.980021) (xy 339.415347 -313.015696) (xy 339.452564 -313.057233)
			(xy 339.483337 -313.103746) (xy 339.507009 -313.154243) (xy 339.523077 -313.20765) (xy 339.531197 -313.262826)
			(xy 339.531706 -313.290712) (xy 339.78418 -313.290712) (xy 339.788251 -313.23509) (xy 339.800377 -313.180653)
			(xy 339.8203 -313.128562) (xy 339.847596 -313.079927) (xy 339.881682 -313.035784) (xy 339.921831 -312.997075)
			(xy 339.967189 -312.964624) (xy 340.016789 -312.939123) (xy 340.069573 -312.921116) (xy 340.124416 -312.910986)
			(xy 340.18015 -312.908949) (xy 340.235587 -312.915049) (xy 340.289544 -312.929155) (xy 340.340873 -312.950967)
			(xy 340.388479 -312.980021) (xy 340.431347 -313.015696) (xy 340.468564 -313.057233) (xy 340.499337 -313.103746)
			(xy 340.523009 -313.154243) (xy 340.539077 -313.20765) (xy 340.547197 -313.262826) (xy 340.547706 -313.290712)
			(xy 340.80018 -313.290712) (xy 340.804251 -313.23509) (xy 340.816377 -313.180653) (xy 340.8363 -313.128562)
			(xy 340.863596 -313.079927) (xy 340.897682 -313.035784) (xy 340.937831 -312.997075) (xy 340.983189 -312.964624)
			(xy 341.032789 -312.939123) (xy 341.085573 -312.921116) (xy 341.140416 -312.910986) (xy 341.19615 -312.908949)
			(xy 341.251587 -312.915049) (xy 341.305544 -312.929155) (xy 341.356873 -312.950967) (xy 341.404479 -312.980021)
			(xy 341.447347 -313.015696) (xy 341.484564 -313.057233) (xy 341.515337 -313.103746) (xy 341.539009 -313.154243)
			(xy 341.555077 -313.20765) (xy 341.563197 -313.262826) (xy 341.563706 -313.290712) (xy 341.81618 -313.290712)
			(xy 341.820251 -313.23509) (xy 341.832377 -313.180653) (xy 341.8523 -313.128562) (xy 341.879596 -313.079927)
			(xy 341.913682 -313.035784) (xy 341.953831 -312.997075) (xy 341.999189 -312.964624) (xy 342.048789 -312.939123)
			(xy 342.101573 -312.921116) (xy 342.156416 -312.910986) (xy 342.21215 -312.908949) (xy 342.267587 -312.915049)
			(xy 342.321544 -312.929155) (xy 342.372873 -312.950967) (xy 342.420479 -312.980021) (xy 342.463347 -313.015696)
			(xy 342.500564 -313.057233) (xy 342.531337 -313.103746) (xy 342.555009 -313.154243) (xy 342.571077 -313.20765)
			(xy 342.579197 -313.262826) (xy 342.579706 -313.290712) (xy 342.579197 -313.318598) (xy 342.571077 -313.373774)
			(xy 342.555009 -313.427181) (xy 342.531337 -313.477678) (xy 342.500564 -313.524191) (xy 342.463347 -313.565728)
			(xy 342.420479 -313.601403) (xy 342.372873 -313.630457) (xy 342.321544 -313.652269) (xy 342.267587 -313.666375)
			(xy 342.21215 -313.672475) (xy 342.156416 -313.670438) (xy 342.101573 -313.660308) (xy 342.048789 -313.642301)
			(xy 341.999189 -313.6168) (xy 341.953831 -313.584349) (xy 341.913682 -313.54564) (xy 341.879596 -313.501497)
			(xy 341.8523 -313.452862) (xy 341.832377 -313.400771) (xy 341.820251 -313.346334) (xy 341.81618 -313.290712)
			(xy 341.563706 -313.290712) (xy 341.563197 -313.318598) (xy 341.555077 -313.373774) (xy 341.539009 -313.427181)
			(xy 341.515337 -313.477678) (xy 341.484564 -313.524191) (xy 341.447347 -313.565728) (xy 341.404479 -313.601403)
			(xy 341.356873 -313.630457) (xy 341.305544 -313.652269) (xy 341.251587 -313.666375) (xy 341.19615 -313.672475)
			(xy 341.140416 -313.670438) (xy 341.085573 -313.660308) (xy 341.032789 -313.642301) (xy 340.983189 -313.6168)
			(xy 340.937831 -313.584349) (xy 340.897682 -313.54564) (xy 340.863596 -313.501497) (xy 340.8363 -313.452862)
			(xy 340.816377 -313.400771) (xy 340.804251 -313.346334) (xy 340.80018 -313.290712) (xy 340.547706 -313.290712)
			(xy 340.547197 -313.318598) (xy 340.539077 -313.373774) (xy 340.523009 -313.427181) (xy 340.499337 -313.477678)
			(xy 340.468564 -313.524191) (xy 340.431347 -313.565728) (xy 340.388479 -313.601403) (xy 340.340873 -313.630457)
			(xy 340.289544 -313.652269) (xy 340.235587 -313.666375) (xy 340.18015 -313.672475) (xy 340.124416 -313.670438)
			(xy 340.069573 -313.660308) (xy 340.016789 -313.642301) (xy 339.967189 -313.6168) (xy 339.921831 -313.584349)
			(xy 339.881682 -313.54564) (xy 339.847596 -313.501497) (xy 339.8203 -313.452862) (xy 339.800377 -313.400771)
			(xy 339.788251 -313.346334) (xy 339.78418 -313.290712) (xy 339.531706 -313.290712) (xy 339.531197 -313.318598)
			(xy 339.523077 -313.373774) (xy 339.507009 -313.427181) (xy 339.483337 -313.477678) (xy 339.452564 -313.524191)
			(xy 339.415347 -313.565728) (xy 339.372479 -313.601403) (xy 339.324873 -313.630457) (xy 339.273544 -313.652269)
			(xy 339.219587 -313.666375) (xy 339.16415 -313.672475) (xy 339.108416 -313.670438) (xy 339.053573 -313.660308)
			(xy 339.000789 -313.642301) (xy 338.951189 -313.6168) (xy 338.905831 -313.584349) (xy 338.865682 -313.54564)
			(xy 338.831596 -313.501497) (xy 338.8043 -313.452862) (xy 338.784377 -313.400771) (xy 338.772251 -313.346334)
			(xy 338.76818 -313.290712) (xy 338.515706 -313.290712) (xy 338.515197 -313.318598) (xy 338.507077 -313.373774)
			(xy 338.491009 -313.427181) (xy 338.467337 -313.477678) (xy 338.436564 -313.524191) (xy 338.399347 -313.565728)
			(xy 338.356479 -313.601403) (xy 338.308873 -313.630457) (xy 338.257544 -313.652269) (xy 338.203587 -313.666375)
			(xy 338.14815 -313.672475) (xy 338.092416 -313.670438) (xy 338.037573 -313.660308) (xy 337.984789 -313.642301)
			(xy 337.935189 -313.6168) (xy 337.889831 -313.584349) (xy 337.849682 -313.54564) (xy 337.815596 -313.501497)
			(xy 337.7883 -313.452862) (xy 337.768377 -313.400771) (xy 337.756251 -313.346334) (xy 337.75218 -313.290712)
			(xy 337.499706 -313.290712) (xy 337.499197 -313.318598) (xy 337.491077 -313.373774) (xy 337.475009 -313.427181)
			(xy 337.451337 -313.477678) (xy 337.420564 -313.524191) (xy 337.383347 -313.565728) (xy 337.340479 -313.601403)
			(xy 337.292873 -313.630457) (xy 337.241544 -313.652269) (xy 337.187587 -313.666375) (xy 337.13215 -313.672475)
			(xy 337.076416 -313.670438) (xy 337.021573 -313.660308) (xy 336.968789 -313.642301) (xy 336.919189 -313.6168)
			(xy 336.873831 -313.584349) (xy 336.833682 -313.54564) (xy 336.799596 -313.501497) (xy 336.7723 -313.452862)
			(xy 336.752377 -313.400771) (xy 336.740251 -313.346334) (xy 336.73618 -313.290712) (xy 336.483706 -313.290712)
			(xy 336.483197 -313.318598) (xy 336.475077 -313.373774) (xy 336.459009 -313.427181) (xy 336.435337 -313.477678)
			(xy 336.404564 -313.524191) (xy 336.367347 -313.565728) (xy 336.324479 -313.601403) (xy 336.276873 -313.630457)
			(xy 336.225544 -313.652269) (xy 336.171587 -313.666375) (xy 336.11615 -313.672475) (xy 336.060416 -313.670438)
			(xy 336.005573 -313.660308) (xy 335.952789 -313.642301) (xy 335.903189 -313.6168) (xy 335.857831 -313.584349)
			(xy 335.817682 -313.54564) (xy 335.783596 -313.501497) (xy 335.7563 -313.452862) (xy 335.736377 -313.400771)
			(xy 335.724251 -313.346334) (xy 335.72018 -313.290712) (xy 335.467706 -313.290712) (xy 335.467197 -313.318598)
			(xy 335.459077 -313.373774) (xy 335.443009 -313.427181) (xy 335.419337 -313.477678) (xy 335.388564 -313.524191)
			(xy 335.351347 -313.565728) (xy 335.308479 -313.601403) (xy 335.260873 -313.630457) (xy 335.209544 -313.652269)
			(xy 335.155587 -313.666375) (xy 335.10015 -313.672475) (xy 335.044416 -313.670438) (xy 334.989573 -313.660308)
			(xy 334.936789 -313.642301) (xy 334.887189 -313.6168) (xy 334.841831 -313.584349) (xy 334.801682 -313.54564)
			(xy 334.767596 -313.501497) (xy 334.7403 -313.452862) (xy 334.720377 -313.400771) (xy 334.708251 -313.346334)
			(xy 334.70418 -313.290712) (xy 334.451706 -313.290712) (xy 334.451197 -313.318598) (xy 334.443077 -313.373774)
			(xy 334.427009 -313.427181) (xy 334.403337 -313.477678) (xy 334.372564 -313.524191) (xy 334.335347 -313.565728)
			(xy 334.292479 -313.601403) (xy 334.244873 -313.630457) (xy 334.193544 -313.652269) (xy 334.139587 -313.666375)
			(xy 334.08415 -313.672475) (xy 334.028416 -313.670438) (xy 333.973573 -313.660308) (xy 333.920789 -313.642301)
			(xy 333.871189 -313.6168) (xy 333.825831 -313.584349) (xy 333.785682 -313.54564) (xy 333.751596 -313.501497)
			(xy 333.7243 -313.452862) (xy 333.704377 -313.400771) (xy 333.692251 -313.346334) (xy 333.68818 -313.290712)
			(xy 333.435706 -313.290712) (xy 333.435197 -313.318598) (xy 333.427077 -313.373774) (xy 333.411009 -313.427181)
			(xy 333.387337 -313.477678) (xy 333.356564 -313.524191) (xy 333.319347 -313.565728) (xy 333.276479 -313.601403)
			(xy 333.228873 -313.630457) (xy 333.177544 -313.652269) (xy 333.123587 -313.666375) (xy 333.06815 -313.672475)
			(xy 333.012416 -313.670438) (xy 332.957573 -313.660308) (xy 332.904789 -313.642301) (xy 332.855189 -313.6168)
			(xy 332.809831 -313.584349) (xy 332.769682 -313.54564) (xy 332.735596 -313.501497) (xy 332.7083 -313.452862)
			(xy 332.688377 -313.400771) (xy 332.676251 -313.346334) (xy 332.67218 -313.290712) (xy 329.420701 -313.290712)
			(xy 330.099583 -314.306712) (xy 333.68818 -314.306712) (xy 333.692251 -314.25109) (xy 333.704377 -314.196653)
			(xy 333.7243 -314.144562) (xy 333.751596 -314.095927) (xy 333.785682 -314.051784) (xy 333.825831 -314.013075)
			(xy 333.871189 -313.980624) (xy 333.920789 -313.955123) (xy 333.973573 -313.937116) (xy 334.028416 -313.926986)
			(xy 334.08415 -313.924949) (xy 334.139587 -313.931049) (xy 334.193544 -313.945155) (xy 334.244873 -313.966967)
			(xy 334.292479 -313.996021) (xy 334.335347 -314.031696) (xy 334.372564 -314.073233) (xy 334.403337 -314.119746)
			(xy 334.427009 -314.170243) (xy 334.443077 -314.22365) (xy 334.451197 -314.278826) (xy 334.451706 -314.306712)
			(xy 334.70418 -314.306712) (xy 334.708251 -314.25109) (xy 334.720377 -314.196653) (xy 334.7403 -314.144562)
			(xy 334.767596 -314.095927) (xy 334.801682 -314.051784) (xy 334.841831 -314.013075) (xy 334.887189 -313.980624)
			(xy 334.936789 -313.955123) (xy 334.989573 -313.937116) (xy 335.044416 -313.926986) (xy 335.10015 -313.924949)
			(xy 335.155587 -313.931049) (xy 335.209544 -313.945155) (xy 335.260873 -313.966967) (xy 335.308479 -313.996021)
			(xy 335.351347 -314.031696) (xy 335.388564 -314.073233) (xy 335.419337 -314.119746) (xy 335.443009 -314.170243)
			(xy 335.459077 -314.22365) (xy 335.467197 -314.278826) (xy 335.467706 -314.306712) (xy 335.72018 -314.306712)
			(xy 335.724251 -314.25109) (xy 335.736377 -314.196653) (xy 335.7563 -314.144562) (xy 335.783596 -314.095927)
			(xy 335.817682 -314.051784) (xy 335.857831 -314.013075) (xy 335.903189 -313.980624) (xy 335.952789 -313.955123)
			(xy 336.005573 -313.937116) (xy 336.060416 -313.926986) (xy 336.11615 -313.924949) (xy 336.171587 -313.931049)
			(xy 336.225544 -313.945155) (xy 336.276873 -313.966967) (xy 336.324479 -313.996021) (xy 336.367347 -314.031696)
			(xy 336.404564 -314.073233) (xy 336.435337 -314.119746) (xy 336.459009 -314.170243) (xy 336.475077 -314.22365)
			(xy 336.483197 -314.278826) (xy 336.483706 -314.306712) (xy 336.73618 -314.306712) (xy 336.740251 -314.25109)
			(xy 336.752377 -314.196653) (xy 336.7723 -314.144562) (xy 336.799596 -314.095927) (xy 336.833682 -314.051784)
			(xy 336.873831 -314.013075) (xy 336.919189 -313.980624) (xy 336.968789 -313.955123) (xy 337.021573 -313.937116)
			(xy 337.076416 -313.926986) (xy 337.13215 -313.924949) (xy 337.187587 -313.931049) (xy 337.241544 -313.945155)
			(xy 337.292873 -313.966967) (xy 337.340479 -313.996021) (xy 337.383347 -314.031696) (xy 337.420564 -314.073233)
			(xy 337.451337 -314.119746) (xy 337.475009 -314.170243) (xy 337.491077 -314.22365) (xy 337.499197 -314.278826)
			(xy 337.499706 -314.306712) (xy 337.75218 -314.306712) (xy 337.756251 -314.25109) (xy 337.768377 -314.196653)
			(xy 337.7883 -314.144562) (xy 337.815596 -314.095927) (xy 337.849682 -314.051784) (xy 337.889831 -314.013075)
			(xy 337.935189 -313.980624) (xy 337.984789 -313.955123) (xy 338.037573 -313.937116) (xy 338.092416 -313.926986)
			(xy 338.14815 -313.924949) (xy 338.203587 -313.931049) (xy 338.257544 -313.945155) (xy 338.308873 -313.966967)
			(xy 338.356479 -313.996021) (xy 338.399347 -314.031696) (xy 338.436564 -314.073233) (xy 338.467337 -314.119746)
			(xy 338.491009 -314.170243) (xy 338.507077 -314.22365) (xy 338.515197 -314.278826) (xy 338.515706 -314.306712)
			(xy 338.76818 -314.306712) (xy 338.772251 -314.25109) (xy 338.784377 -314.196653) (xy 338.8043 -314.144562)
			(xy 338.831596 -314.095927) (xy 338.865682 -314.051784) (xy 338.905831 -314.013075) (xy 338.951189 -313.980624)
			(xy 339.000789 -313.955123) (xy 339.053573 -313.937116) (xy 339.108416 -313.926986) (xy 339.16415 -313.924949)
			(xy 339.219587 -313.931049) (xy 339.273544 -313.945155) (xy 339.324873 -313.966967) (xy 339.372479 -313.996021)
			(xy 339.415347 -314.031696) (xy 339.452564 -314.073233) (xy 339.483337 -314.119746) (xy 339.507009 -314.170243)
			(xy 339.523077 -314.22365) (xy 339.531197 -314.278826) (xy 339.531706 -314.306712) (xy 339.78418 -314.306712)
			(xy 339.788251 -314.25109) (xy 339.800377 -314.196653) (xy 339.8203 -314.144562) (xy 339.847596 -314.095927)
			(xy 339.881682 -314.051784) (xy 339.921831 -314.013075) (xy 339.967189 -313.980624) (xy 340.016789 -313.955123)
			(xy 340.069573 -313.937116) (xy 340.124416 -313.926986) (xy 340.18015 -313.924949) (xy 340.235587 -313.931049)
			(xy 340.289544 -313.945155) (xy 340.340873 -313.966967) (xy 340.388479 -313.996021) (xy 340.431347 -314.031696)
			(xy 340.468564 -314.073233) (xy 340.499337 -314.119746) (xy 340.523009 -314.170243) (xy 340.539077 -314.22365)
			(xy 340.547197 -314.278826) (xy 340.547706 -314.306712) (xy 340.80018 -314.306712) (xy 340.804251 -314.25109)
			(xy 340.816377 -314.196653) (xy 340.8363 -314.144562) (xy 340.863596 -314.095927) (xy 340.897682 -314.051784)
			(xy 340.937831 -314.013075) (xy 340.983189 -313.980624) (xy 341.032789 -313.955123) (xy 341.085573 -313.937116)
			(xy 341.140416 -313.926986) (xy 341.19615 -313.924949) (xy 341.251587 -313.931049) (xy 341.305544 -313.945155)
			(xy 341.356873 -313.966967) (xy 341.404479 -313.996021) (xy 341.447347 -314.031696) (xy 341.484564 -314.073233)
			(xy 341.515337 -314.119746) (xy 341.539009 -314.170243) (xy 341.555077 -314.22365) (xy 341.563197 -314.278826)
			(xy 341.563706 -314.306712) (xy 341.81618 -314.306712) (xy 341.820251 -314.25109) (xy 341.832377 -314.196653)
			(xy 341.8523 -314.144562) (xy 341.879596 -314.095927) (xy 341.913682 -314.051784) (xy 341.953831 -314.013075)
			(xy 341.999189 -313.980624) (xy 342.048789 -313.955123) (xy 342.101573 -313.937116) (xy 342.156416 -313.926986)
			(xy 342.21215 -313.924949) (xy 342.267587 -313.931049) (xy 342.321544 -313.945155) (xy 342.372873 -313.966967)
			(xy 342.420479 -313.996021) (xy 342.463347 -314.031696) (xy 342.500564 -314.073233) (xy 342.531337 -314.119746)
			(xy 342.555009 -314.170243) (xy 342.571077 -314.22365) (xy 342.579197 -314.278826) (xy 342.579706 -314.306712)
			(xy 342.579197 -314.334598) (xy 342.571077 -314.389774) (xy 342.555009 -314.443181) (xy 342.531337 -314.493678)
			(xy 342.500564 -314.540191) (xy 342.463347 -314.581728) (xy 342.420479 -314.617403) (xy 342.372873 -314.646457)
			(xy 342.321544 -314.668269) (xy 342.267587 -314.682375) (xy 342.21215 -314.688475) (xy 342.156416 -314.686438)
			(xy 342.101573 -314.676308) (xy 342.048789 -314.658301) (xy 341.999189 -314.6328) (xy 341.953831 -314.600349)
			(xy 341.913682 -314.56164) (xy 341.879596 -314.517497) (xy 341.8523 -314.468862) (xy 341.832377 -314.416771)
			(xy 341.820251 -314.362334) (xy 341.81618 -314.306712) (xy 341.563706 -314.306712) (xy 341.563197 -314.334598)
			(xy 341.555077 -314.389774) (xy 341.539009 -314.443181) (xy 341.515337 -314.493678) (xy 341.484564 -314.540191)
			(xy 341.447347 -314.581728) (xy 341.404479 -314.617403) (xy 341.356873 -314.646457) (xy 341.305544 -314.668269)
			(xy 341.251587 -314.682375) (xy 341.19615 -314.688475) (xy 341.140416 -314.686438) (xy 341.085573 -314.676308)
			(xy 341.032789 -314.658301) (xy 340.983189 -314.6328) (xy 340.937831 -314.600349) (xy 340.897682 -314.56164)
			(xy 340.863596 -314.517497) (xy 340.8363 -314.468862) (xy 340.816377 -314.416771) (xy 340.804251 -314.362334)
			(xy 340.80018 -314.306712) (xy 340.547706 -314.306712) (xy 340.547197 -314.334598) (xy 340.539077 -314.389774)
			(xy 340.523009 -314.443181) (xy 340.499337 -314.493678) (xy 340.468564 -314.540191) (xy 340.431347 -314.581728)
			(xy 340.388479 -314.617403) (xy 340.340873 -314.646457) (xy 340.289544 -314.668269) (xy 340.235587 -314.682375)
			(xy 340.18015 -314.688475) (xy 340.124416 -314.686438) (xy 340.069573 -314.676308) (xy 340.016789 -314.658301)
			(xy 339.967189 -314.6328) (xy 339.921831 -314.600349) (xy 339.881682 -314.56164) (xy 339.847596 -314.517497)
			(xy 339.8203 -314.468862) (xy 339.800377 -314.416771) (xy 339.788251 -314.362334) (xy 339.78418 -314.306712)
			(xy 339.531706 -314.306712) (xy 339.531197 -314.334598) (xy 339.523077 -314.389774) (xy 339.507009 -314.443181)
			(xy 339.483337 -314.493678) (xy 339.452564 -314.540191) (xy 339.415347 -314.581728) (xy 339.372479 -314.617403)
			(xy 339.324873 -314.646457) (xy 339.273544 -314.668269) (xy 339.219587 -314.682375) (xy 339.16415 -314.688475)
			(xy 339.108416 -314.686438) (xy 339.053573 -314.676308) (xy 339.000789 -314.658301) (xy 338.951189 -314.6328)
			(xy 338.905831 -314.600349) (xy 338.865682 -314.56164) (xy 338.831596 -314.517497) (xy 338.8043 -314.468862)
			(xy 338.784377 -314.416771) (xy 338.772251 -314.362334) (xy 338.76818 -314.306712) (xy 338.515706 -314.306712)
			(xy 338.515197 -314.334598) (xy 338.507077 -314.389774) (xy 338.491009 -314.443181) (xy 338.467337 -314.493678)
			(xy 338.436564 -314.540191) (xy 338.399347 -314.581728) (xy 338.356479 -314.617403) (xy 338.308873 -314.646457)
			(xy 338.257544 -314.668269) (xy 338.203587 -314.682375) (xy 338.14815 -314.688475) (xy 338.092416 -314.686438)
			(xy 338.037573 -314.676308) (xy 337.984789 -314.658301) (xy 337.935189 -314.6328) (xy 337.889831 -314.600349)
			(xy 337.849682 -314.56164) (xy 337.815596 -314.517497) (xy 337.7883 -314.468862) (xy 337.768377 -314.416771)
			(xy 337.756251 -314.362334) (xy 337.75218 -314.306712) (xy 337.499706 -314.306712) (xy 337.499197 -314.334598)
			(xy 337.491077 -314.389774) (xy 337.475009 -314.443181) (xy 337.451337 -314.493678) (xy 337.420564 -314.540191)
			(xy 337.383347 -314.581728) (xy 337.340479 -314.617403) (xy 337.292873 -314.646457) (xy 337.241544 -314.668269)
			(xy 337.187587 -314.682375) (xy 337.13215 -314.688475) (xy 337.076416 -314.686438) (xy 337.021573 -314.676308)
			(xy 336.968789 -314.658301) (xy 336.919189 -314.6328) (xy 336.873831 -314.600349) (xy 336.833682 -314.56164)
			(xy 336.799596 -314.517497) (xy 336.7723 -314.468862) (xy 336.752377 -314.416771) (xy 336.740251 -314.362334)
			(xy 336.73618 -314.306712) (xy 336.483706 -314.306712) (xy 336.483197 -314.334598) (xy 336.475077 -314.389774)
			(xy 336.459009 -314.443181) (xy 336.435337 -314.493678) (xy 336.404564 -314.540191) (xy 336.367347 -314.581728)
			(xy 336.324479 -314.617403) (xy 336.276873 -314.646457) (xy 336.225544 -314.668269) (xy 336.171587 -314.682375)
			(xy 336.11615 -314.688475) (xy 336.060416 -314.686438) (xy 336.005573 -314.676308) (xy 335.952789 -314.658301)
			(xy 335.903189 -314.6328) (xy 335.857831 -314.600349) (xy 335.817682 -314.56164) (xy 335.783596 -314.517497)
			(xy 335.7563 -314.468862) (xy 335.736377 -314.416771) (xy 335.724251 -314.362334) (xy 335.72018 -314.306712)
			(xy 335.467706 -314.306712) (xy 335.467197 -314.334598) (xy 335.459077 -314.389774) (xy 335.443009 -314.443181)
			(xy 335.419337 -314.493678) (xy 335.388564 -314.540191) (xy 335.351347 -314.581728) (xy 335.308479 -314.617403)
			(xy 335.260873 -314.646457) (xy 335.209544 -314.668269) (xy 335.155587 -314.682375) (xy 335.10015 -314.688475)
			(xy 335.044416 -314.686438) (xy 334.989573 -314.676308) (xy 334.936789 -314.658301) (xy 334.887189 -314.6328)
			(xy 334.841831 -314.600349) (xy 334.801682 -314.56164) (xy 334.767596 -314.517497) (xy 334.7403 -314.468862)
			(xy 334.720377 -314.416771) (xy 334.708251 -314.362334) (xy 334.70418 -314.306712) (xy 334.451706 -314.306712)
			(xy 334.451197 -314.334598) (xy 334.443077 -314.389774) (xy 334.427009 -314.443181) (xy 334.403337 -314.493678)
			(xy 334.372564 -314.540191) (xy 334.335347 -314.581728) (xy 334.292479 -314.617403) (xy 334.244873 -314.646457)
			(xy 334.193544 -314.668269) (xy 334.139587 -314.682375) (xy 334.08415 -314.688475) (xy 334.028416 -314.686438)
			(xy 333.973573 -314.676308) (xy 333.920789 -314.658301) (xy 333.871189 -314.6328) (xy 333.825831 -314.600349)
			(xy 333.785682 -314.56164) (xy 333.751596 -314.517497) (xy 333.7243 -314.468862) (xy 333.704377 -314.416771)
			(xy 333.692251 -314.362334) (xy 333.68818 -314.306712) (xy 330.099583 -314.306712) (xy 330.47178 -314.863734)
			(xy 330.47813 -314.871608) (xy 330.929234 -315.322712) (xy 333.68818 -315.322712) (xy 333.692251 -315.26709)
			(xy 333.704377 -315.212653) (xy 333.7243 -315.160562) (xy 333.751596 -315.111927) (xy 333.785682 -315.067784)
			(xy 333.825831 -315.029075) (xy 333.871189 -314.996624) (xy 333.920789 -314.971123) (xy 333.973573 -314.953116)
			(xy 334.028416 -314.942986) (xy 334.08415 -314.940949) (xy 334.139587 -314.947049) (xy 334.193544 -314.961155)
			(xy 334.244873 -314.982967) (xy 334.292479 -315.012021) (xy 334.335347 -315.047696) (xy 334.372564 -315.089233)
			(xy 334.403337 -315.135746) (xy 334.427009 -315.186243) (xy 334.443077 -315.23965) (xy 334.451197 -315.294826)
			(xy 334.451706 -315.322712) (xy 334.70418 -315.322712) (xy 334.708251 -315.26709) (xy 334.720377 -315.212653)
			(xy 334.7403 -315.160562) (xy 334.767596 -315.111927) (xy 334.801682 -315.067784) (xy 334.841831 -315.029075)
			(xy 334.887189 -314.996624) (xy 334.936789 -314.971123) (xy 334.989573 -314.953116) (xy 335.044416 -314.942986)
			(xy 335.10015 -314.940949) (xy 335.155587 -314.947049) (xy 335.209544 -314.961155) (xy 335.260873 -314.982967)
			(xy 335.308479 -315.012021) (xy 335.351347 -315.047696) (xy 335.388564 -315.089233) (xy 335.419337 -315.135746)
			(xy 335.443009 -315.186243) (xy 335.459077 -315.23965) (xy 335.467197 -315.294826) (xy 335.467706 -315.322712)
			(xy 335.72018 -315.322712) (xy 335.724251 -315.26709) (xy 335.736377 -315.212653) (xy 335.7563 -315.160562)
			(xy 335.783596 -315.111927) (xy 335.817682 -315.067784) (xy 335.857831 -315.029075) (xy 335.903189 -314.996624)
			(xy 335.952789 -314.971123) (xy 336.005573 -314.953116) (xy 336.060416 -314.942986) (xy 336.11615 -314.940949)
			(xy 336.171587 -314.947049) (xy 336.225544 -314.961155) (xy 336.276873 -314.982967) (xy 336.324479 -315.012021)
			(xy 336.367347 -315.047696) (xy 336.404564 -315.089233) (xy 336.435337 -315.135746) (xy 336.459009 -315.186243)
			(xy 336.475077 -315.23965) (xy 336.483197 -315.294826) (xy 336.483706 -315.322712) (xy 336.73618 -315.322712)
			(xy 336.740251 -315.26709) (xy 336.752377 -315.212653) (xy 336.7723 -315.160562) (xy 336.799596 -315.111927)
			(xy 336.833682 -315.067784) (xy 336.873831 -315.029075) (xy 336.919189 -314.996624) (xy 336.968789 -314.971123)
			(xy 337.021573 -314.953116) (xy 337.076416 -314.942986) (xy 337.13215 -314.940949) (xy 337.187587 -314.947049)
			(xy 337.241544 -314.961155) (xy 337.292873 -314.982967) (xy 337.340479 -315.012021) (xy 337.383347 -315.047696)
			(xy 337.420564 -315.089233) (xy 337.451337 -315.135746) (xy 337.475009 -315.186243) (xy 337.491077 -315.23965)
			(xy 337.499197 -315.294826) (xy 337.499706 -315.322712) (xy 337.75218 -315.322712) (xy 337.756251 -315.26709)
			(xy 337.768377 -315.212653) (xy 337.7883 -315.160562) (xy 337.815596 -315.111927) (xy 337.849682 -315.067784)
			(xy 337.889831 -315.029075) (xy 337.935189 -314.996624) (xy 337.984789 -314.971123) (xy 338.037573 -314.953116)
			(xy 338.092416 -314.942986) (xy 338.14815 -314.940949) (xy 338.203587 -314.947049) (xy 338.257544 -314.961155)
			(xy 338.308873 -314.982967) (xy 338.356479 -315.012021) (xy 338.399347 -315.047696) (xy 338.436564 -315.089233)
			(xy 338.467337 -315.135746) (xy 338.491009 -315.186243) (xy 338.507077 -315.23965) (xy 338.515197 -315.294826)
			(xy 338.515706 -315.322712) (xy 338.76818 -315.322712) (xy 338.772251 -315.26709) (xy 338.784377 -315.212653)
			(xy 338.8043 -315.160562) (xy 338.831596 -315.111927) (xy 338.865682 -315.067784) (xy 338.905831 -315.029075)
			(xy 338.951189 -314.996624) (xy 339.000789 -314.971123) (xy 339.053573 -314.953116) (xy 339.108416 -314.942986)
			(xy 339.16415 -314.940949) (xy 339.219587 -314.947049) (xy 339.273544 -314.961155) (xy 339.324873 -314.982967)
			(xy 339.372479 -315.012021) (xy 339.415347 -315.047696) (xy 339.452564 -315.089233) (xy 339.483337 -315.135746)
			(xy 339.507009 -315.186243) (xy 339.523077 -315.23965) (xy 339.531197 -315.294826) (xy 339.531706 -315.322712)
			(xy 339.78418 -315.322712) (xy 339.788251 -315.26709) (xy 339.800377 -315.212653) (xy 339.8203 -315.160562)
			(xy 339.847596 -315.111927) (xy 339.881682 -315.067784) (xy 339.921831 -315.029075) (xy 339.967189 -314.996624)
			(xy 340.016789 -314.971123) (xy 340.069573 -314.953116) (xy 340.124416 -314.942986) (xy 340.18015 -314.940949)
			(xy 340.235587 -314.947049) (xy 340.289544 -314.961155) (xy 340.340873 -314.982967) (xy 340.388479 -315.012021)
			(xy 340.431347 -315.047696) (xy 340.468564 -315.089233) (xy 340.499337 -315.135746) (xy 340.523009 -315.186243)
			(xy 340.539077 -315.23965) (xy 340.547197 -315.294826) (xy 340.547706 -315.322712) (xy 340.80018 -315.322712)
			(xy 340.804251 -315.26709) (xy 340.816377 -315.212653) (xy 340.8363 -315.160562) (xy 340.863596 -315.111927)
			(xy 340.897682 -315.067784) (xy 340.937831 -315.029075) (xy 340.983189 -314.996624) (xy 341.032789 -314.971123)
			(xy 341.085573 -314.953116) (xy 341.140416 -314.942986) (xy 341.19615 -314.940949) (xy 341.251587 -314.947049)
			(xy 341.305544 -314.961155) (xy 341.356873 -314.982967) (xy 341.404479 -315.012021) (xy 341.447347 -315.047696)
			(xy 341.484564 -315.089233) (xy 341.515337 -315.135746) (xy 341.539009 -315.186243) (xy 341.555077 -315.23965)
			(xy 341.563197 -315.294826) (xy 341.563706 -315.322712) (xy 341.81618 -315.322712) (xy 341.820251 -315.26709)
			(xy 341.832377 -315.212653) (xy 341.8523 -315.160562) (xy 341.879596 -315.111927) (xy 341.913682 -315.067784)
			(xy 341.953831 -315.029075) (xy 341.999189 -314.996624) (xy 342.048789 -314.971123) (xy 342.101573 -314.953116)
			(xy 342.156416 -314.942986) (xy 342.21215 -314.940949) (xy 342.267587 -314.947049) (xy 342.321544 -314.961155)
			(xy 342.372873 -314.982967) (xy 342.420479 -315.012021) (xy 342.463347 -315.047696) (xy 342.500564 -315.089233)
			(xy 342.531337 -315.135746) (xy 342.555009 -315.186243) (xy 342.571077 -315.23965) (xy 342.579197 -315.294826)
			(xy 342.579706 -315.322712) (xy 342.579197 -315.350598) (xy 342.571077 -315.405774) (xy 342.555009 -315.459181)
			(xy 342.531337 -315.509678) (xy 342.500564 -315.556191) (xy 342.463347 -315.597728) (xy 342.420479 -315.633403)
			(xy 342.372873 -315.662457) (xy 342.321544 -315.684269) (xy 342.267587 -315.698375) (xy 342.21215 -315.704475)
			(xy 342.156416 -315.702438) (xy 342.101573 -315.692308) (xy 342.048789 -315.674301) (xy 341.999189 -315.6488)
			(xy 341.953831 -315.616349) (xy 341.913682 -315.57764) (xy 341.879596 -315.533497) (xy 341.8523 -315.484862)
			(xy 341.832377 -315.432771) (xy 341.820251 -315.378334) (xy 341.81618 -315.322712) (xy 341.563706 -315.322712)
			(xy 341.563197 -315.350598) (xy 341.555077 -315.405774) (xy 341.539009 -315.459181) (xy 341.515337 -315.509678)
			(xy 341.484564 -315.556191) (xy 341.447347 -315.597728) (xy 341.404479 -315.633403) (xy 341.356873 -315.662457)
			(xy 341.305544 -315.684269) (xy 341.251587 -315.698375) (xy 341.19615 -315.704475) (xy 341.140416 -315.702438)
			(xy 341.085573 -315.692308) (xy 341.032789 -315.674301) (xy 340.983189 -315.6488) (xy 340.937831 -315.616349)
			(xy 340.897682 -315.57764) (xy 340.863596 -315.533497) (xy 340.8363 -315.484862) (xy 340.816377 -315.432771)
			(xy 340.804251 -315.378334) (xy 340.80018 -315.322712) (xy 340.547706 -315.322712) (xy 340.547197 -315.350598)
			(xy 340.539077 -315.405774) (xy 340.523009 -315.459181) (xy 340.499337 -315.509678) (xy 340.468564 -315.556191)
			(xy 340.431347 -315.597728) (xy 340.388479 -315.633403) (xy 340.340873 -315.662457) (xy 340.289544 -315.684269)
			(xy 340.235587 -315.698375) (xy 340.18015 -315.704475) (xy 340.124416 -315.702438) (xy 340.069573 -315.692308)
			(xy 340.016789 -315.674301) (xy 339.967189 -315.6488) (xy 339.921831 -315.616349) (xy 339.881682 -315.57764)
			(xy 339.847596 -315.533497) (xy 339.8203 -315.484862) (xy 339.800377 -315.432771) (xy 339.788251 -315.378334)
			(xy 339.78418 -315.322712) (xy 339.531706 -315.322712) (xy 339.531197 -315.350598) (xy 339.523077 -315.405774)
			(xy 339.507009 -315.459181) (xy 339.483337 -315.509678) (xy 339.452564 -315.556191) (xy 339.415347 -315.597728)
			(xy 339.372479 -315.633403) (xy 339.324873 -315.662457) (xy 339.273544 -315.684269) (xy 339.219587 -315.698375)
			(xy 339.16415 -315.704475) (xy 339.108416 -315.702438) (xy 339.053573 -315.692308) (xy 339.000789 -315.674301)
			(xy 338.951189 -315.6488) (xy 338.905831 -315.616349) (xy 338.865682 -315.57764) (xy 338.831596 -315.533497)
			(xy 338.8043 -315.484862) (xy 338.784377 -315.432771) (xy 338.772251 -315.378334) (xy 338.76818 -315.322712)
			(xy 338.515706 -315.322712) (xy 338.515197 -315.350598) (xy 338.507077 -315.405774) (xy 338.491009 -315.459181)
			(xy 338.467337 -315.509678) (xy 338.436564 -315.556191) (xy 338.399347 -315.597728) (xy 338.356479 -315.633403)
			(xy 338.308873 -315.662457) (xy 338.257544 -315.684269) (xy 338.203587 -315.698375) (xy 338.14815 -315.704475)
			(xy 338.092416 -315.702438) (xy 338.037573 -315.692308) (xy 337.984789 -315.674301) (xy 337.935189 -315.6488)
			(xy 337.889831 -315.616349) (xy 337.849682 -315.57764) (xy 337.815596 -315.533497) (xy 337.7883 -315.484862)
			(xy 337.768377 -315.432771) (xy 337.756251 -315.378334) (xy 337.75218 -315.322712) (xy 337.499706 -315.322712)
			(xy 337.499197 -315.350598) (xy 337.491077 -315.405774) (xy 337.475009 -315.459181) (xy 337.451337 -315.509678)
			(xy 337.420564 -315.556191) (xy 337.383347 -315.597728) (xy 337.340479 -315.633403) (xy 337.292873 -315.662457)
			(xy 337.241544 -315.684269) (xy 337.187587 -315.698375) (xy 337.13215 -315.704475) (xy 337.076416 -315.702438)
			(xy 337.021573 -315.692308) (xy 336.968789 -315.674301) (xy 336.919189 -315.6488) (xy 336.873831 -315.616349)
			(xy 336.833682 -315.57764) (xy 336.799596 -315.533497) (xy 336.7723 -315.484862) (xy 336.752377 -315.432771)
			(xy 336.740251 -315.378334) (xy 336.73618 -315.322712) (xy 336.483706 -315.322712) (xy 336.483197 -315.350598)
			(xy 336.475077 -315.405774) (xy 336.459009 -315.459181) (xy 336.435337 -315.509678) (xy 336.404564 -315.556191)
			(xy 336.367347 -315.597728) (xy 336.324479 -315.633403) (xy 336.276873 -315.662457) (xy 336.225544 -315.684269)
			(xy 336.171587 -315.698375) (xy 336.11615 -315.704475) (xy 336.060416 -315.702438) (xy 336.005573 -315.692308)
			(xy 335.952789 -315.674301) (xy 335.903189 -315.6488) (xy 335.857831 -315.616349) (xy 335.817682 -315.57764)
			(xy 335.783596 -315.533497) (xy 335.7563 -315.484862) (xy 335.736377 -315.432771) (xy 335.724251 -315.378334)
			(xy 335.72018 -315.322712) (xy 335.467706 -315.322712) (xy 335.467197 -315.350598) (xy 335.459077 -315.405774)
			(xy 335.443009 -315.459181) (xy 335.419337 -315.509678) (xy 335.388564 -315.556191) (xy 335.351347 -315.597728)
			(xy 335.308479 -315.633403) (xy 335.260873 -315.662457) (xy 335.209544 -315.684269) (xy 335.155587 -315.698375)
			(xy 335.10015 -315.704475) (xy 335.044416 -315.702438) (xy 334.989573 -315.692308) (xy 334.936789 -315.674301)
			(xy 334.887189 -315.6488) (xy 334.841831 -315.616349) (xy 334.801682 -315.57764) (xy 334.767596 -315.533497)
			(xy 334.7403 -315.484862) (xy 334.720377 -315.432771) (xy 334.708251 -315.378334) (xy 334.70418 -315.322712)
			(xy 334.451706 -315.322712) (xy 334.451197 -315.350598) (xy 334.443077 -315.405774) (xy 334.427009 -315.459181)
			(xy 334.403337 -315.509678) (xy 334.372564 -315.556191) (xy 334.335347 -315.597728) (xy 334.292479 -315.633403)
			(xy 334.244873 -315.662457) (xy 334.193544 -315.684269) (xy 334.139587 -315.698375) (xy 334.08415 -315.704475)
			(xy 334.028416 -315.702438) (xy 333.973573 -315.692308) (xy 333.920789 -315.674301) (xy 333.871189 -315.6488)
			(xy 333.825831 -315.616349) (xy 333.785682 -315.57764) (xy 333.751596 -315.533497) (xy 333.7243 -315.484862)
			(xy 333.704377 -315.432771) (xy 333.692251 -315.378334) (xy 333.68818 -315.322712) (xy 330.929234 -315.322712)
			(xy 331.712824 -316.106302) (xy 331.719734 -316.112558) (xy 331.736771 -316.120079) (xy 331.75537 -316.121046)
			(xy 331.773096 -316.115333) (xy 331.780642 -316.109858) (xy 331.78115 -316.10935) (xy 331.786992 -316.104778)
			(xy 331.80696 -316.089869) (xy 331.850034 -316.06481) (xy 331.896005 -316.045576) (xy 331.944091 -316.032496)
			(xy 331.993471 -316.025794) (xy 332.018386 -316.025276) (xy 332.025752 -316.025276) (xy 332.052751 -316.026124)
			(xy 332.106117 -316.034494) (xy 332.157767 -316.050308) (xy 332.20667 -316.073251) (xy 332.251848 -316.102863)
			(xy 332.292396 -316.138553) (xy 332.327504 -316.179606) (xy 332.356469 -316.2252) (xy 332.378713 -316.274425)
			(xy 332.39379 -316.326296) (xy 332.395556 -316.338712) (xy 335.72018 -316.338712) (xy 335.724251 -316.28309)
			(xy 335.736377 -316.228653) (xy 335.7563 -316.176562) (xy 335.783596 -316.127927) (xy 335.817682 -316.083784)
			(xy 335.857831 -316.045075) (xy 335.903189 -316.012624) (xy 335.952789 -315.987123) (xy 336.005573 -315.969116)
			(xy 336.060416 -315.958986) (xy 336.11615 -315.956949) (xy 336.171587 -315.963049) (xy 336.225544 -315.977155)
			(xy 336.276873 -315.998967) (xy 336.324479 -316.028021) (xy 336.367347 -316.063696) (xy 336.404564 -316.105233)
			(xy 336.435337 -316.151746) (xy 336.459009 -316.202243) (xy 336.475077 -316.25565) (xy 336.483197 -316.310826)
			(xy 336.483706 -316.338712) (xy 336.73618 -316.338712) (xy 336.740251 -316.28309) (xy 336.752377 -316.228653)
			(xy 336.7723 -316.176562) (xy 336.799596 -316.127927) (xy 336.833682 -316.083784) (xy 336.873831 -316.045075)
			(xy 336.919189 -316.012624) (xy 336.968789 -315.987123) (xy 337.021573 -315.969116) (xy 337.076416 -315.958986)
			(xy 337.13215 -315.956949) (xy 337.187587 -315.963049) (xy 337.241544 -315.977155) (xy 337.292873 -315.998967)
			(xy 337.340479 -316.028021) (xy 337.383347 -316.063696) (xy 337.420564 -316.105233) (xy 337.451337 -316.151746)
			(xy 337.475009 -316.202243) (xy 337.491077 -316.25565) (xy 337.499197 -316.310826) (xy 337.499706 -316.338712)
			(xy 337.75218 -316.338712) (xy 337.756251 -316.28309) (xy 337.768377 -316.228653) (xy 337.7883 -316.176562)
			(xy 337.815596 -316.127927) (xy 337.849682 -316.083784) (xy 337.889831 -316.045075) (xy 337.935189 -316.012624)
			(xy 337.984789 -315.987123) (xy 338.037573 -315.969116) (xy 338.092416 -315.958986) (xy 338.14815 -315.956949)
			(xy 338.203587 -315.963049) (xy 338.257544 -315.977155) (xy 338.308873 -315.998967) (xy 338.356479 -316.028021)
			(xy 338.399347 -316.063696) (xy 338.436564 -316.105233) (xy 338.467337 -316.151746) (xy 338.491009 -316.202243)
			(xy 338.507077 -316.25565) (xy 338.515197 -316.310826) (xy 338.515706 -316.338712) (xy 338.76818 -316.338712)
			(xy 338.772251 -316.28309) (xy 338.784377 -316.228653) (xy 338.8043 -316.176562) (xy 338.831596 -316.127927)
			(xy 338.865682 -316.083784) (xy 338.905831 -316.045075) (xy 338.951189 -316.012624) (xy 339.000789 -315.987123)
			(xy 339.053573 -315.969116) (xy 339.108416 -315.958986) (xy 339.16415 -315.956949) (xy 339.219587 -315.963049)
			(xy 339.273544 -315.977155) (xy 339.324873 -315.998967) (xy 339.372479 -316.028021) (xy 339.415347 -316.063696)
			(xy 339.452564 -316.105233) (xy 339.483337 -316.151746) (xy 339.507009 -316.202243) (xy 339.523077 -316.25565)
			(xy 339.531197 -316.310826) (xy 339.531706 -316.338712) (xy 339.78418 -316.338712) (xy 339.788251 -316.28309)
			(xy 339.800377 -316.228653) (xy 339.8203 -316.176562) (xy 339.847596 -316.127927) (xy 339.881682 -316.083784)
			(xy 339.921831 -316.045075) (xy 339.967189 -316.012624) (xy 340.016789 -315.987123) (xy 340.069573 -315.969116)
			(xy 340.124416 -315.958986) (xy 340.18015 -315.956949) (xy 340.235587 -315.963049) (xy 340.289544 -315.977155)
			(xy 340.340873 -315.998967) (xy 340.388479 -316.028021) (xy 340.431347 -316.063696) (xy 340.468564 -316.105233)
			(xy 340.499337 -316.151746) (xy 340.523009 -316.202243) (xy 340.539077 -316.25565) (xy 340.547197 -316.310826)
			(xy 340.547706 -316.338712) (xy 340.80018 -316.338712) (xy 340.804251 -316.28309) (xy 340.816377 -316.228653)
			(xy 340.8363 -316.176562) (xy 340.863596 -316.127927) (xy 340.897682 -316.083784) (xy 340.937831 -316.045075)
			(xy 340.983189 -316.012624) (xy 341.032789 -315.987123) (xy 341.085573 -315.969116) (xy 341.140416 -315.958986)
			(xy 341.19615 -315.956949) (xy 341.251587 -315.963049) (xy 341.305544 -315.977155) (xy 341.356873 -315.998967)
			(xy 341.404479 -316.028021) (xy 341.447347 -316.063696) (xy 341.484564 -316.105233) (xy 341.515337 -316.151746)
			(xy 341.539009 -316.202243) (xy 341.555077 -316.25565) (xy 341.563197 -316.310826) (xy 341.563706 -316.338712)
			(xy 341.81618 -316.338712) (xy 341.820251 -316.28309) (xy 341.832377 -316.228653) (xy 341.8523 -316.176562)
			(xy 341.879596 -316.127927) (xy 341.913682 -316.083784) (xy 341.953831 -316.045075) (xy 341.999189 -316.012624)
			(xy 342.048789 -315.987123) (xy 342.101573 -315.969116) (xy 342.156416 -315.958986) (xy 342.21215 -315.956949)
			(xy 342.267587 -315.963049) (xy 342.321544 -315.977155) (xy 342.351701 -315.98997) (xy 349.475042 -315.98997)
			(xy 349.479113 -315.934348) (xy 349.491239 -315.879911) (xy 349.511162 -315.82782) (xy 349.538458 -315.779185)
			(xy 349.572544 -315.735042) (xy 349.612693 -315.696333) (xy 349.658051 -315.663882) (xy 349.707651 -315.638381)
			(xy 349.760435 -315.620374) (xy 349.815278 -315.610244) (xy 349.871012 -315.608207) (xy 349.926449 -315.614307)
			(xy 349.980406 -315.628413) (xy 350.031735 -315.650225) (xy 350.079341 -315.679279) (xy 350.122209 -315.714954)
			(xy 350.159426 -315.756491) (xy 350.190199 -315.803004) (xy 350.213871 -315.853501) (xy 350.229939 -315.906908)
			(xy 350.238059 -315.962084) (xy 350.238568 -315.98997) (xy 350.238059 -316.017856) (xy 350.229939 -316.073032)
			(xy 350.213871 -316.126439) (xy 350.190199 -316.176936) (xy 350.159426 -316.223449) (xy 350.122209 -316.264986)
			(xy 350.079341 -316.300661) (xy 350.031735 -316.329715) (xy 349.980406 -316.351527) (xy 349.926449 -316.365633)
			(xy 349.871012 -316.371733) (xy 349.815278 -316.369696) (xy 349.760435 -316.359566) (xy 349.707651 -316.341559)
			(xy 349.658051 -316.316058) (xy 349.612693 -316.283607) (xy 349.572544 -316.244898) (xy 349.538458 -316.200755)
			(xy 349.511162 -316.15212) (xy 349.491239 -316.100029) (xy 349.479113 -316.045592) (xy 349.475042 -315.98997)
			(xy 342.351701 -315.98997) (xy 342.372873 -315.998967) (xy 342.420479 -316.028021) (xy 342.463347 -316.063696)
			(xy 342.500564 -316.105233) (xy 342.531337 -316.151746) (xy 342.555009 -316.202243) (xy 342.571077 -316.25565)
			(xy 342.579197 -316.310826) (xy 342.579706 -316.338712) (xy 342.579197 -316.366598) (xy 342.571077 -316.421774)
			(xy 342.555009 -316.475181) (xy 342.531337 -316.525678) (xy 342.500564 -316.572191) (xy 342.463347 -316.613728)
			(xy 342.420479 -316.649403) (xy 342.372873 -316.678457) (xy 342.321544 -316.700269) (xy 342.267587 -316.714375)
			(xy 342.21215 -316.720475) (xy 342.156416 -316.718438) (xy 342.101573 -316.708308) (xy 342.048789 -316.690301)
			(xy 341.999189 -316.6648) (xy 341.953831 -316.632349) (xy 341.913682 -316.59364) (xy 341.879596 -316.549497)
			(xy 341.8523 -316.500862) (xy 341.832377 -316.448771) (xy 341.820251 -316.394334) (xy 341.81618 -316.338712)
			(xy 341.563706 -316.338712) (xy 341.563197 -316.366598) (xy 341.555077 -316.421774) (xy 341.539009 -316.475181)
			(xy 341.515337 -316.525678) (xy 341.484564 -316.572191) (xy 341.447347 -316.613728) (xy 341.404479 -316.649403)
			(xy 341.356873 -316.678457) (xy 341.305544 -316.700269) (xy 341.251587 -316.714375) (xy 341.19615 -316.720475)
			(xy 341.140416 -316.718438) (xy 341.085573 -316.708308) (xy 341.032789 -316.690301) (xy 340.983189 -316.6648)
			(xy 340.937831 -316.632349) (xy 340.897682 -316.59364) (xy 340.863596 -316.549497) (xy 340.8363 -316.500862)
			(xy 340.816377 -316.448771) (xy 340.804251 -316.394334) (xy 340.80018 -316.338712) (xy 340.547706 -316.338712)
			(xy 340.547197 -316.366598) (xy 340.539077 -316.421774) (xy 340.523009 -316.475181) (xy 340.499337 -316.525678)
			(xy 340.468564 -316.572191) (xy 340.431347 -316.613728) (xy 340.388479 -316.649403) (xy 340.340873 -316.678457)
			(xy 340.289544 -316.700269) (xy 340.235587 -316.714375) (xy 340.18015 -316.720475) (xy 340.124416 -316.718438)
			(xy 340.069573 -316.708308) (xy 340.016789 -316.690301) (xy 339.967189 -316.6648) (xy 339.921831 -316.632349)
			(xy 339.881682 -316.59364) (xy 339.847596 -316.549497) (xy 339.8203 -316.500862) (xy 339.800377 -316.448771)
			(xy 339.788251 -316.394334) (xy 339.78418 -316.338712) (xy 339.531706 -316.338712) (xy 339.531197 -316.366598)
			(xy 339.523077 -316.421774) (xy 339.507009 -316.475181) (xy 339.483337 -316.525678) (xy 339.452564 -316.572191)
			(xy 339.415347 -316.613728) (xy 339.372479 -316.649403) (xy 339.324873 -316.678457) (xy 339.273544 -316.700269)
			(xy 339.219587 -316.714375) (xy 339.16415 -316.720475) (xy 339.108416 -316.718438) (xy 339.053573 -316.708308)
			(xy 339.000789 -316.690301) (xy 338.951189 -316.6648) (xy 338.905831 -316.632349) (xy 338.865682 -316.59364)
			(xy 338.831596 -316.549497) (xy 338.8043 -316.500862) (xy 338.784377 -316.448771) (xy 338.772251 -316.394334)
			(xy 338.76818 -316.338712) (xy 338.515706 -316.338712) (xy 338.515197 -316.366598) (xy 338.507077 -316.421774)
			(xy 338.491009 -316.475181) (xy 338.467337 -316.525678) (xy 338.436564 -316.572191) (xy 338.399347 -316.613728)
			(xy 338.356479 -316.649403) (xy 338.308873 -316.678457) (xy 338.257544 -316.700269) (xy 338.203587 -316.714375)
			(xy 338.14815 -316.720475) (xy 338.092416 -316.718438) (xy 338.037573 -316.708308) (xy 337.984789 -316.690301)
			(xy 337.935189 -316.6648) (xy 337.889831 -316.632349) (xy 337.849682 -316.59364) (xy 337.815596 -316.549497)
			(xy 337.7883 -316.500862) (xy 337.768377 -316.448771) (xy 337.756251 -316.394334) (xy 337.75218 -316.338712)
			(xy 337.499706 -316.338712) (xy 337.499197 -316.366598) (xy 337.491077 -316.421774) (xy 337.475009 -316.475181)
			(xy 337.451337 -316.525678) (xy 337.420564 -316.572191) (xy 337.383347 -316.613728) (xy 337.340479 -316.649403)
			(xy 337.292873 -316.678457) (xy 337.241544 -316.700269) (xy 337.187587 -316.714375) (xy 337.13215 -316.720475)
			(xy 337.076416 -316.718438) (xy 337.021573 -316.708308) (xy 336.968789 -316.690301) (xy 336.919189 -316.6648)
			(xy 336.873831 -316.632349) (xy 336.833682 -316.59364) (xy 336.799596 -316.549497) (xy 336.7723 -316.500862)
			(xy 336.752377 -316.448771) (xy 336.740251 -316.394334) (xy 336.73618 -316.338712) (xy 336.483706 -316.338712)
			(xy 336.483197 -316.366598) (xy 336.475077 -316.421774) (xy 336.459009 -316.475181) (xy 336.435337 -316.525678)
			(xy 336.404564 -316.572191) (xy 336.367347 -316.613728) (xy 336.324479 -316.649403) (xy 336.276873 -316.678457)
			(xy 336.225544 -316.700269) (xy 336.171587 -316.714375) (xy 336.11615 -316.720475) (xy 336.060416 -316.718438)
			(xy 336.005573 -316.708308) (xy 335.952789 -316.690301) (xy 335.903189 -316.6648) (xy 335.857831 -316.632349)
			(xy 335.817682 -316.59364) (xy 335.783596 -316.549497) (xy 335.7563 -316.500862) (xy 335.736377 -316.448771)
			(xy 335.724251 -316.394334) (xy 335.72018 -316.338712) (xy 332.395556 -316.338712) (xy 332.401398 -316.379775)
			(xy 332.401926 -316.406784) (xy 332.401441 -316.434036) (xy 332.393687 -316.487987) (xy 332.378333 -316.540285)
			(xy 332.355693 -316.589865) (xy 332.326228 -316.635719) (xy 332.290536 -316.676912) (xy 332.249346 -316.712607)
			(xy 332.203495 -316.742077) (xy 332.153916 -316.764721) (xy 332.10162 -316.78008) (xy 332.04767 -316.787839)
			(xy 332.020418 -316.788292) (xy 332.00537 -316.788187) (xy 331.975363 -316.785901) (xy 331.960474 -316.78372)
			(xy 331.949552 -316.781942) (xy 331.928216 -316.788038) (xy 331.86116 -316.845442) (xy 331.853148 -316.853019)
			(xy 331.843952 -316.873035) (xy 331.84338 -316.88405) (xy 331.84338 -317.69304) (xy 349.475042 -317.69304)
			(xy 349.479113 -317.637418) (xy 349.491239 -317.582981) (xy 349.511162 -317.53089) (xy 349.538458 -317.482255)
			(xy 349.572544 -317.438112) (xy 349.612693 -317.399403) (xy 349.658051 -317.366952) (xy 349.707651 -317.341451)
			(xy 349.760435 -317.323444) (xy 349.815278 -317.313314) (xy 349.871012 -317.311277) (xy 349.926449 -317.317377)
			(xy 349.980406 -317.331483) (xy 350.031735 -317.353295) (xy 350.079341 -317.382349) (xy 350.122209 -317.418024)
			(xy 350.159426 -317.459561) (xy 350.190199 -317.506074) (xy 350.213871 -317.556571) (xy 350.229939 -317.609978)
			(xy 350.238059 -317.665154) (xy 350.238568 -317.69304) (xy 350.238059 -317.720926) (xy 350.229939 -317.776102)
			(xy 350.213871 -317.829509) (xy 350.190199 -317.880006) (xy 350.159426 -317.926519) (xy 350.122209 -317.968056)
			(xy 350.079341 -318.003731) (xy 350.031735 -318.032785) (xy 349.980406 -318.054597) (xy 349.926449 -318.068703)
			(xy 349.871012 -318.074803) (xy 349.815278 -318.072766) (xy 349.760435 -318.062636) (xy 349.707651 -318.044629)
			(xy 349.658051 -318.019128) (xy 349.612693 -317.986677) (xy 349.572544 -317.947968) (xy 349.538458 -317.903825)
			(xy 349.511162 -317.85519) (xy 349.491239 -317.803099) (xy 349.479113 -317.748662) (xy 349.475042 -317.69304)
			(xy 331.84338 -317.69304) (xy 331.84338 -317.885064) (xy 331.843473 -317.890083) (xy 331.845395 -317.899934)
			(xy 331.84719 -317.904622) (xy 331.860652 -317.936626) (xy 331.870304 -317.961264) (xy 331.870558 -317.961772)
			(xy 331.932534 -318.11087) (xy 331.934311 -318.115497) (xy 331.936237 -318.125219) (xy 331.936344 -318.130174)
			(xy 331.936344 -318.200532) (xy 331.936434 -318.205552) (xy 331.938349 -318.215406) (xy 331.940154 -318.22009)
			(xy 332.046072 -318.474598) (xy 332.064101 -318.519617) (xy 332.075643 -318.557656) (xy 349.475042 -318.557656)
			(xy 349.479113 -318.502034) (xy 349.491239 -318.447597) (xy 349.511162 -318.395506) (xy 349.538458 -318.346871)
			(xy 349.572544 -318.302728) (xy 349.612693 -318.264019) (xy 349.658051 -318.231568) (xy 349.707651 -318.206067)
			(xy 349.760435 -318.18806) (xy 349.815278 -318.17793) (xy 349.871012 -318.175893) (xy 349.926449 -318.181993)
			(xy 349.980406 -318.196099) (xy 350.031735 -318.217911) (xy 350.079341 -318.246965) (xy 350.122209 -318.28264)
			(xy 350.159426 -318.324177) (xy 350.190199 -318.37069) (xy 350.213871 -318.421187) (xy 350.229939 -318.474594)
			(xy 350.238059 -318.52977) (xy 350.238568 -318.557656) (xy 350.238059 -318.585542) (xy 350.229939 -318.640718)
			(xy 350.213871 -318.694125) (xy 350.190199 -318.744622) (xy 350.159426 -318.791135) (xy 350.122209 -318.832672)
			(xy 350.079341 -318.868347) (xy 350.031735 -318.897401) (xy 349.980406 -318.919213) (xy 349.926449 -318.933319)
			(xy 349.871012 -318.939419) (xy 349.815278 -318.937382) (xy 349.760435 -318.927252) (xy 349.707651 -318.909245)
			(xy 349.658051 -318.883744) (xy 349.612693 -318.851293) (xy 349.572544 -318.812584) (xy 349.538458 -318.768441)
			(xy 349.511162 -318.719806) (xy 349.491239 -318.667715) (xy 349.479113 -318.613278) (xy 349.475042 -318.557656)
			(xy 332.075643 -318.557656) (xy 332.09226 -318.612423) (xy 332.111183 -318.707542) (xy 332.120688 -318.804058)
			(xy 332.121256 -318.85255) (xy 332.121256 -321.021202) (xy 332.121198 -321.041098) (xy 332.119672 -321.080861)
			(xy 332.118208 -321.100704) (xy 331.936598 -323.357748) (xy 331.936344 -323.361812) (xy 331.936344 -323.416168)
			(xy 331.936229 -323.421123) (xy 331.934317 -323.430847) (xy 331.932534 -323.435472) (xy 331.929486 -323.442838)
			(xy 331.910944 -323.671692) (xy 331.906546 -323.719362) (xy 331.889676 -323.813602) (xy 331.863762 -323.905766)
			(xy 331.846936 -323.950584) (xy 331.84338 -323.959474) (xy 331.84338 -324.074282) (xy 331.843864 -324.084294)
			(xy 331.85152 -324.102795) (xy 331.865673 -324.116959) (xy 331.884169 -324.124628) (xy 331.89418 -324.125082)
			(xy 331.910436 -324.125082) (xy 331.936852 -324.106286) (xy 331.942186 -324.091046) (xy 331.951231 -324.066502)
			(xy 331.975095 -324.019955) (xy 332.005102 -323.97711) (xy 332.040686 -323.938771) (xy 332.081179 -323.905659)
			(xy 332.125821 -323.878397) (xy 332.173771 -323.857496) (xy 332.22413 -323.843349) (xy 332.27595 -323.836223)
			(xy 332.302104 -323.835776) (xy 332.329356 -323.836262) (xy 332.383306 -323.844019) (xy 332.435602 -323.859376)
			(xy 332.485181 -323.882018) (xy 332.531033 -323.911485) (xy 332.572224 -323.947178) (xy 332.607917 -323.98837)
			(xy 332.637384 -324.034222) (xy 332.660026 -324.083802) (xy 332.675381 -324.136098) (xy 332.683138 -324.190048)
			(xy 332.683138 -324.244552) (xy 332.675381 -324.298502) (xy 332.660026 -324.350798) (xy 332.637384 -324.400378)
			(xy 332.607917 -324.44623) (xy 332.572224 -324.487422) (xy 332.531033 -324.523115) (xy 332.485181 -324.552582)
			(xy 332.435602 -324.575224) (xy 332.383306 -324.590581) (xy 332.329356 -324.598338) (xy 332.302104 -324.598792)
			(xy 332.275785 -324.59837) (xy 332.223643 -324.591169) (xy 332.172987 -324.576863) (xy 332.124781 -324.555723)
			(xy 332.079943 -324.528151) (xy 332.039324 -324.494672) (xy 332.02118 -324.475602) (xy 332.013814 -324.467474)
			(xy 331.994764 -324.459092) (xy 331.978254 -324.459092) (xy 331.973569 -324.459249) (xy 331.964369 -324.461039)
			(xy 331.959966 -324.462648) (xy 331.875892 -324.49516) (xy 331.866494 -324.499267) (xy 331.851774 -324.513522)
			(xy 331.843828 -324.53241) (xy 331.84338 -324.542658) (xy 331.84338 -325.6153) (xy 331.843813 -325.624977)
			(xy 331.850977 -325.642958) (xy 331.86426 -325.657037) (xy 331.872844 -325.661528) (xy 331.97038 -325.706232)
			(xy 331.99959 -325.702168) (xy 332.01102 -325.692262) (xy 332.031863 -325.675049) (xy 332.077483 -325.646053)
			(xy 332.126736 -325.623779) (xy 332.178637 -325.608672) (xy 332.23215 -325.601033) (xy 332.259178 -325.600568)
			(xy 332.259686 -325.600568) (xy 332.290773 -325.6012) (xy 332.35212 -325.611309) (xy 332.411023 -325.631213)
			(xy 332.438756 -325.645272) (xy 332.451587 -325.651559) (xy 332.479527 -325.657474) (xy 332.508013 -325.655421)
			(xy 332.534816 -325.645559) (xy 332.55784 -325.628659) (xy 332.575282 -325.606045) (xy 332.580996 -325.592948)
			(xy 332.591933 -325.566553) (xy 332.620505 -325.517079) (xy 332.65613 -325.472414) (xy 332.698012 -325.433556)
			(xy 332.745217 -325.401373) (xy 332.796691 -325.376583) (xy 332.851283 -325.359739) (xy 332.907776 -325.351217)
			(xy 332.936342 -325.350632) (xy 332.96361 -325.351121) (xy 333.01759 -325.358888) (xy 333.069915 -325.374257)
			(xy 333.119521 -325.396916) (xy 333.165397 -325.426404) (xy 333.20661 -325.462119) (xy 333.242322 -325.503337)
			(xy 333.271804 -325.549216) (xy 333.294458 -325.598824) (xy 333.309821 -325.651151) (xy 333.317582 -325.705132)
			(xy 333.317582 -325.759668) (xy 333.309821 -325.813649) (xy 333.294458 -325.865976) (xy 333.271804 -325.915584)
			(xy 333.242322 -325.961463) (xy 333.20661 -326.002681) (xy 333.165397 -326.038396) (xy 333.119521 -326.067884)
			(xy 333.069915 -326.090543) (xy 333.01759 -326.105912) (xy 332.96361 -326.113679) (xy 332.936342 -326.114156)
			(xy 332.935834 -326.114156) (xy 332.904747 -326.113525) (xy 332.843398 -326.10342) (xy 332.784493 -326.083519)
			(xy 332.756764 -326.069452) (xy 332.743933 -326.063161) (xy 332.71599 -326.057239) (xy 332.6875 -326.059289)
			(xy 332.660692 -326.06915) (xy 332.637666 -326.086052) (xy 332.620222 -326.108671) (xy 332.614524 -326.121776)
			(xy 332.603591 -326.148176) (xy 332.575025 -326.19766) (xy 332.539404 -326.242336) (xy 332.497523 -326.281204)
			(xy 332.450318 -326.313396) (xy 332.398842 -326.338195) (xy 332.344245 -326.355046) (xy 332.287747 -326.363572)
			(xy 332.259178 -326.364092) (xy 332.232747 -326.363641) (xy 332.180392 -326.35634) (xy 332.129547 -326.34188)
			(xy 332.081185 -326.320539) (xy 332.036232 -326.292725) (xy 332.015592 -326.276208) (xy 332.010004 -326.271636)
			(xy 331.996288 -326.26554) (xy 331.98616 -326.261609) (xy 331.964454 -326.261734) (xy 331.954378 -326.265794)
			(xy 331.873098 -326.303132) (xy 331.865986 -326.306942) (xy 331.856688 -326.313832) (xy 331.845052 -326.33381)
			(xy 331.843634 -326.345296) (xy 331.84338 -326.34936) (xy 331.84338 -327.081134) (xy 331.843842 -327.09101)
			(xy 331.851287 -327.109307) (xy 331.857858 -327.116694) (xy 331.858112 -327.116948) (xy 332.065376 -327.324212)
			(xy 332.065884 -327.32472) (xy 332.073265 -327.331301) (xy 332.091565 -327.338745) (xy 332.101444 -327.339198)
			(xy 349.56242 -327.339198)
		)
		(stroke
			(width 0)
			(type solid)
		)
		(fill yes)
		(layer "In15.Cu")
		(net "P0V8_SERDES_VDDA_PEX2")
	)
	(gr_poly
		(pts
			(xy 205.504288 -167.694356) (xy 205.504796 -167.694356) (xy 205.512318 -167.692762) (xy 205.526019 -167.685798)
			(xy 205.53172 -167.68064) (xy 211.905342 -161.307018) (xy 211.912742 -161.300176) (xy 211.93134 -161.292454)
			(xy 211.94141 -161.292032) (xy 213.623906 -161.292032) (xy 213.633976 -161.291609) (xy 213.652582 -161.283896)
			(xy 213.659974 -161.277046) (xy 213.724998 -161.212022) (xy 213.741307 -161.196005) (xy 213.776018 -161.166254)
			(xy 213.79434 -161.152586) (xy 213.797388 -161.150554) (xy 213.893908 -161.054034) (xy 213.901252 -161.047221)
			(xy 213.919715 -161.039486) (xy 213.929722 -161.039048) (xy 216.469722 -161.039048) (xy 216.481409 -161.038404)
			(xy 216.502316 -161.027938) (xy 216.509854 -161.018982) (xy 216.511632 -161.016696) (xy 216.549224 -160.96107)
			(xy 216.553204 -160.95471) (xy 216.557605 -160.940374) (xy 216.55786 -160.932876) (xy 216.55786 -160.909254)
			(xy 216.554812 -160.900872) (xy 216.543938 -160.86901) (xy 216.532304 -160.802706) (xy 216.531698 -160.769046)
			(xy 216.531698 -160.764474) (xy 216.531923 -160.754287) (xy 216.533323 -160.733956) (xy 216.534492 -160.723834)
			(xy 216.538099 -160.697778) (xy 216.551559 -160.646926) (xy 216.571889 -160.598411) (xy 216.598702 -160.553155)
			(xy 216.614756 -160.532318) (xy 216.62009 -160.52546) (xy 216.62263 -160.51784) (xy 216.623998 -160.513782)
			(xy 216.625523 -160.505356) (xy 216.625678 -160.501076) (xy 216.625678 -160.479232) (xy 216.625825 -160.473793)
			(xy 216.628138 -160.463164) (xy 216.63025 -160.45815) (xy 216.631012 -160.456626) (xy 216.633469 -160.451299)
			(xy 216.636154 -160.439883) (xy 216.636346 -160.43402) (xy 216.636346 -160.416748) (xy 216.636072 -160.408785)
			(xy 216.631145 -160.39364) (xy 216.626694 -160.38703) (xy 216.624154 -160.383982) (xy 216.619836 -160.378902)
			(xy 216.619582 -160.378648) (xy 216.603054 -160.358018) (xy 216.575246 -160.313061) (xy 216.553912 -160.264696)
			(xy 216.53946 -160.213849) (xy 216.532167 -160.161493) (xy 216.531698 -160.135062) (xy 216.532184 -160.107811)
			(xy 216.53994 -160.053863) (xy 216.555295 -160.001568) (xy 216.577937 -159.951991) (xy 216.607403 -159.906141)
			(xy 216.643094 -159.86495) (xy 216.684285 -159.829259) (xy 216.730135 -159.799793) (xy 216.779712 -159.777151)
			(xy 216.832007 -159.761796) (xy 216.885955 -159.75404) (xy 216.940457 -159.75404) (xy 216.994405 -159.761796)
			(xy 217.0467 -159.777151) (xy 217.096277 -159.799793) (xy 217.142127 -159.829259) (xy 217.183318 -159.86495)
			(xy 217.219009 -159.906141) (xy 217.248475 -159.951991) (xy 217.25718 -159.971051) (xy 232.232178 -159.971051)
			(xy 232.232178 -159.916549) (xy 232.239934 -159.862601) (xy 232.255289 -159.810306) (xy 232.277931 -159.760729)
			(xy 232.307397 -159.714879) (xy 232.343088 -159.673688) (xy 232.384279 -159.637997) (xy 232.430129 -159.608531)
			(xy 232.479706 -159.585889) (xy 232.532001 -159.570534) (xy 232.585949 -159.562778) (xy 232.6132 -159.562292)
			(xy 232.64057 -159.56276) (xy 232.694749 -159.570578) (xy 232.747252 -159.586066) (xy 232.796999 -159.608908)
			(xy 232.842966 -159.638631) (xy 232.863898 -159.656272) (xy 232.864152 -159.656526) (xy 232.871246 -159.662102)
			(xy 232.888157 -159.668354) (xy 232.897172 -159.668718) (xy 232.964228 -159.668718) (xy 232.973246 -159.668371)
			(xy 232.990163 -159.662116) (xy 232.997248 -159.656526) (xy 232.997248 -159.656272) (xy 232.997502 -159.656272)
			(xy 233.018419 -159.638614) (xy 233.064396 -159.608906) (xy 233.114148 -159.586074) (xy 233.166652 -159.570587)
			(xy 233.22083 -159.562764) (xy 233.2482 -159.562292) (xy 233.275451 -159.562778) (xy 233.329399 -159.570534)
			(xy 233.381694 -159.585889) (xy 233.431271 -159.608531) (xy 233.477121 -159.637997) (xy 233.518312 -159.673688)
			(xy 233.554003 -159.714879) (xy 233.583469 -159.760729) (xy 233.606111 -159.810306) (xy 233.616296 -159.844994)
			(xy 238.850168 -159.844994) (xy 238.854239 -159.789372) (xy 238.866365 -159.734935) (xy 238.886288 -159.682844)
			(xy 238.913584 -159.634209) (xy 238.94767 -159.590066) (xy 238.987819 -159.551357) (xy 239.033177 -159.518906)
			(xy 239.082777 -159.493405) (xy 239.135561 -159.475398) (xy 239.190404 -159.465268) (xy 239.246138 -159.463231)
			(xy 239.301575 -159.469331) (xy 239.355532 -159.483437) (xy 239.406861 -159.505249) (xy 239.454467 -159.534303)
			(xy 239.497335 -159.569978) (xy 239.534552 -159.611515) (xy 239.565325 -159.658028) (xy 239.588997 -159.708525)
			(xy 239.605065 -159.761932) (xy 239.613185 -159.817108) (xy 239.613694 -159.844994) (xy 239.613185 -159.87288)
			(xy 239.605065 -159.928056) (xy 239.588997 -159.981463) (xy 239.565325 -160.03196) (xy 239.534552 -160.078473)
			(xy 239.497335 -160.12001) (xy 239.454467 -160.155685) (xy 239.406861 -160.184739) (xy 239.355532 -160.206551)
			(xy 239.301575 -160.220657) (xy 239.246138 -160.226757) (xy 239.190404 -160.22472) (xy 239.135561 -160.21459)
			(xy 239.082777 -160.196583) (xy 239.033177 -160.171082) (xy 238.987819 -160.138631) (xy 238.94767 -160.099922)
			(xy 238.913584 -160.055779) (xy 238.886288 -160.007144) (xy 238.866365 -159.955053) (xy 238.854239 -159.900616)
			(xy 238.850168 -159.844994) (xy 233.616296 -159.844994) (xy 233.621466 -159.862601) (xy 233.629222 -159.916549)
			(xy 233.629222 -159.971051) (xy 233.621466 -160.024999) (xy 233.606111 -160.077294) (xy 233.583469 -160.126871)
			(xy 233.554003 -160.172721) (xy 233.518312 -160.213912) (xy 233.477121 -160.249603) (xy 233.431271 -160.279069)
			(xy 233.381694 -160.301711) (xy 233.329399 -160.317066) (xy 233.275451 -160.324822) (xy 233.2482 -160.325308)
			(xy 233.22083 -160.32484) (xy 233.166651 -160.317022) (xy 233.114148 -160.301534) (xy 233.064401 -160.278692)
			(xy 233.018434 -160.248969) (xy 232.997502 -160.231328) (xy 232.997248 -160.231074) (xy 232.990154 -160.225498)
			(xy 232.973243 -160.219246) (xy 232.964228 -160.218882) (xy 232.897172 -160.218882) (xy 232.888154 -160.219229)
			(xy 232.871237 -160.225484) (xy 232.864152 -160.231074) (xy 232.864152 -160.231328) (xy 232.863898 -160.231328)
			(xy 232.842981 -160.248986) (xy 232.797004 -160.278694) (xy 232.747252 -160.301526) (xy 232.694748 -160.317013)
			(xy 232.64057 -160.324836) (xy 232.6132 -160.325308) (xy 232.585949 -160.324822) (xy 232.532001 -160.317066)
			(xy 232.479706 -160.301711) (xy 232.430129 -160.279069) (xy 232.384279 -160.249603) (xy 232.343088 -160.213912)
			(xy 232.307397 -160.172721) (xy 232.277931 -160.126871) (xy 232.255289 -160.077294) (xy 232.239934 -160.024999)
			(xy 232.232178 -159.971051) (xy 217.25718 -159.971051) (xy 217.271117 -160.001568) (xy 217.286472 -160.053863)
			(xy 217.294228 -160.107811) (xy 217.294714 -160.135062) (xy 217.294714 -160.13557) (xy 217.294286 -160.161197)
			(xy 217.28739 -160.211984) (xy 217.273747 -160.261389) (xy 217.253602 -160.308517) (xy 217.227319 -160.352519)
			(xy 217.211656 -160.372806) (xy 217.206322 -160.379664) (xy 217.203782 -160.387284) (xy 217.202407 -160.391341)
			(xy 217.200869 -160.399767) (xy 217.200734 -160.404048) (xy 217.200734 -160.425892) (xy 217.200594 -160.431332)
			(xy 217.198292 -160.441966) (xy 217.196162 -160.446974) (xy 217.19159 -160.456118) (xy 217.186755 -160.465449)
			(xy 217.184297 -160.486298) (xy 217.190332 -160.506406) (xy 217.19667 -160.514792) (xy 217.199464 -160.518094)
			(xy 217.20556 -160.525206) (xy 217.206576 -160.526222) (xy 217.20937 -160.530032) (xy 217.228382 -160.554431)
			(xy 217.259088 -160.608124) (xy 217.280745 -160.666061) (xy 217.29279 -160.726729) (xy 217.29446 -160.757616)
			(xy 217.294714 -160.770062) (xy 217.294714 -160.770824) (xy 217.294284 -160.79436) (xy 217.28837 -160.841063)
			(xy 217.276769 -160.886686) (xy 217.268552 -160.908746) (xy 217.266266 -160.914588) (xy 217.264742 -160.92678)
			(xy 217.26525 -160.932622) (xy 217.26611 -160.938719) (xy 217.270343 -160.950277) (xy 217.273632 -160.955482)
			(xy 217.28049 -160.965388) (xy 217.316812 -161.019236) (xy 217.319098 -161.022284) (xy 217.326304 -161.029611)
			(xy 217.34492 -161.038269) (xy 217.355166 -161.039048) (xy 222.910146 -161.039048) (xy 222.919041 -161.038604)
			(xy 222.935726 -161.032416) (xy 222.949296 -161.020904) (xy 222.954088 -161.013394) (xy 222.983806 -160.956244)
			(xy 222.985915 -160.951296) (xy 222.988222 -160.940792) (xy 222.988378 -160.935416) (xy 222.988378 -160.902904)
			(xy 222.988313 -160.899097) (xy 222.98717 -160.89157) (xy 222.986092 -160.887918) (xy 222.984314 -160.882076)
			(xy 222.98025 -160.875726) (xy 222.965703 -160.852449) (xy 222.942723 -160.802603) (xy 222.927138 -160.749974)
			(xy 222.919271 -160.695652) (xy 222.918782 -160.668208) (xy 222.919268 -160.640957) (xy 222.927024 -160.587009)
			(xy 222.942379 -160.534714) (xy 222.965021 -160.485137) (xy 222.994487 -160.439287) (xy 223.030178 -160.398096)
			(xy 223.071369 -160.362405) (xy 223.117219 -160.332939) (xy 223.166796 -160.310297) (xy 223.219091 -160.294942)
			(xy 223.273039 -160.287186) (xy 223.327541 -160.287186) (xy 223.381489 -160.294942) (xy 223.433784 -160.310297)
			(xy 223.483361 -160.332939) (xy 223.529211 -160.362405) (xy 223.570402 -160.398096) (xy 223.606093 -160.439287)
			(xy 223.635559 -160.485137) (xy 223.658201 -160.534714) (xy 223.673556 -160.587009) (xy 223.681312 -160.640957)
			(xy 223.681798 -160.668208) (xy 223.681273 -160.696641) (xy 223.672831 -160.752877) (xy 223.656134 -160.807236)
			(xy 223.631554 -160.858515) (xy 223.616012 -160.88233) (xy 223.612202 -160.887918) (xy 223.602804 -160.916874)
			(xy 223.602974 -160.923027) (xy 223.605927 -160.934974) (xy 223.608646 -160.940496) (xy 223.63811 -160.99663)
			(xy 223.63811 -160.997138) (xy 223.646238 -161.012124) (xy 223.650906 -161.020013) (xy 223.664668 -161.0321)
			(xy 223.681786 -161.038619) (xy 223.690942 -161.039048) (xy 233.874564 -161.039048) (xy 233.881676 -161.03854)
			(xy 233.889299 -161.037141) (xy 233.903253 -161.030412) (xy 233.909108 -161.025332) (xy 233.950002 -160.986978)
			(xy 233.957368 -160.979866) (xy 233.965496 -160.961832) (xy 233.966258 -160.953196) (xy 233.966258 -160.952434)
			(xy 233.9687 -160.923832) (xy 233.981087 -160.867782) (xy 234.001734 -160.814222) (xy 234.030174 -160.76436)
			(xy 234.065765 -160.719324) (xy 234.107703 -160.68013) (xy 234.155042 -160.647663) (xy 234.206711 -160.622656)
			(xy 234.261544 -160.605676) (xy 234.318303 -160.597104) (xy 234.347004 -160.59658) (xy 234.375656 -160.597087)
			(xy 234.432318 -160.605641) (xy 234.487065 -160.62257) (xy 234.538664 -160.647495) (xy 234.585957 -160.679855)
			(xy 234.598289 -160.691347) (xy 239.187022 -160.691347) (xy 239.187022 -160.636853) (xy 239.194777 -160.582914)
			(xy 239.210129 -160.530627) (xy 239.232766 -160.481058) (xy 239.262226 -160.435214) (xy 239.297911 -160.394029)
			(xy 239.339093 -160.358342) (xy 239.384935 -160.328878) (xy 239.434503 -160.306238) (xy 239.486789 -160.290883)
			(xy 239.540727 -160.283124) (xy 239.567974 -160.282636) (xy 239.594502 -160.283086) (xy 239.647047 -160.290421)
			(xy 239.698069 -160.304967) (xy 239.746583 -160.326443) (xy 239.791653 -160.354435) (xy 239.832409 -160.388402)
			(xy 239.868064 -160.427689) (xy 239.897931 -160.471539) (xy 239.921434 -160.519104) (xy 239.938118 -160.569467)
			(xy 239.947662 -160.621657) (xy 239.949228 -160.648142) (xy 239.950231 -160.662657) (xy 239.959576 -160.690203)
			(xy 239.976316 -160.713991) (xy 239.999091 -160.732086) (xy 240.026047 -160.743015) (xy 240.054993 -160.745891)
			(xy 240.06937 -160.743646) (xy 240.086858 -160.740549) (xy 240.122223 -160.737244) (xy 240.139982 -160.737042)
			(xy 240.140236 -160.737042) (xy 240.167489 -160.73743) (xy 240.22144 -160.745192) (xy 240.273737 -160.760552)
			(xy 240.323316 -160.783198) (xy 240.369168 -160.81267) (xy 240.41036 -160.848366) (xy 240.446052 -160.88956)
			(xy 240.475519 -160.935415) (xy 240.489438 -160.965896) (xy 241.137692 -160.965896) (xy 241.141763 -160.910274)
			(xy 241.153889 -160.855837) (xy 241.173812 -160.803746) (xy 241.201108 -160.755111) (xy 241.235194 -160.710968)
			(xy 241.275343 -160.672259) (xy 241.320701 -160.639808) (xy 241.370301 -160.614307) (xy 241.423085 -160.5963)
			(xy 241.477928 -160.58617) (xy 241.533662 -160.584133) (xy 241.589099 -160.590233) (xy 241.643056 -160.604339)
			(xy 241.694385 -160.626151) (xy 241.741991 -160.655205) (xy 241.784859 -160.69088) (xy 241.822076 -160.732417)
			(xy 241.852849 -160.77893) (xy 241.876521 -160.829427) (xy 241.892589 -160.882834) (xy 241.900709 -160.93801)
			(xy 241.901181 -160.963864) (xy 242.529612 -160.963864) (xy 242.533683 -160.908242) (xy 242.545809 -160.853805)
			(xy 242.565732 -160.801714) (xy 242.593028 -160.753079) (xy 242.627114 -160.708936) (xy 242.667263 -160.670227)
			(xy 242.712621 -160.637776) (xy 242.762221 -160.612275) (xy 242.815005 -160.594268) (xy 242.869848 -160.584138)
			(xy 242.925582 -160.582101) (xy 242.981019 -160.588201) (xy 243.034976 -160.602307) (xy 243.086305 -160.624119)
			(xy 243.133911 -160.653173) (xy 243.176779 -160.688848) (xy 243.213996 -160.730385) (xy 243.244769 -160.776898)
			(xy 243.268441 -160.827395) (xy 243.284509 -160.880802) (xy 243.292629 -160.935978) (xy 243.293138 -160.963864)
			(xy 243.293045 -160.968944) (xy 243.80139 -160.968944) (xy 243.805461 -160.913322) (xy 243.817587 -160.858885)
			(xy 243.83751 -160.806794) (xy 243.864806 -160.758159) (xy 243.898892 -160.714016) (xy 243.939041 -160.675307)
			(xy 243.984399 -160.642856) (xy 244.033999 -160.617355) (xy 244.086783 -160.599348) (xy 244.141626 -160.589218)
			(xy 244.19736 -160.587181) (xy 244.252797 -160.593281) (xy 244.306754 -160.607387) (xy 244.358083 -160.629199)
			(xy 244.405689 -160.658253) (xy 244.448557 -160.693928) (xy 244.485774 -160.735465) (xy 244.516547 -160.781978)
			(xy 244.540219 -160.832475) (xy 244.556287 -160.885882) (xy 244.55868 -160.902142) (xy 245.582692 -160.902142)
			(xy 245.586763 -160.84652) (xy 245.598889 -160.792083) (xy 245.618812 -160.739992) (xy 245.646108 -160.691357)
			(xy 245.680194 -160.647214) (xy 245.720343 -160.608505) (xy 245.765701 -160.576054) (xy 245.815301 -160.550553)
			(xy 245.868085 -160.532546) (xy 245.922928 -160.522416) (xy 245.978662 -160.520379) (xy 246.034099 -160.526479)
			(xy 246.088056 -160.540585) (xy 246.139385 -160.562397) (xy 246.186991 -160.591451) (xy 246.229859 -160.627126)
			(xy 246.267076 -160.668663) (xy 246.297849 -160.715176) (xy 246.321521 -160.765673) (xy 246.337589 -160.81908)
			(xy 246.345709 -160.874256) (xy 246.346218 -160.902142) (xy 246.345709 -160.930028) (xy 246.337589 -160.985204)
			(xy 246.321521 -161.038611) (xy 246.297849 -161.089108) (xy 246.267076 -161.135621) (xy 246.229859 -161.177158)
			(xy 246.186991 -161.212833) (xy 246.139385 -161.241887) (xy 246.088056 -161.263699) (xy 246.034099 -161.277805)
			(xy 245.978662 -161.283905) (xy 245.922928 -161.281868) (xy 245.868085 -161.271738) (xy 245.815301 -161.253731)
			(xy 245.765701 -161.22823) (xy 245.720343 -161.195779) (xy 245.680194 -161.15707) (xy 245.646108 -161.112927)
			(xy 245.618812 -161.064292) (xy 245.598889 -161.012201) (xy 245.586763 -160.957764) (xy 245.582692 -160.902142)
			(xy 244.55868 -160.902142) (xy 244.564407 -160.941058) (xy 244.564916 -160.968944) (xy 244.564407 -160.99683)
			(xy 244.556287 -161.052006) (xy 244.540219 -161.105413) (xy 244.516547 -161.15591) (xy 244.485774 -161.202423)
			(xy 244.448557 -161.24396) (xy 244.405689 -161.279635) (xy 244.358083 -161.308689) (xy 244.306754 -161.330501)
			(xy 244.252797 -161.344607) (xy 244.19736 -161.350707) (xy 244.141626 -161.34867) (xy 244.086783 -161.33854)
			(xy 244.033999 -161.320533) (xy 243.984399 -161.295032) (xy 243.939041 -161.262581) (xy 243.898892 -161.223872)
			(xy 243.864806 -161.179729) (xy 243.83751 -161.131094) (xy 243.817587 -161.079003) (xy 243.805461 -161.024566)
			(xy 243.80139 -160.968944) (xy 243.293045 -160.968944) (xy 243.292629 -160.99175) (xy 243.284509 -161.046926)
			(xy 243.268441 -161.100333) (xy 243.244769 -161.15083) (xy 243.213996 -161.197343) (xy 243.176779 -161.23888)
			(xy 243.133911 -161.274555) (xy 243.086305 -161.303609) (xy 243.034976 -161.325421) (xy 242.981019 -161.339527)
			(xy 242.925582 -161.345627) (xy 242.869848 -161.34359) (xy 242.815005 -161.33346) (xy 242.762221 -161.315453)
			(xy 242.712621 -161.289952) (xy 242.667263 -161.257501) (xy 242.627114 -161.218792) (xy 242.593028 -161.174649)
			(xy 242.565732 -161.126014) (xy 242.545809 -161.073923) (xy 242.533683 -161.019486) (xy 242.529612 -160.963864)
			(xy 241.901181 -160.963864) (xy 241.901218 -160.965896) (xy 241.900709 -160.993782) (xy 241.892589 -161.048958)
			(xy 241.876521 -161.102365) (xy 241.852849 -161.152862) (xy 241.822076 -161.199375) (xy 241.784859 -161.240912)
			(xy 241.741991 -161.276587) (xy 241.694385 -161.305641) (xy 241.643056 -161.327453) (xy 241.589099 -161.341559)
			(xy 241.533662 -161.347659) (xy 241.477928 -161.345622) (xy 241.423085 -161.335492) (xy 241.370301 -161.317485)
			(xy 241.320701 -161.291984) (xy 241.275343 -161.259533) (xy 241.235194 -161.220824) (xy 241.201108 -161.176681)
			(xy 241.173812 -161.128046) (xy 241.153889 -161.075955) (xy 241.141763 -161.021518) (xy 241.137692 -160.965896)
			(xy 240.489438 -160.965896) (xy 240.49816 -160.984996) (xy 240.513516 -161.037295) (xy 240.521272 -161.091247)
			(xy 240.521272 -161.145753) (xy 240.513516 -161.199705) (xy 240.49816 -161.252004) (xy 240.475519 -161.301585)
			(xy 240.446052 -161.34744) (xy 240.41036 -161.388634) (xy 240.369168 -161.42433) (xy 240.323316 -161.453802)
			(xy 240.273737 -161.476448) (xy 240.22144 -161.491808) (xy 240.167489 -161.49957) (xy 240.140236 -161.500058)
			(xy 240.113708 -161.499604) (xy 240.061163 -161.492271) (xy 240.010141 -161.477726) (xy 239.961626 -161.456251)
			(xy 239.916556 -161.428259) (xy 239.8758 -161.394292) (xy 239.840144 -161.355005) (xy 239.810277 -161.311156)
			(xy 239.786775 -161.26359) (xy 239.770091 -161.213227) (xy 239.760548 -161.161037) (xy 239.758982 -161.134552)
			(xy 239.757972 -161.120038) (xy 239.748627 -161.092494) (xy 239.731888 -161.068707) (xy 239.709115 -161.050613)
			(xy 239.68216 -161.039682) (xy 239.653217 -161.036805) (xy 239.63884 -161.039048) (xy 239.621351 -161.042143)
			(xy 239.585987 -161.04545) (xy 239.568228 -161.045652) (xy 239.567974 -161.045652) (xy 239.540727 -161.045076)
			(xy 239.486789 -161.037317) (xy 239.434503 -161.021962) (xy 239.384935 -160.999322) (xy 239.339093 -160.969858)
			(xy 239.297911 -160.934171) (xy 239.262226 -160.892986) (xy 239.232766 -160.847142) (xy 239.210129 -160.797573)
			(xy 239.194777 -160.745286) (xy 239.187022 -160.691347) (xy 234.598289 -160.691347) (xy 234.62788 -160.718922)
			(xy 234.663491 -160.763818) (xy 234.691988 -160.813534) (xy 234.712732 -160.866952) (xy 234.725255 -160.922871)
			(xy 234.72775 -160.951418) (xy 234.728258 -160.962086) (xy 234.73664 -160.98012) (xy 234.743752 -160.986724)
			(xy 234.744006 -160.986978) (xy 234.785154 -161.025332) (xy 234.788774 -161.028522) (xy 234.796958 -161.033632)
			(xy 234.80141 -161.035492) (xy 234.810554 -161.039048) (xy 238.995712 -161.039048) (xy 239.005697 -161.039589)
			(xy 239.024122 -161.047311) (xy 239.031526 -161.054034) (xy 239.034828 -161.057336) (xy 239.065398 -161.065566)
			(xy 239.124718 -161.087689) (xy 239.181337 -161.11602) (xy 239.234606 -161.150236) (xy 239.283917 -161.189945)
			(xy 239.306608 -161.212022) (xy 241.507772 -163.413186) (xy 241.515174 -163.420022) (xy 241.533772 -163.427733)
			(xy 241.54384 -163.428172) (xy 248.207276 -163.428172) (xy 248.215911 -163.427829) (xy 248.232192 -163.422069)
			(xy 248.245615 -163.411202) (xy 248.250456 -163.404042) (xy 248.261632 -163.386262) (xy 248.261632 -163.385754)
			(xy 248.297954 -163.326572) (xy 248.297954 -163.31184) (xy 248.2977 -163.29914) (xy 248.292366 -163.28898)
			(xy 248.279096 -163.261871) (xy 248.260325 -163.204511) (xy 248.250802 -163.144913) (xy 248.250202 -163.114736)
			(xy 248.250688 -163.087485) (xy 248.258444 -163.033537) (xy 248.273799 -162.981242) (xy 248.296441 -162.931665)
			(xy 248.325907 -162.885815) (xy 248.361598 -162.844624) (xy 248.402789 -162.808933) (xy 248.448639 -162.779467)
			(xy 248.498216 -162.756825) (xy 248.550511 -162.74147) (xy 248.604459 -162.733714) (xy 248.658961 -162.733714)
			(xy 248.712909 -162.74147) (xy 248.765204 -162.756825) (xy 248.814781 -162.779467) (xy 248.860631 -162.808933)
			(xy 248.901822 -162.844624) (xy 248.937513 -162.885815) (xy 248.966979 -162.931665) (xy 248.989621 -162.981242)
			(xy 249.004976 -163.033537) (xy 249.012732 -163.087485) (xy 249.013218 -163.114736) (xy 249.012647 -163.144915)
			(xy 249.003133 -163.204518) (xy 248.984335 -163.261874) (xy 248.971054 -163.28898) (xy 248.968271 -163.294877)
			(xy 248.965449 -163.307605) (xy 248.965466 -163.314126) (xy 248.965974 -163.32708) (xy 248.96699 -163.328858)
			(xy 249.01271 -163.403788) (xy 249.017531 -163.41104) (xy 249.031035 -163.422015) (xy 249.047442 -163.427815)
			(xy 249.056144 -163.428172) (xy 252.742192 -163.428172) (xy 252.749304 -163.42233) (xy 253.674118 -162.49777)
			(xy 253.679104 -162.49227) (xy 253.685944 -162.479103) (xy 253.68758 -162.471862) (xy 253.688596 -162.46221)
			(xy 253.688596 -158.941008) (xy 253.689018 -158.930937) (xy 253.69673 -158.91233) (xy 253.703582 -158.90494)
			(xy 254.188722 -158.4198) (xy 254.193911 -158.414165) (xy 254.201021 -158.400605) (xy 254.202692 -158.39313)
			(xy 254.203962 -158.385764) (xy 254.20193 -158.370524) (xy 254.198628 -158.363158) (xy 254.186056 -158.334524)
			(xy 254.16638 -158.27516) (xy 254.153127 -158.21404) (xy 254.146448 -158.151858) (xy 254.14605 -158.120588)
			(xy 254.14605 -158.120334) (xy 254.146509 -158.087437) (xy 254.153872 -158.022056) (xy 254.168509 -157.957911)
			(xy 254.190235 -157.895808) (xy 254.218779 -157.836528) (xy 254.25378 -157.780816) (xy 254.294798 -157.729374)
			(xy 254.317754 -157.705806) (xy 254.632206 -157.391354) (xy 254.639602 -157.384503) (xy 254.658201 -157.376762)
			(xy 254.668274 -157.376368) (xy 256.359406 -157.376368) (xy 256.366027 -157.375221) (xy 256.378379 -157.369939)
			(xy 256.38379 -157.365954) (xy 269.913354 -143.83639) (xy 269.917357 -143.83099) (xy 269.922631 -143.818631)
			(xy 269.923768 -143.812006) (xy 269.923768 -139.859512) (xy 269.924188 -139.84944) (xy 269.931896 -139.83083)
			(xy 269.938754 -139.823444) (xy 275.561044 -134.201154) (xy 275.568442 -134.194309) (xy 275.587041 -134.186582)
			(xy 275.597112 -134.186168) (xy 280.269188 -134.186168) (xy 280.27926 -134.186588) (xy 280.29787 -134.194296)
			(xy 280.305256 -134.201154) (xy 281.000454 -134.896352) (xy 285.8389 -134.896352) (xy 285.8389 -134.032752)
			(xy 285.83939 -134.002768) (xy 285.847218 -133.943312) (xy 285.862739 -133.885387) (xy 285.885688 -133.829983)
			(xy 285.915672 -133.778049) (xy 285.952178 -133.730473) (xy 285.994583 -133.688068) (xy 286.042159 -133.651562)
			(xy 286.094093 -133.621578) (xy 286.149497 -133.598629) (xy 286.207422 -133.583108) (xy 286.266878 -133.57528)
			(xy 286.326846 -133.57528) (xy 286.386302 -133.583108) (xy 286.444227 -133.598629) (xy 286.499631 -133.621578)
			(xy 286.551565 -133.651562) (xy 286.599141 -133.688068) (xy 286.641546 -133.730473) (xy 286.678052 -133.778049)
			(xy 286.708036 -133.829983) (xy 286.730985 -133.885387) (xy 286.746506 -133.943312) (xy 286.754334 -134.002768)
			(xy 286.754824 -134.032752) (xy 286.754824 -134.896352) (xy 286.754334 -134.926336) (xy 286.746506 -134.985792)
			(xy 286.730985 -135.043717) (xy 286.708036 -135.099121) (xy 286.678052 -135.151055) (xy 286.641546 -135.198631)
			(xy 286.599141 -135.241036) (xy 286.551565 -135.277542) (xy 286.499631 -135.307526) (xy 286.444227 -135.330475)
			(xy 286.386302 -135.345996) (xy 286.326846 -135.353824) (xy 286.266878 -135.353824) (xy 286.207422 -135.345996)
			(xy 286.149497 -135.330475) (xy 286.094093 -135.307526) (xy 286.042159 -135.277542) (xy 285.994583 -135.241036)
			(xy 285.952178 -135.198631) (xy 285.915672 -135.151055) (xy 285.885688 -135.099121) (xy 285.862739 -135.043717)
			(xy 285.847218 -134.985792) (xy 285.83939 -134.926336) (xy 285.8389 -134.896352) (xy 281.000454 -134.896352)
			(xy 283.146246 -137.042144) (xy 283.153128 -137.047176) (xy 283.169223 -137.052767) (xy 283.177742 -137.053066)
			(xy 283.426916 -137.053066) (xy 283.433893 -137.052823) (xy 283.447305 -137.048967) (xy 283.453332 -137.045446)
			(xy 283.454348 -137.044938) (xy 283.454602 -137.044684) (xy 283.462222 -137.039858) (xy 283.468318 -137.03427)
			(xy 283.474668 -137.028682) (xy 283.482034 -137.015474) (xy 283.48305 -137.013188) (xy 283.494532 -136.987966)
			(xy 283.52371 -136.940854) (xy 283.559398 -136.89846) (xy 283.600845 -136.861676) (xy 283.647178 -136.831276)
			(xy 283.697422 -136.807901) (xy 283.75052 -136.792041) (xy 283.805354 -136.784032) (xy 283.833062 -136.783572)
			(xy 283.833824 -136.783572) (xy 283.856329 -136.783934) (xy 283.901021 -136.789287) (xy 283.922978 -136.79424)
			(xy 283.92501 -136.794748) (xy 283.929582 -136.79551) (xy 283.940408 -136.79638) (xy 283.961144 -136.789995)
			(xy 283.977395 -136.775619) (xy 283.986261 -136.755815) (xy 283.986732 -136.744964) (xy 283.986732 -136.739376)
			(xy 283.986478 -136.73709) (xy 283.9847 -136.697212) (xy 283.9847 -135.83285) (xy 283.98519 -135.802866)
			(xy 283.993018 -135.74341) (xy 284.008539 -135.685485) (xy 284.031488 -135.630081) (xy 284.061472 -135.578147)
			(xy 284.097978 -135.530571) (xy 284.140383 -135.488166) (xy 284.187959 -135.45166) (xy 284.239893 -135.421676)
			(xy 284.295297 -135.398727) (xy 284.353222 -135.383206) (xy 284.412678 -135.375378) (xy 284.472646 -135.375378)
			(xy 284.532102 -135.383206) (xy 284.590027 -135.398727) (xy 284.645431 -135.421676) (xy 284.697365 -135.45166)
			(xy 284.744941 -135.488166) (xy 284.787346 -135.530571) (xy 284.823852 -135.578147) (xy 284.853836 -135.630081)
			(xy 284.876785 -135.685485) (xy 284.892306 -135.74341) (xy 284.900134 -135.802866) (xy 284.900624 -135.83285)
			(xy 284.900624 -136.697212) (xy 284.898846 -136.73709) (xy 284.898592 -136.739376) (xy 284.898592 -136.744964)
			(xy 284.899037 -136.755862) (xy 284.907939 -136.775751) (xy 284.924286 -136.790158) (xy 284.945135 -136.796492)
			(xy 284.955996 -136.79551) (xy 284.960568 -136.794748) (xy 284.961584 -136.794494) (xy 284.96387 -136.793986)
			(xy 284.981396 -136.790176) (xy 285.007558 -136.786112) (xy 285.01467 -136.78535) (xy 285.052262 -136.783572)
			(xy 285.080209 -136.784065) (xy 285.135504 -136.792227) (xy 285.189018 -136.808367) (xy 285.239604 -136.832141)
			(xy 285.286182 -136.863039) (xy 285.327754 -136.900401) (xy 285.363432 -136.943428) (xy 285.392453 -136.991198)
			(xy 285.403798 -137.016744) (xy 285.406592 -137.023602) (xy 285.41091 -137.02919) (xy 285.413308 -137.032066)
			(xy 285.418792 -137.037164) (xy 285.421832 -137.03935) (xy 285.42869 -137.043922) (xy 285.435189 -137.048108)
			(xy 285.449922 -137.052768) (xy 285.457646 -137.053066) (xy 286.1945 -137.053066) (xy 286.202944 -137.052669)
			(xy 286.218888 -137.047091) (xy 286.225742 -137.042144) (xy 289.062414 -134.205472) (xy 289.08599 -134.182526)
			(xy 289.137431 -134.141508) (xy 289.193141 -134.106507) (xy 289.25242 -134.077964) (xy 289.314522 -134.056238)
			(xy 289.378666 -134.041602) (xy 289.444046 -134.03424) (xy 289.476942 -134.033768) (xy 289.512369 -134.034305)
			(xy 289.582704 -134.04285) (xy 289.651498 -134.05981) (xy 289.717745 -134.084939) (xy 289.780481 -134.117869)
			(xy 289.83879 -134.158121) (xy 289.891822 -134.205107) (xy 289.938805 -134.258143) (xy 289.979053 -134.316455)
			(xy 290.010919 -134.377176) (xy 298.799504 -134.377176) (xy 298.799504 -133.513576) (xy 298.799994 -133.483608)
			(xy 298.807817 -133.424186) (xy 298.82333 -133.366293) (xy 298.846266 -133.31092) (xy 298.876233 -133.259014)
			(xy 298.91272 -133.211464) (xy 298.9551 -133.169084) (xy 299.00265 -133.132597) (xy 299.054556 -133.10263)
			(xy 299.109929 -133.079694) (xy 299.167822 -133.064181) (xy 299.227244 -133.056358) (xy 299.28718 -133.056358)
			(xy 299.346602 -133.064181) (xy 299.404495 -133.079694) (xy 299.459868 -133.10263) (xy 299.511774 -133.132597)
			(xy 299.559324 -133.169084) (xy 299.601704 -133.211464) (xy 299.638191 -133.259014) (xy 299.668158 -133.31092)
			(xy 299.691094 -133.366293) (xy 299.706607 -133.424186) (xy 299.71443 -133.483608) (xy 299.71492 -133.513576)
			(xy 299.71492 -134.377176) (xy 299.71443 -134.407144) (xy 299.706607 -134.466566) (xy 299.691094 -134.524459)
			(xy 299.668158 -134.579832) (xy 299.638191 -134.631738) (xy 299.601704 -134.679288) (xy 299.559324 -134.721668)
			(xy 299.511774 -134.758155) (xy 299.459868 -134.788122) (xy 299.404495 -134.811058) (xy 299.346602 -134.826571)
			(xy 299.28718 -134.834394) (xy 299.227244 -134.834394) (xy 299.167822 -134.826571) (xy 299.109929 -134.811058)
			(xy 299.054556 -134.788122) (xy 299.00265 -134.758155) (xy 298.9551 -134.721668) (xy 298.91272 -134.679288)
			(xy 298.876233 -134.631738) (xy 298.846266 -134.579832) (xy 298.82333 -134.524459) (xy 298.807817 -134.466566)
			(xy 298.799994 -134.407144) (xy 298.799504 -134.377176) (xy 290.010919 -134.377176) (xy 290.011978 -134.379193)
			(xy 290.037102 -134.445442) (xy 290.054058 -134.514237) (xy 290.062598 -134.584573) (xy 290.063174 -134.62)
			(xy 290.062713 -134.652896) (xy 290.055347 -134.718276) (xy 290.040708 -134.782419) (xy 290.018979 -134.84452)
			(xy 289.990434 -134.903799) (xy 289.955432 -134.959508) (xy 289.914413 -135.010949) (xy 289.89147 -135.034528)
			(xy 289.385248 -135.54075) (xy 289.382962 -135.57885) (xy 289.3949 -135.59409) (xy 289.410145 -135.614275)
			(xy 289.43574 -135.657905) (xy 289.455337 -135.704538) (xy 289.468592 -135.753354) (xy 289.475273 -135.803494)
			(xy 289.475672 -135.828786) (xy 289.47521 -135.856039) (xy 289.467454 -135.909989) (xy 289.452099 -135.962287)
			(xy 289.429457 -136.011866) (xy 289.399988 -136.057718) (xy 289.364294 -136.09891) (xy 289.323101 -136.134602)
			(xy 289.277247 -136.164067) (xy 289.248324 -136.177274) (xy 296.945304 -136.177274) (xy 296.945304 -135.313674)
			(xy 296.945794 -135.283706) (xy 296.953617 -135.224284) (xy 296.96913 -135.166391) (xy 296.992066 -135.111018)
			(xy 297.022033 -135.059112) (xy 297.05852 -135.011562) (xy 297.1009 -134.969182) (xy 297.14845 -134.932695)
			(xy 297.200356 -134.902728) (xy 297.255729 -134.879792) (xy 297.313622 -134.864279) (xy 297.373044 -134.856456)
			(xy 297.43298 -134.856456) (xy 297.492402 -134.864279) (xy 297.550295 -134.879792) (xy 297.605668 -134.902728)
			(xy 297.657574 -134.932695) (xy 297.705124 -134.969182) (xy 297.747504 -135.011562) (xy 297.783991 -135.059112)
			(xy 297.813958 -135.111018) (xy 297.836894 -135.166391) (xy 297.852407 -135.224284) (xy 297.86023 -135.283706)
			(xy 297.86072 -135.313674) (xy 297.86072 -136.177274) (xy 297.86023 -136.207242) (xy 297.852407 -136.266664)
			(xy 297.836894 -136.324557) (xy 297.813958 -136.37993) (xy 297.783991 -136.431836) (xy 297.747504 -136.479386)
			(xy 297.705124 -136.521766) (xy 297.657574 -136.558253) (xy 297.605668 -136.58822) (xy 297.550295 -136.611156)
			(xy 297.492402 -136.626669) (xy 297.43298 -136.634492) (xy 297.373044 -136.634492) (xy 297.313622 -136.626669)
			(xy 297.255729 -136.611156) (xy 297.200356 -136.58822) (xy 297.14845 -136.558253) (xy 297.1009 -136.521766)
			(xy 297.05852 -136.479386) (xy 297.022033 -136.431836) (xy 296.992066 -136.37993) (xy 296.96913 -136.324557)
			(xy 296.953617 -136.266664) (xy 296.945794 -136.207242) (xy 296.945304 -136.177274) (xy 289.248324 -136.177274)
			(xy 289.227666 -136.186707) (xy 289.175368 -136.202059) (xy 289.121417 -136.209811) (xy 289.094164 -136.210294)
			(xy 289.068873 -136.20988) (xy 289.018736 -136.203191) (xy 288.969923 -136.189935) (xy 288.923289 -136.170345)
			(xy 288.879653 -136.144764) (xy 288.859468 -136.129522) (xy 288.844228 -136.117584) (xy 288.806128 -136.11987)
			(xy 287.638998 -137.287) (xy 288.967924 -137.287) (xy 288.971995 -137.231378) (xy 288.984121 -137.176941)
			(xy 289.004044 -137.12485) (xy 289.03134 -137.076215) (xy 289.065426 -137.032072) (xy 289.105575 -136.993363)
			(xy 289.150933 -136.960912) (xy 289.200533 -136.935411) (xy 289.253317 -136.917404) (xy 289.30816 -136.907274)
			(xy 289.363894 -136.905237) (xy 289.419331 -136.911337) (xy 289.473288 -136.925443) (xy 289.524617 -136.947255)
			(xy 289.572223 -136.976309) (xy 289.615091 -137.011984) (xy 289.652308 -137.053521) (xy 289.683081 -137.100034)
			(xy 289.706753 -137.150531) (xy 289.722821 -137.203938) (xy 289.730941 -137.259114) (xy 289.73145 -137.287)
			(xy 289.730941 -137.314886) (xy 289.722821 -137.370062) (xy 289.706753 -137.423469) (xy 289.683081 -137.473966)
			(xy 289.652308 -137.520479) (xy 289.615091 -137.562016) (xy 289.572223 -137.597691) (xy 289.524617 -137.626745)
			(xy 289.473288 -137.648557) (xy 289.419331 -137.662663) (xy 289.363894 -137.668763) (xy 289.30816 -137.666726)
			(xy 289.253317 -137.656596) (xy 289.200533 -137.638589) (xy 289.150933 -137.613088) (xy 289.105575 -137.580637)
			(xy 289.065426 -137.541928) (xy 289.03134 -137.497785) (xy 289.004044 -137.44915) (xy 288.984121 -137.397059)
			(xy 288.971995 -137.342622) (xy 288.967924 -137.287) (xy 287.638998 -137.287) (xy 287.07715 -137.848848)
			(xy 294.139872 -137.848848) (xy 294.143943 -137.793226) (xy 294.156069 -137.738789) (xy 294.175992 -137.686698)
			(xy 294.203288 -137.638063) (xy 294.237374 -137.59392) (xy 294.277523 -137.555211) (xy 294.322881 -137.52276)
			(xy 294.372481 -137.497259) (xy 294.425265 -137.479252) (xy 294.480108 -137.469122) (xy 294.535842 -137.467085)
			(xy 294.591279 -137.473185) (xy 294.645236 -137.487291) (xy 294.696565 -137.509103) (xy 294.744171 -137.538157)
			(xy 294.787039 -137.573832) (xy 294.824256 -137.615369) (xy 294.855029 -137.661882) (xy 294.878701 -137.712379)
			(xy 294.894769 -137.765786) (xy 294.902889 -137.820962) (xy 294.903398 -137.848848) (xy 294.902889 -137.876734)
			(xy 294.894769 -137.93191) (xy 294.878701 -137.985317) (xy 294.855029 -138.035814) (xy 294.824256 -138.082327)
			(xy 294.787039 -138.123864) (xy 294.744171 -138.159539) (xy 294.696565 -138.188593) (xy 294.645236 -138.210405)
			(xy 294.591279 -138.224511) (xy 294.535842 -138.230611) (xy 294.480108 -138.228574) (xy 294.425265 -138.218444)
			(xy 294.372481 -138.200437) (xy 294.322881 -138.174936) (xy 294.277523 -138.142485) (xy 294.237374 -138.103776)
			(xy 294.203288 -138.059633) (xy 294.175992 -138.010998) (xy 294.156069 -137.958907) (xy 294.143943 -137.90447)
			(xy 294.139872 -137.848848) (xy 287.07715 -137.848848) (xy 286.635952 -138.290046) (xy 286.628553 -138.296891)
			(xy 286.609955 -138.304616) (xy 286.599884 -138.305032) (xy 282.772104 -138.305032) (xy 282.762033 -138.30461)
			(xy 282.743424 -138.296901) (xy 282.736036 -138.290046) (xy 282.3337 -137.88771) (xy 282.326815 -137.882689)
			(xy 282.31072 -137.87712) (xy 282.302204 -137.876788) (xy 281.916124 -137.876788) (xy 281.906099 -137.877203)
			(xy 281.887571 -137.884869) (xy 281.873389 -137.899041) (xy 281.86571 -137.917563) (xy 281.865324 -137.927588)
			(xy 281.865324 -138.95705) (xy 288.714434 -138.95705) (xy 288.71492 -138.929799) (xy 288.722676 -138.875851)
			(xy 288.738031 -138.823556) (xy 288.760673 -138.773979) (xy 288.790139 -138.728129) (xy 288.82583 -138.686938)
			(xy 288.867021 -138.651247) (xy 288.912871 -138.621781) (xy 288.962448 -138.599139) (xy 289.014743 -138.583784)
			(xy 289.068691 -138.576028) (xy 289.123193 -138.576028) (xy 289.177141 -138.583784) (xy 289.229436 -138.599139)
			(xy 289.279013 -138.621781) (xy 289.324863 -138.651247) (xy 289.366054 -138.686938) (xy 289.401745 -138.728129)
			(xy 289.431211 -138.773979) (xy 289.453853 -138.823556) (xy 289.465977 -138.864848) (xy 294.139872 -138.864848)
			(xy 294.143943 -138.809226) (xy 294.156069 -138.754789) (xy 294.175992 -138.702698) (xy 294.203288 -138.654063)
			(xy 294.237374 -138.60992) (xy 294.277523 -138.571211) (xy 294.322881 -138.53876) (xy 294.372481 -138.513259)
			(xy 294.425265 -138.495252) (xy 294.480108 -138.485122) (xy 294.535842 -138.483085) (xy 294.591279 -138.489185)
			(xy 294.645236 -138.503291) (xy 294.696565 -138.525103) (xy 294.744171 -138.554157) (xy 294.787039 -138.589832)
			(xy 294.824256 -138.631369) (xy 294.855029 -138.677882) (xy 294.878701 -138.728379) (xy 294.894769 -138.781786)
			(xy 294.902889 -138.836962) (xy 294.903398 -138.864848) (xy 294.902889 -138.892734) (xy 294.894769 -138.94791)
			(xy 294.878701 -139.001317) (xy 294.855029 -139.051814) (xy 294.824256 -139.098327) (xy 294.787039 -139.139864)
			(xy 294.744171 -139.175539) (xy 294.696565 -139.204593) (xy 294.645236 -139.226405) (xy 294.591279 -139.240511)
			(xy 294.535842 -139.246611) (xy 294.480108 -139.244574) (xy 294.425265 -139.234444) (xy 294.372481 -139.216437)
			(xy 294.322881 -139.190936) (xy 294.277523 -139.158485) (xy 294.237374 -139.119776) (xy 294.203288 -139.075633)
			(xy 294.175992 -139.026998) (xy 294.156069 -138.974907) (xy 294.143943 -138.92047) (xy 294.139872 -138.864848)
			(xy 289.465977 -138.864848) (xy 289.469208 -138.875851) (xy 289.476964 -138.929799) (xy 289.47745 -138.95705)
			(xy 289.476953 -138.98483) (xy 289.468879 -139.039801) (xy 289.45291 -139.093017) (xy 289.429384 -139.143351)
			(xy 289.398799 -139.189735) (xy 289.380676 -139.210796) (xy 289.380422 -139.21105) (xy 289.374119 -139.218931)
			(xy 289.367701 -139.238047) (xy 289.367976 -139.248134) (xy 289.37331 -139.321286) (xy 289.374479 -139.331363)
			(xy 289.383651 -139.34944) (xy 289.39109 -139.356338) (xy 289.391344 -139.356592) (xy 289.412369 -139.3748)
			(xy 289.449409 -139.416293) (xy 289.480036 -139.46272) (xy 289.503604 -139.5131) (xy 289.519614 -139.566366)
			(xy 289.527726 -139.621391) (xy 289.52825 -139.6492) (xy 289.527764 -139.676451) (xy 289.520008 -139.730399)
			(xy 289.504653 -139.782694) (xy 289.482011 -139.832271) (xy 289.452545 -139.878121) (xy 289.416854 -139.919312)
			(xy 289.375663 -139.955003) (xy 289.329813 -139.984469) (xy 289.280236 -140.007111) (xy 289.227941 -140.022466)
			(xy 289.173993 -140.030222) (xy 289.119491 -140.030222) (xy 289.065543 -140.022466) (xy 289.013248 -140.007111)
			(xy 288.963671 -139.984469) (xy 288.917821 -139.955003) (xy 288.87663 -139.919312) (xy 288.840939 -139.878121)
			(xy 288.811473 -139.832271) (xy 288.788831 -139.782694) (xy 288.773476 -139.730399) (xy 288.76572 -139.676451)
			(xy 288.765234 -139.6492) (xy 288.765765 -139.621421) (xy 288.773832 -139.566452) (xy 288.789793 -139.513237)
			(xy 288.813312 -139.462903) (xy 288.843889 -139.416516) (xy 288.862008 -139.395454) (xy 288.862262 -139.3952)
			(xy 288.868587 -139.387334) (xy 288.874992 -139.368207) (xy 288.874708 -139.358116) (xy 288.869374 -139.284964)
			(xy 288.868234 -139.274881) (xy 288.859041 -139.256807) (xy 288.851594 -139.249912) (xy 288.85134 -139.249658)
			(xy 288.830335 -139.231427) (xy 288.793295 -139.189938) (xy 288.762666 -139.143516) (xy 288.739094 -139.093141)
			(xy 288.72308 -139.039879) (xy 288.714962 -138.984858) (xy 288.714434 -138.95705) (xy 281.865324 -138.95705)
			(xy 281.865324 -140.127482) (xy 283.80512 -140.127482) (xy 283.809191 -140.07186) (xy 283.821317 -140.017423)
			(xy 283.84124 -139.965332) (xy 283.868536 -139.916697) (xy 283.902622 -139.872554) (xy 283.942771 -139.833845)
			(xy 283.988129 -139.801394) (xy 284.037729 -139.775893) (xy 284.090513 -139.757886) (xy 284.145356 -139.747756)
			(xy 284.20109 -139.745719) (xy 284.256527 -139.751819) (xy 284.310484 -139.765925) (xy 284.361813 -139.787737)
			(xy 284.409419 -139.816791) (xy 284.452287 -139.852466) (xy 284.489504 -139.894003) (xy 284.520277 -139.940516)
			(xy 284.543949 -139.991013) (xy 284.560017 -140.04442) (xy 284.568137 -140.099596) (xy 284.568646 -140.127482)
			(xy 284.568137 -140.155368) (xy 284.560017 -140.210544) (xy 284.543949 -140.263951) (xy 284.520277 -140.314448)
			(xy 284.489504 -140.360961) (xy 284.452287 -140.402498) (xy 284.409419 -140.438173) (xy 284.361813 -140.467227)
			(xy 284.310484 -140.489039) (xy 284.256527 -140.503145) (xy 284.20109 -140.509245) (xy 284.145356 -140.507208)
			(xy 284.090513 -140.497078) (xy 284.037729 -140.479071) (xy 283.988129 -140.45357) (xy 283.942771 -140.421119)
			(xy 283.902622 -140.38241) (xy 283.868536 -140.338267) (xy 283.84124 -140.289632) (xy 283.821317 -140.237541)
			(xy 283.809191 -140.183104) (xy 283.80512 -140.127482) (xy 281.865324 -140.127482) (xy 281.865324 -140.565451)
			(xy 295.630578 -140.565451) (xy 295.630578 -140.510949) (xy 295.638334 -140.457001) (xy 295.653689 -140.404706)
			(xy 295.676331 -140.355129) (xy 295.705797 -140.309279) (xy 295.741488 -140.268088) (xy 295.782679 -140.232397)
			(xy 295.828529 -140.202931) (xy 295.878106 -140.180289) (xy 295.930401 -140.164934) (xy 295.984349 -140.157178)
			(xy 296.0116 -140.156692) (xy 296.03897 -140.15716) (xy 296.093149 -140.164978) (xy 296.145652 -140.180466)
			(xy 296.195399 -140.203308) (xy 296.241366 -140.233031) (xy 296.262298 -140.250672) (xy 296.262552 -140.250926)
			(xy 296.269646 -140.256502) (xy 296.286557 -140.262754) (xy 296.295572 -140.263118) (xy 296.362628 -140.263118)
			(xy 296.371646 -140.262771) (xy 296.388563 -140.256516) (xy 296.395648 -140.250926) (xy 296.395648 -140.250672)
			(xy 296.395902 -140.250672) (xy 296.416819 -140.233014) (xy 296.462796 -140.203306) (xy 296.512548 -140.180474)
			(xy 296.565052 -140.164987) (xy 296.61923 -140.157164) (xy 296.6466 -140.156692) (xy 296.673851 -140.157178)
			(xy 296.727799 -140.164934) (xy 296.780094 -140.180289) (xy 296.829671 -140.202931) (xy 296.875521 -140.232397)
			(xy 296.916712 -140.268088) (xy 296.952403 -140.309279) (xy 296.981869 -140.355129) (xy 297.004511 -140.404706)
			(xy 297.019866 -140.457001) (xy 297.027622 -140.510949) (xy 297.027622 -140.565451) (xy 297.019866 -140.619399)
			(xy 297.004511 -140.671694) (xy 296.981869 -140.721271) (xy 296.952403 -140.767121) (xy 296.916712 -140.808312)
			(xy 296.875521 -140.844003) (xy 296.829671 -140.873469) (xy 296.780094 -140.896111) (xy 296.727799 -140.911466)
			(xy 296.673851 -140.919222) (xy 296.6466 -140.919708) (xy 296.61923 -140.91924) (xy 296.565051 -140.911422)
			(xy 296.512548 -140.895934) (xy 296.462801 -140.873092) (xy 296.416834 -140.843369) (xy 296.395902 -140.825728)
			(xy 296.395648 -140.825474) (xy 296.388554 -140.819898) (xy 296.371643 -140.813646) (xy 296.362628 -140.813282)
			(xy 296.295572 -140.813282) (xy 296.286554 -140.813629) (xy 296.269637 -140.819884) (xy 296.262552 -140.825474)
			(xy 296.262552 -140.825728) (xy 296.262298 -140.825728) (xy 296.241381 -140.843386) (xy 296.195404 -140.873094)
			(xy 296.145652 -140.895926) (xy 296.093148 -140.911413) (xy 296.03897 -140.919236) (xy 296.0116 -140.919708)
			(xy 295.984349 -140.919222) (xy 295.930401 -140.911466) (xy 295.878106 -140.896111) (xy 295.828529 -140.873469)
			(xy 295.782679 -140.844003) (xy 295.741488 -140.808312) (xy 295.705797 -140.767121) (xy 295.676331 -140.721271)
			(xy 295.653689 -140.671694) (xy 295.638334 -140.619399) (xy 295.630578 -140.565451) (xy 281.865324 -140.565451)
			(xy 281.865324 -140.858494) (xy 281.865805 -140.868217) (xy 281.873112 -140.886243) (xy 281.879548 -140.893546)
			(xy 282.353512 -141.367256) (xy 282.359523 -141.37199) (xy 282.373612 -141.377939) (xy 282.381198 -141.37894)
			(xy 284.187138 -141.37894) (xy 284.222549 -141.379477) (xy 284.292854 -141.388018) (xy 284.361617 -141.404971)
			(xy 284.427835 -141.430088) (xy 284.490543 -141.463004) (xy 284.548826 -141.503239) (xy 284.601835 -141.550205)
			(xy 284.648796 -141.603218) (xy 284.689025 -141.661505) (xy 284.721935 -141.724216) (xy 284.747046 -141.790437)
			(xy 284.763992 -141.859201) (xy 284.772527 -141.929507) (xy 284.772622 -141.9352) (xy 288.724084 -141.9352)
			(xy 288.728155 -141.879578) (xy 288.740281 -141.825141) (xy 288.760204 -141.77305) (xy 288.7875 -141.724415)
			(xy 288.821586 -141.680272) (xy 288.861735 -141.641563) (xy 288.907093 -141.609112) (xy 288.956693 -141.583611)
			(xy 289.009477 -141.565604) (xy 289.06432 -141.555474) (xy 289.120054 -141.553437) (xy 289.175491 -141.559537)
			(xy 289.229448 -141.573643) (xy 289.280777 -141.595455) (xy 289.328383 -141.624509) (xy 289.371251 -141.660184)
			(xy 289.408468 -141.701721) (xy 289.439241 -141.748234) (xy 289.462913 -141.798731) (xy 289.478981 -141.852138)
			(xy 289.487101 -141.907314) (xy 289.48761 -141.9352) (xy 289.487101 -141.963086) (xy 289.478981 -142.018262)
			(xy 289.462913 -142.071669) (xy 289.439241 -142.122166) (xy 289.408468 -142.168679) (xy 289.371251 -142.210216)
			(xy 289.328383 -142.245891) (xy 289.280777 -142.274945) (xy 289.229448 -142.296757) (xy 289.175491 -142.310863)
			(xy 289.120054 -142.316963) (xy 289.06432 -142.314926) (xy 289.009477 -142.304796) (xy 288.956693 -142.286789)
			(xy 288.907093 -142.261288) (xy 288.861735 -142.228837) (xy 288.821586 -142.190128) (xy 288.7875 -142.145985)
			(xy 288.760204 -142.09735) (xy 288.740281 -142.045259) (xy 288.728155 -141.990822) (xy 288.724084 -141.9352)
			(xy 284.772622 -141.9352) (xy 284.773116 -141.964918) (xy 284.772526 -142.002468) (xy 284.762892 -142.076949)
			(xy 284.74381 -142.149586) (xy 284.715595 -142.219186) (xy 284.697678 -142.252192) (xy 284.69463 -142.25778)
			(xy 284.691582 -142.26921) (xy 284.690573 -142.273193) (xy 284.689681 -142.281359) (xy 284.689804 -142.285466)
			(xy 284.691328 -142.29588) (xy 284.69463 -142.307818) (xy 284.697678 -142.313406) (xy 284.715581 -142.346418)
			(xy 284.743775 -142.416022) (xy 284.762854 -142.488656) (xy 284.772506 -142.563132) (xy 284.773116 -142.60068)
			(xy 284.772622 -142.634759) (xy 284.764713 -142.702456) (xy 284.749 -142.768778) (xy 284.725695 -142.832827)
			(xy 284.695114 -142.893739) (xy 284.657669 -142.950689) (xy 284.65724 -142.9512) (xy 288.74034 -142.9512)
			(xy 288.744411 -142.895578) (xy 288.756537 -142.841141) (xy 288.77646 -142.78905) (xy 288.803756 -142.740415)
			(xy 288.837842 -142.696272) (xy 288.877991 -142.657563) (xy 288.923349 -142.625112) (xy 288.972949 -142.599611)
			(xy 289.025733 -142.581604) (xy 289.080576 -142.571474) (xy 289.13631 -142.569437) (xy 289.191747 -142.575537)
			(xy 289.245704 -142.589643) (xy 289.297033 -142.611455) (xy 289.344639 -142.640509) (xy 289.387507 -142.676184)
			(xy 289.424724 -142.717721) (xy 289.455497 -142.764234) (xy 289.479169 -142.814731) (xy 289.495237 -142.868138)
			(xy 289.503357 -142.923314) (xy 289.503866 -142.9512) (xy 289.503357 -142.979086) (xy 289.495237 -143.034262)
			(xy 289.479169 -143.087669) (xy 289.455497 -143.138166) (xy 289.424724 -143.184679) (xy 289.387507 -143.226216)
			(xy 289.344639 -143.261891) (xy 289.297033 -143.290945) (xy 289.245704 -143.312757) (xy 289.191747 -143.326863)
			(xy 289.13631 -143.332963) (xy 289.080576 -143.330926) (xy 289.025733 -143.320796) (xy 288.972949 -143.302789)
			(xy 288.923349 -143.277288) (xy 288.877991 -143.244837) (xy 288.837842 -143.206128) (xy 288.803756 -143.161985)
			(xy 288.77646 -143.11335) (xy 288.756537 -143.061259) (xy 288.744411 -143.006822) (xy 288.74034 -142.9512)
			(xy 284.65724 -142.9512) (xy 284.613866 -143.002908) (xy 284.564299 -143.04969) (xy 284.509637 -143.090403)
			(xy 284.450618 -143.124495) (xy 284.388042 -143.151507) (xy 284.35554 -143.161766) (xy 284.31668 -143.172725)
			(xy 284.236891 -143.185088) (xy 284.196536 -143.186404) (xy 284.187646 -143.186404) (xy 284.187138 -143.186404)
			(xy 284.150473 -143.185869) (xy 284.077711 -143.176783) (xy 284.006651 -143.158684) (xy 283.938407 -143.131857)
			(xy 283.90596 -143.114776) (xy 283.900626 -143.111728) (xy 283.882084 -143.106902) (xy 283.86913 -143.105124)
			(xy 281.701494 -143.105124) (xy 281.691424 -143.1047) (xy 281.672819 -143.096987) (xy 281.665426 -143.090138)
			(xy 281.518614 -142.943326) (xy 281.517598 -142.94231) (xy 281.508708 -142.933674) (xy 280.395934 -141.8209)
			(xy 280.387298 -141.81201) (xy 280.386282 -141.810994) (xy 280.23947 -141.664182) (xy 280.232619 -141.656786)
			(xy 280.22488 -141.638187) (xy 280.224484 -141.628114) (xy 280.224484 -137.527538) (xy 280.224315 -137.521529)
			(xy 280.221488 -137.509848) (xy 280.218896 -137.504424) (xy 280.217059 -137.500948) (xy 280.212469 -137.494566)
			(xy 280.209752 -137.491724) (xy 279.884632 -137.166604) (xy 279.881781 -137.163898) (xy 279.875403 -137.159304)
			(xy 279.871932 -137.15746) (xy 279.866505 -137.154877) (xy 279.854825 -137.152056) (xy 279.848818 -137.151872)
			(xy 277.186644 -137.151872) (xy 277.177738 -137.152301) (xy 277.161023 -137.158463) (xy 277.147414 -137.16996)
			(xy 277.142702 -137.177526) (xy 277.11781 -137.225278) (xy 277.115702 -137.230226) (xy 277.113399 -137.24073)
			(xy 277.113238 -137.246106) (xy 277.113238 -137.274046) (xy 277.113317 -137.277789) (xy 277.114463 -137.285188)
			(xy 277.115524 -137.288778) (xy 277.117302 -137.295128) (xy 277.121874 -137.301732) (xy 277.137814 -137.326315)
			(xy 277.165312 -137.378056) (xy 277.187564 -137.43226) (xy 277.196296 -137.460228) (xy 277.204214 -137.487848)
			(xy 277.215294 -137.544232) (xy 277.220862 -137.601423) (xy 277.221188 -137.630154) (xy 277.221188 -137.631424)
			(xy 277.221188 -137.633202) (xy 277.220766 -137.665507) (xy 277.213742 -137.729733) (xy 277.199757 -137.792811)
			(xy 277.178977 -137.853988) (xy 277.151651 -137.912534) (xy 277.118103 -137.967751) (xy 277.09876 -137.993628)
			(xy 277.093426 -138.000486) (xy 277.090886 -138.007598) (xy 277.089588 -138.011667) (xy 277.088186 -138.020092)
			(xy 277.088092 -138.024362) (xy 277.088092 -138.10488) (xy 277.0886 -138.108436) (xy 277.090124 -138.119358)
			(xy 277.093934 -138.126724) (xy 277.098506 -138.136122) (xy 277.101554 -138.140186) (xy 277.120448 -138.165876)
			(xy 277.153218 -138.220588) (xy 277.179909 -138.27851) (xy 277.20021 -138.338967) (xy 277.213885 -138.401259)
			(xy 277.220777 -138.464661) (xy 277.221188 -138.496548) (xy 277.221188 -138.496802) (xy 277.220649 -138.532513)
			(xy 277.216813 -138.564112) (xy 278.891236 -138.564112) (xy 278.895307 -138.50849) (xy 278.907433 -138.454053)
			(xy 278.927356 -138.401962) (xy 278.954652 -138.353327) (xy 278.988738 -138.309184) (xy 279.028887 -138.270475)
			(xy 279.074245 -138.238024) (xy 279.123845 -138.212523) (xy 279.176629 -138.194516) (xy 279.231472 -138.184386)
			(xy 279.287206 -138.182349) (xy 279.342643 -138.188449) (xy 279.3966 -138.202555) (xy 279.447929 -138.224367)
			(xy 279.495535 -138.253421) (xy 279.538403 -138.289096) (xy 279.57562 -138.330633) (xy 279.606393 -138.377146)
			(xy 279.630065 -138.427643) (xy 279.646133 -138.48105) (xy 279.654253 -138.536226) (xy 279.654762 -138.564112)
			(xy 279.654253 -138.591998) (xy 279.646133 -138.647174) (xy 279.630065 -138.700581) (xy 279.606393 -138.751078)
			(xy 279.57562 -138.797591) (xy 279.538403 -138.839128) (xy 279.495535 -138.874803) (xy 279.447929 -138.903857)
			(xy 279.3966 -138.925669) (xy 279.342643 -138.939775) (xy 279.287206 -138.945875) (xy 279.231472 -138.943838)
			(xy 279.176629 -138.933708) (xy 279.123845 -138.915701) (xy 279.074245 -138.8902) (xy 279.028887 -138.857749)
			(xy 278.988738 -138.81904) (xy 278.954652 -138.774897) (xy 278.927356 -138.726262) (xy 278.907433 -138.674171)
			(xy 278.895307 -138.619734) (xy 278.891236 -138.564112) (xy 277.216813 -138.564112) (xy 277.212043 -138.603413)
			(xy 277.194955 -138.67276) (xy 277.169636 -138.739543) (xy 277.136454 -138.802788) (xy 277.095893 -138.861574)
			(xy 277.048544 -138.915044) (xy 276.995097 -138.962419) (xy 276.93633 -139.003008) (xy 276.873101 -139.03622)
			(xy 276.80633 -139.061571) (xy 276.736991 -139.078692) (xy 276.666094 -139.087332) (xy 276.630384 -139.08786)
			(xy 276.597223 -139.087378) (xy 276.53132 -139.079921) (xy 276.466666 -139.065136) (xy 276.404073 -139.043208)
			(xy 276.344327 -139.014413) (xy 276.288178 -138.979113) (xy 276.236333 -138.937751) (xy 276.212554 -138.914632)
			(xy 276.10562 -138.807698) (xy 276.102769 -138.804993) (xy 276.09639 -138.800401) (xy 276.09292 -138.798554)
			(xy 276.087493 -138.795973) (xy 276.075813 -138.793155) (xy 276.069806 -138.792966) (xy 275.848064 -138.792966)
			(xy 275.838168 -138.793491) (xy 275.819879 -138.801077) (xy 275.812504 -138.807698) (xy 274.610322 -140.00988)
			(xy 274.60575 -140.015214) (xy 274.601593 -140.021204) (xy 274.596558 -140.034882) (xy 274.595844 -140.042138)
			(xy 274.595844 -140.565378) (xy 275.789644 -140.565378) (xy 275.790086 -140.538007) (xy 275.797908 -140.483826)
			(xy 275.813402 -140.431322) (xy 275.83625 -140.381576) (xy 275.86598 -140.335611) (xy 275.883624 -140.31468)
			(xy 275.883878 -140.314426) (xy 275.889469 -140.307343) (xy 275.895711 -140.290423) (xy 275.89607 -140.281406)
			(xy 275.89607 -140.21435) (xy 275.895696 -140.205335) (xy 275.889461 -140.188417) (xy 275.883878 -140.18133)
			(xy 275.883624 -140.18133) (xy 275.883624 -140.181076) (xy 275.866011 -140.160123) (xy 275.836294 -140.114156)
			(xy 275.813453 -140.064414) (xy 275.797956 -140.011918) (xy 275.790121 -139.957746) (xy 275.789644 -139.930378)
			(xy 275.790157 -139.903128) (xy 275.797915 -139.849184) (xy 275.813271 -139.796893) (xy 275.835911 -139.747319)
			(xy 275.865375 -139.701471) (xy 275.901064 -139.660282) (xy 275.94225 -139.624591) (xy 275.988096 -139.595124)
			(xy 276.037668 -139.57248) (xy 276.089959 -139.557121) (xy 276.143902 -139.549359) (xy 276.171152 -139.54887)
			(xy 276.198522 -139.549347) (xy 276.252701 -139.55716) (xy 276.305205 -139.572645) (xy 276.354952 -139.595485)
			(xy 276.400919 -139.625209) (xy 276.42185 -139.64285) (xy 276.422104 -139.643104) (xy 276.429185 -139.648699)
			(xy 276.446106 -139.65494) (xy 276.455124 -139.655296) (xy 276.52218 -139.655296) (xy 276.531196 -139.65493)
			(xy 276.548113 -139.648689) (xy 276.5552 -139.643104) (xy 276.5552 -139.64285) (xy 276.555454 -139.64285)
			(xy 276.576399 -139.625227) (xy 276.622367 -139.595511) (xy 276.672112 -139.572671) (xy 276.72461 -139.557176)
			(xy 276.778784 -139.549345) (xy 276.806152 -139.54887) (xy 276.833403 -139.5494) (xy 276.88735 -139.55715)
			(xy 276.939645 -139.572499) (xy 276.989224 -139.595134) (xy 277.035076 -139.624595) (xy 277.076269 -139.660282)
			(xy 277.111963 -139.701468) (xy 277.141433 -139.747315) (xy 277.164077 -139.796889) (xy 277.179435 -139.849181)
			(xy 277.187195 -139.903127) (xy 277.18766 -139.930378) (xy 277.187191 -139.957748) (xy 277.179375 -140.011928)
			(xy 277.163887 -140.064431) (xy 277.141046 -140.114178) (xy 277.111321 -140.160145) (xy 277.09368 -140.181076)
			(xy 277.093426 -140.18133) (xy 277.087854 -140.188426) (xy 277.0816 -140.205336) (xy 277.081234 -140.21435)
			(xy 277.081234 -140.281406) (xy 277.081581 -140.290424) (xy 277.087834 -140.307341) (xy 277.093426 -140.314426)
			(xy 277.09368 -140.314426) (xy 277.09368 -140.31468) (xy 277.11132 -140.335611) (xy 277.141032 -140.381584)
			(xy 277.163869 -140.431332) (xy 277.179359 -140.483833) (xy 277.187187 -140.538009) (xy 277.18766 -140.565378)
			(xy 277.187224 -140.592632) (xy 277.179469 -140.646587) (xy 277.164113 -140.698888) (xy 277.14147 -140.748471)
			(xy 277.112 -140.794327) (xy 277.076303 -140.835521) (xy 277.035106 -140.871215) (xy 276.989249 -140.900682)
			(xy 276.939664 -140.923322) (xy 276.887361 -140.938674) (xy 276.833407 -140.946426) (xy 276.806152 -140.946886)
			(xy 276.778783 -140.946393) (xy 276.724605 -140.938582) (xy 276.672102 -140.9231) (xy 276.622354 -140.900264)
			(xy 276.576386 -140.870545) (xy 276.555454 -140.852906) (xy 276.5552 -140.852652) (xy 276.548122 -140.847054)
			(xy 276.531198 -140.840815) (xy 276.52218 -140.84046) (xy 276.455124 -140.84046) (xy 276.446107 -140.840815)
			(xy 276.429189 -140.847063) (xy 276.422104 -140.852652) (xy 276.422104 -140.852906) (xy 276.42185 -140.852906)
			(xy 276.400911 -140.870536) (xy 276.35494 -140.900249) (xy 276.305194 -140.923087) (xy 276.252695 -140.93858)
			(xy 276.198521 -140.946411) (xy 276.171152 -140.946886) (xy 276.143899 -140.946467) (xy 276.089947 -140.938703)
			(xy 276.03765 -140.923341) (xy 275.988071 -140.900692) (xy 275.94222 -140.871219) (xy 275.90103 -140.835521)
			(xy 275.865339 -140.794324) (xy 275.835874 -140.748467) (xy 275.813235 -140.698884) (xy 275.797882 -140.646584)
			(xy 275.790128 -140.592632) (xy 275.789644 -140.565378) (xy 274.595844 -140.565378) (xy 274.595844 -143.48714)
			(xy 298.799504 -143.48714) (xy 298.799504 -142.62354) (xy 298.799994 -142.593572) (xy 298.807817 -142.53415)
			(xy 298.82333 -142.476257) (xy 298.846266 -142.420884) (xy 298.876233 -142.368978) (xy 298.91272 -142.321428)
			(xy 298.9551 -142.279048) (xy 299.00265 -142.242561) (xy 299.054556 -142.212594) (xy 299.109929 -142.189658)
			(xy 299.167822 -142.174145) (xy 299.227244 -142.166322) (xy 299.28718 -142.166322) (xy 299.346602 -142.174145)
			(xy 299.404495 -142.189658) (xy 299.459868 -142.212594) (xy 299.511774 -142.242561) (xy 299.559324 -142.279048)
			(xy 299.601704 -142.321428) (xy 299.638191 -142.368978) (xy 299.668158 -142.420884) (xy 299.691094 -142.476257)
			(xy 299.706607 -142.53415) (xy 299.71443 -142.593572) (xy 299.71492 -142.62354) (xy 299.71492 -143.48714)
			(xy 299.71443 -143.517108) (xy 299.706607 -143.57653) (xy 299.691094 -143.634423) (xy 299.668158 -143.689796)
			(xy 299.638191 -143.741702) (xy 299.601704 -143.789252) (xy 299.559324 -143.831632) (xy 299.511774 -143.868119)
			(xy 299.459868 -143.898086) (xy 299.404495 -143.921022) (xy 299.346602 -143.936535) (xy 299.28718 -143.944358)
			(xy 299.227244 -143.944358) (xy 299.167822 -143.936535) (xy 299.109929 -143.921022) (xy 299.054556 -143.898086)
			(xy 299.00265 -143.868119) (xy 298.9551 -143.831632) (xy 298.91272 -143.789252) (xy 298.876233 -143.741702)
			(xy 298.846266 -143.689796) (xy 298.82333 -143.634423) (xy 298.807817 -143.57653) (xy 298.799994 -143.517108)
			(xy 298.799504 -143.48714) (xy 274.595844 -143.48714) (xy 274.595844 -143.722598) (xy 274.59559 -143.734282)
			(xy 274.59559 -144.052544) (xy 274.595062 -144.062536) (xy 274.587362 -144.080982) (xy 274.580604 -144.088358)
			(xy 273.36322 -145.30578) (xy 275.33854 -145.30578) (xy 275.338981 -145.278444) (xy 275.346762 -145.22433)
			(xy 275.362191 -145.171881) (xy 275.384951 -145.122172) (xy 275.414575 -145.076223) (xy 275.450458 -145.034975)
			(xy 275.491863 -144.999274) (xy 275.537941 -144.969851) (xy 275.587749 -144.947308) (xy 275.613876 -144.939258)
			(xy 275.622747 -144.936279) (xy 275.637723 -144.925083) (xy 275.643086 -144.917414) (xy 275.68398 -144.852136)
			(xy 275.687536 -144.834356) (xy 275.686012 -144.825212) (xy 275.686012 -144.824704) (xy 275.683526 -144.809074)
			(xy 275.680858 -144.777537) (xy 275.680678 -144.761712) (xy 275.681189 -144.734462) (xy 275.688944 -144.680516)
			(xy 275.704297 -144.628222) (xy 275.726935 -144.578646) (xy 275.756399 -144.532796) (xy 275.792088 -144.491606)
			(xy 275.833276 -144.455915) (xy 275.879123 -144.426448) (xy 275.928698 -144.403806) (xy 275.98099 -144.388449)
			(xy 276.034936 -144.380691) (xy 276.062186 -144.380204) (xy 276.074157 -144.380319) (xy 276.09805 -144.381842)
			(xy 276.109938 -144.383252) (xy 276.110192 -144.383252) (xy 276.119366 -144.383961) (xy 276.137209 -144.379527)
			(xy 276.14499 -144.374616) (xy 276.201124 -144.3355) (xy 276.20853 -144.329917) (xy 276.219078 -144.314679)
			(xy 276.221698 -144.305782) (xy 276.221698 -144.305528) (xy 276.228685 -144.277974) (xy 276.249719 -144.225167)
			(xy 276.278359 -144.176067) (xy 276.31397 -144.131763) (xy 276.355762 -144.093234) (xy 276.40281 -144.061336)
			(xy 276.454072 -144.036774) (xy 276.508411 -144.020093) (xy 276.564625 -144.011663) (xy 276.593046 -144.011142)
			(xy 276.617717 -144.011555) (xy 276.666643 -144.017956) (xy 276.714338 -144.030605) (xy 276.737318 -144.03959)
			(xy 276.748421 -144.043493) (xy 276.771863 -144.041773) (xy 276.782276 -144.036288) (xy 276.852126 -143.994632)
			(xy 276.861901 -143.988159) (xy 276.874755 -143.968589) (xy 276.876764 -143.95704) (xy 276.876764 -143.956532)
			(xy 276.880473 -143.928978) (xy 276.894734 -143.875244) (xy 276.916645 -143.824151) (xy 276.945743 -143.77678)
			(xy 276.981412 -143.734137) (xy 277.022894 -143.697125) (xy 277.069311 -143.666528) (xy 277.119679 -143.642996)
			(xy 277.17293 -143.627027) (xy 277.227935 -143.618959) (xy 277.255732 -143.618458) (xy 277.282982 -143.618948)
			(xy 277.336928 -143.626708) (xy 277.389221 -143.642065) (xy 277.438796 -143.664708) (xy 277.484645 -143.694174)
			(xy 277.525834 -143.729865) (xy 277.561525 -143.771054) (xy 277.590991 -143.816902) (xy 277.613634 -143.866477)
			(xy 277.628992 -143.91877) (xy 277.636752 -143.972716) (xy 277.63724 -143.999966) (xy 277.636763 -144.026547)
			(xy 277.629382 -144.079193) (xy 277.614757 -144.130303) (xy 277.593173 -144.178885) (xy 277.565048 -144.223997)
			(xy 277.530928 -144.264764) (xy 277.52319 -144.272) (xy 288.586924 -144.272) (xy 288.590995 -144.216378)
			(xy 288.603121 -144.161941) (xy 288.623044 -144.10985) (xy 288.65034 -144.061215) (xy 288.684426 -144.017072)
			(xy 288.724575 -143.978363) (xy 288.769933 -143.945912) (xy 288.819533 -143.920411) (xy 288.872317 -143.902404)
			(xy 288.92716 -143.892274) (xy 288.982894 -143.890237) (xy 289.038331 -143.896337) (xy 289.092288 -143.910443)
			(xy 289.143617 -143.932255) (xy 289.191223 -143.961309) (xy 289.234091 -143.996984) (xy 289.271308 -144.038521)
			(xy 289.302081 -144.085034) (xy 289.325753 -144.135531) (xy 289.341821 -144.188938) (xy 289.349941 -144.244114)
			(xy 289.35045 -144.272) (xy 289.349941 -144.299886) (xy 289.341821 -144.355062) (xy 289.325753 -144.408469)
			(xy 289.302081 -144.458966) (xy 289.271308 -144.505479) (xy 289.234091 -144.547016) (xy 289.191223 -144.582691)
			(xy 289.143617 -144.611745) (xy 289.092288 -144.633557) (xy 289.038331 -144.647663) (xy 288.982894 -144.653763)
			(xy 288.92716 -144.651726) (xy 288.872317 -144.641596) (xy 288.819533 -144.623589) (xy 288.769933 -144.598088)
			(xy 288.724575 -144.565637) (xy 288.684426 -144.526928) (xy 288.65034 -144.482785) (xy 288.623044 -144.43415)
			(xy 288.603121 -144.382059) (xy 288.590995 -144.327622) (xy 288.586924 -144.272) (xy 277.52319 -144.272)
			(xy 277.51151 -144.282922) (xy 277.504912 -144.28939) (xy 277.496452 -144.305801) (xy 277.495 -144.314926)
			(xy 277.487634 -144.381474) (xy 277.486886 -144.39065) (xy 277.491331 -144.408501) (xy 277.49627 -144.416272)
			(xy 277.512386 -144.440397) (xy 277.53792 -144.492491) (xy 277.555277 -144.547849) (xy 277.564056 -144.605196)
			(xy 277.564596 -144.634204) (xy 277.564148 -144.661457) (xy 277.556391 -144.71541) (xy 277.541033 -144.767708)
			(xy 277.51839 -144.817289) (xy 277.48892 -144.863143) (xy 277.453225 -144.904336) (xy 277.41203 -144.94003)
			(xy 277.366175 -144.969497) (xy 277.316593 -144.992139) (xy 277.264294 -145.007494) (xy 277.210342 -145.015249)
			(xy 277.183088 -145.015712) (xy 277.18258 -145.015712) (xy 277.172783 -145.015648) (xy 277.153215 -145.014631)
			(xy 277.143464 -145.01368) (xy 277.14321 -145.01368) (xy 277.13382 -145.013064) (xy 277.115682 -145.018034)
			(xy 277.107904 -145.023332) (xy 277.044912 -145.070068) (xy 277.035006 -145.08607) (xy 277.033228 -145.095722)
			(xy 277.027834 -145.121559) (xy 277.010903 -145.17155) (xy 276.987243 -145.21873) (xy 276.957306 -145.262199)
			(xy 276.93438 -145.287238) (xy 296.945304 -145.287238) (xy 296.945304 -144.423638) (xy 296.945794 -144.39367)
			(xy 296.953617 -144.334248) (xy 296.96913 -144.276355) (xy 296.992066 -144.220982) (xy 297.022033 -144.169076)
			(xy 297.05852 -144.121526) (xy 297.1009 -144.079146) (xy 297.14845 -144.042659) (xy 297.200356 -144.012692)
			(xy 297.255729 -143.989756) (xy 297.313622 -143.974243) (xy 297.373044 -143.96642) (xy 297.43298 -143.96642)
			(xy 297.492402 -143.974243) (xy 297.550295 -143.989756) (xy 297.605668 -144.012692) (xy 297.657574 -144.042659)
			(xy 297.705124 -144.079146) (xy 297.747504 -144.121526) (xy 297.783991 -144.169076) (xy 297.813958 -144.220982)
			(xy 297.836894 -144.276355) (xy 297.852407 -144.334248) (xy 297.86023 -144.39367) (xy 297.86072 -144.423638)
			(xy 297.86072 -145.287238) (xy 297.86023 -145.317206) (xy 297.852407 -145.376628) (xy 297.836894 -145.434521)
			(xy 297.813958 -145.489894) (xy 297.783991 -145.5418) (xy 297.747504 -145.58935) (xy 297.705124 -145.63173)
			(xy 297.657574 -145.668217) (xy 297.605668 -145.698184) (xy 297.550295 -145.72112) (xy 297.492402 -145.736633)
			(xy 297.43298 -145.744456) (xy 297.373044 -145.744456) (xy 297.313622 -145.736633) (xy 297.255729 -145.72112)
			(xy 297.200356 -145.698184) (xy 297.14845 -145.668217) (xy 297.1009 -145.63173) (xy 297.05852 -145.58935)
			(xy 297.022033 -145.5418) (xy 296.992066 -145.489894) (xy 296.96913 -145.434521) (xy 296.953617 -145.376628)
			(xy 296.945794 -145.317206) (xy 296.945304 -145.287238) (xy 276.93438 -145.287238) (xy 276.921663 -145.301127)
			(xy 276.880995 -145.334771) (xy 276.836079 -145.362488) (xy 276.78777 -145.38375) (xy 276.736992 -145.39815)
			(xy 276.684714 -145.405415) (xy 276.658324 -145.405856) (xy 276.630773 -145.405409) (xy 276.576244 -145.397485)
			(xy 276.523422 -145.381798) (xy 276.473406 -145.358675) (xy 276.427238 -145.328597) (xy 276.385877 -145.29219)
			(xy 276.350184 -145.25021) (xy 276.320902 -145.203533) (xy 276.309328 -145.178526) (xy 276.305518 -145.16989)
			(xy 276.292056 -145.156428) (xy 276.211792 -145.121122) (xy 276.19325 -145.120106) (xy 276.18436 -145.1229)
			(xy 276.183344 -145.123408) (xy 276.168358 -145.128234) (xy 276.159493 -145.131229) (xy 276.144513 -145.142413)
			(xy 276.139148 -145.150078) (xy 276.098254 -145.215356) (xy 276.094698 -145.233136) (xy 276.096222 -145.24228)
			(xy 276.096222 -145.242788) (xy 276.098706 -145.258418) (xy 276.101375 -145.289955) (xy 276.101556 -145.30578)
			(xy 276.10107 -145.333031) (xy 276.093314 -145.386979) (xy 276.077959 -145.439274) (xy 276.055317 -145.488851)
			(xy 276.025851 -145.534701) (xy 275.99016 -145.575892) (xy 275.948969 -145.611583) (xy 275.903119 -145.641049)
			(xy 275.853542 -145.663691) (xy 275.801247 -145.679046) (xy 275.747299 -145.686802) (xy 275.692797 -145.686802)
			(xy 275.638849 -145.679046) (xy 275.586554 -145.663691) (xy 275.536977 -145.641049) (xy 275.491127 -145.611583)
			(xy 275.449936 -145.575892) (xy 275.414245 -145.534701) (xy 275.384779 -145.488851) (xy 275.362137 -145.439274)
			(xy 275.346782 -145.386979) (xy 275.339026 -145.333031) (xy 275.33854 -145.30578) (xy 273.36322 -145.30578)
			(xy 271.92918 -146.739864) (xy 281.109926 -146.739864) (xy 281.113997 -146.684242) (xy 281.126123 -146.629805)
			(xy 281.146046 -146.577714) (xy 281.173342 -146.529079) (xy 281.207428 -146.484936) (xy 281.247577 -146.446227)
			(xy 281.292935 -146.413776) (xy 281.342535 -146.388275) (xy 281.395319 -146.370268) (xy 281.450162 -146.360138)
			(xy 281.505896 -146.358101) (xy 281.561333 -146.364201) (xy 281.61529 -146.378307) (xy 281.666619 -146.400119)
			(xy 281.714225 -146.429173) (xy 281.757093 -146.464848) (xy 281.79431 -146.506385) (xy 281.825083 -146.552898)
			(xy 281.848755 -146.603395) (xy 281.864823 -146.656802) (xy 281.872943 -146.711978) (xy 281.873452 -146.739864)
			(xy 281.872943 -146.76775) (xy 281.868786 -146.795998) (xy 282.743654 -146.795998) (xy 282.747725 -146.740376)
			(xy 282.759851 -146.685939) (xy 282.779774 -146.633848) (xy 282.80707 -146.585213) (xy 282.841156 -146.54107)
			(xy 282.881305 -146.502361) (xy 282.926663 -146.46991) (xy 282.976263 -146.444409) (xy 283.029047 -146.426402)
			(xy 283.08389 -146.416272) (xy 283.139624 -146.414235) (xy 283.195061 -146.420335) (xy 283.249018 -146.434441)
			(xy 283.300347 -146.456253) (xy 283.347953 -146.485307) (xy 283.390821 -146.520982) (xy 283.428038 -146.562519)
			(xy 283.458811 -146.609032) (xy 283.482483 -146.659529) (xy 283.498551 -146.712936) (xy 283.506671 -146.768112)
			(xy 283.50718 -146.795998) (xy 283.506671 -146.823884) (xy 283.498551 -146.87906) (xy 283.482483 -146.932467)
			(xy 283.458811 -146.982964) (xy 283.428038 -147.029477) (xy 283.390821 -147.071014) (xy 283.371208 -147.087336)
			(xy 298.799504 -147.087336) (xy 298.799504 -146.223736) (xy 298.799994 -146.193768) (xy 298.807817 -146.134346)
			(xy 298.82333 -146.076453) (xy 298.846266 -146.02108) (xy 298.876233 -145.969174) (xy 298.91272 -145.921624)
			(xy 298.9551 -145.879244) (xy 299.00265 -145.842757) (xy 299.054556 -145.81279) (xy 299.109929 -145.789854)
			(xy 299.167822 -145.774341) (xy 299.227244 -145.766518) (xy 299.28718 -145.766518) (xy 299.346602 -145.774341)
			(xy 299.404495 -145.789854) (xy 299.459868 -145.81279) (xy 299.511774 -145.842757) (xy 299.559324 -145.879244)
			(xy 299.601704 -145.921624) (xy 299.638191 -145.969174) (xy 299.668158 -146.02108) (xy 299.691094 -146.076453)
			(xy 299.706607 -146.134346) (xy 299.71443 -146.193768) (xy 299.71492 -146.223736) (xy 299.71492 -147.087336)
			(xy 299.71443 -147.117304) (xy 299.706607 -147.176726) (xy 299.691094 -147.234619) (xy 299.668158 -147.289992)
			(xy 299.638191 -147.341898) (xy 299.601704 -147.389448) (xy 299.559324 -147.431828) (xy 299.511774 -147.468315)
			(xy 299.459868 -147.498282) (xy 299.404495 -147.521218) (xy 299.346602 -147.536731) (xy 299.28718 -147.544554)
			(xy 299.227244 -147.544554) (xy 299.167822 -147.536731) (xy 299.109929 -147.521218) (xy 299.054556 -147.498282)
			(xy 299.00265 -147.468315) (xy 298.9551 -147.431828) (xy 298.91272 -147.389448) (xy 298.876233 -147.341898)
			(xy 298.846266 -147.289992) (xy 298.82333 -147.234619) (xy 298.807817 -147.176726) (xy 298.799994 -147.117304)
			(xy 298.799504 -147.087336) (xy 283.371208 -147.087336) (xy 283.347953 -147.106689) (xy 283.300347 -147.135743)
			(xy 283.249018 -147.157555) (xy 283.195061 -147.171661) (xy 283.139624 -147.177761) (xy 283.08389 -147.175724)
			(xy 283.029047 -147.165594) (xy 282.976263 -147.147587) (xy 282.926663 -147.122086) (xy 282.881305 -147.089635)
			(xy 282.841156 -147.050926) (xy 282.80707 -147.006783) (xy 282.779774 -146.958148) (xy 282.759851 -146.906057)
			(xy 282.747725 -146.85162) (xy 282.743654 -146.795998) (xy 281.868786 -146.795998) (xy 281.864823 -146.822926)
			(xy 281.848755 -146.876333) (xy 281.825083 -146.92683) (xy 281.79431 -146.973343) (xy 281.757093 -147.01488)
			(xy 281.714225 -147.050555) (xy 281.666619 -147.079609) (xy 281.61529 -147.101421) (xy 281.561333 -147.115527)
			(xy 281.505896 -147.121627) (xy 281.450162 -147.11959) (xy 281.395319 -147.10946) (xy 281.342535 -147.091453)
			(xy 281.292935 -147.065952) (xy 281.247577 -147.033501) (xy 281.207428 -146.994792) (xy 281.173342 -146.950649)
			(xy 281.146046 -146.902014) (xy 281.126123 -146.849923) (xy 281.113997 -146.795486) (xy 281.109926 -146.739864)
			(xy 271.92918 -146.739864) (xy 269.781677 -148.887434) (xy 296.945304 -148.887434) (xy 296.945304 -148.023834)
			(xy 296.945794 -147.993866) (xy 296.953617 -147.934444) (xy 296.96913 -147.876551) (xy 296.992066 -147.821178)
			(xy 297.022033 -147.769272) (xy 297.05852 -147.721722) (xy 297.1009 -147.679342) (xy 297.14845 -147.642855)
			(xy 297.200356 -147.612888) (xy 297.255729 -147.589952) (xy 297.313622 -147.574439) (xy 297.373044 -147.566616)
			(xy 297.43298 -147.566616) (xy 297.492402 -147.574439) (xy 297.550295 -147.589952) (xy 297.605668 -147.612888)
			(xy 297.657574 -147.642855) (xy 297.705124 -147.679342) (xy 297.747504 -147.721722) (xy 297.783991 -147.769272)
			(xy 297.813958 -147.821178) (xy 297.836894 -147.876551) (xy 297.852407 -147.934444) (xy 297.86023 -147.993866)
			(xy 297.86072 -148.023834) (xy 297.86072 -148.887434) (xy 297.86023 -148.917402) (xy 297.852407 -148.976824)
			(xy 297.836894 -149.034717) (xy 297.813958 -149.09009) (xy 297.783991 -149.141996) (xy 297.747504 -149.189546)
			(xy 297.705124 -149.231926) (xy 297.657574 -149.268413) (xy 297.605668 -149.29838) (xy 297.550295 -149.321316)
			(xy 297.492402 -149.336829) (xy 297.43298 -149.344652) (xy 297.373044 -149.344652) (xy 297.313622 -149.336829)
			(xy 297.255729 -149.321316) (xy 297.200356 -149.29838) (xy 297.14845 -149.268413) (xy 297.1009 -149.231926)
			(xy 297.05852 -149.189546) (xy 297.022033 -149.141996) (xy 296.992066 -149.09009) (xy 296.96913 -149.034717)
			(xy 296.953617 -148.976824) (xy 296.945794 -148.917402) (xy 296.945304 -148.887434) (xy 269.781677 -148.887434)
			(xy 266.37742 -152.291796) (xy 266.376404 -152.301448) (xy 266.376404 -153.3144) (xy 269.390874 -153.3144)
			(xy 269.394945 -153.258778) (xy 269.407071 -153.204341) (xy 269.426994 -153.15225) (xy 269.45429 -153.103615)
			(xy 269.488376 -153.059472) (xy 269.528525 -153.020763) (xy 269.573883 -152.988312) (xy 269.623483 -152.962811)
			(xy 269.676267 -152.944804) (xy 269.73111 -152.934674) (xy 269.786844 -152.932637) (xy 269.842281 -152.938737)
			(xy 269.896238 -152.952843) (xy 269.947567 -152.974655) (xy 269.995173 -153.003709) (xy 270.038041 -153.039384)
			(xy 270.075258 -153.080921) (xy 270.106031 -153.127434) (xy 270.129703 -153.177931) (xy 270.145771 -153.231338)
			(xy 270.153891 -153.286514) (xy 270.1544 -153.3144) (xy 270.153891 -153.342286) (xy 270.145771 -153.397462)
			(xy 270.129703 -153.450869) (xy 270.106031 -153.501366) (xy 270.075258 -153.547879) (xy 270.038041 -153.589416)
			(xy 269.995173 -153.625091) (xy 269.947567 -153.654145) (xy 269.896238 -153.675957) (xy 269.842281 -153.690063)
			(xy 269.786844 -153.696163) (xy 269.73111 -153.694126) (xy 269.676267 -153.683996) (xy 269.623483 -153.665989)
			(xy 269.573883 -153.640488) (xy 269.528525 -153.608037) (xy 269.488376 -153.569328) (xy 269.45429 -153.525185)
			(xy 269.426994 -153.47655) (xy 269.407071 -153.424459) (xy 269.394945 -153.370022) (xy 269.390874 -153.3144)
			(xy 266.376404 -153.3144) (xy 266.376404 -155.56738) (xy 266.37742 -155.577032) (xy 266.379045 -155.584278)
			(xy 266.385881 -155.597451) (xy 266.390882 -155.60294) (xy 266.71524 -155.927298) (xy 266.72074 -155.932284)
			(xy 266.733907 -155.939125) (xy 266.741148 -155.94076) (xy 266.7508 -155.941776) (xy 268.969236 -155.941776)
			(xy 268.980666 -155.939744) (xy 268.993112 -155.935934) (xy 268.998848 -155.933093) (xy 269.008756 -155.924996)
			(xy 269.01267 -155.919932) (xy 269.06728 -155.846272) (xy 269.067788 -155.843224) (xy 269.057298 -155.812214)
			(xy 269.042479 -155.748445) (xy 269.034861 -155.683423) (xy 269.03426 -155.650692) (xy 269.03426 -155.648152)
			(xy 269.03426 -155.647644) (xy 269.03426 -155.64358) (xy 269.035022 -155.61818) (xy 269.037672 -155.578483)
			(xy 269.052358 -155.50029) (xy 269.077492 -155.424805) (xy 269.094458 -155.388818) (xy 269.096744 -155.383992)
			(xy 269.09903 -155.374848) (xy 269.100346 -155.368349) (xy 269.099958 -155.355099) (xy 269.098268 -155.348686)
			(xy 269.09395 -155.334208) (xy 269.089886 -155.327858) (xy 269.071876 -155.299278) (xy 269.041811 -155.23878)
			(xy 269.018899 -155.175228) (xy 269.003442 -155.109463) (xy 268.995646 -155.042358) (xy 268.995144 -155.00858)
			(xy 268.995144 -155.008326) (xy 268.995676 -154.972922) (xy 269.004206 -154.902631) (xy 269.021145 -154.83388)
			(xy 269.046245 -154.767671) (xy 269.079141 -154.704969) (xy 269.119354 -154.646689) (xy 269.166297 -154.593679)
			(xy 269.219286 -154.546713) (xy 269.277548 -154.506475) (xy 269.340235 -154.473551) (xy 269.406433 -154.448422)
			(xy 269.475177 -154.431453) (xy 269.545465 -154.422892) (xy 269.580868 -154.422348) (xy 270.149828 -154.422348)
			(xy 270.15893 -154.421361) (xy 270.175592 -154.413805) (xy 270.18234 -154.407616) (xy 275.52142 -149.068536)
			(xy 275.529802 -149.060408) (xy 275.530818 -149.059392) (xy 275.678138 -148.912072) (xy 275.685535 -148.905224)
			(xy 275.704134 -148.897492) (xy 275.714206 -148.897086) (xy 275.92401 -148.897086) (xy 275.935694 -148.896832)
			(xy 285.16707 -148.896832) (xy 285.202485 -148.897343) (xy 285.272799 -148.905878) (xy 285.341572 -148.922826)
			(xy 285.4078 -148.94794) (xy 285.470518 -148.980855) (xy 285.528811 -149.021089) (xy 285.581829 -149.068057)
			(xy 285.628799 -149.121074) (xy 285.669035 -149.179365) (xy 285.701952 -149.242082) (xy 285.727068 -149.308309)
			(xy 285.744019 -149.377081) (xy 285.752555 -149.447395) (xy 285.753048 -149.48281) (xy 285.752563 -149.514894)
			(xy 285.745439 -149.578666) (xy 285.738824 -149.610064) (xy 285.732303 -149.637962) (xy 285.714541 -149.692434)
			(xy 285.691551 -149.744915) (xy 285.677864 -149.770084) (xy 285.674816 -149.775164) (xy 285.671768 -149.785578)
			(xy 285.669849 -149.792821) (xy 285.669852 -149.807798) (xy 285.671768 -149.815042) (xy 285.674816 -149.825456)
			(xy 285.677864 -149.830536) (xy 285.691563 -149.855699) (xy 285.714554 -149.90818) (xy 285.732315 -149.962655)
			(xy 285.738824 -149.990556) (xy 285.745424 -150.021957) (xy 285.752551 -150.085727) (xy 285.753048 -150.11781)
			(xy 285.752534 -150.153223) (xy 285.743995 -150.223533) (xy 285.727044 -150.2923) (xy 285.701927 -150.358523)
			(xy 285.669011 -150.421235) (xy 285.628775 -150.479523) (xy 285.581807 -150.532535) (xy 285.528791 -150.5795)
			(xy 285.470501 -150.619732) (xy 285.407786 -150.652643) (xy 285.341562 -150.677756) (xy 285.302921 -150.687278)
			(xy 298.799504 -150.687278) (xy 298.799504 -149.823678) (xy 298.799994 -149.79371) (xy 298.807817 -149.734288)
			(xy 298.82333 -149.676395) (xy 298.846266 -149.621022) (xy 298.876233 -149.569116) (xy 298.91272 -149.521566)
			(xy 298.9551 -149.479186) (xy 299.00265 -149.442699) (xy 299.054556 -149.412732) (xy 299.109929 -149.389796)
			(xy 299.167822 -149.374283) (xy 299.227244 -149.36646) (xy 299.28718 -149.36646) (xy 299.346602 -149.374283)
			(xy 299.404495 -149.389796) (xy 299.459868 -149.412732) (xy 299.511774 -149.442699) (xy 299.559324 -149.479186)
			(xy 299.601704 -149.521566) (xy 299.638191 -149.569116) (xy 299.668158 -149.621022) (xy 299.691094 -149.676395)
			(xy 299.706607 -149.734288) (xy 299.71443 -149.79371) (xy 299.71492 -149.823678) (xy 299.71492 -150.687278)
			(xy 299.71443 -150.717246) (xy 299.706607 -150.776668) (xy 299.691094 -150.834561) (xy 299.668158 -150.889934)
			(xy 299.638191 -150.94184) (xy 299.601704 -150.98939) (xy 299.559324 -151.03177) (xy 299.511774 -151.068257)
			(xy 299.459868 -151.098224) (xy 299.404495 -151.12116) (xy 299.346602 -151.136673) (xy 299.28718 -151.144496)
			(xy 299.227244 -151.144496) (xy 299.167822 -151.136673) (xy 299.109929 -151.12116) (xy 299.054556 -151.098224)
			(xy 299.00265 -151.068257) (xy 298.9551 -151.03177) (xy 298.91272 -150.98939) (xy 298.876233 -150.94184)
			(xy 298.846266 -150.889934) (xy 298.82333 -150.834561) (xy 298.807817 -150.776668) (xy 298.799994 -150.717246)
			(xy 298.799504 -150.687278) (xy 285.302921 -150.687278) (xy 285.272793 -150.694702) (xy 285.202483 -150.703236)
			(xy 285.16707 -150.703788) (xy 276.328886 -150.703788) (xy 276.319783 -150.704774) (xy 276.303121 -150.71233)
			(xy 276.296374 -150.71852) (xy 275.757867 -151.257) (xy 284.776924 -151.257) (xy 284.780995 -151.201378)
			(xy 284.793121 -151.146941) (xy 284.813044 -151.09485) (xy 284.84034 -151.046215) (xy 284.874426 -151.002072)
			(xy 284.914575 -150.963363) (xy 284.959933 -150.930912) (xy 285.009533 -150.905411) (xy 285.062317 -150.887404)
			(xy 285.11716 -150.877274) (xy 285.172894 -150.875237) (xy 285.228331 -150.881337) (xy 285.282288 -150.895443)
			(xy 285.333617 -150.917255) (xy 285.381223 -150.946309) (xy 285.424091 -150.981984) (xy 285.461308 -151.023521)
			(xy 285.492081 -151.070034) (xy 285.515753 -151.120531) (xy 285.531821 -151.173938) (xy 285.539941 -151.229114)
			(xy 285.54045 -151.257) (xy 285.539941 -151.284886) (xy 285.531821 -151.340062) (xy 285.515753 -151.393469)
			(xy 285.492081 -151.443966) (xy 285.461308 -151.490479) (xy 285.424091 -151.532016) (xy 285.381223 -151.567691)
			(xy 285.333617 -151.596745) (xy 285.282288 -151.618557) (xy 285.228331 -151.632663) (xy 285.172894 -151.638763)
			(xy 285.11716 -151.636726) (xy 285.062317 -151.626596) (xy 285.009533 -151.608589) (xy 284.959933 -151.583088)
			(xy 284.914575 -151.550637) (xy 284.874426 -151.511928) (xy 284.84034 -151.467785) (xy 284.813044 -151.41915)
			(xy 284.793121 -151.367059) (xy 284.780995 -151.312622) (xy 284.776924 -151.257) (xy 275.757867 -151.257)
			(xy 274.527429 -152.487376) (xy 296.945304 -152.487376) (xy 296.945304 -151.623776) (xy 296.945794 -151.593808)
			(xy 296.953617 -151.534386) (xy 296.96913 -151.476493) (xy 296.992066 -151.42112) (xy 297.022033 -151.369214)
			(xy 297.05852 -151.321664) (xy 297.1009 -151.279284) (xy 297.14845 -151.242797) (xy 297.200356 -151.21283)
			(xy 297.255729 -151.189894) (xy 297.313622 -151.174381) (xy 297.373044 -151.166558) (xy 297.43298 -151.166558)
			(xy 297.492402 -151.174381) (xy 297.550295 -151.189894) (xy 297.605668 -151.21283) (xy 297.657574 -151.242797)
			(xy 297.705124 -151.279284) (xy 297.747504 -151.321664) (xy 297.783991 -151.369214) (xy 297.813958 -151.42112)
			(xy 297.836894 -151.476493) (xy 297.852407 -151.534386) (xy 297.86023 -151.593808) (xy 297.86072 -151.623776)
			(xy 297.86072 -152.487376) (xy 297.86023 -152.517344) (xy 297.852407 -152.576766) (xy 297.836894 -152.634659)
			(xy 297.813958 -152.690032) (xy 297.783991 -152.741938) (xy 297.747504 -152.789488) (xy 297.705124 -152.831868)
			(xy 297.657574 -152.868355) (xy 297.605668 -152.898322) (xy 297.550295 -152.921258) (xy 297.492402 -152.936771)
			(xy 297.43298 -152.944594) (xy 297.373044 -152.944594) (xy 297.313622 -152.936771) (xy 297.255729 -152.921258)
			(xy 297.200356 -152.898322) (xy 297.14845 -152.868355) (xy 297.1009 -152.831868) (xy 297.05852 -152.789488)
			(xy 297.022033 -152.741938) (xy 296.992066 -152.690032) (xy 296.96913 -152.634659) (xy 296.953617 -152.576766)
			(xy 296.945794 -152.517344) (xy 296.945304 -152.487376) (xy 274.527429 -152.487376) (xy 273.454733 -153.560018)
			(xy 284.649924 -153.560018) (xy 284.653995 -153.504396) (xy 284.666121 -153.449959) (xy 284.686044 -153.397868)
			(xy 284.71334 -153.349233) (xy 284.747426 -153.30509) (xy 284.787575 -153.266381) (xy 284.832933 -153.23393)
			(xy 284.882533 -153.208429) (xy 284.935317 -153.190422) (xy 284.99016 -153.180292) (xy 285.045894 -153.178255)
			(xy 285.101331 -153.184355) (xy 285.155288 -153.198461) (xy 285.206617 -153.220273) (xy 285.254223 -153.249327)
			(xy 285.297091 -153.285002) (xy 285.334308 -153.326539) (xy 285.365081 -153.373052) (xy 285.388753 -153.423549)
			(xy 285.404821 -153.476956) (xy 285.412941 -153.532132) (xy 285.41345 -153.560018) (xy 285.412941 -153.587904)
			(xy 285.404821 -153.64308) (xy 285.388753 -153.696487) (xy 285.365081 -153.746984) (xy 285.334308 -153.793497)
			(xy 285.297091 -153.835034) (xy 285.254223 -153.870709) (xy 285.206617 -153.899763) (xy 285.155288 -153.921575)
			(xy 285.101331 -153.935681) (xy 285.045894 -153.941781) (xy 284.99016 -153.939744) (xy 284.935317 -153.929614)
			(xy 284.882533 -153.911607) (xy 284.832933 -153.886106) (xy 284.787575 -153.853655) (xy 284.747426 -153.814946)
			(xy 284.71334 -153.770803) (xy 284.686044 -153.722168) (xy 284.666121 -153.670077) (xy 284.653995 -153.61564)
			(xy 284.649924 -153.560018) (xy 273.454733 -153.560018) (xy 272.854755 -154.159966) (xy 283.506924 -154.159966)
			(xy 283.510995 -154.104344) (xy 283.523121 -154.049907) (xy 283.543044 -153.997816) (xy 283.57034 -153.949181)
			(xy 283.604426 -153.905038) (xy 283.644575 -153.866329) (xy 283.689933 -153.833878) (xy 283.739533 -153.808377)
			(xy 283.792317 -153.79037) (xy 283.84716 -153.78024) (xy 283.902894 -153.778203) (xy 283.958331 -153.784303)
			(xy 284.012288 -153.798409) (xy 284.063617 -153.820221) (xy 284.111223 -153.849275) (xy 284.154091 -153.88495)
			(xy 284.191308 -153.926487) (xy 284.222081 -153.973) (xy 284.245753 -154.023497) (xy 284.261821 -154.076904)
			(xy 284.269941 -154.13208) (xy 284.27045 -154.159966) (xy 284.269941 -154.187852) (xy 284.261821 -154.243028)
			(xy 284.248525 -154.28722) (xy 298.799504 -154.28722) (xy 298.799504 -153.42362) (xy 298.799994 -153.393652)
			(xy 298.807817 -153.33423) (xy 298.82333 -153.276337) (xy 298.846266 -153.220964) (xy 298.876233 -153.169058)
			(xy 298.91272 -153.121508) (xy 298.9551 -153.079128) (xy 299.00265 -153.042641) (xy 299.054556 -153.012674)
			(xy 299.109929 -152.989738) (xy 299.167822 -152.974225) (xy 299.227244 -152.966402) (xy 299.28718 -152.966402)
			(xy 299.346602 -152.974225) (xy 299.404495 -152.989738) (xy 299.459868 -153.012674) (xy 299.511774 -153.042641)
			(xy 299.559324 -153.079128) (xy 299.601704 -153.121508) (xy 299.638191 -153.169058) (xy 299.668158 -153.220964)
			(xy 299.691094 -153.276337) (xy 299.706607 -153.33423) (xy 299.71443 -153.393652) (xy 299.71492 -153.42362)
			(xy 299.71492 -154.28722) (xy 299.71443 -154.317188) (xy 299.706607 -154.37661) (xy 299.691094 -154.434503)
			(xy 299.668158 -154.489876) (xy 299.638191 -154.541782) (xy 299.601704 -154.589332) (xy 299.559324 -154.631712)
			(xy 299.511774 -154.668199) (xy 299.459868 -154.698166) (xy 299.404495 -154.721102) (xy 299.346602 -154.736615)
			(xy 299.28718 -154.744438) (xy 299.227244 -154.744438) (xy 299.167822 -154.736615) (xy 299.109929 -154.721102)
			(xy 299.054556 -154.698166) (xy 299.00265 -154.668199) (xy 298.9551 -154.631712) (xy 298.91272 -154.589332)
			(xy 298.876233 -154.541782) (xy 298.846266 -154.489876) (xy 298.82333 -154.434503) (xy 298.807817 -154.37661)
			(xy 298.799994 -154.317188) (xy 298.799504 -154.28722) (xy 284.248525 -154.28722) (xy 284.245753 -154.296435)
			(xy 284.222081 -154.346932) (xy 284.191308 -154.393445) (xy 284.154091 -154.434982) (xy 284.111223 -154.470657)
			(xy 284.063617 -154.499711) (xy 284.012288 -154.521523) (xy 283.958331 -154.535629) (xy 283.902894 -154.541729)
			(xy 283.84716 -154.539692) (xy 283.792317 -154.529562) (xy 283.739533 -154.511555) (xy 283.689933 -154.486054)
			(xy 283.644575 -154.453603) (xy 283.604426 -154.414894) (xy 283.57034 -154.370751) (xy 283.543044 -154.322116)
			(xy 283.523121 -154.270025) (xy 283.510995 -154.215588) (xy 283.506924 -154.159966) (xy 272.854755 -154.159966)
			(xy 271.973077 -155.0416) (xy 280.363674 -155.0416) (xy 280.367745 -154.985978) (xy 280.379871 -154.931541)
			(xy 280.399794 -154.87945) (xy 280.42709 -154.830815) (xy 280.461176 -154.786672) (xy 280.501325 -154.747963)
			(xy 280.546683 -154.715512) (xy 280.596283 -154.690011) (xy 280.649067 -154.672004) (xy 280.70391 -154.661874)
			(xy 280.759644 -154.659837) (xy 280.815081 -154.665937) (xy 280.869038 -154.680043) (xy 280.920367 -154.701855)
			(xy 280.967973 -154.730909) (xy 281.010841 -154.766584) (xy 281.048058 -154.808121) (xy 281.078831 -154.854634)
			(xy 281.102503 -154.905131) (xy 281.118496 -154.958288) (xy 284.944056 -154.958288) (xy 284.948127 -154.902666)
			(xy 284.960253 -154.848229) (xy 284.980176 -154.796138) (xy 285.007472 -154.747503) (xy 285.041558 -154.70336)
			(xy 285.081707 -154.664651) (xy 285.127065 -154.6322) (xy 285.176665 -154.606699) (xy 285.229449 -154.588692)
			(xy 285.284292 -154.578562) (xy 285.340026 -154.576525) (xy 285.395463 -154.582625) (xy 285.44942 -154.596731)
			(xy 285.500749 -154.618543) (xy 285.548355 -154.647597) (xy 285.591223 -154.683272) (xy 285.62844 -154.724809)
			(xy 285.659213 -154.771322) (xy 285.682885 -154.821819) (xy 285.698953 -154.875226) (xy 285.707073 -154.930402)
			(xy 285.707582 -154.958288) (xy 285.707073 -154.986174) (xy 285.698953 -155.04135) (xy 285.682885 -155.094757)
			(xy 285.659213 -155.145254) (xy 285.62844 -155.191767) (xy 285.591223 -155.233304) (xy 285.548355 -155.268979)
			(xy 285.500749 -155.298033) (xy 285.44942 -155.319845) (xy 285.395463 -155.333951) (xy 285.340026 -155.340051)
			(xy 285.284292 -155.338014) (xy 285.229449 -155.327884) (xy 285.176665 -155.309877) (xy 285.127065 -155.284376)
			(xy 285.081707 -155.251925) (xy 285.041558 -155.213216) (xy 285.007472 -155.169073) (xy 284.980176 -155.120438)
			(xy 284.960253 -155.068347) (xy 284.948127 -155.01391) (xy 284.944056 -154.958288) (xy 281.118496 -154.958288)
			(xy 281.118571 -154.958538) (xy 281.126691 -155.013714) (xy 281.1272 -155.0416) (xy 281.126691 -155.069486)
			(xy 281.118571 -155.124662) (xy 281.102503 -155.178069) (xy 281.078831 -155.228566) (xy 281.048058 -155.275079)
			(xy 281.010841 -155.316616) (xy 280.967973 -155.352291) (xy 280.920367 -155.381345) (xy 280.869038 -155.403157)
			(xy 280.815081 -155.417263) (xy 280.759644 -155.423363) (xy 280.70391 -155.421326) (xy 280.649067 -155.411196)
			(xy 280.596283 -155.393189) (xy 280.546683 -155.367688) (xy 280.501325 -155.335237) (xy 280.461176 -155.296528)
			(xy 280.42709 -155.252385) (xy 280.399794 -155.20375) (xy 280.379871 -155.151659) (xy 280.367745 -155.097222)
			(xy 280.363674 -155.0416) (xy 271.973077 -155.0416) (xy 271.246092 -155.768548) (xy 271.235917 -155.779536)
			(xy 271.221873 -155.805968) (xy 271.216088 -155.835336) (xy 271.219056 -155.86512) (xy 271.230523 -155.892768)
			(xy 271.249507 -155.915909) (xy 271.27438 -155.93256) (xy 271.303009 -155.941293) (xy 271.317974 -155.941776)
			(xy 280.346912 -155.941776) (xy 280.35092 -155.941705) (xy 280.358832 -155.940425) (xy 280.36266 -155.939236)
			(xy 280.374852 -155.933394) (xy 280.380948 -155.92933) (xy 280.390854 -155.917392) (xy 280.393648 -155.910534)
			(xy 280.400914 -155.893708) (xy 280.418218 -155.861395) (xy 280.428192 -155.846018) (xy 280.443567 -155.823825)
			(xy 280.479572 -155.783592) (xy 280.520889 -155.748838) (xy 280.566693 -155.720256) (xy 280.616069 -155.698418)
			(xy 280.668031 -155.683759) (xy 280.721541 -155.676573) (xy 280.77553 -155.677003) (xy 280.828918 -155.685041)
			(xy 280.88064 -155.700526) (xy 280.929663 -155.723148) (xy 280.975006 -155.752456) (xy 281.015763 -155.787864)
			(xy 281.051122 -155.828665) (xy 281.080375 -155.874043) (xy 281.092148 -155.898342) (xy 281.092656 -155.89885)
			(xy 281.095196 -155.904692) (xy 281.103832 -155.914598) (xy 281.132026 -155.93314) (xy 281.138405 -155.937074)
			(xy 281.152732 -155.941454) (xy 281.16022 -155.941776) (xy 283.530294 -155.941776) (xy 283.535462 -155.941589)
			(xy 283.545571 -155.939411) (xy 283.55036 -155.937458) (xy 283.558234 -155.933648) (xy 283.563294 -155.930517)
			(xy 283.571905 -155.92231) (xy 283.575252 -155.917392) (xy 283.593032 -155.88742) (xy 283.593032 -155.886912)
			(xy 283.61894 -155.842208) (xy 283.623657 -155.833117) (xy 283.626134 -155.812804) (xy 283.623766 -155.802838)
			(xy 283.619956 -155.78963) (xy 283.615384 -155.781248) (xy 283.611828 -155.774644) (xy 283.598236 -155.747269)
			(xy 283.578991 -155.689262) (xy 283.569254 -155.628926) (xy 283.568648 -155.598368) (xy 283.569134 -155.571117)
			(xy 283.57689 -155.517169) (xy 283.592245 -155.464874) (xy 283.614887 -155.415297) (xy 283.644353 -155.369447)
			(xy 283.680044 -155.328256) (xy 283.721235 -155.292565) (xy 283.767085 -155.263099) (xy 283.816662 -155.240457)
			(xy 283.868957 -155.225102) (xy 283.922905 -155.217346) (xy 283.977407 -155.217346) (xy 284.031355 -155.225102)
			(xy 284.08365 -155.240457) (xy 284.133227 -155.263099) (xy 284.179077 -155.292565) (xy 284.220268 -155.328256)
			(xy 284.255959 -155.369447) (xy 284.285425 -155.415297) (xy 284.308067 -155.464874) (xy 284.323422 -155.517169)
			(xy 284.331178 -155.571117) (xy 284.331664 -155.598368) (xy 284.329632 -155.636976) (xy 284.328616 -155.647136)
			(xy 284.331156 -155.65628) (xy 284.332909 -155.661656) (xy 284.338414 -155.671531) (xy 284.342078 -155.675838)
			(xy 284.38729 -155.726638) (xy 284.388814 -155.727908) (xy 284.395672 -155.734766) (xy 284.401422 -155.739963)
			(xy 284.415255 -155.746936) (xy 284.42285 -155.748482) (xy 284.431232 -155.749244) (xy 284.996128 -155.749244)
			(xy 285.001148 -155.749154) (xy 285.011002 -155.74724) (xy 285.015686 -155.745434) (xy 285.063438 -155.725622)
			(xy 285.08357 -155.717678) (xy 285.12538 -155.70649) (xy 285.16829 -155.700844) (xy 285.18993 -155.700476)
			(xy 292.98011 -155.700476) (xy 293.006132 -155.701008) (xy 293.05753 -155.709184) (xy 293.10702 -155.725285)
			(xy 293.153389 -155.748919) (xy 293.195498 -155.779503) (xy 293.214298 -155.797504) (xy 293.358062 -155.941268)
			(xy 293.365174 -155.941776) (xy 296.894504 -155.941776) (xy 296.904523 -155.941355) (xy 296.923034 -155.933684)
			(xy 296.937199 -155.919511) (xy 296.944861 -155.900995) (xy 296.945304 -155.890976) (xy 296.945304 -155.223718)
			(xy 296.945794 -155.19375) (xy 296.953617 -155.134328) (xy 296.96913 -155.076435) (xy 296.992066 -155.021062)
			(xy 297.022033 -154.969156) (xy 297.05852 -154.921606) (xy 297.1009 -154.879226) (xy 297.14845 -154.842739)
			(xy 297.200356 -154.812772) (xy 297.255729 -154.789836) (xy 297.313622 -154.774323) (xy 297.373044 -154.7665)
			(xy 297.43298 -154.7665) (xy 297.492402 -154.774323) (xy 297.550295 -154.789836) (xy 297.605668 -154.812772)
			(xy 297.657574 -154.842739) (xy 297.705124 -154.879226) (xy 297.747504 -154.921606) (xy 297.783991 -154.969156)
			(xy 297.813958 -155.021062) (xy 297.836894 -155.076435) (xy 297.852407 -155.134328) (xy 297.86023 -155.19375)
			(xy 297.86072 -155.223718) (xy 297.86072 -155.890976) (xy 297.861136 -155.900999) (xy 297.868802 -155.919521)
			(xy 297.882976 -155.933695) (xy 297.901497 -155.941363) (xy 297.91152 -155.941776) (xy 307.432456 -155.941776)
			(xy 307.440838 -155.941014) (xy 307.442108 -155.94076) (xy 308.104032 -155.278836) (xy 308.105048 -155.269184)
			(xy 308.105048 -129.481834) (xy 308.104978 -129.478028) (xy 308.103824 -129.470504) (xy 308.102762 -129.466848)
			(xy 308.096158 -129.445512) (xy 308.09184 -129.439162) (xy 308.072646 -129.410107) (xy 308.040562 -129.348302)
			(xy 308.016085 -129.283108) (xy 307.999567 -129.215458) (xy 307.991242 -129.14632) (xy 307.990748 -129.111502)
			(xy 307.990748 -128.669288) (xy 307.99147 -128.637261) (xy 307.99907 -128.573648) (xy 308.013616 -128.511256)
			(xy 308.034932 -128.450841) (xy 308.062758 -128.393135) (xy 308.079394 -128.365758) (xy 308.083204 -128.359662)
			(xy 308.085236 -128.35255) (xy 308.087014 -128.339088) (xy 308.087014 -128.328928) (xy 308.085236 -128.315466)
			(xy 308.083204 -128.308354) (xy 308.079394 -128.302258) (xy 308.062741 -128.274889) (xy 308.034895 -128.217187)
			(xy 308.013569 -128.156771) (xy 307.999022 -128.094376) (xy 307.991431 -128.030758) (xy 307.990748 -127.998728)
			(xy 307.990748 -127.556768) (xy 307.991471 -127.524741) (xy 307.999073 -127.461129) (xy 308.013621 -127.398739)
			(xy 308.034938 -127.338325) (xy 308.062766 -127.28062) (xy 308.079394 -127.253238) (xy 308.083204 -127.247142)
			(xy 308.085236 -127.24003) (xy 308.087014 -127.226568) (xy 308.087014 -127.216408) (xy 308.085236 -127.202946)
			(xy 308.083204 -127.195834) (xy 308.079394 -127.189738) (xy 308.062742 -127.162368) (xy 308.034898 -127.104667)
			(xy 308.013574 -127.044251) (xy 307.999029 -126.981855) (xy 307.99144 -126.918238) (xy 307.990748 -126.886208)
			(xy 307.990748 -126.444248) (xy 307.991472 -126.412221) (xy 307.999077 -126.34861) (xy 308.013626 -126.286221)
			(xy 308.034945 -126.225808) (xy 308.062774 -126.168105) (xy 308.079394 -126.140718) (xy 308.083204 -126.134622)
			(xy 308.085236 -126.12751) (xy 308.087014 -126.114048) (xy 308.087014 -126.103888) (xy 308.085236 -126.090426)
			(xy 308.083204 -126.083314) (xy 308.079394 -126.077218) (xy 308.062743 -126.049848) (xy 308.034901 -125.992146)
			(xy 308.013579 -125.93173) (xy 307.999037 -125.869334) (xy 307.991449 -125.805717) (xy 307.990748 -125.773688)
			(xy 307.990748 -125.331728) (xy 307.991473 -125.299702) (xy 307.99908 -125.236092) (xy 308.013631 -125.173703)
			(xy 308.034952 -125.113292) (xy 308.062782 -125.055589) (xy 308.079394 -125.028198) (xy 308.083204 -125.022102)
			(xy 308.085236 -125.01499) (xy 308.087014 -125.001528) (xy 308.087014 -124.991368) (xy 308.085236 -124.977906)
			(xy 308.083204 -124.970794) (xy 308.079394 -124.964698) (xy 308.062744 -124.937328) (xy 308.034904 -124.879625)
			(xy 308.013584 -124.819209) (xy 307.999044 -124.756814) (xy 307.991459 -124.693197) (xy 307.990748 -124.661168)
			(xy 307.990748 -124.219208) (xy 307.991474 -124.187182) (xy 307.999083 -124.123573) (xy 308.013636 -124.061185)
			(xy 308.034958 -124.000775) (xy 308.062791 -123.943074) (xy 308.079394 -123.915678) (xy 308.083204 -123.909582)
			(xy 308.085236 -123.90247) (xy 308.087014 -123.889008) (xy 308.087014 -123.878848) (xy 308.085236 -123.865386)
			(xy 308.083204 -123.858274) (xy 308.079394 -123.852178) (xy 308.06274 -123.824809) (xy 308.034892 -123.767108)
			(xy 308.013564 -123.706692) (xy 307.999015 -123.644296) (xy 307.991421 -123.580678) (xy 307.990748 -123.548648)
			(xy 307.990748 -123.106688) (xy 307.99147 -123.074661) (xy 307.99907 -123.011048) (xy 308.013616 -122.948656)
			(xy 308.034932 -122.888241) (xy 308.062758 -122.830535) (xy 308.079394 -122.803158) (xy 308.083204 -122.797062)
			(xy 308.085236 -122.78995) (xy 308.087014 -122.776488) (xy 308.087014 -122.766328) (xy 308.085236 -122.752866)
			(xy 308.083204 -122.745754) (xy 308.079394 -122.739658) (xy 308.062741 -122.712289) (xy 308.034895 -122.654587)
			(xy 308.013569 -122.594171) (xy 307.999022 -122.531776) (xy 307.991431 -122.468158) (xy 307.990748 -122.436128)
			(xy 307.990748 -121.994168) (xy 307.991471 -121.962141) (xy 307.999073 -121.898529) (xy 308.013621 -121.836139)
			(xy 308.034938 -121.775725) (xy 308.062766 -121.71802) (xy 308.079394 -121.690638) (xy 308.083204 -121.684542)
			(xy 308.085236 -121.67743) (xy 308.087014 -121.663968) (xy 308.087014 -121.653808) (xy 308.085236 -121.640346)
			(xy 308.083204 -121.633234) (xy 308.079394 -121.627138) (xy 308.062742 -121.599768) (xy 308.034898 -121.542067)
			(xy 308.013574 -121.481651) (xy 307.999029 -121.419255) (xy 307.99144 -121.355638) (xy 307.990748 -121.323608)
			(xy 307.990748 -120.881648) (xy 307.991472 -120.849621) (xy 307.999077 -120.78601) (xy 308.013626 -120.723621)
			(xy 308.034945 -120.663208) (xy 308.062774 -120.605505) (xy 308.079394 -120.578118) (xy 308.083204 -120.572022)
			(xy 308.085236 -120.56491) (xy 308.087014 -120.551448) (xy 308.087014 -120.541288) (xy 308.085236 -120.527826)
			(xy 308.083204 -120.520714) (xy 308.079394 -120.514618) (xy 308.062743 -120.487248) (xy 308.034901 -120.429546)
			(xy 308.013579 -120.36913) (xy 307.999037 -120.306734) (xy 307.991449 -120.243117) (xy 307.990748 -120.211088)
			(xy 307.990748 -119.769128) (xy 307.991473 -119.737102) (xy 307.99908 -119.673492) (xy 308.013631 -119.611103)
			(xy 308.034952 -119.550692) (xy 308.062782 -119.492989) (xy 308.079394 -119.465598) (xy 308.083204 -119.459502)
			(xy 308.085236 -119.45239) (xy 308.087014 -119.438928) (xy 308.087014 -119.428768) (xy 308.085236 -119.415306)
			(xy 308.083204 -119.408194) (xy 308.079394 -119.402098) (xy 308.062744 -119.374728) (xy 308.034904 -119.317025)
			(xy 308.013584 -119.256609) (xy 307.999044 -119.194214) (xy 307.991459 -119.130597) (xy 307.990748 -119.098568)
			(xy 307.990748 -118.656608) (xy 307.991279 -118.621053) (xy 307.999937 -118.550473) (xy 308.017124 -118.481473)
			(xy 308.042585 -118.415078) (xy 308.075941 -118.352278) (xy 308.095904 -118.322852) (xy 308.100476 -118.316248)
			(xy 308.102762 -118.309136) (xy 308.10383 -118.305417) (xy 308.104979 -118.297765) (xy 308.105048 -118.293896)
			(xy 308.105048 -118.27637) (xy 308.104618 -118.266303) (xy 308.09689 -118.247712) (xy 308.090062 -118.240302)
			(xy 307.927502 -118.077742) (xy 307.920106 -118.070891) (xy 307.901507 -118.063149) (xy 307.891434 -118.062756)
			(xy 307.685694 -118.062756) (xy 307.675626 -118.063182) (xy 307.657028 -118.070904) (xy 307.649626 -118.077742)
			(xy 307.550566 -118.176802) (xy 307.526787 -118.199911) (xy 307.474933 -118.241241) (xy 307.418778 -118.276508)
			(xy 307.359029 -118.305266) (xy 307.296435 -118.327155) (xy 307.231785 -118.341901) (xy 307.165891 -118.349316)
			(xy 307.132736 -118.349776) (xy 307.097029 -118.349261) (xy 307.026137 -118.340657) (xy 306.956798 -118.323569)
			(xy 306.890025 -118.298248) (xy 306.826791 -118.265063) (xy 306.768018 -118.224497) (xy 306.714564 -118.177142)
			(xy 306.667208 -118.123688) (xy 306.626641 -118.064916) (xy 306.593455 -118.001683) (xy 306.568133 -117.93491)
			(xy 306.551045 -117.865571) (xy 306.54244 -117.794679) (xy 306.541932 -117.758972) (xy 306.541932 -117.758464)
			(xy 306.542381 -117.726202) (xy 306.549444 -117.662066) (xy 306.56345 -117.599081) (xy 306.584231 -117.537995)
			(xy 306.611542 -117.479536) (xy 306.645056 -117.424399) (xy 306.66436 -117.398546) (xy 306.67452 -117.385846)
			(xy 306.675028 -117.384068) (xy 306.675028 -117.27815) (xy 306.66944 -117.262402) (xy 306.66436 -117.255798)
			(xy 306.645032 -117.22996) (xy 306.611503 -117.174828) (xy 306.584184 -117.116368) (xy 306.563403 -117.055278)
			(xy 306.549407 -116.992286) (xy 306.542362 -116.928144) (xy 306.541932 -116.89588) (xy 306.541932 -116.895372)
			(xy 306.542451 -116.859668) (xy 306.551062 -116.788781) (xy 306.568154 -116.719449) (xy 306.593479 -116.652683)
			(xy 306.626667 -116.589457) (xy 306.667235 -116.530691) (xy 306.71459 -116.477244) (xy 306.768042 -116.429895)
			(xy 306.826811 -116.389334) (xy 306.890042 -116.356153) (xy 306.956811 -116.330835) (xy 307.026144 -116.31375)
			(xy 307.097032 -116.305147) (xy 307.132736 -116.304568) (xy 307.16589 -116.305034) (xy 307.231782 -116.312457)
			(xy 307.29643 -116.327206) (xy 307.359022 -116.349096) (xy 307.418771 -116.377852) (xy 307.474927 -116.413113)
			(xy 307.526786 -116.454435) (xy 307.550566 -116.477542) (xy 307.657246 -116.584222) (xy 307.664643 -116.59107)
			(xy 307.683242 -116.5988) (xy 307.693314 -116.599208) (xy 308.274212 -116.599208) (xy 308.307367 -116.599672)
			(xy 308.373259 -116.607094) (xy 308.437908 -116.621841) (xy 308.5005 -116.643731) (xy 308.56025 -116.672486)
			(xy 308.616407 -116.707747) (xy 308.668266 -116.749071) (xy 308.692042 -116.772182) (xy 309.40883 -117.48897)
			(xy 309.43194 -117.512748) (xy 309.473272 -117.564601) (xy 309.508539 -117.620756) (xy 309.537298 -117.680506)
			(xy 309.559186 -117.743099) (xy 309.573929 -117.80775) (xy 309.581342 -117.873645) (xy 309.581804 -117.9068)
			(xy 309.581804 -119.559324) (xy 313.274456 -119.559324) (xy 313.274456 -118.695724) (xy 313.274946 -118.665756)
			(xy 313.282769 -118.606334) (xy 313.298282 -118.548441) (xy 313.321218 -118.493068) (xy 313.351185 -118.441162)
			(xy 313.387672 -118.393612) (xy 313.430052 -118.351232) (xy 313.477602 -118.314745) (xy 313.529508 -118.284778)
			(xy 313.584881 -118.261842) (xy 313.642774 -118.246329) (xy 313.702196 -118.238506) (xy 313.762132 -118.238506)
			(xy 313.821554 -118.246329) (xy 313.879447 -118.261842) (xy 313.93482 -118.284778) (xy 313.986726 -118.314745)
			(xy 314.034276 -118.351232) (xy 314.076656 -118.393612) (xy 314.113143 -118.441162) (xy 314.14311 -118.493068)
			(xy 314.166046 -118.548441) (xy 314.181559 -118.606334) (xy 314.189382 -118.665756) (xy 314.189872 -118.695724)
			(xy 314.189872 -119.559324) (xy 314.189382 -119.589292) (xy 314.181559 -119.648714) (xy 314.166046 -119.706607)
			(xy 314.14311 -119.76198) (xy 314.113143 -119.813886) (xy 314.076656 -119.861436) (xy 314.034276 -119.903816)
			(xy 313.986726 -119.940303) (xy 313.93482 -119.97027) (xy 313.879447 -119.993206) (xy 313.821554 -120.008719)
			(xy 313.762132 -120.016542) (xy 313.702196 -120.016542) (xy 313.642774 -120.008719) (xy 313.584881 -119.993206)
			(xy 313.529508 -119.97027) (xy 313.477602 -119.940303) (xy 313.430052 -119.903816) (xy 313.387672 -119.861436)
			(xy 313.351185 -119.813886) (xy 313.321218 -119.76198) (xy 313.298282 -119.706607) (xy 313.282769 -119.648714)
			(xy 313.274946 -119.589292) (xy 313.274456 -119.559324) (xy 309.581804 -119.559324) (xy 309.581804 -121.365772)
			(xy 315.916564 -121.365772) (xy 315.916564 -120.502172) (xy 315.917054 -120.472204) (xy 315.924877 -120.412782)
			(xy 315.94039 -120.354889) (xy 315.963326 -120.299516) (xy 315.993293 -120.24761) (xy 316.02978 -120.20006)
			(xy 316.07216 -120.15768) (xy 316.11971 -120.121193) (xy 316.171616 -120.091226) (xy 316.226989 -120.06829)
			(xy 316.284882 -120.052777) (xy 316.344304 -120.044954) (xy 316.40424 -120.044954) (xy 316.463662 -120.052777)
			(xy 316.521555 -120.06829) (xy 316.576928 -120.091226) (xy 316.628834 -120.121193) (xy 316.676384 -120.15768)
			(xy 316.718764 -120.20006) (xy 316.755251 -120.24761) (xy 316.785218 -120.299516) (xy 316.808154 -120.354889)
			(xy 316.823667 -120.412782) (xy 316.83149 -120.472204) (xy 316.83198 -120.502172) (xy 316.83198 -121.365772)
			(xy 316.83149 -121.39574) (xy 316.823667 -121.455162) (xy 316.808154 -121.513055) (xy 316.785218 -121.568428)
			(xy 316.755251 -121.620334) (xy 316.718764 -121.667884) (xy 316.676384 -121.710264) (xy 316.628834 -121.746751)
			(xy 316.576928 -121.776718) (xy 316.521555 -121.799654) (xy 316.463662 -121.815167) (xy 316.40424 -121.82299)
			(xy 316.344304 -121.82299) (xy 316.284882 -121.815167) (xy 316.226989 -121.799654) (xy 316.171616 -121.776718)
			(xy 316.11971 -121.746751) (xy 316.07216 -121.710264) (xy 316.02978 -121.667884) (xy 315.993293 -121.620334)
			(xy 315.963326 -121.568428) (xy 315.94039 -121.513055) (xy 315.924877 -121.455162) (xy 315.917054 -121.39574)
			(xy 315.916564 -121.365772) (xy 309.581804 -121.365772) (xy 309.581804 -123.159266) (xy 313.274456 -123.159266)
			(xy 313.274456 -122.295666) (xy 313.274946 -122.265698) (xy 313.282769 -122.206276) (xy 313.298282 -122.148383)
			(xy 313.321218 -122.09301) (xy 313.351185 -122.041104) (xy 313.387672 -121.993554) (xy 313.430052 -121.951174)
			(xy 313.477602 -121.914687) (xy 313.529508 -121.88472) (xy 313.584881 -121.861784) (xy 313.642774 -121.846271)
			(xy 313.702196 -121.838448) (xy 313.762132 -121.838448) (xy 313.821554 -121.846271) (xy 313.879447 -121.861784)
			(xy 313.93482 -121.88472) (xy 313.986726 -121.914687) (xy 314.034276 -121.951174) (xy 314.076656 -121.993554)
			(xy 314.113143 -122.041104) (xy 314.14311 -122.09301) (xy 314.166046 -122.148383) (xy 314.181559 -122.206276)
			(xy 314.189382 -122.265698) (xy 314.189872 -122.295666) (xy 314.189872 -123.159266) (xy 314.189382 -123.189234)
			(xy 314.181559 -123.248656) (xy 314.166046 -123.306549) (xy 314.14311 -123.361922) (xy 314.113143 -123.413828)
			(xy 314.076656 -123.461378) (xy 314.034276 -123.503758) (xy 313.986726 -123.540245) (xy 313.93482 -123.570212)
			(xy 313.879447 -123.593148) (xy 313.821554 -123.608661) (xy 313.762132 -123.616484) (xy 313.702196 -123.616484)
			(xy 313.642774 -123.608661) (xy 313.584881 -123.593148) (xy 313.529508 -123.570212) (xy 313.477602 -123.540245)
			(xy 313.430052 -123.503758) (xy 313.387672 -123.461378) (xy 313.351185 -123.413828) (xy 313.321218 -123.361922)
			(xy 313.298282 -123.306549) (xy 313.282769 -123.248656) (xy 313.274946 -123.189234) (xy 313.274456 -123.159266)
			(xy 309.581804 -123.159266) (xy 309.581804 -124.965714) (xy 315.916564 -124.965714) (xy 315.916564 -124.102114)
			(xy 315.917054 -124.072146) (xy 315.924877 -124.012724) (xy 315.94039 -123.954831) (xy 315.963326 -123.899458)
			(xy 315.993293 -123.847552) (xy 316.02978 -123.800002) (xy 316.07216 -123.757622) (xy 316.11971 -123.721135)
			(xy 316.171616 -123.691168) (xy 316.226989 -123.668232) (xy 316.284882 -123.652719) (xy 316.344304 -123.644896)
			(xy 316.40424 -123.644896) (xy 316.463662 -123.652719) (xy 316.521555 -123.668232) (xy 316.576928 -123.691168)
			(xy 316.628834 -123.721135) (xy 316.676384 -123.757622) (xy 316.718764 -123.800002) (xy 316.755251 -123.847552)
			(xy 316.785218 -123.899458) (xy 316.808154 -123.954831) (xy 316.823667 -124.012724) (xy 316.83149 -124.072146)
			(xy 316.83198 -124.102114) (xy 316.83198 -124.965714) (xy 316.83149 -124.995682) (xy 316.823667 -125.055104)
			(xy 316.808154 -125.112997) (xy 316.785218 -125.16837) (xy 316.755251 -125.220276) (xy 316.718764 -125.267826)
			(xy 316.676384 -125.310206) (xy 316.628834 -125.346693) (xy 316.576928 -125.37666) (xy 316.521555 -125.399596)
			(xy 316.463662 -125.415109) (xy 316.40424 -125.422932) (xy 316.344304 -125.422932) (xy 316.284882 -125.415109)
			(xy 316.226989 -125.399596) (xy 316.171616 -125.37666) (xy 316.11971 -125.346693) (xy 316.07216 -125.310206)
			(xy 316.02978 -125.267826) (xy 315.993293 -125.220276) (xy 315.963326 -125.16837) (xy 315.94039 -125.112997)
			(xy 315.924877 -125.055104) (xy 315.917054 -124.995682) (xy 315.916564 -124.965714) (xy 309.581804 -124.965714)
			(xy 309.581804 -130.769106) (xy 313.274456 -130.769106) (xy 313.274456 -129.905506) (xy 313.274946 -129.875538)
			(xy 313.282769 -129.816116) (xy 313.298282 -129.758223) (xy 313.321218 -129.70285) (xy 313.351185 -129.650944)
			(xy 313.387672 -129.603394) (xy 313.430052 -129.561014) (xy 313.477602 -129.524527) (xy 313.529508 -129.49456)
			(xy 313.584881 -129.471624) (xy 313.642774 -129.456111) (xy 313.702196 -129.448288) (xy 313.762132 -129.448288)
			(xy 313.821554 -129.456111) (xy 313.879447 -129.471624) (xy 313.93482 -129.49456) (xy 313.986726 -129.524527)
			(xy 314.034276 -129.561014) (xy 314.076656 -129.603394) (xy 314.113143 -129.650944) (xy 314.14311 -129.70285)
			(xy 314.166046 -129.758223) (xy 314.181559 -129.816116) (xy 314.189382 -129.875538) (xy 314.189872 -129.905506)
			(xy 314.189872 -130.769106) (xy 314.189382 -130.799074) (xy 314.181559 -130.858496) (xy 314.166046 -130.916389)
			(xy 314.14311 -130.971762) (xy 314.113143 -131.023668) (xy 314.076656 -131.071218) (xy 314.034276 -131.113598)
			(xy 313.986726 -131.150085) (xy 313.93482 -131.180052) (xy 313.879447 -131.202988) (xy 313.821554 -131.218501)
			(xy 313.762132 -131.226324) (xy 313.702196 -131.226324) (xy 313.642774 -131.218501) (xy 313.584881 -131.202988)
			(xy 313.529508 -131.180052) (xy 313.477602 -131.150085) (xy 313.430052 -131.113598) (xy 313.387672 -131.071218)
			(xy 313.351185 -131.023668) (xy 313.321218 -130.971762) (xy 313.298282 -130.916389) (xy 313.282769 -130.858496)
			(xy 313.274946 -130.799074) (xy 313.274456 -130.769106) (xy 309.581804 -130.769106) (xy 309.581804 -132.575808)
			(xy 315.916564 -132.575808) (xy 315.916564 -131.712208) (xy 315.917054 -131.68224) (xy 315.924877 -131.622818)
			(xy 315.94039 -131.564925) (xy 315.963326 -131.509552) (xy 315.993293 -131.457646) (xy 316.02978 -131.410096)
			(xy 316.07216 -131.367716) (xy 316.11971 -131.331229) (xy 316.171616 -131.301262) (xy 316.226989 -131.278326)
			(xy 316.284882 -131.262813) (xy 316.344304 -131.25499) (xy 316.40424 -131.25499) (xy 316.463662 -131.262813)
			(xy 316.521555 -131.278326) (xy 316.576928 -131.301262) (xy 316.628834 -131.331229) (xy 316.676384 -131.367716)
			(xy 316.718764 -131.410096) (xy 316.755251 -131.457646) (xy 316.785218 -131.509552) (xy 316.808154 -131.564925)
			(xy 316.823667 -131.622818) (xy 316.83149 -131.68224) (xy 316.83198 -131.712208) (xy 316.83198 -132.575808)
			(xy 316.83149 -132.605776) (xy 316.823667 -132.665198) (xy 316.808154 -132.723091) (xy 316.785218 -132.778464)
			(xy 316.755251 -132.83037) (xy 316.718764 -132.87792) (xy 316.676384 -132.9203) (xy 316.628834 -132.956787)
			(xy 316.576928 -132.986754) (xy 316.521555 -133.00969) (xy 316.463662 -133.025203) (xy 316.40424 -133.033026)
			(xy 316.344304 -133.033026) (xy 316.284882 -133.025203) (xy 316.226989 -133.00969) (xy 316.171616 -132.986754)
			(xy 316.11971 -132.956787) (xy 316.07216 -132.9203) (xy 316.02978 -132.87792) (xy 315.993293 -132.83037)
			(xy 315.963326 -132.778464) (xy 315.94039 -132.723091) (xy 315.924877 -132.665198) (xy 315.917054 -132.605776)
			(xy 315.916564 -132.575808) (xy 309.581804 -132.575808) (xy 309.581804 -134.369302) (xy 313.274456 -134.369302)
			(xy 313.274456 -133.505702) (xy 313.274946 -133.475734) (xy 313.282769 -133.416312) (xy 313.298282 -133.358419)
			(xy 313.321218 -133.303046) (xy 313.351185 -133.25114) (xy 313.387672 -133.20359) (xy 313.430052 -133.16121)
			(xy 313.477602 -133.124723) (xy 313.529508 -133.094756) (xy 313.584881 -133.07182) (xy 313.642774 -133.056307)
			(xy 313.702196 -133.048484) (xy 313.762132 -133.048484) (xy 313.821554 -133.056307) (xy 313.879447 -133.07182)
			(xy 313.93482 -133.094756) (xy 313.986726 -133.124723) (xy 314.034276 -133.16121) (xy 314.076656 -133.20359)
			(xy 314.113143 -133.25114) (xy 314.14311 -133.303046) (xy 314.166046 -133.358419) (xy 314.181559 -133.416312)
			(xy 314.189382 -133.475734) (xy 314.189872 -133.505702) (xy 314.189872 -134.369302) (xy 314.189382 -134.39927)
			(xy 314.181559 -134.458692) (xy 314.166046 -134.516585) (xy 314.14311 -134.571958) (xy 314.113143 -134.623864)
			(xy 314.076656 -134.671414) (xy 314.034276 -134.713794) (xy 313.986726 -134.750281) (xy 313.93482 -134.780248)
			(xy 313.879447 -134.803184) (xy 313.821554 -134.818697) (xy 313.762132 -134.82652) (xy 313.702196 -134.82652)
			(xy 313.642774 -134.818697) (xy 313.584881 -134.803184) (xy 313.529508 -134.780248) (xy 313.477602 -134.750281)
			(xy 313.430052 -134.713794) (xy 313.387672 -134.671414) (xy 313.351185 -134.623864) (xy 313.321218 -134.571958)
			(xy 313.298282 -134.516585) (xy 313.282769 -134.458692) (xy 313.274946 -134.39927) (xy 313.274456 -134.369302)
			(xy 309.581804 -134.369302) (xy 309.581804 -136.17575) (xy 315.916564 -136.17575) (xy 315.916564 -135.31215)
			(xy 315.917054 -135.282182) (xy 315.924877 -135.22276) (xy 315.94039 -135.164867) (xy 315.963326 -135.109494)
			(xy 315.993293 -135.057588) (xy 316.02978 -135.010038) (xy 316.07216 -134.967658) (xy 316.11971 -134.931171)
			(xy 316.171616 -134.901204) (xy 316.226989 -134.878268) (xy 316.284882 -134.862755) (xy 316.344304 -134.854932)
			(xy 316.40424 -134.854932) (xy 316.463662 -134.862755) (xy 316.521555 -134.878268) (xy 316.576928 -134.901204)
			(xy 316.628834 -134.931171) (xy 316.676384 -134.967658) (xy 316.718764 -135.010038) (xy 316.755251 -135.057588)
			(xy 316.785218 -135.109494) (xy 316.808154 -135.164867) (xy 316.823667 -135.22276) (xy 316.83149 -135.282182)
			(xy 316.83198 -135.31215) (xy 316.83198 -136.17575) (xy 316.83149 -136.205718) (xy 316.823667 -136.26514)
			(xy 316.808154 -136.323033) (xy 316.785218 -136.378406) (xy 316.755251 -136.430312) (xy 316.718764 -136.477862)
			(xy 316.676384 -136.520242) (xy 316.628834 -136.556729) (xy 316.576928 -136.586696) (xy 316.521555 -136.609632)
			(xy 316.463662 -136.625145) (xy 316.40424 -136.632968) (xy 316.344304 -136.632968) (xy 316.284882 -136.625145)
			(xy 316.226989 -136.609632) (xy 316.171616 -136.586696) (xy 316.11971 -136.556729) (xy 316.07216 -136.520242)
			(xy 316.02978 -136.477862) (xy 315.993293 -136.430312) (xy 315.963326 -136.378406) (xy 315.94039 -136.323033)
			(xy 315.924877 -136.26514) (xy 315.917054 -136.205718) (xy 315.916564 -136.17575) (xy 309.581804 -136.17575)
			(xy 309.581804 -136.98601) (xy 312.757564 -136.98601) (xy 312.761635 -136.930388) (xy 312.773761 -136.875951)
			(xy 312.793684 -136.82386) (xy 312.82098 -136.775225) (xy 312.855066 -136.731082) (xy 312.895215 -136.692373)
			(xy 312.940573 -136.659922) (xy 312.990173 -136.634421) (xy 313.042957 -136.616414) (xy 313.0978 -136.606284)
			(xy 313.153534 -136.604247) (xy 313.208971 -136.610347) (xy 313.262928 -136.624453) (xy 313.314257 -136.646265)
			(xy 313.361863 -136.675319) (xy 313.404731 -136.710994) (xy 313.441948 -136.752531) (xy 313.472721 -136.799044)
			(xy 313.496393 -136.849541) (xy 313.512461 -136.902948) (xy 313.520581 -136.958124) (xy 313.52109 -136.98601)
			(xy 313.520581 -137.013896) (xy 313.512461 -137.069072) (xy 313.496393 -137.122479) (xy 313.472721 -137.172976)
			(xy 313.441948 -137.219489) (xy 313.404731 -137.261026) (xy 313.361863 -137.296701) (xy 313.314257 -137.325755)
			(xy 313.262928 -137.347567) (xy 313.208971 -137.361673) (xy 313.153534 -137.367773) (xy 313.0978 -137.365736)
			(xy 313.042957 -137.355606) (xy 312.990173 -137.337599) (xy 312.940573 -137.312098) (xy 312.895215 -137.279647)
			(xy 312.855066 -137.240938) (xy 312.82098 -137.196795) (xy 312.793684 -137.14816) (xy 312.773761 -137.096069)
			(xy 312.761635 -137.041632) (xy 312.757564 -136.98601) (xy 309.581804 -136.98601) (xy 309.581804 -140.487654)
			(xy 317.90208 -140.487654) (xy 317.906151 -140.432032) (xy 317.918277 -140.377595) (xy 317.9382 -140.325504)
			(xy 317.965496 -140.276869) (xy 317.999582 -140.232726) (xy 318.039731 -140.194017) (xy 318.085089 -140.161566)
			(xy 318.134689 -140.136065) (xy 318.187473 -140.118058) (xy 318.242316 -140.107928) (xy 318.29805 -140.105891)
			(xy 318.353487 -140.111991) (xy 318.407444 -140.126097) (xy 318.458773 -140.147909) (xy 318.506379 -140.176963)
			(xy 318.549247 -140.212638) (xy 318.586464 -140.254175) (xy 318.617237 -140.300688) (xy 318.640909 -140.351185)
			(xy 318.65331 -140.392404) (xy 356.667814 -140.392404) (xy 356.671885 -140.336782) (xy 356.684011 -140.282345)
			(xy 356.703934 -140.230254) (xy 356.73123 -140.181619) (xy 356.765316 -140.137476) (xy 356.805465 -140.098767)
			(xy 356.850823 -140.066316) (xy 356.900423 -140.040815) (xy 356.953207 -140.022808) (xy 357.00805 -140.012678)
			(xy 357.063784 -140.010641) (xy 357.119221 -140.016741) (xy 357.173178 -140.030847) (xy 357.224507 -140.052659)
			(xy 357.272113 -140.081713) (xy 357.314981 -140.117388) (xy 357.352198 -140.158925) (xy 357.382971 -140.205438)
			(xy 357.406643 -140.255935) (xy 357.422711 -140.309342) (xy 357.430831 -140.364518) (xy 357.43134 -140.392404)
			(xy 357.430831 -140.42029) (xy 357.422711 -140.475466) (xy 357.406643 -140.528873) (xy 357.382971 -140.57937)
			(xy 357.352198 -140.625883) (xy 357.314981 -140.66742) (xy 357.272113 -140.703095) (xy 357.224507 -140.732149)
			(xy 357.173178 -140.753961) (xy 357.119221 -140.768067) (xy 357.063784 -140.774167) (xy 357.00805 -140.77213)
			(xy 356.953207 -140.762) (xy 356.900423 -140.743993) (xy 356.850823 -140.718492) (xy 356.805465 -140.686041)
			(xy 356.765316 -140.647332) (xy 356.73123 -140.603189) (xy 356.703934 -140.554554) (xy 356.684011 -140.502463)
			(xy 356.671885 -140.448026) (xy 356.667814 -140.392404) (xy 318.65331 -140.392404) (xy 318.656977 -140.404592)
			(xy 318.665097 -140.459768) (xy 318.665606 -140.487654) (xy 318.665097 -140.51554) (xy 318.656977 -140.570716)
			(xy 318.640909 -140.624123) (xy 318.617237 -140.67462) (xy 318.586464 -140.721133) (xy 318.549247 -140.76267)
			(xy 318.506379 -140.798345) (xy 318.479823 -140.814552) (xy 351.041206 -140.814552) (xy 351.045277 -140.75893)
			(xy 351.057403 -140.704493) (xy 351.077326 -140.652402) (xy 351.104622 -140.603767) (xy 351.138708 -140.559624)
			(xy 351.178857 -140.520915) (xy 351.224215 -140.488464) (xy 351.273815 -140.462963) (xy 351.326599 -140.444956)
			(xy 351.381442 -140.434826) (xy 351.437176 -140.432789) (xy 351.492613 -140.438889) (xy 351.54657 -140.452995)
			(xy 351.597899 -140.474807) (xy 351.645505 -140.503861) (xy 351.688373 -140.539536) (xy 351.72559 -140.581073)
			(xy 351.756363 -140.627586) (xy 351.780035 -140.678083) (xy 351.796103 -140.73149) (xy 351.804223 -140.786666)
			(xy 351.804732 -140.814552) (xy 351.804223 -140.842438) (xy 351.796103 -140.897614) (xy 351.780035 -140.951021)
			(xy 351.756363 -141.001518) (xy 351.72559 -141.048031) (xy 351.688373 -141.089568) (xy 351.645505 -141.125243)
			(xy 351.597899 -141.154297) (xy 351.54657 -141.176109) (xy 351.492613 -141.190215) (xy 351.437176 -141.196315)
			(xy 351.381442 -141.194278) (xy 351.326599 -141.184148) (xy 351.273815 -141.166141) (xy 351.224215 -141.14064)
			(xy 351.178857 -141.108189) (xy 351.138708 -141.06948) (xy 351.104622 -141.025337) (xy 351.077326 -140.976702)
			(xy 351.057403 -140.924611) (xy 351.045277 -140.870174) (xy 351.041206 -140.814552) (xy 318.479823 -140.814552)
			(xy 318.458773 -140.827399) (xy 318.407444 -140.849211) (xy 318.353487 -140.863317) (xy 318.29805 -140.869417)
			(xy 318.242316 -140.86738) (xy 318.187473 -140.85725) (xy 318.134689 -140.839243) (xy 318.085089 -140.813742)
			(xy 318.039731 -140.781291) (xy 317.999582 -140.742582) (xy 317.965496 -140.698439) (xy 317.9382 -140.649804)
			(xy 317.918277 -140.597713) (xy 317.906151 -140.543276) (xy 317.90208 -140.487654) (xy 309.581804 -140.487654)
			(xy 309.581804 -141.424152) (xy 336.674204 -141.424152) (xy 336.678275 -141.36853) (xy 336.690401 -141.314093)
			(xy 336.710324 -141.262002) (xy 336.73762 -141.213367) (xy 336.771706 -141.169224) (xy 336.811855 -141.130515)
			(xy 336.857213 -141.098064) (xy 336.906813 -141.072563) (xy 336.959597 -141.054556) (xy 337.01444 -141.044426)
			(xy 337.070174 -141.042389) (xy 337.125611 -141.048489) (xy 337.179568 -141.062595) (xy 337.230897 -141.084407)
			(xy 337.278503 -141.113461) (xy 337.321371 -141.149136) (xy 337.358588 -141.190673) (xy 337.389361 -141.237186)
			(xy 337.409018 -141.279118) (xy 354.101652 -141.279118) (xy 354.105723 -141.223496) (xy 354.117849 -141.169059)
			(xy 354.137772 -141.116968) (xy 354.165068 -141.068333) (xy 354.199154 -141.02419) (xy 354.239303 -140.985481)
			(xy 354.284661 -140.95303) (xy 354.334261 -140.927529) (xy 354.387045 -140.909522) (xy 354.441888 -140.899392)
			(xy 354.497622 -140.897355) (xy 354.553059 -140.903455) (xy 354.607016 -140.917561) (xy 354.658345 -140.939373)
			(xy 354.705951 -140.968427) (xy 354.748819 -141.004102) (xy 354.786036 -141.045639) (xy 354.786639 -141.046551)
			(xy 359.055154 -141.046551) (xy 359.055154 -140.992049) (xy 359.06291 -140.938101) (xy 359.078264 -140.885806)
			(xy 359.100904 -140.836228) (xy 359.130368 -140.790377) (xy 359.166058 -140.749185) (xy 359.207246 -140.713491)
			(xy 359.253095 -140.684022) (xy 359.30267 -140.661377) (xy 359.354964 -140.646018) (xy 359.408911 -140.638256)
			(xy 359.436162 -140.637768) (xy 359.462477 -140.638204) (xy 359.514606 -140.645447) (xy 359.565249 -140.659773)
			(xy 359.613448 -140.680911) (xy 359.658291 -140.708462) (xy 359.69893 -140.741905) (xy 359.717086 -140.760958)
			(xy 359.724617 -140.768349) (xy 359.74389 -140.776881) (xy 359.754424 -140.777468) (xy 359.8291 -140.777468)
			(xy 359.839653 -140.776962) (xy 359.858948 -140.768412) (xy 359.866438 -140.760958) (xy 359.884574 -140.741883)
			(xy 359.925209 -140.708429) (xy 359.970053 -140.680874) (xy 360.018258 -140.659739) (xy 360.068908 -140.645426)
			(xy 360.121045 -140.638205) (xy 360.147362 -140.637768) (xy 360.174615 -140.638277) (xy 360.228567 -140.646029)
			(xy 360.280866 -140.661381) (xy 360.330447 -140.684019) (xy 360.376302 -140.713485) (xy 360.417497 -140.749176)
			(xy 360.453193 -140.790367) (xy 360.482662 -140.836219) (xy 360.505306 -140.885799) (xy 360.520663 -140.938096)
			(xy 360.528421 -140.992047) (xy 360.528421 -141.046553) (xy 360.520663 -141.100504) (xy 360.505306 -141.152801)
			(xy 360.482662 -141.202381) (xy 360.453193 -141.248233) (xy 360.417497 -141.289424) (xy 360.376302 -141.325115)
			(xy 360.330447 -141.354581) (xy 360.280866 -141.377219) (xy 360.228567 -141.392571) (xy 360.174615 -141.400323)
			(xy 360.147362 -141.400784) (xy 360.121047 -141.400347) (xy 360.068917 -141.393107) (xy 360.018273 -141.378782)
			(xy 359.970074 -141.357644) (xy 359.925232 -141.330092) (xy 359.884594 -141.296648) (xy 359.866438 -141.277594)
			(xy 359.858905 -141.270206) (xy 359.839634 -141.261674) (xy 359.8291 -141.261084) (xy 359.754424 -141.261084)
			(xy 359.743875 -141.261618) (xy 359.72458 -141.27015) (xy 359.717086 -141.277594) (xy 359.698929 -141.296648)
			(xy 359.6583 -141.330106) (xy 359.61346 -141.357665) (xy 359.565259 -141.378804) (xy 359.514612 -141.393121)
			(xy 359.462478 -141.400346) (xy 359.436162 -141.400784) (xy 359.408911 -141.400344) (xy 359.354964 -141.392582)
			(xy 359.30267 -141.377223) (xy 359.253095 -141.354578) (xy 359.207246 -141.325109) (xy 359.166058 -141.289415)
			(xy 359.130368 -141.248223) (xy 359.100904 -141.202372) (xy 359.078264 -141.152794) (xy 359.06291 -141.100499)
			(xy 359.055154 -141.046551) (xy 354.786639 -141.046551) (xy 354.816809 -141.092152) (xy 354.840481 -141.142649)
			(xy 354.856549 -141.196056) (xy 354.864669 -141.251232) (xy 354.865178 -141.279118) (xy 354.864669 -141.307004)
			(xy 354.856549 -141.36218) (xy 354.840481 -141.415587) (xy 354.816809 -141.466084) (xy 354.786036 -141.512597)
			(xy 354.748819 -141.554134) (xy 354.705951 -141.589809) (xy 354.658345 -141.618863) (xy 354.607016 -141.640675)
			(xy 354.553059 -141.654781) (xy 354.497622 -141.660881) (xy 354.441888 -141.658844) (xy 354.387045 -141.648714)
			(xy 354.334261 -141.630707) (xy 354.284661 -141.605206) (xy 354.239303 -141.572755) (xy 354.199154 -141.534046)
			(xy 354.165068 -141.489903) (xy 354.137772 -141.441268) (xy 354.117849 -141.389177) (xy 354.105723 -141.33474)
			(xy 354.101652 -141.279118) (xy 337.409018 -141.279118) (xy 337.413033 -141.287683) (xy 337.429101 -141.34109)
			(xy 337.437221 -141.396266) (xy 337.43773 -141.424152) (xy 337.437221 -141.452038) (xy 337.429101 -141.507214)
			(xy 337.413033 -141.560621) (xy 337.389361 -141.611118) (xy 337.358588 -141.657631) (xy 337.321371 -141.699168)
			(xy 337.278503 -141.734843) (xy 337.230897 -141.763897) (xy 337.179568 -141.785709) (xy 337.125611 -141.799815)
			(xy 337.070174 -141.805915) (xy 337.01444 -141.803878) (xy 336.959597 -141.793748) (xy 336.906813 -141.775741)
			(xy 336.857213 -141.75024) (xy 336.811855 -141.717789) (xy 336.771706 -141.67908) (xy 336.73762 -141.634937)
			(xy 336.710324 -141.586302) (xy 336.690401 -141.534211) (xy 336.678275 -141.479774) (xy 336.674204 -141.424152)
			(xy 309.581804 -141.424152) (xy 309.581804 -141.859) (xy 334.643982 -141.859) (xy 334.648053 -141.803378)
			(xy 334.660179 -141.748941) (xy 334.680102 -141.69685) (xy 334.707398 -141.648215) (xy 334.741484 -141.604072)
			(xy 334.781633 -141.565363) (xy 334.826991 -141.532912) (xy 334.876591 -141.507411) (xy 334.929375 -141.489404)
			(xy 334.984218 -141.479274) (xy 335.039952 -141.477237) (xy 335.095389 -141.483337) (xy 335.149346 -141.497443)
			(xy 335.200675 -141.519255) (xy 335.248281 -141.548309) (xy 335.291149 -141.583984) (xy 335.328366 -141.625521)
			(xy 335.359139 -141.672034) (xy 335.382811 -141.722531) (xy 335.398879 -141.775938) (xy 335.406999 -141.831114)
			(xy 335.407508 -141.859) (xy 335.406999 -141.886886) (xy 335.400076 -141.93393) (xy 349.735392 -141.93393)
			(xy 349.739463 -141.878308) (xy 349.751589 -141.823871) (xy 349.771512 -141.77178) (xy 349.798808 -141.723145)
			(xy 349.832894 -141.679002) (xy 349.873043 -141.640293) (xy 349.918401 -141.607842) (xy 349.968001 -141.582341)
			(xy 350.020785 -141.564334) (xy 350.075628 -141.554204) (xy 350.131362 -141.552167) (xy 350.186799 -141.558267)
			(xy 350.240756 -141.572373) (xy 350.292085 -141.594185) (xy 350.339691 -141.623239) (xy 350.382559 -141.658914)
			(xy 350.419776 -141.700451) (xy 350.450549 -141.746964) (xy 350.474221 -141.797461) (xy 350.490289 -141.850868)
			(xy 350.498409 -141.906044) (xy 350.498918 -141.93393) (xy 350.498409 -141.961816) (xy 350.490289 -142.016992)
			(xy 350.474221 -142.070399) (xy 350.450549 -142.120896) (xy 350.419776 -142.167409) (xy 350.382559 -142.208946)
			(xy 350.339691 -142.244621) (xy 350.292085 -142.273675) (xy 350.240756 -142.295487) (xy 350.186799 -142.309593)
			(xy 350.131362 -142.315693) (xy 350.075628 -142.313656) (xy 350.020785 -142.303526) (xy 349.968001 -142.285519)
			(xy 349.918401 -142.260018) (xy 349.873043 -142.227567) (xy 349.832894 -142.188858) (xy 349.798808 -142.144715)
			(xy 349.771512 -142.09608) (xy 349.751589 -142.043989) (xy 349.739463 -141.989552) (xy 349.735392 -141.93393)
			(xy 335.400076 -141.93393) (xy 335.398879 -141.942062) (xy 335.382811 -141.995469) (xy 335.359139 -142.045966)
			(xy 335.328366 -142.092479) (xy 335.291149 -142.134016) (xy 335.248281 -142.169691) (xy 335.200675 -142.198745)
			(xy 335.149346 -142.220557) (xy 335.095389 -142.234663) (xy 335.039952 -142.240763) (xy 334.984218 -142.238726)
			(xy 334.929375 -142.228596) (xy 334.876591 -142.210589) (xy 334.826991 -142.185088) (xy 334.781633 -142.152637)
			(xy 334.741484 -142.113928) (xy 334.707398 -142.069785) (xy 334.680102 -142.02115) (xy 334.660179 -141.969059)
			(xy 334.648053 -141.914622) (xy 334.643982 -141.859) (xy 309.581804 -141.859) (xy 309.581804 -143.479266)
			(xy 313.274456 -143.479266) (xy 313.274456 -142.615666) (xy 313.274946 -142.585698) (xy 313.282769 -142.526276)
			(xy 313.298282 -142.468383) (xy 313.321218 -142.41301) (xy 313.351185 -142.361104) (xy 313.387672 -142.313554)
			(xy 313.430052 -142.271174) (xy 313.477602 -142.234687) (xy 313.529508 -142.20472) (xy 313.584881 -142.181784)
			(xy 313.642774 -142.166271) (xy 313.702196 -142.158448) (xy 313.762132 -142.158448) (xy 313.821554 -142.166271)
			(xy 313.879447 -142.181784) (xy 313.93482 -142.20472) (xy 313.986726 -142.234687) (xy 314.034276 -142.271174)
			(xy 314.076656 -142.313554) (xy 314.113143 -142.361104) (xy 314.14311 -142.41301) (xy 314.166046 -142.468383)
			(xy 314.181559 -142.526276) (xy 314.189382 -142.585698) (xy 314.189872 -142.615666) (xy 314.189872 -142.875)
			(xy 334.643982 -142.875) (xy 334.648053 -142.819378) (xy 334.660179 -142.764941) (xy 334.680102 -142.71285)
			(xy 334.707398 -142.664215) (xy 334.741484 -142.620072) (xy 334.781633 -142.581363) (xy 334.826991 -142.548912)
			(xy 334.876591 -142.523411) (xy 334.929375 -142.505404) (xy 334.984218 -142.495274) (xy 335.039952 -142.493237)
			(xy 335.095389 -142.499337) (xy 335.149346 -142.513443) (xy 335.200675 -142.535255) (xy 335.248281 -142.564309)
			(xy 335.291149 -142.599984) (xy 335.328366 -142.641521) (xy 335.359139 -142.688034) (xy 335.382811 -142.738531)
			(xy 335.398879 -142.791938) (xy 335.406999 -142.847114) (xy 335.407508 -142.875) (xy 336.675982 -142.875)
			(xy 336.680053 -142.819378) (xy 336.692179 -142.764941) (xy 336.712102 -142.71285) (xy 336.739398 -142.664215)
			(xy 336.773484 -142.620072) (xy 336.813633 -142.581363) (xy 336.858991 -142.548912) (xy 336.908591 -142.523411)
			(xy 336.961375 -142.505404) (xy 337.016218 -142.495274) (xy 337.071952 -142.493237) (xy 337.127389 -142.499337)
			(xy 337.181346 -142.513443) (xy 337.232675 -142.535255) (xy 337.280281 -142.564309) (xy 337.323149 -142.599984)
			(xy 337.360366 -142.641521) (xy 337.391139 -142.688034) (xy 337.414811 -142.738531) (xy 337.430879 -142.791938)
			(xy 337.438999 -142.847114) (xy 337.439508 -142.875) (xy 339.469982 -142.875) (xy 339.474053 -142.819378)
			(xy 339.486179 -142.764941) (xy 339.506102 -142.71285) (xy 339.533398 -142.664215) (xy 339.567484 -142.620072)
			(xy 339.607633 -142.581363) (xy 339.652991 -142.548912) (xy 339.702591 -142.523411) (xy 339.755375 -142.505404)
			(xy 339.810218 -142.495274) (xy 339.865952 -142.493237) (xy 339.872886 -142.494) (xy 352.866196 -142.494)
			(xy 352.870267 -142.438378) (xy 352.882393 -142.383941) (xy 352.902316 -142.33185) (xy 352.929612 -142.283215)
			(xy 352.963698 -142.239072) (xy 353.003847 -142.200363) (xy 353.049205 -142.167912) (xy 353.098805 -142.142411)
			(xy 353.151589 -142.124404) (xy 353.206432 -142.114274) (xy 353.262166 -142.112237) (xy 353.317603 -142.118337)
			(xy 353.37156 -142.132443) (xy 353.422889 -142.154255) (xy 353.470495 -142.183309) (xy 353.513363 -142.218984)
			(xy 353.55058 -142.260521) (xy 353.581353 -142.307034) (xy 353.605025 -142.357531) (xy 353.621093 -142.410938)
			(xy 353.629213 -142.466114) (xy 353.629722 -142.494) (xy 353.629213 -142.521886) (xy 353.621093 -142.577062)
			(xy 353.605025 -142.630469) (xy 353.581353 -142.680966) (xy 353.55058 -142.727479) (xy 353.513363 -142.769016)
			(xy 353.470495 -142.804691) (xy 353.422889 -142.833745) (xy 353.37156 -142.855557) (xy 353.317603 -142.869663)
			(xy 353.262166 -142.875763) (xy 353.206432 -142.873726) (xy 353.151589 -142.863596) (xy 353.098805 -142.845589)
			(xy 353.049205 -142.820088) (xy 353.003847 -142.787637) (xy 352.963698 -142.748928) (xy 352.929612 -142.704785)
			(xy 352.902316 -142.65615) (xy 352.882393 -142.604059) (xy 352.870267 -142.549622) (xy 352.866196 -142.494)
			(xy 339.872886 -142.494) (xy 339.921389 -142.499337) (xy 339.975346 -142.513443) (xy 340.026675 -142.535255)
			(xy 340.074281 -142.564309) (xy 340.117149 -142.599984) (xy 340.154366 -142.641521) (xy 340.185139 -142.688034)
			(xy 340.208811 -142.738531) (xy 340.224879 -142.791938) (xy 340.232999 -142.847114) (xy 340.233508 -142.875)
			(xy 340.232999 -142.902886) (xy 340.224879 -142.958062) (xy 340.208811 -143.011469) (xy 340.185139 -143.061966)
			(xy 340.154366 -143.108479) (xy 340.117149 -143.150016) (xy 340.074281 -143.185691) (xy 340.026675 -143.214745)
			(xy 339.975346 -143.236557) (xy 339.921389 -143.250663) (xy 339.865952 -143.256763) (xy 339.810218 -143.254726)
			(xy 339.755375 -143.244596) (xy 339.702591 -143.226589) (xy 339.652991 -143.201088) (xy 339.607633 -143.168637)
			(xy 339.567484 -143.129928) (xy 339.533398 -143.085785) (xy 339.506102 -143.03715) (xy 339.486179 -142.985059)
			(xy 339.474053 -142.930622) (xy 339.469982 -142.875) (xy 337.439508 -142.875) (xy 337.438999 -142.902886)
			(xy 337.430879 -142.958062) (xy 337.414811 -143.011469) (xy 337.391139 -143.061966) (xy 337.360366 -143.108479)
			(xy 337.323149 -143.150016) (xy 337.280281 -143.185691) (xy 337.232675 -143.214745) (xy 337.181346 -143.236557)
			(xy 337.127389 -143.250663) (xy 337.071952 -143.256763) (xy 337.016218 -143.254726) (xy 336.961375 -143.244596)
			(xy 336.908591 -143.226589) (xy 336.858991 -143.201088) (xy 336.813633 -143.168637) (xy 336.773484 -143.129928)
			(xy 336.739398 -143.085785) (xy 336.712102 -143.03715) (xy 336.692179 -142.985059) (xy 336.680053 -142.930622)
			(xy 336.675982 -142.875) (xy 335.407508 -142.875) (xy 335.406999 -142.902886) (xy 335.398879 -142.958062)
			(xy 335.382811 -143.011469) (xy 335.359139 -143.061966) (xy 335.328366 -143.108479) (xy 335.291149 -143.150016)
			(xy 335.248281 -143.185691) (xy 335.200675 -143.214745) (xy 335.149346 -143.236557) (xy 335.095389 -143.250663)
			(xy 335.039952 -143.256763) (xy 334.984218 -143.254726) (xy 334.929375 -143.244596) (xy 334.876591 -143.226589)
			(xy 334.826991 -143.201088) (xy 334.781633 -143.168637) (xy 334.741484 -143.129928) (xy 334.707398 -143.085785)
			(xy 334.680102 -143.03715) (xy 334.660179 -142.985059) (xy 334.648053 -142.930622) (xy 334.643982 -142.875)
			(xy 314.189872 -142.875) (xy 314.189872 -143.479266) (xy 314.189382 -143.509234) (xy 314.181559 -143.568656)
			(xy 314.166046 -143.626549) (xy 314.14311 -143.681922) (xy 314.113143 -143.733828) (xy 314.076656 -143.781378)
			(xy 314.034276 -143.823758) (xy 313.986726 -143.860245) (xy 313.93482 -143.890212) (xy 313.879447 -143.913148)
			(xy 313.821554 -143.928661) (xy 313.762132 -143.936484) (xy 313.702196 -143.936484) (xy 313.642774 -143.928661)
			(xy 313.584881 -143.913148) (xy 313.529508 -143.890212) (xy 313.477602 -143.860245) (xy 313.430052 -143.823758)
			(xy 313.387672 -143.781378) (xy 313.351185 -143.733828) (xy 313.321218 -143.681922) (xy 313.298282 -143.626549)
			(xy 313.282769 -143.568656) (xy 313.274946 -143.509234) (xy 313.274456 -143.479266) (xy 309.581804 -143.479266)
			(xy 309.581804 -145.285714) (xy 315.916564 -145.285714) (xy 315.916564 -144.422114) (xy 315.917054 -144.392146)
			(xy 315.924877 -144.332724) (xy 315.94039 -144.274831) (xy 315.963326 -144.219458) (xy 315.993293 -144.167552)
			(xy 316.02978 -144.120002) (xy 316.07216 -144.077622) (xy 316.11971 -144.041135) (xy 316.171616 -144.011168)
			(xy 316.226989 -143.988232) (xy 316.284882 -143.972719) (xy 316.344304 -143.964896) (xy 316.40424 -143.964896)
			(xy 316.463662 -143.972719) (xy 316.521555 -143.988232) (xy 316.576928 -144.011168) (xy 316.628834 -144.041135)
			(xy 316.676384 -144.077622) (xy 316.718764 -144.120002) (xy 316.755251 -144.167552) (xy 316.785218 -144.219458)
			(xy 316.808154 -144.274831) (xy 316.823667 -144.332724) (xy 316.83149 -144.392146) (xy 316.83198 -144.422114)
			(xy 316.83198 -144.43329) (xy 330.02601 -144.43329) (xy 330.026471 -144.407257) (xy 330.03356 -144.355674)
			(xy 330.047592 -144.305534) (xy 330.068307 -144.257765) (xy 330.095319 -144.213253) (xy 330.128129 -144.172824)
			(xy 330.166128 -144.137228) (xy 330.20861 -144.107125) (xy 330.231496 -144.094708) (xy 330.243753 -144.087739)
			(xy 330.264199 -144.068341) (xy 330.278569 -144.044097) (xy 330.285772 -144.01685) (xy 330.28526 -143.988672)
			(xy 330.277072 -143.961705) (xy 330.261831 -143.937999) (xy 330.251562 -143.928338) (xy 330.231547 -143.910136)
			(xy 330.196348 -143.869052) (xy 330.167304 -143.82341) (xy 330.144997 -143.774123) (xy 330.129873 -143.72218)
			(xy 330.122237 -143.668622) (xy 330.121768 -143.641572) (xy 330.122254 -143.614321) (xy 330.13001 -143.560373)
			(xy 330.145365 -143.508078) (xy 330.168007 -143.458501) (xy 330.197473 -143.412651) (xy 330.233164 -143.37146)
			(xy 330.274355 -143.335769) (xy 330.320205 -143.306303) (xy 330.369782 -143.283661) (xy 330.422077 -143.268306)
			(xy 330.476025 -143.26055) (xy 330.530527 -143.26055) (xy 330.584475 -143.268306) (xy 330.63677 -143.283661)
			(xy 330.686347 -143.306303) (xy 330.732197 -143.335769) (xy 330.773388 -143.37146) (xy 330.781626 -143.380968)
			(xy 341.689434 -143.380968) (xy 341.693505 -143.325346) (xy 341.705631 -143.270909) (xy 341.725554 -143.218818)
			(xy 341.75285 -143.170183) (xy 341.786936 -143.12604) (xy 341.827085 -143.087331) (xy 341.872443 -143.05488)
			(xy 341.922043 -143.029379) (xy 341.974827 -143.011372) (xy 342.02967 -143.001242) (xy 342.085404 -142.999205)
			(xy 342.140841 -143.005305) (xy 342.194798 -143.019411) (xy 342.246127 -143.041223) (xy 342.293733 -143.070277)
			(xy 342.336601 -143.105952) (xy 342.373818 -143.147489) (xy 342.404591 -143.194002) (xy 342.428263 -143.244499)
			(xy 342.4305 -143.251936) (xy 349.735392 -143.251936) (xy 349.739463 -143.196314) (xy 349.751589 -143.141877)
			(xy 349.771512 -143.089786) (xy 349.798808 -143.041151) (xy 349.832894 -142.997008) (xy 349.873043 -142.958299)
			(xy 349.918401 -142.925848) (xy 349.968001 -142.900347) (xy 350.020785 -142.88234) (xy 350.075628 -142.87221)
			(xy 350.131362 -142.870173) (xy 350.186799 -142.876273) (xy 350.240756 -142.890379) (xy 350.292085 -142.912191)
			(xy 350.339691 -142.941245) (xy 350.382559 -142.97692) (xy 350.419776 -143.018457) (xy 350.450549 -143.06497)
			(xy 350.456916 -143.078551) (xy 359.055154 -143.078551) (xy 359.055154 -143.024049) (xy 359.06291 -142.970101)
			(xy 359.078264 -142.917806) (xy 359.100904 -142.868228) (xy 359.130368 -142.822377) (xy 359.166058 -142.781185)
			(xy 359.207246 -142.745491) (xy 359.253095 -142.716022) (xy 359.30267 -142.693377) (xy 359.354964 -142.678018)
			(xy 359.408911 -142.670256) (xy 359.436162 -142.669768) (xy 359.462477 -142.670204) (xy 359.514606 -142.677447)
			(xy 359.565249 -142.691773) (xy 359.613448 -142.712911) (xy 359.658291 -142.740462) (xy 359.69893 -142.773905)
			(xy 359.717086 -142.792958) (xy 359.724617 -142.800349) (xy 359.74389 -142.808881) (xy 359.754424 -142.809468)
			(xy 359.8291 -142.809468) (xy 359.839653 -142.808962) (xy 359.858948 -142.800412) (xy 359.866438 -142.792958)
			(xy 359.884574 -142.773883) (xy 359.925209 -142.740429) (xy 359.970053 -142.712874) (xy 360.018258 -142.691739)
			(xy 360.068908 -142.677426) (xy 360.121045 -142.670205) (xy 360.147362 -142.669768) (xy 360.174615 -142.670277)
			(xy 360.228567 -142.678029) (xy 360.280866 -142.693381) (xy 360.330447 -142.716019) (xy 360.376302 -142.745485)
			(xy 360.417497 -142.781176) (xy 360.453193 -142.822367) (xy 360.482662 -142.868219) (xy 360.505306 -142.917799)
			(xy 360.520663 -142.970096) (xy 360.528421 -143.024047) (xy 360.528421 -143.078553) (xy 360.520663 -143.132504)
			(xy 360.505306 -143.184801) (xy 360.482662 -143.234381) (xy 360.453193 -143.280233) (xy 360.417497 -143.321424)
			(xy 360.376302 -143.357115) (xy 360.330447 -143.386581) (xy 360.280866 -143.409219) (xy 360.228567 -143.424571)
			(xy 360.174615 -143.432323) (xy 360.147362 -143.432784) (xy 360.121047 -143.432347) (xy 360.068917 -143.425107)
			(xy 360.018273 -143.410782) (xy 359.970074 -143.389644) (xy 359.925232 -143.362092) (xy 359.884594 -143.328648)
			(xy 359.866438 -143.309594) (xy 359.858905 -143.302206) (xy 359.839634 -143.293674) (xy 359.8291 -143.293084)
			(xy 359.754424 -143.293084) (xy 359.743875 -143.293618) (xy 359.72458 -143.30215) (xy 359.717086 -143.309594)
			(xy 359.698929 -143.328648) (xy 359.6583 -143.362106) (xy 359.61346 -143.389665) (xy 359.565259 -143.410804)
			(xy 359.514612 -143.425121) (xy 359.462478 -143.432346) (xy 359.436162 -143.432784) (xy 359.408911 -143.432344)
			(xy 359.354964 -143.424582) (xy 359.30267 -143.409223) (xy 359.253095 -143.386578) (xy 359.207246 -143.357109)
			(xy 359.166058 -143.321415) (xy 359.130368 -143.280223) (xy 359.100904 -143.234372) (xy 359.078264 -143.184794)
			(xy 359.06291 -143.132499) (xy 359.055154 -143.078551) (xy 350.456916 -143.078551) (xy 350.474221 -143.115467)
			(xy 350.490289 -143.168874) (xy 350.498409 -143.22405) (xy 350.498918 -143.251936) (xy 350.498409 -143.279822)
			(xy 350.490289 -143.334998) (xy 350.474221 -143.388405) (xy 350.450549 -143.438902) (xy 350.419776 -143.485415)
			(xy 350.397748 -143.51) (xy 352.866196 -143.51) (xy 352.870267 -143.454378) (xy 352.882393 -143.399941)
			(xy 352.902316 -143.34785) (xy 352.929612 -143.299215) (xy 352.963698 -143.255072) (xy 353.003847 -143.216363)
			(xy 353.049205 -143.183912) (xy 353.098805 -143.158411) (xy 353.151589 -143.140404) (xy 353.206432 -143.130274)
			(xy 353.262166 -143.128237) (xy 353.317603 -143.134337) (xy 353.37156 -143.148443) (xy 353.422889 -143.170255)
			(xy 353.470495 -143.199309) (xy 353.513363 -143.234984) (xy 353.55058 -143.276521) (xy 353.581353 -143.323034)
			(xy 353.605025 -143.373531) (xy 353.621093 -143.426938) (xy 353.629213 -143.482114) (xy 353.629722 -143.51)
			(xy 353.629213 -143.537886) (xy 353.621093 -143.593062) (xy 353.605025 -143.646469) (xy 353.581353 -143.696966)
			(xy 353.55058 -143.743479) (xy 353.513363 -143.785016) (xy 353.470495 -143.820691) (xy 353.422889 -143.849745)
			(xy 353.37156 -143.871557) (xy 353.317603 -143.885663) (xy 353.262166 -143.891763) (xy 353.206432 -143.889726)
			(xy 353.151589 -143.879596) (xy 353.098805 -143.861589) (xy 353.049205 -143.836088) (xy 353.003847 -143.803637)
			(xy 352.963698 -143.764928) (xy 352.929612 -143.720785) (xy 352.902316 -143.67215) (xy 352.882393 -143.620059)
			(xy 352.870267 -143.565622) (xy 352.866196 -143.51) (xy 350.397748 -143.51) (xy 350.382559 -143.526952)
			(xy 350.339691 -143.562627) (xy 350.292085 -143.591681) (xy 350.240756 -143.613493) (xy 350.186799 -143.627599)
			(xy 350.131362 -143.633699) (xy 350.075628 -143.631662) (xy 350.020785 -143.621532) (xy 349.968001 -143.603525)
			(xy 349.918401 -143.578024) (xy 349.873043 -143.545573) (xy 349.832894 -143.506864) (xy 349.798808 -143.462721)
			(xy 349.771512 -143.414086) (xy 349.751589 -143.361995) (xy 349.739463 -143.307558) (xy 349.735392 -143.251936)
			(xy 342.4305 -143.251936) (xy 342.444331 -143.297906) (xy 342.452451 -143.353082) (xy 342.45296 -143.380968)
			(xy 342.452451 -143.408854) (xy 342.444331 -143.46403) (xy 342.428263 -143.517437) (xy 342.404591 -143.567934)
			(xy 342.373818 -143.614447) (xy 342.336601 -143.655984) (xy 342.293733 -143.691659) (xy 342.246127 -143.720713)
			(xy 342.194798 -143.742525) (xy 342.140841 -143.756631) (xy 342.085404 -143.762731) (xy 342.02967 -143.760694)
			(xy 341.974827 -143.750564) (xy 341.922043 -143.732557) (xy 341.872443 -143.707056) (xy 341.827085 -143.674605)
			(xy 341.786936 -143.635896) (xy 341.75285 -143.591753) (xy 341.725554 -143.543118) (xy 341.705631 -143.491027)
			(xy 341.693505 -143.43659) (xy 341.689434 -143.380968) (xy 330.781626 -143.380968) (xy 330.809079 -143.412651)
			(xy 330.838545 -143.458501) (xy 330.861187 -143.508078) (xy 330.876542 -143.560373) (xy 330.884298 -143.614321)
			(xy 330.884784 -143.641572) (xy 330.884295 -143.667605) (xy 330.877211 -143.719186) (xy 330.863183 -143.769326)
			(xy 330.842473 -143.817095) (xy 330.815465 -143.861607) (xy 330.782658 -143.902036) (xy 330.744662 -143.937633)
			(xy 330.702182 -143.967736) (xy 330.679298 -143.980154) (xy 330.66699 -143.98704) (xy 330.64654 -144.006455)
			(xy 330.632171 -144.030716) (xy 330.624973 -144.057979) (xy 330.625495 -144.086171) (xy 330.633697 -144.113149)
			(xy 330.648955 -144.136862) (xy 330.659232 -144.146524) (xy 330.679227 -144.164747) (xy 330.714428 -144.205826)
			(xy 330.741349 -144.248124) (xy 336.662266 -144.248124) (xy 336.666337 -144.192502) (xy 336.678463 -144.138065)
			(xy 336.698386 -144.085974) (xy 336.725682 -144.037339) (xy 336.759768 -143.993196) (xy 336.799917 -143.954487)
			(xy 336.845275 -143.922036) (xy 336.894875 -143.896535) (xy 336.947659 -143.878528) (xy 337.002502 -143.868398)
			(xy 337.058236 -143.866361) (xy 337.113673 -143.872461) (xy 337.16763 -143.886567) (xy 337.218959 -143.908379)
			(xy 337.266565 -143.937433) (xy 337.309433 -143.973108) (xy 337.34665 -144.014645) (xy 337.377423 -144.061158)
			(xy 337.401095 -144.111655) (xy 337.417163 -144.165062) (xy 337.425283 -144.220238) (xy 337.425792 -144.248124)
			(xy 337.425283 -144.27601) (xy 337.417163 -144.331186) (xy 337.401095 -144.384593) (xy 337.398985 -144.389094)
			(xy 339.797388 -144.389094) (xy 339.801459 -144.333472) (xy 339.813585 -144.279035) (xy 339.833508 -144.226944)
			(xy 339.860804 -144.178309) (xy 339.89489 -144.134166) (xy 339.935039 -144.095457) (xy 339.980397 -144.063006)
			(xy 340.029997 -144.037505) (xy 340.082781 -144.019498) (xy 340.137624 -144.009368) (xy 340.193358 -144.007331)
			(xy 340.248795 -144.013431) (xy 340.302752 -144.027537) (xy 340.354081 -144.049349) (xy 340.401687 -144.078403)
			(xy 340.444555 -144.114078) (xy 340.481772 -144.155615) (xy 340.512545 -144.202128) (xy 340.536217 -144.252625)
			(xy 340.552285 -144.306032) (xy 340.560405 -144.361208) (xy 340.560914 -144.389094) (xy 340.560405 -144.41698)
			(xy 340.552285 -144.472156) (xy 340.536217 -144.525563) (xy 340.512545 -144.57606) (xy 340.481772 -144.622573)
			(xy 340.444555 -144.66411) (xy 340.401687 -144.699785) (xy 340.363478 -144.723104) (xy 349.735392 -144.723104)
			(xy 349.739463 -144.667482) (xy 349.751589 -144.613045) (xy 349.771512 -144.560954) (xy 349.798808 -144.512319)
			(xy 349.832894 -144.468176) (xy 349.873043 -144.429467) (xy 349.918401 -144.397016) (xy 349.968001 -144.371515)
			(xy 350.020785 -144.353508) (xy 350.075628 -144.343378) (xy 350.131362 -144.341341) (xy 350.186799 -144.347441)
			(xy 350.240756 -144.361547) (xy 350.292085 -144.383359) (xy 350.339691 -144.412413) (xy 350.382559 -144.448088)
			(xy 350.419776 -144.489625) (xy 350.443842 -144.526) (xy 352.866196 -144.526) (xy 352.870267 -144.470378)
			(xy 352.882393 -144.415941) (xy 352.902316 -144.36385) (xy 352.929612 -144.315215) (xy 352.963698 -144.271072)
			(xy 353.003847 -144.232363) (xy 353.049205 -144.199912) (xy 353.098805 -144.174411) (xy 353.151589 -144.156404)
			(xy 353.206432 -144.146274) (xy 353.262166 -144.144237) (xy 353.317603 -144.150337) (xy 353.37156 -144.164443)
			(xy 353.422889 -144.186255) (xy 353.470495 -144.215309) (xy 353.513363 -144.250984) (xy 353.55058 -144.292521)
			(xy 353.581353 -144.339034) (xy 353.605025 -144.389531) (xy 353.621093 -144.442938) (xy 353.629213 -144.498114)
			(xy 353.629722 -144.526) (xy 353.629213 -144.553886) (xy 353.621093 -144.609062) (xy 353.605025 -144.662469)
			(xy 353.581353 -144.712966) (xy 353.55058 -144.759479) (xy 353.513363 -144.801016) (xy 353.470495 -144.836691)
			(xy 353.422889 -144.865745) (xy 353.37156 -144.887557) (xy 353.317603 -144.901663) (xy 353.262166 -144.907763)
			(xy 353.206432 -144.905726) (xy 353.151589 -144.895596) (xy 353.098805 -144.877589) (xy 353.049205 -144.852088)
			(xy 353.003847 -144.819637) (xy 352.963698 -144.780928) (xy 352.929612 -144.736785) (xy 352.902316 -144.68815)
			(xy 352.882393 -144.636059) (xy 352.870267 -144.581622) (xy 352.866196 -144.526) (xy 350.443842 -144.526)
			(xy 350.450549 -144.536138) (xy 350.474221 -144.586635) (xy 350.490289 -144.640042) (xy 350.498409 -144.695218)
			(xy 350.498918 -144.723104) (xy 350.498409 -144.75099) (xy 350.490289 -144.806166) (xy 350.474221 -144.859573)
			(xy 350.450549 -144.91007) (xy 350.419776 -144.956583) (xy 350.382559 -144.99812) (xy 350.339691 -145.033795)
			(xy 350.292085 -145.062849) (xy 350.240756 -145.084661) (xy 350.186799 -145.098767) (xy 350.131362 -145.104867)
			(xy 350.075628 -145.10283) (xy 350.020785 -145.0927) (xy 349.968001 -145.074693) (xy 349.918401 -145.049192)
			(xy 349.873043 -145.016741) (xy 349.832894 -144.978032) (xy 349.798808 -144.933889) (xy 349.771512 -144.885254)
			(xy 349.751589 -144.833163) (xy 349.739463 -144.778726) (xy 349.735392 -144.723104) (xy 340.363478 -144.723104)
			(xy 340.354081 -144.728839) (xy 340.302752 -144.750651) (xy 340.248795 -144.764757) (xy 340.193358 -144.770857)
			(xy 340.137624 -144.76882) (xy 340.082781 -144.75869) (xy 340.029997 -144.740683) (xy 339.980397 -144.715182)
			(xy 339.935039 -144.682731) (xy 339.89489 -144.644022) (xy 339.860804 -144.599879) (xy 339.833508 -144.551244)
			(xy 339.813585 -144.499153) (xy 339.801459 -144.444716) (xy 339.797388 -144.389094) (xy 337.398985 -144.389094)
			(xy 337.377423 -144.43509) (xy 337.34665 -144.481603) (xy 337.309433 -144.52314) (xy 337.266565 -144.558815)
			(xy 337.218959 -144.587869) (xy 337.16763 -144.609681) (xy 337.113673 -144.623787) (xy 337.058236 -144.629887)
			(xy 337.002502 -144.62785) (xy 336.947659 -144.61772) (xy 336.894875 -144.599713) (xy 336.845275 -144.574212)
			(xy 336.799917 -144.541761) (xy 336.759768 -144.503052) (xy 336.725682 -144.458909) (xy 336.698386 -144.410274)
			(xy 336.678463 -144.358183) (xy 336.666337 -144.303746) (xy 336.662266 -144.248124) (xy 330.741349 -144.248124)
			(xy 330.743475 -144.251464) (xy 330.765786 -144.300746) (xy 330.780913 -144.352686) (xy 330.788554 -144.406241)
			(xy 330.789026 -144.43329) (xy 330.78854 -144.460541) (xy 330.780784 -144.514489) (xy 330.765429 -144.566784)
			(xy 330.742787 -144.616361) (xy 330.713321 -144.662211) (xy 330.67763 -144.703402) (xy 330.636439 -144.739093)
			(xy 330.590589 -144.768559) (xy 330.541012 -144.791201) (xy 330.488717 -144.806556) (xy 330.434769 -144.814312)
			(xy 330.380267 -144.814312) (xy 330.326319 -144.806556) (xy 330.274024 -144.791201) (xy 330.224447 -144.768559)
			(xy 330.178597 -144.739093) (xy 330.137406 -144.703402) (xy 330.101715 -144.662211) (xy 330.072249 -144.616361)
			(xy 330.049607 -144.566784) (xy 330.034252 -144.514489) (xy 330.026496 -144.460541) (xy 330.02601 -144.43329)
			(xy 316.83198 -144.43329) (xy 316.83198 -145.285714) (xy 316.83149 -145.315682) (xy 316.823667 -145.375104)
			(xy 316.808154 -145.432997) (xy 316.785218 -145.48837) (xy 316.755251 -145.540276) (xy 316.718764 -145.587826)
			(xy 316.676384 -145.630206) (xy 316.628834 -145.666693) (xy 316.576928 -145.69666) (xy 316.521555 -145.719596)
			(xy 316.463662 -145.735109) (xy 316.40424 -145.742932) (xy 316.344304 -145.742932) (xy 316.284882 -145.735109)
			(xy 316.226989 -145.719596) (xy 316.171616 -145.69666) (xy 316.11971 -145.666693) (xy 316.07216 -145.630206)
			(xy 316.02978 -145.587826) (xy 315.993293 -145.540276) (xy 315.963326 -145.48837) (xy 315.94039 -145.432997)
			(xy 315.924877 -145.375104) (xy 315.917054 -145.315682) (xy 315.916564 -145.285714) (xy 309.581804 -145.285714)
			(xy 309.581804 -147.079208) (xy 313.274456 -147.079208) (xy 313.274456 -146.215608) (xy 313.274946 -146.18564)
			(xy 313.282769 -146.126218) (xy 313.298282 -146.068325) (xy 313.321218 -146.012952) (xy 313.351185 -145.961046)
			(xy 313.387672 -145.913496) (xy 313.430052 -145.871116) (xy 313.477602 -145.834629) (xy 313.529508 -145.804662)
			(xy 313.584881 -145.781726) (xy 313.642774 -145.766213) (xy 313.702196 -145.75839) (xy 313.762132 -145.75839)
			(xy 313.821554 -145.766213) (xy 313.879447 -145.781726) (xy 313.93482 -145.804662) (xy 313.986726 -145.834629)
			(xy 314.034276 -145.871116) (xy 314.076656 -145.913496) (xy 314.083949 -145.923) (xy 334.643982 -145.923)
			(xy 334.648053 -145.867378) (xy 334.660179 -145.812941) (xy 334.680102 -145.76085) (xy 334.707398 -145.712215)
			(xy 334.741484 -145.668072) (xy 334.781633 -145.629363) (xy 334.826991 -145.596912) (xy 334.876591 -145.571411)
			(xy 334.929375 -145.553404) (xy 334.984218 -145.543274) (xy 335.039952 -145.541237) (xy 335.095389 -145.547337)
			(xy 335.149346 -145.561443) (xy 335.200675 -145.583255) (xy 335.248281 -145.612309) (xy 335.2694 -145.629884)
			(xy 336.686904 -145.629884) (xy 336.690975 -145.574262) (xy 336.703101 -145.519825) (xy 336.723024 -145.467734)
			(xy 336.75032 -145.419099) (xy 336.784406 -145.374956) (xy 336.824555 -145.336247) (xy 336.869913 -145.303796)
			(xy 336.919513 -145.278295) (xy 336.972297 -145.260288) (xy 337.02714 -145.250158) (xy 337.082874 -145.248121)
			(xy 337.138311 -145.254221) (xy 337.192268 -145.268327) (xy 337.19493 -145.269458) (xy 351.054414 -145.269458)
			(xy 351.058485 -145.213836) (xy 351.070611 -145.159399) (xy 351.090534 -145.107308) (xy 351.11783 -145.058673)
			(xy 351.151916 -145.01453) (xy 351.192065 -144.975821) (xy 351.237423 -144.94337) (xy 351.287023 -144.917869)
			(xy 351.339807 -144.899862) (xy 351.39465 -144.889732) (xy 351.450384 -144.887695) (xy 351.505821 -144.893795)
			(xy 351.559778 -144.907901) (xy 351.611107 -144.929713) (xy 351.658713 -144.958767) (xy 351.701581 -144.994442)
			(xy 351.738798 -145.035979) (xy 351.769571 -145.082492) (xy 351.782725 -145.110551) (xy 359.055154 -145.110551)
			(xy 359.055154 -145.056049) (xy 359.06291 -145.002101) (xy 359.078264 -144.949806) (xy 359.100904 -144.900228)
			(xy 359.130368 -144.854377) (xy 359.166058 -144.813185) (xy 359.207246 -144.777491) (xy 359.253095 -144.748022)
			(xy 359.30267 -144.725377) (xy 359.354964 -144.710018) (xy 359.408911 -144.702256) (xy 359.436162 -144.701768)
			(xy 359.462477 -144.702204) (xy 359.514606 -144.709447) (xy 359.565249 -144.723773) (xy 359.613448 -144.744911)
			(xy 359.658291 -144.772462) (xy 359.69893 -144.805905) (xy 359.717086 -144.824958) (xy 359.724617 -144.832349)
			(xy 359.74389 -144.840881) (xy 359.754424 -144.841468) (xy 359.8291 -144.841468) (xy 359.839653 -144.840962)
			(xy 359.858948 -144.832412) (xy 359.866438 -144.824958) (xy 359.884574 -144.805883) (xy 359.925209 -144.772429)
			(xy 359.970053 -144.744874) (xy 360.018258 -144.723739) (xy 360.068908 -144.709426) (xy 360.121045 -144.702205)
			(xy 360.147362 -144.701768) (xy 360.174615 -144.702277) (xy 360.228567 -144.710029) (xy 360.280866 -144.725381)
			(xy 360.330447 -144.748019) (xy 360.376302 -144.777485) (xy 360.417497 -144.813176) (xy 360.453193 -144.854367)
			(xy 360.482662 -144.900219) (xy 360.505306 -144.949799) (xy 360.506611 -144.954244) (xy 366.239044 -144.954244)
			(xy 366.239619 -144.926996) (xy 366.247368 -144.873054) (xy 366.262715 -144.820764) (xy 366.285348 -144.77119)
			(xy 366.314805 -144.725342) (xy 366.350487 -144.684152) (xy 366.391668 -144.64846) (xy 366.437509 -144.618992)
			(xy 366.487078 -144.596348) (xy 366.539364 -144.580988) (xy 366.593304 -144.573226) (xy 366.620552 -144.572736)
			(xy 366.646454 -144.573157) (xy 366.697782 -144.580172) (xy 366.747688 -144.594068) (xy 366.795255 -144.614588)
			(xy 366.817656 -144.6276) (xy 366.825993 -144.632083) (xy 366.844618 -144.635352) (xy 366.853978 -144.63395)
			(xy 366.884458 -144.6276) (xy 366.893839 -144.625352) (xy 366.910032 -144.614896) (xy 366.915954 -144.60728)
			(xy 366.933866 -144.58282) (xy 366.974542 -144.537862) (xy 367.02028 -144.498067) (xy 367.070431 -144.464)
			(xy 367.124281 -144.436146) (xy 367.181064 -144.4149) (xy 367.239972 -144.400565) (xy 367.300168 -144.393346)
			(xy 367.330482 -144.392904) (xy 367.788444 -144.392904) (xy 367.79826 -144.392501) (xy 367.816457 -144.38514)
			(xy 367.830551 -144.371476) (xy 367.834926 -144.362678) (xy 367.872518 -144.277588) (xy 367.876049 -144.268516)
			(xy 367.876661 -144.249071) (xy 367.87003 -144.230782) (xy 367.863882 -144.223232) (xy 367.863628 -144.223232)
			(xy 367.863628 -144.222978) (xy 367.845073 -144.201796) (xy 367.813718 -144.155023) (xy 367.789573 -144.104151)
			(xy 367.773162 -144.050285) (xy 367.764842 -143.994593) (xy 367.764314 -143.966438) (xy 367.764725 -143.940462)
			(xy 367.771775 -143.88899) (xy 367.785751 -143.838952) (xy 367.806392 -143.791277) (xy 367.833317 -143.746846)
			(xy 367.866026 -143.706483) (xy 367.903914 -143.670936) (xy 367.924842 -143.655542) (xy 367.934333 -143.64791)
			(xy 367.945478 -143.626298) (xy 367.946178 -143.61414) (xy 367.946178 -143.531336) (xy 367.945487 -143.519174)
			(xy 367.934347 -143.497553) (xy 367.924842 -143.489934) (xy 367.903923 -143.474532) (xy 367.866046 -143.438979)
			(xy 367.833346 -143.398614) (xy 367.806428 -143.354184) (xy 367.785789 -143.306512) (xy 367.771812 -143.256479)
			(xy 367.764756 -143.205012) (xy 367.764314 -143.179038) (xy 367.764823 -143.150299) (xy 367.773453 -143.093472)
			(xy 367.790508 -143.038582) (xy 367.815602 -142.98687) (xy 367.848168 -142.939508) (xy 367.867438 -142.91818)
			(xy 367.874042 -142.911322) (xy 367.881154 -142.893288) (xy 367.881154 -142.804388) (xy 367.874042 -142.786354)
			(xy 367.867438 -142.779496) (xy 367.848204 -142.758137) (xy 367.815637 -142.71078) (xy 367.790542 -142.659074)
			(xy 367.773488 -142.604188) (xy 367.764862 -142.547365) (xy 367.764858 -142.489891) (xy 367.773476 -142.433066)
			(xy 367.790522 -142.378178) (xy 367.815609 -142.326468) (xy 367.848169 -142.279106) (xy 367.867438 -142.25778)
			(xy 367.874042 -142.250922) (xy 367.881154 -142.232888) (xy 367.881154 -142.143988) (xy 367.874042 -142.125954)
			(xy 367.867438 -142.119096) (xy 367.848204 -142.097737) (xy 367.815637 -142.05038) (xy 367.790542 -141.998674)
			(xy 367.773488 -141.943788) (xy 367.764862 -141.886965) (xy 367.764858 -141.829491) (xy 367.773476 -141.772666)
			(xy 367.790522 -141.717778) (xy 367.815609 -141.666068) (xy 367.848169 -141.618706) (xy 367.867438 -141.59738)
			(xy 367.874042 -141.590522) (xy 367.881154 -141.572488) (xy 367.881154 -141.483588) (xy 367.874042 -141.465554)
			(xy 367.867438 -141.458696) (xy 367.848204 -141.437337) (xy 367.815637 -141.38998) (xy 367.790542 -141.338274)
			(xy 367.773488 -141.283388) (xy 367.764862 -141.226565) (xy 367.764858 -141.169091) (xy 367.773476 -141.112266)
			(xy 367.790522 -141.057378) (xy 367.815609 -141.005668) (xy 367.848169 -140.958306) (xy 367.867438 -140.93698)
			(xy 367.874042 -140.930122) (xy 367.881154 -140.912088) (xy 367.881154 -140.823188) (xy 367.874042 -140.805154)
			(xy 367.867438 -140.798296) (xy 367.848185 -140.776953) (xy 367.815617 -140.729596) (xy 367.790521 -140.677888)
			(xy 367.773466 -140.623001) (xy 367.764838 -140.566176) (xy 367.764314 -140.537438) (xy 367.7648 -140.510187)
			(xy 367.772556 -140.456239) (xy 367.787911 -140.403944) (xy 367.810553 -140.354367) (xy 367.840019 -140.308517)
			(xy 367.87571 -140.267326) (xy 367.916901 -140.231635) (xy 367.962751 -140.202169) (xy 368.012328 -140.179527)
			(xy 368.064623 -140.164172) (xy 368.118571 -140.156416) (xy 368.173073 -140.156416) (xy 368.227021 -140.164172)
			(xy 368.279316 -140.179527) (xy 368.328893 -140.202169) (xy 368.374743 -140.231635) (xy 368.415934 -140.267326)
			(xy 368.451625 -140.308517) (xy 368.463095 -140.326364) (xy 383.992118 -140.326364) (xy 383.996189 -140.270742)
			(xy 384.008315 -140.216305) (xy 384.028238 -140.164214) (xy 384.055534 -140.115579) (xy 384.08962 -140.071436)
			(xy 384.129769 -140.032727) (xy 384.175127 -140.000276) (xy 384.224727 -139.974775) (xy 384.277511 -139.956768)
			(xy 384.332354 -139.946638) (xy 384.388088 -139.944601) (xy 384.443525 -139.950701) (xy 384.497482 -139.964807)
			(xy 384.548811 -139.986619) (xy 384.596417 -140.015673) (xy 384.639285 -140.051348) (xy 384.676502 -140.092885)
			(xy 384.707275 -140.139398) (xy 384.730947 -140.189895) (xy 384.747015 -140.243302) (xy 384.755135 -140.298478)
			(xy 384.755644 -140.326364) (xy 384.755135 -140.35425) (xy 384.747015 -140.409426) (xy 384.730947 -140.462833)
			(xy 384.707275 -140.51333) (xy 384.676502 -140.559843) (xy 384.639285 -140.60138) (xy 384.596417 -140.637055)
			(xy 384.548811 -140.666109) (xy 384.497482 -140.687921) (xy 384.443525 -140.702027) (xy 384.388088 -140.708127)
			(xy 384.332354 -140.70609) (xy 384.277511 -140.69596) (xy 384.224727 -140.677953) (xy 384.175127 -140.652452)
			(xy 384.129769 -140.620001) (xy 384.08962 -140.581292) (xy 384.055534 -140.537149) (xy 384.028238 -140.488514)
			(xy 384.008315 -140.436423) (xy 383.996189 -140.381986) (xy 383.992118 -140.326364) (xy 368.463095 -140.326364)
			(xy 368.481091 -140.354367) (xy 368.503733 -140.403944) (xy 368.519088 -140.456239) (xy 368.526844 -140.510187)
			(xy 368.52733 -140.537438) (xy 368.526821 -140.566177) (xy 368.518194 -140.623005) (xy 368.50114 -140.677896)
			(xy 368.476045 -140.729607) (xy 368.443478 -140.776969) (xy 368.424206 -140.798296) (xy 368.417602 -140.805154)
			(xy 368.41049 -140.823188) (xy 368.41049 -140.912088) (xy 368.417602 -140.930122) (xy 368.424206 -140.93698)
			(xy 368.443513 -140.958275) (xy 368.476075 -141.005644) (xy 368.501162 -141.057361) (xy 368.518208 -141.112256)
			(xy 368.526826 -141.169087) (xy 368.526822 -141.226568) (xy 368.518195 -141.283398) (xy 368.501142 -141.338291)
			(xy 368.476047 -141.390004) (xy 368.443478 -141.437368) (xy 368.424206 -141.458696) (xy 368.417602 -141.465554)
			(xy 368.41049 -141.483588) (xy 368.41049 -141.572488) (xy 368.417602 -141.590522) (xy 368.424206 -141.59738)
			(xy 368.443513 -141.618675) (xy 368.476075 -141.666044) (xy 368.501162 -141.717761) (xy 368.518208 -141.772656)
			(xy 368.526826 -141.829487) (xy 368.526822 -141.886968) (xy 368.518195 -141.943798) (xy 368.501142 -141.998691)
			(xy 368.476047 -142.050404) (xy 368.443478 -142.097768) (xy 368.424206 -142.119096) (xy 368.417602 -142.125954)
			(xy 368.41049 -142.143988) (xy 368.41049 -142.232888) (xy 368.417602 -142.250922) (xy 368.424206 -142.25778)
			(xy 368.443513 -142.279075) (xy 368.476075 -142.326444) (xy 368.501162 -142.378161) (xy 368.518208 -142.433056)
			(xy 368.526826 -142.489887) (xy 368.526822 -142.547368) (xy 368.518195 -142.604198) (xy 368.501142 -142.659091)
			(xy 368.476047 -142.710804) (xy 368.443478 -142.758168) (xy 368.424206 -142.779496) (xy 368.417602 -142.786354)
			(xy 368.41049 -142.804388) (xy 368.41049 -142.893288) (xy 368.417602 -142.911322) (xy 368.424206 -142.91818)
			(xy 368.443485 -142.9395) (xy 368.476052 -142.986863) (xy 368.501144 -143.038576) (xy 368.518192 -143.093469)
			(xy 368.526811 -143.150298) (xy 368.52733 -143.179038) (xy 368.526925 -143.205015) (xy 368.519876 -143.256488)
			(xy 368.505902 -143.306526) (xy 368.48526 -143.354203) (xy 368.458334 -143.398634) (xy 368.425622 -143.438996)
			(xy 368.387731 -143.474541) (xy 368.366802 -143.489934) (xy 368.35733 -143.497587) (xy 368.346173 -143.519183)
			(xy 368.345466 -143.531336) (xy 368.345466 -143.61414) (xy 368.346155 -143.626303) (xy 368.357295 -143.647925)
			(xy 368.366802 -143.655542) (xy 368.38772 -143.670946) (xy 368.425594 -143.7065) (xy 368.458293 -143.746865)
			(xy 368.485211 -143.791295) (xy 368.50585 -143.838967) (xy 368.519828 -143.888998) (xy 368.526887 -143.940464)
			(xy 368.52733 -143.966438) (xy 368.526846 -143.994597) (xy 368.518541 -144.050299) (xy 368.502132 -144.104174)
			(xy 368.477977 -144.155048) (xy 368.4466 -144.201816) (xy 368.428016 -144.222978) (xy 368.427762 -144.223232)
			(xy 368.421603 -144.230782) (xy 368.414927 -144.249063) (xy 368.415583 -144.268514) (xy 368.419126 -144.277588)
			(xy 368.456718 -144.362678) (xy 368.461086 -144.371472) (xy 368.475198 -144.385105) (xy 368.493389 -144.392458)
			(xy 368.5032 -144.392904) (xy 368.573812 -144.392904) (xy 368.607096 -144.393492) (xy 368.673089 -144.402228)
			(xy 368.737379 -144.419495) (xy 368.798868 -144.445) (xy 368.856505 -144.478307) (xy 368.909307 -144.518846)
			(xy 368.933222 -144.542002) (xy 370.923058 -146.531838) (xy 370.946274 -146.555702) (xy 370.986832 -146.608502)
			(xy 371.020149 -146.666146) (xy 371.045655 -146.727647) (xy 371.062912 -146.791951) (xy 371.071625 -146.857958)
			(xy 371.072156 -146.891248) (xy 371.072156 -147.741386) (xy 371.071654 -147.773347) (xy 371.063643 -147.836765)
			(xy 371.047746 -147.898679) (xy 371.024214 -147.958112) (xy 370.99342 -148.014127) (xy 370.955847 -148.065842)
			(xy 370.91209 -148.112439) (xy 370.862837 -148.153184) (xy 370.808866 -148.187435) (xy 370.751027 -148.214652)
			(xy 370.690234 -148.234405) (xy 370.627444 -148.246383) (xy 370.563648 -148.250397) (xy 370.499852 -148.246383)
			(xy 370.437062 -148.234405) (xy 370.376269 -148.214652) (xy 370.31843 -148.187435) (xy 370.264459 -148.153184)
			(xy 370.215206 -148.112439) (xy 370.171449 -148.065842) (xy 370.133876 -148.014127) (xy 370.103082 -147.958112)
			(xy 370.07955 -147.898679) (xy 370.063653 -147.836765) (xy 370.055642 -147.773347) (xy 370.05514 -147.741386)
			(xy 370.05514 -147.457922) (xy 370.054723 -147.448661) (xy 370.048112 -147.431361) (xy 370.035755 -147.417564)
			(xy 370.027708 -147.412964) (xy 369.935252 -147.364704) (xy 369.907058 -147.366736) (xy 369.895374 -147.374864)
			(xy 369.871164 -147.391135) (xy 369.818862 -147.416956) (xy 369.763238 -147.434513) (xy 369.70559 -147.443397)
			(xy 369.676426 -147.443952) (xy 369.649177 -147.443398) (xy 369.595234 -147.435646) (xy 369.542944 -147.420296)
			(xy 369.49337 -147.397661) (xy 369.447521 -147.368202) (xy 369.406332 -147.332518) (xy 369.37064 -147.291335)
			(xy 369.341172 -147.245492) (xy 369.318528 -147.195922) (xy 369.303169 -147.143634) (xy 369.295407 -147.089692)
			(xy 369.294918 -147.062444) (xy 369.295474 -147.033101) (xy 369.304455 -146.975107) (xy 369.322212 -146.919173)
			(xy 369.348326 -146.866618) (xy 369.382181 -146.818683) (xy 369.422977 -146.776498) (xy 369.469754 -146.741059)
			(xy 369.495324 -146.726656) (xy 369.5055 -146.720472) (xy 369.519144 -146.700993) (xy 369.521486 -146.689318)
			(xy 369.53317 -146.608546) (xy 369.534293 -146.596729) (xy 369.526865 -146.574211) (xy 369.518946 -146.565366)
			(xy 368.378232 -145.424906) (xy 368.370814 -145.418088) (xy 368.352229 -145.410355) (xy 368.342164 -145.40992)
			(xy 367.782856 -145.40992) (xy 367.774311 -145.41027) (xy 367.75817 -145.415882) (xy 367.744779 -145.426499)
			(xy 367.73993 -145.433542) (xy 367.693956 -145.505678) (xy 367.689594 -145.513068) (xy 367.685671 -145.529765)
			(xy 367.687513 -145.546818) (xy 367.690908 -145.5547) (xy 367.702345 -145.580216) (xy 367.718514 -145.63374)
			(xy 367.726715 -145.68905) (xy 367.72723 -145.717006) (xy 367.726776 -145.744) (xy 367.719169 -145.797448)
			(xy 367.704107 -145.849292) (xy 367.681891 -145.898496) (xy 367.652965 -145.94408) (xy 367.63579 -145.96491)
			(xy 367.628678 -145.973038) (xy 367.622582 -145.993612) (xy 367.633504 -146.078956) (xy 367.635295 -146.089496)
			(xy 367.646338 -146.107781) (xy 367.65484 -146.114262) (xy 367.676045 -146.12965) (xy 367.714499 -146.165231)
			(xy 367.74772 -146.205741) (xy 367.775082 -146.250419) (xy 367.79607 -146.298421) (xy 367.810288 -146.348845)
			(xy 367.817469 -146.400741) (xy 367.817908 -146.426936) (xy 367.817422 -146.454187) (xy 367.809666 -146.508135)
			(xy 367.794311 -146.56043) (xy 367.771669 -146.610007) (xy 367.742203 -146.655857) (xy 367.706512 -146.697048)
			(xy 367.665321 -146.732739) (xy 367.619471 -146.762205) (xy 367.569894 -146.784847) (xy 367.517599 -146.800202)
			(xy 367.463651 -146.807958) (xy 367.409149 -146.807958) (xy 367.355201 -146.800202) (xy 367.302906 -146.784847)
			(xy 367.253329 -146.762205) (xy 367.207479 -146.732739) (xy 367.166288 -146.697048) (xy 367.130597 -146.655857)
			(xy 367.101131 -146.610007) (xy 367.078489 -146.56043) (xy 367.063134 -146.508135) (xy 367.055378 -146.454187)
			(xy 367.054892 -146.426936) (xy 367.055365 -146.399943) (xy 367.062967 -146.346495) (xy 367.078024 -146.294651)
			(xy 367.100235 -146.245447) (xy 367.129158 -146.199862) (xy 367.146332 -146.179032) (xy 367.153444 -146.170904)
			(xy 367.15954 -146.15033) (xy 367.148618 -146.064986) (xy 367.146848 -146.054441) (xy 367.135789 -146.036159)
			(xy 367.127282 -146.02968) (xy 367.102981 -146.012068) (xy 367.059722 -145.970472) (xy 367.041176 -145.946876)
			(xy 367.035334 -145.939002) (xy 367.017808 -145.928588) (xy 366.927384 -145.91538) (xy 366.90808 -145.920206)
			(xy 366.900206 -145.926048) (xy 366.899952 -145.926048) (xy 366.87521 -145.943554) (xy 366.821357 -145.971357)
			(xy 366.763784 -145.990292) (xy 366.703941 -145.999884) (xy 366.673638 -146.00047) (xy 366.646384 -146.000009)
			(xy 366.592431 -145.992256) (xy 366.540131 -145.976903) (xy 366.490549 -145.954262) (xy 366.444693 -145.924795)
			(xy 366.403499 -145.889101) (xy 366.367805 -145.847907) (xy 366.338338 -145.802051) (xy 366.315697 -145.752469)
			(xy 366.300344 -145.700169) (xy 366.292591 -145.646216) (xy 366.29213 -145.618962) (xy 366.292566 -145.592928)
			(xy 366.299657 -145.541345) (xy 366.31369 -145.491203) (xy 366.334403 -145.443433) (xy 366.361413 -145.398918)
			(xy 366.377474 -145.378424) (xy 366.383214 -145.370666) (xy 366.388956 -145.352256) (xy 366.38865 -145.34261)
			(xy 366.3823 -145.262854) (xy 366.373664 -145.245074) (xy 366.366298 -145.238724) (xy 366.346658 -145.220536)
			(xy 366.312132 -145.179632) (xy 366.28366 -145.134305) (xy 366.261801 -145.085445) (xy 366.246983 -145.034009)
			(xy 366.239498 -144.981008) (xy 366.239044 -144.954244) (xy 360.506611 -144.954244) (xy 360.520663 -145.002096)
			(xy 360.528421 -145.056047) (xy 360.528421 -145.110553) (xy 360.520663 -145.164504) (xy 360.505306 -145.216801)
			(xy 360.482662 -145.266381) (xy 360.453193 -145.312233) (xy 360.417497 -145.353424) (xy 360.376302 -145.389115)
			(xy 360.330447 -145.418581) (xy 360.280866 -145.441219) (xy 360.228567 -145.456571) (xy 360.174615 -145.464323)
			(xy 360.147362 -145.464784) (xy 360.121047 -145.464347) (xy 360.068917 -145.457107) (xy 360.018273 -145.442782)
			(xy 359.970074 -145.421644) (xy 359.925232 -145.394092) (xy 359.884594 -145.360648) (xy 359.866438 -145.341594)
			(xy 359.858905 -145.334206) (xy 359.839634 -145.325674) (xy 359.8291 -145.325084) (xy 359.754424 -145.325084)
			(xy 359.743875 -145.325618) (xy 359.72458 -145.33415) (xy 359.717086 -145.341594) (xy 359.698929 -145.360648)
			(xy 359.6583 -145.394106) (xy 359.61346 -145.421665) (xy 359.565259 -145.442804) (xy 359.514612 -145.457121)
			(xy 359.462478 -145.464346) (xy 359.436162 -145.464784) (xy 359.408911 -145.464344) (xy 359.354964 -145.456582)
			(xy 359.30267 -145.441223) (xy 359.253095 -145.418578) (xy 359.207246 -145.389109) (xy 359.166058 -145.353415)
			(xy 359.130368 -145.312223) (xy 359.100904 -145.266372) (xy 359.078264 -145.216794) (xy 359.06291 -145.164499)
			(xy 359.055154 -145.110551) (xy 351.782725 -145.110551) (xy 351.793243 -145.132989) (xy 351.809311 -145.186396)
			(xy 351.817431 -145.241572) (xy 351.81794 -145.269458) (xy 351.817431 -145.297344) (xy 351.809311 -145.35252)
			(xy 351.793243 -145.405927) (xy 351.769571 -145.456424) (xy 351.738798 -145.502937) (xy 351.701581 -145.544474)
			(xy 351.658713 -145.580149) (xy 351.611107 -145.609203) (xy 351.559778 -145.631015) (xy 351.505821 -145.645121)
			(xy 351.450384 -145.651221) (xy 351.39465 -145.649184) (xy 351.339807 -145.639054) (xy 351.287023 -145.621047)
			(xy 351.237423 -145.595546) (xy 351.192065 -145.563095) (xy 351.151916 -145.524386) (xy 351.11783 -145.480243)
			(xy 351.090534 -145.431608) (xy 351.070611 -145.379517) (xy 351.058485 -145.32508) (xy 351.054414 -145.269458)
			(xy 337.19493 -145.269458) (xy 337.243597 -145.290139) (xy 337.291203 -145.319193) (xy 337.334071 -145.354868)
			(xy 337.371288 -145.396405) (xy 337.402061 -145.442918) (xy 337.425733 -145.493415) (xy 337.441801 -145.546822)
			(xy 337.449921 -145.601998) (xy 337.45043 -145.629884) (xy 337.449921 -145.65777) (xy 337.441801 -145.712946)
			(xy 337.425733 -145.766353) (xy 337.402061 -145.81685) (xy 337.371288 -145.863363) (xy 337.334071 -145.9049)
			(xy 337.291203 -145.940575) (xy 337.243597 -145.969629) (xy 337.192268 -145.991441) (xy 337.138311 -146.005547)
			(xy 337.082874 -146.011647) (xy 337.02714 -146.00961) (xy 336.972297 -145.99948) (xy 336.919513 -145.981473)
			(xy 336.869913 -145.955972) (xy 336.824555 -145.923521) (xy 336.784406 -145.884812) (xy 336.75032 -145.840669)
			(xy 336.723024 -145.792034) (xy 336.703101 -145.739943) (xy 336.690975 -145.685506) (xy 336.686904 -145.629884)
			(xy 335.2694 -145.629884) (xy 335.291149 -145.647984) (xy 335.328366 -145.689521) (xy 335.359139 -145.736034)
			(xy 335.382811 -145.786531) (xy 335.398879 -145.839938) (xy 335.406999 -145.895114) (xy 335.407508 -145.923)
			(xy 335.406999 -145.950886) (xy 335.398879 -146.006062) (xy 335.382811 -146.059469) (xy 335.359139 -146.109966)
			(xy 335.328366 -146.156479) (xy 335.291149 -146.198016) (xy 335.248281 -146.233691) (xy 335.200675 -146.262745)
			(xy 335.149346 -146.284557) (xy 335.095389 -146.298663) (xy 335.039952 -146.304763) (xy 334.984218 -146.302726)
			(xy 334.929375 -146.292596) (xy 334.876591 -146.274589) (xy 334.826991 -146.249088) (xy 334.781633 -146.216637)
			(xy 334.741484 -146.177928) (xy 334.707398 -146.133785) (xy 334.680102 -146.08515) (xy 334.660179 -146.033059)
			(xy 334.648053 -145.978622) (xy 334.643982 -145.923) (xy 314.083949 -145.923) (xy 314.113143 -145.961046)
			(xy 314.14311 -146.012952) (xy 314.166046 -146.068325) (xy 314.181559 -146.126218) (xy 314.189382 -146.18564)
			(xy 314.189872 -146.215608) (xy 314.189872 -146.50212) (xy 341.637364 -146.50212) (xy 341.641435 -146.446498)
			(xy 341.653561 -146.392061) (xy 341.673484 -146.33997) (xy 341.70078 -146.291335) (xy 341.734866 -146.247192)
			(xy 341.775015 -146.208483) (xy 341.820373 -146.176032) (xy 341.869973 -146.150531) (xy 341.922757 -146.132524)
			(xy 341.9776 -146.122394) (xy 342.033334 -146.120357) (xy 342.088771 -146.126457) (xy 342.142728 -146.140563)
			(xy 342.194057 -146.162375) (xy 342.241663 -146.191429) (xy 342.284531 -146.227104) (xy 342.321748 -146.268641)
			(xy 342.352521 -146.315154) (xy 342.376193 -146.365651) (xy 342.392261 -146.419058) (xy 342.400381 -146.474234)
			(xy 342.40089 -146.50212) (xy 342.400381 -146.530006) (xy 342.392261 -146.585182) (xy 342.376193 -146.638589)
			(xy 342.352521 -146.689086) (xy 342.321748 -146.735599) (xy 342.284531 -146.777136) (xy 342.241663 -146.812811)
			(xy 342.194057 -146.841865) (xy 342.142728 -146.863677) (xy 342.088771 -146.877783) (xy 342.033334 -146.883883)
			(xy 341.9776 -146.881846) (xy 341.922757 -146.871716) (xy 341.869973 -146.853709) (xy 341.820373 -146.828208)
			(xy 341.775015 -146.795757) (xy 341.734866 -146.757048) (xy 341.70078 -146.712905) (xy 341.673484 -146.66427)
			(xy 341.653561 -146.612179) (xy 341.641435 -146.557742) (xy 341.637364 -146.50212) (xy 314.189872 -146.50212)
			(xy 314.189872 -146.939) (xy 334.643982 -146.939) (xy 334.648053 -146.883378) (xy 334.660179 -146.828941)
			(xy 334.680102 -146.77685) (xy 334.707398 -146.728215) (xy 334.741484 -146.684072) (xy 334.781633 -146.645363)
			(xy 334.826991 -146.612912) (xy 334.876591 -146.587411) (xy 334.929375 -146.569404) (xy 334.984218 -146.559274)
			(xy 335.039952 -146.557237) (xy 335.095389 -146.563337) (xy 335.149346 -146.577443) (xy 335.200675 -146.599255)
			(xy 335.248281 -146.628309) (xy 335.291149 -146.663984) (xy 335.328366 -146.705521) (xy 335.359139 -146.752034)
			(xy 335.382811 -146.802531) (xy 335.398879 -146.855938) (xy 335.406999 -146.911114) (xy 335.407508 -146.939)
			(xy 336.675982 -146.939) (xy 336.680053 -146.883378) (xy 336.692179 -146.828941) (xy 336.712102 -146.77685)
			(xy 336.739398 -146.728215) (xy 336.773484 -146.684072) (xy 336.813633 -146.645363) (xy 336.858991 -146.612912)
			(xy 336.908591 -146.587411) (xy 336.961375 -146.569404) (xy 337.016218 -146.559274) (xy 337.071952 -146.557237)
			(xy 337.127389 -146.563337) (xy 337.181346 -146.577443) (xy 337.232675 -146.599255) (xy 337.280281 -146.628309)
			(xy 337.323149 -146.663984) (xy 337.360366 -146.705521) (xy 337.391139 -146.752034) (xy 337.414811 -146.802531)
			(xy 337.430879 -146.855938) (xy 337.438999 -146.911114) (xy 337.439508 -146.939) (xy 337.438999 -146.966886)
			(xy 337.430879 -147.022062) (xy 337.414811 -147.075469) (xy 337.391139 -147.125966) (xy 337.373845 -147.152106)
			(xy 340.499444 -147.152106) (xy 340.503515 -147.096484) (xy 340.515641 -147.042047) (xy 340.535564 -146.989956)
			(xy 340.56286 -146.941321) (xy 340.596946 -146.897178) (xy 340.637095 -146.858469) (xy 340.682453 -146.826018)
			(xy 340.732053 -146.800517) (xy 340.784837 -146.78251) (xy 340.83968 -146.77238) (xy 340.895414 -146.770343)
			(xy 340.950851 -146.776443) (xy 341.004808 -146.790549) (xy 341.056137 -146.812361) (xy 341.103743 -146.841415)
			(xy 341.146611 -146.87709) (xy 341.180462 -146.91487) (xy 367.916204 -146.91487) (xy 367.920275 -146.859248)
			(xy 367.932401 -146.804811) (xy 367.952324 -146.75272) (xy 367.97962 -146.704085) (xy 368.013706 -146.659942)
			(xy 368.053855 -146.621233) (xy 368.099213 -146.588782) (xy 368.148813 -146.563281) (xy 368.201597 -146.545274)
			(xy 368.25644 -146.535144) (xy 368.312174 -146.533107) (xy 368.367611 -146.539207) (xy 368.421568 -146.553313)
			(xy 368.472897 -146.575125) (xy 368.520503 -146.604179) (xy 368.563371 -146.639854) (xy 368.600588 -146.681391)
			(xy 368.631361 -146.727904) (xy 368.655033 -146.778401) (xy 368.671101 -146.831808) (xy 368.679221 -146.886984)
			(xy 368.67973 -146.91487) (xy 368.679221 -146.942756) (xy 368.671101 -146.997932) (xy 368.655033 -147.051339)
			(xy 368.631361 -147.101836) (xy 368.600588 -147.148349) (xy 368.563371 -147.189886) (xy 368.520503 -147.225561)
			(xy 368.472897 -147.254615) (xy 368.421568 -147.276427) (xy 368.367611 -147.290533) (xy 368.312174 -147.296633)
			(xy 368.25644 -147.294596) (xy 368.201597 -147.284466) (xy 368.148813 -147.266459) (xy 368.099213 -147.240958)
			(xy 368.053855 -147.208507) (xy 368.013706 -147.169798) (xy 367.97962 -147.125655) (xy 367.952324 -147.07702)
			(xy 367.932401 -147.024929) (xy 367.920275 -146.970492) (xy 367.916204 -146.91487) (xy 341.180462 -146.91487)
			(xy 341.183828 -146.918627) (xy 341.214601 -146.96514) (xy 341.238273 -147.015637) (xy 341.254341 -147.069044)
			(xy 341.262461 -147.12422) (xy 341.26297 -147.152106) (xy 341.262461 -147.179992) (xy 341.254341 -147.235168)
			(xy 341.238273 -147.288575) (xy 341.214601 -147.339072) (xy 341.183828 -147.385585) (xy 341.146611 -147.427122)
			(xy 341.103743 -147.462797) (xy 341.056137 -147.491851) (xy 341.004808 -147.513663) (xy 340.950851 -147.527769)
			(xy 340.895414 -147.533869) (xy 340.83968 -147.531832) (xy 340.784837 -147.521702) (xy 340.732053 -147.503695)
			(xy 340.682453 -147.478194) (xy 340.637095 -147.445743) (xy 340.596946 -147.407034) (xy 340.56286 -147.362891)
			(xy 340.535564 -147.314256) (xy 340.515641 -147.262165) (xy 340.503515 -147.207728) (xy 340.499444 -147.152106)
			(xy 337.373845 -147.152106) (xy 337.360366 -147.172479) (xy 337.323149 -147.214016) (xy 337.280281 -147.249691)
			(xy 337.232675 -147.278745) (xy 337.181346 -147.300557) (xy 337.127389 -147.314663) (xy 337.071952 -147.320763)
			(xy 337.016218 -147.318726) (xy 336.961375 -147.308596) (xy 336.908591 -147.290589) (xy 336.858991 -147.265088)
			(xy 336.813633 -147.232637) (xy 336.773484 -147.193928) (xy 336.739398 -147.149785) (xy 336.712102 -147.10115)
			(xy 336.692179 -147.049059) (xy 336.680053 -146.994622) (xy 336.675982 -146.939) (xy 335.407508 -146.939)
			(xy 335.406999 -146.966886) (xy 335.398879 -147.022062) (xy 335.382811 -147.075469) (xy 335.359139 -147.125966)
			(xy 335.328366 -147.172479) (xy 335.291149 -147.214016) (xy 335.248281 -147.249691) (xy 335.200675 -147.278745)
			(xy 335.149346 -147.300557) (xy 335.095389 -147.314663) (xy 335.039952 -147.320763) (xy 334.984218 -147.318726)
			(xy 334.929375 -147.308596) (xy 334.876591 -147.290589) (xy 334.826991 -147.265088) (xy 334.781633 -147.232637)
			(xy 334.741484 -147.193928) (xy 334.707398 -147.149785) (xy 334.680102 -147.10115) (xy 334.660179 -147.049059)
			(xy 334.648053 -146.994622) (xy 334.643982 -146.939) (xy 314.189872 -146.939) (xy 314.189872 -147.079208)
			(xy 314.189382 -147.109176) (xy 314.181559 -147.168598) (xy 314.166046 -147.226491) (xy 314.14311 -147.281864)
			(xy 314.113143 -147.33377) (xy 314.076656 -147.38132) (xy 314.034276 -147.4237) (xy 313.986726 -147.460187)
			(xy 313.93482 -147.490154) (xy 313.879447 -147.51309) (xy 313.821554 -147.528603) (xy 313.762132 -147.536426)
			(xy 313.702196 -147.536426) (xy 313.642774 -147.528603) (xy 313.584881 -147.51309) (xy 313.529508 -147.490154)
			(xy 313.477602 -147.460187) (xy 313.430052 -147.4237) (xy 313.387672 -147.38132) (xy 313.351185 -147.33377)
			(xy 313.321218 -147.281864) (xy 313.298282 -147.226491) (xy 313.282769 -147.168598) (xy 313.274946 -147.109176)
			(xy 313.274456 -147.079208) (xy 309.581804 -147.079208) (xy 309.581804 -148.88591) (xy 315.916564 -148.88591)
			(xy 315.916564 -148.02231) (xy 315.917054 -147.992342) (xy 315.924877 -147.93292) (xy 315.94039 -147.875027)
			(xy 315.963326 -147.819654) (xy 315.993293 -147.767748) (xy 316.02978 -147.720198) (xy 316.07216 -147.677818)
			(xy 316.11971 -147.641331) (xy 316.171616 -147.611364) (xy 316.226989 -147.588428) (xy 316.284882 -147.572915)
			(xy 316.344304 -147.565092) (xy 316.40424 -147.565092) (xy 316.463662 -147.572915) (xy 316.521555 -147.588428)
			(xy 316.576928 -147.611364) (xy 316.628834 -147.641331) (xy 316.676384 -147.677818) (xy 316.718764 -147.720198)
			(xy 316.755251 -147.767748) (xy 316.775079 -147.802092) (xy 341.637364 -147.802092) (xy 341.641435 -147.74647)
			(xy 341.653561 -147.692033) (xy 341.673484 -147.639942) (xy 341.70078 -147.591307) (xy 341.734866 -147.547164)
			(xy 341.775015 -147.508455) (xy 341.820373 -147.476004) (xy 341.869973 -147.450503) (xy 341.922757 -147.432496)
			(xy 341.9776 -147.422366) (xy 342.033334 -147.420329) (xy 342.088771 -147.426429) (xy 342.142728 -147.440535)
			(xy 342.194057 -147.462347) (xy 342.241663 -147.491401) (xy 342.284531 -147.527076) (xy 342.321748 -147.568613)
			(xy 342.352521 -147.615126) (xy 342.370987 -147.654518) (xy 350.89973 -147.654518) (xy 350.900216 -147.627267)
			(xy 350.907972 -147.573319) (xy 350.923327 -147.521024) (xy 350.945969 -147.471447) (xy 350.975435 -147.425597)
			(xy 351.011126 -147.384406) (xy 351.052317 -147.348715) (xy 351.098167 -147.319249) (xy 351.147744 -147.296607)
			(xy 351.200039 -147.281252) (xy 351.253987 -147.273496) (xy 351.308489 -147.273496) (xy 351.362437 -147.281252)
			(xy 351.414732 -147.296607) (xy 351.464309 -147.319249) (xy 351.510159 -147.348715) (xy 351.55135 -147.384406)
			(xy 351.587041 -147.425597) (xy 351.616507 -147.471447) (xy 351.639149 -147.521024) (xy 351.654504 -147.573319)
			(xy 351.66226 -147.627267) (xy 351.662746 -147.654518) (xy 352.95408 -147.654518) (xy 352.958151 -147.598896)
			(xy 352.970277 -147.544459) (xy 352.9902 -147.492368) (xy 353.017496 -147.443733) (xy 353.051582 -147.39959)
			(xy 353.091731 -147.360881) (xy 353.137089 -147.32843) (xy 353.186689 -147.302929) (xy 353.239473 -147.284922)
			(xy 353.294316 -147.274792) (xy 353.35005 -147.272755) (xy 353.405487 -147.278855) (xy 353.459444 -147.292961)
			(xy 353.510773 -147.314773) (xy 353.558379 -147.343827) (xy 353.601247 -147.379502) (xy 353.638464 -147.421039)
			(xy 353.669237 -147.467552) (xy 353.692909 -147.518049) (xy 353.708977 -147.571456) (xy 353.717097 -147.626632)
			(xy 353.717606 -147.654518) (xy 353.717549 -147.657656) (xy 359.450543 -147.657656) (xy 359.450543 -147.603144)
			(xy 359.458301 -147.549188) (xy 359.47366 -147.496885) (xy 359.496306 -147.447301) (xy 359.525779 -147.401445)
			(xy 359.561478 -147.360249) (xy 359.602677 -147.324555) (xy 359.648536 -147.295087) (xy 359.698123 -147.272446)
			(xy 359.750427 -147.257093) (xy 359.804384 -147.24934) (xy 359.83164 -147.24888) (xy 359.857955 -147.249327)
			(xy 359.910084 -147.256567) (xy 359.960727 -147.270891) (xy 360.008925 -147.292027) (xy 360.053768 -147.319576)
			(xy 360.094408 -147.353017) (xy 360.112564 -147.37207) (xy 360.120101 -147.379453) (xy 360.139369 -147.387989)
			(xy 360.149902 -147.38858) (xy 360.224578 -147.38858) (xy 360.235129 -147.388058) (xy 360.254424 -147.379519)
			(xy 360.261916 -147.37207) (xy 360.281736 -147.351282) (xy 360.326508 -147.315307) (xy 360.376166 -147.286447)
			(xy 360.429588 -147.265354) (xy 360.485567 -147.252505) (xy 360.54284 -147.24819) (xy 360.600113 -147.252505)
			(xy 360.656092 -147.265354) (xy 360.709514 -147.286447) (xy 360.759172 -147.315307) (xy 360.803944 -147.351282)
			(xy 360.823764 -147.37207) (xy 360.831301 -147.379453) (xy 360.850569 -147.387989) (xy 360.861102 -147.38858)
			(xy 360.935778 -147.38858) (xy 360.946329 -147.388058) (xy 360.965624 -147.379519) (xy 360.973116 -147.37207)
			(xy 360.991265 -147.353008) (xy 361.031897 -147.319553) (xy 361.076739 -147.291995) (xy 361.124941 -147.270858)
			(xy 361.175589 -147.256542) (xy 361.227724 -147.249318) (xy 361.25404 -147.24888) (xy 361.281288 -147.249393)
			(xy 361.33523 -147.257154) (xy 361.387518 -147.272512) (xy 361.437089 -147.295155) (xy 361.482933 -147.324621)
			(xy 361.524117 -147.360311) (xy 361.559803 -147.401499) (xy 361.589265 -147.447346) (xy 361.611902 -147.496919)
			(xy 361.627255 -147.549209) (xy 361.63501 -147.603151) (xy 361.63501 -147.657649) (xy 361.627255 -147.711591)
			(xy 361.611902 -147.763881) (xy 361.589265 -147.813454) (xy 361.559803 -147.859301) (xy 361.524117 -147.900489)
			(xy 361.482933 -147.936179) (xy 361.437089 -147.965645) (xy 361.387518 -147.988288) (xy 361.33523 -148.003646)
			(xy 361.281288 -148.011407) (xy 361.25404 -148.011896) (xy 361.227725 -148.01147) (xy 361.175594 -148.004227)
			(xy 361.124951 -147.9899) (xy 361.076752 -147.968759) (xy 361.031909 -147.941206) (xy 360.991271 -147.907761)
			(xy 360.973116 -147.888706) (xy 360.965589 -147.88131) (xy 360.946313 -147.872782) (xy 360.935778 -147.872196)
			(xy 360.861102 -147.872196) (xy 360.850551 -147.872714) (xy 360.831256 -147.881257) (xy 360.823764 -147.888706)
			(xy 360.803944 -147.909494) (xy 360.759172 -147.945469) (xy 360.709514 -147.974329) (xy 360.656092 -147.995422)
			(xy 360.600113 -148.008271) (xy 360.54284 -148.012586) (xy 360.485567 -148.008271) (xy 360.429588 -147.995422)
			(xy 360.376166 -147.974329) (xy 360.326508 -147.945469) (xy 360.281736 -147.909494) (xy 360.261916 -147.888706)
			(xy 360.254389 -147.88131) (xy 360.235113 -147.872782) (xy 360.224578 -147.872196) (xy 360.149902 -147.872196)
			(xy 360.139351 -147.872714) (xy 360.120056 -147.881257) (xy 360.112564 -147.888706) (xy 360.09442 -147.907773)
			(xy 360.053788 -147.941229) (xy 360.008945 -147.968786) (xy 359.960742 -147.989923) (xy 359.910092 -148.004237)
			(xy 359.857957 -148.011459) (xy 359.83164 -148.011896) (xy 359.804384 -148.01146) (xy 359.750427 -148.003707)
			(xy 359.698123 -147.988354) (xy 359.648536 -147.965713) (xy 359.602677 -147.936245) (xy 359.561478 -147.900551)
			(xy 359.525779 -147.859355) (xy 359.496306 -147.813499) (xy 359.47366 -147.763915) (xy 359.458301 -147.711612)
			(xy 359.450543 -147.657656) (xy 353.717549 -147.657656) (xy 353.717097 -147.682404) (xy 353.708977 -147.73758)
			(xy 353.692909 -147.790987) (xy 353.669237 -147.841484) (xy 353.638464 -147.887997) (xy 353.601247 -147.929534)
			(xy 353.558379 -147.965209) (xy 353.510773 -147.994263) (xy 353.459444 -148.016075) (xy 353.453083 -148.017738)
			(xy 364.277654 -148.017738) (xy 364.281725 -147.962116) (xy 364.293851 -147.907679) (xy 364.313774 -147.855588)
			(xy 364.34107 -147.806953) (xy 364.375156 -147.76281) (xy 364.415305 -147.724101) (xy 364.460663 -147.69165)
			(xy 364.510263 -147.666149) (xy 364.563047 -147.648142) (xy 364.61789 -147.638012) (xy 364.673624 -147.635975)
			(xy 364.729061 -147.642075) (xy 364.783018 -147.656181) (xy 364.834347 -147.677993) (xy 364.881953 -147.707047)
			(xy 364.924821 -147.742722) (xy 364.962038 -147.784259) (xy 364.992811 -147.830772) (xy 365.016483 -147.881269)
			(xy 365.032551 -147.934676) (xy 365.040671 -147.989852) (xy 365.04118 -148.017738) (xy 365.040671 -148.045624)
			(xy 365.032551 -148.1008) (xy 365.016483 -148.154207) (xy 364.992811 -148.204704) (xy 364.962038 -148.251217)
			(xy 364.924821 -148.292754) (xy 364.881953 -148.328429) (xy 364.834347 -148.357483) (xy 364.783018 -148.379295)
			(xy 364.729061 -148.393401) (xy 364.673624 -148.399501) (xy 364.61789 -148.397464) (xy 364.563047 -148.387334)
			(xy 364.510263 -148.369327) (xy 364.460663 -148.343826) (xy 364.415305 -148.311375) (xy 364.375156 -148.272666)
			(xy 364.34107 -148.228523) (xy 364.313774 -148.179888) (xy 364.293851 -148.127797) (xy 364.281725 -148.07336)
			(xy 364.277654 -148.017738) (xy 353.453083 -148.017738) (xy 353.405487 -148.030181) (xy 353.35005 -148.036281)
			(xy 353.294316 -148.034244) (xy 353.239473 -148.024114) (xy 353.186689 -148.006107) (xy 353.137089 -147.980606)
			(xy 353.091731 -147.948155) (xy 353.051582 -147.909446) (xy 353.017496 -147.865303) (xy 352.9902 -147.816668)
			(xy 352.970277 -147.764577) (xy 352.958151 -147.71014) (xy 352.95408 -147.654518) (xy 351.662746 -147.654518)
			(xy 351.662331 -147.681517) (xy 351.654726 -147.734977) (xy 351.639657 -147.78683) (xy 351.617425 -147.836039)
			(xy 351.588474 -147.881621) (xy 351.553384 -147.922663) (xy 351.512855 -147.958345) (xy 351.490534 -147.973542)
			(xy 351.478774 -147.981858) (xy 351.460084 -148.003757) (xy 351.448242 -148.029999) (xy 351.444188 -148.058503)
			(xy 351.448244 -148.087006) (xy 351.460087 -148.113247) (xy 351.478778 -148.135145) (xy 351.490534 -148.143468)
			(xy 351.512908 -148.158695) (xy 351.553587 -148.194389) (xy 351.588816 -148.235471) (xy 351.617889 -148.281117)
			(xy 351.640223 -148.330412) (xy 351.655371 -148.382367) (xy 351.663029 -148.435941) (xy 351.663508 -148.463)
			(xy 351.663022 -148.490251) (xy 351.655266 -148.544199) (xy 351.639911 -148.596494) (xy 351.617269 -148.646071)
			(xy 351.587803 -148.691921) (xy 351.552112 -148.733112) (xy 351.510921 -148.768803) (xy 351.465071 -148.798269)
			(xy 351.415494 -148.820911) (xy 351.363199 -148.836266) (xy 351.309251 -148.844022) (xy 351.254749 -148.844022)
			(xy 351.200801 -148.836266) (xy 351.148506 -148.820911) (xy 351.098929 -148.798269) (xy 351.053079 -148.768803)
			(xy 351.011888 -148.733112) (xy 350.976197 -148.691921) (xy 350.946731 -148.646071) (xy 350.924089 -148.596494)
			(xy 350.908734 -148.544199) (xy 350.900978 -148.490251) (xy 350.900492 -148.463) (xy 350.900949 -148.436003)
			(xy 350.90855 -148.382546) (xy 350.923614 -148.330695) (xy 350.94584 -148.281487) (xy 350.974783 -148.235905)
			(xy 351.009866 -148.194861) (xy 351.050387 -148.159175) (xy 351.072704 -148.143976) (xy 351.08449 -148.135666)
			(xy 351.103264 -148.113794) (xy 351.115165 -148.087541) (xy 351.119242 -148.059007) (xy 351.115169 -148.030472)
			(xy 351.103272 -148.004218) (xy 351.084501 -147.982344) (xy 351.072704 -147.97405) (xy 351.0503 -147.958864)
			(xy 351.009621 -147.923164) (xy 350.974393 -147.882076) (xy 350.945322 -147.836423) (xy 350.922992 -147.787121)
			(xy 350.907852 -147.735159) (xy 350.900203 -147.681579) (xy 350.89973 -147.654518) (xy 342.370987 -147.654518)
			(xy 342.376193 -147.665623) (xy 342.392261 -147.71903) (xy 342.400381 -147.774206) (xy 342.40089 -147.802092)
			(xy 342.400381 -147.829978) (xy 342.392261 -147.885154) (xy 342.376193 -147.938561) (xy 342.352521 -147.989058)
			(xy 342.321748 -148.035571) (xy 342.284531 -148.077108) (xy 342.241663 -148.112783) (xy 342.194057 -148.141837)
			(xy 342.142728 -148.163649) (xy 342.088771 -148.177755) (xy 342.033334 -148.183855) (xy 341.9776 -148.181818)
			(xy 341.922757 -148.171688) (xy 341.869973 -148.153681) (xy 341.820373 -148.12818) (xy 341.775015 -148.095729)
			(xy 341.734866 -148.05702) (xy 341.70078 -148.012877) (xy 341.673484 -147.964242) (xy 341.653561 -147.912151)
			(xy 341.641435 -147.857714) (xy 341.637364 -147.802092) (xy 316.775079 -147.802092) (xy 316.785218 -147.819654)
			(xy 316.808154 -147.875027) (xy 316.823667 -147.93292) (xy 316.83149 -147.992342) (xy 316.83198 -148.02231)
			(xy 316.83198 -148.291804) (xy 336.675982 -148.291804) (xy 336.680053 -148.236182) (xy 336.692179 -148.181745)
			(xy 336.712102 -148.129654) (xy 336.739398 -148.081019) (xy 336.773484 -148.036876) (xy 336.813633 -147.998167)
			(xy 336.858991 -147.965716) (xy 336.908591 -147.940215) (xy 336.961375 -147.922208) (xy 337.016218 -147.912078)
			(xy 337.071952 -147.910041) (xy 337.127389 -147.916141) (xy 337.181346 -147.930247) (xy 337.232675 -147.952059)
			(xy 337.280281 -147.981113) (xy 337.323149 -148.016788) (xy 337.360366 -148.058325) (xy 337.391139 -148.104838)
			(xy 337.414811 -148.155335) (xy 337.430879 -148.208742) (xy 337.438999 -148.263918) (xy 337.439508 -148.291804)
			(xy 337.438999 -148.31969) (xy 337.430879 -148.374866) (xy 337.414811 -148.428273) (xy 337.403652 -148.452078)
			(xy 349.87306 -148.452078) (xy 349.877131 -148.396456) (xy 349.889257 -148.342019) (xy 349.90918 -148.289928)
			(xy 349.936476 -148.241293) (xy 349.970562 -148.19715) (xy 350.010711 -148.158441) (xy 350.056069 -148.12599)
			(xy 350.105669 -148.100489) (xy 350.158453 -148.082482) (xy 350.213296 -148.072352) (xy 350.26903 -148.070315)
			(xy 350.324467 -148.076415) (xy 350.378424 -148.090521) (xy 350.429753 -148.112333) (xy 350.477359 -148.141387)
			(xy 350.520227 -148.177062) (xy 350.557444 -148.218599) (xy 350.588217 -148.265112) (xy 350.611889 -148.315609)
			(xy 350.627957 -148.369016) (xy 350.636077 -148.424192) (xy 350.636586 -148.452078) (xy 350.636077 -148.479964)
			(xy 350.627957 -148.53514) (xy 350.611889 -148.588547) (xy 350.588217 -148.639044) (xy 350.557444 -148.685557)
			(xy 350.520227 -148.727094) (xy 350.477359 -148.762769) (xy 350.429753 -148.791823) (xy 350.378424 -148.813635)
			(xy 350.324467 -148.827741) (xy 350.26903 -148.833841) (xy 350.213296 -148.831804) (xy 350.158453 -148.821674)
			(xy 350.105669 -148.803667) (xy 350.056069 -148.778166) (xy 350.010711 -148.745715) (xy 349.970562 -148.707006)
			(xy 349.936476 -148.662863) (xy 349.90918 -148.614228) (xy 349.889257 -148.562137) (xy 349.877131 -148.5077)
			(xy 349.87306 -148.452078) (xy 337.403652 -148.452078) (xy 337.391139 -148.47877) (xy 337.360366 -148.525283)
			(xy 337.323149 -148.56682) (xy 337.280281 -148.602495) (xy 337.232675 -148.631549) (xy 337.181346 -148.653361)
			(xy 337.127389 -148.667467) (xy 337.071952 -148.673567) (xy 337.016218 -148.67153) (xy 336.961375 -148.6614)
			(xy 336.908591 -148.643393) (xy 336.858991 -148.617892) (xy 336.813633 -148.585441) (xy 336.773484 -148.546732)
			(xy 336.739398 -148.502589) (xy 336.712102 -148.453954) (xy 336.692179 -148.401863) (xy 336.680053 -148.347426)
			(xy 336.675982 -148.291804) (xy 316.83198 -148.291804) (xy 316.83198 -148.88591) (xy 316.83149 -148.915878)
			(xy 316.824233 -148.971) (xy 334.643982 -148.971) (xy 334.648053 -148.915378) (xy 334.660179 -148.860941)
			(xy 334.680102 -148.80885) (xy 334.707398 -148.760215) (xy 334.741484 -148.716072) (xy 334.781633 -148.677363)
			(xy 334.826991 -148.644912) (xy 334.876591 -148.619411) (xy 334.929375 -148.601404) (xy 334.984218 -148.591274)
			(xy 335.039952 -148.589237) (xy 335.095389 -148.595337) (xy 335.149346 -148.609443) (xy 335.200675 -148.631255)
			(xy 335.248281 -148.660309) (xy 335.291149 -148.695984) (xy 335.328366 -148.737521) (xy 335.359139 -148.784034)
			(xy 335.382811 -148.834531) (xy 335.395823 -148.877782) (xy 340.11057 -148.877782) (xy 340.114641 -148.82216)
			(xy 340.126767 -148.767723) (xy 340.14669 -148.715632) (xy 340.173986 -148.666997) (xy 340.208072 -148.622854)
			(xy 340.248221 -148.584145) (xy 340.293579 -148.551694) (xy 340.343179 -148.526193) (xy 340.395963 -148.508186)
			(xy 340.450806 -148.498056) (xy 340.50654 -148.496019) (xy 340.561977 -148.502119) (xy 340.615934 -148.516225)
			(xy 340.667263 -148.538037) (xy 340.714869 -148.567091) (xy 340.757737 -148.602766) (xy 340.794954 -148.644303)
			(xy 340.825727 -148.690816) (xy 340.849399 -148.741313) (xy 340.865467 -148.79472) (xy 340.873587 -148.849896)
			(xy 340.874096 -148.877782) (xy 340.873587 -148.905668) (xy 340.865467 -148.960844) (xy 340.849399 -149.014251)
			(xy 340.825727 -149.064748) (xy 340.794954 -149.111261) (xy 340.757737 -149.152798) (xy 340.714869 -149.188473)
			(xy 340.667263 -149.217527) (xy 340.615934 -149.239339) (xy 340.561977 -149.253445) (xy 340.50654 -149.259545)
			(xy 340.450806 -149.257508) (xy 340.395963 -149.247378) (xy 340.343179 -149.229371) (xy 340.293579 -149.20387)
			(xy 340.248221 -149.171419) (xy 340.208072 -149.13271) (xy 340.173986 -149.088567) (xy 340.14669 -149.039932)
			(xy 340.126767 -148.987841) (xy 340.114641 -148.933404) (xy 340.11057 -148.877782) (xy 335.395823 -148.877782)
			(xy 335.398879 -148.887938) (xy 335.406999 -148.943114) (xy 335.407508 -148.971) (xy 335.406999 -148.998886)
			(xy 335.398879 -149.054062) (xy 335.382811 -149.107469) (xy 335.359139 -149.157966) (xy 335.328366 -149.204479)
			(xy 335.291149 -149.246016) (xy 335.248281 -149.281691) (xy 335.200675 -149.310745) (xy 335.149346 -149.332557)
			(xy 335.095389 -149.346663) (xy 335.039952 -149.352763) (xy 334.984218 -149.350726) (xy 334.929375 -149.340596)
			(xy 334.876591 -149.322589) (xy 334.826991 -149.297088) (xy 334.781633 -149.264637) (xy 334.741484 -149.225928)
			(xy 334.707398 -149.181785) (xy 334.680102 -149.13315) (xy 334.660179 -149.081059) (xy 334.648053 -149.026622)
			(xy 334.643982 -148.971) (xy 316.824233 -148.971) (xy 316.823667 -148.9753) (xy 316.808154 -149.033193)
			(xy 316.785218 -149.088566) (xy 316.755251 -149.140472) (xy 316.718764 -149.188022) (xy 316.676384 -149.230402)
			(xy 316.628834 -149.266889) (xy 316.576928 -149.296856) (xy 316.521555 -149.319792) (xy 316.463662 -149.335305)
			(xy 316.40424 -149.343128) (xy 316.344304 -149.343128) (xy 316.284882 -149.335305) (xy 316.226989 -149.319792)
			(xy 316.171616 -149.296856) (xy 316.11971 -149.266889) (xy 316.07216 -149.230402) (xy 316.02978 -149.188022)
			(xy 315.993293 -149.140472) (xy 315.963326 -149.088566) (xy 315.94039 -149.033193) (xy 315.924877 -148.9753)
			(xy 315.917054 -148.915878) (xy 315.916564 -148.88591) (xy 309.581804 -148.88591) (xy 309.581804 -150.67915)
			(xy 313.274456 -150.67915) (xy 313.274456 -149.81555) (xy 313.274946 -149.785582) (xy 313.282769 -149.72616)
			(xy 313.298282 -149.668267) (xy 313.321218 -149.612894) (xy 313.351185 -149.560988) (xy 313.387672 -149.513438)
			(xy 313.430052 -149.471058) (xy 313.477602 -149.434571) (xy 313.529508 -149.404604) (xy 313.584881 -149.381668)
			(xy 313.642774 -149.366155) (xy 313.702196 -149.358332) (xy 313.762132 -149.358332) (xy 313.821554 -149.366155)
			(xy 313.879447 -149.381668) (xy 313.93482 -149.404604) (xy 313.986726 -149.434571) (xy 314.034276 -149.471058)
			(xy 314.076656 -149.513438) (xy 314.113143 -149.560988) (xy 314.14311 -149.612894) (xy 314.166046 -149.668267)
			(xy 314.181559 -149.72616) (xy 314.189382 -149.785582) (xy 314.189872 -149.81555) (xy 314.189872 -149.987)
			(xy 334.643982 -149.987) (xy 334.648053 -149.931378) (xy 334.660179 -149.876941) (xy 334.680102 -149.82485)
			(xy 334.707398 -149.776215) (xy 334.741484 -149.732072) (xy 334.781633 -149.693363) (xy 334.826991 -149.660912)
			(xy 334.876591 -149.635411) (xy 334.929375 -149.617404) (xy 334.984218 -149.607274) (xy 335.039952 -149.605237)
			(xy 335.095389 -149.611337) (xy 335.149346 -149.625443) (xy 335.200675 -149.647255) (xy 335.248281 -149.676309)
			(xy 335.291149 -149.711984) (xy 335.328366 -149.753521) (xy 335.359139 -149.800034) (xy 335.382811 -149.850531)
			(xy 335.398879 -149.903938) (xy 335.406999 -149.959114) (xy 335.407313 -149.976332) (xy 340.739982 -149.976332)
			(xy 340.744053 -149.92071) (xy 340.756179 -149.866273) (xy 340.776102 -149.814182) (xy 340.803398 -149.765547)
			(xy 340.837484 -149.721404) (xy 340.877633 -149.682695) (xy 340.922991 -149.650244) (xy 340.972591 -149.624743)
			(xy 341.025375 -149.606736) (xy 341.080218 -149.596606) (xy 341.135952 -149.594569) (xy 341.191389 -149.600669)
			(xy 341.245346 -149.614775) (xy 341.296675 -149.636587) (xy 341.344281 -149.665641) (xy 341.387149 -149.701316)
			(xy 341.424366 -149.742853) (xy 341.455139 -149.789366) (xy 341.478811 -149.839863) (xy 341.494879 -149.89327)
			(xy 341.502999 -149.948446) (xy 341.503355 -149.96795) (xy 351.007932 -149.96795) (xy 351.012003 -149.912328)
			(xy 351.024129 -149.857891) (xy 351.044052 -149.8058) (xy 351.071348 -149.757165) (xy 351.105434 -149.713022)
			(xy 351.145583 -149.674313) (xy 351.190941 -149.641862) (xy 351.240541 -149.616361) (xy 351.293325 -149.598354)
			(xy 351.348168 -149.588224) (xy 351.403902 -149.586187) (xy 351.459339 -149.592287) (xy 351.513296 -149.606393)
			(xy 351.564625 -149.628205) (xy 351.612231 -149.657259) (xy 351.655099 -149.692934) (xy 351.692316 -149.734471)
			(xy 351.723089 -149.780984) (xy 351.746761 -149.831481) (xy 351.762829 -149.884888) (xy 351.770949 -149.940064)
			(xy 351.771458 -149.96795) (xy 351.770949 -149.995836) (xy 351.762829 -150.051012) (xy 351.746761 -150.104419)
			(xy 351.723089 -150.154916) (xy 351.696004 -150.195854) (xy 359.450565 -150.195854) (xy 359.450565 -150.141346)
			(xy 359.458323 -150.087393) (xy 359.473681 -150.035093) (xy 359.496326 -149.985512) (xy 359.525797 -149.939658)
			(xy 359.561494 -149.898465) (xy 359.60269 -149.862773) (xy 359.648547 -149.833307) (xy 359.698131 -149.810667)
			(xy 359.750432 -149.795315) (xy 359.804386 -149.787563) (xy 359.83164 -149.787102) (xy 359.857955 -149.787542)
			(xy 359.910085 -149.794782) (xy 359.960728 -149.809107) (xy 360.008927 -149.830244) (xy 360.05377 -149.857795)
			(xy 360.094408 -149.891238) (xy 360.112564 -149.910292) (xy 360.120098 -149.917679) (xy 360.139369 -149.926212)
			(xy 360.149902 -149.926802) (xy 360.224578 -149.926802) (xy 360.235128 -149.926274) (xy 360.254423 -149.917738)
			(xy 360.261916 -149.910292) (xy 360.281736 -149.889504) (xy 360.326508 -149.853529) (xy 360.376166 -149.824669)
			(xy 360.429588 -149.803576) (xy 360.485567 -149.790727) (xy 360.54284 -149.786412) (xy 360.600113 -149.790727)
			(xy 360.656092 -149.803576) (xy 360.709514 -149.824669) (xy 360.759172 -149.853529) (xy 360.803944 -149.889504)
			(xy 360.823764 -149.910292) (xy 360.831298 -149.917679) (xy 360.850569 -149.926212) (xy 360.861102 -149.926802)
			(xy 360.935778 -149.926802) (xy 360.946328 -149.926274) (xy 360.965623 -149.917738) (xy 360.973116 -149.910292)
			(xy 360.991269 -149.891234) (xy 361.0319 -149.857778) (xy 361.07674 -149.830219) (xy 361.124942 -149.809081)
			(xy 361.175589 -149.794764) (xy 361.227724 -149.78754) (xy 361.25404 -149.787102) (xy 361.28129 -149.787571)
			(xy 361.335235 -149.795332) (xy 361.387526 -149.810691) (xy 361.4371 -149.833335) (xy 361.482946 -149.862803)
			(xy 361.524133 -149.898495) (xy 361.559821 -149.939686) (xy 361.589284 -149.985535) (xy 361.611923 -150.035111)
			(xy 361.627277 -150.087404) (xy 361.6311 -150.114) (xy 363.091982 -150.114) (xy 363.096053 -150.058378)
			(xy 363.108179 -150.003941) (xy 363.128102 -149.95185) (xy 363.155398 -149.903215) (xy 363.189484 -149.859072)
			(xy 363.229633 -149.820363) (xy 363.274991 -149.787912) (xy 363.324591 -149.762411) (xy 363.377375 -149.744404)
			(xy 363.432218 -149.734274) (xy 363.487952 -149.732237) (xy 363.543389 -149.738337) (xy 363.597346 -149.752443)
			(xy 363.648675 -149.774255) (xy 363.696281 -149.803309) (xy 363.739149 -149.838984) (xy 363.776366 -149.880521)
			(xy 363.807139 -149.927034) (xy 363.830811 -149.977531) (xy 363.846879 -150.030938) (xy 363.851664 -150.063454)
			(xy 364.138208 -150.063454) (xy 364.142279 -150.007832) (xy 364.154405 -149.953395) (xy 364.174328 -149.901304)
			(xy 364.201624 -149.852669) (xy 364.23571 -149.808526) (xy 364.275859 -149.769817) (xy 364.321217 -149.737366)
			(xy 364.370817 -149.711865) (xy 364.423601 -149.693858) (xy 364.478444 -149.683728) (xy 364.534178 -149.681691)
			(xy 364.589615 -149.687791) (xy 364.643572 -149.701897) (xy 364.694901 -149.723709) (xy 364.742507 -149.752763)
			(xy 364.785375 -149.788438) (xy 364.822592 -149.829975) (xy 364.853365 -149.876488) (xy 364.877037 -149.926985)
			(xy 364.893105 -149.980392) (xy 364.901225 -150.035568) (xy 364.901734 -150.063454) (xy 364.901225 -150.09134)
			(xy 364.893105 -150.146516) (xy 364.877037 -150.199923) (xy 364.853365 -150.25042) (xy 364.822592 -150.296933)
			(xy 364.785375 -150.33847) (xy 364.742507 -150.374145) (xy 364.694901 -150.403199) (xy 364.643572 -150.425011)
			(xy 364.589615 -150.439117) (xy 364.534178 -150.445217) (xy 364.478444 -150.44318) (xy 364.423601 -150.43305)
			(xy 364.370817 -150.415043) (xy 364.321217 -150.389542) (xy 364.275859 -150.357091) (xy 364.23571 -150.318382)
			(xy 364.201624 -150.274239) (xy 364.174328 -150.225604) (xy 364.154405 -150.173513) (xy 364.142279 -150.119076)
			(xy 364.138208 -150.063454) (xy 363.851664 -150.063454) (xy 363.854999 -150.086114) (xy 363.855508 -150.114)
			(xy 363.854999 -150.141886) (xy 363.846879 -150.197062) (xy 363.830811 -150.250469) (xy 363.807139 -150.300966)
			(xy 363.776366 -150.347479) (xy 363.739149 -150.389016) (xy 363.696281 -150.424691) (xy 363.648675 -150.453745)
			(xy 363.597346 -150.475557) (xy 363.543389 -150.489663) (xy 363.487952 -150.495763) (xy 363.432218 -150.493726)
			(xy 363.377375 -150.483596) (xy 363.324591 -150.465589) (xy 363.274991 -150.440088) (xy 363.229633 -150.407637)
			(xy 363.189484 -150.368928) (xy 363.155398 -150.324785) (xy 363.128102 -150.27615) (xy 363.108179 -150.224059)
			(xy 363.096053 -150.169622) (xy 363.091982 -150.114) (xy 361.6311 -150.114) (xy 361.635032 -150.14135)
			(xy 361.635032 -150.19585) (xy 361.627277 -150.249796) (xy 361.611923 -150.302089) (xy 361.589284 -150.351665)
			(xy 361.559821 -150.397514) (xy 361.524133 -150.438705) (xy 361.482946 -150.474397) (xy 361.4371 -150.503865)
			(xy 361.387526 -150.526509) (xy 361.335235 -150.541868) (xy 361.28129 -150.549629) (xy 361.25404 -150.550118)
			(xy 361.227725 -150.549685) (xy 361.175595 -150.542442) (xy 361.124952 -150.528116) (xy 361.076753 -150.506977)
			(xy 361.031911 -150.479425) (xy 360.991272 -150.445982) (xy 360.973116 -150.426928) (xy 360.965587 -150.419535)
			(xy 360.946313 -150.411005) (xy 360.935778 -150.410418) (xy 360.861102 -150.410418) (xy 360.85055 -150.410929)
			(xy 360.831255 -150.419477) (xy 360.823764 -150.426928) (xy 360.803944 -150.447716) (xy 360.759172 -150.483691)
			(xy 360.709514 -150.512551) (xy 360.656092 -150.533644) (xy 360.600113 -150.546493) (xy 360.54284 -150.550808)
			(xy 360.485567 -150.546493) (xy 360.429588 -150.533644) (xy 360.376166 -150.512551) (xy 360.326508 -150.483691)
			(xy 360.281736 -150.447716) (xy 360.261916 -150.426928) (xy 360.254387 -150.419535) (xy 360.235113 -150.411005)
			(xy 360.224578 -150.410418) (xy 360.149902 -150.410418) (xy 360.13935 -150.410929) (xy 360.120055 -150.419477)
			(xy 360.112564 -150.426928) (xy 360.094424 -150.445999) (xy 360.053791 -150.479454) (xy 360.008947 -150.50701)
			(xy 359.960743 -150.528146) (xy 359.910093 -150.54246) (xy 359.857957 -150.549681) (xy 359.83164 -150.550118)
			(xy 359.804386 -150.549637) (xy 359.750432 -150.541885) (xy 359.698131 -150.526533) (xy 359.648547 -150.503893)
			(xy 359.60269 -150.474427) (xy 359.561494 -150.438735) (xy 359.525797 -150.397542) (xy 359.496326 -150.351688)
			(xy 359.473681 -150.302107) (xy 359.458323 -150.249807) (xy 359.450565 -150.195854) (xy 351.696004 -150.195854)
			(xy 351.692316 -150.201429) (xy 351.655099 -150.242966) (xy 351.612231 -150.278641) (xy 351.564625 -150.307695)
			(xy 351.513296 -150.329507) (xy 351.459339 -150.343613) (xy 351.403902 -150.349713) (xy 351.348168 -150.347676)
			(xy 351.293325 -150.337546) (xy 351.240541 -150.319539) (xy 351.190941 -150.294038) (xy 351.145583 -150.261587)
			(xy 351.105434 -150.222878) (xy 351.071348 -150.178735) (xy 351.044052 -150.1301) (xy 351.024129 -150.078009)
			(xy 351.012003 -150.023572) (xy 351.007932 -149.96795) (xy 341.503355 -149.96795) (xy 341.503508 -149.976332)
			(xy 341.502999 -150.004218) (xy 341.494879 -150.059394) (xy 341.478811 -150.112801) (xy 341.455139 -150.163298)
			(xy 341.424366 -150.209811) (xy 341.387149 -150.251348) (xy 341.344281 -150.287023) (xy 341.296675 -150.316077)
			(xy 341.245346 -150.337889) (xy 341.191389 -150.351995) (xy 341.135952 -150.358095) (xy 341.080218 -150.356058)
			(xy 341.025375 -150.345928) (xy 340.972591 -150.327921) (xy 340.922991 -150.30242) (xy 340.877633 -150.269969)
			(xy 340.837484 -150.23126) (xy 340.803398 -150.187117) (xy 340.776102 -150.138482) (xy 340.756179 -150.086391)
			(xy 340.744053 -150.031954) (xy 340.739982 -149.976332) (xy 335.407313 -149.976332) (xy 335.407508 -149.987)
			(xy 335.406999 -150.014886) (xy 335.398879 -150.070062) (xy 335.382811 -150.123469) (xy 335.359139 -150.173966)
			(xy 335.328366 -150.220479) (xy 335.291149 -150.262016) (xy 335.248281 -150.297691) (xy 335.200675 -150.326745)
			(xy 335.149346 -150.348557) (xy 335.095389 -150.362663) (xy 335.039952 -150.368763) (xy 334.984218 -150.366726)
			(xy 334.929375 -150.356596) (xy 334.876591 -150.338589) (xy 334.826991 -150.313088) (xy 334.781633 -150.280637)
			(xy 334.741484 -150.241928) (xy 334.707398 -150.197785) (xy 334.680102 -150.14915) (xy 334.660179 -150.097059)
			(xy 334.648053 -150.042622) (xy 334.643982 -149.987) (xy 314.189872 -149.987) (xy 314.189872 -150.67915)
			(xy 314.189382 -150.709118) (xy 314.181559 -150.76854) (xy 314.166046 -150.826433) (xy 314.14311 -150.881806)
			(xy 314.113143 -150.933712) (xy 314.076656 -150.981262) (xy 314.054918 -151.003) (xy 336.675982 -151.003)
			(xy 336.680053 -150.947378) (xy 336.692179 -150.892941) (xy 336.712102 -150.84085) (xy 336.739398 -150.792215)
			(xy 336.773484 -150.748072) (xy 336.813633 -150.709363) (xy 336.858991 -150.676912) (xy 336.908591 -150.651411)
			(xy 336.961375 -150.633404) (xy 337.016218 -150.623274) (xy 337.071952 -150.621237) (xy 337.127389 -150.627337)
			(xy 337.181346 -150.641443) (xy 337.232675 -150.663255) (xy 337.280281 -150.692309) (xy 337.323149 -150.727984)
			(xy 337.360366 -150.769521) (xy 337.391139 -150.816034) (xy 337.414811 -150.866531) (xy 337.430879 -150.919938)
			(xy 337.438999 -150.975114) (xy 337.439508 -151.003) (xy 338.707982 -151.003) (xy 338.712053 -150.947378)
			(xy 338.724179 -150.892941) (xy 338.744102 -150.84085) (xy 338.771398 -150.792215) (xy 338.805484 -150.748072)
			(xy 338.845633 -150.709363) (xy 338.890991 -150.676912) (xy 338.940591 -150.651411) (xy 338.993375 -150.633404)
			(xy 339.048218 -150.623274) (xy 339.103952 -150.621237) (xy 339.159389 -150.627337) (xy 339.213346 -150.641443)
			(xy 339.264675 -150.663255) (xy 339.312281 -150.692309) (xy 339.355149 -150.727984) (xy 339.392366 -150.769521)
			(xy 339.423139 -150.816034) (xy 339.446811 -150.866531) (xy 339.462879 -150.919938) (xy 339.470999 -150.975114)
			(xy 339.471508 -151.003) (xy 339.470999 -151.030886) (xy 339.462879 -151.086062) (xy 339.446811 -151.139469)
			(xy 339.423139 -151.189966) (xy 339.392366 -151.236479) (xy 339.355149 -151.278016) (xy 339.312281 -151.313691)
			(xy 339.264675 -151.342745) (xy 339.213346 -151.364557) (xy 339.159389 -151.378663) (xy 339.103952 -151.384763)
			(xy 339.048218 -151.382726) (xy 338.993375 -151.372596) (xy 338.940591 -151.354589) (xy 338.890991 -151.329088)
			(xy 338.845633 -151.296637) (xy 338.805484 -151.257928) (xy 338.771398 -151.213785) (xy 338.744102 -151.16515)
			(xy 338.724179 -151.113059) (xy 338.712053 -151.058622) (xy 338.707982 -151.003) (xy 337.439508 -151.003)
			(xy 337.438999 -151.030886) (xy 337.430879 -151.086062) (xy 337.414811 -151.139469) (xy 337.391139 -151.189966)
			(xy 337.360366 -151.236479) (xy 337.323149 -151.278016) (xy 337.280281 -151.313691) (xy 337.232675 -151.342745)
			(xy 337.181346 -151.364557) (xy 337.127389 -151.378663) (xy 337.071952 -151.384763) (xy 337.016218 -151.382726)
			(xy 336.961375 -151.372596) (xy 336.908591 -151.354589) (xy 336.858991 -151.329088) (xy 336.813633 -151.296637)
			(xy 336.773484 -151.257928) (xy 336.739398 -151.213785) (xy 336.712102 -151.16515) (xy 336.692179 -151.113059)
			(xy 336.680053 -151.058622) (xy 336.675982 -151.003) (xy 314.054918 -151.003) (xy 314.034276 -151.023642)
			(xy 313.986726 -151.060129) (xy 313.93482 -151.090096) (xy 313.879447 -151.113032) (xy 313.821554 -151.128545)
			(xy 313.762132 -151.136368) (xy 313.702196 -151.136368) (xy 313.642774 -151.128545) (xy 313.584881 -151.113032)
			(xy 313.529508 -151.090096) (xy 313.477602 -151.060129) (xy 313.430052 -151.023642) (xy 313.387672 -150.981262)
			(xy 313.351185 -150.933712) (xy 313.321218 -150.881806) (xy 313.298282 -150.826433) (xy 313.282769 -150.76854)
			(xy 313.274946 -150.709118) (xy 313.274456 -150.67915) (xy 309.581804 -150.67915) (xy 309.581804 -152.485852)
			(xy 315.916564 -152.485852) (xy 315.916564 -151.622252) (xy 315.917054 -151.592284) (xy 315.924877 -151.532862)
			(xy 315.94039 -151.474969) (xy 315.963326 -151.419596) (xy 315.993293 -151.36769) (xy 316.02978 -151.32014)
			(xy 316.07216 -151.27776) (xy 316.11971 -151.241273) (xy 316.171616 -151.211306) (xy 316.226989 -151.18837)
			(xy 316.284882 -151.172857) (xy 316.344304 -151.165034) (xy 316.40424 -151.165034) (xy 316.463662 -151.172857)
			(xy 316.521555 -151.18837) (xy 316.576928 -151.211306) (xy 316.628834 -151.241273) (xy 316.676384 -151.27776)
			(xy 316.718764 -151.32014) (xy 316.755251 -151.36769) (xy 316.785218 -151.419596) (xy 316.808154 -151.474969)
			(xy 316.823667 -151.532862) (xy 316.83149 -151.592284) (xy 316.83198 -151.622252) (xy 316.83198 -152.007316)
			(xy 334.726024 -152.007316) (xy 334.730095 -151.951694) (xy 334.742221 -151.897257) (xy 334.762144 -151.845166)
			(xy 334.78944 -151.796531) (xy 334.823526 -151.752388) (xy 334.863675 -151.713679) (xy 334.909033 -151.681228)
			(xy 334.958633 -151.655727) (xy 335.011417 -151.63772) (xy 335.06626 -151.62759) (xy 335.121994 -151.625553)
			(xy 335.177431 -151.631653) (xy 335.231388 -151.645759) (xy 335.282717 -151.667571) (xy 335.288368 -151.67102)
			(xy 364.093758 -151.67102) (xy 364.097829 -151.615398) (xy 364.109955 -151.560961) (xy 364.129878 -151.50887)
			(xy 364.157174 -151.460235) (xy 364.19126 -151.416092) (xy 364.231409 -151.377383) (xy 364.276767 -151.344932)
			(xy 364.326367 -151.319431) (xy 364.379151 -151.301424) (xy 364.433994 -151.291294) (xy 364.489728 -151.289257)
			(xy 364.545165 -151.295357) (xy 364.599122 -151.309463) (xy 364.650451 -151.331275) (xy 364.698057 -151.360329)
			(xy 364.740925 -151.396004) (xy 364.778142 -151.437541) (xy 364.808915 -151.484054) (xy 364.832587 -151.534551)
			(xy 364.848655 -151.587958) (xy 364.856775 -151.643134) (xy 364.857284 -151.67102) (xy 364.856811 -151.696928)
			(xy 365.109758 -151.696928) (xy 365.113829 -151.641306) (xy 365.125955 -151.586869) (xy 365.145878 -151.534778)
			(xy 365.173174 -151.486143) (xy 365.20726 -151.442) (xy 365.247409 -151.403291) (xy 365.292767 -151.37084)
			(xy 365.342367 -151.345339) (xy 365.395151 -151.327332) (xy 365.449994 -151.317202) (xy 365.505728 -151.315165)
			(xy 365.561165 -151.321265) (xy 365.615122 -151.335371) (xy 365.666451 -151.357183) (xy 365.714057 -151.386237)
			(xy 365.738533 -151.406606) (xy 366.336832 -151.406606) (xy 366.340903 -151.350984) (xy 366.353029 -151.296547)
			(xy 366.372952 -151.244456) (xy 366.400248 -151.195821) (xy 366.434334 -151.151678) (xy 366.474483 -151.112969)
			(xy 366.519841 -151.080518) (xy 366.569441 -151.055017) (xy 366.622225 -151.03701) (xy 366.677068 -151.02688)
			(xy 366.732802 -151.024843) (xy 366.788239 -151.030943) (xy 366.842196 -151.045049) (xy 366.893525 -151.066861)
			(xy 366.941131 -151.095915) (xy 366.983999 -151.13159) (xy 367.021216 -151.173127) (xy 367.051989 -151.21964)
			(xy 367.075661 -151.270137) (xy 367.091729 -151.323544) (xy 367.099849 -151.37872) (xy 367.100358 -151.406606)
			(xy 367.099849 -151.434492) (xy 367.091729 -151.489668) (xy 367.075661 -151.543075) (xy 367.057119 -151.582628)
			(xy 367.662458 -151.582628) (xy 367.666529 -151.527006) (xy 367.678655 -151.472569) (xy 367.698578 -151.420478)
			(xy 367.725874 -151.371843) (xy 367.75996 -151.3277) (xy 367.800109 -151.288991) (xy 367.845467 -151.25654)
			(xy 367.895067 -151.231039) (xy 367.947851 -151.213032) (xy 368.002694 -151.202902) (xy 368.058428 -151.200865)
			(xy 368.113865 -151.206965) (xy 368.167822 -151.221071) (xy 368.219151 -151.242883) (xy 368.266757 -151.271937)
			(xy 368.309625 -151.307612) (xy 368.346842 -151.349149) (xy 368.377615 -151.395662) (xy 368.401287 -151.446159)
			(xy 368.417355 -151.499566) (xy 368.425475 -151.554742) (xy 368.425738 -151.569166) (xy 369.173758 -151.569166)
			(xy 369.177829 -151.513544) (xy 369.189955 -151.459107) (xy 369.209878 -151.407016) (xy 369.237174 -151.358381)
			(xy 369.27126 -151.314238) (xy 369.311409 -151.275529) (xy 369.356767 -151.243078) (xy 369.406367 -151.217577)
			(xy 369.459151 -151.19957) (xy 369.513994 -151.18944) (xy 369.569728 -151.187403) (xy 369.625165 -151.193503)
			(xy 369.679122 -151.207609) (xy 369.730451 -151.229421) (xy 369.778057 -151.258475) (xy 369.820925 -151.29415)
			(xy 369.858142 -151.335687) (xy 369.888915 -151.3822) (xy 369.912587 -151.432697) (xy 369.928655 -151.486104)
			(xy 369.936775 -151.54128) (xy 369.937284 -151.569166) (xy 369.936775 -151.597052) (xy 369.928655 -151.652228)
			(xy 369.912587 -151.705635) (xy 369.888915 -151.756132) (xy 369.858142 -151.802645) (xy 369.820925 -151.844182)
			(xy 369.778057 -151.879857) (xy 369.730451 -151.908911) (xy 369.679122 -151.930723) (xy 369.625165 -151.944829)
			(xy 369.569728 -151.950929) (xy 369.513994 -151.948892) (xy 369.459151 -151.938762) (xy 369.406367 -151.920755)
			(xy 369.356767 -151.895254) (xy 369.311409 -151.862803) (xy 369.27126 -151.824094) (xy 369.237174 -151.779951)
			(xy 369.209878 -151.731316) (xy 369.189955 -151.679225) (xy 369.177829 -151.624788) (xy 369.173758 -151.569166)
			(xy 368.425738 -151.569166) (xy 368.425984 -151.582628) (xy 368.425475 -151.610514) (xy 368.417355 -151.66569)
			(xy 368.401287 -151.719097) (xy 368.377615 -151.769594) (xy 368.346842 -151.816107) (xy 368.309625 -151.857644)
			(xy 368.266757 -151.893319) (xy 368.219151 -151.922373) (xy 368.167822 -151.944185) (xy 368.113865 -151.958291)
			(xy 368.058428 -151.964391) (xy 368.002694 -151.962354) (xy 367.947851 -151.952224) (xy 367.895067 -151.934217)
			(xy 367.845467 -151.908716) (xy 367.800109 -151.876265) (xy 367.75996 -151.837556) (xy 367.725874 -151.793413)
			(xy 367.698578 -151.744778) (xy 367.678655 -151.692687) (xy 367.666529 -151.63825) (xy 367.662458 -151.582628)
			(xy 367.057119 -151.582628) (xy 367.051989 -151.593572) (xy 367.021216 -151.640085) (xy 366.983999 -151.681622)
			(xy 366.941131 -151.717297) (xy 366.893525 -151.746351) (xy 366.842196 -151.768163) (xy 366.788239 -151.782269)
			(xy 366.732802 -151.788369) (xy 366.677068 -151.786332) (xy 366.622225 -151.776202) (xy 366.569441 -151.758195)
			(xy 366.519841 -151.732694) (xy 366.474483 -151.700243) (xy 366.434334 -151.661534) (xy 366.400248 -151.617391)
			(xy 366.372952 -151.568756) (xy 366.353029 -151.516665) (xy 366.340903 -151.462228) (xy 366.336832 -151.406606)
			(xy 365.738533 -151.406606) (xy 365.756925 -151.421912) (xy 365.794142 -151.463449) (xy 365.824915 -151.509962)
			(xy 365.848587 -151.560459) (xy 365.864655 -151.613866) (xy 365.872775 -151.669042) (xy 365.873284 -151.696928)
			(xy 365.872775 -151.724814) (xy 365.864655 -151.77999) (xy 365.848587 -151.833397) (xy 365.824915 -151.883894)
			(xy 365.794142 -151.930407) (xy 365.756925 -151.971944) (xy 365.714057 -152.007619) (xy 365.666451 -152.036673)
			(xy 365.615122 -152.058485) (xy 365.561165 -152.072591) (xy 365.505728 -152.078691) (xy 365.449994 -152.076654)
			(xy 365.395151 -152.066524) (xy 365.342367 -152.048517) (xy 365.292767 -152.023016) (xy 365.247409 -151.990565)
			(xy 365.20726 -151.951856) (xy 365.173174 -151.907713) (xy 365.145878 -151.859078) (xy 365.125955 -151.806987)
			(xy 365.113829 -151.75255) (xy 365.109758 -151.696928) (xy 364.856811 -151.696928) (xy 364.856775 -151.698906)
			(xy 364.848655 -151.754082) (xy 364.832587 -151.807489) (xy 364.808915 -151.857986) (xy 364.778142 -151.904499)
			(xy 364.740925 -151.946036) (xy 364.698057 -151.981711) (xy 364.650451 -152.010765) (xy 364.599122 -152.032577)
			(xy 364.545165 -152.046683) (xy 364.489728 -152.052783) (xy 364.433994 -152.050746) (xy 364.379151 -152.040616)
			(xy 364.326367 -152.022609) (xy 364.276767 -151.997108) (xy 364.231409 -151.964657) (xy 364.19126 -151.925948)
			(xy 364.157174 -151.881805) (xy 364.129878 -151.83317) (xy 364.109955 -151.781079) (xy 364.097829 -151.726642)
			(xy 364.093758 -151.67102) (xy 335.288368 -151.67102) (xy 335.330323 -151.696625) (xy 335.373191 -151.7323)
			(xy 335.410408 -151.773837) (xy 335.441181 -151.82035) (xy 335.464853 -151.870847) (xy 335.480921 -151.924254)
			(xy 335.489041 -151.97943) (xy 335.48955 -152.007316) (xy 335.489041 -152.035202) (xy 335.480921 -152.090378)
			(xy 335.464853 -152.143785) (xy 335.441181 -152.194282) (xy 335.410408 -152.240795) (xy 335.373191 -152.282332)
			(xy 335.330323 -152.318007) (xy 335.282717 -152.347061) (xy 335.231388 -152.368873) (xy 335.177431 -152.382979)
			(xy 335.121994 -152.389079) (xy 335.06626 -152.387042) (xy 335.011417 -152.376912) (xy 334.958633 -152.358905)
			(xy 334.909033 -152.333404) (xy 334.863675 -152.300953) (xy 334.823526 -152.262244) (xy 334.78944 -152.218101)
			(xy 334.762144 -152.169466) (xy 334.742221 -152.117375) (xy 334.730095 -152.062938) (xy 334.726024 -152.007316)
			(xy 316.83198 -152.007316) (xy 316.83198 -152.485852) (xy 316.83149 -152.51582) (xy 316.823667 -152.575242)
			(xy 316.808154 -152.633135) (xy 316.785218 -152.688508) (xy 316.775665 -152.705054) (xy 341.103964 -152.705054)
			(xy 341.108035 -152.649432) (xy 341.120161 -152.594995) (xy 341.140084 -152.542904) (xy 341.16738 -152.494269)
			(xy 341.201466 -152.450126) (xy 341.241615 -152.411417) (xy 341.286973 -152.378966) (xy 341.336573 -152.353465)
			(xy 341.389357 -152.335458) (xy 341.4442 -152.325328) (xy 341.499934 -152.323291) (xy 341.555371 -152.329391)
			(xy 341.609328 -152.343497) (xy 341.660657 -152.365309) (xy 341.708263 -152.394363) (xy 341.751131 -152.430038)
			(xy 341.788348 -152.471575) (xy 341.819121 -152.518088) (xy 341.842793 -152.568585) (xy 341.858861 -152.621992)
			(xy 341.866981 -152.677168) (xy 341.86749 -152.705054) (xy 341.866981 -152.73294) (xy 341.858861 -152.788116)
			(xy 341.842793 -152.841523) (xy 341.819121 -152.89202) (xy 341.788348 -152.938533) (xy 341.751131 -152.98007)
			(xy 341.708263 -153.015745) (xy 341.660657 -153.044799) (xy 341.609328 -153.066611) (xy 341.555371 -153.080717)
			(xy 341.499934 -153.086817) (xy 341.4442 -153.08478) (xy 341.389357 -153.07465) (xy 341.336573 -153.056643)
			(xy 341.286973 -153.031142) (xy 341.241615 -152.998691) (xy 341.201466 -152.959982) (xy 341.16738 -152.915839)
			(xy 341.140084 -152.867204) (xy 341.120161 -152.815113) (xy 341.108035 -152.760676) (xy 341.103964 -152.705054)
			(xy 316.775665 -152.705054) (xy 316.755251 -152.740414) (xy 316.718764 -152.787964) (xy 316.676384 -152.830344)
			(xy 316.628834 -152.866831) (xy 316.576928 -152.896798) (xy 316.521555 -152.919734) (xy 316.463662 -152.935247)
			(xy 316.40424 -152.94307) (xy 316.344304 -152.94307) (xy 316.284882 -152.935247) (xy 316.226989 -152.919734)
			(xy 316.171616 -152.896798) (xy 316.11971 -152.866831) (xy 316.07216 -152.830344) (xy 316.02978 -152.787964)
			(xy 315.993293 -152.740414) (xy 315.963326 -152.688508) (xy 315.94039 -152.633135) (xy 315.924877 -152.575242)
			(xy 315.917054 -152.51582) (xy 315.916564 -152.485852) (xy 309.581804 -152.485852) (xy 309.581804 -154.279346)
			(xy 313.274456 -154.279346) (xy 313.274456 -153.415746) (xy 313.274946 -153.385778) (xy 313.282769 -153.326356)
			(xy 313.298282 -153.268463) (xy 313.321218 -153.21309) (xy 313.351185 -153.161184) (xy 313.387672 -153.113634)
			(xy 313.430052 -153.071254) (xy 313.477602 -153.034767) (xy 313.529508 -153.0048) (xy 313.584881 -152.981864)
			(xy 313.642774 -152.966351) (xy 313.702196 -152.958528) (xy 313.762132 -152.958528) (xy 313.821554 -152.966351)
			(xy 313.879447 -152.981864) (xy 313.93482 -153.0048) (xy 313.986726 -153.034767) (xy 314.034276 -153.071254)
			(xy 314.076656 -153.113634) (xy 314.113143 -153.161184) (xy 314.14311 -153.21309) (xy 314.166046 -153.268463)
			(xy 314.181559 -153.326356) (xy 314.189382 -153.385778) (xy 314.189872 -153.415746) (xy 314.189872 -153.67)
			(xy 334.643982 -153.67) (xy 334.648053 -153.614378) (xy 334.660179 -153.559941) (xy 334.680102 -153.50785)
			(xy 334.707398 -153.459215) (xy 334.741484 -153.415072) (xy 334.781633 -153.376363) (xy 334.826991 -153.343912)
			(xy 334.876591 -153.318411) (xy 334.929375 -153.300404) (xy 334.984218 -153.290274) (xy 335.039952 -153.288237)
			(xy 335.095389 -153.294337) (xy 335.149346 -153.308443) (xy 335.200675 -153.330255) (xy 335.248281 -153.359309)
			(xy 335.291149 -153.394984) (xy 335.328366 -153.436521) (xy 335.359139 -153.483034) (xy 335.382811 -153.533531)
			(xy 335.398879 -153.586938) (xy 335.406999 -153.642114) (xy 335.407508 -153.67) (xy 336.675982 -153.67)
			(xy 336.680053 -153.614378) (xy 336.692179 -153.559941) (xy 336.712102 -153.50785) (xy 336.739398 -153.459215)
			(xy 336.773484 -153.415072) (xy 336.813633 -153.376363) (xy 336.858991 -153.343912) (xy 336.908591 -153.318411)
			(xy 336.961375 -153.300404) (xy 337.016218 -153.290274) (xy 337.071952 -153.288237) (xy 337.127389 -153.294337)
			(xy 337.181346 -153.308443) (xy 337.232675 -153.330255) (xy 337.280281 -153.359309) (xy 337.323149 -153.394984)
			(xy 337.360366 -153.436521) (xy 337.391139 -153.483034) (xy 337.414811 -153.533531) (xy 337.430879 -153.586938)
			(xy 337.438999 -153.642114) (xy 337.439508 -153.67) (xy 337.438999 -153.697886) (xy 337.432076 -153.74493)
			(xy 349.735392 -153.74493) (xy 349.739463 -153.689308) (xy 349.751589 -153.634871) (xy 349.771512 -153.58278)
			(xy 349.798808 -153.534145) (xy 349.832894 -153.490002) (xy 349.873043 -153.451293) (xy 349.918401 -153.418842)
			(xy 349.968001 -153.393341) (xy 350.020785 -153.375334) (xy 350.075628 -153.365204) (xy 350.131362 -153.363167)
			(xy 350.186799 -153.369267) (xy 350.240756 -153.383373) (xy 350.292085 -153.405185) (xy 350.339691 -153.434239)
			(xy 350.382559 -153.469914) (xy 350.419776 -153.511451) (xy 350.450549 -153.557964) (xy 350.474221 -153.608461)
			(xy 350.490289 -153.661868) (xy 350.498409 -153.717044) (xy 350.498918 -153.74493) (xy 350.498409 -153.772816)
			(xy 350.496981 -153.782522) (xy 363.077758 -153.782522) (xy 363.081829 -153.7269) (xy 363.093955 -153.672463)
			(xy 363.113878 -153.620372) (xy 363.141174 -153.571737) (xy 363.17526 -153.527594) (xy 363.215409 -153.488885)
			(xy 363.260767 -153.456434) (xy 363.310367 -153.430933) (xy 363.363151 -153.412926) (xy 363.417994 -153.402796)
			(xy 363.473728 -153.400759) (xy 363.529165 -153.406859) (xy 363.583122 -153.420965) (xy 363.634451 -153.442777)
			(xy 363.682057 -153.471831) (xy 363.724925 -153.507506) (xy 363.762142 -153.549043) (xy 363.792915 -153.595556)
			(xy 363.816587 -153.646053) (xy 363.832655 -153.69946) (xy 363.840775 -153.754636) (xy 363.841284 -153.782522)
			(xy 364.093758 -153.782522) (xy 364.097829 -153.7269) (xy 364.109955 -153.672463) (xy 364.129878 -153.620372)
			(xy 364.157174 -153.571737) (xy 364.19126 -153.527594) (xy 364.231409 -153.488885) (xy 364.276767 -153.456434)
			(xy 364.326367 -153.430933) (xy 364.379151 -153.412926) (xy 364.433994 -153.402796) (xy 364.489728 -153.400759)
			(xy 364.545165 -153.406859) (xy 364.599122 -153.420965) (xy 364.650451 -153.442777) (xy 364.698057 -153.471831)
			(xy 364.740925 -153.507506) (xy 364.778142 -153.549043) (xy 364.808915 -153.595556) (xy 364.832587 -153.646053)
			(xy 364.848655 -153.69946) (xy 364.856775 -153.754636) (xy 364.857284 -153.782522) (xy 364.856775 -153.810408)
			(xy 364.853627 -153.831798) (xy 365.109758 -153.831798) (xy 365.113829 -153.776176) (xy 365.125955 -153.721739)
			(xy 365.145878 -153.669648) (xy 365.173174 -153.621013) (xy 365.20726 -153.57687) (xy 365.247409 -153.538161)
			(xy 365.292767 -153.50571) (xy 365.342367 -153.480209) (xy 365.395151 -153.462202) (xy 365.449994 -153.452072)
			(xy 365.505728 -153.450035) (xy 365.561165 -153.456135) (xy 365.615122 -153.470241) (xy 365.666451 -153.492053)
			(xy 365.714057 -153.521107) (xy 365.756925 -153.556782) (xy 365.794142 -153.598319) (xy 365.824915 -153.644832)
			(xy 365.848587 -153.695329) (xy 365.864655 -153.748736) (xy 365.869627 -153.782522) (xy 368.157758 -153.782522)
			(xy 368.161829 -153.7269) (xy 368.173955 -153.672463) (xy 368.193878 -153.620372) (xy 368.221174 -153.571737)
			(xy 368.25526 -153.527594) (xy 368.295409 -153.488885) (xy 368.340767 -153.456434) (xy 368.390367 -153.430933)
			(xy 368.443151 -153.412926) (xy 368.497994 -153.402796) (xy 368.553728 -153.400759) (xy 368.609165 -153.406859)
			(xy 368.663122 -153.420965) (xy 368.714451 -153.442777) (xy 368.762057 -153.471831) (xy 368.804925 -153.507506)
			(xy 368.842142 -153.549043) (xy 368.872915 -153.595556) (xy 368.896587 -153.646053) (xy 368.912655 -153.69946)
			(xy 368.920775 -153.754636) (xy 368.921284 -153.782522) (xy 370.189758 -153.782522) (xy 370.193829 -153.7269)
			(xy 370.205955 -153.672463) (xy 370.225878 -153.620372) (xy 370.253174 -153.571737) (xy 370.28726 -153.527594)
			(xy 370.327409 -153.488885) (xy 370.372767 -153.456434) (xy 370.422367 -153.430933) (xy 370.475151 -153.412926)
			(xy 370.529994 -153.402796) (xy 370.585728 -153.400759) (xy 370.641165 -153.406859) (xy 370.695122 -153.420965)
			(xy 370.746451 -153.442777) (xy 370.794057 -153.471831) (xy 370.836925 -153.507506) (xy 370.874142 -153.549043)
			(xy 370.904915 -153.595556) (xy 370.928587 -153.646053) (xy 370.944655 -153.69946) (xy 370.952775 -153.754636)
			(xy 370.953284 -153.782522) (xy 370.952775 -153.810408) (xy 370.944655 -153.865584) (xy 370.928587 -153.918991)
			(xy 370.904915 -153.969488) (xy 370.874142 -154.016001) (xy 370.836925 -154.057538) (xy 370.794057 -154.093213)
			(xy 370.746451 -154.122267) (xy 370.695122 -154.144079) (xy 370.641165 -154.158185) (xy 370.585728 -154.164285)
			(xy 370.529994 -154.162248) (xy 370.475151 -154.152118) (xy 370.422367 -154.134111) (xy 370.372767 -154.10861)
			(xy 370.327409 -154.076159) (xy 370.28726 -154.03745) (xy 370.253174 -153.993307) (xy 370.225878 -153.944672)
			(xy 370.205955 -153.892581) (xy 370.193829 -153.838144) (xy 370.189758 -153.782522) (xy 368.921284 -153.782522)
			(xy 368.920775 -153.810408) (xy 368.912655 -153.865584) (xy 368.896587 -153.918991) (xy 368.872915 -153.969488)
			(xy 368.842142 -154.016001) (xy 368.804925 -154.057538) (xy 368.762057 -154.093213) (xy 368.714451 -154.122267)
			(xy 368.663122 -154.144079) (xy 368.609165 -154.158185) (xy 368.553728 -154.164285) (xy 368.497994 -154.162248)
			(xy 368.443151 -154.152118) (xy 368.390367 -154.134111) (xy 368.340767 -154.10861) (xy 368.295409 -154.076159)
			(xy 368.25526 -154.03745) (xy 368.221174 -153.993307) (xy 368.193878 -153.944672) (xy 368.173955 -153.892581)
			(xy 368.161829 -153.838144) (xy 368.157758 -153.782522) (xy 365.869627 -153.782522) (xy 365.872775 -153.803912)
			(xy 365.873284 -153.831798) (xy 365.872775 -153.859684) (xy 365.864655 -153.91486) (xy 365.848587 -153.968267)
			(xy 365.824915 -154.018764) (xy 365.794142 -154.065277) (xy 365.756925 -154.106814) (xy 365.714057 -154.142489)
			(xy 365.666451 -154.171543) (xy 365.615122 -154.193355) (xy 365.561165 -154.207461) (xy 365.505728 -154.213561)
			(xy 365.449994 -154.211524) (xy 365.395151 -154.201394) (xy 365.342367 -154.183387) (xy 365.292767 -154.157886)
			(xy 365.247409 -154.125435) (xy 365.20726 -154.086726) (xy 365.173174 -154.042583) (xy 365.145878 -153.993948)
			(xy 365.125955 -153.941857) (xy 365.113829 -153.88742) (xy 365.109758 -153.831798) (xy 364.853627 -153.831798)
			(xy 364.848655 -153.865584) (xy 364.832587 -153.918991) (xy 364.808915 -153.969488) (xy 364.778142 -154.016001)
			(xy 364.740925 -154.057538) (xy 364.698057 -154.093213) (xy 364.650451 -154.122267) (xy 364.599122 -154.144079)
			(xy 364.545165 -154.158185) (xy 364.489728 -154.164285) (xy 364.433994 -154.162248) (xy 364.379151 -154.152118)
			(xy 364.326367 -154.134111) (xy 364.276767 -154.10861) (xy 364.231409 -154.076159) (xy 364.19126 -154.03745)
			(xy 364.157174 -153.993307) (xy 364.129878 -153.944672) (xy 364.109955 -153.892581) (xy 364.097829 -153.838144)
			(xy 364.093758 -153.782522) (xy 363.841284 -153.782522) (xy 363.840775 -153.810408) (xy 363.832655 -153.865584)
			(xy 363.816587 -153.918991) (xy 363.792915 -153.969488) (xy 363.762142 -154.016001) (xy 363.724925 -154.057538)
			(xy 363.682057 -154.093213) (xy 363.634451 -154.122267) (xy 363.583122 -154.144079) (xy 363.529165 -154.158185)
			(xy 363.473728 -154.164285) (xy 363.417994 -154.162248) (xy 363.363151 -154.152118) (xy 363.310367 -154.134111)
			(xy 363.260767 -154.10861) (xy 363.215409 -154.076159) (xy 363.17526 -154.03745) (xy 363.141174 -153.993307)
			(xy 363.113878 -153.944672) (xy 363.093955 -153.892581) (xy 363.081829 -153.838144) (xy 363.077758 -153.782522)
			(xy 350.496981 -153.782522) (xy 350.490289 -153.827992) (xy 350.474221 -153.881399) (xy 350.450549 -153.931896)
			(xy 350.419776 -153.978409) (xy 350.382559 -154.019946) (xy 350.339691 -154.055621) (xy 350.292085 -154.084675)
			(xy 350.240756 -154.106487) (xy 350.186799 -154.120593) (xy 350.131362 -154.126693) (xy 350.075628 -154.124656)
			(xy 350.020785 -154.114526) (xy 349.968001 -154.096519) (xy 349.918401 -154.071018) (xy 349.873043 -154.038567)
			(xy 349.832894 -153.999858) (xy 349.798808 -153.955715) (xy 349.771512 -153.90708) (xy 349.751589 -153.854989)
			(xy 349.739463 -153.800552) (xy 349.735392 -153.74493) (xy 337.432076 -153.74493) (xy 337.430879 -153.753062)
			(xy 337.414811 -153.806469) (xy 337.391139 -153.856966) (xy 337.360366 -153.903479) (xy 337.323149 -153.945016)
			(xy 337.280281 -153.980691) (xy 337.232675 -154.009745) (xy 337.181346 -154.031557) (xy 337.127389 -154.045663)
			(xy 337.071952 -154.051763) (xy 337.016218 -154.049726) (xy 336.961375 -154.039596) (xy 336.908591 -154.021589)
			(xy 336.858991 -153.996088) (xy 336.813633 -153.963637) (xy 336.773484 -153.924928) (xy 336.739398 -153.880785)
			(xy 336.712102 -153.83215) (xy 336.692179 -153.780059) (xy 336.680053 -153.725622) (xy 336.675982 -153.67)
			(xy 335.407508 -153.67) (xy 335.406999 -153.697886) (xy 335.398879 -153.753062) (xy 335.382811 -153.806469)
			(xy 335.359139 -153.856966) (xy 335.328366 -153.903479) (xy 335.291149 -153.945016) (xy 335.248281 -153.980691)
			(xy 335.200675 -154.009745) (xy 335.149346 -154.031557) (xy 335.095389 -154.045663) (xy 335.039952 -154.051763)
			(xy 334.984218 -154.049726) (xy 334.929375 -154.039596) (xy 334.876591 -154.021589) (xy 334.826991 -153.996088)
			(xy 334.781633 -153.963637) (xy 334.741484 -153.924928) (xy 334.707398 -153.880785) (xy 334.680102 -153.83215)
			(xy 334.660179 -153.780059) (xy 334.648053 -153.725622) (xy 334.643982 -153.67) (xy 314.189872 -153.67)
			(xy 314.189872 -154.156156) (xy 341.026748 -154.156156) (xy 341.030819 -154.100534) (xy 341.042945 -154.046097)
			(xy 341.062868 -153.994006) (xy 341.090164 -153.945371) (xy 341.12425 -153.901228) (xy 341.164399 -153.862519)
			(xy 341.209757 -153.830068) (xy 341.259357 -153.804567) (xy 341.312141 -153.78656) (xy 341.366984 -153.77643)
			(xy 341.422718 -153.774393) (xy 341.478155 -153.780493) (xy 341.532112 -153.794599) (xy 341.583441 -153.816411)
			(xy 341.631047 -153.845465) (xy 341.673915 -153.88114) (xy 341.711132 -153.922677) (xy 341.741905 -153.96919)
			(xy 341.765577 -154.019687) (xy 341.781645 -154.073094) (xy 341.789765 -154.12827) (xy 341.790274 -154.156156)
			(xy 341.789765 -154.184042) (xy 341.781645 -154.239218) (xy 341.765577 -154.292625) (xy 341.759776 -154.305)
			(xy 352.866196 -154.305) (xy 352.870267 -154.249378) (xy 352.882393 -154.194941) (xy 352.902316 -154.14285)
			(xy 352.929612 -154.094215) (xy 352.963698 -154.050072) (xy 353.003847 -154.011363) (xy 353.049205 -153.978912)
			(xy 353.098805 -153.953411) (xy 353.151589 -153.935404) (xy 353.206432 -153.925274) (xy 353.262166 -153.923237)
			(xy 353.317603 -153.929337) (xy 353.37156 -153.943443) (xy 353.422889 -153.965255) (xy 353.470495 -153.994309)
			(xy 353.513363 -154.029984) (xy 353.55058 -154.071521) (xy 353.581353 -154.118034) (xy 353.605025 -154.168531)
			(xy 353.621093 -154.221938) (xy 353.629213 -154.277114) (xy 353.629722 -154.305) (xy 353.629213 -154.332886)
			(xy 353.621093 -154.388062) (xy 353.605025 -154.441469) (xy 353.581353 -154.491966) (xy 353.55058 -154.538479)
			(xy 353.513363 -154.580016) (xy 353.470495 -154.615691) (xy 353.422889 -154.644745) (xy 353.37156 -154.666557)
			(xy 353.317603 -154.680663) (xy 353.262166 -154.686763) (xy 353.206432 -154.684726) (xy 353.151589 -154.674596)
			(xy 353.098805 -154.656589) (xy 353.049205 -154.631088) (xy 353.003847 -154.598637) (xy 352.963698 -154.559928)
			(xy 352.929612 -154.515785) (xy 352.902316 -154.46715) (xy 352.882393 -154.415059) (xy 352.870267 -154.360622)
			(xy 352.866196 -154.305) (xy 341.759776 -154.305) (xy 341.741905 -154.343122) (xy 341.711132 -154.389635)
			(xy 341.673915 -154.431172) (xy 341.631047 -154.466847) (xy 341.583441 -154.495901) (xy 341.532112 -154.517713)
			(xy 341.478155 -154.531819) (xy 341.422718 -154.537919) (xy 341.366984 -154.535882) (xy 341.312141 -154.525752)
			(xy 341.259357 -154.507745) (xy 341.209757 -154.482244) (xy 341.164399 -154.449793) (xy 341.12425 -154.411084)
			(xy 341.090164 -154.366941) (xy 341.062868 -154.318306) (xy 341.042945 -154.266215) (xy 341.030819 -154.211778)
			(xy 341.026748 -154.156156) (xy 314.189872 -154.156156) (xy 314.189872 -154.279346) (xy 314.189382 -154.309314)
			(xy 314.181559 -154.368736) (xy 314.166046 -154.426629) (xy 314.14311 -154.482002) (xy 314.113143 -154.533908)
			(xy 314.076656 -154.581458) (xy 314.034276 -154.623838) (xy 313.986726 -154.660325) (xy 313.942254 -154.686)
			(xy 334.643982 -154.686) (xy 334.648053 -154.630378) (xy 334.660179 -154.575941) (xy 334.680102 -154.52385)
			(xy 334.707398 -154.475215) (xy 334.741484 -154.431072) (xy 334.781633 -154.392363) (xy 334.826991 -154.359912)
			(xy 334.876591 -154.334411) (xy 334.929375 -154.316404) (xy 334.984218 -154.306274) (xy 335.039952 -154.304237)
			(xy 335.095389 -154.310337) (xy 335.149346 -154.324443) (xy 335.200675 -154.346255) (xy 335.248281 -154.375309)
			(xy 335.291149 -154.410984) (xy 335.328366 -154.452521) (xy 335.359139 -154.499034) (xy 335.382811 -154.549531)
			(xy 335.398879 -154.602938) (xy 335.406999 -154.658114) (xy 335.407508 -154.686) (xy 336.675982 -154.686)
			(xy 336.680053 -154.630378) (xy 336.692179 -154.575941) (xy 336.712102 -154.52385) (xy 336.739398 -154.475215)
			(xy 336.773484 -154.431072) (xy 336.813633 -154.392363) (xy 336.858991 -154.359912) (xy 336.908591 -154.334411)
			(xy 336.961375 -154.316404) (xy 337.016218 -154.306274) (xy 337.071952 -154.304237) (xy 337.127389 -154.310337)
			(xy 337.181346 -154.324443) (xy 337.232675 -154.346255) (xy 337.280281 -154.375309) (xy 337.323149 -154.410984)
			(xy 337.360366 -154.452521) (xy 337.391139 -154.499034) (xy 337.414811 -154.549531) (xy 337.430879 -154.602938)
			(xy 337.438999 -154.658114) (xy 337.439508 -154.686) (xy 339.469982 -154.686) (xy 339.474053 -154.630378)
			(xy 339.486179 -154.575941) (xy 339.506102 -154.52385) (xy 339.533398 -154.475215) (xy 339.567484 -154.431072)
			(xy 339.607633 -154.392363) (xy 339.652991 -154.359912) (xy 339.702591 -154.334411) (xy 339.755375 -154.316404)
			(xy 339.810218 -154.306274) (xy 339.865952 -154.304237) (xy 339.921389 -154.310337) (xy 339.975346 -154.324443)
			(xy 340.026675 -154.346255) (xy 340.074281 -154.375309) (xy 340.117149 -154.410984) (xy 340.154366 -154.452521)
			(xy 340.185139 -154.499034) (xy 340.208811 -154.549531) (xy 340.224879 -154.602938) (xy 340.232999 -154.658114)
			(xy 340.233508 -154.686) (xy 340.232999 -154.713886) (xy 340.224879 -154.769062) (xy 340.208811 -154.822469)
			(xy 340.185139 -154.872966) (xy 340.154366 -154.919479) (xy 340.117149 -154.961016) (xy 340.074281 -154.996691)
			(xy 340.026675 -155.025745) (xy 339.975346 -155.047557) (xy 339.921389 -155.061663) (xy 339.865952 -155.067763)
			(xy 339.810218 -155.065726) (xy 339.755375 -155.055596) (xy 339.702591 -155.037589) (xy 339.652991 -155.012088)
			(xy 339.607633 -154.979637) (xy 339.567484 -154.940928) (xy 339.533398 -154.896785) (xy 339.506102 -154.84815)
			(xy 339.486179 -154.796059) (xy 339.474053 -154.741622) (xy 339.469982 -154.686) (xy 337.439508 -154.686)
			(xy 337.438999 -154.713886) (xy 337.430879 -154.769062) (xy 337.414811 -154.822469) (xy 337.391139 -154.872966)
			(xy 337.360366 -154.919479) (xy 337.323149 -154.961016) (xy 337.280281 -154.996691) (xy 337.232675 -155.025745)
			(xy 337.181346 -155.047557) (xy 337.127389 -155.061663) (xy 337.071952 -155.067763) (xy 337.016218 -155.065726)
			(xy 336.961375 -155.055596) (xy 336.908591 -155.037589) (xy 336.858991 -155.012088) (xy 336.813633 -154.979637)
			(xy 336.773484 -154.940928) (xy 336.739398 -154.896785) (xy 336.712102 -154.84815) (xy 336.692179 -154.796059)
			(xy 336.680053 -154.741622) (xy 336.675982 -154.686) (xy 335.407508 -154.686) (xy 335.406999 -154.713886)
			(xy 335.398879 -154.769062) (xy 335.382811 -154.822469) (xy 335.359139 -154.872966) (xy 335.328366 -154.919479)
			(xy 335.291149 -154.961016) (xy 335.248281 -154.996691) (xy 335.200675 -155.025745) (xy 335.149346 -155.047557)
			(xy 335.095389 -155.061663) (xy 335.039952 -155.067763) (xy 334.984218 -155.065726) (xy 334.929375 -155.055596)
			(xy 334.876591 -155.037589) (xy 334.826991 -155.012088) (xy 334.781633 -154.979637) (xy 334.741484 -154.940928)
			(xy 334.707398 -154.896785) (xy 334.680102 -154.84815) (xy 334.660179 -154.796059) (xy 334.648053 -154.741622)
			(xy 334.643982 -154.686) (xy 313.942254 -154.686) (xy 313.93482 -154.690292) (xy 313.879447 -154.713228)
			(xy 313.821554 -154.728741) (xy 313.762132 -154.736564) (xy 313.702196 -154.736564) (xy 313.642774 -154.728741)
			(xy 313.584881 -154.713228) (xy 313.529508 -154.690292) (xy 313.477602 -154.660325) (xy 313.430052 -154.623838)
			(xy 313.387672 -154.581458) (xy 313.351185 -154.533908) (xy 313.321218 -154.482002) (xy 313.298282 -154.426629)
			(xy 313.282769 -154.368736) (xy 313.274946 -154.309314) (xy 313.274456 -154.279346) (xy 309.581804 -154.279346)
			(xy 309.581804 -155.62707) (xy 309.581245 -155.662924) (xy 309.57251 -155.734099) (xy 309.555237 -155.803697)
			(xy 309.542942 -155.837382) (xy 309.542942 -155.837636) (xy 309.540226 -155.845687) (xy 309.539714 -155.86266)
			(xy 309.544765 -155.878873) (xy 309.549546 -155.885896) (xy 309.576216 -155.921964) (xy 309.582636 -155.929509)
			(xy 309.599754 -155.939443) (xy 309.60949 -155.941268) (xy 309.616602 -155.941776) (xy 315.570108 -155.941776)
			(xy 315.580268 -155.937204) (xy 315.605194 -155.926204) (xy 315.657388 -155.910586) (xy 315.711273 -155.902546)
			(xy 315.73851 -155.901898) (xy 315.74105 -155.901898) (xy 315.755071 -155.902021) (xy 315.783039 -155.904056)
			(xy 315.79693 -155.905962) (xy 315.798708 -155.906216) (xy 315.800232 -155.90647) (xy 315.805058 -155.906724)
			(xy 315.813354 -155.906823) (xy 315.829303 -155.902291) (xy 315.8363 -155.897834) (xy 315.839602 -155.895548)
			(xy 315.898784 -155.844748) (xy 315.905965 -155.837995) (xy 315.914962 -155.820479) (xy 315.91631 -155.810712)
			(xy 315.916564 -155.80614) (xy 315.916564 -155.222194) (xy 315.917054 -155.192226) (xy 315.924877 -155.132804)
			(xy 315.94039 -155.074911) (xy 315.963326 -155.019538) (xy 315.993293 -154.967632) (xy 316.02978 -154.920082)
			(xy 316.07216 -154.877702) (xy 316.11971 -154.841215) (xy 316.171616 -154.811248) (xy 316.226989 -154.788312)
			(xy 316.284882 -154.772799) (xy 316.344304 -154.764976) (xy 316.40424 -154.764976) (xy 316.463662 -154.772799)
			(xy 316.521555 -154.788312) (xy 316.576928 -154.811248) (xy 316.628834 -154.841215) (xy 316.676384 -154.877702)
			(xy 316.718764 -154.920082) (xy 316.755251 -154.967632) (xy 316.785218 -155.019538) (xy 316.808154 -155.074911)
			(xy 316.823667 -155.132804) (xy 316.83149 -155.192226) (xy 316.83198 -155.222194) (xy 316.83198 -155.80614)
			(xy 316.832102 -155.811094) (xy 316.834028 -155.820812) (xy 316.83579 -155.825444) (xy 316.838238 -155.830947)
			(xy 316.845302 -155.840698) (xy 316.84976 -155.844748) (xy 316.907418 -155.894024) (xy 316.91453 -155.90012)
			(xy 316.934088 -155.907232) (xy 316.947804 -155.90647) (xy 316.950344 -155.906216) (xy 316.964546 -155.904201)
			(xy 316.993151 -155.902037) (xy 317.007494 -155.901898) (xy 317.008256 -155.901898) (xy 317.035794 -155.902401)
			(xy 317.090294 -155.91036) (xy 317.143082 -155.926075) (xy 317.168276 -155.937204) (xy 317.178436 -155.941776)
			(xy 336.594958 -155.941776) (xy 336.606808 -155.941165) (xy 336.62801 -155.930577) (xy 336.635598 -155.921456)
			(xy 336.68462 -155.855924) (xy 336.688012 -155.851181) (xy 336.692765 -155.840536) (xy 336.694018 -155.834842)
			(xy 336.69605 -155.823158) (xy 336.692494 -155.81122) (xy 336.685041 -155.784531) (xy 336.677013 -155.729705)
			(xy 336.676492 -155.702) (xy 336.676978 -155.674749) (xy 336.684734 -155.620801) (xy 336.700089 -155.568506)
			(xy 336.722731 -155.518929) (xy 336.752197 -155.473079) (xy 336.787888 -155.431888) (xy 336.829079 -155.396197)
			(xy 336.874929 -155.366731) (xy 336.924506 -155.344089) (xy 336.976801 -155.328734) (xy 337.030749 -155.320978)
			(xy 337.085251 -155.320978) (xy 337.139199 -155.328734) (xy 337.191494 -155.344089) (xy 337.241071 -155.366731)
			(xy 337.286921 -155.396197) (xy 337.328112 -155.431888) (xy 337.363803 -155.473079) (xy 337.393269 -155.518929)
			(xy 337.415911 -155.568506) (xy 337.431266 -155.620801) (xy 337.439022 -155.674749) (xy 337.439508 -155.702)
			(xy 337.439067 -155.728055) (xy 337.431927 -155.779673) (xy 337.425284 -155.80487) (xy 337.423506 -155.811474)
			(xy 337.423506 -155.828492) (xy 337.423506 -155.829254) (xy 337.423878 -155.8367) (xy 337.428398 -155.850901)
			(xy 337.432396 -155.857194) (xy 337.443318 -155.871926) (xy 337.479894 -155.921202) (xy 337.484119 -155.926516)
			(xy 337.494805 -155.934882) (xy 337.500976 -155.937712) (xy 337.510628 -155.941776) (xy 339.86724 -155.941776)
			(xy 339.872066 -155.941522) (xy 339.875783 -155.941092) (xy 339.883049 -155.939303) (xy 339.886544 -155.937966)
			(xy 339.912452 -155.927298) (xy 339.91931 -155.920948) (xy 339.940604 -155.901792) (xy 339.987861 -155.869432)
			(xy 340.039425 -155.844503) (xy 340.094138 -155.827565) (xy 340.150769 -155.819) (xy 340.208043 -155.819)
			(xy 340.264674 -155.827565) (xy 340.319387 -155.844503) (xy 340.370951 -155.869432) (xy 340.418208 -155.901792)
			(xy 340.439502 -155.920948) (xy 340.44636 -155.927298) (xy 340.472268 -155.937966) (xy 340.475755 -155.939329)
			(xy 340.483025 -155.941109) (xy 340.486746 -155.941522) (xy 340.491572 -155.941776) (xy 340.681056 -155.941776)
			(xy 340.691019 -155.941291) (xy 340.709443 -155.933703) (xy 340.71687 -155.927044) (xy 340.747096 -155.896818)
			(xy 340.757764 -155.886404) (xy 340.75878 -155.885388) (xy 340.905338 -155.73883) (xy 340.912684 -155.732022)
			(xy 340.931147 -155.724299) (xy 340.941152 -155.723844) (xy 341.772494 -155.723844) (xy 341.78685 -155.723354)
			(xy 341.814428 -155.715367) (xy 341.838695 -155.700022) (xy 341.857734 -155.678531) (xy 341.870041 -155.652592)
			(xy 341.872824 -155.6385) (xy 341.874523 -155.625575) (xy 341.87205 -155.599632) (xy 341.863083 -155.575163)
			(xy 341.848207 -155.553766) (xy 341.838534 -155.545028) (xy 341.836756 -155.543758) (xy 341.814313 -155.52554)
			(xy 341.774654 -155.483488) (xy 341.741782 -155.435943) (xy 341.716445 -155.383989) (xy 341.699222 -155.328811)
			(xy 341.690506 -155.271669) (xy 341.689944 -155.242768) (xy 341.69043 -155.215517) (xy 341.698186 -155.161569)
			(xy 341.713541 -155.109274) (xy 341.736183 -155.059697) (xy 341.765649 -155.013847) (xy 341.80134 -154.972656)
			(xy 341.842531 -154.936965) (xy 341.888381 -154.907499) (xy 341.937958 -154.884857) (xy 341.990253 -154.869502)
			(xy 342.044201 -154.861746) (xy 342.098703 -154.861746) (xy 342.152651 -154.869502) (xy 342.204946 -154.884857)
			(xy 342.254523 -154.907499) (xy 342.300373 -154.936965) (xy 342.341564 -154.972656) (xy 342.377255 -155.013847)
			(xy 342.406721 -155.059697) (xy 342.4082 -155.062936) (xy 349.735392 -155.062936) (xy 349.739463 -155.007314)
			(xy 349.751589 -154.952877) (xy 349.771512 -154.900786) (xy 349.798808 -154.852151) (xy 349.832894 -154.808008)
			(xy 349.873043 -154.769299) (xy 349.918401 -154.736848) (xy 349.968001 -154.711347) (xy 350.020785 -154.69334)
			(xy 350.075628 -154.68321) (xy 350.131362 -154.681173) (xy 350.186799 -154.687273) (xy 350.240756 -154.701379)
			(xy 350.292085 -154.723191) (xy 350.339691 -154.752245) (xy 350.382559 -154.78792) (xy 350.419776 -154.829457)
			(xy 350.450549 -154.87597) (xy 350.474221 -154.926467) (xy 350.490289 -154.979874) (xy 350.498409 -155.03505)
			(xy 350.498918 -155.062936) (xy 350.498409 -155.090822) (xy 350.490289 -155.145998) (xy 350.474221 -155.199405)
			(xy 350.450549 -155.249902) (xy 350.419776 -155.296415) (xy 350.397748 -155.321) (xy 352.866196 -155.321)
			(xy 352.870267 -155.265378) (xy 352.882393 -155.210941) (xy 352.902316 -155.15885) (xy 352.929612 -155.110215)
			(xy 352.963698 -155.066072) (xy 353.003847 -155.027363) (xy 353.049205 -154.994912) (xy 353.098805 -154.969411)
			(xy 353.151589 -154.951404) (xy 353.206432 -154.941274) (xy 353.262166 -154.939237) (xy 353.317603 -154.945337)
			(xy 353.37156 -154.959443) (xy 353.422889 -154.981255) (xy 353.470495 -155.010309) (xy 353.513363 -155.045984)
			(xy 353.55058 -155.087521) (xy 353.581353 -155.134034) (xy 353.605025 -155.184531) (xy 353.6133 -155.212034)
			(xy 355.569264 -155.212034) (xy 355.573335 -155.156412) (xy 355.585461 -155.101975) (xy 355.605384 -155.049884)
			(xy 355.63268 -155.001249) (xy 355.666766 -154.957106) (xy 355.706915 -154.918397) (xy 355.752273 -154.885946)
			(xy 355.801873 -154.860445) (xy 355.854657 -154.842438) (xy 355.9095 -154.832308) (xy 355.965234 -154.830271)
			(xy 356.020671 -154.836371) (xy 356.074628 -154.850477) (xy 356.125957 -154.872289) (xy 356.173563 -154.901343)
			(xy 356.216431 -154.937018) (xy 356.253648 -154.978555) (xy 356.284421 -155.025068) (xy 356.308093 -155.075565)
			(xy 356.309184 -155.079192) (xy 358.16997 -155.079192) (xy 358.174041 -155.02357) (xy 358.186167 -154.969133)
			(xy 358.20609 -154.917042) (xy 358.233386 -154.868407) (xy 358.267472 -154.824264) (xy 358.307621 -154.785555)
			(xy 358.352979 -154.753104) (xy 358.402579 -154.727603) (xy 358.455363 -154.709596) (xy 358.510206 -154.699466)
			(xy 358.56594 -154.697429) (xy 358.621377 -154.703529) (xy 358.675334 -154.717635) (xy 358.726663 -154.739447)
			(xy 358.774269 -154.768501) (xy 358.817137 -154.804176) (xy 358.854354 -154.845713) (xy 358.885127 -154.892226)
			(xy 358.908799 -154.942723) (xy 358.924867 -154.99613) (xy 358.932987 -155.051306) (xy 358.933496 -155.079192)
			(xy 358.933431 -155.082748) (xy 359.49382 -155.082748) (xy 359.494246 -155.056433) (xy 359.501489 -155.004302)
			(xy 359.515815 -154.953658) (xy 359.536956 -154.905459) (xy 359.564509 -154.860617) (xy 359.597955 -154.819979)
			(xy 359.61701 -154.801824) (xy 359.624405 -154.794297) (xy 359.632933 -154.775021) (xy 359.63352 -154.764486)
			(xy 359.63352 -154.68981) (xy 359.632993 -154.67926) (xy 359.624456 -154.659965) (xy 359.61701 -154.652472)
			(xy 359.59795 -154.634321) (xy 359.564493 -154.593691) (xy 359.536934 -154.548849) (xy 359.515796 -154.500648)
			(xy 359.50148 -154.449999) (xy 359.494257 -154.397864) (xy 359.49382 -154.371548) (xy 359.4943 -154.344295)
			(xy 359.502051 -154.290343) (xy 359.517403 -154.238044) (xy 359.540042 -154.188462) (xy 359.569507 -154.142607)
			(xy 359.605199 -154.101414) (xy 359.646391 -154.065719) (xy 359.692245 -154.036251) (xy 359.741825 -154.01361)
			(xy 359.794124 -153.998255) (xy 359.848075 -153.990501) (xy 359.875328 -153.99004) (xy 359.901643 -153.990476)
			(xy 359.953774 -153.997715) (xy 360.004417 -154.01204) (xy 360.052617 -154.033178) (xy 360.097459 -154.06073)
			(xy 360.138097 -154.094175) (xy 360.156252 -154.11323) (xy 360.163762 -154.120646) (xy 360.18305 -154.129165)
			(xy 360.19359 -154.12974) (xy 360.268266 -154.12974) (xy 360.278813 -154.129194) (xy 360.298108 -154.12067)
			(xy 360.305604 -154.11323) (xy 360.325424 -154.092442) (xy 360.370196 -154.056467) (xy 360.419854 -154.027607)
			(xy 360.473276 -154.006514) (xy 360.529255 -153.993665) (xy 360.586528 -153.98935) (xy 360.643801 -153.993665)
			(xy 360.69978 -154.006514) (xy 360.753202 -154.027607) (xy 360.80286 -154.056467) (xy 360.847632 -154.092442)
			(xy 360.867452 -154.11323) (xy 360.874962 -154.120646) (xy 360.89425 -154.129165) (xy 360.90479 -154.12974)
			(xy 360.979466 -154.12974) (xy 360.990013 -154.129194) (xy 361.009308 -154.12067) (xy 361.016804 -154.11323)
			(xy 361.036624 -154.092442) (xy 361.081396 -154.056467) (xy 361.131054 -154.027607) (xy 361.184476 -154.006514)
			(xy 361.240455 -153.993665) (xy 361.297728 -153.98935) (xy 361.355001 -153.993665) (xy 361.41098 -154.006514)
			(xy 361.464402 -154.027607) (xy 361.51406 -154.056467) (xy 361.558832 -154.092442) (xy 361.578652 -154.11323)
			(xy 361.586162 -154.120646) (xy 361.60545 -154.129165) (xy 361.61599 -154.12974) (xy 361.690666 -154.12974)
			(xy 361.701213 -154.129194) (xy 361.720508 -154.12067) (xy 361.728004 -154.11323) (xy 361.746171 -154.094185)
			(xy 361.786797 -154.060726) (xy 361.831635 -154.033165) (xy 361.879834 -154.012024) (xy 361.93048 -153.997705)
			(xy 361.982612 -153.990479) (xy 362.008928 -153.99004) (xy 362.036184 -153.990429) (xy 362.09014 -153.998191)
			(xy 362.142442 -154.013553) (xy 362.192026 -154.036202) (xy 362.237881 -154.065678) (xy 362.279075 -154.101379)
			(xy 362.314768 -154.14258) (xy 362.344234 -154.188441) (xy 362.366874 -154.238029) (xy 362.382225 -154.290334)
			(xy 362.389976 -154.344292) (xy 362.390436 -154.371548) (xy 362.389989 -154.397863) (xy 362.382748 -154.449991)
			(xy 362.368424 -154.500634) (xy 362.347288 -154.548833) (xy 362.319739 -154.593676) (xy 362.286298 -154.634315)
			(xy 362.267246 -154.652472) (xy 362.259862 -154.660008) (xy 362.251326 -154.679277) (xy 362.250736 -154.68981)
			(xy 362.250736 -154.764486) (xy 362.251248 -154.775038) (xy 362.259794 -154.794334) (xy 362.267246 -154.801824)
			(xy 362.286315 -154.819966) (xy 362.319769 -154.8606) (xy 362.347325 -154.905443) (xy 362.368461 -154.953646)
			(xy 362.382776 -155.004296) (xy 362.389998 -155.056431) (xy 362.390436 -155.082748) (xy 362.389967 -155.109999)
			(xy 362.382205 -155.163946) (xy 362.366845 -155.216239) (xy 362.3442 -155.265815) (xy 362.314731 -155.311664)
			(xy 362.279038 -155.352853) (xy 362.237848 -155.388543) (xy 362.191997 -155.41801) (xy 362.142421 -155.440652)
			(xy 362.090126 -155.456009) (xy 362.036179 -155.463768) (xy 362.008928 -155.464256) (xy 361.982612 -155.463851)
			(xy 361.93048 -155.456605) (xy 361.879836 -155.442275) (xy 361.831636 -155.421131) (xy 361.786795 -155.393573)
			(xy 361.746158 -155.360123) (xy 361.728004 -155.341066) (xy 361.720474 -155.333674) (xy 361.701201 -155.325142)
			(xy 361.690666 -155.324556) (xy 361.61599 -155.324556) (xy 361.60544 -155.325079) (xy 361.586146 -155.33362)
			(xy 361.578652 -155.341066) (xy 361.558832 -155.361854) (xy 361.51406 -155.397829) (xy 361.464402 -155.426689)
			(xy 361.41098 -155.447782) (xy 361.355001 -155.460631) (xy 361.297728 -155.464946) (xy 361.240455 -155.460631)
			(xy 361.184476 -155.447782) (xy 361.131054 -155.426689) (xy 361.081396 -155.397829) (xy 361.036624 -155.361854)
			(xy 361.016804 -155.341066) (xy 361.009274 -155.333674) (xy 360.990001 -155.325142) (xy 360.979466 -155.324556)
			(xy 360.90479 -155.324556) (xy 360.89424 -155.325079) (xy 360.874946 -155.33362) (xy 360.867452 -155.341066)
			(xy 360.847632 -155.361854) (xy 360.80286 -155.397829) (xy 360.753202 -155.426689) (xy 360.69978 -155.447782)
			(xy 360.643801 -155.460631) (xy 360.586528 -155.464946) (xy 360.529255 -155.460631) (xy 360.473276 -155.447782)
			(xy 360.419854 -155.426689) (xy 360.370196 -155.397829) (xy 360.325424 -155.361854) (xy 360.305604 -155.341066)
			(xy 360.298074 -155.333674) (xy 360.278801 -155.325142) (xy 360.268266 -155.324556) (xy 360.19359 -155.324556)
			(xy 360.18304 -155.325079) (xy 360.163746 -155.33362) (xy 360.156252 -155.341066) (xy 360.138126 -155.36015)
			(xy 360.097488 -155.393602) (xy 360.052641 -155.421156) (xy 360.004435 -155.442289) (xy 359.953783 -155.456601)
			(xy 359.901646 -155.46382) (xy 359.875328 -155.464256) (xy 359.84808 -155.463696) (xy 359.794137 -155.455944)
			(xy 359.741847 -155.440595) (xy 359.692273 -155.417961) (xy 359.646425 -155.388502) (xy 359.605235 -155.352818)
			(xy 359.569544 -155.311636) (xy 359.540076 -155.265794) (xy 359.517431 -155.216225) (xy 359.502072 -155.163937)
			(xy 359.49431 -155.109996) (xy 359.49382 -155.082748) (xy 358.933431 -155.082748) (xy 358.932987 -155.107078)
			(xy 358.924867 -155.162254) (xy 358.908799 -155.215661) (xy 358.885127 -155.266158) (xy 358.854354 -155.312671)
			(xy 358.817137 -155.354208) (xy 358.774269 -155.389883) (xy 358.726663 -155.418937) (xy 358.675334 -155.440749)
			(xy 358.621377 -155.454855) (xy 358.56594 -155.460955) (xy 358.510206 -155.458918) (xy 358.455363 -155.448788)
			(xy 358.402579 -155.430781) (xy 358.352979 -155.40528) (xy 358.307621 -155.372829) (xy 358.267472 -155.33412)
			(xy 358.233386 -155.289977) (xy 358.20609 -155.241342) (xy 358.186167 -155.189251) (xy 358.174041 -155.134814)
			(xy 358.16997 -155.079192) (xy 356.309184 -155.079192) (xy 356.324161 -155.128972) (xy 356.332281 -155.184148)
			(xy 356.33279 -155.212034) (xy 356.332281 -155.23992) (xy 356.324161 -155.295096) (xy 356.308093 -155.348503)
			(xy 356.284421 -155.399) (xy 356.253648 -155.445513) (xy 356.216431 -155.48705) (xy 356.173563 -155.522725)
			(xy 356.125957 -155.551779) (xy 356.074628 -155.573591) (xy 356.020671 -155.587697) (xy 355.965234 -155.593797)
			(xy 355.9095 -155.59176) (xy 355.854657 -155.58163) (xy 355.801873 -155.563623) (xy 355.752273 -155.538122)
			(xy 355.706915 -155.505671) (xy 355.666766 -155.466962) (xy 355.63268 -155.422819) (xy 355.605384 -155.374184)
			(xy 355.585461 -155.322093) (xy 355.573335 -155.267656) (xy 355.569264 -155.212034) (xy 353.6133 -155.212034)
			(xy 353.621093 -155.237938) (xy 353.629213 -155.293114) (xy 353.629722 -155.321) (xy 353.629213 -155.348886)
			(xy 353.621093 -155.404062) (xy 353.605025 -155.457469) (xy 353.581353 -155.507966) (xy 353.55058 -155.554479)
			(xy 353.513363 -155.596016) (xy 353.470495 -155.631691) (xy 353.422889 -155.660745) (xy 353.37156 -155.682557)
			(xy 353.317603 -155.696663) (xy 353.262166 -155.702763) (xy 353.206432 -155.700726) (xy 353.151589 -155.690596)
			(xy 353.098805 -155.672589) (xy 353.049205 -155.647088) (xy 353.003847 -155.614637) (xy 352.963698 -155.575928)
			(xy 352.929612 -155.531785) (xy 352.902316 -155.48315) (xy 352.882393 -155.431059) (xy 352.870267 -155.376622)
			(xy 352.866196 -155.321) (xy 350.397748 -155.321) (xy 350.382559 -155.337952) (xy 350.339691 -155.373627)
			(xy 350.292085 -155.402681) (xy 350.240756 -155.424493) (xy 350.186799 -155.438599) (xy 350.131362 -155.444699)
			(xy 350.075628 -155.442662) (xy 350.020785 -155.432532) (xy 349.968001 -155.414525) (xy 349.918401 -155.389024)
			(xy 349.873043 -155.356573) (xy 349.832894 -155.317864) (xy 349.798808 -155.273721) (xy 349.771512 -155.225086)
			(xy 349.751589 -155.172995) (xy 349.739463 -155.118558) (xy 349.735392 -155.062936) (xy 342.4082 -155.062936)
			(xy 342.429363 -155.109274) (xy 342.444718 -155.161569) (xy 342.452474 -155.215517) (xy 342.45296 -155.242768)
			(xy 342.452431 -155.271672) (xy 342.443722 -155.328819) (xy 342.426499 -155.384002) (xy 342.401156 -155.435957)
			(xy 342.368271 -155.483499) (xy 342.328595 -155.525542) (xy 342.306148 -155.543758) (xy 342.30437 -155.545028)
			(xy 342.294731 -155.553797) (xy 342.279868 -155.57519) (xy 342.270899 -155.599646) (xy 342.268407 -155.625577)
			(xy 342.27008 -155.6385) (xy 342.272858 -155.652594) (xy 342.285155 -155.678541) (xy 342.304194 -155.700035)
			(xy 342.328467 -155.715374) (xy 342.356053 -155.723343) (xy 342.37041 -155.723844) (xy 349.175578 -155.723844)
			(xy 349.187516 -155.725368) (xy 349.192732 -155.726816) (xy 349.202463 -155.731554) (xy 349.20682 -155.734766)
			(xy 349.210072 -155.737241) (xy 349.217219 -155.741202) (xy 349.221044 -155.74264) (xy 349.229426 -155.745434)
			(xy 349.273114 -155.745434) (xy 349.2831 -155.745975) (xy 349.301525 -155.753696) (xy 349.308928 -155.76042)
			(xy 349.410274 -155.861766) (xy 349.410528 -155.861766) (xy 349.786702 -156.23794) (xy 349.790272 -156.241344)
			(xy 349.798456 -156.246846) (xy 349.802958 -156.248862) (xy 349.81261 -156.252926) (xy 349.83166 -156.252926)
			(xy 349.841566 -156.25318) (xy 349.873316 -156.240734) (xy 349.879412 -156.235908) (xy 349.899724 -156.220222)
			(xy 349.94376 -156.193867) (xy 349.990934 -156.173658) (xy 350.040393 -156.159961) (xy 350.091242 -156.153023)
			(xy 350.116902 -156.152596) (xy 350.11741 -156.152596) (xy 350.144661 -156.153082) (xy 350.198607 -156.16084)
			(xy 350.2509 -156.176196) (xy 350.300476 -156.198838) (xy 350.346325 -156.228305) (xy 350.387514 -156.263996)
			(xy 350.423204 -156.305186) (xy 350.443649 -156.337) (xy 352.866196 -156.337) (xy 352.870267 -156.281378)
			(xy 352.882393 -156.226941) (xy 352.902316 -156.17485) (xy 352.929612 -156.126215) (xy 352.963698 -156.082072)
			(xy 353.003847 -156.043363) (xy 353.049205 -156.010912) (xy 353.098805 -155.985411) (xy 353.151589 -155.967404)
			(xy 353.206432 -155.957274) (xy 353.262166 -155.955237) (xy 353.317603 -155.961337) (xy 353.37156 -155.975443)
			(xy 353.422889 -155.997255) (xy 353.470495 -156.026309) (xy 353.513363 -156.061984) (xy 353.55058 -156.103521)
			(xy 353.581353 -156.150034) (xy 353.605025 -156.200531) (xy 353.621093 -156.253938) (xy 353.629213 -156.309114)
			(xy 353.629722 -156.337) (xy 353.629213 -156.364886) (xy 353.621093 -156.420062) (xy 353.605025 -156.473469)
			(xy 353.581353 -156.523966) (xy 353.55058 -156.570479) (xy 353.513363 -156.612016) (xy 353.470495 -156.647691)
			(xy 353.422889 -156.676745) (xy 353.38259 -156.69387) (xy 357.187498 -156.69387) (xy 357.191569 -156.638248)
			(xy 357.203695 -156.583811) (xy 357.223618 -156.53172) (xy 357.250914 -156.483085) (xy 357.285 -156.438942)
			(xy 357.325149 -156.400233) (xy 357.370507 -156.367782) (xy 357.420107 -156.342281) (xy 357.472891 -156.324274)
			(xy 357.527734 -156.314144) (xy 357.583468 -156.312107) (xy 357.638905 -156.318207) (xy 357.692862 -156.332313)
			(xy 357.744191 -156.354125) (xy 357.791797 -156.383179) (xy 357.834665 -156.418854) (xy 357.871882 -156.460391)
			(xy 357.902655 -156.506904) (xy 357.926327 -156.557401) (xy 357.942395 -156.610808) (xy 357.950515 -156.665984)
			(xy 357.951024 -156.69387) (xy 357.950515 -156.721756) (xy 357.942395 -156.776932) (xy 357.926327 -156.830339)
			(xy 357.902655 -156.880836) (xy 357.871882 -156.927349) (xy 357.834665 -156.968886) (xy 357.791797 -157.004561)
			(xy 357.744191 -157.033615) (xy 357.692862 -157.055427) (xy 357.638905 -157.069533) (xy 357.583468 -157.075633)
			(xy 357.527734 -157.073596) (xy 357.472891 -157.063466) (xy 357.420107 -157.045459) (xy 357.370507 -157.019958)
			(xy 357.325149 -156.987507) (xy 357.285 -156.948798) (xy 357.250914 -156.904655) (xy 357.223618 -156.85602)
			(xy 357.203695 -156.803929) (xy 357.191569 -156.749492) (xy 357.187498 -156.69387) (xy 353.38259 -156.69387)
			(xy 353.37156 -156.698557) (xy 353.317603 -156.712663) (xy 353.262166 -156.718763) (xy 353.206432 -156.716726)
			(xy 353.151589 -156.706596) (xy 353.098805 -156.688589) (xy 353.049205 -156.663088) (xy 353.003847 -156.630637)
			(xy 352.963698 -156.591928) (xy 352.929612 -156.547785) (xy 352.902316 -156.49915) (xy 352.882393 -156.447059)
			(xy 352.870267 -156.392622) (xy 352.866196 -156.337) (xy 350.443649 -156.337) (xy 350.452669 -156.351036)
			(xy 350.475309 -156.400613) (xy 350.490663 -156.452907) (xy 350.498419 -156.506853) (xy 350.498918 -156.534104)
			(xy 350.499172 -156.534104) (xy 350.498687 -156.561673) (xy 350.490752 -156.616238) (xy 350.475048 -156.669092)
			(xy 350.451902 -156.719137) (xy 350.421796 -156.765331) (xy 350.403922 -156.786326) (xy 350.397572 -156.793438)
			(xy 350.394524 -156.80182) (xy 350.392982 -156.806168) (xy 350.391323 -156.815242) (xy 350.391222 -156.819854)
			(xy 350.391222 -156.821124) (xy 350.391526 -156.828381) (xy 350.395658 -156.8423) (xy 350.39935 -156.848556)
			(xy 350.40316 -156.854398) (xy 350.62922 -157.080458) (xy 351.054414 -157.080458) (xy 351.058485 -157.024836)
			(xy 351.070611 -156.970399) (xy 351.090534 -156.918308) (xy 351.11783 -156.869673) (xy 351.151916 -156.82553)
			(xy 351.192065 -156.786821) (xy 351.237423 -156.75437) (xy 351.287023 -156.728869) (xy 351.339807 -156.710862)
			(xy 351.39465 -156.700732) (xy 351.450384 -156.698695) (xy 351.505821 -156.704795) (xy 351.559778 -156.718901)
			(xy 351.611107 -156.740713) (xy 351.658713 -156.769767) (xy 351.701581 -156.805442) (xy 351.738798 -156.846979)
			(xy 351.769571 -156.893492) (xy 351.793243 -156.943989) (xy 351.809311 -156.997396) (xy 351.817431 -157.052572)
			(xy 351.81794 -157.080458) (xy 351.817431 -157.108344) (xy 351.809311 -157.16352) (xy 351.793243 -157.216927)
			(xy 351.769571 -157.267424) (xy 351.738798 -157.313937) (xy 351.701581 -157.355474) (xy 351.658713 -157.391149)
			(xy 351.611107 -157.420203) (xy 351.559778 -157.442015) (xy 351.505821 -157.456121) (xy 351.450384 -157.462221)
			(xy 351.39465 -157.460184) (xy 351.339807 -157.450054) (xy 351.287023 -157.432047) (xy 351.237423 -157.406546)
			(xy 351.192065 -157.374095) (xy 351.151916 -157.335386) (xy 351.11783 -157.291243) (xy 351.090534 -157.242608)
			(xy 351.070611 -157.190517) (xy 351.058485 -157.13608) (xy 351.054414 -157.080458) (xy 350.62922 -157.080458)
			(xy 351.361756 -157.812994) (xy 354.950266 -157.812994) (xy 354.954337 -157.757372) (xy 354.966463 -157.702935)
			(xy 354.986386 -157.650844) (xy 355.013682 -157.602209) (xy 355.047768 -157.558066) (xy 355.087917 -157.519357)
			(xy 355.133275 -157.486906) (xy 355.182875 -157.461405) (xy 355.235659 -157.443398) (xy 355.290502 -157.433268)
			(xy 355.346236 -157.431231) (xy 355.401673 -157.437331) (xy 355.45563 -157.451437) (xy 355.506959 -157.473249)
			(xy 355.554565 -157.502303) (xy 355.597433 -157.537978) (xy 355.63465 -157.579515) (xy 355.665423 -157.626028)
			(xy 355.675673 -157.647894) (xy 359.313988 -157.647894) (xy 359.314524 -157.621251) (xy 359.323048 -157.568653)
			(xy 359.339905 -157.518105) (xy 359.364658 -157.470919) (xy 359.396665 -157.428318) (xy 359.435096 -157.391409)
			(xy 359.456736 -157.37586) (xy 359.468026 -157.367502) (xy 359.485877 -157.345826) (xy 359.497157 -157.320111)
			(xy 359.501013 -157.292297) (xy 359.497155 -157.264483) (xy 359.485874 -157.238768) (xy 359.468021 -157.217094)
			(xy 359.456736 -157.208728) (xy 359.435134 -157.193132) (xy 359.396719 -157.156218) (xy 359.364719 -157.113623)
			(xy 359.339961 -157.066449) (xy 359.323086 -157.015916) (xy 359.31453 -156.963332) (xy 359.313988 -156.936694)
			(xy 359.314498 -156.910707) (xy 359.322628 -156.859372) (xy 359.338689 -156.809942) (xy 359.362285 -156.763632)
			(xy 359.392835 -156.721584) (xy 359.429586 -156.684833) (xy 359.471634 -156.654283) (xy 359.517944 -156.630687)
			(xy 359.567374 -156.614626) (xy 359.618709 -156.606496) (xy 359.670683 -156.606496) (xy 359.722018 -156.614626)
			(xy 359.771448 -156.630687) (xy 359.817758 -156.654283) (xy 359.859806 -156.684833) (xy 359.896557 -156.721584)
			(xy 359.927107 -156.763632) (xy 359.950703 -156.809942) (xy 359.966764 -156.859372) (xy 359.974894 -156.910707)
			(xy 359.975404 -156.936694) (xy 359.974862 -156.963336) (xy 359.96634 -157.015935) (xy 359.949485 -157.066483)
			(xy 359.924733 -157.113669) (xy 359.892726 -157.15627) (xy 359.854296 -157.193179) (xy 359.832656 -157.208728)
			(xy 359.821379 -157.217101) (xy 359.803529 -157.238774) (xy 359.79225 -157.264486) (xy 359.788392 -157.292297)
			(xy 359.792248 -157.320108) (xy 359.803525 -157.34582) (xy 359.821374 -157.367494) (xy 359.832656 -157.37586)
			(xy 359.854251 -157.391466) (xy 359.892666 -157.428378) (xy 359.924667 -157.47097) (xy 359.949427 -157.518142)
			(xy 359.966303 -157.568674) (xy 359.974861 -157.621257) (xy 359.975404 -157.647894) (xy 360.21391 -157.647894)
			(xy 360.214437 -157.621251) (xy 360.222961 -157.568652) (xy 360.239819 -157.518103) (xy 360.264574 -157.470917)
			(xy 360.296583 -157.428317) (xy 360.335017 -157.391408) (xy 360.356658 -157.37586) (xy 360.367946 -157.3675)
			(xy 360.385793 -157.345824) (xy 360.39707 -157.320109) (xy 360.400926 -157.292297) (xy 360.397068 -157.264484)
			(xy 360.38579 -157.23877) (xy 360.367941 -157.217095) (xy 360.356658 -157.208728) (xy 360.335061 -157.193125)
			(xy 360.296645 -157.156214) (xy 360.264643 -157.11362) (xy 360.239884 -157.066447) (xy 360.223009 -157.015915)
			(xy 360.214452 -156.963332) (xy 360.21391 -156.936694) (xy 360.21442 -156.910707) (xy 360.22255 -156.859372)
			(xy 360.238611 -156.809942) (xy 360.262207 -156.763632) (xy 360.292757 -156.721584) (xy 360.329508 -156.684833)
			(xy 360.371556 -156.654283) (xy 360.417866 -156.630687) (xy 360.467296 -156.614626) (xy 360.518631 -156.606496)
			(xy 360.570605 -156.606496) (xy 360.62194 -156.614626) (xy 360.67137 -156.630687) (xy 360.71768 -156.654283)
			(xy 360.759728 -156.684833) (xy 360.796479 -156.721584) (xy 360.827029 -156.763632) (xy 360.850625 -156.809942)
			(xy 360.866686 -156.859372) (xy 360.874816 -156.910707) (xy 360.875326 -156.936694) (xy 360.874817 -156.963338)
			(xy 360.866294 -157.01594) (xy 360.849434 -157.06649) (xy 360.824675 -157.113677) (xy 360.792661 -157.156276)
			(xy 360.754222 -157.193182) (xy 360.732578 -157.208728) (xy 360.721299 -157.2171) (xy 360.703445 -157.238772)
			(xy 360.692163 -157.264484) (xy 360.688305 -157.292297) (xy 360.692161 -157.320109) (xy 360.703441 -157.345823)
			(xy 360.721294 -157.367495) (xy 360.732578 -157.37586) (xy 360.754178 -157.391459) (xy 360.792592 -157.428373)
			(xy 360.824592 -157.470967) (xy 360.84935 -157.518141) (xy 360.866226 -157.568673) (xy 360.874783 -157.621256)
			(xy 360.875326 -157.647894) (xy 361.113832 -157.647894) (xy 361.11435 -157.62125) (xy 361.122874 -157.56865)
			(xy 361.139734 -157.518101) (xy 361.16449 -157.470914) (xy 361.196502 -157.428315) (xy 361.234937 -157.391407)
			(xy 361.25658 -157.37586) (xy 361.267875 -157.367505) (xy 361.285736 -157.345832) (xy 361.297022 -157.320115)
			(xy 361.300881 -157.292297) (xy 361.29702 -157.264479) (xy 361.285732 -157.238762) (xy 361.26787 -157.217091)
			(xy 361.25658 -157.208728) (xy 361.234987 -157.193119) (xy 361.19657 -157.156209) (xy 361.164567 -157.113617)
			(xy 361.139808 -157.066446) (xy 361.122931 -157.015915) (xy 361.114374 -156.963331) (xy 361.113832 -156.936694)
			(xy 361.114342 -156.910707) (xy 361.122472 -156.859372) (xy 361.138533 -156.809942) (xy 361.162129 -156.763632)
			(xy 361.192679 -156.721584) (xy 361.22943 -156.684833) (xy 361.271478 -156.654283) (xy 361.317788 -156.630687)
			(xy 361.367218 -156.614626) (xy 361.418553 -156.606496) (xy 361.470527 -156.606496) (xy 361.521862 -156.614626)
			(xy 361.571292 -156.630687) (xy 361.617602 -156.654283) (xy 361.65965 -156.684833) (xy 361.696401 -156.721584)
			(xy 361.726951 -156.763632) (xy 361.750547 -156.809942) (xy 361.766608 -156.859372) (xy 361.774738 -156.910707)
			(xy 361.775248 -156.936694) (xy 361.77473 -156.963338) (xy 361.766207 -157.015938) (xy 361.749348 -157.066488)
			(xy 361.724592 -157.113675) (xy 361.69258 -157.156274) (xy 361.654143 -157.193181) (xy 361.6325 -157.208728)
			(xy 361.621219 -157.217099) (xy 361.603362 -157.23877) (xy 361.592077 -157.264483) (xy 361.588218 -157.292297)
			(xy 361.592075 -157.320111) (xy 361.603358 -157.345825) (xy 361.621214 -157.367496) (xy 361.6325 -157.37586)
			(xy 361.654083 -157.391483) (xy 361.692501 -157.428389) (xy 361.724506 -157.470977) (xy 361.749267 -157.518147)
			(xy 361.766146 -157.568676) (xy 361.774705 -157.621257) (xy 361.775248 -157.647894) (xy 362.014008 -157.647894)
			(xy 362.014536 -157.621251) (xy 362.02306 -157.568652) (xy 362.039918 -157.518103) (xy 362.064672 -157.470917)
			(xy 362.096682 -157.428317) (xy 362.135115 -157.391408) (xy 362.156756 -157.37586) (xy 362.168044 -157.367501)
			(xy 362.185892 -157.345824) (xy 362.197169 -157.320109) (xy 362.201024 -157.292297) (xy 362.197167 -157.264484)
			(xy 362.185888 -157.23877) (xy 362.168039 -157.217095) (xy 362.156756 -157.208728) (xy 362.135158 -157.193126)
			(xy 362.096742 -157.156214) (xy 362.064741 -157.113621) (xy 362.039982 -157.066448) (xy 362.023107 -157.015916)
			(xy 362.01455 -156.963332) (xy 362.014008 -156.936694) (xy 362.014518 -156.910707) (xy 362.022648 -156.859372)
			(xy 362.038709 -156.809942) (xy 362.062305 -156.763632) (xy 362.092855 -156.721584) (xy 362.129606 -156.684833)
			(xy 362.171654 -156.654283) (xy 362.217964 -156.630687) (xy 362.267394 -156.614626) (xy 362.318729 -156.606496)
			(xy 362.370703 -156.606496) (xy 362.422038 -156.614626) (xy 362.471468 -156.630687) (xy 362.517778 -156.654283)
			(xy 362.559826 -156.684833) (xy 362.596577 -156.721584) (xy 362.627127 -156.763632) (xy 362.650723 -156.809942)
			(xy 362.666784 -156.859372) (xy 362.674914 -156.910707) (xy 362.675424 -156.936694) (xy 362.674916 -156.963338)
			(xy 362.666392 -157.01594) (xy 362.649532 -157.06649) (xy 362.624774 -157.113677) (xy 362.59276 -157.156276)
			(xy 362.55432 -157.193182) (xy 362.532676 -157.208728) (xy 362.521397 -157.2171) (xy 362.503544 -157.238772)
			(xy 362.492262 -157.264484) (xy 362.488404 -157.292297) (xy 362.49226 -157.320109) (xy 362.50354 -157.345822)
			(xy 362.521392 -157.367495) (xy 362.532676 -157.37586) (xy 362.554275 -157.39146) (xy 362.592689 -157.428374)
			(xy 362.624689 -157.470968) (xy 362.649448 -157.518141) (xy 362.666324 -157.568673) (xy 362.674881 -157.621256)
			(xy 362.675383 -157.645862) (xy 363.629448 -157.645862) (xy 363.629875 -157.619546) (xy 363.637116 -157.567416)
			(xy 363.651442 -157.516771) (xy 363.672582 -157.468572) (xy 363.700136 -157.42373) (xy 363.733582 -157.383093)
			(xy 363.752638 -157.364938) (xy 363.760016 -157.357396) (xy 363.768556 -157.338132) (xy 363.769148 -157.3276)
			(xy 363.769148 -157.252924) (xy 363.768605 -157.242376) (xy 363.760078 -157.223082) (xy 363.752638 -157.215586)
			(xy 363.733571 -157.197442) (xy 363.700117 -157.156809) (xy 363.672561 -157.111965) (xy 363.651425 -157.063763)
			(xy 363.63711 -157.013114) (xy 363.629886 -156.960979) (xy 363.629448 -156.934662) (xy 363.629934 -156.907411)
			(xy 363.63769 -156.853463) (xy 363.653045 -156.801168) (xy 363.675687 -156.751591) (xy 363.705153 -156.705741)
			(xy 363.740844 -156.66455) (xy 363.782035 -156.628859) (xy 363.827885 -156.599393) (xy 363.877462 -156.576751)
			(xy 363.929757 -156.561396) (xy 363.983705 -156.55364) (xy 364.038207 -156.55364) (xy 364.092155 -156.561396)
			(xy 364.14445 -156.576751) (xy 364.194027 -156.599393) (xy 364.239877 -156.628859) (xy 364.258622 -156.645101)
			(xy 365.614017 -156.645101) (xy 365.618332 -156.587828) (xy 365.631182 -156.531849) (xy 365.652276 -156.478427)
			(xy 365.681137 -156.428769) (xy 365.717113 -156.383997) (xy 365.737902 -156.364178) (xy 365.745315 -156.356667)
			(xy 365.753833 -156.337379) (xy 365.754412 -156.32684) (xy 365.754412 -156.252164) (xy 365.753858 -156.241617)
			(xy 365.74534 -156.222322) (xy 365.737902 -156.214826) (xy 365.718866 -156.19665) (xy 365.685407 -156.156025)
			(xy 365.657846 -156.111189) (xy 365.636704 -156.062992) (xy 365.622382 -156.012348) (xy 365.615153 -155.960217)
			(xy 365.614712 -155.933902) (xy 365.615198 -155.906651) (xy 365.622954 -155.852703) (xy 365.638309 -155.800408)
			(xy 365.660951 -155.750831) (xy 365.690417 -155.704981) (xy 365.726108 -155.66379) (xy 365.767299 -155.628099)
			(xy 365.813149 -155.598633) (xy 365.862726 -155.575991) (xy 365.915021 -155.560636) (xy 365.968969 -155.55288)
			(xy 366.023471 -155.55288) (xy 366.077419 -155.560636) (xy 366.129714 -155.575991) (xy 366.179291 -155.598633)
			(xy 366.225141 -155.628099) (xy 366.266332 -155.66379) (xy 366.302023 -155.704981) (xy 366.331489 -155.750831)
			(xy 366.354131 -155.800408) (xy 366.369486 -155.852703) (xy 366.377242 -155.906651) (xy 366.377728 -155.933902)
			(xy 366.377253 -155.960216) (xy 366.370018 -156.012343) (xy 366.3557 -156.062986) (xy 366.334569 -156.111184)
			(xy 366.307025 -156.156028) (xy 366.273588 -156.196669) (xy 366.254538 -156.214826) (xy 366.247129 -156.222341)
			(xy 366.238608 -156.241626) (xy 366.238028 -156.252164) (xy 366.238028 -156.32684) (xy 366.238568 -156.337389)
			(xy 366.247095 -156.356685) (xy 366.254538 -156.364178) (xy 366.275327 -156.383996) (xy 366.3113 -156.42877)
			(xy 366.340158 -156.478428) (xy 366.36125 -156.53185) (xy 366.374098 -156.587829) (xy 366.378413 -156.645101)
			(xy 366.374098 -156.702374) (xy 366.372962 -156.707322) (xy 368.679825 -156.707322) (xy 368.684137 -156.650052)
			(xy 368.696983 -156.594076) (xy 368.718071 -156.540656) (xy 368.746926 -156.491) (xy 368.782897 -156.446228)
			(xy 368.803682 -156.426408) (xy 368.811079 -156.418883) (xy 368.819607 -156.399606) (xy 368.820192 -156.38907)
			(xy 368.820192 -156.314394) (xy 368.819682 -156.303842) (xy 368.811133 -156.284547) (xy 368.803682 -156.277056)
			(xy 368.784609 -156.258918) (xy 368.751154 -156.218284) (xy 368.723598 -156.17344) (xy 368.702462 -156.125236)
			(xy 368.688149 -156.074586) (xy 368.680928 -156.022449) (xy 368.680492 -155.996132) (xy 368.680978 -155.968881)
			(xy 368.688734 -155.914933) (xy 368.704089 -155.862638) (xy 368.726731 -155.813061) (xy 368.756197 -155.767211)
			(xy 368.791888 -155.72602) (xy 368.833079 -155.690329) (xy 368.878929 -155.660863) (xy 368.928506 -155.638221)
			(xy 368.980801 -155.622866) (xy 369.034749 -155.61511) (xy 369.089251 -155.61511) (xy 369.143199 -155.622866)
			(xy 369.195494 -155.638221) (xy 369.245071 -155.660863) (xy 369.290921 -155.690329) (xy 369.332112 -155.72602)
			(xy 369.367803 -155.767211) (xy 369.397269 -155.813061) (xy 369.419911 -155.862638) (xy 369.435266 -155.914933)
			(xy 369.443022 -155.968881) (xy 369.443508 -155.996132) (xy 369.443059 -156.022447) (xy 369.43582 -156.074576)
			(xy 369.421497 -156.125219) (xy 369.400361 -156.173418) (xy 369.372812 -156.218261) (xy 369.339371 -156.2589)
			(xy 369.320318 -156.277056) (xy 369.312936 -156.284594) (xy 369.3044 -156.303862) (xy 369.303808 -156.314394)
			(xy 369.303808 -156.38907) (xy 369.304337 -156.39962) (xy 369.312872 -156.418915) (xy 369.320318 -156.426408)
			(xy 369.341138 -156.446196) (xy 369.377113 -156.490973) (xy 369.405971 -156.540635) (xy 369.427062 -156.594062)
			(xy 369.439909 -156.650045) (xy 369.444222 -156.707322) (xy 369.439903 -156.764598) (xy 369.427049 -156.82058)
			(xy 369.405952 -156.874004) (xy 369.377088 -156.923663) (xy 369.341108 -156.968436) (xy 369.320318 -156.988256)
			(xy 369.312936 -156.995794) (xy 369.3044 -157.015062) (xy 369.303808 -157.025594) (xy 369.303808 -157.10027)
			(xy 369.304337 -157.11082) (xy 369.312872 -157.130115) (xy 369.320318 -157.137608) (xy 369.339374 -157.155763)
			(xy 369.37283 -157.196393) (xy 369.400389 -157.241234) (xy 369.421527 -157.289435) (xy 369.435844 -157.340082)
			(xy 369.443069 -157.392216) (xy 369.443508 -157.418532) (xy 369.443022 -157.445783) (xy 369.435266 -157.499731)
			(xy 369.419911 -157.552026) (xy 369.397269 -157.601603) (xy 369.367803 -157.647453) (xy 369.332112 -157.688644)
			(xy 369.290921 -157.724335) (xy 369.245071 -157.753801) (xy 369.195494 -157.776443) (xy 369.143199 -157.791798)
			(xy 369.089251 -157.799554) (xy 369.034749 -157.799554) (xy 368.980801 -157.791798) (xy 368.928506 -157.776443)
			(xy 368.878929 -157.753801) (xy 368.833079 -157.724335) (xy 368.791888 -157.688644) (xy 368.756197 -157.647453)
			(xy 368.726731 -157.601603) (xy 368.704089 -157.552026) (xy 368.688734 -157.499731) (xy 368.680978 -157.445783)
			(xy 368.680492 -157.418532) (xy 368.680917 -157.392217) (xy 368.688161 -157.340086) (xy 368.702488 -157.289443)
			(xy 368.723629 -157.241244) (xy 368.751182 -157.196402) (xy 368.784627 -157.155764) (xy 368.803682 -157.137608)
			(xy 368.811079 -157.130083) (xy 368.819607 -157.110806) (xy 368.820192 -157.10027) (xy 368.820192 -157.025594)
			(xy 368.819682 -157.015042) (xy 368.811133 -156.995747) (xy 368.803682 -156.988256) (xy 368.782926 -156.968404)
			(xy 368.746951 -156.923636) (xy 368.71809 -156.873983) (xy 368.696996 -156.820566) (xy 368.684144 -156.764591)
			(xy 368.679825 -156.707322) (xy 366.372962 -156.707322) (xy 366.361249 -156.758353) (xy 366.340157 -156.811774)
			(xy 366.311299 -156.861432) (xy 366.275325 -156.906205) (xy 366.254538 -156.926026) (xy 366.247129 -156.933541)
			(xy 366.238608 -156.952826) (xy 366.238028 -156.963364) (xy 366.238028 -157.03804) (xy 366.238568 -157.048589)
			(xy 366.247095 -157.067885) (xy 366.254538 -157.075378) (xy 366.273583 -157.093544) (xy 366.30704 -157.134172)
			(xy 366.334599 -157.179011) (xy 366.355739 -157.227209) (xy 366.370059 -157.277854) (xy 366.377287 -157.329987)
			(xy 366.377728 -157.356302) (xy 366.377242 -157.383553) (xy 366.369486 -157.437501) (xy 366.354131 -157.489796)
			(xy 366.331489 -157.539373) (xy 366.302023 -157.585223) (xy 366.266332 -157.626414) (xy 366.225141 -157.662105)
			(xy 366.179291 -157.691571) (xy 366.129714 -157.714213) (xy 366.077419 -157.729568) (xy 366.023471 -157.737324)
			(xy 365.968969 -157.737324) (xy 365.915021 -157.729568) (xy 365.862726 -157.714213) (xy 365.813149 -157.691571)
			(xy 365.767299 -157.662105) (xy 365.726108 -157.626414) (xy 365.690417 -157.585223) (xy 365.660951 -157.539373)
			(xy 365.638309 -157.489796) (xy 365.622954 -157.437501) (xy 365.615198 -157.383553) (xy 365.614712 -157.356302)
			(xy 365.615177 -157.329988) (xy 365.622412 -157.277859) (xy 365.636731 -157.227216) (xy 365.657864 -157.179017)
			(xy 365.685411 -157.134174) (xy 365.71885 -157.093534) (xy 365.737902 -157.075378) (xy 365.745315 -157.067867)
			(xy 365.753833 -157.048579) (xy 365.754412 -157.03804) (xy 365.754412 -156.963364) (xy 365.753858 -156.952817)
			(xy 365.74534 -156.933522) (xy 365.737902 -156.926026) (xy 365.717115 -156.906205) (xy 365.681138 -156.861433)
			(xy 365.652277 -156.811776) (xy 365.631183 -156.758354) (xy 365.618333 -156.702374) (xy 365.614017 -156.645101)
			(xy 364.258622 -156.645101) (xy 364.281068 -156.66455) (xy 364.316759 -156.705741) (xy 364.346225 -156.751591)
			(xy 364.368867 -156.801168) (xy 364.384222 -156.853463) (xy 364.391978 -156.907411) (xy 364.392464 -156.934662)
			(xy 364.392049 -156.960978) (xy 364.384805 -157.013109) (xy 364.370477 -157.063753) (xy 364.349334 -157.111952)
			(xy 364.321778 -157.156794) (xy 364.28833 -157.197431) (xy 364.269274 -157.215586) (xy 364.261887 -157.223121)
			(xy 364.253352 -157.24239) (xy 364.252764 -157.252924) (xy 364.252764 -157.3276) (xy 364.25329 -157.33815)
			(xy 364.261829 -157.357444) (xy 364.269274 -157.364938) (xy 364.288336 -157.383087) (xy 364.321794 -157.423718)
			(xy 364.349352 -157.468559) (xy 364.37049 -157.516761) (xy 364.384805 -157.56741) (xy 364.392027 -157.619545)
			(xy 364.392464 -157.645862) (xy 364.391978 -157.673113) (xy 364.384222 -157.727061) (xy 364.368867 -157.779356)
			(xy 364.346225 -157.828933) (xy 364.316759 -157.874783) (xy 364.281068 -157.915974) (xy 364.239877 -157.951665)
			(xy 364.194027 -157.981131) (xy 364.14445 -158.003773) (xy 364.092155 -158.019128) (xy 364.038207 -158.026884)
			(xy 363.983705 -158.026884) (xy 363.929757 -158.019128) (xy 363.877462 -158.003773) (xy 363.827885 -157.981131)
			(xy 363.782035 -157.951665) (xy 363.740844 -157.915974) (xy 363.705153 -157.874783) (xy 363.675687 -157.828933)
			(xy 363.653045 -157.779356) (xy 363.63769 -157.727061) (xy 363.629934 -157.673113) (xy 363.629448 -157.645862)
			(xy 362.675383 -157.645862) (xy 362.675424 -157.647894) (xy 362.674914 -157.673881) (xy 362.666784 -157.725216)
			(xy 362.650723 -157.774646) (xy 362.627127 -157.820956) (xy 362.596577 -157.863004) (xy 362.559826 -157.899755)
			(xy 362.517778 -157.930305) (xy 362.471468 -157.953901) (xy 362.422038 -157.969962) (xy 362.370703 -157.978092)
			(xy 362.318729 -157.978092) (xy 362.267394 -157.969962) (xy 362.217964 -157.953901) (xy 362.171654 -157.930305)
			(xy 362.129606 -157.899755) (xy 362.092855 -157.863004) (xy 362.062305 -157.820956) (xy 362.038709 -157.774646)
			(xy 362.022648 -157.725216) (xy 362.014518 -157.673881) (xy 362.014008 -157.647894) (xy 361.775248 -157.647894)
			(xy 361.774738 -157.673881) (xy 361.766608 -157.725216) (xy 361.750547 -157.774646) (xy 361.726951 -157.820956)
			(xy 361.696401 -157.863004) (xy 361.65965 -157.899755) (xy 361.617602 -157.930305) (xy 361.571292 -157.953901)
			(xy 361.521862 -157.969962) (xy 361.470527 -157.978092) (xy 361.418553 -157.978092) (xy 361.367218 -157.969962)
			(xy 361.317788 -157.953901) (xy 361.271478 -157.930305) (xy 361.22943 -157.899755) (xy 361.192679 -157.863004)
			(xy 361.162129 -157.820956) (xy 361.138533 -157.774646) (xy 361.122472 -157.725216) (xy 361.114342 -157.673881)
			(xy 361.113832 -157.647894) (xy 360.875326 -157.647894) (xy 360.874816 -157.673881) (xy 360.866686 -157.725216)
			(xy 360.850625 -157.774646) (xy 360.827029 -157.820956) (xy 360.796479 -157.863004) (xy 360.759728 -157.899755)
			(xy 360.71768 -157.930305) (xy 360.67137 -157.953901) (xy 360.62194 -157.969962) (xy 360.570605 -157.978092)
			(xy 360.518631 -157.978092) (xy 360.467296 -157.969962) (xy 360.417866 -157.953901) (xy 360.371556 -157.930305)
			(xy 360.329508 -157.899755) (xy 360.292757 -157.863004) (xy 360.262207 -157.820956) (xy 360.238611 -157.774646)
			(xy 360.22255 -157.725216) (xy 360.21442 -157.673881) (xy 360.21391 -157.647894) (xy 359.975404 -157.647894)
			(xy 359.974894 -157.673881) (xy 359.966764 -157.725216) (xy 359.950703 -157.774646) (xy 359.927107 -157.820956)
			(xy 359.896557 -157.863004) (xy 359.859806 -157.899755) (xy 359.817758 -157.930305) (xy 359.771448 -157.953901)
			(xy 359.722018 -157.969962) (xy 359.670683 -157.978092) (xy 359.618709 -157.978092) (xy 359.567374 -157.969962)
			(xy 359.517944 -157.953901) (xy 359.471634 -157.930305) (xy 359.429586 -157.899755) (xy 359.392835 -157.863004)
			(xy 359.362285 -157.820956) (xy 359.338689 -157.774646) (xy 359.322628 -157.725216) (xy 359.314498 -157.673881)
			(xy 359.313988 -157.647894) (xy 355.675673 -157.647894) (xy 355.689095 -157.676525) (xy 355.705163 -157.729932)
			(xy 355.713283 -157.785108) (xy 355.713792 -157.812994) (xy 355.713283 -157.84088) (xy 355.705163 -157.896056)
			(xy 355.689095 -157.949463) (xy 355.665423 -157.99996) (xy 355.63465 -158.046473) (xy 355.62218 -158.06039)
			(xy 357.139746 -158.06039) (xy 357.143817 -158.004768) (xy 357.155943 -157.950331) (xy 357.175866 -157.89824)
			(xy 357.203162 -157.849605) (xy 357.237248 -157.805462) (xy 357.277397 -157.766753) (xy 357.322755 -157.734302)
			(xy 357.372355 -157.708801) (xy 357.425139 -157.690794) (xy 357.479982 -157.680664) (xy 357.535716 -157.678627)
			(xy 357.591153 -157.684727) (xy 357.64511 -157.698833) (xy 357.696439 -157.720645) (xy 357.744045 -157.749699)
			(xy 357.786913 -157.785374) (xy 357.82413 -157.826911) (xy 357.854903 -157.873424) (xy 357.878575 -157.923921)
			(xy 357.894643 -157.977328) (xy 357.902763 -158.032504) (xy 357.903272 -158.06039) (xy 357.902763 -158.088276)
			(xy 357.894643 -158.143452) (xy 357.878575 -158.196859) (xy 357.854903 -158.247356) (xy 357.82413 -158.293869)
			(xy 357.786913 -158.335406) (xy 357.744045 -158.371081) (xy 357.696439 -158.400135) (xy 357.64511 -158.421947)
			(xy 357.591153 -158.436053) (xy 357.535716 -158.442153) (xy 357.479982 -158.440116) (xy 357.425139 -158.429986)
			(xy 357.372355 -158.411979) (xy 357.322755 -158.386478) (xy 357.277397 -158.354027) (xy 357.237248 -158.315318)
			(xy 357.203162 -158.271175) (xy 357.175866 -158.22254) (xy 357.155943 -158.170449) (xy 357.143817 -158.116012)
			(xy 357.139746 -158.06039) (xy 355.62218 -158.06039) (xy 355.597433 -158.08801) (xy 355.554565 -158.123685)
			(xy 355.506959 -158.152739) (xy 355.45563 -158.174551) (xy 355.401673 -158.188657) (xy 355.346236 -158.194757)
			(xy 355.290502 -158.19272) (xy 355.235659 -158.18259) (xy 355.182875 -158.164583) (xy 355.133275 -158.139082)
			(xy 355.087917 -158.106631) (xy 355.047768 -158.067922) (xy 355.013682 -158.023779) (xy 354.986386 -157.975144)
			(xy 354.966463 -157.923053) (xy 354.954337 -157.868616) (xy 354.950266 -157.812994) (xy 351.361756 -157.812994)
			(xy 351.96653 -158.417768) (xy 353.080826 -158.417768) (xy 353.084897 -158.362146) (xy 353.097023 -158.307709)
			(xy 353.116946 -158.255618) (xy 353.144242 -158.206983) (xy 353.178328 -158.16284) (xy 353.218477 -158.124131)
			(xy 353.263835 -158.09168) (xy 353.313435 -158.066179) (xy 353.366219 -158.048172) (xy 353.421062 -158.038042)
			(xy 353.476796 -158.036005) (xy 353.532233 -158.042105) (xy 353.58619 -158.056211) (xy 353.637519 -158.078023)
			(xy 353.685125 -158.107077) (xy 353.727993 -158.142752) (xy 353.76521 -158.184289) (xy 353.795983 -158.230802)
			(xy 353.819655 -158.281299) (xy 353.835723 -158.334706) (xy 353.843843 -158.389882) (xy 353.844352 -158.417768)
			(xy 353.843843 -158.445654) (xy 353.835723 -158.50083) (xy 353.819655 -158.554237) (xy 353.795983 -158.604734)
			(xy 353.76521 -158.651247) (xy 353.727993 -158.692784) (xy 353.685125 -158.728459) (xy 353.637519 -158.757513)
			(xy 353.58619 -158.779325) (xy 353.532233 -158.793431) (xy 353.476796 -158.799531) (xy 353.421062 -158.797494)
			(xy 353.366219 -158.787364) (xy 353.313435 -158.769357) (xy 353.263835 -158.743856) (xy 353.218477 -158.711405)
			(xy 353.178328 -158.672696) (xy 353.144242 -158.628553) (xy 353.116946 -158.579918) (xy 353.097023 -158.527827)
			(xy 353.084897 -158.47339) (xy 353.080826 -158.417768) (xy 351.96653 -158.417768) (xy 352.377756 -158.828994)
			(xy 354.950266 -158.828994) (xy 354.954337 -158.773372) (xy 354.966463 -158.718935) (xy 354.986386 -158.666844)
			(xy 355.013682 -158.618209) (xy 355.047768 -158.574066) (xy 355.087917 -158.535357) (xy 355.133275 -158.502906)
			(xy 355.182875 -158.477405) (xy 355.235659 -158.459398) (xy 355.290502 -158.449268) (xy 355.346236 -158.447231)
			(xy 355.401673 -158.453331) (xy 355.45563 -158.467437) (xy 355.506959 -158.489249) (xy 355.554565 -158.518303)
			(xy 355.597433 -158.553978) (xy 355.63465 -158.595515) (xy 355.665423 -158.642028) (xy 355.689095 -158.692525)
			(xy 355.705163 -158.745932) (xy 355.706248 -158.753302) (xy 364.816642 -158.753302) (xy 364.820713 -158.69768)
			(xy 364.832839 -158.643243) (xy 364.852762 -158.591152) (xy 364.880058 -158.542517) (xy 364.914144 -158.498374)
			(xy 364.954293 -158.459665) (xy 364.999651 -158.427214) (xy 365.049251 -158.401713) (xy 365.102035 -158.383706)
			(xy 365.156878 -158.373576) (xy 365.212612 -158.371539) (xy 365.268049 -158.377639) (xy 365.322006 -158.391745)
			(xy 365.373335 -158.413557) (xy 365.420941 -158.442611) (xy 365.463809 -158.478286) (xy 365.501026 -158.519823)
			(xy 365.531799 -158.566336) (xy 365.555471 -158.616833) (xy 365.571539 -158.67024) (xy 365.579659 -158.725416)
			(xy 365.580168 -158.753302) (xy 365.579659 -158.781188) (xy 365.571539 -158.836364) (xy 365.555471 -158.889771)
			(xy 365.531799 -158.940268) (xy 365.501026 -158.986781) (xy 365.463809 -159.028318) (xy 365.420941 -159.063993)
			(xy 365.373335 -159.093047) (xy 365.322006 -159.114859) (xy 365.268049 -159.128965) (xy 365.212612 -159.135065)
			(xy 365.156878 -159.133028) (xy 365.102035 -159.122898) (xy 365.049251 -159.104891) (xy 364.999651 -159.07939)
			(xy 364.954293 -159.046939) (xy 364.914144 -159.00823) (xy 364.880058 -158.964087) (xy 364.852762 -158.915452)
			(xy 364.832839 -158.863361) (xy 364.820713 -158.808924) (xy 364.816642 -158.753302) (xy 355.706248 -158.753302)
			(xy 355.713283 -158.801108) (xy 355.713792 -158.828994) (xy 355.713283 -158.85688) (xy 355.705163 -158.912056)
			(xy 355.689095 -158.965463) (xy 355.665423 -159.01596) (xy 355.63465 -159.062473) (xy 355.597433 -159.10401)
			(xy 355.554565 -159.139685) (xy 355.506959 -159.168739) (xy 355.45563 -159.190551) (xy 355.401673 -159.204657)
			(xy 355.346236 -159.210757) (xy 355.290502 -159.20872) (xy 355.235659 -159.19859) (xy 355.182875 -159.180583)
			(xy 355.133275 -159.155082) (xy 355.087917 -159.122631) (xy 355.047768 -159.083922) (xy 355.013682 -159.039779)
			(xy 354.986386 -158.991144) (xy 354.966463 -158.939053) (xy 354.954337 -158.884616) (xy 354.950266 -158.828994)
			(xy 352.377756 -158.828994) (xy 352.987864 -159.439102) (xy 357.208072 -159.439102) (xy 357.212143 -159.38348)
			(xy 357.224269 -159.329043) (xy 357.244192 -159.276952) (xy 357.271488 -159.228317) (xy 357.305574 -159.184174)
			(xy 357.345723 -159.145465) (xy 357.391081 -159.113014) (xy 357.440681 -159.087513) (xy 357.493465 -159.069506)
			(xy 357.548308 -159.059376) (xy 357.604042 -159.057339) (xy 357.659479 -159.063439) (xy 357.713436 -159.077545)
			(xy 357.764765 -159.099357) (xy 357.812371 -159.128411) (xy 357.855239 -159.164086) (xy 357.892456 -159.205623)
			(xy 357.923229 -159.252136) (xy 357.946901 -159.302633) (xy 357.962969 -159.35604) (xy 357.971089 -159.411216)
			(xy 357.971598 -159.439102) (xy 357.971089 -159.466988) (xy 357.962969 -159.522164) (xy 357.960066 -159.531812)
			(xy 360.41279 -159.531812) (xy 360.416861 -159.47619) (xy 360.428987 -159.421753) (xy 360.44891 -159.369662)
			(xy 360.476206 -159.321027) (xy 360.510292 -159.276884) (xy 360.550441 -159.238175) (xy 360.595799 -159.205724)
			(xy 360.645399 -159.180223) (xy 360.698183 -159.162216) (xy 360.753026 -159.152086) (xy 360.80876 -159.150049)
			(xy 360.864197 -159.156149) (xy 360.918154 -159.170255) (xy 360.969483 -159.192067) (xy 361.017089 -159.221121)
			(xy 361.059957 -159.256796) (xy 361.097174 -159.298333) (xy 361.127947 -159.344846) (xy 361.151619 -159.395343)
			(xy 361.167687 -159.44875) (xy 361.171463 -159.474408) (xy 362.882432 -159.474408) (xy 362.886503 -159.418786)
			(xy 362.898629 -159.364349) (xy 362.918552 -159.312258) (xy 362.945848 -159.263623) (xy 362.979934 -159.21948)
			(xy 363.020083 -159.180771) (xy 363.065441 -159.14832) (xy 363.115041 -159.122819) (xy 363.167825 -159.104812)
			(xy 363.222668 -159.094682) (xy 363.278402 -159.092645) (xy 363.333839 -159.098745) (xy 363.387796 -159.112851)
			(xy 363.439125 -159.134663) (xy 363.486731 -159.163717) (xy 363.529599 -159.199392) (xy 363.566816 -159.240929)
			(xy 363.597589 -159.287442) (xy 363.621261 -159.337939) (xy 363.637329 -159.391346) (xy 363.645449 -159.446522)
			(xy 363.645958 -159.474408) (xy 363.645449 -159.502294) (xy 363.637329 -159.55747) (xy 363.621261 -159.610877)
			(xy 363.597589 -159.661374) (xy 363.566816 -159.707887) (xy 363.529599 -159.749424) (xy 363.486731 -159.785099)
			(xy 363.439125 -159.814153) (xy 363.387796 -159.835965) (xy 363.333839 -159.850071) (xy 363.278402 -159.856171)
			(xy 363.222668 -159.854134) (xy 363.167825 -159.844004) (xy 363.115041 -159.825997) (xy 363.065441 -159.800496)
			(xy 363.020083 -159.768045) (xy 362.979934 -159.729336) (xy 362.945848 -159.685193) (xy 362.918552 -159.636558)
			(xy 362.898629 -159.584467) (xy 362.886503 -159.53003) (xy 362.882432 -159.474408) (xy 361.171463 -159.474408)
			(xy 361.175807 -159.503926) (xy 361.176316 -159.531812) (xy 361.175807 -159.559698) (xy 361.167687 -159.614874)
			(xy 361.151619 -159.668281) (xy 361.127947 -159.718778) (xy 361.097174 -159.765291) (xy 361.059957 -159.806828)
			(xy 361.017089 -159.842503) (xy 360.969483 -159.871557) (xy 360.918154 -159.893369) (xy 360.864197 -159.907475)
			(xy 360.80876 -159.913575) (xy 360.753026 -159.911538) (xy 360.698183 -159.901408) (xy 360.645399 -159.883401)
			(xy 360.595799 -159.8579) (xy 360.550441 -159.825449) (xy 360.510292 -159.78674) (xy 360.476206 -159.742597)
			(xy 360.44891 -159.693962) (xy 360.428987 -159.641871) (xy 360.416861 -159.587434) (xy 360.41279 -159.531812)
			(xy 357.960066 -159.531812) (xy 357.946901 -159.575571) (xy 357.923229 -159.626068) (xy 357.892456 -159.672581)
			(xy 357.855239 -159.714118) (xy 357.812371 -159.749793) (xy 357.764765 -159.778847) (xy 357.713436 -159.800659)
			(xy 357.659479 -159.814765) (xy 357.604042 -159.820865) (xy 357.548308 -159.818828) (xy 357.493465 -159.808698)
			(xy 357.440681 -159.790691) (xy 357.391081 -159.76519) (xy 357.345723 -159.732739) (xy 357.305574 -159.69403)
			(xy 357.271488 -159.649887) (xy 357.244192 -159.601252) (xy 357.224269 -159.549161) (xy 357.212143 -159.494724)
			(xy 357.208072 -159.439102) (xy 352.987864 -159.439102) (xy 353.393756 -159.844994) (xy 354.950266 -159.844994)
			(xy 354.954337 -159.789372) (xy 354.966463 -159.734935) (xy 354.986386 -159.682844) (xy 355.013682 -159.634209)
			(xy 355.047768 -159.590066) (xy 355.087917 -159.551357) (xy 355.133275 -159.518906) (xy 355.182875 -159.493405)
			(xy 355.235659 -159.475398) (xy 355.290502 -159.465268) (xy 355.346236 -159.463231) (xy 355.401673 -159.469331)
			(xy 355.45563 -159.483437) (xy 355.506959 -159.505249) (xy 355.554565 -159.534303) (xy 355.597433 -159.569978)
			(xy 355.63465 -159.611515) (xy 355.665423 -159.658028) (xy 355.689095 -159.708525) (xy 355.705163 -159.761932)
			(xy 355.713283 -159.817108) (xy 355.713792 -159.844994) (xy 355.713283 -159.87288) (xy 355.705163 -159.928056)
			(xy 355.689095 -159.981463) (xy 355.665423 -160.03196) (xy 355.63465 -160.078473) (xy 355.597433 -160.12001)
			(xy 355.554565 -160.155685) (xy 355.506959 -160.184739) (xy 355.45563 -160.206551) (xy 355.401673 -160.220657)
			(xy 355.346236 -160.226757) (xy 355.290502 -160.22472) (xy 355.235659 -160.21459) (xy 355.182875 -160.196583)
			(xy 355.133275 -160.171082) (xy 355.087917 -160.138631) (xy 355.047768 -160.099922) (xy 355.013682 -160.055779)
			(xy 354.986386 -160.007144) (xy 354.966463 -159.955053) (xy 354.954337 -159.900616) (xy 354.950266 -159.844994)
			(xy 353.393756 -159.844994) (xy 354.514658 -160.965896) (xy 357.23779 -160.965896) (xy 357.241861 -160.910274)
			(xy 357.253987 -160.855837) (xy 357.27391 -160.803746) (xy 357.301206 -160.755111) (xy 357.335292 -160.710968)
			(xy 357.375441 -160.672259) (xy 357.420799 -160.639808) (xy 357.470399 -160.614307) (xy 357.523183 -160.5963)
			(xy 357.578026 -160.58617) (xy 357.63376 -160.584133) (xy 357.689197 -160.590233) (xy 357.743154 -160.604339)
			(xy 357.794483 -160.626151) (xy 357.842089 -160.655205) (xy 357.884957 -160.69088) (xy 357.922174 -160.732417)
			(xy 357.952947 -160.77893) (xy 357.976619 -160.829427) (xy 357.992687 -160.882834) (xy 358.000807 -160.93801)
			(xy 358.001279 -160.963864) (xy 358.62971 -160.963864) (xy 358.633781 -160.908242) (xy 358.645907 -160.853805)
			(xy 358.66583 -160.801714) (xy 358.693126 -160.753079) (xy 358.727212 -160.708936) (xy 358.767361 -160.670227)
			(xy 358.812719 -160.637776) (xy 358.862319 -160.612275) (xy 358.915103 -160.594268) (xy 358.969946 -160.584138)
			(xy 359.02568 -160.582101) (xy 359.081117 -160.588201) (xy 359.135074 -160.602307) (xy 359.186403 -160.624119)
			(xy 359.234009 -160.653173) (xy 359.276877 -160.688848) (xy 359.314094 -160.730385) (xy 359.344867 -160.776898)
			(xy 359.368539 -160.827395) (xy 359.384607 -160.880802) (xy 359.392727 -160.935978) (xy 359.393236 -160.963864)
			(xy 359.393143 -160.968944) (xy 359.901488 -160.968944) (xy 359.905559 -160.913322) (xy 359.917685 -160.858885)
			(xy 359.937608 -160.806794) (xy 359.964904 -160.758159) (xy 359.99899 -160.714016) (xy 360.039139 -160.675307)
			(xy 360.084497 -160.642856) (xy 360.134097 -160.617355) (xy 360.186881 -160.599348) (xy 360.241724 -160.589218)
			(xy 360.297458 -160.587181) (xy 360.352895 -160.593281) (xy 360.406852 -160.607387) (xy 360.458181 -160.629199)
			(xy 360.505787 -160.658253) (xy 360.548655 -160.693928) (xy 360.585872 -160.735465) (xy 360.616645 -160.781978)
			(xy 360.640317 -160.832475) (xy 360.656385 -160.885882) (xy 360.658778 -160.902142) (xy 361.68279 -160.902142)
			(xy 361.686861 -160.84652) (xy 361.698987 -160.792083) (xy 361.71891 -160.739992) (xy 361.746206 -160.691357)
			(xy 361.780292 -160.647214) (xy 361.820441 -160.608505) (xy 361.865799 -160.576054) (xy 361.915399 -160.550553)
			(xy 361.968183 -160.532546) (xy 362.023026 -160.522416) (xy 362.07876 -160.520379) (xy 362.134197 -160.526479)
			(xy 362.188154 -160.540585) (xy 362.239483 -160.562397) (xy 362.287089 -160.591451) (xy 362.329957 -160.627126)
			(xy 362.367174 -160.668663) (xy 362.397947 -160.715176) (xy 362.421619 -160.765673) (xy 362.437687 -160.81908)
			(xy 362.445807 -160.874256) (xy 362.446316 -160.902142) (xy 362.445807 -160.930028) (xy 362.437687 -160.985204)
			(xy 362.421619 -161.038611) (xy 362.397947 -161.089108) (xy 362.367174 -161.135621) (xy 362.329957 -161.177158)
			(xy 362.287089 -161.212833) (xy 362.239483 -161.241887) (xy 362.188154 -161.263699) (xy 362.134197 -161.277805)
			(xy 362.07876 -161.283905) (xy 362.023026 -161.281868) (xy 361.968183 -161.271738) (xy 361.915399 -161.253731)
			(xy 361.865799 -161.22823) (xy 361.820441 -161.195779) (xy 361.780292 -161.15707) (xy 361.746206 -161.112927)
			(xy 361.71891 -161.064292) (xy 361.698987 -161.012201) (xy 361.686861 -160.957764) (xy 361.68279 -160.902142)
			(xy 360.658778 -160.902142) (xy 360.664505 -160.941058) (xy 360.665014 -160.968944) (xy 360.664505 -160.99683)
			(xy 360.656385 -161.052006) (xy 360.640317 -161.105413) (xy 360.616645 -161.15591) (xy 360.585872 -161.202423)
			(xy 360.548655 -161.24396) (xy 360.505787 -161.279635) (xy 360.458181 -161.308689) (xy 360.406852 -161.330501)
			(xy 360.352895 -161.344607) (xy 360.297458 -161.350707) (xy 360.241724 -161.34867) (xy 360.186881 -161.33854)
			(xy 360.134097 -161.320533) (xy 360.084497 -161.295032) (xy 360.039139 -161.262581) (xy 359.99899 -161.223872)
			(xy 359.964904 -161.179729) (xy 359.937608 -161.131094) (xy 359.917685 -161.079003) (xy 359.905559 -161.024566)
			(xy 359.901488 -160.968944) (xy 359.393143 -160.968944) (xy 359.392727 -160.99175) (xy 359.384607 -161.046926)
			(xy 359.368539 -161.100333) (xy 359.344867 -161.15083) (xy 359.314094 -161.197343) (xy 359.276877 -161.23888)
			(xy 359.234009 -161.274555) (xy 359.186403 -161.303609) (xy 359.135074 -161.325421) (xy 359.081117 -161.339527)
			(xy 359.02568 -161.345627) (xy 358.969946 -161.34359) (xy 358.915103 -161.33346) (xy 358.862319 -161.315453)
			(xy 358.812719 -161.289952) (xy 358.767361 -161.257501) (xy 358.727212 -161.218792) (xy 358.693126 -161.174649)
			(xy 358.66583 -161.126014) (xy 358.645907 -161.073923) (xy 358.633781 -161.019486) (xy 358.62971 -160.963864)
			(xy 358.001279 -160.963864) (xy 358.001316 -160.965896) (xy 358.000807 -160.993782) (xy 357.992687 -161.048958)
			(xy 357.976619 -161.102365) (xy 357.952947 -161.152862) (xy 357.922174 -161.199375) (xy 357.884957 -161.240912)
			(xy 357.842089 -161.276587) (xy 357.794483 -161.305641) (xy 357.743154 -161.327453) (xy 357.689197 -161.341559)
			(xy 357.63376 -161.347659) (xy 357.578026 -161.345622) (xy 357.523183 -161.335492) (xy 357.470399 -161.317485)
			(xy 357.420799 -161.291984) (xy 357.375441 -161.259533) (xy 357.335292 -161.220824) (xy 357.301206 -161.176681)
			(xy 357.27391 -161.128046) (xy 357.253987 -161.075955) (xy 357.241861 -161.021518) (xy 357.23779 -160.965896)
			(xy 354.514658 -160.965896) (xy 356.43693 -162.888168) (xy 356.439782 -162.890872) (xy 356.446162 -162.895462)
			(xy 356.44963 -162.897312) (xy 356.455057 -162.899896) (xy 356.466736 -162.902722) (xy 356.472744 -162.9029)
			(xy 357.215694 -162.9029) (xy 357.223425 -162.902633) (xy 357.238169 -162.897978) (xy 357.24465 -162.893756)
			(xy 357.253032 -162.887914) (xy 357.261668 -162.880294) (xy 357.265732 -162.875976) (xy 357.268272 -162.872928)
			(xy 357.271574 -162.865562) (xy 357.277918 -162.851663) (xy 357.29254 -162.824832) (xy 357.300784 -162.811968)
			(xy 357.315993 -162.789663) (xy 357.351694 -162.749168) (xy 357.392744 -162.714107) (xy 357.438325 -162.68518)
			(xy 357.487527 -162.662963) (xy 357.539369 -162.647902) (xy 357.592815 -162.640295) (xy 357.646801 -162.640295)
			(xy 357.700247 -162.647902) (xy 357.752089 -162.662963) (xy 357.801291 -162.68518) (xy 357.846872 -162.714107)
			(xy 357.887922 -162.749168) (xy 357.923623 -162.789663) (xy 357.938832 -162.811968) (xy 357.947058 -162.824842)
			(xy 357.961682 -162.851671) (xy 357.968042 -162.865562) (xy 357.971344 -162.872928) (xy 357.977694 -162.88004)
			(xy 357.982012 -162.884866) (xy 357.995474 -162.89401) (xy 358.002078 -162.898328) (xy 358.010206 -162.900868)
			(xy 358.01427 -162.901884) (xy 358.02443 -162.9029) (xy 358.373172 -162.9029) (xy 358.383162 -162.903432)
			(xy 358.401601 -162.911139) (xy 358.408986 -162.917886) (xy 358.484932 -162.993832) (xy 358.485186 -162.993832)
			(xy 358.563164 -163.07181) (xy 358.567228 -163.075874) (xy 358.57434 -163.082986) (xy 358.580089 -163.088185)
			(xy 358.593921 -163.095164) (xy 358.601518 -163.096702) (xy 358.6099 -163.097464) (xy 364.305088 -163.097464)
			(xy 364.3122 -163.096956) (xy 364.322824 -163.094964) (xy 364.341075 -163.08342) (xy 364.352942 -163.065378)
			(xy 364.355126 -163.054792) (xy 364.355126 -163.054538) (xy 364.359838 -163.028) (xy 364.375751 -162.976503)
			(xy 364.398754 -162.92776) (xy 364.42839 -162.88274) (xy 364.464067 -162.84234) (xy 364.505077 -162.807364)
			(xy 364.550601 -162.778509) (xy 364.599734 -162.756349) (xy 364.651496 -162.741326) (xy 364.704859 -162.733739)
			(xy 364.758757 -162.733739) (xy 364.81212 -162.741326) (xy 364.863882 -162.756349) (xy 364.913015 -162.778509)
			(xy 364.958539 -162.807364) (xy 364.999549 -162.84234) (xy 365.035226 -162.88274) (xy 365.064862 -162.92776)
			(xy 365.087865 -162.976503) (xy 365.103778 -163.028) (xy 365.10849 -163.054538) (xy 365.10849 -163.054792)
			(xy 365.11072 -163.065354) (xy 365.122613 -163.083346) (xy 365.140817 -163.094912) (xy 365.151416 -163.096956)
			(xy 365.158528 -163.097464) (xy 368.074194 -163.097464) (xy 368.084181 -163.096926) (xy 368.102611 -163.089211)
			(xy 368.110008 -163.082478) (xy 368.69116 -162.501326) (xy 368.697694 -162.494265) (xy 368.705367 -162.476641)
			(xy 368.705957 -162.457427) (xy 368.703098 -162.44824) (xy 368.703098 -162.447986) (xy 368.692571 -162.416705)
			(xy 368.681198 -162.351697) (xy 368.680492 -162.3187) (xy 368.680978 -162.291449) (xy 368.688734 -162.237501)
			(xy 368.704089 -162.185206) (xy 368.726731 -162.135629) (xy 368.756197 -162.089779) (xy 368.791888 -162.048588)
			(xy 368.833079 -162.012897) (xy 368.878929 -161.983431) (xy 368.928506 -161.960789) (xy 368.980801 -161.945434)
			(xy 369.034749 -161.937678) (xy 369.062 -161.937192) (xy 369.094999 -161.937888) (xy 369.16001 -161.949253)
			(xy 369.191286 -161.959798) (xy 369.19154 -161.959798) (xy 369.200725 -161.962625) (xy 369.219917 -161.961974)
			(xy 369.237543 -161.954354) (xy 369.244626 -161.94786) (xy 385.446016 -145.74647) (xy 385.452219 -145.73973)
			(xy 385.459786 -145.723065) (xy 385.460748 -145.713958) (xy 385.460748 -141.78026) (xy 385.461002 -141.768576)
			(xy 385.461002 -141.556486) (xy 385.461542 -141.5465) (xy 385.469259 -141.528072) (xy 385.475988 -141.520672)
			(xy 385.622546 -141.374114) (xy 385.623562 -141.373098) (xy 385.633976 -141.36243) (xy 389.486394 -137.510012)
			(xy 389.497062 -137.499598) (xy 389.498078 -137.498582) (xy 389.644636 -137.352024) (xy 389.651982 -137.345216)
			(xy 389.670445 -137.337493) (xy 389.68045 -137.337038) (xy 389.89254 -137.337038) (xy 389.904224 -137.336784)
			(xy 392.17346 -137.336784) (xy 392.180718 -137.336075) (xy 392.194402 -137.331049) (xy 392.200384 -137.326878)
			(xy 392.205718 -137.322306) (xy 392.312652 -137.215372) (xy 392.336411 -137.192229) (xy 392.388253 -137.150854)
			(xy 392.444401 -137.115544) (xy 392.504151 -137.086742) (xy 392.566749 -137.064812) (xy 392.631409 -137.050028)
			(xy 392.697318 -137.042577) (xy 392.730482 -137.042144) (xy 392.763651 -137.042591) (xy 392.829571 -137.050016)
			(xy 392.894245 -137.064776) (xy 392.95686 -137.086684) (xy 393.016628 -137.115466) (xy 393.072798 -137.150758)
			(xy 393.124663 -137.192118) (xy 393.171572 -137.239025) (xy 393.209832 -137.287) (xy 405.068022 -137.287)
			(xy 405.072093 -137.231378) (xy 405.084219 -137.176941) (xy 405.104142 -137.12485) (xy 405.131438 -137.076215)
			(xy 405.165524 -137.032072) (xy 405.205673 -136.993363) (xy 405.251031 -136.960912) (xy 405.300631 -136.935411)
			(xy 405.353415 -136.917404) (xy 405.408258 -136.907274) (xy 405.463992 -136.905237) (xy 405.519429 -136.911337)
			(xy 405.573386 -136.925443) (xy 405.624715 -136.947255) (xy 405.672321 -136.976309) (xy 405.715189 -137.011984)
			(xy 405.752406 -137.053521) (xy 405.783179 -137.100034) (xy 405.806851 -137.150531) (xy 405.822919 -137.203938)
			(xy 405.831039 -137.259114) (xy 405.831548 -137.287) (xy 405.831039 -137.314886) (xy 405.822919 -137.370062)
			(xy 405.806851 -137.423469) (xy 405.783179 -137.473966) (xy 405.752406 -137.520479) (xy 405.715189 -137.562016)
			(xy 405.672321 -137.597691) (xy 405.624715 -137.626745) (xy 405.573386 -137.648557) (xy 405.519429 -137.662663)
			(xy 405.463992 -137.668763) (xy 405.408258 -137.666726) (xy 405.353415 -137.656596) (xy 405.300631 -137.638589)
			(xy 405.251031 -137.613088) (xy 405.205673 -137.580637) (xy 405.165524 -137.541928) (xy 405.131438 -137.497785)
			(xy 405.104142 -137.44915) (xy 405.084219 -137.397059) (xy 405.072093 -137.342622) (xy 405.068022 -137.287)
			(xy 393.209832 -137.287) (xy 393.212933 -137.290889) (xy 393.248227 -137.347058) (xy 393.27701 -137.406825)
			(xy 393.29892 -137.469439) (xy 393.313681 -137.534113) (xy 393.321108 -137.600033) (xy 393.32154 -137.633202)
			(xy 393.321095 -137.665493) (xy 393.314026 -137.729688) (xy 393.299995 -137.792728) (xy 393.279168 -137.853861)
			(xy 393.251796 -137.912356) (xy 393.218204 -137.967515) (xy 393.198858 -137.993374) (xy 393.193778 -138.000232)
			(xy 393.191238 -138.007344) (xy 393.189953 -138.011351) (xy 393.188544 -138.019647) (xy 393.188444 -138.023854)
			(xy 393.188444 -138.105388) (xy 393.188952 -138.108944) (xy 393.18946 -138.111992) (xy 393.190202 -138.117144)
			(xy 393.193523 -138.127007) (xy 393.196064 -138.13155) (xy 393.19835 -138.135106) (xy 393.201144 -138.139424)
			(xy 393.20216 -138.140694) (xy 393.206224 -138.146282) (xy 393.206732 -138.147298) (xy 393.22844 -138.177788)
			(xy 393.264813 -138.243204) (xy 393.292629 -138.312691) (xy 393.311442 -138.385137) (xy 393.320949 -138.459378)
			(xy 393.32154 -138.496802) (xy 393.321022 -138.532523) (xy 393.317186 -138.564112) (xy 394.991334 -138.564112)
			(xy 394.995405 -138.50849) (xy 395.007531 -138.454053) (xy 395.027454 -138.401962) (xy 395.05475 -138.353327)
			(xy 395.088836 -138.309184) (xy 395.128985 -138.270475) (xy 395.174343 -138.238024) (xy 395.223943 -138.212523)
			(xy 395.276727 -138.194516) (xy 395.33157 -138.184386) (xy 395.387304 -138.182349) (xy 395.442741 -138.188449)
			(xy 395.496698 -138.202555) (xy 395.548027 -138.224367) (xy 395.595633 -138.253421) (xy 395.638501 -138.289096)
			(xy 395.675718 -138.330633) (xy 395.706491 -138.377146) (xy 395.730163 -138.427643) (xy 395.746231 -138.48105)
			(xy 395.754351 -138.536226) (xy 395.75486 -138.564112) (xy 395.754351 -138.591998) (xy 395.746231 -138.647174)
			(xy 395.730163 -138.700581) (xy 395.706491 -138.751078) (xy 395.675718 -138.797591) (xy 395.638501 -138.839128)
			(xy 395.595633 -138.874803) (xy 395.548027 -138.903857) (xy 395.496698 -138.925669) (xy 395.442741 -138.939775)
			(xy 395.387304 -138.945875) (xy 395.33157 -138.943838) (xy 395.276727 -138.933708) (xy 395.223943 -138.915701)
			(xy 395.174343 -138.8902) (xy 395.128985 -138.857749) (xy 395.088836 -138.81904) (xy 395.05475 -138.774897)
			(xy 395.027454 -138.726262) (xy 395.007531 -138.674171) (xy 394.995405 -138.619734) (xy 394.991334 -138.564112)
			(xy 393.317186 -138.564112) (xy 393.31241 -138.603443) (xy 393.295313 -138.672808) (xy 393.269979 -138.739607)
			(xy 393.236778 -138.802864) (xy 393.196194 -138.861659) (xy 393.148818 -138.915133) (xy 393.101502 -138.95705)
			(xy 404.814532 -138.95705) (xy 404.815018 -138.929799) (xy 404.822774 -138.875851) (xy 404.838129 -138.823556)
			(xy 404.860771 -138.773979) (xy 404.890237 -138.728129) (xy 404.925928 -138.686938) (xy 404.967119 -138.651247)
			(xy 405.012969 -138.621781) (xy 405.062546 -138.599139) (xy 405.114841 -138.583784) (xy 405.168789 -138.576028)
			(xy 405.223291 -138.576028) (xy 405.277239 -138.583784) (xy 405.329534 -138.599139) (xy 405.379111 -138.621781)
			(xy 405.424961 -138.651247) (xy 405.466152 -138.686938) (xy 405.501843 -138.728129) (xy 405.531309 -138.773979)
			(xy 405.553951 -138.823556) (xy 405.569306 -138.875851) (xy 405.577062 -138.929799) (xy 405.577548 -138.95705)
			(xy 405.577051 -138.98483) (xy 405.568978 -139.039801) (xy 405.553008 -139.093017) (xy 405.529482 -139.143351)
			(xy 405.498897 -139.189735) (xy 405.480774 -139.210796) (xy 405.48052 -139.21105) (xy 405.474217 -139.218931)
			(xy 405.467799 -139.238047) (xy 405.468074 -139.248134) (xy 405.473408 -139.321286) (xy 405.474577 -139.331363)
			(xy 405.48375 -139.349439) (xy 405.491188 -139.356338) (xy 405.491442 -139.356592) (xy 405.512467 -139.374801)
			(xy 405.549506 -139.416293) (xy 405.580134 -139.462721) (xy 405.603702 -139.5131) (xy 405.619711 -139.566366)
			(xy 405.627824 -139.621391) (xy 405.628348 -139.6492) (xy 405.627862 -139.676451) (xy 405.620106 -139.730399)
			(xy 405.604751 -139.782694) (xy 405.582109 -139.832271) (xy 405.552643 -139.878121) (xy 405.516952 -139.919312)
			(xy 405.475761 -139.955003) (xy 405.429911 -139.984469) (xy 405.380334 -140.007111) (xy 405.328039 -140.022466)
			(xy 405.274091 -140.030222) (xy 405.219589 -140.030222) (xy 405.165641 -140.022466) (xy 405.113346 -140.007111)
			(xy 405.063769 -139.984469) (xy 405.017919 -139.955003) (xy 404.976728 -139.919312) (xy 404.941037 -139.878121)
			(xy 404.911571 -139.832271) (xy 404.888929 -139.782694) (xy 404.873574 -139.730399) (xy 404.865818 -139.676451)
			(xy 404.865332 -139.6492) (xy 404.865864 -139.621421) (xy 404.87393 -139.566452) (xy 404.889891 -139.513237)
			(xy 404.91341 -139.462903) (xy 404.943987 -139.416516) (xy 404.962106 -139.395454) (xy 404.96236 -139.3952)
			(xy 404.968685 -139.387334) (xy 404.97509 -139.368207) (xy 404.974806 -139.358116) (xy 404.969472 -139.284964)
			(xy 404.968333 -139.274881) (xy 404.95914 -139.256806) (xy 404.951692 -139.249912) (xy 404.951438 -139.249658)
			(xy 404.930433 -139.231427) (xy 404.893393 -139.189939) (xy 404.862764 -139.143516) (xy 404.839192 -139.093141)
			(xy 404.823178 -139.039879) (xy 404.81506 -138.984858) (xy 404.814532 -138.95705) (xy 393.101502 -138.95705)
			(xy 393.095343 -138.962506) (xy 393.036547 -139.003088) (xy 392.973288 -139.036287) (xy 392.906489 -139.061619)
			(xy 392.837123 -139.078714) (xy 392.766203 -139.087323) (xy 392.730482 -139.08786) (xy 392.697321 -139.087378)
			(xy 392.631418 -139.079921) (xy 392.566764 -139.065135) (xy 392.504171 -139.043207) (xy 392.444425 -139.014412)
			(xy 392.388277 -138.979112) (xy 392.336432 -138.93775) (xy 392.312652 -138.914632) (xy 392.213084 -138.815318)
			(xy 392.20942 -138.811804) (xy 392.20097 -138.80618) (xy 392.19632 -138.804142) (xy 392.188192 -138.80084)
			(xy 390.40816 -138.80084) (xy 390.39927 -138.807952) (xy 388.641844 -140.565378) (xy 391.889742 -140.565378)
			(xy 391.890185 -140.538007) (xy 391.898007 -140.483826) (xy 391.913501 -140.431323) (xy 391.936348 -140.381576)
			(xy 391.966078 -140.335611) (xy 391.983722 -140.31468) (xy 391.983976 -140.314426) (xy 391.989567 -140.307343)
			(xy 391.995809 -140.290423) (xy 391.996168 -140.281406) (xy 391.996168 -140.21435) (xy 391.995794 -140.205335)
			(xy 391.989559 -140.188417) (xy 391.983976 -140.18133) (xy 391.983722 -140.18133) (xy 391.983722 -140.181076)
			(xy 391.966108 -140.160123) (xy 391.936392 -140.114156) (xy 391.913551 -140.064414) (xy 391.898054 -140.011918)
			(xy 391.890219 -139.957746) (xy 391.889742 -139.930378) (xy 391.890135 -139.903122) (xy 391.897896 -139.849166)
			(xy 391.913257 -139.796864) (xy 391.935906 -139.74728) (xy 391.965381 -139.701425) (xy 392.001082 -139.660231)
			(xy 392.042283 -139.624538) (xy 392.088144 -139.595071) (xy 392.137731 -139.572432) (xy 392.190037 -139.55708)
			(xy 392.243994 -139.549329) (xy 392.27125 -139.54887) (xy 392.29862 -139.549348) (xy 392.352799 -139.557161)
			(xy 392.405303 -139.572646) (xy 392.45505 -139.595485) (xy 392.501017 -139.625209) (xy 392.521948 -139.64285)
			(xy 392.522202 -139.643104) (xy 392.529283 -139.648698) (xy 392.546204 -139.65494) (xy 392.555222 -139.655296)
			(xy 392.622278 -139.655296) (xy 392.631294 -139.654929) (xy 392.648211 -139.648689) (xy 392.655298 -139.643104)
			(xy 392.655298 -139.64285) (xy 392.655552 -139.64285) (xy 392.676498 -139.625228) (xy 392.722466 -139.595512)
			(xy 392.77221 -139.572672) (xy 392.824708 -139.557177) (xy 392.878882 -139.549345) (xy 392.90625 -139.54887)
			(xy 392.933501 -139.549402) (xy 392.987448 -139.557151) (xy 393.039743 -139.5725) (xy 393.089322 -139.595135)
			(xy 393.135174 -139.624596) (xy 393.176367 -139.660282) (xy 393.212061 -139.701468) (xy 393.24153 -139.747315)
			(xy 393.264175 -139.796889) (xy 393.279533 -139.849182) (xy 393.287293 -139.903127) (xy 393.287758 -139.930378)
			(xy 393.287289 -139.957748) (xy 393.279474 -140.011928) (xy 393.263986 -140.064431) (xy 393.241144 -140.114178)
			(xy 393.21142 -140.160145) (xy 393.193778 -140.181076) (xy 393.193524 -140.18133) (xy 393.187952 -140.188426)
			(xy 393.181698 -140.205336) (xy 393.181332 -140.21435) (xy 393.181332 -140.281406) (xy 393.181679 -140.290424)
			(xy 393.187933 -140.307341) (xy 393.193524 -140.314426) (xy 393.193778 -140.314426) (xy 393.193778 -140.31468)
			(xy 393.211418 -140.335612) (xy 393.24113 -140.381584) (xy 393.263966 -140.431332) (xy 393.279457 -140.483833)
			(xy 393.287285 -140.538009) (xy 393.287758 -140.565378) (xy 393.287324 -140.592633) (xy 393.279569 -140.646587)
			(xy 393.264213 -140.698889) (xy 393.242363 -140.746734) (xy 400.39493 -140.746734) (xy 400.399001 -140.691112)
			(xy 400.411127 -140.636675) (xy 400.43105 -140.584584) (xy 400.458346 -140.535949) (xy 400.492432 -140.491806)
			(xy 400.532581 -140.453097) (xy 400.577939 -140.420646) (xy 400.627539 -140.395145) (xy 400.680323 -140.377138)
			(xy 400.735166 -140.367008) (xy 400.7909 -140.364971) (xy 400.846337 -140.371071) (xy 400.900294 -140.385177)
			(xy 400.951623 -140.406989) (xy 400.999229 -140.436043) (xy 401.042097 -140.471718) (xy 401.079314 -140.513255)
			(xy 401.110087 -140.559768) (xy 401.133759 -140.610265) (xy 401.149827 -140.663672) (xy 401.157947 -140.718848)
			(xy 401.158456 -140.746734) (xy 401.157947 -140.77462) (xy 401.149827 -140.829796) (xy 401.133759 -140.883203)
			(xy 401.110087 -140.9337) (xy 401.079314 -140.980213) (xy 401.042097 -141.02175) (xy 400.999229 -141.057425)
			(xy 400.951623 -141.086479) (xy 400.900294 -141.108291) (xy 400.846337 -141.122397) (xy 400.7909 -141.128497)
			(xy 400.735166 -141.12646) (xy 400.680323 -141.11633) (xy 400.627539 -141.098323) (xy 400.577939 -141.072822)
			(xy 400.532581 -141.040371) (xy 400.492432 -141.001662) (xy 400.458346 -140.957519) (xy 400.43105 -140.908884)
			(xy 400.411127 -140.856793) (xy 400.399001 -140.802356) (xy 400.39493 -140.746734) (xy 393.242363 -140.746734)
			(xy 393.241569 -140.748472) (xy 393.212099 -140.794328) (xy 393.176402 -140.835522) (xy 393.135205 -140.871216)
			(xy 393.089347 -140.900683) (xy 393.039762 -140.923323) (xy 392.98746 -140.938675) (xy 392.933505 -140.946426)
			(xy 392.90625 -140.946886) (xy 392.878881 -140.946394) (xy 392.824703 -140.938583) (xy 392.7722 -140.9231)
			(xy 392.722452 -140.900264) (xy 392.676484 -140.870545) (xy 392.655552 -140.852906) (xy 392.655298 -140.852652)
			(xy 392.64822 -140.847053) (xy 392.631297 -140.840815) (xy 392.622278 -140.84046) (xy 392.555222 -140.84046)
			(xy 392.546205 -140.840815) (xy 392.529287 -140.847062) (xy 392.522202 -140.852652) (xy 392.522202 -140.852906)
			(xy 392.521948 -140.852906) (xy 392.501009 -140.870537) (xy 392.455038 -140.90025) (xy 392.405292 -140.923087)
			(xy 392.352793 -140.93858) (xy 392.298619 -140.946411) (xy 392.27125 -140.946886) (xy 392.243997 -140.946398)
			(xy 392.190046 -140.938647) (xy 392.137747 -140.923297) (xy 392.088166 -140.900658) (xy 392.042312 -140.871193)
			(xy 392.001118 -140.835502) (xy 391.965423 -140.794311) (xy 391.935955 -140.748459) (xy 391.913313 -140.698879)
			(xy 391.897959 -140.646581) (xy 391.890204 -140.592631) (xy 391.889742 -140.565378) (xy 388.641844 -140.565378)
			(xy 386.931916 -142.275306) (xy 386.924804 -142.284196) (xy 386.924804 -142.60068) (xy 399.905728 -142.60068)
			(xy 399.906192 -142.573275) (xy 399.914043 -142.519031) (xy 399.92958 -142.466469) (xy 399.952483 -142.416674)
			(xy 399.982281 -142.370671) (xy 399.999962 -142.349728) (xy 400.000216 -142.349474) (xy 400.00578 -142.342372)
			(xy 400.01204 -142.325467) (xy 400.012408 -142.316454) (xy 400.012408 -142.249144) (xy 400.012028 -142.240129)
			(xy 400.005796 -142.223212) (xy 400.000216 -142.216124) (xy 399.999708 -142.215616) (xy 399.982064 -142.194688)
			(xy 399.952353 -142.148714) (xy 399.929518 -142.098966) (xy 399.914028 -142.046464) (xy 399.906201 -141.992287)
			(xy 399.905728 -141.964918) (xy 399.906214 -141.937667) (xy 399.91397 -141.883719) (xy 399.929325 -141.831424)
			(xy 399.951967 -141.781847) (xy 399.981433 -141.735997) (xy 400.017124 -141.694806) (xy 400.058315 -141.659115)
			(xy 400.104165 -141.629649) (xy 400.153742 -141.607007) (xy 400.206037 -141.591652) (xy 400.259985 -141.583896)
			(xy 400.314487 -141.583896) (xy 400.368435 -141.591652) (xy 400.42073 -141.607007) (xy 400.470307 -141.629649)
			(xy 400.516157 -141.659115) (xy 400.557348 -141.694806) (xy 400.593039 -141.735997) (xy 400.622505 -141.781847)
			(xy 400.645147 -141.831424) (xy 400.660502 -141.883719) (xy 400.667903 -141.9352) (xy 404.824182 -141.9352)
			(xy 404.828253 -141.879578) (xy 404.840379 -141.825141) (xy 404.860302 -141.77305) (xy 404.887598 -141.724415)
			(xy 404.921684 -141.680272) (xy 404.961833 -141.641563) (xy 405.007191 -141.609112) (xy 405.056791 -141.583611)
			(xy 405.109575 -141.565604) (xy 405.164418 -141.555474) (xy 405.220152 -141.553437) (xy 405.275589 -141.559537)
			(xy 405.329546 -141.573643) (xy 405.380875 -141.595455) (xy 405.428481 -141.624509) (xy 405.471349 -141.660184)
			(xy 405.508566 -141.701721) (xy 405.539339 -141.748234) (xy 405.563011 -141.798731) (xy 405.579079 -141.852138)
			(xy 405.587199 -141.907314) (xy 405.587708 -141.9352) (xy 405.587199 -141.963086) (xy 405.579079 -142.018262)
			(xy 405.563011 -142.071669) (xy 405.539339 -142.122166) (xy 405.508566 -142.168679) (xy 405.471349 -142.210216)
			(xy 405.428481 -142.245891) (xy 405.380875 -142.274945) (xy 405.329546 -142.296757) (xy 405.275589 -142.310863)
			(xy 405.220152 -142.316963) (xy 405.164418 -142.314926) (xy 405.109575 -142.304796) (xy 405.056791 -142.286789)
			(xy 405.007191 -142.261288) (xy 404.961833 -142.228837) (xy 404.921684 -142.190128) (xy 404.887598 -142.145985)
			(xy 404.860302 -142.09735) (xy 404.840379 -142.045259) (xy 404.828253 -141.990822) (xy 404.824182 -141.9352)
			(xy 400.667903 -141.9352) (xy 400.668258 -141.937667) (xy 400.668744 -141.964918) (xy 400.668286 -141.992323)
			(xy 400.660434 -142.046568) (xy 400.644896 -142.09913) (xy 400.621992 -142.148925) (xy 400.592192 -142.194927)
			(xy 400.57451 -142.21587) (xy 400.574256 -142.216124) (xy 400.568648 -142.223196) (xy 400.562415 -142.240124)
			(xy 400.562064 -142.249144) (xy 400.562064 -142.316454) (xy 400.562451 -142.325468) (xy 400.568679 -142.342384)
			(xy 400.574256 -142.349474) (xy 400.574764 -142.349982) (xy 400.592403 -142.370915) (xy 400.622116 -142.416887)
			(xy 400.644952 -142.466634) (xy 400.660443 -142.519135) (xy 400.668271 -142.573311) (xy 400.668744 -142.60068)
			(xy 400.668258 -142.627931) (xy 400.660502 -142.681879) (xy 400.645147 -142.734174) (xy 400.622505 -142.783751)
			(xy 400.593039 -142.829601) (xy 400.557348 -142.870792) (xy 400.516157 -142.906483) (xy 400.470307 -142.935949)
			(xy 400.436913 -142.9512) (xy 404.840438 -142.9512) (xy 404.844509 -142.895578) (xy 404.856635 -142.841141)
			(xy 404.876558 -142.78905) (xy 404.903854 -142.740415) (xy 404.93794 -142.696272) (xy 404.978089 -142.657563)
			(xy 405.023447 -142.625112) (xy 405.073047 -142.599611) (xy 405.125831 -142.581604) (xy 405.180674 -142.571474)
			(xy 405.236408 -142.569437) (xy 405.291845 -142.575537) (xy 405.345802 -142.589643) (xy 405.397131 -142.611455)
			(xy 405.444737 -142.640509) (xy 405.487605 -142.676184) (xy 405.524822 -142.717721) (xy 405.555595 -142.764234)
			(xy 405.579267 -142.814731) (xy 405.595335 -142.868138) (xy 405.603455 -142.923314) (xy 405.603964 -142.9512)
			(xy 405.603455 -142.979086) (xy 405.595335 -143.034262) (xy 405.579267 -143.087669) (xy 405.555595 -143.138166)
			(xy 405.524822 -143.184679) (xy 405.487605 -143.226216) (xy 405.444737 -143.261891) (xy 405.397131 -143.290945)
			(xy 405.345802 -143.312757) (xy 405.291845 -143.326863) (xy 405.236408 -143.332963) (xy 405.180674 -143.330926)
			(xy 405.125831 -143.320796) (xy 405.073047 -143.302789) (xy 405.023447 -143.277288) (xy 404.978089 -143.244837)
			(xy 404.93794 -143.206128) (xy 404.903854 -143.161985) (xy 404.876558 -143.11335) (xy 404.856635 -143.061259)
			(xy 404.844509 -143.006822) (xy 404.840438 -142.9512) (xy 400.436913 -142.9512) (xy 400.42073 -142.958591)
			(xy 400.368435 -142.973946) (xy 400.314487 -142.981702) (xy 400.259985 -142.981702) (xy 400.206037 -142.973946)
			(xy 400.153742 -142.958591) (xy 400.104165 -142.935949) (xy 400.058315 -142.906483) (xy 400.017124 -142.870792)
			(xy 399.981433 -142.829601) (xy 399.951967 -142.783751) (xy 399.929325 -142.734174) (xy 399.91397 -142.681879)
			(xy 399.906214 -142.627931) (xy 399.905728 -142.60068) (xy 386.924804 -142.60068) (xy 386.924804 -145.329148)
			(xy 391.465308 -145.329148) (xy 391.465774 -145.302766) (xy 391.473059 -145.250508) (xy 391.487469 -145.19975)
			(xy 391.50873 -145.151459) (xy 391.536436 -145.106555) (xy 391.57006 -145.065893) (xy 391.608963 -145.030247)
			(xy 391.652402 -145.000297) (xy 391.699551 -144.976611) (xy 391.724388 -144.967706) (xy 391.733278 -144.964658)
			(xy 391.747756 -144.95272) (xy 391.790428 -144.87652) (xy 391.792968 -144.857724) (xy 391.790682 -144.84858)
			(xy 391.786023 -144.827167) (xy 391.781055 -144.783625) (xy 391.780776 -144.761712) (xy 391.781289 -144.734462)
			(xy 391.789044 -144.680516) (xy 391.804397 -144.628223) (xy 391.827035 -144.578647) (xy 391.856499 -144.532797)
			(xy 391.892187 -144.491607) (xy 391.933375 -144.455915) (xy 391.979222 -144.426449) (xy 392.028796 -144.403806)
			(xy 392.081089 -144.38845) (xy 392.135034 -144.380691) (xy 392.162284 -144.380204) (xy 392.174255 -144.38032)
			(xy 392.198148 -144.381842) (xy 392.210036 -144.383252) (xy 392.21029 -144.383252) (xy 392.219464 -144.38396)
			(xy 392.237307 -144.379527) (xy 392.245088 -144.374616) (xy 392.301222 -144.3355) (xy 392.308628 -144.329917)
			(xy 392.319176 -144.314679) (xy 392.321796 -144.305782) (xy 392.321796 -144.305528) (xy 392.328784 -144.277975)
			(xy 392.349819 -144.225168) (xy 392.378459 -144.176068) (xy 392.414069 -144.131763) (xy 392.455861 -144.093235)
			(xy 392.502909 -144.061337) (xy 392.55417 -144.036775) (xy 392.60851 -144.020094) (xy 392.664723 -144.011663)
			(xy 392.693144 -144.011142) (xy 392.717815 -144.011556) (xy 392.766741 -144.017956) (xy 392.814436 -144.030605)
			(xy 392.837416 -144.03959) (xy 392.848519 -144.043492) (xy 392.871961 -144.041772) (xy 392.882374 -144.036288)
			(xy 392.952224 -143.994632) (xy 392.961999 -143.988158) (xy 392.974853 -143.968588) (xy 392.976862 -143.95704)
			(xy 392.976862 -143.956532) (xy 392.980573 -143.928978) (xy 392.994833 -143.875245) (xy 393.016745 -143.824151)
			(xy 393.045843 -143.776781) (xy 393.081511 -143.734138) (xy 393.122993 -143.697125) (xy 393.16941 -143.666529)
			(xy 393.219777 -143.642996) (xy 393.273028 -143.627027) (xy 393.328033 -143.618959) (xy 393.35583 -143.618458)
			(xy 393.38308 -143.61895) (xy 393.437026 -143.62671) (xy 393.489319 -143.642067) (xy 393.538894 -143.664709)
			(xy 393.584742 -143.694175) (xy 393.625931 -143.729866) (xy 393.661622 -143.771054) (xy 393.691089 -143.816903)
			(xy 393.713732 -143.866478) (xy 393.72909 -143.91877) (xy 393.73685 -143.972716) (xy 393.737338 -143.999966)
			(xy 393.736862 -144.026547) (xy 393.72948 -144.079193) (xy 393.714855 -144.130303) (xy 393.693271 -144.178885)
			(xy 393.665146 -144.223998) (xy 393.631026 -144.264764) (xy 393.623288 -144.272) (xy 404.687022 -144.272)
			(xy 404.691093 -144.216378) (xy 404.703219 -144.161941) (xy 404.723142 -144.10985) (xy 404.750438 -144.061215)
			(xy 404.784524 -144.017072) (xy 404.824673 -143.978363) (xy 404.870031 -143.945912) (xy 404.919631 -143.920411)
			(xy 404.972415 -143.902404) (xy 405.027258 -143.892274) (xy 405.082992 -143.890237) (xy 405.138429 -143.896337)
			(xy 405.192386 -143.910443) (xy 405.243715 -143.932255) (xy 405.291321 -143.961309) (xy 405.334189 -143.996984)
			(xy 405.371406 -144.038521) (xy 405.402179 -144.085034) (xy 405.425851 -144.135531) (xy 405.441919 -144.188938)
			(xy 405.450039 -144.244114) (xy 405.450548 -144.272) (xy 405.450039 -144.299886) (xy 405.441919 -144.355062)
			(xy 405.425851 -144.408469) (xy 405.402179 -144.458966) (xy 405.371406 -144.505479) (xy 405.334189 -144.547016)
			(xy 405.291321 -144.582691) (xy 405.243715 -144.611745) (xy 405.192386 -144.633557) (xy 405.138429 -144.647663)
			(xy 405.082992 -144.653763) (xy 405.027258 -144.651726) (xy 404.972415 -144.641596) (xy 404.919631 -144.623589)
			(xy 404.870031 -144.598088) (xy 404.824673 -144.565637) (xy 404.784524 -144.526928) (xy 404.750438 -144.482785)
			(xy 404.723142 -144.43415) (xy 404.703219 -144.382059) (xy 404.691093 -144.327622) (xy 404.687022 -144.272)
			(xy 393.623288 -144.272) (xy 393.611608 -144.282922) (xy 393.605009 -144.289389) (xy 393.59655 -144.305801)
			(xy 393.595098 -144.314926) (xy 393.587732 -144.381474) (xy 393.586984 -144.39065) (xy 393.591429 -144.408501)
			(xy 393.596368 -144.416272) (xy 393.612484 -144.440397) (xy 393.638018 -144.492491) (xy 393.655375 -144.547849)
			(xy 393.664154 -144.605196) (xy 393.664694 -144.634204) (xy 393.664248 -144.661458) (xy 393.65649 -144.71541)
			(xy 393.641133 -144.767709) (xy 393.618489 -144.81729) (xy 393.58902 -144.863144) (xy 393.553324 -144.904337)
			(xy 393.512129 -144.94003) (xy 393.466274 -144.969498) (xy 393.416692 -144.99214) (xy 393.364392 -145.007494)
			(xy 393.31044 -145.01525) (xy 393.283186 -145.015712) (xy 393.282678 -145.015712) (xy 393.272881 -145.015648)
			(xy 393.253313 -145.014631) (xy 393.243562 -145.01368) (xy 393.243308 -145.01368) (xy 393.233918 -145.013063)
			(xy 393.21578 -145.018034) (xy 393.208002 -145.023332) (xy 393.14501 -145.070068) (xy 393.135104 -145.08607)
			(xy 393.133326 -145.095722) (xy 393.127934 -145.12156) (xy 393.111003 -145.171551) (xy 393.087342 -145.218731)
			(xy 393.057405 -145.2622) (xy 393.021762 -145.301128) (xy 392.981094 -145.334771) (xy 392.936177 -145.362489)
			(xy 392.887869 -145.38375) (xy 392.837091 -145.398151) (xy 392.784812 -145.405415) (xy 392.758422 -145.405856)
			(xy 392.72948 -145.405362) (xy 392.67226 -145.396621) (xy 392.617017 -145.379335) (xy 392.56502 -145.353903)
			(xy 392.517461 -145.320908) (xy 392.475433 -145.281106) (xy 392.4399 -145.235412) (xy 392.411678 -145.184875)
			(xy 392.401044 -145.157952) (xy 392.397063 -145.148552) (xy 392.38303 -145.133749) (xy 392.373866 -145.12925)
			(xy 392.344656 -145.116296) (xy 392.335072 -145.112517) (xy 392.314495 -145.112114) (xy 392.304778 -145.115534)
			(xy 392.284712 -145.123154) (xy 392.275822 -145.126202) (xy 392.261344 -145.13814) (xy 392.218672 -145.21434)
			(xy 392.216132 -145.233136) (xy 392.218418 -145.24228) (xy 392.223087 -145.263691) (xy 392.228049 -145.307235)
			(xy 392.228324 -145.329148) (xy 392.227838 -145.356399) (xy 392.220082 -145.410347) (xy 392.204727 -145.462642)
			(xy 392.182085 -145.512219) (xy 392.152619 -145.558069) (xy 392.116928 -145.59926) (xy 392.075737 -145.634951)
			(xy 392.029887 -145.664417) (xy 391.98031 -145.687059) (xy 391.928015 -145.702414) (xy 391.874067 -145.71017)
			(xy 391.819565 -145.71017) (xy 391.765617 -145.702414) (xy 391.713322 -145.687059) (xy 391.663745 -145.664417)
			(xy 391.617895 -145.634951) (xy 391.576704 -145.59926) (xy 391.541013 -145.558069) (xy 391.511547 -145.512219)
			(xy 391.488905 -145.462642) (xy 391.47355 -145.410347) (xy 391.465794 -145.356399) (xy 391.465308 -145.329148)
			(xy 386.924804 -145.329148) (xy 386.924804 -146.19732) (xy 386.92455 -146.209004) (xy 386.92455 -146.421348)
			(xy 386.924427 -146.426302) (xy 386.922501 -146.43602) (xy 386.92074 -146.440652) (xy 386.91693 -146.45005)
			(xy 386.91693 -146.51863) (xy 386.916388 -146.528616) (xy 386.90867 -146.547043) (xy 386.901944 -146.554444)
			(xy 386.716529 -146.739864) (xy 397.210024 -146.739864) (xy 397.214095 -146.684242) (xy 397.226221 -146.629805)
			(xy 397.246144 -146.577714) (xy 397.27344 -146.529079) (xy 397.307526 -146.484936) (xy 397.347675 -146.446227)
			(xy 397.393033 -146.413776) (xy 397.442633 -146.388275) (xy 397.495417 -146.370268) (xy 397.55026 -146.360138)
			(xy 397.605994 -146.358101) (xy 397.661431 -146.364201) (xy 397.715388 -146.378307) (xy 397.766717 -146.400119)
			(xy 397.814323 -146.429173) (xy 397.857191 -146.464848) (xy 397.894408 -146.506385) (xy 397.925181 -146.552898)
			(xy 397.948853 -146.603395) (xy 397.964921 -146.656802) (xy 397.973041 -146.711978) (xy 397.97355 -146.739864)
			(xy 397.973041 -146.76775) (xy 397.968884 -146.795998) (xy 398.843752 -146.795998) (xy 398.847823 -146.740376)
			(xy 398.859949 -146.685939) (xy 398.879872 -146.633848) (xy 398.907168 -146.585213) (xy 398.941254 -146.54107)
			(xy 398.981403 -146.502361) (xy 399.026761 -146.46991) (xy 399.076361 -146.444409) (xy 399.129145 -146.426402)
			(xy 399.183988 -146.416272) (xy 399.239722 -146.414235) (xy 399.295159 -146.420335) (xy 399.349116 -146.434441)
			(xy 399.400445 -146.456253) (xy 399.448051 -146.485307) (xy 399.490919 -146.520982) (xy 399.528136 -146.562519)
			(xy 399.558909 -146.609032) (xy 399.582581 -146.659529) (xy 399.598649 -146.712936) (xy 399.606769 -146.768112)
			(xy 399.607278 -146.795998) (xy 399.606769 -146.823884) (xy 399.598649 -146.87906) (xy 399.582581 -146.932467)
			(xy 399.558909 -146.982964) (xy 399.528136 -147.029477) (xy 399.490919 -147.071014) (xy 399.448051 -147.106689)
			(xy 399.400445 -147.135743) (xy 399.349116 -147.157555) (xy 399.295159 -147.171661) (xy 399.239722 -147.177761)
			(xy 399.183988 -147.175724) (xy 399.129145 -147.165594) (xy 399.076361 -147.147587) (xy 399.026761 -147.122086)
			(xy 398.981403 -147.089635) (xy 398.941254 -147.050926) (xy 398.907168 -147.006783) (xy 398.879872 -146.958148)
			(xy 398.859949 -146.906057) (xy 398.847823 -146.85162) (xy 398.843752 -146.795998) (xy 397.968884 -146.795998)
			(xy 397.964921 -146.822926) (xy 397.948853 -146.876333) (xy 397.925181 -146.92683) (xy 397.894408 -146.973343)
			(xy 397.857191 -147.01488) (xy 397.814323 -147.050555) (xy 397.766717 -147.079609) (xy 397.715388 -147.101421)
			(xy 397.661431 -147.115527) (xy 397.605994 -147.121627) (xy 397.55026 -147.11959) (xy 397.495417 -147.10946)
			(xy 397.442633 -147.091453) (xy 397.393033 -147.065952) (xy 397.347675 -147.033501) (xy 397.307526 -146.994792)
			(xy 397.27344 -146.950649) (xy 397.246144 -146.902014) (xy 397.226221 -146.849923) (xy 397.214095 -146.795486)
			(xy 397.210024 -146.739864) (xy 386.716529 -146.739864) (xy 382.199513 -151.257) (xy 400.877022 -151.257)
			(xy 400.881093 -151.201378) (xy 400.893219 -151.146941) (xy 400.913142 -151.09485) (xy 400.940438 -151.046215)
			(xy 400.974524 -151.002072) (xy 401.014673 -150.963363) (xy 401.060031 -150.930912) (xy 401.109631 -150.905411)
			(xy 401.162415 -150.887404) (xy 401.217258 -150.877274) (xy 401.272992 -150.875237) (xy 401.328429 -150.881337)
			(xy 401.382386 -150.895443) (xy 401.433715 -150.917255) (xy 401.481321 -150.946309) (xy 401.524189 -150.981984)
			(xy 401.561406 -151.023521) (xy 401.592179 -151.070034) (xy 401.615851 -151.120531) (xy 401.631919 -151.173938)
			(xy 401.640039 -151.229114) (xy 401.640548 -151.257) (xy 401.640039 -151.284886) (xy 401.631919 -151.340062)
			(xy 401.615851 -151.393469) (xy 401.592179 -151.443966) (xy 401.561406 -151.490479) (xy 401.524189 -151.532016)
			(xy 401.481321 -151.567691) (xy 401.433715 -151.596745) (xy 401.382386 -151.618557) (xy 401.328429 -151.632663)
			(xy 401.272992 -151.638763) (xy 401.217258 -151.636726) (xy 401.162415 -151.626596) (xy 401.109631 -151.608589)
			(xy 401.060031 -151.583088) (xy 401.014673 -151.550637) (xy 400.974524 -151.511928) (xy 400.940438 -151.467785)
			(xy 400.913142 -151.41915) (xy 400.893219 -151.367059) (xy 400.881093 -151.312622) (xy 400.877022 -151.257)
			(xy 382.199513 -151.257) (xy 380.142167 -153.3144) (xy 385.490972 -153.3144) (xy 385.495043 -153.258778)
			(xy 385.507169 -153.204341) (xy 385.527092 -153.15225) (xy 385.554388 -153.103615) (xy 385.588474 -153.059472)
			(xy 385.628623 -153.020763) (xy 385.673981 -152.988312) (xy 385.723581 -152.962811) (xy 385.776365 -152.944804)
			(xy 385.831208 -152.934674) (xy 385.886942 -152.932637) (xy 385.942379 -152.938737) (xy 385.996336 -152.952843)
			(xy 386.047665 -152.974655) (xy 386.095271 -153.003709) (xy 386.138139 -153.039384) (xy 386.175356 -153.080921)
			(xy 386.206129 -153.127434) (xy 386.229801 -153.177931) (xy 386.245869 -153.231338) (xy 386.253989 -153.286514)
			(xy 386.254498 -153.3144) (xy 386.253989 -153.342286) (xy 386.245869 -153.397462) (xy 386.229801 -153.450869)
			(xy 386.206129 -153.501366) (xy 386.175356 -153.547879) (xy 386.16448 -153.560018) (xy 400.750022 -153.560018)
			(xy 400.754093 -153.504396) (xy 400.766219 -153.449959) (xy 400.786142 -153.397868) (xy 400.813438 -153.349233)
			(xy 400.847524 -153.30509) (xy 400.887673 -153.266381) (xy 400.933031 -153.23393) (xy 400.982631 -153.208429)
			(xy 401.035415 -153.190422) (xy 401.090258 -153.180292) (xy 401.145992 -153.178255) (xy 401.201429 -153.184355)
			(xy 401.255386 -153.198461) (xy 401.306715 -153.220273) (xy 401.354321 -153.249327) (xy 401.397189 -153.285002)
			(xy 401.434406 -153.326539) (xy 401.465179 -153.373052) (xy 401.488851 -153.423549) (xy 401.504919 -153.476956)
			(xy 401.513039 -153.532132) (xy 401.513548 -153.560018) (xy 401.513039 -153.587904) (xy 401.504919 -153.64308)
			(xy 401.488851 -153.696487) (xy 401.465179 -153.746984) (xy 401.434406 -153.793497) (xy 401.397189 -153.835034)
			(xy 401.354321 -153.870709) (xy 401.306715 -153.899763) (xy 401.255386 -153.921575) (xy 401.201429 -153.935681)
			(xy 401.145992 -153.941781) (xy 401.090258 -153.939744) (xy 401.035415 -153.929614) (xy 400.982631 -153.911607)
			(xy 400.933031 -153.886106) (xy 400.887673 -153.853655) (xy 400.847524 -153.814946) (xy 400.813438 -153.770803)
			(xy 400.786142 -153.722168) (xy 400.766219 -153.670077) (xy 400.754093 -153.61564) (xy 400.750022 -153.560018)
			(xy 386.16448 -153.560018) (xy 386.138139 -153.589416) (xy 386.095271 -153.625091) (xy 386.047665 -153.654145)
			(xy 385.996336 -153.675957) (xy 385.942379 -153.690063) (xy 385.886942 -153.696163) (xy 385.831208 -153.694126)
			(xy 385.776365 -153.683996) (xy 385.723581 -153.665989) (xy 385.673981 -153.640488) (xy 385.628623 -153.608037)
			(xy 385.588474 -153.569328) (xy 385.554388 -153.525185) (xy 385.527092 -153.47655) (xy 385.507169 -153.424459)
			(xy 385.495043 -153.370022) (xy 385.490972 -153.3144) (xy 380.142167 -153.3144) (xy 379.296624 -154.159966)
			(xy 399.607022 -154.159966) (xy 399.611093 -154.104344) (xy 399.623219 -154.049907) (xy 399.643142 -153.997816)
			(xy 399.670438 -153.949181) (xy 399.704524 -153.905038) (xy 399.744673 -153.866329) (xy 399.790031 -153.833878)
			(xy 399.839631 -153.808377) (xy 399.892415 -153.79037) (xy 399.947258 -153.78024) (xy 400.002992 -153.778203)
			(xy 400.058429 -153.784303) (xy 400.112386 -153.798409) (xy 400.163715 -153.820221) (xy 400.211321 -153.849275)
			(xy 400.254189 -153.88495) (xy 400.291406 -153.926487) (xy 400.322179 -153.973) (xy 400.345851 -154.023497)
			(xy 400.361919 -154.076904) (xy 400.370039 -154.13208) (xy 400.370548 -154.159966) (xy 400.370039 -154.187852)
			(xy 400.361919 -154.243028) (xy 400.345851 -154.296435) (xy 400.322179 -154.346932) (xy 400.291406 -154.393445)
			(xy 400.254189 -154.434982) (xy 400.211321 -154.470657) (xy 400.163715 -154.499711) (xy 400.112386 -154.521523)
			(xy 400.058429 -154.535629) (xy 400.002992 -154.541729) (xy 399.947258 -154.539692) (xy 399.892415 -154.529562)
			(xy 399.839631 -154.511555) (xy 399.790031 -154.486054) (xy 399.744673 -154.453603) (xy 399.704524 -154.414894)
			(xy 399.670438 -154.370751) (xy 399.643142 -154.322116) (xy 399.623219 -154.270025) (xy 399.611093 -154.215588)
			(xy 399.607022 -154.159966) (xy 379.296624 -154.159966) (xy 378.415013 -155.0416) (xy 396.463772 -155.0416)
			(xy 396.467843 -154.985978) (xy 396.479969 -154.931541) (xy 396.499892 -154.87945) (xy 396.527188 -154.830815)
			(xy 396.561274 -154.786672) (xy 396.601423 -154.747963) (xy 396.646781 -154.715512) (xy 396.696381 -154.690011)
			(xy 396.749165 -154.672004) (xy 396.804008 -154.661874) (xy 396.859742 -154.659837) (xy 396.915179 -154.665937)
			(xy 396.969136 -154.680043) (xy 397.020465 -154.701855) (xy 397.068071 -154.730909) (xy 397.110939 -154.766584)
			(xy 397.148156 -154.808121) (xy 397.178929 -154.854634) (xy 397.202601 -154.905131) (xy 397.218594 -154.958288)
			(xy 401.044154 -154.958288) (xy 401.048225 -154.902666) (xy 401.060351 -154.848229) (xy 401.080274 -154.796138)
			(xy 401.10757 -154.747503) (xy 401.141656 -154.70336) (xy 401.181805 -154.664651) (xy 401.227163 -154.6322)
			(xy 401.276763 -154.606699) (xy 401.329547 -154.588692) (xy 401.38439 -154.578562) (xy 401.440124 -154.576525)
			(xy 401.495561 -154.582625) (xy 401.549518 -154.596731) (xy 401.600847 -154.618543) (xy 401.648453 -154.647597)
			(xy 401.691321 -154.683272) (xy 401.728538 -154.724809) (xy 401.759311 -154.771322) (xy 401.782983 -154.821819)
			(xy 401.799051 -154.875226) (xy 401.807171 -154.930402) (xy 401.80768 -154.958288) (xy 401.807171 -154.986174)
			(xy 401.799051 -155.04135) (xy 401.782983 -155.094757) (xy 401.759311 -155.145254) (xy 401.728538 -155.191767)
			(xy 401.691321 -155.233304) (xy 401.648453 -155.268979) (xy 401.600847 -155.298033) (xy 401.549518 -155.319845)
			(xy 401.495561 -155.333951) (xy 401.440124 -155.340051) (xy 401.38439 -155.338014) (xy 401.329547 -155.327884)
			(xy 401.276763 -155.309877) (xy 401.227163 -155.284376) (xy 401.181805 -155.251925) (xy 401.141656 -155.213216)
			(xy 401.10757 -155.169073) (xy 401.080274 -155.120438) (xy 401.060351 -155.068347) (xy 401.048225 -155.01391)
			(xy 401.044154 -154.958288) (xy 397.218594 -154.958288) (xy 397.218669 -154.958538) (xy 397.226789 -155.013714)
			(xy 397.227298 -155.0416) (xy 397.226789 -155.069486) (xy 397.218669 -155.124662) (xy 397.202601 -155.178069)
			(xy 397.178929 -155.228566) (xy 397.148156 -155.275079) (xy 397.110939 -155.316616) (xy 397.068071 -155.352291)
			(xy 397.020465 -155.381345) (xy 396.969136 -155.403157) (xy 396.915179 -155.417263) (xy 396.859742 -155.423363)
			(xy 396.804008 -155.421326) (xy 396.749165 -155.411196) (xy 396.696381 -155.393189) (xy 396.646781 -155.367688)
			(xy 396.601423 -155.335237) (xy 396.561274 -155.296528) (xy 396.527188 -155.252385) (xy 396.499892 -155.20375)
			(xy 396.479969 -155.151659) (xy 396.467843 -155.097222) (xy 396.463772 -155.0416) (xy 378.415013 -155.0416)
			(xy 377.85826 -155.598368) (xy 399.668236 -155.598368) (xy 399.672307 -155.542746) (xy 399.684433 -155.488309)
			(xy 399.704356 -155.436218) (xy 399.731652 -155.387583) (xy 399.765738 -155.34344) (xy 399.805887 -155.304731)
			(xy 399.851245 -155.27228) (xy 399.900845 -155.246779) (xy 399.953629 -155.228772) (xy 400.008472 -155.218642)
			(xy 400.064206 -155.216605) (xy 400.119643 -155.222705) (xy 400.1736 -155.236811) (xy 400.224929 -155.258623)
			(xy 400.272535 -155.287677) (xy 400.315403 -155.323352) (xy 400.35262 -155.364889) (xy 400.383393 -155.411402)
			(xy 400.407065 -155.461899) (xy 400.423133 -155.515306) (xy 400.431253 -155.570482) (xy 400.431762 -155.598368)
			(xy 400.431253 -155.626254) (xy 400.423133 -155.68143) (xy 400.407065 -155.734837) (xy 400.383393 -155.785334)
			(xy 400.35262 -155.831847) (xy 400.315403 -155.873384) (xy 400.272535 -155.909059) (xy 400.224929 -155.938113)
			(xy 400.1736 -155.959925) (xy 400.119643 -155.974031) (xy 400.064206 -155.980131) (xy 400.008472 -155.978094)
			(xy 399.953629 -155.967964) (xy 399.900845 -155.949957) (xy 399.851245 -155.924456) (xy 399.805887 -155.892005)
			(xy 399.765738 -155.853296) (xy 399.731652 -155.809153) (xy 399.704356 -155.760518) (xy 399.684433 -155.708427)
			(xy 399.672307 -155.65399) (xy 399.668236 -155.598368) (xy 377.85826 -155.598368) (xy 377.313698 -156.142944)
			(xy 377.312682 -156.152596) (xy 377.312682 -156.544518) (xy 401.027898 -156.544518) (xy 401.031969 -156.488896)
			(xy 401.044095 -156.434459) (xy 401.064018 -156.382368) (xy 401.091314 -156.333733) (xy 401.1254 -156.28959)
			(xy 401.165549 -156.250881) (xy 401.210907 -156.21843) (xy 401.260507 -156.192929) (xy 401.313291 -156.174922)
			(xy 401.368134 -156.164792) (xy 401.423868 -156.162755) (xy 401.479305 -156.168855) (xy 401.533262 -156.182961)
			(xy 401.584591 -156.204773) (xy 401.632197 -156.233827) (xy 401.675065 -156.269502) (xy 401.712282 -156.311039)
			(xy 401.743055 -156.357552) (xy 401.766727 -156.408049) (xy 401.782795 -156.461456) (xy 401.790915 -156.516632)
			(xy 401.791424 -156.544518) (xy 401.790915 -156.572404) (xy 401.782795 -156.62758) (xy 401.766727 -156.680987)
			(xy 401.743055 -156.731484) (xy 401.712282 -156.777997) (xy 401.675065 -156.819534) (xy 401.632197 -156.855209)
			(xy 401.584591 -156.884263) (xy 401.533262 -156.906075) (xy 401.479305 -156.920181) (xy 401.423868 -156.926281)
			(xy 401.368134 -156.924244) (xy 401.313291 -156.914114) (xy 401.260507 -156.896107) (xy 401.210907 -156.870606)
			(xy 401.165549 -156.838155) (xy 401.1254 -156.799446) (xy 401.091314 -156.755303) (xy 401.064018 -156.706668)
			(xy 401.044095 -156.654577) (xy 401.031969 -156.60014) (xy 401.027898 -156.544518) (xy 377.312682 -156.544518)
			(xy 377.312682 -157.159198) (xy 377.313698 -157.16885) (xy 377.315324 -157.176095) (xy 377.322162 -157.189267)
			(xy 377.32716 -157.194758) (xy 377.93803 -157.805628) (xy 377.94353 -157.810613) (xy 377.956698 -157.817452)
			(xy 377.963938 -157.81909) (xy 377.97359 -157.820106) (xy 385.53009 -157.820106) (xy 385.536948 -157.819598)
			(xy 385.545608 -157.817995) (xy 385.561181 -157.809795) (xy 385.573092 -157.796839) (xy 385.576826 -157.788864)
			(xy 385.586224 -157.766258) (xy 385.613656 -157.700218) (xy 385.615062 -157.696039) (xy 385.616589 -157.687354)
			(xy 385.616704 -157.682946) (xy 385.6101 -157.66669) (xy 385.605782 -157.656022) (xy 385.60389 -157.651702)
			(xy 385.598784 -157.643773) (xy 385.595622 -157.640274) (xy 385.576171 -157.618917) (xy 385.543285 -157.57143)
			(xy 385.517941 -157.519523) (xy 385.500721 -157.464386) (xy 385.492019 -157.407282) (xy 385.491482 -157.3784)
			(xy 385.491968 -157.351149) (xy 385.499724 -157.297201) (xy 385.515079 -157.244906) (xy 385.537721 -157.195329)
			(xy 385.567187 -157.149479) (xy 385.602878 -157.108288) (xy 385.644069 -157.072597) (xy 385.689919 -157.043131)
			(xy 385.739496 -157.020489) (xy 385.791791 -157.005134) (xy 385.845739 -156.997378) (xy 385.900241 -156.997378)
			(xy 385.954189 -157.005134) (xy 386.006484 -157.020489) (xy 386.056061 -157.043131) (xy 386.101911 -157.072597)
			(xy 386.103069 -157.0736) (xy 399.596862 -157.0736) (xy 399.600933 -157.017978) (xy 399.613059 -156.963541)
			(xy 399.632982 -156.91145) (xy 399.660278 -156.862815) (xy 399.694364 -156.818672) (xy 399.734513 -156.779963)
			(xy 399.779871 -156.747512) (xy 399.829471 -156.722011) (xy 399.882255 -156.704004) (xy 399.937098 -156.693874)
			(xy 399.992832 -156.691837) (xy 400.048269 -156.697937) (xy 400.102226 -156.712043) (xy 400.153555 -156.733855)
			(xy 400.201161 -156.762909) (xy 400.244029 -156.798584) (xy 400.281246 -156.840121) (xy 400.312019 -156.886634)
			(xy 400.335691 -156.937131) (xy 400.351759 -156.990538) (xy 400.359879 -157.045714) (xy 400.360388 -157.0736)
			(xy 400.359879 -157.101486) (xy 400.351759 -157.156662) (xy 400.335691 -157.210069) (xy 400.312019 -157.260566)
			(xy 400.281246 -157.307079) (xy 400.244029 -157.348616) (xy 400.201161 -157.384291) (xy 400.153555 -157.413345)
			(xy 400.102226 -157.435157) (xy 400.048269 -157.449263) (xy 399.992832 -157.455363) (xy 399.937098 -157.453326)
			(xy 399.882255 -157.443196) (xy 399.829471 -157.425189) (xy 399.779871 -157.399688) (xy 399.734513 -157.367237)
			(xy 399.694364 -157.328528) (xy 399.660278 -157.284385) (xy 399.632982 -157.23575) (xy 399.613059 -157.183659)
			(xy 399.600933 -157.129222) (xy 399.596862 -157.0736) (xy 386.103069 -157.0736) (xy 386.143102 -157.108288)
			(xy 386.178793 -157.149479) (xy 386.208259 -157.195329) (xy 386.230901 -157.244906) (xy 386.246256 -157.297201)
			(xy 386.254012 -157.351149) (xy 386.254498 -157.3784) (xy 386.253965 -157.407282) (xy 386.245255 -157.464385)
			(xy 386.228033 -157.519521) (xy 386.202694 -157.57143) (xy 386.169816 -157.618925) (xy 386.150358 -157.640274)
			(xy 386.147175 -157.643758) (xy 386.142053 -157.651683) (xy 386.140198 -157.656022) (xy 386.13588 -157.66669)
			(xy 386.129276 -157.682946) (xy 386.129364 -157.687357) (xy 386.130898 -157.696043) (xy 386.132324 -157.700218)
			(xy 386.159756 -157.766258) (xy 386.169154 -157.788864) (xy 386.172867 -157.796862) (xy 386.184746 -157.809875)
			(xy 386.200351 -157.818054) (xy 386.209032 -157.819598) (xy 386.21589 -157.820106) (xy 390.282938 -157.820106)
			(xy 390.292922 -157.819562) (xy 390.311345 -157.811839) (xy 390.318752 -157.80512) (xy 390.48055 -157.643576)
			(xy 390.487947 -157.636729) (xy 390.506547 -157.629001) (xy 390.516618 -157.62859) (xy 391.114026 -157.62859)
			(xy 391.11555 -157.62859) (xy 391.135108 -157.628336) (xy 399.183098 -157.628336) (xy 399.202656 -157.62859)
			(xy 399.40484 -157.62859) (xy 399.414907 -157.62902) (xy 399.433502 -157.636743) (xy 399.440908 -157.643576)
			(xy 399.588228 -157.790896) (xy 399.589244 -157.791912) (xy 399.597372 -157.799786) (xy 400.793712 -158.996126)
			(xy 400.816658 -159.019681) (xy 400.857679 -159.07108) (xy 400.892684 -159.126751) (xy 400.921232 -159.185993)
			(xy 400.942963 -159.24806) (xy 400.957604 -159.312171) (xy 400.964971 -159.377519) (xy 400.965416 -159.4104)
			(xy 400.96494 -159.442686) (xy 400.95778 -159.506861) (xy 400.943613 -159.569861) (xy 400.92261 -159.630923)
			(xy 400.895026 -159.689308) (xy 400.861194 -159.744309) (xy 400.841718 -159.770064) (xy 400.822922 -159.793178)
			(xy 400.81708 -159.800036) (xy 400.808952 -159.820356) (xy 400.806521 -159.827127) (xy 400.80509 -159.841436)
			(xy 400.806158 -159.84855) (xy 400.809714 -159.867092) (xy 400.814794 -159.89427) (xy 400.816612 -159.901047)
			(xy 400.823438 -159.9133) (xy 400.828256 -159.9184) (xy 400.841718 -159.931862) (xy 400.848576 -159.935418)
			(xy 400.877749 -159.95115) (xy 400.932683 -159.988242) (xy 400.983073 -160.031304) (xy 401.028275 -160.079784)
			(xy 401.067709 -160.133061) (xy 401.100871 -160.190453) (xy 401.114514 -160.22066) (xy 401.114768 -160.220914)
			(xy 401.117445 -160.226805) (xy 401.125293 -160.237089) (xy 401.130262 -160.241234) (xy 401.134326 -160.244282)
			(xy 401.145248 -160.249108) (xy 401.200112 -160.259014) (xy 401.202144 -160.259268) (xy 401.20824 -160.260284)
			(xy 401.208494 -160.260284) (xy 401.220057 -160.262221) (xy 401.242809 -160.25666) (xy 401.252182 -160.249616)
			(xy 406.195022 -155.306776) (xy 406.201837 -155.299433) (xy 406.209573 -155.28097) (xy 406.210008 -155.270962)
			(xy 406.210008 -123.994926) (xy 406.210445 -123.984862) (xy 406.218179 -123.966278) (xy 406.224994 -123.958858)
			(xy 406.371806 -123.812046) (xy 406.372822 -123.81103) (xy 406.381458 -123.80214) (xy 411.389576 -118.794022)
			(xy 411.395504 -118.786328) (xy 411.401652 -118.767919) (xy 411.401514 -118.758208) (xy 411.395418 -118.702074)
			(xy 411.394148 -118.690644) (xy 411.375098 -118.65864) (xy 411.370526 -118.654068) (xy 411.366208 -118.649496)
			(xy 411.361636 -118.646448) (xy 411.34014 -118.631107) (xy 411.301184 -118.595451) (xy 411.267513 -118.554769)
			(xy 411.239768 -118.509834) (xy 411.218479 -118.461506) (xy 411.204052 -118.410705) (xy 411.196762 -118.358401)
			(xy 411.196282 -118.331996) (xy 411.196768 -118.304745) (xy 411.204525 -118.250797) (xy 411.21988 -118.198502)
			(xy 411.242522 -118.148925) (xy 411.271988 -118.103074) (xy 411.307679 -118.061883) (xy 411.348869 -118.026191)
			(xy 411.394719 -117.996724) (xy 411.444296 -117.974082) (xy 411.496591 -117.958726) (xy 411.550539 -117.950968)
			(xy 411.57779 -117.950488) (xy 411.604064 -117.950926) (xy 411.656116 -117.958132) (xy 411.706687 -117.972411)
			(xy 411.754821 -117.993491) (xy 411.777434 -118.006876) (xy 411.780228 -118.008654) (xy 411.783276 -118.010432)
			(xy 411.79496 -118.013988) (xy 411.799607 -118.015283) (xy 411.809196 -118.016315) (xy 411.81401 -118.01602)
			(xy 411.81909 -118.015512) (xy 411.83179 -118.011956) (xy 411.842966 -118.007638) (xy 411.899862 -117.976396)
			(xy 411.90037 -117.976142) (xy 411.90811 -117.97208) (xy 411.920446 -117.959715) (xy 411.927873 -117.943907)
			(xy 411.929072 -117.935248) (xy 411.929072 -116.360448) (xy 411.927891 -116.352112) (xy 411.920903 -116.336808)
			(xy 411.915356 -116.330476) (xy 411.90291 -116.318284) (xy 411.896052 -116.31168) (xy 411.878272 -116.303806)
			(xy 411.86862 -116.303298) (xy 411.8418 -116.301659) (xy 411.788983 -116.291792) (xy 411.738071 -116.274613)
			(xy 411.690072 -116.250465) (xy 411.645934 -116.219822) (xy 411.60653 -116.183293) (xy 411.57264 -116.141597)
			(xy 411.544932 -116.095561) (xy 411.523954 -116.046094) (xy 411.510123 -115.994173) (xy 411.503709 -115.940825)
			(xy 411.504842 -115.887106) (xy 411.513498 -115.834076) (xy 411.529505 -115.782784) (xy 411.552549 -115.734245)
			(xy 411.582172 -115.689417) (xy 411.61779 -115.649187) (xy 411.637988 -115.631468) (xy 411.657616 -115.615301)
			(xy 411.700368 -115.587767) (xy 411.746404 -115.566166) (xy 411.794904 -115.550883) (xy 411.845007 -115.542189)
			(xy 411.870398 -115.54079) (xy 411.88005 -115.540282) (xy 411.888178 -115.536726) (xy 411.892357 -115.534869)
			(xy 411.900023 -115.529884) (xy 411.903418 -115.52682) (xy 411.913324 -115.517422) (xy 411.920557 -115.509976)
			(xy 411.928831 -115.49096) (xy 411.929326 -115.480592) (xy 411.929326 -115.298474) (xy 411.929754 -115.288406)
			(xy 411.937478 -115.269811) (xy 411.944312 -115.262406) (xy 412.091124 -115.115594) (xy 412.09214 -115.114578)
			(xy 412.100776 -115.105688) (xy 412.13278 -115.073684) (xy 412.136731 -115.068635) (xy 412.142252 -115.057069)
			(xy 412.143702 -115.050824) (xy 412.145758 -115.036181) (xy 412.14231 -115.006826) (xy 412.130606 -114.979686)
			(xy 412.111625 -114.95703) (xy 412.086954 -114.940753) (xy 412.058657 -114.932217) (xy 412.04388 -114.931698)
			(xy 387.01726 -114.931698) (xy 387.005078 -114.932467) (xy 386.98347 -114.943744) (xy 386.975858 -114.953288)
			(xy 386.930138 -115.024916) (xy 386.926473 -115.030975) (xy 386.922341 -115.044513) (xy 386.92201 -115.051586)
			(xy 386.92201 -115.066064) (xy 386.934035 -115.092087) (xy 386.951011 -115.146841) (xy 386.959605 -115.203518)
			(xy 386.96011 -115.23218) (xy 386.96011 -115.232688) (xy 386.96011 -115.235228) (xy 386.959569 -115.264113)
			(xy 386.950844 -115.321221) (xy 386.933614 -115.376362) (xy 386.90827 -115.428276) (xy 386.875393 -115.475779)
			(xy 386.835733 -115.517785) (xy 386.790197 -115.553335) (xy 386.739822 -115.581617) (xy 386.685762 -115.601985)
			(xy 386.629249 -115.613974) (xy 386.600446 -115.616228) (xy 386.58927 -115.616736) (xy 386.579618 -115.621816)
			(xy 386.575049 -115.624443) (xy 386.56698 -115.631221) (xy 386.563616 -115.635278) (xy 386.539994 -115.66525)
			(xy 386.516118 -115.695476) (xy 386.512915 -115.699698) (xy 386.508179 -115.709177) (xy 386.50672 -115.714272)
			(xy 386.50418 -115.724686) (xy 386.506212 -115.735608) (xy 386.509043 -115.752356) (xy 386.512099 -115.786188)
			(xy 386.512286 -115.801394) (xy 404.147272 -115.801394) (xy 404.151343 -115.745772) (xy 404.163469 -115.691335)
			(xy 404.183392 -115.639244) (xy 404.210688 -115.590609) (xy 404.244774 -115.546466) (xy 404.284923 -115.507757)
			(xy 404.330281 -115.475306) (xy 404.379881 -115.449805) (xy 404.432665 -115.431798) (xy 404.487508 -115.421668)
			(xy 404.543242 -115.419631) (xy 404.598679 -115.425731) (xy 404.652636 -115.439837) (xy 404.703965 -115.461649)
			(xy 404.751571 -115.490703) (xy 404.794439 -115.526378) (xy 404.831656 -115.567915) (xy 404.862429 -115.614428)
			(xy 404.886101 -115.664925) (xy 404.902169 -115.718332) (xy 404.910289 -115.773508) (xy 404.910798 -115.801394)
			(xy 404.910289 -115.82928) (xy 404.902169 -115.884456) (xy 404.886101 -115.937863) (xy 404.862429 -115.98836)
			(xy 404.831656 -116.034873) (xy 404.794439 -116.07641) (xy 404.751571 -116.112085) (xy 404.703965 -116.141139)
			(xy 404.652636 -116.162951) (xy 404.598679 -116.177057) (xy 404.543242 -116.183157) (xy 404.487508 -116.18112)
			(xy 404.432665 -116.17099) (xy 404.379881 -116.152983) (xy 404.330281 -116.127482) (xy 404.284923 -116.095031)
			(xy 404.244774 -116.056322) (xy 404.210688 -116.012179) (xy 404.183392 -115.963544) (xy 404.163469 -115.911453)
			(xy 404.151343 -115.857016) (xy 404.147272 -115.801394) (xy 386.512286 -115.801394) (xy 386.512308 -115.803172)
			(xy 386.512308 -115.803934) (xy 386.511862 -115.830289) (xy 386.504605 -115.882497) (xy 386.490233 -115.93321)
			(xy 386.46902 -115.981463) (xy 386.44137 -116.026339) (xy 386.407808 -116.066983) (xy 386.368973 -116.102623)
			(xy 386.325603 -116.13258) (xy 386.30225 -116.144802) (xy 386.293106 -116.149374) (xy 386.27431 -116.17198)
			(xy 386.272024 -116.17452) (xy 386.268822 -116.178743) (xy 386.264084 -116.188221) (xy 386.262626 -116.193316)
			(xy 386.259832 -116.204238) (xy 386.247894 -116.24945) (xy 386.246624 -116.260372) (xy 386.246624 -116.274342)
			(xy 386.246689 -116.278351) (xy 386.247959 -116.286266) (xy 386.249164 -116.29009) (xy 386.251196 -116.296694)
			(xy 386.255006 -116.302282) (xy 386.269954 -116.325798) (xy 386.293605 -116.37625) (xy 386.309658 -116.429608)
			(xy 386.317771 -116.484734) (xy 386.318252 -116.512594) (xy 386.317767 -116.539847) (xy 386.310011 -116.593797)
			(xy 386.294657 -116.646095) (xy 386.272017 -116.695676) (xy 386.242551 -116.74153) (xy 386.20686 -116.782725)
			(xy 386.165671 -116.818421) (xy 386.11982 -116.847893) (xy 386.070242 -116.870539) (xy 386.017946 -116.8859)
			(xy 385.963997 -116.893663) (xy 385.936744 -116.894102) (xy 385.911226 -116.893672) (xy 385.860647 -116.886864)
			(xy 385.811425 -116.873376) (xy 385.76444 -116.853449) (xy 385.72053 -116.827439) (xy 385.680477 -116.79581)
			(xy 385.662424 -116.77777) (xy 385.655566 -116.770658) (xy 385.628388 -116.75872) (xy 385.618482 -116.754402)
			(xy 385.561078 -116.754402) (xy 385.553458 -116.755164) (xy 385.54025 -116.75745) (xy 385.534154 -116.758466)
			(xy 385.506722 -116.770658) (xy 385.49961 -116.778024) (xy 385.481574 -116.79604) (xy 385.441548 -116.827614)
			(xy 385.397674 -116.853574) (xy 385.350732 -116.873458) (xy 385.30156 -116.886912) (xy 385.251034 -116.893695)
			(xy 385.225544 -116.894102) (xy 385.19829 -116.893642) (xy 385.144335 -116.88589) (xy 385.092032 -116.870538)
			(xy 385.042448 -116.847898) (xy 384.99659 -116.818432) (xy 384.955392 -116.782739) (xy 384.919694 -116.741546)
			(xy 384.890223 -116.695691) (xy 384.867577 -116.646109) (xy 384.852219 -116.593808) (xy 384.844461 -116.539854)
			(xy 384.844461 -116.485346) (xy 384.852219 -116.431392) (xy 384.867577 -116.379091) (xy 384.890223 -116.329509)
			(xy 384.919694 -116.283654) (xy 384.955392 -116.242461) (xy 384.99659 -116.206768) (xy 385.042447 -116.177302)
			(xy 385.092032 -116.154662) (xy 385.144335 -116.13931) (xy 385.19829 -116.131558) (xy 385.225544 -116.131086)
			(xy 385.251062 -116.131515) (xy 385.301643 -116.138322) (xy 385.350865 -116.151808) (xy 385.397852 -116.171733)
			(xy 385.441764 -116.197742) (xy 385.481819 -116.22937) (xy 385.499864 -116.247418) (xy 385.506722 -116.25453)
			(xy 385.533646 -116.266468) (xy 385.538486 -116.268472) (xy 385.54873 -116.270651) (xy 385.553966 -116.270786)
			(xy 385.601972 -116.270786) (xy 385.611116 -116.270024) (xy 385.628388 -116.266468) (xy 385.633468 -116.264182)
			(xy 385.651756 -116.256308) (xy 385.657598 -116.251482) (xy 385.661408 -116.248434) (xy 385.663694 -116.246148)
			(xy 385.686353 -116.223839) (xy 385.737674 -116.186301) (xy 385.765802 -116.171472) (xy 385.7752 -116.1669)
			(xy 385.802632 -116.134134) (xy 385.805426 -116.122958) (xy 385.821174 -116.063014) (xy 385.821174 -116.062506)
			(xy 385.823206 -116.05514) (xy 385.822952 -116.047774) (xy 385.822748 -116.043951) (xy 385.821352 -116.036425)
			(xy 385.820158 -116.032788) (xy 385.815078 -116.01831) (xy 385.81203 -116.01323) (xy 385.811268 -116.012214)
			(xy 385.796605 -115.988874) (xy 385.773429 -115.938864) (xy 385.757702 -115.886036) (xy 385.749754 -115.831493)
			(xy 385.749292 -115.803934) (xy 385.749829 -115.775046) (xy 385.758546 -115.717931) (xy 385.775771 -115.662783)
			(xy 385.801111 -115.61086) (xy 385.833986 -115.563349) (xy 385.873647 -115.521336) (xy 385.919186 -115.485779)
			(xy 385.969563 -115.457491) (xy 386.023629 -115.437119) (xy 386.080147 -115.425128) (xy 386.108956 -115.422934)
			(xy 386.120132 -115.422426) (xy 386.129784 -115.417346) (xy 386.134352 -115.414717) (xy 386.142417 -115.407936)
			(xy 386.145786 -115.403884) (xy 386.169408 -115.373912) (xy 386.193284 -115.343686) (xy 386.196492 -115.339466)
			(xy 386.201239 -115.32999) (xy 386.202682 -115.32489) (xy 386.205222 -115.314476) (xy 386.20319 -115.303554)
			(xy 386.20036 -115.286806) (xy 386.197308 -115.252974) (xy 386.197094 -115.23599) (xy 386.197094 -115.235228)
			(xy 386.197563 -115.207834) (xy 386.205388 -115.153609) (xy 386.220882 -115.101058) (xy 386.231892 -115.07597)
			(xy 386.2324 -115.074954) (xy 386.232908 -115.073684) (xy 386.236125 -115.064633) (xy 386.236253 -115.045441)
			(xy 386.233162 -115.036346) (xy 386.230368 -115.029488) (xy 386.182616 -114.955066) (xy 386.178552 -114.951256)
			(xy 386.173726 -114.94643) (xy 386.169999 -114.942903) (xy 386.161429 -114.937263) (xy 386.156708 -114.935254)
			(xy 386.148072 -114.931698) (xy 384.920236 -114.931698) (xy 384.915359 -114.931795) (xy 384.905771 -114.933588)
			(xy 384.901186 -114.935254) (xy 384.892042 -114.939064) (xy 384.08737 -115.743736) (xy 384.079973 -115.750585)
			(xy 384.061374 -115.758318) (xy 384.051302 -115.758722) (xy 366.959388 -115.758722) (xy 366.956594 -115.758722)
			(xy 366.945892 -115.759779) (xy 366.926809 -115.769647) (xy 366.919764 -115.777772) (xy 366.872012 -115.840764)
			(xy 366.866932 -115.847622) (xy 366.864392 -115.854988) (xy 366.863109 -115.858995) (xy 366.861706 -115.867292)
			(xy 366.861598 -115.871498) (xy 366.861598 -115.879372) (xy 366.862868 -115.88877) (xy 366.86363 -115.891818)
			(xy 366.869438 -115.915779) (xy 366.875556 -115.964701) (xy 366.875822 -115.989354) (xy 366.875822 -115.991894)
			(xy 366.875822 -115.992402) (xy 366.875406 -116.0181) (xy 366.868523 -116.069033) (xy 366.854883 -116.118587)
			(xy 366.83473 -116.165867) (xy 366.808428 -116.210023) (xy 366.792764 -116.2304) (xy 366.786922 -116.237512)
			(xy 366.784382 -116.244624) (xy 366.783086 -116.248693) (xy 366.781689 -116.257118) (xy 366.781588 -116.261388)
			(xy 366.781588 -116.280438) (xy 366.781444 -116.285877) (xy 366.779135 -116.296508) (xy 366.777016 -116.30152)
			(xy 366.770666 -116.314474) (xy 366.76875 -116.318952) (xy 366.766438 -116.328412) (xy 366.766094 -116.33327)
			(xy 366.765586 -116.34343) (xy 366.772698 -116.363496) (xy 366.779556 -116.371116) (xy 366.797603 -116.392182)
			(xy 366.828047 -116.43855) (xy 366.851456 -116.488838) (xy 366.867336 -116.541986) (xy 366.875353 -116.596873)
			(xy 366.875822 -116.624608) (xy 366.875822 -116.626894) (xy 366.875822 -116.627402) (xy 366.875406 -116.6531)
			(xy 366.868523 -116.704033) (xy 366.854883 -116.753587) (xy 366.83473 -116.800867) (xy 366.808428 -116.845023)
			(xy 366.792764 -116.8654) (xy 366.786922 -116.872512) (xy 366.784382 -116.879624) (xy 366.783086 -116.883693)
			(xy 366.781689 -116.892118) (xy 366.781588 -116.896388) (xy 366.781588 -116.915438) (xy 366.781444 -116.920877)
			(xy 366.779135 -116.931508) (xy 366.777016 -116.93652) (xy 366.770666 -116.949982) (xy 366.76707 -116.958449)
			(xy 366.76554 -116.976766) (xy 366.770577 -116.994443) (xy 366.775746 -117.002052) (xy 366.778794 -117.005608)
			(xy 366.796919 -117.026698) (xy 366.827506 -117.073138) (xy 366.851034 -117.123522) (xy 366.867006 -117.176787)
			(xy 366.875084 -117.231804) (xy 366.875568 -117.259608) (xy 366.875104 -117.286859) (xy 366.867346 -117.340807)
			(xy 366.851989 -117.393102) (xy 366.829345 -117.442679) (xy 366.799876 -117.488528) (xy 366.764182 -117.529716)
			(xy 366.722989 -117.565405) (xy 366.677136 -117.594868) (xy 366.627557 -117.617506) (xy 366.57526 -117.632856)
			(xy 366.521312 -117.640608) (xy 366.49406 -117.641116) (xy 366.493552 -117.641116) (xy 366.467925 -117.640689)
			(xy 366.417136 -117.633796) (xy 366.36773 -117.620155) (xy 366.320599 -117.600012) (xy 366.276595 -117.573731)
			(xy 366.256316 -117.558058) (xy 366.249458 -117.552724) (xy 366.241838 -117.550184) (xy 366.23778 -117.548816)
			(xy 366.229354 -117.54729) (xy 366.225074 -117.547136) (xy 366.20323 -117.547136) (xy 366.197789 -117.546999)
			(xy 366.187153 -117.5447) (xy 366.182148 -117.542564) (xy 366.168686 -117.536214) (xy 366.160221 -117.532621)
			(xy 366.141908 -117.5311) (xy 366.12424 -117.53615) (xy 366.116616 -117.541294) (xy 366.11306 -117.544342)
			(xy 366.09197 -117.562467) (xy 366.045531 -117.593054) (xy 365.995146 -117.616581) (xy 365.941881 -117.632551)
			(xy 365.886864 -117.640626) (xy 365.85906 -117.641116) (xy 365.83181 -117.640627) (xy 365.777867 -117.632866)
			(xy 365.725576 -117.617508) (xy 365.676003 -117.594865) (xy 365.630158 -117.565397) (xy 365.588971 -117.529706)
			(xy 365.553283 -117.488517) (xy 365.52382 -117.442668) (xy 365.501181 -117.393094) (xy 365.485827 -117.340802)
			(xy 365.47807 -117.286858) (xy 365.477552 -117.259608) (xy 365.477552 -117.2591) (xy 365.477983 -117.233474)
			(xy 365.484883 -117.182689) (xy 365.498531 -117.133288) (xy 365.518682 -117.086164) (xy 365.54497 -117.042168)
			(xy 365.56061 -117.021864) (xy 365.565944 -117.015006) (xy 365.568484 -117.007386) (xy 365.569857 -117.003329)
			(xy 365.571391 -116.994903) (xy 365.571532 -116.990622) (xy 365.571532 -116.968778) (xy 365.571674 -116.963338)
			(xy 365.573981 -116.952706) (xy 365.576104 -116.947696) (xy 365.582454 -116.934742) (xy 365.584362 -116.930262)
			(xy 365.586657 -116.920801) (xy 365.587026 -116.915946) (xy 365.587534 -116.905786) (xy 365.580422 -116.88572)
			(xy 365.573564 -116.8781) (xy 365.55552 -116.857033) (xy 365.52508 -116.810663) (xy 365.501674 -116.760375)
			(xy 365.485795 -116.707228) (xy 365.477778 -116.652342) (xy 365.477298 -116.624608) (xy 365.477298 -116.622322)
			(xy 365.477298 -116.621814) (xy 365.477713 -116.596116) (xy 365.484594 -116.545182) (xy 365.498233 -116.495628)
			(xy 365.518386 -116.448346) (xy 365.544688 -116.40419) (xy 365.560356 -116.383816) (xy 365.566198 -116.376704)
			(xy 365.568738 -116.369592) (xy 365.570035 -116.365523) (xy 365.571434 -116.357098) (xy 365.571532 -116.352828)
			(xy 365.571532 -116.333778) (xy 365.571674 -116.328338) (xy 365.573981 -116.317706) (xy 365.576104 -116.312696)
			(xy 365.582454 -116.299742) (xy 365.584362 -116.295262) (xy 365.586657 -116.285801) (xy 365.587026 -116.280946)
			(xy 365.587534 -116.270786) (xy 365.580422 -116.25072) (xy 365.573564 -116.2431) (xy 365.55552 -116.222033)
			(xy 365.52508 -116.175663) (xy 365.501674 -116.125375) (xy 365.485795 -116.072228) (xy 365.477778 -116.017342)
			(xy 365.477298 -115.989608) (xy 365.477731 -115.963691) (xy 365.484741 -115.912332) (xy 365.491268 -115.887246)
			(xy 365.49457 -115.875816) (xy 365.492284 -115.864132) (xy 365.491014 -115.858443) (xy 365.486269 -115.847798)
			(xy 365.482886 -115.84305) (xy 365.445294 -115.79352) (xy 365.43361 -115.77828) (xy 365.426068 -115.769495)
			(xy 365.405296 -115.759324) (xy 365.393732 -115.758722) (xy 362.635546 -115.758722) (xy 362.624878 -115.760754)
			(xy 362.614718 -115.762532) (xy 362.60659 -115.767866) (xy 362.602294 -115.770728) (xy 362.594867 -115.777896)
			(xy 362.591858 -115.78209) (xy 362.546138 -115.849908) (xy 362.545376 -115.851686) (xy 362.540296 -115.860576)
			(xy 362.538772 -115.870482) (xy 362.538235 -115.874337) (xy 362.538239 -115.88212) (xy 362.538772 -115.885976)
			(xy 362.54055 -115.896898) (xy 362.540804 -115.897406) (xy 362.540804 -115.89766) (xy 362.543852 -115.906042)
			(xy 362.554635 -115.937598) (xy 362.56625 -116.003258) (xy 362.566966 -116.036598) (xy 362.566966 -116.046758)
			(xy 362.566712 -116.0526) (xy 362.56605 -116.065758) (xy 362.563127 -116.091944) (xy 362.56087 -116.104924)
			(xy 362.554669 -116.135741) (xy 362.533539 -116.194938) (xy 362.502991 -116.249871) (xy 362.483908 -116.27485)
			(xy 362.478574 -116.281708) (xy 362.476034 -116.289328) (xy 362.474662 -116.293385) (xy 362.473129 -116.301811)
			(xy 362.472986 -116.306092) (xy 362.472986 -116.327936) (xy 362.472843 -116.333375) (xy 362.470534 -116.344006)
			(xy 362.468414 -116.349018) (xy 362.462064 -116.36248) (xy 362.458468 -116.370947) (xy 362.456937 -116.389264)
			(xy 362.461974 -116.406942) (xy 362.467144 -116.41455) (xy 362.470192 -116.418106) (xy 362.488311 -116.439198)
			(xy 362.518886 -116.48564) (xy 362.542401 -116.536026) (xy 362.55836 -116.589289) (xy 362.566424 -116.644305)
			(xy 362.566966 -116.672106) (xy 362.566966 -116.672868) (xy 362.566837 -116.680234) (xy 363.451138 -116.680234)
			(xy 363.455209 -116.624612) (xy 363.467335 -116.570175) (xy 363.487258 -116.518084) (xy 363.514554 -116.469449)
			(xy 363.54864 -116.425306) (xy 363.588789 -116.386597) (xy 363.634147 -116.354146) (xy 363.683747 -116.328645)
			(xy 363.736531 -116.310638) (xy 363.791374 -116.300508) (xy 363.847108 -116.298471) (xy 363.902545 -116.304571)
			(xy 363.956502 -116.318677) (xy 364.007831 -116.340489) (xy 364.055437 -116.369543) (xy 364.098305 -116.405218)
			(xy 364.135522 -116.446755) (xy 364.166295 -116.493268) (xy 364.189967 -116.543765) (xy 364.206035 -116.597172)
			(xy 364.214155 -116.652348) (xy 364.214664 -116.680234) (xy 364.214155 -116.70812) (xy 364.206035 -116.763296)
			(xy 364.189967 -116.816703) (xy 364.166295 -116.8672) (xy 364.135522 -116.913713) (xy 364.098305 -116.95525)
			(xy 364.055437 -116.990925) (xy 364.007831 -117.019979) (xy 363.956502 -117.041791) (xy 363.902545 -117.055897)
			(xy 363.847108 -117.061997) (xy 363.791374 -117.05996) (xy 363.736531 -117.04983) (xy 363.683747 -117.031823)
			(xy 363.634147 -117.006322) (xy 363.588789 -116.973871) (xy 363.54864 -116.935162) (xy 363.514554 -116.891019)
			(xy 363.487258 -116.842384) (xy 363.467335 -116.790293) (xy 363.455209 -116.735856) (xy 363.451138 -116.680234)
			(xy 362.566837 -116.680234) (xy 362.566516 -116.698506) (xy 362.559589 -116.749313) (xy 362.545936 -116.798739)
			(xy 362.536232 -116.822474) (xy 362.5342 -116.827046) (xy 362.53166 -116.837968) (xy 362.529989 -116.84735)
			(xy 362.532984 -116.866155) (xy 362.537502 -116.874544) (xy 362.579158 -116.946426) (xy 362.585617 -116.955404)
			(xy 362.60433 -116.967141) (xy 362.615226 -116.969032) (xy 362.617004 -116.969286) (xy 362.617512 -116.969286)
			(xy 362.645479 -116.972487) (xy 362.700108 -116.986061) (xy 362.75215 -117.007514) (xy 362.800476 -117.036379)
			(xy 362.844036 -117.072031) (xy 362.881886 -117.113696) (xy 362.913205 -117.16047) (xy 362.937311 -117.211337)
			(xy 362.953683 -117.265193) (xy 362.959124 -117.301772) (xy 364.598202 -117.301772) (xy 364.602273 -117.24615)
			(xy 364.614399 -117.191713) (xy 364.634322 -117.139622) (xy 364.661618 -117.090987) (xy 364.695704 -117.046844)
			(xy 364.735853 -117.008135) (xy 364.781211 -116.975684) (xy 364.830811 -116.950183) (xy 364.883595 -116.932176)
			(xy 364.938438 -116.922046) (xy 364.994172 -116.920009) (xy 365.049609 -116.926109) (xy 365.103566 -116.940215)
			(xy 365.154895 -116.962027) (xy 365.202501 -116.991081) (xy 365.245369 -117.026756) (xy 365.282586 -117.068293)
			(xy 365.313359 -117.114806) (xy 365.337031 -117.165303) (xy 365.353099 -117.21871) (xy 365.361219 -117.273886)
			(xy 365.361728 -117.301772) (xy 365.361219 -117.329658) (xy 365.353099 -117.384834) (xy 365.337031 -117.438241)
			(xy 365.313359 -117.488738) (xy 365.282586 -117.535251) (xy 365.245369 -117.576788) (xy 365.202501 -117.612463)
			(xy 365.154895 -117.641517) (xy 365.103566 -117.663329) (xy 365.049609 -117.677435) (xy 364.994172 -117.683535)
			(xy 364.938438 -117.681498) (xy 364.883595 -117.671368) (xy 364.830811 -117.653361) (xy 364.781211 -117.62786)
			(xy 364.735853 -117.595409) (xy 364.695704 -117.5567) (xy 364.661618 -117.512557) (xy 364.634322 -117.463922)
			(xy 364.614399 -117.411831) (xy 364.602273 -117.357394) (xy 364.598202 -117.301772) (xy 362.959124 -117.301772)
			(xy 362.961965 -117.320871) (xy 362.962444 -117.349016) (xy 362.961958 -117.376267) (xy 362.954202 -117.430215)
			(xy 362.938847 -117.48251) (xy 362.916205 -117.532087) (xy 362.886739 -117.577937) (xy 362.851048 -117.619128)
			(xy 362.809857 -117.654819) (xy 362.764007 -117.684285) (xy 362.71443 -117.706927) (xy 362.662135 -117.722282)
			(xy 362.608187 -117.730038) (xy 362.553685 -117.730038) (xy 362.499737 -117.722282) (xy 362.447442 -117.706927)
			(xy 362.397865 -117.684285) (xy 362.352015 -117.654819) (xy 362.310824 -117.619128) (xy 362.275133 -117.577937)
			(xy 362.245667 -117.532087) (xy 362.223025 -117.48251) (xy 362.20767 -117.430215) (xy 362.199914 -117.376267)
			(xy 362.199428 -117.349016) (xy 362.199428 -117.348254) (xy 362.199884 -117.322617) (xy 362.206822 -117.271814)
			(xy 362.220488 -117.222394) (xy 362.230162 -117.198648) (xy 362.232194 -117.194076) (xy 362.234734 -117.183154)
			(xy 362.23639 -117.173775) (xy 362.23337 -117.154985) (xy 362.228892 -117.146578) (xy 362.187236 -117.074696)
			(xy 362.180779 -117.065716) (xy 362.162065 -117.053975) (xy 362.151168 -117.05209) (xy 362.14939 -117.051836)
			(xy 362.148882 -117.051836) (xy 362.121614 -117.04873) (xy 362.068306 -117.03569) (xy 362.01742 -117.015138)
			(xy 361.970009 -116.987499) (xy 361.948222 -116.97081) (xy 361.947968 -116.970556) (xy 361.94619 -116.969032)
			(xy 361.939662 -116.964734) (xy 361.92479 -116.95995) (xy 361.91698 -116.959634) (xy 361.894628 -116.959634)
			(xy 361.889187 -116.959496) (xy 361.878552 -116.957198) (xy 361.873546 -116.955062) (xy 361.860084 -116.948712)
			(xy 361.851619 -116.94512) (xy 361.833307 -116.943599) (xy 361.815639 -116.948649) (xy 361.808014 -116.953792)
			(xy 361.804458 -116.95684) (xy 361.783368 -116.974965) (xy 361.736929 -117.005552) (xy 361.686544 -117.029079)
			(xy 361.633279 -117.045048) (xy 361.578262 -117.053123) (xy 361.550458 -117.053614) (xy 361.523209 -117.053125)
			(xy 361.469265 -117.045364) (xy 361.416975 -117.030005) (xy 361.367403 -117.007362) (xy 361.321557 -116.977895)
			(xy 361.280371 -116.942203) (xy 361.244684 -116.901014) (xy 361.215221 -116.855166) (xy 361.192582 -116.805591)
			(xy 361.177228 -116.7533) (xy 361.169472 -116.699355) (xy 361.16895 -116.672106) (xy 361.16895 -116.671598)
			(xy 361.169381 -116.645972) (xy 361.176281 -116.595188) (xy 361.18993 -116.545787) (xy 361.21008 -116.498663)
			(xy 361.236369 -116.454667) (xy 361.252008 -116.434362) (xy 361.257342 -116.427504) (xy 361.259882 -116.419884)
			(xy 361.261255 -116.415827) (xy 361.262789 -116.407401) (xy 361.26293 -116.40312) (xy 361.26293 -116.381276)
			(xy 361.263072 -116.375836) (xy 361.265379 -116.365205) (xy 361.267502 -116.360194) (xy 361.273852 -116.346732)
			(xy 361.277588 -116.337965) (xy 361.278907 -116.318966) (xy 361.273159 -116.300811) (xy 361.267502 -116.293138)
			(xy 361.265724 -116.291106) (xy 361.245485 -116.26751) (xy 361.212168 -116.215031) (xy 361.187817 -116.157838)
			(xy 361.179872 -116.127784) (xy 361.179872 -116.12753) (xy 361.178052 -116.121102) (xy 361.171622 -116.109398)
			(xy 361.167172 -116.104416) (xy 361.162854 -116.099844) (xy 361.151424 -116.09324) (xy 361.05592 -116.066316)
			(xy 361.044332 -116.064446) (xy 361.02159 -116.07015) (xy 361.012232 -116.077238) (xy 360.72953 -116.359686)
			(xy 360.726824 -116.362537) (xy 360.72223 -116.368914) (xy 360.720386 -116.372386) (xy 360.717808 -116.377814)
			(xy 360.714995 -116.389494) (xy 360.714798 -116.3955) (xy 360.714798 -116.960142) (xy 360.716322 -116.972334)
			(xy 360.722926 -116.994686) (xy 360.726482 -117.000528) (xy 360.739892 -117.023169) (xy 360.761043 -117.071354)
			(xy 360.77537 -117.121988) (xy 360.7826 -117.174111) (xy 360.782597 -117.226733) (xy 360.775361 -117.278855)
			(xy 360.761028 -117.329488) (xy 360.739872 -117.37767) (xy 360.726482 -117.400324) (xy 360.722926 -117.406166)
			(xy 360.716322 -117.428518) (xy 360.714798 -117.44071) (xy 360.714798 -117.7544) (xy 385.388102 -117.7544)
			(xy 385.392173 -117.698778) (xy 385.404299 -117.644341) (xy 385.424222 -117.59225) (xy 385.451518 -117.543615)
			(xy 385.485604 -117.499472) (xy 385.525753 -117.460763) (xy 385.571111 -117.428312) (xy 385.620711 -117.402811)
			(xy 385.673495 -117.384804) (xy 385.728338 -117.374674) (xy 385.784072 -117.372637) (xy 385.839509 -117.378737)
			(xy 385.893466 -117.392843) (xy 385.944795 -117.414655) (xy 385.992401 -117.443709) (xy 386.035269 -117.479384)
			(xy 386.072486 -117.520921) (xy 386.103259 -117.567434) (xy 386.126931 -117.617931) (xy 386.142999 -117.671338)
			(xy 386.151119 -117.726514) (xy 386.151628 -117.7544) (xy 386.151119 -117.782286) (xy 386.142999 -117.837462)
			(xy 386.126931 -117.890869) (xy 386.103259 -117.941366) (xy 386.072486 -117.987879) (xy 386.035269 -118.029416)
			(xy 385.992401 -118.065091) (xy 385.944795 -118.094145) (xy 385.893466 -118.115957) (xy 385.839509 -118.130063)
			(xy 385.784072 -118.136163) (xy 385.728338 -118.134126) (xy 385.673495 -118.123996) (xy 385.620711 -118.105989)
			(xy 385.571111 -118.080488) (xy 385.525753 -118.048037) (xy 385.485604 -118.009328) (xy 385.451518 -117.965185)
			(xy 385.424222 -117.91655) (xy 385.404299 -117.864459) (xy 385.392173 -117.810022) (xy 385.388102 -117.7544)
			(xy 360.714798 -117.7544) (xy 360.714798 -118.194328) (xy 403.844504 -118.194328) (xy 403.848575 -118.138706)
			(xy 403.860701 -118.084269) (xy 403.880624 -118.032178) (xy 403.90792 -117.983543) (xy 403.942006 -117.9394)
			(xy 403.982155 -117.900691) (xy 404.027513 -117.86824) (xy 404.077113 -117.842739) (xy 404.129897 -117.824732)
			(xy 404.18474 -117.814602) (xy 404.240474 -117.812565) (xy 404.295911 -117.818665) (xy 404.349868 -117.832771)
			(xy 404.401197 -117.854583) (xy 404.448803 -117.883637) (xy 404.491671 -117.919312) (xy 404.528888 -117.960849)
			(xy 404.559661 -118.007362) (xy 404.583333 -118.057859) (xy 404.599401 -118.111266) (xy 404.607521 -118.166442)
			(xy 404.60803 -118.194328) (xy 404.607521 -118.222214) (xy 404.599401 -118.27739) (xy 404.583333 -118.330797)
			(xy 404.559661 -118.381294) (xy 404.528888 -118.427807) (xy 404.491671 -118.469344) (xy 404.448803 -118.505019)
			(xy 404.401197 -118.534073) (xy 404.349868 -118.555885) (xy 404.295911 -118.569991) (xy 404.240474 -118.576091)
			(xy 404.18474 -118.574054) (xy 404.129897 -118.563924) (xy 404.077113 -118.545917) (xy 404.027513 -118.520416)
			(xy 403.982155 -118.487965) (xy 403.942006 -118.449256) (xy 403.90792 -118.405113) (xy 403.880624 -118.356478)
			(xy 403.860701 -118.304387) (xy 403.848575 -118.24995) (xy 403.844504 -118.194328) (xy 360.714798 -118.194328)
			(xy 360.714798 -119.115586) (xy 360.716322 -119.127778) (xy 360.722926 -119.15013) (xy 360.726482 -119.155972)
			(xy 360.739897 -119.178613) (xy 360.761055 -119.226799) (xy 360.775389 -119.277435) (xy 360.782627 -119.329561)
			(xy 360.78263 -119.382188) (xy 360.781348 -119.39143) (xy 363.214918 -119.39143) (xy 363.218989 -119.335808)
			(xy 363.231115 -119.281371) (xy 363.251038 -119.22928) (xy 363.278334 -119.180645) (xy 363.31242 -119.136502)
			(xy 363.352569 -119.097793) (xy 363.397927 -119.065342) (xy 363.447527 -119.039841) (xy 363.500311 -119.021834)
			(xy 363.555154 -119.011704) (xy 363.610888 -119.009667) (xy 363.666325 -119.015767) (xy 363.720282 -119.029873)
			(xy 363.771611 -119.051685) (xy 363.819217 -119.080739) (xy 363.862085 -119.116414) (xy 363.899302 -119.157951)
			(xy 363.930075 -119.204464) (xy 363.953747 -119.254961) (xy 363.969815 -119.308368) (xy 363.977935 -119.363544)
			(xy 363.978444 -119.39143) (xy 363.977935 -119.419316) (xy 363.969815 -119.474492) (xy 363.953747 -119.527899)
			(xy 363.930075 -119.578396) (xy 363.899302 -119.624909) (xy 363.862085 -119.666446) (xy 363.819217 -119.702121)
			(xy 363.771611 -119.731175) (xy 363.720282 -119.752987) (xy 363.666325 -119.767093) (xy 363.610888 -119.773193)
			(xy 363.555154 -119.771156) (xy 363.500311 -119.761026) (xy 363.447527 -119.743019) (xy 363.397927 -119.717518)
			(xy 363.352569 -119.685067) (xy 363.31242 -119.646358) (xy 363.278334 -119.602215) (xy 363.251038 -119.55358)
			(xy 363.231115 -119.501489) (xy 363.218989 -119.447052) (xy 363.214918 -119.39143) (xy 360.781348 -119.39143)
			(xy 360.7754 -119.434315) (xy 360.761073 -119.484953) (xy 360.73992 -119.533142) (xy 360.726482 -119.555768)
			(xy 360.722926 -119.56161) (xy 360.716322 -119.583962) (xy 360.714798 -119.596154) (xy 360.714798 -120.087898)
			(xy 382.967992 -120.087898) (xy 382.967992 -119.224298) (xy 382.968482 -119.19433) (xy 382.976305 -119.134908)
			(xy 382.991818 -119.077015) (xy 383.014754 -119.021642) (xy 383.044721 -118.969736) (xy 383.081208 -118.922186)
			(xy 383.123588 -118.879806) (xy 383.171138 -118.843319) (xy 383.223044 -118.813352) (xy 383.278417 -118.790416)
			(xy 383.33631 -118.774903) (xy 383.395732 -118.76708) (xy 383.455668 -118.76708) (xy 383.51509 -118.774903)
			(xy 383.572983 -118.790416) (xy 383.628356 -118.813352) (xy 383.680262 -118.843319) (xy 383.727812 -118.879806)
			(xy 383.770192 -118.922186) (xy 383.806679 -118.969736) (xy 383.836646 -119.021642) (xy 383.859582 -119.077015)
			(xy 383.875095 -119.134908) (xy 383.882918 -119.19433) (xy 383.883408 -119.224298) (xy 383.883408 -120.086374)
			(xy 401.939252 -120.086374) (xy 401.939252 -119.222774) (xy 401.939742 -119.192806) (xy 401.947565 -119.133384)
			(xy 401.963078 -119.075491) (xy 401.986014 -119.020118) (xy 402.015981 -118.968212) (xy 402.052468 -118.920662)
			(xy 402.094848 -118.878282) (xy 402.142398 -118.841795) (xy 402.194304 -118.811828) (xy 402.249677 -118.788892)
			(xy 402.30757 -118.773379) (xy 402.366992 -118.765556) (xy 402.426928 -118.765556) (xy 402.48635 -118.773379)
			(xy 402.544243 -118.788892) (xy 402.599616 -118.811828) (xy 402.651522 -118.841795) (xy 402.699072 -118.878282)
			(xy 402.741452 -118.920662) (xy 402.777939 -118.968212) (xy 402.807906 -119.020118) (xy 402.830842 -119.075491)
			(xy 402.846355 -119.133384) (xy 402.854178 -119.192806) (xy 402.854668 -119.222774) (xy 402.854668 -120.086374)
			(xy 402.854178 -120.116342) (xy 402.846355 -120.175764) (xy 402.830842 -120.233657) (xy 402.807906 -120.28903)
			(xy 402.777939 -120.340936) (xy 402.741452 -120.388486) (xy 402.699072 -120.430866) (xy 402.651522 -120.467353)
			(xy 402.599616 -120.49732) (xy 402.544243 -120.520256) (xy 402.48635 -120.535769) (xy 402.426928 -120.543592)
			(xy 402.366992 -120.543592) (xy 402.30757 -120.535769) (xy 402.249677 -120.520256) (xy 402.194304 -120.49732)
			(xy 402.142398 -120.467353) (xy 402.094848 -120.430866) (xy 402.052468 -120.388486) (xy 402.015981 -120.340936)
			(xy 401.986014 -120.28903) (xy 401.963078 -120.233657) (xy 401.947565 -120.175764) (xy 401.939742 -120.116342)
			(xy 401.939252 -120.086374) (xy 383.883408 -120.086374) (xy 383.883408 -120.087898) (xy 383.882918 -120.117866)
			(xy 383.875095 -120.177288) (xy 383.859582 -120.235181) (xy 383.836646 -120.290554) (xy 383.806679 -120.34246)
			(xy 383.770192 -120.39001) (xy 383.727812 -120.43239) (xy 383.680262 -120.468877) (xy 383.628356 -120.498844)
			(xy 383.572983 -120.52178) (xy 383.51509 -120.537293) (xy 383.455668 -120.545116) (xy 383.395732 -120.545116)
			(xy 383.33631 -120.537293) (xy 383.278417 -120.52178) (xy 383.223044 -120.498844) (xy 383.171138 -120.468877)
			(xy 383.123588 -120.43239) (xy 383.081208 -120.39001) (xy 383.044721 -120.34246) (xy 383.014754 -120.290554)
			(xy 382.991818 -120.235181) (xy 382.976305 -120.177288) (xy 382.968482 -120.117866) (xy 382.967992 -120.087898)
			(xy 360.714798 -120.087898) (xy 360.714798 -121.57075) (xy 361.920028 -121.57075) (xy 361.920517 -121.54338)
			(xy 361.928328 -121.489202) (xy 361.943811 -121.436699) (xy 361.966648 -121.386952) (xy 361.996369 -121.340984)
			(xy 362.014008 -121.320052) (xy 362.014262 -121.319798) (xy 362.019863 -121.312722) (xy 362.026099 -121.295797)
			(xy 362.026454 -121.286778) (xy 362.026454 -121.219722) (xy 362.026096 -121.210705) (xy 362.01985 -121.193788)
			(xy 362.014262 -121.186702) (xy 362.014008 -121.186702) (xy 362.014008 -121.186448) (xy 361.996379 -121.165508)
			(xy 361.966666 -121.119537) (xy 361.943827 -121.069792) (xy 361.928334 -121.017293) (xy 361.920503 -120.963119)
			(xy 361.920028 -120.93575) (xy 361.920514 -120.908499) (xy 361.92827 -120.854551) (xy 361.943625 -120.802256)
			(xy 361.966267 -120.752679) (xy 361.995733 -120.706829) (xy 362.031424 -120.665638) (xy 362.072615 -120.629947)
			(xy 362.118465 -120.600481) (xy 362.168042 -120.577839) (xy 362.220337 -120.562484) (xy 362.274285 -120.554728)
			(xy 362.328787 -120.554728) (xy 362.382735 -120.562484) (xy 362.43503 -120.577839) (xy 362.484607 -120.600481)
			(xy 362.530457 -120.629947) (xy 362.571648 -120.665638) (xy 362.607339 -120.706829) (xy 362.636805 -120.752679)
			(xy 362.659447 -120.802256) (xy 362.674802 -120.854551) (xy 362.682558 -120.908499) (xy 362.683044 -120.93575)
			(xy 362.682562 -120.96312) (xy 362.67475 -121.017299) (xy 362.659266 -121.069802) (xy 362.636427 -121.119549)
			(xy 362.606705 -121.165516) (xy 362.589064 -121.186448) (xy 362.58881 -121.186702) (xy 362.583218 -121.193785)
			(xy 362.576974 -121.210704) (xy 362.576618 -121.219722) (xy 362.576618 -121.286778) (xy 362.576982 -121.295794)
			(xy 362.583224 -121.312711) (xy 362.58881 -121.319798) (xy 362.589064 -121.319798) (xy 362.589064 -121.320052)
			(xy 362.606688 -121.340996) (xy 362.636404 -121.386965) (xy 362.659243 -121.436709) (xy 362.674737 -121.489208)
			(xy 362.682569 -121.543382) (xy 362.683044 -121.57075) (xy 362.682558 -121.598001) (xy 362.674802 -121.651949)
			(xy 362.659447 -121.704244) (xy 362.636805 -121.753821) (xy 362.607339 -121.799671) (xy 362.571648 -121.840862)
			(xy 362.530457 -121.876553) (xy 362.502771 -121.894346) (xy 385.6101 -121.894346) (xy 385.6101 -121.030746)
			(xy 385.61059 -121.000778) (xy 385.618413 -120.941356) (xy 385.633926 -120.883463) (xy 385.656862 -120.82809)
			(xy 385.686829 -120.776184) (xy 385.723316 -120.728634) (xy 385.765696 -120.686254) (xy 385.813246 -120.649767)
			(xy 385.865152 -120.6198) (xy 385.920525 -120.596864) (xy 385.978418 -120.581351) (xy 386.03784 -120.573528)
			(xy 386.097776 -120.573528) (xy 386.157198 -120.581351) (xy 386.215091 -120.596864) (xy 386.270464 -120.6198)
			(xy 386.32237 -120.649767) (xy 386.36992 -120.686254) (xy 386.4123 -120.728634) (xy 386.448787 -120.776184)
			(xy 386.478754 -120.82809) (xy 386.50169 -120.883463) (xy 386.517203 -120.941356) (xy 386.525026 -121.000778)
			(xy 386.525516 -121.030746) (xy 386.525516 -121.886472) (xy 400.085052 -121.886472) (xy 400.085052 -121.022872)
			(xy 400.085542 -120.992904) (xy 400.093365 -120.933482) (xy 400.108878 -120.875589) (xy 400.131814 -120.820216)
			(xy 400.161781 -120.76831) (xy 400.198268 -120.72076) (xy 400.240648 -120.67838) (xy 400.288198 -120.641893)
			(xy 400.340104 -120.611926) (xy 400.395477 -120.58899) (xy 400.45337 -120.573477) (xy 400.512792 -120.565654)
			(xy 400.572728 -120.565654) (xy 400.63215 -120.573477) (xy 400.690043 -120.58899) (xy 400.745416 -120.611926)
			(xy 400.797322 -120.641893) (xy 400.844872 -120.67838) (xy 400.887252 -120.72076) (xy 400.923739 -120.76831)
			(xy 400.953706 -120.820216) (xy 400.976642 -120.875589) (xy 400.992155 -120.933482) (xy 400.999978 -120.992904)
			(xy 401.000468 -121.022872) (xy 401.000468 -121.886472) (xy 400.999978 -121.91644) (xy 400.992155 -121.975862)
			(xy 400.976642 -122.033755) (xy 400.953706 -122.089128) (xy 400.923739 -122.141034) (xy 400.887252 -122.188584)
			(xy 400.844872 -122.230964) (xy 400.797322 -122.267451) (xy 400.745416 -122.297418) (xy 400.690043 -122.320354)
			(xy 400.63215 -122.335867) (xy 400.572728 -122.34369) (xy 400.512792 -122.34369) (xy 400.45337 -122.335867)
			(xy 400.395477 -122.320354) (xy 400.340104 -122.297418) (xy 400.288198 -122.267451) (xy 400.240648 -122.230964)
			(xy 400.198268 -122.188584) (xy 400.161781 -122.141034) (xy 400.131814 -122.089128) (xy 400.108878 -122.033755)
			(xy 400.093365 -121.975862) (xy 400.085542 -121.91644) (xy 400.085052 -121.886472) (xy 386.525516 -121.886472)
			(xy 386.525516 -121.894346) (xy 386.525026 -121.924314) (xy 386.517203 -121.983736) (xy 386.50169 -122.041629)
			(xy 386.478754 -122.097002) (xy 386.448787 -122.148908) (xy 386.4123 -122.196458) (xy 386.36992 -122.238838)
			(xy 386.32237 -122.275325) (xy 386.270464 -122.305292) (xy 386.215091 -122.328228) (xy 386.157198 -122.343741)
			(xy 386.097776 -122.351564) (xy 386.03784 -122.351564) (xy 385.978418 -122.343741) (xy 385.920525 -122.328228)
			(xy 385.865152 -122.305292) (xy 385.813246 -122.275325) (xy 385.765696 -122.238838) (xy 385.723316 -122.196458)
			(xy 385.686829 -122.148908) (xy 385.656862 -122.097002) (xy 385.633926 -122.041629) (xy 385.618413 -121.983736)
			(xy 385.61059 -121.924314) (xy 385.6101 -121.894346) (xy 362.502771 -121.894346) (xy 362.484607 -121.906019)
			(xy 362.43503 -121.928661) (xy 362.382735 -121.944016) (xy 362.328787 -121.951772) (xy 362.274285 -121.951772)
			(xy 362.220337 -121.944016) (xy 362.168042 -121.928661) (xy 362.118465 -121.906019) (xy 362.072615 -121.876553)
			(xy 362.031424 -121.840862) (xy 361.995733 -121.799671) (xy 361.966267 -121.753821) (xy 361.943625 -121.704244)
			(xy 361.92827 -121.651949) (xy 361.920514 -121.598001) (xy 361.920028 -121.57075) (xy 360.714798 -121.57075)
			(xy 360.714798 -122.812048) (xy 360.715073 -122.81937) (xy 360.719207 -122.83342) (xy 360.722926 -122.839734)
			(xy 360.74096 -122.867166) (xy 360.75112 -122.876056) (xy 360.75747 -122.879104) (xy 360.780098 -122.89052)
			(xy 360.822384 -122.918462) (xy 360.860585 -122.95177) (xy 360.877612 -122.970544) (xy 360.87939 -122.972576)
			(xy 360.879644 -122.97283) (xy 360.890058 -122.980958) (xy 360.895242 -122.983787) (xy 360.906531 -122.987252)
			(xy 360.91241 -122.987816) (xy 360.98099 -122.988324) (xy 360.986493 -122.9882) (xy 360.997254 -122.985892)
			(xy 361.002326 -122.983752) (xy 361.029504 -122.97156) (xy 361.036362 -122.964194) (xy 361.05447 -122.945513)
			(xy 361.094872 -122.912735) (xy 361.139353 -122.88575) (xy 361.187087 -122.865059) (xy 361.23719 -122.851045)
			(xy 361.288733 -122.843969) (xy 361.314746 -122.843544) (xy 361.315254 -122.843544) (xy 361.340881 -122.843972)
			(xy 361.391669 -122.850866) (xy 361.441073 -122.864509) (xy 361.488201 -122.884655) (xy 361.532202 -122.91094)
			(xy 361.55249 -122.926602) (xy 361.559348 -122.931936) (xy 361.566968 -122.934476) (xy 361.571026 -122.935845)
			(xy 361.579452 -122.93737) (xy 361.583732 -122.937524) (xy 361.605576 -122.937524) (xy 361.611017 -122.937661)
			(xy 361.621653 -122.939959) (xy 361.626658 -122.942096) (xy 361.64012 -122.948446) (xy 361.640374 -122.948446)
			(xy 361.648959 -122.952011) (xy 361.667481 -122.953394) (xy 361.685293 -122.948128) (xy 361.692952 -122.942858)
			(xy 361.714115 -122.924277) (xy 361.760884 -122.892906) (xy 361.811759 -122.868756) (xy 361.865633 -122.852353)
			(xy 361.921334 -122.844053) (xy 361.949492 -122.843544) (xy 361.949746 -122.843544) (xy 361.974478 -122.843917)
			(xy 362.02353 -122.850285) (xy 362.047536 -122.856244) (xy 362.072752 -122.863402) (xy 362.12109 -122.883678)
			(xy 362.166204 -122.910368) (xy 362.186982 -122.926348) (xy 362.187236 -122.926602) (xy 362.189014 -122.928126)
			(xy 362.195542 -122.932426) (xy 362.210413 -122.937213) (xy 362.218224 -122.937524) (xy 362.240576 -122.937524)
			(xy 362.246017 -122.937661) (xy 362.256653 -122.939959) (xy 362.261658 -122.942096) (xy 362.27512 -122.948446)
			(xy 362.275374 -122.948446) (xy 362.28407 -122.952056) (xy 362.302836 -122.953379) (xy 362.320818 -122.947849)
			(xy 362.32846 -122.94235) (xy 362.346748 -122.926856) (xy 362.356723 -122.918947) (xy 362.377568 -122.904328)
			(xy 362.388404 -122.897646) (xy 362.391452 -122.895868) (xy 362.398976 -122.890026) (xy 362.409414 -122.874109)
			(xy 362.411772 -122.86488) (xy 362.415582 -122.847354) (xy 362.415582 -122.846846) (xy 362.418884 -122.832368)
			(xy 362.419646 -122.823732) (xy 362.419646 -122.769122) (xy 362.418122 -122.75693) (xy 362.415836 -122.747786)
			(xy 362.414058 -122.744992) (xy 362.411264 -122.740674) (xy 362.410248 -122.738896) (xy 362.409232 -122.737118)
			(xy 362.408724 -122.73661) (xy 362.395515 -122.71439) (xy 362.374548 -122.667141) (xy 362.360144 -122.617495)
			(xy 362.352567 -122.566361) (xy 362.351828 -122.540522) (xy 362.351828 -122.533156) (xy 362.352501 -122.506034)
			(xy 362.360573 -122.452385) (xy 362.376165 -122.400421) (xy 362.398961 -122.35119) (xy 362.428503 -122.305685)
			(xy 362.464193 -122.264825) (xy 362.505312 -122.229433) (xy 362.551031 -122.200224) (xy 362.600427 -122.177787)
			(xy 362.652503 -122.162574) (xy 362.70621 -122.154893) (xy 362.733336 -122.154442) (xy 362.760586 -122.154908)
			(xy 362.81453 -122.162669) (xy 362.866821 -122.178029) (xy 362.916393 -122.200674) (xy 362.962238 -122.230144)
			(xy 363.003423 -122.265838) (xy 363.039108 -122.307031) (xy 363.068567 -122.352882) (xy 363.091201 -122.40246)
			(xy 363.106549 -122.454754) (xy 363.114298 -122.5087) (xy 363.114844 -122.53595) (xy 363.114374 -122.563369)
			(xy 363.106536 -122.617644) (xy 363.091015 -122.670239) (xy 363.06813 -122.720074) (xy 363.038351 -122.766122)
			(xy 363.002291 -122.807436) (xy 362.960691 -122.843167) (xy 362.937806 -122.858276) (xy 362.929678 -122.86361)
			(xy 362.90631 -122.895614) (xy 362.904024 -122.906282) (xy 362.899452 -122.92711) (xy 362.898436 -122.937778)
			(xy 362.898436 -122.99188) (xy 362.89996 -123.004072) (xy 362.902246 -123.013216) (xy 362.904532 -123.016772)
			(xy 362.910882 -123.026678) (xy 362.923781 -123.048689) (xy 362.94422 -123.095433) (xy 362.958233 -123.144489)
			(xy 362.965567 -123.194977) (xy 362.966254 -123.22048) (xy 362.966254 -123.2281) (xy 362.965564 -123.25521)
			(xy 362.957462 -123.30883) (xy 362.941848 -123.360763) (xy 362.919037 -123.40996) (xy 362.889489 -123.455432)
			(xy 362.853798 -123.49626) (xy 362.812685 -123.531623) (xy 362.766979 -123.560807) (xy 362.7176 -123.583223)
			(xy 362.665544 -123.598421) (xy 362.611861 -123.606093) (xy 362.584746 -123.60656) (xy 362.584238 -123.60656)
			(xy 362.558611 -123.606132) (xy 362.507824 -123.599237) (xy 362.45842 -123.585592) (xy 362.411292 -123.565446)
			(xy 362.367292 -123.539161) (xy 362.347002 -123.523502) (xy 362.340144 -123.518168) (xy 362.332524 -123.515628)
			(xy 362.328467 -123.514252) (xy 362.320041 -123.512711) (xy 362.31576 -123.51258) (xy 362.293916 -123.51258)
			(xy 362.288475 -123.512442) (xy 362.27784 -123.510143) (xy 362.272834 -123.508008) (xy 362.259372 -123.501658)
			(xy 362.250906 -123.498071) (xy 362.232597 -123.496556) (xy 362.214932 -123.501604) (xy 362.207302 -123.506738)
			(xy 362.203746 -123.509786) (xy 362.182655 -123.527908) (xy 362.136215 -123.55849) (xy 362.085829 -123.582013)
			(xy 362.032565 -123.597979) (xy 361.977549 -123.60605) (xy 361.949746 -123.60656) (xy 361.949492 -123.60656)
			(xy 361.924824 -123.606174) (xy 361.8759 -123.599805) (xy 361.851956 -123.59386) (xy 361.82674 -123.586702)
			(xy 361.778403 -123.566425) (xy 361.733289 -123.539734) (xy 361.71251 -123.523756) (xy 361.712256 -123.523502)
			(xy 361.710478 -123.521978) (xy 361.70395 -123.517678) (xy 361.689078 -123.512894) (xy 361.681268 -123.51258)
			(xy 361.658916 -123.51258) (xy 361.653475 -123.512442) (xy 361.64284 -123.510143) (xy 361.637834 -123.508008)
			(xy 361.624372 -123.501658) (xy 361.615906 -123.498071) (xy 361.597597 -123.496556) (xy 361.579932 -123.501604)
			(xy 361.572302 -123.506738) (xy 361.568746 -123.509786) (xy 361.547655 -123.527908) (xy 361.501215 -123.55849)
			(xy 361.450829 -123.582013) (xy 361.397565 -123.597979) (xy 361.342549 -123.60605) (xy 361.314746 -123.60656)
			(xy 361.288508 -123.606126) (xy 361.236526 -123.598935) (xy 361.186022 -123.584683) (xy 361.13795 -123.56364)
			(xy 361.093218 -123.536202) (xy 361.052672 -123.502889) (xy 361.034584 -123.483878) (xy 361.027472 -123.476258)
			(xy 360.999786 -123.464066) (xy 360.990134 -123.459748) (xy 360.91876 -123.45924) (xy 360.913426 -123.45924)
			(xy 360.908128 -123.459378) (xy 360.897758 -123.461553) (xy 360.892852 -123.463558) (xy 360.8832 -123.467876)
			(xy 360.864119 -123.489744) (xy 360.820497 -123.528022) (xy 360.771596 -123.559274) (xy 360.745278 -123.571508)
			(xy 360.74477 -123.571508) (xy 360.744516 -123.571762) (xy 360.738052 -123.574992) (xy 360.727098 -123.584404)
			(xy 360.722926 -123.590304) (xy 360.718862 -123.5964) (xy 360.714798 -123.61037) (xy 360.714798 -123.68784)
			(xy 382.967992 -123.68784) (xy 382.967992 -122.82424) (xy 382.968482 -122.794272) (xy 382.976305 -122.73485)
			(xy 382.991818 -122.676957) (xy 383.014754 -122.621584) (xy 383.044721 -122.569678) (xy 383.081208 -122.522128)
			(xy 383.123588 -122.479748) (xy 383.171138 -122.443261) (xy 383.223044 -122.413294) (xy 383.278417 -122.390358)
			(xy 383.33631 -122.374845) (xy 383.395732 -122.367022) (xy 383.455668 -122.367022) (xy 383.51509 -122.374845)
			(xy 383.572983 -122.390358) (xy 383.628356 -122.413294) (xy 383.680262 -122.443261) (xy 383.727812 -122.479748)
			(xy 383.770192 -122.522128) (xy 383.806679 -122.569678) (xy 383.836646 -122.621584) (xy 383.859582 -122.676957)
			(xy 383.875095 -122.73485) (xy 383.882918 -122.794272) (xy 383.883408 -122.82424) (xy 383.883408 -123.686316)
			(xy 401.939252 -123.686316) (xy 401.939252 -122.822716) (xy 401.939742 -122.792748) (xy 401.947565 -122.733326)
			(xy 401.963078 -122.675433) (xy 401.986014 -122.62006) (xy 402.015981 -122.568154) (xy 402.052468 -122.520604)
			(xy 402.094848 -122.478224) (xy 402.142398 -122.441737) (xy 402.194304 -122.41177) (xy 402.249677 -122.388834)
			(xy 402.30757 -122.373321) (xy 402.366992 -122.365498) (xy 402.426928 -122.365498) (xy 402.48635 -122.373321)
			(xy 402.544243 -122.388834) (xy 402.599616 -122.41177) (xy 402.651522 -122.441737) (xy 402.699072 -122.478224)
			(xy 402.741452 -122.520604) (xy 402.777939 -122.568154) (xy 402.807906 -122.62006) (xy 402.830842 -122.675433)
			(xy 402.846355 -122.733326) (xy 402.854178 -122.792748) (xy 402.854668 -122.822716) (xy 402.854668 -123.686316)
			(xy 402.854178 -123.716284) (xy 402.846355 -123.775706) (xy 402.830842 -123.833599) (xy 402.807906 -123.888972)
			(xy 402.777939 -123.940878) (xy 402.741452 -123.988428) (xy 402.699072 -124.030808) (xy 402.651522 -124.067295)
			(xy 402.599616 -124.097262) (xy 402.544243 -124.120198) (xy 402.48635 -124.135711) (xy 402.426928 -124.143534)
			(xy 402.366992 -124.143534) (xy 402.30757 -124.135711) (xy 402.249677 -124.120198) (xy 402.194304 -124.097262)
			(xy 402.142398 -124.067295) (xy 402.094848 -124.030808) (xy 402.052468 -123.988428) (xy 402.015981 -123.940878)
			(xy 401.986014 -123.888972) (xy 401.963078 -123.833599) (xy 401.947565 -123.775706) (xy 401.939742 -123.716284)
			(xy 401.939252 -123.686316) (xy 383.883408 -123.686316) (xy 383.883408 -123.68784) (xy 383.882918 -123.717808)
			(xy 383.875095 -123.77723) (xy 383.859582 -123.835123) (xy 383.836646 -123.890496) (xy 383.806679 -123.942402)
			(xy 383.770192 -123.989952) (xy 383.727812 -124.032332) (xy 383.680262 -124.068819) (xy 383.628356 -124.098786)
			(xy 383.572983 -124.121722) (xy 383.51509 -124.137235) (xy 383.455668 -124.145058) (xy 383.395732 -124.145058)
			(xy 383.33631 -124.137235) (xy 383.278417 -124.121722) (xy 383.223044 -124.098786) (xy 383.171138 -124.068819)
			(xy 383.123588 -124.032332) (xy 383.081208 -123.989952) (xy 383.044721 -123.942402) (xy 383.014754 -123.890496)
			(xy 382.991818 -123.835123) (xy 382.976305 -123.77723) (xy 382.968482 -123.717808) (xy 382.967992 -123.68784)
			(xy 360.714798 -123.68784) (xy 360.714798 -125.403356) (xy 363.844332 -125.403356) (xy 363.844823 -125.375987)
			(xy 363.852634 -125.321808) (xy 363.868116 -125.269305) (xy 363.890953 -125.219558) (xy 363.920673 -125.17359)
			(xy 363.938312 -125.152658) (xy 363.938566 -125.152404) (xy 363.944165 -125.145326) (xy 363.950402 -125.128402)
			(xy 363.950758 -125.119384) (xy 363.950758 -125.052328) (xy 363.950397 -125.043311) (xy 363.944153 -125.026394)
			(xy 363.938566 -125.019308) (xy 363.938312 -125.019308) (xy 363.938312 -125.019054) (xy 363.920687 -124.998111)
			(xy 363.890972 -124.952141) (xy 363.868134 -124.902397) (xy 363.852639 -124.849898) (xy 363.844808 -124.795724)
			(xy 363.844332 -124.768356) (xy 363.844818 -124.741105) (xy 363.852574 -124.687157) (xy 363.867929 -124.634862)
			(xy 363.890571 -124.585285) (xy 363.920037 -124.539435) (xy 363.955728 -124.498244) (xy 363.996919 -124.462553)
			(xy 364.042769 -124.433087) (xy 364.092346 -124.410445) (xy 364.144641 -124.39509) (xy 364.198589 -124.387334)
			(xy 364.253091 -124.387334) (xy 364.307039 -124.39509) (xy 364.359334 -124.410445) (xy 364.408911 -124.433087)
			(xy 364.454761 -124.462553) (xy 364.495952 -124.498244) (xy 364.531643 -124.539435) (xy 364.561109 -124.585285)
			(xy 364.583751 -124.634862) (xy 364.599106 -124.687157) (xy 364.606862 -124.741105) (xy 364.607348 -124.768356)
			(xy 364.606869 -124.795726) (xy 364.599056 -124.849905) (xy 364.583571 -124.902408) (xy 364.560732 -124.952156)
			(xy 364.531009 -124.998122) (xy 364.513368 -125.019054) (xy 364.513114 -125.019308) (xy 364.507519 -125.026389)
			(xy 364.501277 -125.04331) (xy 364.500922 -125.052328) (xy 364.500922 -125.119384) (xy 364.501282 -125.128401)
			(xy 364.507527 -125.145318) (xy 364.513114 -125.152404) (xy 364.513368 -125.152404) (xy 364.513368 -125.152658)
			(xy 364.530996 -125.173599) (xy 364.560711 -125.219569) (xy 364.583549 -125.269314) (xy 364.599043 -125.321813)
			(xy 364.606873 -125.375987) (xy 364.607348 -125.403356) (xy 364.606862 -125.430607) (xy 364.599106 -125.484555)
			(xy 364.583751 -125.53685) (xy 364.561109 -125.586427) (xy 364.531643 -125.632277) (xy 364.495952 -125.673468)
			(xy 364.454761 -125.709159) (xy 364.408911 -125.738625) (xy 364.359334 -125.761267) (xy 364.307039 -125.776622)
			(xy 364.253091 -125.784378) (xy 364.198589 -125.784378) (xy 364.144641 -125.776622) (xy 364.092346 -125.761267)
			(xy 364.042769 -125.738625) (xy 363.996919 -125.709159) (xy 363.955728 -125.673468) (xy 363.920037 -125.632277)
			(xy 363.890571 -125.586427) (xy 363.867929 -125.53685) (xy 363.852574 -125.484555) (xy 363.844818 -125.430607)
			(xy 363.844332 -125.403356) (xy 360.714798 -125.403356) (xy 360.714798 -125.853698) (xy 364.784894 -125.853698)
			(xy 364.78536 -125.826328) (xy 364.793178 -125.772149) (xy 364.808667 -125.719646) (xy 364.831509 -125.669899)
			(xy 364.861233 -125.623932) (xy 364.878874 -125.603) (xy 364.879128 -125.602746) (xy 364.884705 -125.595653)
			(xy 364.890956 -125.578741) (xy 364.89132 -125.569726) (xy 364.89132 -125.50267) (xy 364.890973 -125.493652)
			(xy 364.884718 -125.476735) (xy 364.879128 -125.46965) (xy 364.878874 -125.46965) (xy 364.878874 -125.469396)
			(xy 364.861216 -125.44848) (xy 364.831507 -125.402502) (xy 364.808676 -125.352751) (xy 364.793189 -125.300247)
			(xy 364.785366 -125.246068) (xy 364.784894 -125.218698) (xy 364.78538 -125.191447) (xy 364.793136 -125.137499)
			(xy 364.808491 -125.085204) (xy 364.831133 -125.035627) (xy 364.860599 -124.989777) (xy 364.89629 -124.948586)
			(xy 364.937481 -124.912895) (xy 364.983331 -124.883429) (xy 365.032908 -124.860787) (xy 365.085203 -124.845432)
			(xy 365.139151 -124.837676) (xy 365.193653 -124.837676) (xy 365.247601 -124.845432) (xy 365.299896 -124.860787)
			(xy 365.349473 -124.883429) (xy 365.395323 -124.912895) (xy 365.436514 -124.948586) (xy 365.472205 -124.989777)
			(xy 365.501671 -125.035627) (xy 365.524313 -125.085204) (xy 365.539668 -125.137499) (xy 365.547424 -125.191447)
			(xy 365.54791 -125.218698) (xy 365.54744 -125.246068) (xy 365.539623 -125.300247) (xy 365.524135 -125.35275)
			(xy 365.501294 -125.402497) (xy 365.471571 -125.448464) (xy 365.45393 -125.469396) (xy 365.453676 -125.46965)
			(xy 365.448102 -125.476745) (xy 365.441848 -125.493655) (xy 365.441484 -125.50267) (xy 365.441484 -125.569726)
			(xy 365.441832 -125.578744) (xy 365.448086 -125.59566) (xy 365.453676 -125.602746) (xy 365.45393 -125.602746)
			(xy 365.45393 -125.603) (xy 365.471587 -125.623917) (xy 365.501295 -125.669895) (xy 365.524127 -125.719646)
			(xy 365.539614 -125.77215) (xy 365.547438 -125.826328) (xy 365.54791 -125.853698) (xy 365.547424 -125.880949)
			(xy 365.539668 -125.934897) (xy 365.524313 -125.987192) (xy 365.501671 -126.036769) (xy 365.472205 -126.082619)
			(xy 365.436514 -126.12381) (xy 365.395323 -126.159501) (xy 365.349473 -126.188967) (xy 365.299896 -126.211609)
			(xy 365.247601 -126.226964) (xy 365.193653 -126.23472) (xy 365.139151 -126.23472) (xy 365.085203 -126.226964)
			(xy 365.032908 -126.211609) (xy 364.983331 -126.188967) (xy 364.937481 -126.159501) (xy 364.89629 -126.12381)
			(xy 364.860599 -126.082619) (xy 364.831133 -126.036769) (xy 364.808491 -125.987192) (xy 364.793136 -125.934897)
			(xy 364.78538 -125.880949) (xy 364.784894 -125.853698) (xy 360.714798 -125.853698) (xy 360.714798 -126.530354)
			(xy 365.993426 -126.530354) (xy 365.993968 -126.50269) (xy 366.001961 -126.447942) (xy 366.017771 -126.39492)
			(xy 366.041069 -126.344736) (xy 366.071366 -126.298439) (xy 366.108028 -126.257001) (xy 366.150286 -126.221287)
			(xy 366.173512 -126.20625) (xy 366.183163 -126.199581) (xy 366.195622 -126.179744) (xy 366.197388 -126.16815)
			(xy 366.205262 -126.08814) (xy 366.205858 -126.076503) (xy 366.197802 -126.054668) (xy 366.189768 -126.04623)
			(xy 366.189514 -126.045976) (xy 366.170942 -126.027886) (xy 366.138362 -125.987557) (xy 366.111547 -125.943184)
			(xy 366.090993 -125.895587) (xy 366.077078 -125.845645) (xy 366.070059 -125.794277) (xy 366.069626 -125.768354)
			(xy 366.070035 -125.7411) (xy 366.077799 -125.687148) (xy 366.093161 -125.63485) (xy 366.11581 -125.58527)
			(xy 366.145285 -125.539418) (xy 366.180984 -125.498228) (xy 366.222182 -125.462537) (xy 366.26804 -125.433072)
			(xy 366.317625 -125.410433) (xy 366.369926 -125.395082) (xy 366.42388 -125.387329) (xy 366.451134 -125.386846)
			(xy 366.478505 -125.387281) (xy 366.532686 -125.395105) (xy 366.58519 -125.4106) (xy 366.634937 -125.433449)
			(xy 366.680902 -125.463181) (xy 366.701832 -125.480826) (xy 366.702086 -125.48108) (xy 366.709166 -125.486676)
			(xy 366.726088 -125.492915) (xy 366.735106 -125.493272) (xy 366.802162 -125.493272) (xy 366.811178 -125.492903)
			(xy 366.828095 -125.486664) (xy 366.835182 -125.48108) (xy 366.835182 -125.480826) (xy 366.835436 -125.480826)
			(xy 366.856385 -125.463207) (xy 366.902353 -125.433492) (xy 366.952096 -125.410651) (xy 367.004593 -125.395156)
			(xy 367.058766 -125.387322) (xy 367.086134 -125.386846) (xy 367.113384 -125.387346) (xy 367.167329 -125.395106)
			(xy 367.21962 -125.410463) (xy 367.269195 -125.433105) (xy 367.315043 -125.46257) (xy 367.356231 -125.49826)
			(xy 367.391922 -125.539448) (xy 367.421389 -125.585295) (xy 367.444033 -125.634868) (xy 367.459391 -125.687159)
			(xy 367.467153 -125.741104) (xy 367.467642 -125.768354) (xy 367.467113 -125.797271) (xy 367.458389 -125.854442)
			(xy 367.441135 -125.909642) (xy 367.415745 -125.961604) (xy 367.382803 -126.009138) (xy 367.343062 -126.051155)
			(xy 367.320576 -126.069344) (xy 367.311755 -126.076938) (xy 367.30158 -126.097849) (xy 367.301018 -126.109476)
			(xy 367.301018 -126.189232) (xy 367.301547 -126.200865) (xy 367.311742 -126.221775) (xy 367.320576 -126.229364)
			(xy 367.343037 -126.247581) (xy 367.382775 -126.289595) (xy 367.415717 -126.337124) (xy 367.44111 -126.38908)
			(xy 367.45837 -126.444274) (xy 367.467104 -126.501439) (xy 367.467642 -126.530354) (xy 367.467102 -126.557604)
			(xy 367.459352 -126.611551) (xy 367.447251 -126.652782) (xy 367.738914 -126.652782) (xy 367.739366 -126.625411)
			(xy 367.747187 -126.571231) (xy 367.762679 -126.518728) (xy 367.785524 -126.468981) (xy 367.815251 -126.423015)
			(xy 367.832894 -126.402084) (xy 367.833148 -126.40183) (xy 367.838734 -126.394743) (xy 367.84498 -126.377826)
			(xy 367.84534 -126.36881) (xy 367.84534 -126.301754) (xy 367.84497 -126.292738) (xy 367.838733 -126.27582)
			(xy 367.833148 -126.268734) (xy 367.832894 -126.268734) (xy 367.832894 -126.26848) (xy 367.815237 -126.247561)
			(xy 367.785515 -126.20159) (xy 367.762673 -126.151841) (xy 367.74718 -126.099337) (xy 367.739354 -126.045158)
			(xy 367.739355 -125.990415) (xy 367.747186 -125.936236) (xy 367.762683 -125.883733) (xy 367.785529 -125.833986)
			(xy 367.815253 -125.788017) (xy 367.832894 -125.767084) (xy 367.833148 -125.76683) (xy 367.838734 -125.759743)
			(xy 367.84498 -125.742826) (xy 367.84534 -125.73381) (xy 367.84534 -125.666754) (xy 367.84497 -125.657738)
			(xy 367.838733 -125.64082) (xy 367.833148 -125.633734) (xy 367.832894 -125.633734) (xy 367.832894 -125.63348)
			(xy 367.815237 -125.612561) (xy 367.785515 -125.56659) (xy 367.762673 -125.516841) (xy 367.74718 -125.464337)
			(xy 367.739354 -125.410158) (xy 367.739355 -125.355415) (xy 367.747186 -125.301236) (xy 367.762683 -125.248733)
			(xy 367.785529 -125.198986) (xy 367.815253 -125.153017) (xy 367.832894 -125.132084) (xy 367.833148 -125.13183)
			(xy 367.838734 -125.124743) (xy 367.84498 -125.107826) (xy 367.84534 -125.09881) (xy 367.84534 -125.031754)
			(xy 367.84497 -125.022738) (xy 367.838733 -125.00582) (xy 367.833148 -124.998734) (xy 367.832894 -124.998734)
			(xy 367.832894 -124.99848) (xy 367.815278 -124.977529) (xy 367.785563 -124.931562) (xy 367.762723 -124.881819)
			(xy 367.747226 -124.829322) (xy 367.739392 -124.77515) (xy 367.738914 -124.747782) (xy 367.7394 -124.720531)
			(xy 367.747156 -124.666583) (xy 367.762511 -124.614288) (xy 367.785153 -124.564711) (xy 367.814619 -124.518861)
			(xy 367.85031 -124.47767) (xy 367.891501 -124.441979) (xy 367.937351 -124.412513) (xy 367.986928 -124.389871)
			(xy 368.039223 -124.374516) (xy 368.093171 -124.36676) (xy 368.147673 -124.36676) (xy 368.201621 -124.374516)
			(xy 368.253916 -124.389871) (xy 368.303493 -124.412513) (xy 368.349343 -124.441979) (xy 368.390534 -124.47767)
			(xy 368.426225 -124.518861) (xy 368.455691 -124.564711) (xy 368.478333 -124.614288) (xy 368.493688 -124.666583)
			(xy 368.501444 -124.720531) (xy 368.50193 -124.747782) (xy 368.50147 -124.775153) (xy 368.493654 -124.829333)
			(xy 368.478164 -124.881837) (xy 368.45532 -124.931583) (xy 368.425593 -124.977549) (xy 368.40795 -124.99848)
			(xy 368.407696 -124.998734) (xy 368.40213 -125.005835) (xy 368.395871 -125.022741) (xy 368.395504 -125.031754)
			(xy 368.395504 -125.09881) (xy 368.395855 -125.107827) (xy 368.402107 -125.124744) (xy 368.407696 -125.13183)
			(xy 368.40795 -125.13183) (xy 368.40795 -125.132084) (xy 368.425574 -125.153031) (xy 368.455301 -125.198995)
			(xy 368.478149 -125.248739) (xy 368.493648 -125.301239) (xy 368.501479 -125.355416) (xy 368.50148 -125.410156)
			(xy 368.493654 -125.464334) (xy 368.484738 -125.494542) (xy 385.6101 -125.494542) (xy 385.6101 -124.630942)
			(xy 385.61059 -124.600974) (xy 385.618413 -124.541552) (xy 385.633926 -124.483659) (xy 385.656862 -124.428286)
			(xy 385.686829 -124.37638) (xy 385.723316 -124.32883) (xy 385.765696 -124.28645) (xy 385.813246 -124.249963)
			(xy 385.865152 -124.219996) (xy 385.920525 -124.19706) (xy 385.978418 -124.181547) (xy 386.03784 -124.173724)
			(xy 386.097776 -124.173724) (xy 386.157198 -124.181547) (xy 386.215091 -124.19706) (xy 386.270464 -124.219996)
			(xy 386.32237 -124.249963) (xy 386.36992 -124.28645) (xy 386.4123 -124.32883) (xy 386.448787 -124.37638)
			(xy 386.478754 -124.428286) (xy 386.50169 -124.483659) (xy 386.517203 -124.541552) (xy 386.525026 -124.600974)
			(xy 386.525516 -124.630942) (xy 386.525516 -125.486414) (xy 400.085052 -125.486414) (xy 400.085052 -124.622814)
			(xy 400.085542 -124.592846) (xy 400.093365 -124.533424) (xy 400.108878 -124.475531) (xy 400.131814 -124.420158)
			(xy 400.161781 -124.368252) (xy 400.198268 -124.320702) (xy 400.240648 -124.278322) (xy 400.288198 -124.241835)
			(xy 400.340104 -124.211868) (xy 400.395477 -124.188932) (xy 400.45337 -124.173419) (xy 400.512792 -124.165596)
			(xy 400.572728 -124.165596) (xy 400.63215 -124.173419) (xy 400.690043 -124.188932) (xy 400.745416 -124.211868)
			(xy 400.797322 -124.241835) (xy 400.844872 -124.278322) (xy 400.887252 -124.320702) (xy 400.923739 -124.368252)
			(xy 400.953706 -124.420158) (xy 400.976642 -124.475531) (xy 400.992155 -124.533424) (xy 400.999978 -124.592846)
			(xy 401.000468 -124.622814) (xy 401.000468 -125.486414) (xy 400.999978 -125.516382) (xy 400.992155 -125.575804)
			(xy 400.976642 -125.633697) (xy 400.953706 -125.68907) (xy 400.923739 -125.740976) (xy 400.887252 -125.788526)
			(xy 400.844872 -125.830906) (xy 400.797322 -125.867393) (xy 400.745416 -125.89736) (xy 400.690043 -125.920296)
			(xy 400.63215 -125.935809) (xy 400.572728 -125.943632) (xy 400.512792 -125.943632) (xy 400.45337 -125.935809)
			(xy 400.395477 -125.920296) (xy 400.340104 -125.89736) (xy 400.288198 -125.867393) (xy 400.240648 -125.830906)
			(xy 400.198268 -125.788526) (xy 400.161781 -125.740976) (xy 400.131814 -125.68907) (xy 400.108878 -125.633697)
			(xy 400.093365 -125.575804) (xy 400.085542 -125.516382) (xy 400.085052 -125.486414) (xy 386.525516 -125.486414)
			(xy 386.525516 -125.494542) (xy 386.525026 -125.52451) (xy 386.517203 -125.583932) (xy 386.50169 -125.641825)
			(xy 386.478754 -125.697198) (xy 386.448787 -125.749104) (xy 386.4123 -125.796654) (xy 386.36992 -125.839034)
			(xy 386.32237 -125.875521) (xy 386.270464 -125.905488) (xy 386.215091 -125.928424) (xy 386.157198 -125.943937)
			(xy 386.097776 -125.95176) (xy 386.03784 -125.95176) (xy 385.978418 -125.943937) (xy 385.920525 -125.928424)
			(xy 385.865152 -125.905488) (xy 385.813246 -125.875521) (xy 385.765696 -125.839034) (xy 385.723316 -125.796654)
			(xy 385.686829 -125.749104) (xy 385.656862 -125.697198) (xy 385.633926 -125.641825) (xy 385.618413 -125.583932)
			(xy 385.61059 -125.52451) (xy 385.6101 -125.494542) (xy 368.484738 -125.494542) (xy 368.478159 -125.516835)
			(xy 368.455314 -125.566581) (xy 368.42559 -125.612548) (xy 368.40795 -125.63348) (xy 368.407696 -125.633734)
			(xy 368.40213 -125.640835) (xy 368.395871 -125.657741) (xy 368.395504 -125.666754) (xy 368.395504 -125.73381)
			(xy 368.395855 -125.742827) (xy 368.402107 -125.759744) (xy 368.407696 -125.76683) (xy 368.40795 -125.76683)
			(xy 368.40795 -125.767084) (xy 368.425574 -125.788031) (xy 368.455301 -125.833995) (xy 368.478149 -125.883739)
			(xy 368.493648 -125.936239) (xy 368.501479 -125.990416) (xy 368.50148 -126.045156) (xy 368.493654 -126.099334)
			(xy 368.478159 -126.151835) (xy 368.455314 -126.201581) (xy 368.42559 -126.247548) (xy 368.40795 -126.26848)
			(xy 368.407696 -126.268734) (xy 368.40213 -126.275835) (xy 368.395871 -126.292741) (xy 368.395504 -126.301754)
			(xy 368.395504 -126.36881) (xy 368.395855 -126.377827) (xy 368.402107 -126.394744) (xy 368.407696 -126.40183)
			(xy 368.40795 -126.40183) (xy 368.40795 -126.402084) (xy 368.425587 -126.423018) (xy 368.455301 -126.468989)
			(xy 368.478138 -126.518736) (xy 368.493629 -126.571237) (xy 368.501457 -126.625413) (xy 368.50193 -126.652782)
			(xy 368.501444 -126.680033) (xy 368.493688 -126.733981) (xy 368.478333 -126.786276) (xy 368.455691 -126.835853)
			(xy 368.426225 -126.881703) (xy 368.390534 -126.922894) (xy 368.349343 -126.958585) (xy 368.303493 -126.988051)
			(xy 368.253916 -127.010693) (xy 368.201621 -127.026048) (xy 368.147673 -127.033804) (xy 368.093171 -127.033804)
			(xy 368.039223 -127.026048) (xy 367.986928 -127.010693) (xy 367.937351 -126.988051) (xy 367.891501 -126.958585)
			(xy 367.85031 -126.922894) (xy 367.814619 -126.881703) (xy 367.785153 -126.835853) (xy 367.762511 -126.786276)
			(xy 367.747156 -126.733981) (xy 367.7394 -126.680033) (xy 367.738914 -126.652782) (xy 367.447251 -126.652782)
			(xy 367.444004 -126.663845) (xy 367.421369 -126.713423) (xy 367.391909 -126.759274) (xy 367.356223 -126.800467)
			(xy 367.315038 -126.836161) (xy 367.269193 -126.865631) (xy 367.21962 -126.888276) (xy 367.167329 -126.903635)
			(xy 367.113384 -126.911396) (xy 367.086134 -126.911862) (xy 367.059818 -126.911451) (xy 367.007687 -126.904206)
			(xy 366.957042 -126.889877) (xy 366.908843 -126.868734) (xy 366.864001 -126.841177) (xy 366.823365 -126.807728)
			(xy 366.80521 -126.788672) (xy 366.797677 -126.781283) (xy 366.778406 -126.772749) (xy 366.767872 -126.772162)
			(xy 366.693196 -126.772162) (xy 366.682646 -126.772687) (xy 366.663352 -126.781226) (xy 366.655858 -126.788672)
			(xy 366.63771 -126.807736) (xy 366.59708 -126.841193) (xy 366.552238 -126.868752) (xy 366.504035 -126.889889)
			(xy 366.453386 -126.904204) (xy 366.401251 -126.911426) (xy 366.374934 -126.911862) (xy 366.34768 -126.911413)
			(xy 366.293726 -126.903659) (xy 366.241425 -126.888305) (xy 366.191842 -126.865663) (xy 366.145987 -126.836195)
			(xy 366.104792 -126.800499) (xy 366.069098 -126.759304) (xy 366.039631 -126.713447) (xy 366.01699 -126.663864)
			(xy 366.001638 -126.611562) (xy 365.993886 -126.557608) (xy 365.993426 -126.530354) (xy 360.714798 -126.530354)
			(xy 360.714798 -131.297934) (xy 382.967992 -131.297934) (xy 382.967992 -130.434334) (xy 382.968482 -130.404366)
			(xy 382.976305 -130.344944) (xy 382.991818 -130.287051) (xy 383.014754 -130.231678) (xy 383.044721 -130.179772)
			(xy 383.081208 -130.132222) (xy 383.123588 -130.089842) (xy 383.171138 -130.053355) (xy 383.223044 -130.023388)
			(xy 383.278417 -130.000452) (xy 383.33631 -129.984939) (xy 383.395732 -129.977116) (xy 383.455668 -129.977116)
			(xy 383.51509 -129.984939) (xy 383.572983 -130.000452) (xy 383.628356 -130.023388) (xy 383.680262 -130.053355)
			(xy 383.727812 -130.089842) (xy 383.770192 -130.132222) (xy 383.806679 -130.179772) (xy 383.836646 -130.231678)
			(xy 383.859582 -130.287051) (xy 383.875095 -130.344944) (xy 383.882918 -130.404366) (xy 383.883408 -130.434334)
			(xy 383.883408 -131.29641) (xy 401.939252 -131.29641) (xy 401.939252 -130.43281) (xy 401.939742 -130.402842)
			(xy 401.947565 -130.34342) (xy 401.963078 -130.285527) (xy 401.986014 -130.230154) (xy 402.015981 -130.178248)
			(xy 402.052468 -130.130698) (xy 402.094848 -130.088318) (xy 402.142398 -130.051831) (xy 402.194304 -130.021864)
			(xy 402.249677 -129.998928) (xy 402.30757 -129.983415) (xy 402.366992 -129.975592) (xy 402.426928 -129.975592)
			(xy 402.48635 -129.983415) (xy 402.544243 -129.998928) (xy 402.599616 -130.021864) (xy 402.651522 -130.051831)
			(xy 402.699072 -130.088318) (xy 402.741452 -130.130698) (xy 402.777939 -130.178248) (xy 402.807906 -130.230154)
			(xy 402.830842 -130.285527) (xy 402.846355 -130.34342) (xy 402.854178 -130.402842) (xy 402.854668 -130.43281)
			(xy 402.854668 -131.29641) (xy 402.854178 -131.326378) (xy 402.846355 -131.3858) (xy 402.830842 -131.443693)
			(xy 402.807906 -131.499066) (xy 402.777939 -131.550972) (xy 402.741452 -131.598522) (xy 402.699072 -131.640902)
			(xy 402.651522 -131.677389) (xy 402.599616 -131.707356) (xy 402.544243 -131.730292) (xy 402.48635 -131.745805)
			(xy 402.426928 -131.753628) (xy 402.366992 -131.753628) (xy 402.30757 -131.745805) (xy 402.249677 -131.730292)
			(xy 402.194304 -131.707356) (xy 402.142398 -131.677389) (xy 402.094848 -131.640902) (xy 402.052468 -131.598522)
			(xy 402.015981 -131.550972) (xy 401.986014 -131.499066) (xy 401.963078 -131.443693) (xy 401.947565 -131.3858)
			(xy 401.939742 -131.326378) (xy 401.939252 -131.29641) (xy 383.883408 -131.29641) (xy 383.883408 -131.297934)
			(xy 383.882918 -131.327902) (xy 383.875095 -131.387324) (xy 383.859582 -131.445217) (xy 383.836646 -131.50059)
			(xy 383.806679 -131.552496) (xy 383.770192 -131.600046) (xy 383.727812 -131.642426) (xy 383.680262 -131.678913)
			(xy 383.628356 -131.70888) (xy 383.572983 -131.731816) (xy 383.51509 -131.747329) (xy 383.455668 -131.755152)
			(xy 383.395732 -131.755152) (xy 383.33631 -131.747329) (xy 383.278417 -131.731816) (xy 383.223044 -131.70888)
			(xy 383.171138 -131.678913) (xy 383.123588 -131.642426) (xy 383.081208 -131.600046) (xy 383.044721 -131.552496)
			(xy 383.014754 -131.50059) (xy 382.991818 -131.445217) (xy 382.976305 -131.387324) (xy 382.968482 -131.327902)
			(xy 382.967992 -131.297934) (xy 360.714798 -131.297934) (xy 360.714798 -133.104382) (xy 385.6101 -133.104382)
			(xy 385.6101 -132.240782) (xy 385.61059 -132.210814) (xy 385.618413 -132.151392) (xy 385.633926 -132.093499)
			(xy 385.656862 -132.038126) (xy 385.686829 -131.98622) (xy 385.723316 -131.93867) (xy 385.765696 -131.89629)
			(xy 385.813246 -131.859803) (xy 385.865152 -131.829836) (xy 385.920525 -131.8069) (xy 385.978418 -131.791387)
			(xy 386.03784 -131.783564) (xy 386.097776 -131.783564) (xy 386.157198 -131.791387) (xy 386.215091 -131.8069)
			(xy 386.270464 -131.829836) (xy 386.32237 -131.859803) (xy 386.36992 -131.89629) (xy 386.4123 -131.93867)
			(xy 386.448787 -131.98622) (xy 386.478754 -132.038126) (xy 386.50169 -132.093499) (xy 386.517203 -132.151392)
			(xy 386.525026 -132.210814) (xy 386.525516 -132.240782) (xy 386.525516 -133.096508) (xy 400.085052 -133.096508)
			(xy 400.085052 -132.232908) (xy 400.085542 -132.20294) (xy 400.093365 -132.143518) (xy 400.108878 -132.085625)
			(xy 400.131814 -132.030252) (xy 400.161781 -131.978346) (xy 400.198268 -131.930796) (xy 400.240648 -131.888416)
			(xy 400.288198 -131.851929) (xy 400.340104 -131.821962) (xy 400.395477 -131.799026) (xy 400.45337 -131.783513)
			(xy 400.512792 -131.77569) (xy 400.572728 -131.77569) (xy 400.63215 -131.783513) (xy 400.690043 -131.799026)
			(xy 400.745416 -131.821962) (xy 400.797322 -131.851929) (xy 400.844872 -131.888416) (xy 400.887252 -131.930796)
			(xy 400.923739 -131.978346) (xy 400.953706 -132.030252) (xy 400.976642 -132.085625) (xy 400.992155 -132.143518)
			(xy 400.999978 -132.20294) (xy 401.000468 -132.232908) (xy 401.000468 -133.096508) (xy 400.999978 -133.126476)
			(xy 400.992155 -133.185898) (xy 400.976642 -133.243791) (xy 400.953706 -133.299164) (xy 400.923739 -133.35107)
			(xy 400.887252 -133.39862) (xy 400.844872 -133.441) (xy 400.797322 -133.477487) (xy 400.745416 -133.507454)
			(xy 400.690043 -133.53039) (xy 400.63215 -133.545903) (xy 400.572728 -133.553726) (xy 400.512792 -133.553726)
			(xy 400.45337 -133.545903) (xy 400.395477 -133.53039) (xy 400.340104 -133.507454) (xy 400.288198 -133.477487)
			(xy 400.240648 -133.441) (xy 400.198268 -133.39862) (xy 400.161781 -133.35107) (xy 400.131814 -133.299164)
			(xy 400.108878 -133.243791) (xy 400.093365 -133.185898) (xy 400.085542 -133.126476) (xy 400.085052 -133.096508)
			(xy 386.525516 -133.096508) (xy 386.525516 -133.104382) (xy 386.525026 -133.13435) (xy 386.517203 -133.193772)
			(xy 386.50169 -133.251665) (xy 386.478754 -133.307038) (xy 386.448787 -133.358944) (xy 386.4123 -133.406494)
			(xy 386.36992 -133.448874) (xy 386.32237 -133.485361) (xy 386.270464 -133.515328) (xy 386.215091 -133.538264)
			(xy 386.157198 -133.553777) (xy 386.097776 -133.5616) (xy 386.03784 -133.5616) (xy 385.978418 -133.553777)
			(xy 385.920525 -133.538264) (xy 385.865152 -133.515328) (xy 385.813246 -133.485361) (xy 385.765696 -133.448874)
			(xy 385.723316 -133.406494) (xy 385.686829 -133.358944) (xy 385.656862 -133.307038) (xy 385.633926 -133.251665)
			(xy 385.618413 -133.193772) (xy 385.61059 -133.13435) (xy 385.6101 -133.104382) (xy 360.714798 -133.104382)
			(xy 360.714798 -133.260592) (xy 360.714376 -133.270663) (xy 360.706664 -133.289269) (xy 360.699812 -133.29666)
			(xy 360.141774 -133.854698) (xy 360.13898 -133.858) (xy 360.133285 -133.865483) (xy 360.12724 -133.883273)
			(xy 360.128007 -133.902046) (xy 360.13136 -133.910832) (xy 360.169714 -133.9977) (xy 360.174093 -134.006491)
			(xy 360.18819 -134.020137) (xy 360.206385 -134.027481) (xy 360.216196 -134.027926) (xy 360.218482 -134.027926)
			(xy 360.236008 -134.027418) (xy 360.236516 -134.027418) (xy 360.263756 -134.027919) (xy 360.317679 -134.035701)
			(xy 360.369947 -134.051075) (xy 360.419495 -134.073728) (xy 360.465316 -134.103201) (xy 360.506479 -134.138893)
			(xy 360.542144 -134.180078) (xy 360.571588 -134.225918) (xy 360.59421 -134.27548) (xy 360.609551 -134.327757)
			(xy 360.617298 -134.381685) (xy 360.61777 -134.408926) (xy 360.617301 -134.436346) (xy 360.609467 -134.490624)
			(xy 360.593949 -134.543222) (xy 360.571067 -134.59306) (xy 360.54129 -134.639113) (xy 360.505232 -134.680432)
			(xy 360.463634 -134.716168) (xy 360.440732 -134.731252) (xy 360.432604 -134.736586) (xy 360.409236 -134.76859)
			(xy 360.40695 -134.779258) (xy 360.402378 -134.800086) (xy 360.401362 -134.810754) (xy 360.401362 -134.864856)
			(xy 360.402886 -134.877048) (xy 360.405172 -134.886192) (xy 360.407204 -134.889748) (xy 360.412623 -134.897876)
			(xy 382.967992 -134.897876) (xy 382.967992 -134.034276) (xy 382.968482 -134.004308) (xy 382.976305 -133.944886)
			(xy 382.991818 -133.886993) (xy 383.014754 -133.83162) (xy 383.044721 -133.779714) (xy 383.081208 -133.732164)
			(xy 383.123588 -133.689784) (xy 383.171138 -133.653297) (xy 383.223044 -133.62333) (xy 383.278417 -133.600394)
			(xy 383.33631 -133.584881) (xy 383.395732 -133.577058) (xy 383.455668 -133.577058) (xy 383.51509 -133.584881)
			(xy 383.572983 -133.600394) (xy 383.628356 -133.62333) (xy 383.680262 -133.653297) (xy 383.727812 -133.689784)
			(xy 383.770192 -133.732164) (xy 383.806679 -133.779714) (xy 383.836646 -133.83162) (xy 383.859582 -133.886993)
			(xy 383.875095 -133.944886) (xy 383.882918 -134.004308) (xy 383.883408 -134.034276) (xy 383.883408 -134.896352)
			(xy 401.939252 -134.896352) (xy 401.939252 -134.032752) (xy 401.939742 -134.002784) (xy 401.947565 -133.943362)
			(xy 401.963078 -133.885469) (xy 401.986014 -133.830096) (xy 402.015981 -133.77819) (xy 402.052468 -133.73064)
			(xy 402.094848 -133.68826) (xy 402.142398 -133.651773) (xy 402.194304 -133.621806) (xy 402.249677 -133.59887)
			(xy 402.30757 -133.583357) (xy 402.366992 -133.575534) (xy 402.426928 -133.575534) (xy 402.48635 -133.583357)
			(xy 402.544243 -133.59887) (xy 402.599616 -133.621806) (xy 402.651522 -133.651773) (xy 402.699072 -133.68826)
			(xy 402.741452 -133.73064) (xy 402.777939 -133.77819) (xy 402.807906 -133.830096) (xy 402.830842 -133.885469)
			(xy 402.846355 -133.943362) (xy 402.854178 -134.002784) (xy 402.854668 -134.032752) (xy 402.854668 -134.62)
			(xy 405.195022 -134.62) (xy 405.199093 -134.564378) (xy 405.211219 -134.509941) (xy 405.231142 -134.45785)
			(xy 405.258438 -134.409215) (xy 405.292524 -134.365072) (xy 405.332673 -134.326363) (xy 405.378031 -134.293912)
			(xy 405.427631 -134.268411) (xy 405.480415 -134.250404) (xy 405.535258 -134.240274) (xy 405.590992 -134.238237)
			(xy 405.646429 -134.244337) (xy 405.700386 -134.258443) (xy 405.751715 -134.280255) (xy 405.799321 -134.309309)
			(xy 405.842189 -134.344984) (xy 405.879406 -134.386521) (xy 405.910179 -134.433034) (xy 405.933851 -134.483531)
			(xy 405.949919 -134.536938) (xy 405.958039 -134.592114) (xy 405.958548 -134.62) (xy 405.958039 -134.647886)
			(xy 405.949919 -134.703062) (xy 405.933851 -134.756469) (xy 405.910179 -134.806966) (xy 405.879406 -134.853479)
			(xy 405.842189 -134.895016) (xy 405.799321 -134.930691) (xy 405.751715 -134.959745) (xy 405.700386 -134.981557)
			(xy 405.646429 -134.995663) (xy 405.590992 -135.001763) (xy 405.535258 -134.999726) (xy 405.480415 -134.989596)
			(xy 405.427631 -134.971589) (xy 405.378031 -134.946088) (xy 405.332673 -134.913637) (xy 405.292524 -134.874928)
			(xy 405.258438 -134.830785) (xy 405.231142 -134.78215) (xy 405.211219 -134.730059) (xy 405.199093 -134.675622)
			(xy 405.195022 -134.62) (xy 402.854668 -134.62) (xy 402.854668 -134.896352) (xy 402.854178 -134.92632)
			(xy 402.846355 -134.985742) (xy 402.830842 -135.043635) (xy 402.807906 -135.099008) (xy 402.777939 -135.150914)
			(xy 402.741452 -135.198464) (xy 402.699072 -135.240844) (xy 402.651522 -135.277331) (xy 402.599616 -135.307298)
			(xy 402.544243 -135.330234) (xy 402.48635 -135.345747) (xy 402.426928 -135.35357) (xy 402.366992 -135.35357)
			(xy 402.30757 -135.345747) (xy 402.249677 -135.330234) (xy 402.194304 -135.307298) (xy 402.142398 -135.277331)
			(xy 402.094848 -135.240844) (xy 402.052468 -135.198464) (xy 402.015981 -135.150914) (xy 401.986014 -135.099008)
			(xy 401.963078 -135.043635) (xy 401.947565 -134.985742) (xy 401.939742 -134.92632) (xy 401.939252 -134.896352)
			(xy 383.883408 -134.896352) (xy 383.883408 -134.897876) (xy 383.882918 -134.927844) (xy 383.875095 -134.987266)
			(xy 383.859582 -135.045159) (xy 383.836646 -135.100532) (xy 383.806679 -135.152438) (xy 383.770192 -135.199988)
			(xy 383.727812 -135.242368) (xy 383.680262 -135.278855) (xy 383.628356 -135.308822) (xy 383.572983 -135.331758)
			(xy 383.51509 -135.347271) (xy 383.455668 -135.355094) (xy 383.395732 -135.355094) (xy 383.33631 -135.347271)
			(xy 383.278417 -135.331758) (xy 383.223044 -135.308822) (xy 383.171138 -135.278855) (xy 383.123588 -135.242368)
			(xy 383.081208 -135.199988) (xy 383.044721 -135.152438) (xy 383.014754 -135.100532) (xy 382.991818 -135.045159)
			(xy 382.976305 -134.987266) (xy 382.968482 -134.927844) (xy 382.967992 -134.897876) (xy 360.412623 -134.897876)
			(xy 360.413808 -134.899654) (xy 360.426708 -134.921665) (xy 360.447149 -134.968409) (xy 360.461164 -135.017465)
			(xy 360.468501 -135.067953) (xy 360.46918 -135.093456) (xy 360.46918 -135.101076) (xy 360.468485 -135.128183)
			(xy 360.460375 -135.181796) (xy 360.444755 -135.233721) (xy 360.42194 -135.282911) (xy 360.392389 -135.328375)
			(xy 360.356699 -135.369197) (xy 360.315589 -135.404554) (xy 360.269886 -135.433733) (xy 360.220512 -135.456147)
			(xy 360.168461 -135.471344) (xy 360.114784 -135.479018) (xy 360.087672 -135.479536) (xy 360.087164 -135.479536)
			(xy 360.061539 -135.479103) (xy 360.010757 -135.472198) (xy 359.961359 -135.458546) (xy 359.914238 -135.438391)
			(xy 359.870246 -135.4121) (xy 359.849928 -135.396478) (xy 359.84307 -135.391144) (xy 359.83545 -135.388604)
			(xy 359.831392 -135.387234) (xy 359.822966 -135.385706) (xy 359.818686 -135.385556) (xy 359.796842 -135.385556)
			(xy 359.791403 -135.38541) (xy 359.780775 -135.383095) (xy 359.77576 -135.380984) (xy 359.762298 -135.374634)
			(xy 359.753833 -135.371038) (xy 359.735518 -135.369512) (xy 359.717847 -135.374561) (xy 359.710228 -135.379714)
			(xy 359.706672 -135.382762) (xy 359.685582 -135.400887) (xy 359.639143 -135.431474) (xy 359.588758 -135.455001)
			(xy 359.535493 -135.470972) (xy 359.480476 -135.479048) (xy 359.452672 -135.479536) (xy 359.452418 -135.479536)
			(xy 359.42775 -135.479151) (xy 359.378825 -135.472785) (xy 359.354882 -135.466836) (xy 359.329668 -135.459673)
			(xy 359.281337 -135.439387) (xy 359.236231 -135.412689) (xy 359.215436 -135.396732) (xy 359.215182 -135.396478)
			(xy 359.213404 -135.394954) (xy 359.206877 -135.390653) (xy 359.192005 -135.385863) (xy 359.184194 -135.385556)
			(xy 359.161842 -135.385556) (xy 359.156403 -135.38541) (xy 359.145775 -135.383095) (xy 359.14076 -135.380984)
			(xy 359.127298 -135.374634) (xy 359.118833 -135.371038) (xy 359.100518 -135.369512) (xy 359.082847 -135.374561)
			(xy 359.075228 -135.379714) (xy 359.071672 -135.382762) (xy 359.050582 -135.400887) (xy 359.004143 -135.431474)
			(xy 358.953758 -135.455001) (xy 358.900493 -135.470972) (xy 358.845476 -135.479048) (xy 358.817672 -135.479536)
			(xy 358.817418 -135.479536) (xy 358.792552 -135.479155) (xy 358.743239 -135.47273) (xy 358.695179 -135.459947)
			(xy 358.649189 -135.441023) (xy 358.627426 -135.42899) (xy 358.623362 -135.426704) (xy 358.597962 -135.419592)
			(xy 358.590319 -135.419856) (xy 358.575719 -135.424386) (xy 358.56926 -135.428482) (xy 358.561894 -135.434578)
			(xy 357.444294 -136.552178) (xy 357.436896 -136.559026) (xy 357.418298 -136.566761) (xy 357.408226 -136.567164)
			(xy 355.189282 -136.567164) (xy 355.184048 -136.56732) (xy 355.173806 -136.569494) (xy 355.168962 -136.571482)
			(xy 355.142038 -136.58342) (xy 355.134926 -136.59104) (xy 355.131878 -136.594088) (xy 355.112182 -136.613685)
			(xy 355.068132 -136.647543) (xy 355.019635 -136.674651) (xy 354.967717 -136.694434) (xy 354.913478 -136.706474)
			(xy 354.858066 -136.710516) (xy 354.802654 -136.706474) (xy 354.748415 -136.694434) (xy 354.696497 -136.674651)
			(xy 354.648 -136.647543) (xy 354.60395 -136.613685) (xy 354.584254 -136.594088) (xy 354.581206 -136.59104)
			(xy 354.574094 -136.58342) (xy 354.54717 -136.571482) (xy 354.54233 -136.569478) (xy 354.532086 -136.567299)
			(xy 354.52685 -136.567164) (xy 335.979262 -136.567164) (xy 335.969196 -136.566733) (xy 335.950604 -136.559005)
			(xy 335.943194 -136.552178) (xy 333.83474 -134.443724) (xy 333.827901 -134.436323) (xy 333.820188 -134.417725)
			(xy 333.819754 -134.407656) (xy 333.819754 -115.04676) (xy 333.819327 -115.036747) (xy 333.811648 -115.018252)
			(xy 333.797476 -115.004104) (xy 333.778967 -114.996456) (xy 333.768954 -114.99596) (xy 322.342002 -114.99596)
			(xy 322.338954 -114.99596) (xy 322.332776 -114.996497) (xy 322.320949 -115.000213) (xy 322.315586 -115.003326)
			(xy 322.310292 -115.006771) (xy 322.301426 -115.015761) (xy 322.29806 -115.021106) (xy 322.297044 -115.022884)
			(xy 322.297044 -115.023138) (xy 322.269612 -115.075208) (xy 322.269612 -115.075716) (xy 322.254626 -115.103656)
			(xy 322.25228 -115.108878) (xy 322.249712 -115.120032) (xy 322.249546 -115.125754) (xy 322.249546 -115.137946)
			(xy 322.257928 -115.154456) (xy 322.259706 -115.15725) (xy 322.275066 -115.180996) (xy 322.299369 -115.232059)
			(xy 322.315874 -115.286148) (xy 322.324222 -115.34208) (xy 322.32473 -115.370356) (xy 322.324244 -115.397607)
			(xy 322.316488 -115.451555) (xy 322.301133 -115.50385) (xy 322.278491 -115.553427) (xy 322.249025 -115.599277)
			(xy 322.213334 -115.640468) (xy 322.172143 -115.676159) (xy 322.126293 -115.705625) (xy 322.076716 -115.728267)
			(xy 322.024421 -115.743622) (xy 321.970473 -115.751378) (xy 321.915971 -115.751378) (xy 321.862023 -115.743622)
			(xy 321.809728 -115.728267) (xy 321.760151 -115.705625) (xy 321.714301 -115.676159) (xy 321.67311 -115.640468)
			(xy 321.637419 -115.599277) (xy 321.607953 -115.553427) (xy 321.585311 -115.50385) (xy 321.569956 -115.451555)
			(xy 321.5622 -115.397607) (xy 321.561714 -115.370356) (xy 321.561714 -115.369848) (xy 321.562228 -115.341718)
			(xy 321.570516 -115.286071) (xy 321.586888 -115.232245) (xy 321.610991 -115.181408) (xy 321.62623 -115.157758)
			(xy 321.628262 -115.154456) (xy 321.633342 -115.138708) (xy 321.633342 -115.1382) (xy 321.637152 -115.126008)
			(xy 321.637012 -115.120568) (xy 321.634711 -115.109933) (xy 321.63258 -115.104926) (xy 321.63131 -115.102386)
			(xy 321.593718 -115.031012) (xy 321.591178 -115.026694) (xy 321.590162 -115.024662) (xy 321.589908 -115.024408)
			(xy 321.589654 -115.024154) (xy 321.586293 -115.017878) (xy 321.576755 -115.007315) (xy 321.570858 -115.003326)
			(xy 321.565524 -114.99977) (xy 321.551808 -114.99596) (xy 320.218816 -114.99596) (xy 320.21252 -114.996146)
			(xy 320.200311 -114.999224) (xy 320.194686 -115.002056) (xy 320.188272 -115.005838) (xy 320.177806 -115.016419)
			(xy 320.174112 -115.022884) (xy 320.13525 -115.103656) (xy 320.13525 -115.104164) (xy 320.130932 -115.113308)
			(xy 320.130424 -115.123976) (xy 320.130321 -115.129024) (xy 320.131865 -115.139001) (xy 320.133472 -115.143788)
			(xy 320.139822 -115.16106) (xy 320.14287 -115.165124) (xy 320.144902 -115.167918) (xy 320.16388 -115.193637)
			(xy 320.193883 -115.25007) (xy 320.204592 -115.280186) (xy 320.207386 -115.288822) (xy 320.210688 -115.29949)
			(xy 320.675508 -115.76431) (xy 320.693537 -115.783082) (xy 320.724111 -115.825201) (xy 320.727898 -115.832636)
			(xy 325.17918 -115.832636) (xy 325.183251 -115.777014) (xy 325.195377 -115.722577) (xy 325.2153 -115.670486)
			(xy 325.242596 -115.621851) (xy 325.276682 -115.577708) (xy 325.316831 -115.538999) (xy 325.362189 -115.506548)
			(xy 325.411789 -115.481047) (xy 325.464573 -115.46304) (xy 325.519416 -115.45291) (xy 325.57515 -115.450873)
			(xy 325.630587 -115.456973) (xy 325.684544 -115.471079) (xy 325.735873 -115.492891) (xy 325.783479 -115.521945)
			(xy 325.826347 -115.55762) (xy 325.863564 -115.599157) (xy 325.894337 -115.64567) (xy 325.918009 -115.696167)
			(xy 325.934077 -115.749574) (xy 325.942197 -115.80475) (xy 325.942706 -115.832636) (xy 325.942197 -115.860522)
			(xy 325.934077 -115.915698) (xy 325.918009 -115.969105) (xy 325.894337 -116.019602) (xy 325.863564 -116.066115)
			(xy 325.826347 -116.107652) (xy 325.783479 -116.143327) (xy 325.735873 -116.172381) (xy 325.684544 -116.194193)
			(xy 325.630587 -116.208299) (xy 325.57515 -116.214399) (xy 325.519416 -116.212362) (xy 325.464573 -116.202232)
			(xy 325.411789 -116.184225) (xy 325.362189 -116.158724) (xy 325.316831 -116.126273) (xy 325.276682 -116.087564)
			(xy 325.242596 -116.043421) (xy 325.2153 -115.994786) (xy 325.195377 -115.942695) (xy 325.183251 -115.888258)
			(xy 325.17918 -115.832636) (xy 320.727898 -115.832636) (xy 320.747731 -115.871577) (xy 320.763819 -115.921074)
			(xy 320.771979 -115.972476) (xy 320.772536 -115.998498) (xy 320.772536 -116.66982) (xy 321.573142 -116.66982)
			(xy 321.577213 -116.614198) (xy 321.589339 -116.559761) (xy 321.609262 -116.50767) (xy 321.636558 -116.459035)
			(xy 321.670644 -116.414892) (xy 321.710793 -116.376183) (xy 321.756151 -116.343732) (xy 321.805751 -116.318231)
			(xy 321.858535 -116.300224) (xy 321.913378 -116.290094) (xy 321.969112 -116.288057) (xy 322.024549 -116.294157)
			(xy 322.078506 -116.308263) (xy 322.129835 -116.330075) (xy 322.177441 -116.359129) (xy 322.220309 -116.394804)
			(xy 322.257526 -116.436341) (xy 322.288299 -116.482854) (xy 322.311971 -116.533351) (xy 322.328039 -116.586758)
			(xy 322.336159 -116.641934) (xy 322.336668 -116.66982) (xy 322.336159 -116.697706) (xy 322.328039 -116.752882)
			(xy 322.311971 -116.806289) (xy 322.288299 -116.856786) (xy 322.257526 -116.903299) (xy 322.220309 -116.944836)
			(xy 322.177441 -116.980511) (xy 322.129835 -117.009565) (xy 322.078506 -117.031377) (xy 322.024549 -117.045483)
			(xy 321.969112 -117.051583) (xy 321.913378 -117.049546) (xy 321.858535 -117.039416) (xy 321.805751 -117.021409)
			(xy 321.756151 -116.995908) (xy 321.710793 -116.963457) (xy 321.670644 -116.924748) (xy 321.636558 -116.880605)
			(xy 321.609262 -116.83197) (xy 321.589339 -116.779879) (xy 321.577213 -116.725442) (xy 321.573142 -116.66982)
			(xy 320.772536 -116.66982) (xy 320.772536 -117.390446) (xy 322.942518 -117.390446) (xy 322.942518 -117.335954)
			(xy 322.950273 -117.282015) (xy 322.965624 -117.229729) (xy 322.98826 -117.18016) (xy 323.017719 -117.134317)
			(xy 323.053402 -117.093132) (xy 323.094583 -117.057444) (xy 323.140423 -117.02798) (xy 323.18999 -117.005339)
			(xy 323.242274 -116.989982) (xy 323.296212 -116.982221) (xy 323.323458 -116.981732) (xy 323.352374 -116.982268)
			(xy 323.409545 -116.990992) (xy 323.464744 -117.008245) (xy 323.516706 -117.033634) (xy 323.564241 -117.066575)
			(xy 323.606258 -117.106313) (xy 323.624448 -117.128798) (xy 323.632044 -117.137617) (xy 323.652953 -117.147794)
			(xy 323.66458 -117.148356) (xy 323.744336 -117.148356) (xy 323.755971 -117.147839) (xy 323.776881 -117.137636)
			(xy 323.784468 -117.128798) (xy 323.802677 -117.106329) (xy 323.844693 -117.066593) (xy 323.892224 -117.033653)
			(xy 323.944182 -117.008262) (xy 323.999376 -116.991002) (xy 324.056543 -116.982269) (xy 324.085458 -116.981732)
			(xy 324.112716 -116.982112) (xy 324.166677 -116.989865) (xy 324.218985 -117.005219) (xy 324.268576 -117.027862)
			(xy 324.314439 -117.057332) (xy 324.355641 -117.093029) (xy 324.363966 -117.102636) (xy 325.17918 -117.102636)
			(xy 325.183251 -117.047014) (xy 325.195377 -116.992577) (xy 325.2153 -116.940486) (xy 325.242596 -116.891851)
			(xy 325.276682 -116.847708) (xy 325.316831 -116.808999) (xy 325.362189 -116.776548) (xy 325.411789 -116.751047)
			(xy 325.464573 -116.73304) (xy 325.519416 -116.72291) (xy 325.57515 -116.720873) (xy 325.630587 -116.726973)
			(xy 325.684544 -116.741079) (xy 325.735873 -116.762891) (xy 325.783479 -116.791945) (xy 325.826347 -116.82762)
			(xy 325.863564 -116.869157) (xy 325.894337 -116.91567) (xy 325.918009 -116.966167) (xy 325.934077 -117.019574)
			(xy 325.942197 -117.07475) (xy 325.942706 -117.102636) (xy 325.942197 -117.130522) (xy 325.934077 -117.185698)
			(xy 325.918009 -117.239105) (xy 325.894337 -117.289602) (xy 325.863564 -117.336115) (xy 325.826347 -117.377652)
			(xy 325.783479 -117.413327) (xy 325.735873 -117.442381) (xy 325.684544 -117.464193) (xy 325.630587 -117.478299)
			(xy 325.57515 -117.484399) (xy 325.519416 -117.482362) (xy 325.464573 -117.472232) (xy 325.411789 -117.454225)
			(xy 325.362189 -117.428724) (xy 325.316831 -117.396273) (xy 325.276682 -117.357564) (xy 325.242596 -117.313421)
			(xy 325.2153 -117.264786) (xy 325.195377 -117.212695) (xy 325.183251 -117.158258) (xy 325.17918 -117.102636)
			(xy 324.363966 -117.102636) (xy 324.391343 -117.134227) (xy 324.420818 -117.180087) (xy 324.443466 -117.229675)
			(xy 324.458826 -117.281982) (xy 324.466585 -117.335942) (xy 324.466585 -117.390458) (xy 324.458826 -117.444418)
			(xy 324.443466 -117.496725) (xy 324.420818 -117.546313) (xy 324.391343 -117.592173) (xy 324.355641 -117.633371)
			(xy 324.314439 -117.669068) (xy 324.268576 -117.698538) (xy 324.218985 -117.721181) (xy 324.166677 -117.736535)
			(xy 324.112716 -117.744288) (xy 324.085458 -117.744748) (xy 324.056542 -117.744208) (xy 323.999371 -117.735486)
			(xy 323.944171 -117.718234) (xy 323.892209 -117.692847) (xy 323.844675 -117.659906) (xy 323.802658 -117.620167)
			(xy 323.784468 -117.597682) (xy 323.776868 -117.588867) (xy 323.755962 -117.578688) (xy 323.744336 -117.578124)
			(xy 323.66458 -117.578124) (xy 323.652947 -117.578657) (xy 323.632037 -117.588849) (xy 323.624448 -117.597682)
			(xy 323.606225 -117.620139) (xy 323.564213 -117.659876) (xy 323.516685 -117.692819) (xy 323.464729 -117.718212)
			(xy 323.409537 -117.735474) (xy 323.352372 -117.74421) (xy 323.323458 -117.744748) (xy 323.296212 -117.744179)
			(xy 323.242274 -117.736418) (xy 323.18999 -117.721061) (xy 323.140423 -117.69842) (xy 323.094583 -117.668956)
			(xy 323.053402 -117.633268) (xy 323.017719 -117.592083) (xy 322.98826 -117.54624) (xy 322.965624 -117.496671)
			(xy 322.950273 -117.444385) (xy 322.942518 -117.390446) (xy 320.772536 -117.390446) (xy 320.772536 -118.467886)
			(xy 329.682346 -118.467886) (xy 329.686417 -118.412264) (xy 329.698543 -118.357827) (xy 329.718466 -118.305736)
			(xy 329.745762 -118.257101) (xy 329.779848 -118.212958) (xy 329.819997 -118.174249) (xy 329.865355 -118.141798)
			(xy 329.914955 -118.116297) (xy 329.967739 -118.09829) (xy 330.022582 -118.08816) (xy 330.078316 -118.086123)
			(xy 330.133753 -118.092223) (xy 330.18771 -118.106329) (xy 330.239039 -118.128141) (xy 330.286645 -118.157195)
			(xy 330.329513 -118.19287) (xy 330.36673 -118.234407) (xy 330.397503 -118.28092) (xy 330.421175 -118.331417)
			(xy 330.437243 -118.384824) (xy 330.445363 -118.44) (xy 330.445872 -118.467886) (xy 330.445363 -118.495772)
			(xy 330.437243 -118.550948) (xy 330.421175 -118.604355) (xy 330.397503 -118.654852) (xy 330.36673 -118.701365)
			(xy 330.329513 -118.742902) (xy 330.286645 -118.778577) (xy 330.239039 -118.807631) (xy 330.18771 -118.829443)
			(xy 330.133753 -118.843549) (xy 330.078316 -118.849649) (xy 330.022582 -118.847612) (xy 329.967739 -118.837482)
			(xy 329.914955 -118.819475) (xy 329.865355 -118.793974) (xy 329.819997 -118.761523) (xy 329.779848 -118.722814)
			(xy 329.745762 -118.678671) (xy 329.718466 -118.630036) (xy 329.698543 -118.577945) (xy 329.686417 -118.523508)
			(xy 329.682346 -118.467886) (xy 320.772536 -118.467886) (xy 320.772536 -119.407557) (xy 326.699509 -119.407557)
			(xy 326.699509 -119.353043) (xy 326.707268 -119.299083) (xy 326.722627 -119.246777) (xy 326.745274 -119.197189)
			(xy 326.774748 -119.151329) (xy 326.810449 -119.11013) (xy 326.85165 -119.074432) (xy 326.897512 -119.044962)
			(xy 326.947101 -119.022318) (xy 326.999408 -119.006962) (xy 327.053369 -118.999207) (xy 327.080626 -118.998746)
			(xy 327.107997 -118.999186) (xy 327.162178 -119.007008) (xy 327.214682 -119.022503) (xy 327.264428 -119.045351)
			(xy 327.310394 -119.075082) (xy 327.331324 -119.092726) (xy 327.331578 -119.09298) (xy 327.33866 -119.098573)
			(xy 327.355581 -119.104814) (xy 327.364598 -119.105172) (xy 327.431654 -119.105172) (xy 327.440669 -119.104799)
			(xy 327.457587 -119.098563) (xy 327.464674 -119.09298) (xy 327.464674 -119.092726) (xy 327.464928 -119.092726)
			(xy 327.48588 -119.075111) (xy 327.531847 -119.045395) (xy 327.581589 -119.022554) (xy 327.634086 -119.007057)
			(xy 327.688258 -118.999223) (xy 327.715626 -118.998746) (xy 327.742873 -118.999326) (xy 327.796811 -119.007085)
			(xy 327.849096 -119.02244) (xy 327.898664 -119.04508) (xy 327.944506 -119.074543) (xy 327.985688 -119.11023)
			(xy 328.021372 -119.151415) (xy 328.050833 -119.197259) (xy 328.073469 -119.246828) (xy 328.088821 -119.299114)
			(xy 328.096576 -119.353053) (xy 328.096576 -119.407547) (xy 328.088821 -119.461486) (xy 328.084258 -119.477028)
			(xy 331.808072 -119.477028) (xy 331.812143 -119.421406) (xy 331.824269 -119.366969) (xy 331.844192 -119.314878)
			(xy 331.871488 -119.266243) (xy 331.905574 -119.2221) (xy 331.945723 -119.183391) (xy 331.991081 -119.15094)
			(xy 332.040681 -119.125439) (xy 332.093465 -119.107432) (xy 332.148308 -119.097302) (xy 332.204042 -119.095265)
			(xy 332.259479 -119.101365) (xy 332.313436 -119.115471) (xy 332.364765 -119.137283) (xy 332.412371 -119.166337)
			(xy 332.455239 -119.202012) (xy 332.492456 -119.243549) (xy 332.523229 -119.290062) (xy 332.546901 -119.340559)
			(xy 332.562969 -119.393966) (xy 332.571089 -119.449142) (xy 332.571598 -119.477028) (xy 332.571089 -119.504914)
			(xy 332.562969 -119.56009) (xy 332.546901 -119.613497) (xy 332.523229 -119.663994) (xy 332.492456 -119.710507)
			(xy 332.455239 -119.752044) (xy 332.426164 -119.77624) (xy 332.735934 -119.77624) (xy 332.740005 -119.720618)
			(xy 332.752131 -119.666181) (xy 332.772054 -119.61409) (xy 332.79935 -119.565455) (xy 332.833436 -119.521312)
			(xy 332.873585 -119.482603) (xy 332.918943 -119.450152) (xy 332.968543 -119.424651) (xy 333.021327 -119.406644)
			(xy 333.07617 -119.396514) (xy 333.131904 -119.394477) (xy 333.187341 -119.400577) (xy 333.241298 -119.414683)
			(xy 333.292627 -119.436495) (xy 333.340233 -119.465549) (xy 333.383101 -119.501224) (xy 333.420318 -119.542761)
			(xy 333.451091 -119.589274) (xy 333.474763 -119.639771) (xy 333.490831 -119.693178) (xy 333.498951 -119.748354)
			(xy 333.49946 -119.77624) (xy 333.498951 -119.804126) (xy 333.490831 -119.859302) (xy 333.474763 -119.912709)
			(xy 333.451091 -119.963206) (xy 333.420318 -120.009719) (xy 333.383101 -120.051256) (xy 333.340233 -120.086931)
			(xy 333.292627 -120.115985) (xy 333.241298 -120.137797) (xy 333.187341 -120.151903) (xy 333.131904 -120.158003)
			(xy 333.07617 -120.155966) (xy 333.021327 -120.145836) (xy 332.968543 -120.127829) (xy 332.918943 -120.102328)
			(xy 332.873585 -120.069877) (xy 332.833436 -120.031168) (xy 332.79935 -119.987025) (xy 332.772054 -119.93839)
			(xy 332.752131 -119.886299) (xy 332.740005 -119.831862) (xy 332.735934 -119.77624) (xy 332.426164 -119.77624)
			(xy 332.412371 -119.787719) (xy 332.364765 -119.816773) (xy 332.313436 -119.838585) (xy 332.259479 -119.852691)
			(xy 332.204042 -119.858791) (xy 332.148308 -119.856754) (xy 332.093465 -119.846624) (xy 332.040681 -119.828617)
			(xy 331.991081 -119.803116) (xy 331.945723 -119.770665) (xy 331.905574 -119.731956) (xy 331.871488 -119.687813)
			(xy 331.844192 -119.639178) (xy 331.824269 -119.587087) (xy 331.812143 -119.53265) (xy 331.808072 -119.477028)
			(xy 328.084258 -119.477028) (xy 328.073469 -119.513772) (xy 328.050833 -119.563341) (xy 328.021372 -119.609185)
			(xy 327.985688 -119.65037) (xy 327.944506 -119.686057) (xy 327.898664 -119.71552) (xy 327.849096 -119.73816)
			(xy 327.796811 -119.753515) (xy 327.742873 -119.761274) (xy 327.715626 -119.761762) (xy 327.688256 -119.76129)
			(xy 327.634077 -119.753475) (xy 327.581573 -119.737988) (xy 327.531826 -119.715147) (xy 327.48586 -119.685423)
			(xy 327.464928 -119.667782) (xy 327.464674 -119.667528) (xy 327.457577 -119.661958) (xy 327.440668 -119.655703)
			(xy 327.431654 -119.655336) (xy 327.364598 -119.655336) (xy 327.35558 -119.655684) (xy 327.338663 -119.661937)
			(xy 327.331578 -119.667528) (xy 327.331578 -119.667782) (xy 327.331324 -119.667782) (xy 327.310391 -119.685421)
			(xy 327.264419 -119.715133) (xy 327.214672 -119.737969) (xy 327.162171 -119.753461) (xy 327.107995 -119.761288)
			(xy 327.080626 -119.761762) (xy 327.053369 -119.761393) (xy 326.999408 -119.753638) (xy 326.947101 -119.738282)
			(xy 326.897512 -119.715638) (xy 326.85165 -119.686168) (xy 326.810449 -119.65047) (xy 326.774748 -119.609271)
			(xy 326.745274 -119.563411) (xy 326.722627 -119.513823) (xy 326.707268 -119.461517) (xy 326.699509 -119.407557)
			(xy 320.772536 -119.407557) (xy 320.772536 -119.89308) (xy 329.76896 -119.89308) (xy 329.773031 -119.837458)
			(xy 329.785157 -119.783021) (xy 329.80508 -119.73093) (xy 329.832376 -119.682295) (xy 329.866462 -119.638152)
			(xy 329.906611 -119.599443) (xy 329.951969 -119.566992) (xy 330.001569 -119.541491) (xy 330.054353 -119.523484)
			(xy 330.109196 -119.513354) (xy 330.16493 -119.511317) (xy 330.220367 -119.517417) (xy 330.274324 -119.531523)
			(xy 330.325653 -119.553335) (xy 330.373259 -119.582389) (xy 330.416127 -119.618064) (xy 330.453344 -119.659601)
			(xy 330.484117 -119.706114) (xy 330.507789 -119.756611) (xy 330.523857 -119.810018) (xy 330.531977 -119.865194)
			(xy 330.532486 -119.89308) (xy 330.531977 -119.920966) (xy 330.523857 -119.976142) (xy 330.507789 -120.029549)
			(xy 330.484117 -120.080046) (xy 330.453344 -120.126559) (xy 330.416127 -120.168096) (xy 330.373259 -120.203771)
			(xy 330.325653 -120.232825) (xy 330.274324 -120.254637) (xy 330.220367 -120.268743) (xy 330.16493 -120.274843)
			(xy 330.109196 -120.272806) (xy 330.054353 -120.262676) (xy 330.001569 -120.244669) (xy 329.951969 -120.219168)
			(xy 329.906611 -120.186717) (xy 329.866462 -120.148008) (xy 329.832376 -120.103865) (xy 329.80508 -120.05523)
			(xy 329.785157 -120.003139) (xy 329.773031 -119.948702) (xy 329.76896 -119.89308) (xy 320.772536 -119.89308)
			(xy 320.772536 -122.192034) (xy 321.650614 -122.192034) (xy 321.651097 -122.164664) (xy 321.65891 -122.110486)
			(xy 321.674395 -122.057983) (xy 321.697233 -122.008236) (xy 321.726954 -121.962268) (xy 321.744594 -121.941336)
			(xy 321.744848 -121.941082) (xy 321.750454 -121.934009) (xy 321.756688 -121.917082) (xy 321.75704 -121.908062)
			(xy 321.75704 -121.841006) (xy 321.756693 -121.831988) (xy 321.75044 -121.81507) (xy 321.744848 -121.807986)
			(xy 321.744594 -121.807986) (xy 321.744594 -121.807732) (xy 321.726988 -121.786772) (xy 321.697264 -121.740808)
			(xy 321.674419 -121.691066) (xy 321.658922 -121.638568) (xy 321.65109 -121.584394) (xy 321.651087 -121.529657)
			(xy 321.658911 -121.475482) (xy 321.674401 -121.422982) (xy 321.69724 -121.373237) (xy 321.726957 -121.327269)
			(xy 321.744594 -121.306336) (xy 321.744848 -121.306082) (xy 321.750454 -121.299009) (xy 321.756688 -121.282082)
			(xy 321.75704 -121.273062) (xy 321.75704 -121.206006) (xy 321.756693 -121.196988) (xy 321.75044 -121.18007)
			(xy 321.744848 -121.172986) (xy 321.744594 -121.172986) (xy 321.744594 -121.172732) (xy 321.726988 -121.151772)
			(xy 321.697264 -121.105808) (xy 321.674419 -121.056066) (xy 321.658922 -121.003568) (xy 321.65109 -120.949394)
			(xy 321.651087 -120.894657) (xy 321.658911 -120.840482) (xy 321.674401 -120.787982) (xy 321.69724 -120.738237)
			(xy 321.726957 -120.692269) (xy 321.744594 -120.671336) (xy 321.744848 -120.671082) (xy 321.750454 -120.664009)
			(xy 321.756688 -120.647082) (xy 321.75704 -120.638062) (xy 321.75704 -120.571006) (xy 321.756693 -120.561988)
			(xy 321.75044 -120.54507) (xy 321.744848 -120.537986) (xy 321.744594 -120.537986) (xy 321.744594 -120.537732)
			(xy 321.726956 -120.516799) (xy 321.697244 -120.470827) (xy 321.674408 -120.421079) (xy 321.658917 -120.368579)
			(xy 321.651088 -120.314403) (xy 321.650614 -120.287034) (xy 321.6511 -120.259783) (xy 321.658856 -120.205835)
			(xy 321.674211 -120.15354) (xy 321.696853 -120.103963) (xy 321.726319 -120.058113) (xy 321.76201 -120.016922)
			(xy 321.803201 -119.981231) (xy 321.849051 -119.951765) (xy 321.898628 -119.929123) (xy 321.950923 -119.913768)
			(xy 322.004871 -119.906012) (xy 322.059373 -119.906012) (xy 322.113321 -119.913768) (xy 322.165616 -119.929123)
			(xy 322.215193 -119.951765) (xy 322.261043 -119.981231) (xy 322.302234 -120.016922) (xy 322.337925 -120.058113)
			(xy 322.367391 -120.103963) (xy 322.390033 -120.15354) (xy 322.405388 -120.205835) (xy 322.413144 -120.259783)
			(xy 322.41363 -120.287034) (xy 322.413201 -120.314406) (xy 322.405377 -120.368587) (xy 322.38988 -120.421091)
			(xy 322.36703 -120.470838) (xy 322.352675 -120.493028) (xy 331.804008 -120.493028) (xy 331.808079 -120.437406)
			(xy 331.820205 -120.382969) (xy 331.840128 -120.330878) (xy 331.867424 -120.282243) (xy 331.90151 -120.2381)
			(xy 331.941659 -120.199391) (xy 331.987017 -120.16694) (xy 332.036617 -120.141439) (xy 332.089401 -120.123432)
			(xy 332.144244 -120.113302) (xy 332.199978 -120.111265) (xy 332.255415 -120.117365) (xy 332.309372 -120.131471)
			(xy 332.360701 -120.153283) (xy 332.408307 -120.182337) (xy 332.451175 -120.218012) (xy 332.488392 -120.259549)
			(xy 332.519165 -120.306062) (xy 332.542837 -120.356559) (xy 332.558905 -120.409966) (xy 332.567025 -120.465142)
			(xy 332.567534 -120.493028) (xy 332.567025 -120.520914) (xy 332.558905 -120.57609) (xy 332.542837 -120.629497)
			(xy 332.519165 -120.679994) (xy 332.488392 -120.726507) (xy 332.451175 -120.768044) (xy 332.4221 -120.79224)
			(xy 332.735934 -120.79224) (xy 332.740005 -120.736618) (xy 332.752131 -120.682181) (xy 332.772054 -120.63009)
			(xy 332.79935 -120.581455) (xy 332.833436 -120.537312) (xy 332.873585 -120.498603) (xy 332.918943 -120.466152)
			(xy 332.968543 -120.440651) (xy 333.021327 -120.422644) (xy 333.07617 -120.412514) (xy 333.131904 -120.410477)
			(xy 333.187341 -120.416577) (xy 333.241298 -120.430683) (xy 333.292627 -120.452495) (xy 333.340233 -120.481549)
			(xy 333.383101 -120.517224) (xy 333.420318 -120.558761) (xy 333.451091 -120.605274) (xy 333.474763 -120.655771)
			(xy 333.490831 -120.709178) (xy 333.498951 -120.764354) (xy 333.49946 -120.79224) (xy 333.498951 -120.820126)
			(xy 333.490831 -120.875302) (xy 333.474763 -120.928709) (xy 333.451091 -120.979206) (xy 333.420318 -121.025719)
			(xy 333.383101 -121.067256) (xy 333.340233 -121.102931) (xy 333.292627 -121.131985) (xy 333.241298 -121.153797)
			(xy 333.187341 -121.167903) (xy 333.131904 -121.174003) (xy 333.07617 -121.171966) (xy 333.021327 -121.161836)
			(xy 332.968543 -121.143829) (xy 332.918943 -121.118328) (xy 332.873585 -121.085877) (xy 332.833436 -121.047168)
			(xy 332.79935 -121.003025) (xy 332.772054 -120.95439) (xy 332.752131 -120.902299) (xy 332.740005 -120.847862)
			(xy 332.735934 -120.79224) (xy 332.4221 -120.79224) (xy 332.408307 -120.803719) (xy 332.360701 -120.832773)
			(xy 332.309372 -120.854585) (xy 332.255415 -120.868691) (xy 332.199978 -120.874791) (xy 332.144244 -120.872754)
			(xy 332.089401 -120.862624) (xy 332.036617 -120.844617) (xy 331.987017 -120.819116) (xy 331.941659 -120.786665)
			(xy 331.90151 -120.747956) (xy 331.867424 -120.703813) (xy 331.840128 -120.655178) (xy 331.820205 -120.603087)
			(xy 331.808079 -120.54865) (xy 331.804008 -120.493028) (xy 322.352675 -120.493028) (xy 322.337296 -120.516802)
			(xy 322.31965 -120.537732) (xy 322.319396 -120.537986) (xy 322.313809 -120.545072) (xy 322.307563 -120.561989)
			(xy 322.307204 -120.571006) (xy 322.307204 -120.638062) (xy 322.307579 -120.647077) (xy 322.313814 -120.663994)
			(xy 322.319396 -120.671082) (xy 322.31965 -120.671082) (xy 322.31965 -120.671336) (xy 322.337325 -120.692241)
			(xy 322.36705 -120.738213) (xy 322.389895 -120.787964) (xy 322.40539 -120.84047) (xy 322.413215 -120.894653)
			(xy 322.413212 -120.949398) (xy 322.405379 -121.00358) (xy 322.389877 -121.056084) (xy 322.367025 -121.105832)
			(xy 322.337294 -121.1518) (xy 322.31965 -121.172732) (xy 322.319396 -121.172986) (xy 322.313809 -121.180072)
			(xy 322.307563 -121.196989) (xy 322.307493 -121.198756) (xy 322.685317 -121.198756) (xy 322.685317 -121.144244)
			(xy 322.693075 -121.090287) (xy 322.708433 -121.037983) (xy 322.731079 -120.988397) (xy 322.76055 -120.942539)
			(xy 322.796249 -120.901342) (xy 322.837447 -120.865644) (xy 322.883306 -120.836174) (xy 322.932892 -120.81353)
			(xy 322.985196 -120.798173) (xy 323.039154 -120.790416) (xy 323.06641 -120.789954) (xy 323.093781 -120.790401)
			(xy 323.147962 -120.798221) (xy 323.200465 -120.813714) (xy 323.250212 -120.836561) (xy 323.296177 -120.86629)
			(xy 323.317108 -120.883934) (xy 323.317362 -120.884188) (xy 323.324456 -120.889763) (xy 323.341367 -120.896017)
			(xy 323.350382 -120.89638) (xy 323.417438 -120.89638) (xy 323.426457 -120.896045) (xy 323.443374 -120.889783)
			(xy 323.450458 -120.884188) (xy 323.450458 -120.883934) (xy 323.450712 -120.883934) (xy 323.471671 -120.866328)
			(xy 323.517636 -120.83661) (xy 323.567376 -120.813767) (xy 323.619871 -120.798268) (xy 323.674043 -120.790432)
			(xy 323.70141 -120.789954) (xy 323.728658 -120.790517) (xy 323.782599 -120.798274) (xy 323.834888 -120.813628)
			(xy 323.884458 -120.836268) (xy 323.930303 -120.865731) (xy 323.971488 -120.901419) (xy 324.007175 -120.942605)
			(xy 324.036637 -120.98845) (xy 324.059275 -121.038022) (xy 324.074628 -121.090311) (xy 324.082384 -121.144252)
			(xy 324.082384 -121.198748) (xy 324.074628 -121.252689) (xy 324.059275 -121.304978) (xy 324.036637 -121.35455)
			(xy 324.007175 -121.400395) (xy 323.971488 -121.441581) (xy 323.930303 -121.477269) (xy 323.884458 -121.506732)
			(xy 323.834888 -121.529372) (xy 323.782599 -121.544726) (xy 323.728658 -121.552483) (xy 323.70141 -121.55297)
			(xy 323.67404 -121.552505) (xy 323.61986 -121.544688) (xy 323.567357 -121.529199) (xy 323.51761 -121.506357)
			(xy 323.471643 -121.476632) (xy 323.450712 -121.45899) (xy 323.450458 -121.458736) (xy 323.443364 -121.45316)
			(xy 323.426453 -121.446909) (xy 323.417438 -121.446544) (xy 323.350382 -121.446544) (xy 323.341363 -121.446883)
			(xy 323.324446 -121.453142) (xy 323.317362 -121.458736) (xy 323.317362 -121.45899) (xy 323.317108 -121.45899)
			(xy 323.296182 -121.476637) (xy 323.250208 -121.506348) (xy 323.200459 -121.529183) (xy 323.147957 -121.544672)
			(xy 323.09378 -121.552497) (xy 323.06641 -121.55297) (xy 323.039154 -121.552584) (xy 322.985197 -121.544827)
			(xy 322.932892 -121.52947) (xy 322.883306 -121.506826) (xy 322.837447 -121.477356) (xy 322.796249 -121.441658)
			(xy 322.76055 -121.400461) (xy 322.731079 -121.354603) (xy 322.708433 -121.305017) (xy 322.693075 -121.252713)
			(xy 322.685317 -121.198756) (xy 322.307493 -121.198756) (xy 322.307204 -121.206006) (xy 322.307204 -121.273062)
			(xy 322.307579 -121.282077) (xy 322.313814 -121.298994) (xy 322.319396 -121.306082) (xy 322.31965 -121.306082)
			(xy 322.31965 -121.306336) (xy 322.337325 -121.327241) (xy 322.36705 -121.373213) (xy 322.389895 -121.422964)
			(xy 322.40539 -121.47547) (xy 322.413215 -121.529653) (xy 322.413212 -121.584398) (xy 322.405968 -121.634504)
			(xy 324.20433 -121.634504) (xy 324.204791 -121.607134) (xy 324.212609 -121.552954) (xy 324.228099 -121.50045)
			(xy 324.250942 -121.450704) (xy 324.280668 -121.404737) (xy 324.29831 -121.383806) (xy 324.298564 -121.383552)
			(xy 324.304143 -121.37646) (xy 324.310392 -121.359547) (xy 324.310756 -121.350532) (xy 324.310756 -121.283476)
			(xy 324.31042 -121.274457) (xy 324.304159 -121.257539) (xy 324.298564 -121.250456) (xy 324.29831 -121.250456)
			(xy 324.29831 -121.250202) (xy 324.28066 -121.229279) (xy 324.250949 -121.183304) (xy 324.228115 -121.133554)
			(xy 324.212627 -121.081051) (xy 324.204802 -121.026874) (xy 324.20433 -120.999504) (xy 324.204759 -120.97225)
			(xy 324.212517 -120.918295) (xy 324.227874 -120.865995) (xy 324.250519 -120.816412) (xy 324.27999 -120.770557)
			(xy 324.315687 -120.729363) (xy 324.356884 -120.69367) (xy 324.402742 -120.664203) (xy 324.452326 -120.641562)
			(xy 324.504629 -120.626209) (xy 324.558583 -120.618457) (xy 324.585838 -120.617996) (xy 324.61496 -120.618546)
			(xy 324.672531 -120.627378) (xy 324.72809 -120.64486) (xy 324.780344 -120.670586) (xy 324.82808 -120.703959)
			(xy 324.870186 -120.744201) (xy 324.905684 -120.790378) (xy 324.933748 -120.841415) (xy 324.953726 -120.896126)
			(xy 324.95998 -120.924574) (xy 324.962266 -120.936258) (xy 324.976744 -120.955054) (xy 325.060818 -120.99544)
			(xy 325.071632 -121.000003) (xy 325.095071 -120.999743) (xy 325.105776 -120.994932) (xy 325.106284 -120.994932)
			(xy 325.13334 -120.981644) (xy 325.190617 -120.962868) (xy 325.250136 -120.953351) (xy 325.280274 -120.952768)
			(xy 325.307525 -120.953279) (xy 325.361473 -120.961032) (xy 325.413769 -120.976384) (xy 325.463347 -120.999021)
			(xy 325.509199 -121.028485) (xy 325.550391 -121.064173) (xy 325.586085 -121.105361) (xy 325.615555 -121.151209)
			(xy 325.638199 -121.200785) (xy 325.649355 -121.238772) (xy 329.7842 -121.238772) (xy 329.788271 -121.18315)
			(xy 329.800397 -121.128713) (xy 329.82032 -121.076622) (xy 329.847616 -121.027987) (xy 329.881702 -120.983844)
			(xy 329.921851 -120.945135) (xy 329.967209 -120.912684) (xy 330.016809 -120.887183) (xy 330.069593 -120.869176)
			(xy 330.124436 -120.859046) (xy 330.18017 -120.857009) (xy 330.235607 -120.863109) (xy 330.289564 -120.877215)
			(xy 330.340893 -120.899027) (xy 330.388499 -120.928081) (xy 330.431367 -120.963756) (xy 330.468584 -121.005293)
			(xy 330.499357 -121.051806) (xy 330.523029 -121.102303) (xy 330.539097 -121.15571) (xy 330.547217 -121.210886)
			(xy 330.547726 -121.238772) (xy 330.547217 -121.266658) (xy 330.539097 -121.321834) (xy 330.523029 -121.375241)
			(xy 330.499357 -121.425738) (xy 330.468584 -121.472251) (xy 330.431367 -121.513788) (xy 330.388499 -121.549463)
			(xy 330.340893 -121.578517) (xy 330.289564 -121.600329) (xy 330.235607 -121.614435) (xy 330.18017 -121.620535)
			(xy 330.124436 -121.618498) (xy 330.069593 -121.608368) (xy 330.016809 -121.590361) (xy 329.967209 -121.56486)
			(xy 329.921851 -121.532409) (xy 329.881702 -121.4937) (xy 329.847616 -121.449557) (xy 329.82032 -121.400922)
			(xy 329.800397 -121.348831) (xy 329.788271 -121.294394) (xy 329.7842 -121.238772) (xy 325.649355 -121.238772)
			(xy 325.653557 -121.253078) (xy 325.661317 -121.307025) (xy 325.661782 -121.334276) (xy 325.661306 -121.361646)
			(xy 325.653491 -121.415825) (xy 325.638005 -121.468328) (xy 325.615165 -121.518075) (xy 325.585442 -121.564042)
			(xy 325.567802 -121.584974) (xy 325.567548 -121.585228) (xy 325.561979 -121.592327) (xy 325.555723 -121.609234)
			(xy 325.555356 -121.618248) (xy 325.555356 -121.685304) (xy 325.555699 -121.694323) (xy 325.561955 -121.71124)
			(xy 325.567548 -121.718324) (xy 325.567802 -121.718324) (xy 325.567802 -121.718578) (xy 325.585445 -121.739507)
			(xy 325.615156 -121.785481) (xy 325.637991 -121.835229) (xy 325.653481 -121.88773) (xy 325.661309 -121.941907)
			(xy 325.661782 -121.969276) (xy 325.661322 -121.996529) (xy 325.653568 -122.050482) (xy 325.638214 -122.102781)
			(xy 325.615572 -122.152363) (xy 325.586104 -122.198218) (xy 325.55041 -122.239411) (xy 325.509216 -122.275105)
			(xy 325.463361 -122.304573) (xy 325.413779 -122.327214) (xy 325.36148 -122.342568) (xy 325.307527 -122.350322)
			(xy 325.280274 -122.350784) (xy 325.251151 -122.350239) (xy 325.193579 -122.341409) (xy 325.13802 -122.323927)
			(xy 325.085764 -122.2982) (xy 325.038028 -122.264827) (xy 324.995922 -122.224584) (xy 324.960424 -122.178406)
			(xy 324.932361 -122.127367) (xy 324.912385 -122.072655) (xy 324.906132 -122.044206) (xy 324.903846 -122.032522)
			(xy 324.889368 -122.013726) (xy 324.805294 -121.97334) (xy 324.794479 -121.968779) (xy 324.77104 -121.969034)
			(xy 324.760336 -121.973848) (xy 324.759828 -121.973848) (xy 324.732769 -121.98713) (xy 324.675494 -122.005909)
			(xy 324.615975 -122.015428) (xy 324.585838 -122.016012) (xy 324.558586 -122.015509) (xy 324.504637 -122.007758)
			(xy 324.45234 -121.992407) (xy 324.40276 -121.969769) (xy 324.356907 -121.940305) (xy 324.315714 -121.904616)
			(xy 324.28002 -121.863426) (xy 324.250551 -121.817577) (xy 324.227908 -121.767999) (xy 324.212551 -121.715704)
			(xy 324.204794 -121.661756) (xy 324.20433 -121.634504) (xy 322.405968 -121.634504) (xy 322.405379 -121.63858)
			(xy 322.389877 -121.691084) (xy 322.367025 -121.740832) (xy 322.337294 -121.7868) (xy 322.31965 -121.807732)
			(xy 322.319396 -121.807986) (xy 322.313809 -121.815072) (xy 322.307563 -121.831989) (xy 322.307204 -121.841006)
			(xy 322.307204 -121.908062) (xy 322.307579 -121.917077) (xy 322.313814 -121.933994) (xy 322.319396 -121.941082)
			(xy 322.31965 -121.941082) (xy 322.31965 -121.941336) (xy 322.337265 -121.962288) (xy 322.366982 -122.008254)
			(xy 322.389823 -122.057997) (xy 322.40532 -122.110493) (xy 322.413153 -122.164666) (xy 322.41363 -122.192034)
			(xy 322.413144 -122.219285) (xy 322.405388 -122.273233) (xy 322.390033 -122.325528) (xy 322.367391 -122.375105)
			(xy 322.337925 -122.420955) (xy 322.302234 -122.462146) (xy 322.261043 -122.497837) (xy 322.215193 -122.527303)
			(xy 322.165616 -122.549945) (xy 322.113321 -122.5653) (xy 322.059373 -122.573056) (xy 322.004871 -122.573056)
			(xy 321.950923 -122.5653) (xy 321.898628 -122.549945) (xy 321.849051 -122.527303) (xy 321.803201 -122.497837)
			(xy 321.76201 -122.462146) (xy 321.726319 -122.420955) (xy 321.696853 -122.375105) (xy 321.674211 -122.325528)
			(xy 321.658856 -122.273233) (xy 321.6511 -122.219285) (xy 321.650614 -122.192034) (xy 320.772536 -122.192034)
			(xy 320.772536 -123.364548) (xy 326.264298 -123.364548) (xy 326.264298 -123.310052) (xy 326.272053 -123.256109)
			(xy 326.287406 -123.20382) (xy 326.310044 -123.154247) (xy 326.339506 -123.108401) (xy 326.375192 -123.067214)
			(xy 326.416377 -123.031524) (xy 326.462221 -123.002058) (xy 326.511792 -122.979417) (xy 326.56408 -122.96406)
			(xy 326.618022 -122.9563) (xy 326.64527 -122.955812) (xy 326.67264 -122.956293) (xy 326.726818 -122.964107)
			(xy 326.779321 -122.979592) (xy 326.829068 -123.002431) (xy 326.875036 -123.032152) (xy 326.895968 -123.049792)
			(xy 326.896222 -123.050046) (xy 326.903294 -123.055653) (xy 326.920222 -123.061886) (xy 326.929242 -123.062238)
			(xy 326.996298 -123.062238) (xy 327.005314 -123.061872) (xy 327.02223 -123.055629) (xy 327.029318 -123.050046)
			(xy 327.029318 -123.049792) (xy 327.029572 -123.049792) (xy 327.050505 -123.032151) (xy 327.096473 -123.002427)
			(xy 327.146219 -122.979581) (xy 327.198721 -122.964085) (xy 327.252899 -122.956256) (xy 327.307641 -122.956256)
			(xy 327.361819 -122.964085) (xy 327.414321 -122.979581) (xy 327.464067 -123.002427) (xy 327.510035 -123.032151)
			(xy 327.530968 -123.049792) (xy 327.531222 -123.050046) (xy 327.538294 -123.055653) (xy 327.555222 -123.061886)
			(xy 327.564242 -123.062238) (xy 327.631298 -123.062238) (xy 327.640314 -123.061872) (xy 327.65723 -123.055629)
			(xy 327.664318 -123.050046) (xy 327.664318 -123.049792) (xy 327.664572 -123.049792) (xy 327.685503 -123.032151)
			(xy 327.731476 -123.00244) (xy 327.781224 -122.979604) (xy 327.833725 -122.964114) (xy 327.887901 -122.956286)
			(xy 327.91527 -122.955812) (xy 327.942526 -122.956233) (xy 327.996483 -122.963987) (xy 328.048787 -122.979341)
			(xy 328.098374 -123.001983) (xy 328.144233 -123.031452) (xy 328.185431 -123.067147) (xy 328.22113 -123.108343)
			(xy 328.250603 -123.1542) (xy 328.273248 -123.203785) (xy 328.288607 -123.256088) (xy 328.296365 -123.310044)
			(xy 328.296365 -123.364556) (xy 328.288607 -123.418512) (xy 328.273248 -123.470815) (xy 328.250603 -123.5204)
			(xy 328.22113 -123.566257) (xy 328.185431 -123.607453) (xy 328.144233 -123.643148) (xy 328.098374 -123.672617)
			(xy 328.048787 -123.695259) (xy 327.996483 -123.710613) (xy 327.942526 -123.718367) (xy 327.91527 -123.718828)
			(xy 327.887898 -123.718397) (xy 327.833717 -123.710573) (xy 327.781213 -123.695077) (xy 327.731466 -123.672227)
			(xy 327.685502 -123.642494) (xy 327.664572 -123.624848) (xy 327.664318 -123.624594) (xy 327.657231 -123.619008)
			(xy 327.640315 -123.612761) (xy 327.631298 -123.612402) (xy 327.564242 -123.612402) (xy 327.555227 -123.612779)
			(xy 327.53831 -123.619013) (xy 327.531222 -123.624594) (xy 327.530968 -123.624848) (xy 327.510035 -123.642489)
			(xy 327.464067 -123.672213) (xy 327.414321 -123.695059) (xy 327.361819 -123.710555) (xy 327.307641 -123.718384)
			(xy 327.252899 -123.718384) (xy 327.198721 -123.710555) (xy 327.146219 -123.695059) (xy 327.096473 -123.672213)
			(xy 327.050505 -123.642489) (xy 327.029572 -123.624848) (xy 327.029318 -123.624594) (xy 327.022231 -123.619008)
			(xy 327.005315 -123.612761) (xy 326.996298 -123.612402) (xy 326.929242 -123.612402) (xy 326.920227 -123.612779)
			(xy 326.90331 -123.619013) (xy 326.896222 -123.624594) (xy 326.896222 -123.624848) (xy 326.895968 -123.624848)
			(xy 326.875014 -123.642461) (xy 326.829048 -123.672178) (xy 326.779306 -123.69502) (xy 326.72681 -123.710517)
			(xy 326.672638 -123.718351) (xy 326.64527 -123.718828) (xy 326.618022 -123.7183) (xy 326.56408 -123.71054)
			(xy 326.511792 -123.695183) (xy 326.462221 -123.672542) (xy 326.416377 -123.643076) (xy 326.375192 -123.607386)
			(xy 326.339506 -123.566199) (xy 326.310044 -123.520353) (xy 326.287406 -123.47078) (xy 326.272053 -123.418491)
			(xy 326.264298 -123.364548) (xy 320.772536 -123.364548) (xy 320.772536 -123.822229) (xy 329.642205 -123.822229)
			(xy 329.642208 -123.767731) (xy 329.649966 -123.713788) (xy 329.665323 -123.661498) (xy 329.687965 -123.611926)
			(xy 329.717431 -123.566081) (xy 329.753121 -123.524896) (xy 329.79431 -123.489209) (xy 329.840158 -123.459747)
			(xy 329.889732 -123.43711) (xy 329.942023 -123.421759) (xy 329.995967 -123.414005) (xy 330.023216 -123.41352)
			(xy 330.023724 -123.41352) (xy 330.034096 -123.4136) (xy 330.054808 -123.414744) (xy 330.065126 -123.415806)
			(xy 330.079675 -123.416857) (xy 330.108365 -123.411664) (xy 330.134422 -123.398584) (xy 330.155726 -123.378679)
			(xy 330.170544 -123.35357) (xy 330.177672 -123.325299) (xy 330.176529 -123.296165) (xy 330.172314 -123.282202)
			(xy 330.162954 -123.252595) (xy 330.152876 -123.191327) (xy 330.152248 -123.160282) (xy 330.152248 -123.160028)
			(xy 330.152725 -123.132772) (xy 330.160479 -123.078814) (xy 330.175834 -123.02651) (xy 330.198476 -122.976922)
			(xy 330.227945 -122.931063) (xy 330.263641 -122.889864) (xy 330.304837 -122.854164) (xy 330.350694 -122.824691)
			(xy 330.40028 -122.802045) (xy 330.452583 -122.786686) (xy 330.50654 -122.778927) (xy 330.561052 -122.778927)
			(xy 330.615009 -122.786684) (xy 330.667313 -122.802042) (xy 330.716899 -122.824688) (xy 330.762757 -122.85416)
			(xy 330.803953 -122.889858) (xy 330.83965 -122.931056) (xy 330.86912 -122.976915) (xy 330.891763 -123.026502)
			(xy 330.907119 -123.078807) (xy 330.914874 -123.132764) (xy 330.914872 -123.187276) (xy 330.907111 -123.241233)
			(xy 330.891749 -123.293535) (xy 330.869101 -123.34312) (xy 330.839626 -123.388976) (xy 330.803925 -123.43017)
			(xy 330.762725 -123.465864) (xy 330.716863 -123.495332) (xy 330.667275 -123.517972) (xy 330.61497 -123.533324)
			(xy 330.561012 -123.541076) (xy 330.533756 -123.541536) (xy 330.533248 -123.541536) (xy 330.522876 -123.541459)
			(xy 330.502164 -123.540313) (xy 330.491846 -123.53925) (xy 330.477298 -123.538232) (xy 330.448617 -123.543429)
			(xy 330.422569 -123.556508) (xy 330.40127 -123.576406) (xy 330.386452 -123.601506) (xy 330.379319 -123.629767)
			(xy 330.380451 -123.658893) (xy 330.384658 -123.672854) (xy 330.39401 -123.702463) (xy 330.404093 -123.763729)
			(xy 330.404724 -123.794774) (xy 330.404724 -123.795028) (xy 330.404192 -123.822277) (xy 330.396432 -123.87622)
			(xy 330.381074 -123.928509) (xy 330.358432 -123.978081) (xy 330.328965 -124.023925) (xy 330.293273 -124.06511)
			(xy 330.252084 -124.100796) (xy 330.206235 -124.130257) (xy 330.15666 -124.152893) (xy 330.104369 -124.168243)
			(xy 330.050425 -124.175996) (xy 329.995927 -124.175992) (xy 329.941984 -124.168233) (xy 329.889695 -124.152876)
			(xy 329.840123 -124.130234) (xy 329.794278 -124.100767) (xy 329.753093 -124.065076) (xy 329.717407 -124.023887)
			(xy 329.687945 -123.978039) (xy 329.665309 -123.928464) (xy 329.649958 -123.876173) (xy 329.642205 -123.822229)
			(xy 320.772536 -123.822229) (xy 320.772536 -124.215144) (xy 326.806558 -124.215144) (xy 326.810629 -124.159522)
			(xy 326.822755 -124.105085) (xy 326.842678 -124.052994) (xy 326.869974 -124.004359) (xy 326.90406 -123.960216)
			(xy 326.944209 -123.921507) (xy 326.989567 -123.889056) (xy 327.039167 -123.863555) (xy 327.091951 -123.845548)
			(xy 327.146794 -123.835418) (xy 327.202528 -123.833381) (xy 327.257965 -123.839481) (xy 327.311922 -123.853587)
			(xy 327.363251 -123.875399) (xy 327.410857 -123.904453) (xy 327.453725 -123.940128) (xy 327.490942 -123.981665)
			(xy 327.521715 -124.028178) (xy 327.545387 -124.078675) (xy 327.561455 -124.132082) (xy 327.569575 -124.187258)
			(xy 327.570084 -124.215144) (xy 327.569575 -124.24303) (xy 327.561455 -124.298206) (xy 327.545387 -124.351613)
			(xy 327.521715 -124.40211) (xy 327.490942 -124.448623) (xy 327.453725 -124.49016) (xy 327.410857 -124.525835)
			(xy 327.363251 -124.554889) (xy 327.311922 -124.576701) (xy 327.257965 -124.590807) (xy 327.202528 -124.596907)
			(xy 327.146794 -124.59487) (xy 327.091951 -124.58474) (xy 327.039167 -124.566733) (xy 326.989567 -124.541232)
			(xy 326.944209 -124.508781) (xy 326.90406 -124.470072) (xy 326.869974 -124.425929) (xy 326.842678 -124.377294)
			(xy 326.822755 -124.325203) (xy 326.810629 -124.270766) (xy 326.806558 -124.215144) (xy 320.772536 -124.215144)
			(xy 320.772536 -125.891544) (xy 327.375012 -125.891544) (xy 327.375438 -125.865229) (xy 327.382681 -125.813098)
			(xy 327.397008 -125.762454) (xy 327.418148 -125.714256) (xy 327.445702 -125.669413) (xy 327.479147 -125.628775)
			(xy 327.498202 -125.61062) (xy 327.505597 -125.603093) (xy 327.514125 -125.583817) (xy 327.514712 -125.573282)
			(xy 327.514712 -125.498606) (xy 327.51419 -125.488056) (xy 327.505649 -125.46876) (xy 327.498202 -125.461268)
			(xy 327.479138 -125.443121) (xy 327.445682 -125.402489) (xy 327.418124 -125.357647) (xy 327.396987 -125.309445)
			(xy 327.382671 -125.258796) (xy 327.375449 -125.206661) (xy 327.375012 -125.180344) (xy 327.375498 -125.153093)
			(xy 327.383254 -125.099145) (xy 327.398609 -125.04685) (xy 327.421251 -124.997273) (xy 327.450717 -124.951423)
			(xy 327.486408 -124.910232) (xy 327.527599 -124.874541) (xy 327.573449 -124.845075) (xy 327.623026 -124.822433)
			(xy 327.675321 -124.807078) (xy 327.729269 -124.799322) (xy 327.783771 -124.799322) (xy 327.837719 -124.807078)
			(xy 327.890014 -124.822433) (xy 327.939591 -124.845075) (xy 327.985441 -124.874541) (xy 328.026632 -124.910232)
			(xy 328.062323 -124.951423) (xy 328.091789 -124.997273) (xy 328.114431 -125.04685) (xy 328.129786 -125.099145)
			(xy 328.137542 -125.153093) (xy 328.138028 -125.180344) (xy 328.137581 -125.206659) (xy 328.130341 -125.258788)
			(xy 328.116017 -125.30943) (xy 328.094881 -125.357629) (xy 328.067331 -125.402472) (xy 328.03389 -125.443111)
			(xy 328.014838 -125.461268) (xy 328.007454 -125.468805) (xy 327.998919 -125.488073) (xy 327.998328 -125.498606)
			(xy 327.998328 -125.573282) (xy 327.998845 -125.583833) (xy 328.007388 -125.603129) (xy 328.014838 -125.61062)
			(xy 328.033903 -125.628765) (xy 328.067358 -125.669398) (xy 328.094915 -125.714241) (xy 328.116052 -125.762443)
			(xy 328.130367 -125.813092) (xy 328.13759 -125.865227) (xy 328.138028 -125.891544) (xy 328.137542 -125.918795)
			(xy 328.129786 -125.972743) (xy 328.114431 -126.025038) (xy 328.091789 -126.074615) (xy 328.062323 -126.120465)
			(xy 328.026632 -126.161656) (xy 327.985441 -126.197347) (xy 327.939591 -126.226813) (xy 327.890014 -126.249455)
			(xy 327.837719 -126.26481) (xy 327.783771 -126.272566) (xy 327.729269 -126.272566) (xy 327.675321 -126.26481)
			(xy 327.623026 -126.249455) (xy 327.573449 -126.226813) (xy 327.527599 -126.197347) (xy 327.486408 -126.161656)
			(xy 327.450717 -126.120465) (xy 327.421251 -126.074615) (xy 327.398609 -126.025038) (xy 327.383254 -125.972743)
			(xy 327.375498 -125.918795) (xy 327.375012 -125.891544) (xy 320.772536 -125.891544) (xy 320.772536 -135.249666)
			(xy 320.772007 -135.275689) (xy 320.763838 -135.327091) (xy 320.747742 -135.376586) (xy 320.724113 -135.42296)
			(xy 320.693532 -135.465076) (xy 320.675508 -135.483854) (xy 318.711072 -137.44829) (xy 356.645208 -137.44829)
			(xy 356.649279 -137.392668) (xy 356.661405 -137.338231) (xy 356.681328 -137.28614) (xy 356.708624 -137.237505)
			(xy 356.74271 -137.193362) (xy 356.782859 -137.154653) (xy 356.828217 -137.122202) (xy 356.877817 -137.096701)
			(xy 356.930601 -137.078694) (xy 356.985444 -137.068564) (xy 357.041178 -137.066527) (xy 357.096615 -137.072627)
			(xy 357.150572 -137.086733) (xy 357.201901 -137.108545) (xy 357.249507 -137.137599) (xy 357.292375 -137.173274)
			(xy 357.329592 -137.214811) (xy 357.360365 -137.261324) (xy 357.3674 -137.276332) (xy 361.347258 -137.276332)
			(xy 361.347662 -137.250016) (xy 361.354907 -137.197884) (xy 361.369237 -137.147239) (xy 361.390382 -137.09904)
			(xy 361.41794 -137.054198) (xy 361.451391 -137.013562) (xy 361.470448 -136.995408) (xy 361.47784 -136.987878)
			(xy 361.486372 -136.968605) (xy 361.486958 -136.95807) (xy 361.486958 -136.883394) (xy 361.486458 -136.872841)
			(xy 361.477904 -136.853545) (xy 361.470448 -136.846056) (xy 361.451368 -136.827925) (xy 361.417915 -136.787289)
			(xy 361.390361 -136.742443) (xy 361.369227 -136.694238) (xy 361.354914 -136.643586) (xy 361.347694 -136.591449)
			(xy 361.347258 -136.565132) (xy 361.347744 -136.537881) (xy 361.3555 -136.483933) (xy 361.370855 -136.431638)
			(xy 361.393497 -136.382061) (xy 361.422963 -136.336211) (xy 361.458654 -136.29502) (xy 361.499845 -136.259329)
			(xy 361.545695 -136.229863) (xy 361.595272 -136.207221) (xy 361.647567 -136.191866) (xy 361.701515 -136.18411)
			(xy 361.756017 -136.18411) (xy 361.809965 -136.191866) (xy 361.86226 -136.207221) (xy 361.911837 -136.229863)
			(xy 361.957687 -136.259329) (xy 361.998878 -136.29502) (xy 362.034569 -136.336211) (xy 362.064035 -136.382061)
			(xy 362.086677 -136.431638) (xy 362.102032 -136.483933) (xy 362.109788 -136.537881) (xy 362.110274 -136.565132)
			(xy 362.109836 -136.591447) (xy 362.102596 -136.643577) (xy 362.088272 -136.694221) (xy 362.067134 -136.74242)
			(xy 362.039582 -136.787263) (xy 362.006138 -136.827901) (xy 361.987084 -136.846056) (xy 361.979697 -136.85359)
			(xy 361.971165 -136.872861) (xy 361.970574 -136.883394) (xy 361.970574 -136.95807) (xy 361.971114 -136.968618)
			(xy 361.979642 -136.987913) (xy 361.987084 -136.995408) (xy 362.006133 -137.01357) (xy 362.039592 -137.054198)
			(xy 362.067152 -137.099037) (xy 362.088292 -137.147236) (xy 362.10261 -137.197883) (xy 362.109835 -137.250016)
			(xy 362.110274 -137.276332) (xy 362.109788 -137.303583) (xy 362.102032 -137.357531) (xy 362.086677 -137.409826)
			(xy 362.064035 -137.459403) (xy 362.034569 -137.505253) (xy 361.998878 -137.546444) (xy 361.957687 -137.582135)
			(xy 361.911837 -137.611601) (xy 361.86226 -137.634243) (xy 361.809965 -137.649598) (xy 361.756017 -137.657354)
			(xy 361.701515 -137.657354) (xy 361.647567 -137.649598) (xy 361.595272 -137.634243) (xy 361.545695 -137.611601)
			(xy 361.499845 -137.582135) (xy 361.458654 -137.546444) (xy 361.422963 -137.505253) (xy 361.393497 -137.459403)
			(xy 361.370855 -137.409826) (xy 361.3555 -137.357531) (xy 361.347744 -137.303583) (xy 361.347258 -137.276332)
			(xy 357.3674 -137.276332) (xy 357.384037 -137.311821) (xy 357.400105 -137.365228) (xy 357.408225 -137.420404)
			(xy 357.408734 -137.44829) (xy 357.408225 -137.476176) (xy 357.400105 -137.531352) (xy 357.384037 -137.584759)
			(xy 357.360365 -137.635256) (xy 357.329592 -137.681769) (xy 357.292375 -137.723306) (xy 357.288328 -137.726674)
			(xy 362.28782 -137.726674) (xy 362.288266 -137.699303) (xy 362.296088 -137.645123) (xy 362.311581 -137.592619)
			(xy 362.334428 -137.542873) (xy 362.364157 -137.496907) (xy 362.3818 -137.475976) (xy 362.382054 -137.475722)
			(xy 362.387644 -137.468638) (xy 362.393887 -137.451719) (xy 362.394246 -137.442702) (xy 362.394246 -137.375646)
			(xy 362.393879 -137.36663) (xy 362.38764 -137.349712) (xy 362.382054 -137.342626) (xy 362.3818 -137.342626)
			(xy 362.3818 -137.342372) (xy 362.364181 -137.321424) (xy 362.334466 -137.275455) (xy 362.311626 -137.225712)
			(xy 362.296131 -137.173215) (xy 362.288297 -137.119042) (xy 362.28782 -137.091674) (xy 362.288306 -137.064423)
			(xy 362.296062 -137.010475) (xy 362.311417 -136.95818) (xy 362.334059 -136.908603) (xy 362.363525 -136.862753)
			(xy 362.399216 -136.821562) (xy 362.440407 -136.785871) (xy 362.486257 -136.756405) (xy 362.535834 -136.733763)
			(xy 362.588129 -136.718408) (xy 362.642077 -136.710652) (xy 362.696579 -136.710652) (xy 362.750527 -136.718408)
			(xy 362.802822 -136.733763) (xy 362.852399 -136.756405) (xy 362.898249 -136.785871) (xy 362.93944 -136.821562)
			(xy 362.975131 -136.862753) (xy 363.004597 -136.908603) (xy 363.027239 -136.95818) (xy 363.042594 -137.010475)
			(xy 363.05035 -137.064423) (xy 363.050836 -137.091674) (xy 363.05037 -137.119044) (xy 363.042555 -137.173224)
			(xy 363.027066 -137.225728) (xy 363.004224 -137.275475) (xy 362.974498 -137.321441) (xy 362.956856 -137.342372)
			(xy 362.956602 -137.342626) (xy 362.95104 -137.34973) (xy 362.944779 -137.366633) (xy 362.94441 -137.375646)
			(xy 362.94441 -137.442702) (xy 362.944764 -137.451719) (xy 362.951013 -137.468636) (xy 362.956602 -137.475722)
			(xy 362.956856 -137.475722) (xy 362.956856 -137.475976) (xy 362.97449 -137.496912) (xy 363.004205 -137.542883)
			(xy 363.027042 -137.592629) (xy 363.042534 -137.64513) (xy 363.050362 -137.699305) (xy 363.050836 -137.726674)
			(xy 363.05035 -137.753925) (xy 363.042594 -137.807873) (xy 363.027239 -137.860168) (xy 363.004597 -137.909745)
			(xy 362.975131 -137.955595) (xy 362.93944 -137.996786) (xy 362.898249 -138.032477) (xy 362.852399 -138.061943)
			(xy 362.802822 -138.084585) (xy 362.750527 -138.09994) (xy 362.696579 -138.107696) (xy 362.642077 -138.107696)
			(xy 362.588129 -138.09994) (xy 362.535834 -138.084585) (xy 362.486257 -138.061943) (xy 362.440407 -138.032477)
			(xy 362.399216 -137.996786) (xy 362.363525 -137.955595) (xy 362.334059 -137.909745) (xy 362.311417 -137.860168)
			(xy 362.296062 -137.807873) (xy 362.288306 -137.753925) (xy 362.28782 -137.726674) (xy 357.288328 -137.726674)
			(xy 357.249507 -137.758981) (xy 357.201901 -137.788035) (xy 357.150572 -137.809847) (xy 357.096615 -137.823953)
			(xy 357.041178 -137.830053) (xy 356.985444 -137.828016) (xy 356.930601 -137.817886) (xy 356.877817 -137.799879)
			(xy 356.828217 -137.774378) (xy 356.782859 -137.741927) (xy 356.74271 -137.703218) (xy 356.708624 -137.659075)
			(xy 356.681328 -137.61044) (xy 356.661405 -137.558349) (xy 356.649279 -137.503912) (xy 356.645208 -137.44829)
			(xy 318.711072 -137.44829) (xy 317.798958 -138.360404) (xy 354.476048 -138.360404) (xy 354.480119 -138.304782)
			(xy 354.492245 -138.250345) (xy 354.512168 -138.198254) (xy 354.539464 -138.149619) (xy 354.57355 -138.105476)
			(xy 354.613699 -138.066767) (xy 354.659057 -138.034316) (xy 354.708657 -138.008815) (xy 354.761441 -137.990808)
			(xy 354.816284 -137.980678) (xy 354.872018 -137.978641) (xy 354.927455 -137.984741) (xy 354.981412 -137.998847)
			(xy 355.032741 -138.020659) (xy 355.080347 -138.049713) (xy 355.123215 -138.085388) (xy 355.160432 -138.126925)
			(xy 355.191205 -138.173438) (xy 355.214877 -138.223935) (xy 355.230945 -138.277342) (xy 355.239065 -138.332518)
			(xy 355.239574 -138.360404) (xy 355.239065 -138.38829) (xy 355.236852 -138.40333) (xy 363.496352 -138.40333)
			(xy 363.496863 -138.375665) (xy 363.50486 -138.320914) (xy 363.520675 -138.267892) (xy 363.543977 -138.217707)
			(xy 363.574279 -138.171411) (xy 363.610946 -138.129973) (xy 363.65321 -138.094262) (xy 363.676438 -138.079226)
			(xy 363.686103 -138.072575) (xy 363.698554 -138.052724) (xy 363.700314 -138.041126) (xy 363.708188 -137.961116)
			(xy 363.708791 -137.949479) (xy 363.700729 -137.927644) (xy 363.692694 -137.919206) (xy 363.69244 -137.918952)
			(xy 363.673861 -137.900869) (xy 363.641281 -137.860538) (xy 363.614466 -137.816165) (xy 363.593913 -137.768567)
			(xy 363.58 -137.718622) (xy 363.572983 -137.667253) (xy 363.572552 -137.64133) (xy 363.573106 -137.614081)
			(xy 363.580857 -137.560138) (xy 363.596207 -137.507847) (xy 363.618841 -137.458273) (xy 363.648301 -137.412424)
			(xy 363.683985 -137.371235) (xy 363.725168 -137.335543) (xy 363.771011 -137.306075) (xy 363.820582 -137.283431)
			(xy 363.87287 -137.268072) (xy 363.926811 -137.260311) (xy 363.95406 -137.259822) (xy 363.98143 -137.260306)
			(xy 364.035608 -137.268119) (xy 364.088111 -137.283603) (xy 364.137858 -137.306441) (xy 364.183826 -137.336162)
			(xy 364.204758 -137.353802) (xy 364.205012 -137.354056) (xy 364.212086 -137.35966) (xy 364.229013 -137.365895)
			(xy 364.238032 -137.366248) (xy 364.305088 -137.366248) (xy 364.314106 -137.365896) (xy 364.331023 -137.359646)
			(xy 364.338108 -137.354056) (xy 364.338108 -137.353802) (xy 364.338362 -137.353802) (xy 364.359298 -137.336168)
			(xy 364.40527 -137.306455) (xy 364.455016 -137.283618) (xy 364.507516 -137.268126) (xy 364.561691 -137.260297)
			(xy 364.58906 -137.259822) (xy 364.616313 -137.260293) (xy 364.670265 -137.268045) (xy 364.722565 -137.283397)
			(xy 364.772147 -137.306037) (xy 364.818002 -137.335504) (xy 364.859196 -137.371197) (xy 364.89489 -137.41239)
			(xy 364.924358 -137.458244) (xy 364.946999 -137.507826) (xy 364.962353 -137.560125) (xy 364.970107 -137.614077)
			(xy 364.970568 -137.64133) (xy 364.970012 -137.670246) (xy 364.961292 -137.727416) (xy 364.944043 -137.782614)
			(xy 364.918658 -137.834576) (xy 364.885721 -137.882111) (xy 364.845985 -137.924129) (xy 364.823502 -137.94232)
			(xy 364.814696 -137.949929) (xy 364.804512 -137.970828) (xy 364.803944 -137.982452) (xy 364.803944 -138.062208)
			(xy 364.804478 -138.073841) (xy 364.814669 -138.094751) (xy 364.823502 -138.10234) (xy 364.846005 -138.120508)
			(xy 364.885739 -138.162533) (xy 364.918676 -138.210072) (xy 364.944061 -138.262038) (xy 364.961312 -138.31724)
			(xy 364.970036 -138.374413) (xy 364.970568 -138.40333) (xy 364.970173 -138.430585) (xy 364.962411 -138.484541)
			(xy 364.950305 -138.525758) (xy 365.24184 -138.525758) (xy 365.24233 -138.498389) (xy 365.250141 -138.44421)
			(xy 365.265624 -138.391707) (xy 365.28846 -138.34196) (xy 365.318181 -138.295992) (xy 365.33582 -138.27506)
			(xy 365.336074 -138.274806) (xy 365.341673 -138.267728) (xy 365.34791 -138.250804) (xy 365.348266 -138.241786)
			(xy 365.348266 -138.17473) (xy 365.347902 -138.165714) (xy 365.34166 -138.148796) (xy 365.336074 -138.14171)
			(xy 365.33582 -138.14171) (xy 365.33582 -138.141456) (xy 365.318138 -138.120556) (xy 365.288416 -138.074583)
			(xy 365.265573 -138.024831) (xy 365.250081 -137.972324) (xy 365.242256 -137.918141) (xy 365.242261 -137.863396)
			(xy 365.250094 -137.809214) (xy 365.265596 -137.75671) (xy 365.288446 -137.706962) (xy 365.318177 -137.660993)
			(xy 365.33582 -137.64006) (xy 365.336074 -137.639806) (xy 365.341673 -137.632728) (xy 365.34791 -137.615804)
			(xy 365.348266 -137.606786) (xy 365.348266 -137.53973) (xy 365.347902 -137.530714) (xy 365.34166 -137.513796)
			(xy 365.336074 -137.50671) (xy 365.33582 -137.50671) (xy 365.33582 -137.506456) (xy 365.318138 -137.485556)
			(xy 365.288416 -137.439583) (xy 365.265573 -137.389831) (xy 365.250081 -137.337324) (xy 365.242256 -137.283141)
			(xy 365.242261 -137.228396) (xy 365.250094 -137.174214) (xy 365.265596 -137.12171) (xy 365.288446 -137.071962)
			(xy 365.318177 -137.025993) (xy 365.33582 -137.00506) (xy 365.336074 -137.004806) (xy 365.341673 -136.997728)
			(xy 365.34791 -136.980804) (xy 365.348266 -136.971786) (xy 365.348266 -136.90473) (xy 365.347902 -136.895714)
			(xy 365.34166 -136.878796) (xy 365.336074 -136.87171) (xy 365.33582 -136.87171) (xy 365.33582 -136.871456)
			(xy 365.318197 -136.850511) (xy 365.288482 -136.804542) (xy 365.265643 -136.754798) (xy 365.250148 -136.7023)
			(xy 365.242316 -136.648126) (xy 365.24184 -136.620758) (xy 365.242326 -136.593507) (xy 365.250082 -136.539559)
			(xy 365.265437 -136.487264) (xy 365.288079 -136.437687) (xy 365.317545 -136.391837) (xy 365.353236 -136.350646)
			(xy 365.394427 -136.314955) (xy 365.440277 -136.285489) (xy 365.489854 -136.262847) (xy 365.542149 -136.247492)
			(xy 365.596097 -136.239736) (xy 365.650599 -136.239736) (xy 365.704547 -136.247492) (xy 365.756842 -136.262847)
			(xy 365.806419 -136.285489) (xy 365.852269 -136.314955) (xy 365.89346 -136.350646) (xy 365.929151 -136.391837)
			(xy 365.958617 -136.437687) (xy 365.981259 -136.487264) (xy 365.996614 -136.539559) (xy 366.00437 -136.593507)
			(xy 366.004856 -136.620758) (xy 366.004376 -136.648128) (xy 365.996563 -136.702307) (xy 365.995968 -136.704324)
			(xy 385.6101 -136.704324) (xy 385.6101 -135.840724) (xy 385.61059 -135.810756) (xy 385.618413 -135.751334)
			(xy 385.633926 -135.693441) (xy 385.656862 -135.638068) (xy 385.686829 -135.586162) (xy 385.723316 -135.538612)
			(xy 385.765696 -135.496232) (xy 385.813246 -135.459745) (xy 385.865152 -135.429778) (xy 385.920525 -135.406842)
			(xy 385.978418 -135.391329) (xy 386.03784 -135.383506) (xy 386.097776 -135.383506) (xy 386.157198 -135.391329)
			(xy 386.215091 -135.406842) (xy 386.270464 -135.429778) (xy 386.32237 -135.459745) (xy 386.36992 -135.496232)
			(xy 386.4123 -135.538612) (xy 386.448787 -135.586162) (xy 386.478754 -135.638068) (xy 386.50169 -135.693441)
			(xy 386.517203 -135.751334) (xy 386.525026 -135.810756) (xy 386.525516 -135.840724) (xy 386.525516 -136.69645)
			(xy 400.085052 -136.69645) (xy 400.085052 -135.83285) (xy 400.085542 -135.802882) (xy 400.093365 -135.74346)
			(xy 400.108878 -135.685567) (xy 400.131814 -135.630194) (xy 400.161781 -135.578288) (xy 400.198268 -135.530738)
			(xy 400.240648 -135.488358) (xy 400.288198 -135.451871) (xy 400.340104 -135.421904) (xy 400.395477 -135.398968)
			(xy 400.45337 -135.383455) (xy 400.512792 -135.375632) (xy 400.572728 -135.375632) (xy 400.63215 -135.383455)
			(xy 400.690043 -135.398968) (xy 400.745416 -135.421904) (xy 400.797322 -135.451871) (xy 400.844872 -135.488358)
			(xy 400.887252 -135.530738) (xy 400.923739 -135.578288) (xy 400.953706 -135.630194) (xy 400.976642 -135.685567)
			(xy 400.992155 -135.74346) (xy 400.999978 -135.802882) (xy 401.000468 -135.83285) (xy 401.000468 -136.69645)
			(xy 400.999978 -136.726418) (xy 400.992155 -136.78584) (xy 400.976642 -136.843733) (xy 400.953706 -136.899106)
			(xy 400.923739 -136.951012) (xy 400.887252 -136.998562) (xy 400.844872 -137.040942) (xy 400.797322 -137.077429)
			(xy 400.745416 -137.107396) (xy 400.690043 -137.130332) (xy 400.63215 -137.145845) (xy 400.572728 -137.153668)
			(xy 400.512792 -137.153668) (xy 400.45337 -137.145845) (xy 400.395477 -137.130332) (xy 400.340104 -137.107396)
			(xy 400.288198 -137.077429) (xy 400.240648 -137.040942) (xy 400.198268 -136.998562) (xy 400.161781 -136.951012)
			(xy 400.131814 -136.899106) (xy 400.108878 -136.843733) (xy 400.093365 -136.78584) (xy 400.085542 -136.726418)
			(xy 400.085052 -136.69645) (xy 386.525516 -136.69645) (xy 386.525516 -136.704324) (xy 386.525026 -136.734292)
			(xy 386.517203 -136.793714) (xy 386.50169 -136.851607) (xy 386.478754 -136.90698) (xy 386.448787 -136.958886)
			(xy 386.4123 -137.006436) (xy 386.36992 -137.048816) (xy 386.32237 -137.085303) (xy 386.270464 -137.11527)
			(xy 386.215091 -137.138206) (xy 386.157198 -137.153719) (xy 386.097776 -137.161542) (xy 386.03784 -137.161542)
			(xy 385.978418 -137.153719) (xy 385.920525 -137.138206) (xy 385.865152 -137.11527) (xy 385.813246 -137.085303)
			(xy 385.765696 -137.048816) (xy 385.723316 -137.006436) (xy 385.686829 -136.958886) (xy 385.656862 -136.90698)
			(xy 385.633926 -136.851607) (xy 385.618413 -136.793714) (xy 385.61059 -136.734292) (xy 385.6101 -136.704324)
			(xy 365.995968 -136.704324) (xy 365.981078 -136.75481) (xy 365.958239 -136.804557) (xy 365.928517 -136.850524)
			(xy 365.910876 -136.871456) (xy 365.910622 -136.87171) (xy 365.905016 -136.878783) (xy 365.898783 -136.89571)
			(xy 365.89843 -136.90473) (xy 365.89843 -136.971786) (xy 365.898787 -136.980803) (xy 365.905034 -136.99772)
			(xy 365.910622 -137.004806) (xy 365.910876 -137.004806) (xy 365.910876 -137.00506) (xy 365.928475 -137.026026)
			(xy 365.958202 -137.071988) (xy 365.981049 -137.121729) (xy 365.996549 -137.174226) (xy 366.004381 -137.2284)
			(xy 366.004386 -137.283137) (xy 365.996562 -137.337312) (xy 365.981072 -137.389812) (xy 365.958232 -137.439556)
			(xy 365.928514 -137.485523) (xy 365.910876 -137.506456) (xy 365.910622 -137.50671) (xy 365.905016 -137.513783)
			(xy 365.898783 -137.53071) (xy 365.89843 -137.53973) (xy 365.89843 -137.606786) (xy 365.898787 -137.615803)
			(xy 365.905034 -137.63272) (xy 365.910622 -137.639806) (xy 365.910876 -137.639806) (xy 365.910876 -137.64006)
			(xy 365.928475 -137.661026) (xy 365.958202 -137.706988) (xy 365.981049 -137.756729) (xy 365.996549 -137.809226)
			(xy 366.004381 -137.8634) (xy 366.004386 -137.918137) (xy 365.996562 -137.972312) (xy 365.981072 -138.024812)
			(xy 365.958232 -138.074556) (xy 365.928514 -138.120523) (xy 365.910876 -138.141456) (xy 365.910622 -138.14171)
			(xy 365.905016 -138.148783) (xy 365.898783 -138.16571) (xy 365.89843 -138.17473) (xy 365.89843 -138.241786)
			(xy 365.898787 -138.250803) (xy 365.905034 -138.26772) (xy 365.910622 -138.274806) (xy 365.910876 -138.274806)
			(xy 365.910876 -138.27506) (xy 365.928506 -138.295999) (xy 365.95822 -138.34197) (xy 365.981058 -138.391715)
			(xy 365.996551 -138.444215) (xy 366.004381 -138.498389) (xy 366.004856 -138.525758) (xy 366.004277 -138.554944)
			(xy 365.995383 -138.612636) (xy 365.977812 -138.668301) (xy 365.951974 -138.720644) (xy 365.918469 -138.768444)
			(xy 365.87808 -138.810588) (xy 365.85525 -138.82878) (xy 365.846159 -138.836456) (xy 365.835688 -138.857787)
			(xy 365.835184 -138.869674) (xy 365.835946 -138.950954) (xy 365.836649 -138.962668) (xy 365.847243 -138.983581)
			(xy 365.856266 -138.991086) (xy 365.856774 -138.991594) (xy 365.88065 -139.010644) (xy 365.880904 -139.010898)
			(xy 365.887985 -139.016492) (xy 365.904906 -139.022734) (xy 365.913924 -139.02309) (xy 365.98098 -139.02309)
			(xy 365.989996 -139.022726) (xy 366.006913 -139.016484) (xy 366.014 -139.010898) (xy 366.014 -139.010644)
			(xy 366.014254 -139.010644) (xy 366.035187 -138.993003) (xy 366.081155 -138.963279) (xy 366.130901 -138.940433)
			(xy 366.183403 -138.924937) (xy 366.237581 -138.917108) (xy 366.292323 -138.917108) (xy 366.346501 -138.924937)
			(xy 366.399003 -138.940433) (xy 366.448749 -138.963279) (xy 366.494717 -138.993003) (xy 366.51565 -139.010644)
			(xy 366.515904 -139.010898) (xy 366.522985 -139.016492) (xy 366.539906 -139.022734) (xy 366.548924 -139.02309)
			(xy 366.61598 -139.02309) (xy 366.624996 -139.022726) (xy 366.641913 -139.016484) (xy 366.649 -139.010898)
			(xy 366.649 -139.010644) (xy 366.649254 -139.010644) (xy 366.670187 -138.993003) (xy 366.716155 -138.963279)
			(xy 366.765901 -138.940433) (xy 366.818403 -138.924937) (xy 366.872581 -138.917108) (xy 366.927323 -138.917108)
			(xy 366.981501 -138.924937) (xy 367.034003 -138.940433) (xy 367.083749 -138.963279) (xy 367.129717 -138.993003)
			(xy 367.15065 -139.010644) (xy 367.150904 -139.010898) (xy 367.157985 -139.016492) (xy 367.174906 -139.022734)
			(xy 367.183924 -139.02309) (xy 367.25098 -139.02309) (xy 367.259996 -139.022726) (xy 367.276913 -139.016484)
			(xy 367.284 -139.010898) (xy 367.284 -139.010644) (xy 367.284254 -139.010644) (xy 367.305198 -138.99302)
			(xy 367.351167 -138.963304) (xy 367.400911 -138.940465) (xy 367.45341 -138.92497) (xy 367.507584 -138.917139)
			(xy 367.534952 -138.916664) (xy 367.562205 -138.91718) (xy 367.616157 -138.924931) (xy 367.668457 -138.940282)
			(xy 367.71804 -138.96292) (xy 367.763895 -138.992384) (xy 367.805091 -139.028075) (xy 367.840787 -139.069266)
			(xy 367.870257 -139.115118) (xy 367.892902 -139.164698) (xy 367.908259 -139.216996) (xy 367.916017 -139.270947)
			(xy 367.916017 -139.325453) (xy 367.908259 -139.379404) (xy 367.892902 -139.431702) (xy 367.870257 -139.481282)
			(xy 367.840787 -139.527134) (xy 367.805091 -139.568325) (xy 367.763895 -139.604016) (xy 367.71804 -139.63348)
			(xy 367.668457 -139.656118) (xy 367.616157 -139.671469) (xy 367.562205 -139.67922) (xy 367.534952 -139.67968)
			(xy 367.507583 -139.679188) (xy 367.453404 -139.671377) (xy 367.400901 -139.655895) (xy 367.351154 -139.633058)
			(xy 367.305186 -139.603339) (xy 367.284254 -139.5857) (xy 367.284 -139.585446) (xy 367.276922 -139.579847)
			(xy 367.259999 -139.573609) (xy 367.25098 -139.573254) (xy 367.183924 -139.573254) (xy 367.174907 -139.573611)
			(xy 367.157989 -139.579857) (xy 367.150904 -139.585446) (xy 367.150904 -139.5857) (xy 367.15065 -139.5857)
			(xy 367.129717 -139.603341) (xy 367.083749 -139.633065) (xy 367.034003 -139.655911) (xy 366.981501 -139.671407)
			(xy 366.927323 -139.679236) (xy 366.872581 -139.679236) (xy 366.818403 -139.671407) (xy 366.765901 -139.655911)
			(xy 366.716155 -139.633065) (xy 366.670187 -139.603341) (xy 366.649254 -139.5857) (xy 366.649 -139.585446)
			(xy 366.641922 -139.579847) (xy 366.624999 -139.573609) (xy 366.61598 -139.573254) (xy 366.548924 -139.573254)
			(xy 366.539907 -139.573611) (xy 366.522989 -139.579857) (xy 366.515904 -139.585446) (xy 366.515904 -139.5857)
			(xy 366.51565 -139.5857) (xy 366.494717 -139.603341) (xy 366.448749 -139.633065) (xy 366.399003 -139.655911)
			(xy 366.346501 -139.671407) (xy 366.292323 -139.679236) (xy 366.237581 -139.679236) (xy 366.183403 -139.671407)
			(xy 366.130901 -139.655911) (xy 366.081155 -139.633065) (xy 366.035187 -139.603341) (xy 366.014254 -139.5857)
			(xy 366.014 -139.585446) (xy 366.006922 -139.579847) (xy 365.989999 -139.573609) (xy 365.98098 -139.573254)
			(xy 365.913924 -139.573254) (xy 365.904907 -139.573611) (xy 365.887989 -139.579857) (xy 365.880904 -139.585446)
			(xy 365.880904 -139.5857) (xy 365.88065 -139.5857) (xy 365.85971 -139.603329) (xy 365.813739 -139.633042)
			(xy 365.763994 -139.65588) (xy 365.711495 -139.671374) (xy 365.657321 -139.679205) (xy 365.629952 -139.67968)
			(xy 365.602698 -139.679267) (xy 365.548747 -139.671503) (xy 365.496449 -139.65614) (xy 365.446869 -139.633492)
			(xy 365.401018 -139.604018) (xy 365.359828 -139.568319) (xy 365.324137 -139.527121) (xy 365.294672 -139.481264)
			(xy 365.272033 -139.43168) (xy 365.256681 -139.379379) (xy 365.248928 -139.325426) (xy 365.248444 -139.298172)
			(xy 365.248973 -139.268984) (xy 365.257877 -139.21129) (xy 365.275458 -139.155623) (xy 365.301306 -139.103281)
			(xy 365.334819 -139.055482) (xy 365.375216 -139.013341) (xy 365.39805 -138.99515) (xy 365.407128 -138.98746)
			(xy 365.417605 -138.96614) (xy 365.418116 -138.954256) (xy 365.417354 -138.872976) (xy 365.416635 -138.861264)
			(xy 365.406052 -138.840351) (xy 365.397034 -138.832844) (xy 365.397034 -138.83259) (xy 365.396526 -138.83259)
			(xy 365.372936 -138.814499) (xy 365.331183 -138.772183) (xy 365.296507 -138.723897) (xy 365.269751 -138.670812)
			(xy 365.251562 -138.614216) (xy 365.242384 -138.555482) (xy 365.24184 -138.525758) (xy 364.950305 -138.525758)
			(xy 364.947049 -138.536843) (xy 364.9244 -138.586426) (xy 364.894925 -138.63228) (xy 364.859224 -138.673474)
			(xy 364.818024 -138.709167) (xy 364.772164 -138.738634) (xy 364.722577 -138.761273) (xy 364.670272 -138.776626)
			(xy 364.616316 -138.784378) (xy 364.58906 -138.784838) (xy 364.562744 -138.784417) (xy 364.510613 -138.777175)
			(xy 364.459969 -138.762849) (xy 364.411769 -138.741708) (xy 364.366927 -138.714152) (xy 364.32629 -138.680704)
			(xy 364.308136 -138.661648) (xy 364.300596 -138.654267) (xy 364.28133 -138.645729) (xy 364.270798 -138.645138)
			(xy 364.196122 -138.645138) (xy 364.18557 -138.645654) (xy 364.166274 -138.654197) (xy 364.158784 -138.661648)
			(xy 364.140639 -138.680713) (xy 364.100006 -138.714168) (xy 364.055163 -138.741724) (xy 364.00696 -138.762861)
			(xy 363.956312 -138.777176) (xy 363.904177 -138.7844) (xy 363.87786 -138.784838) (xy 363.850609 -138.784359)
			(xy 363.796663 -138.776598) (xy 363.74437 -138.76124) (xy 363.694794 -138.738596) (xy 363.648946 -138.709128)
			(xy 363.607757 -138.673436) (xy 363.572066 -138.632246) (xy 363.542599 -138.586397) (xy 363.519957 -138.536821)
			(xy 363.5046 -138.484527) (xy 363.49684 -138.430581) (xy 363.496352 -138.40333) (xy 355.236852 -138.40333)
			(xy 355.230945 -138.443466) (xy 355.214877 -138.496873) (xy 355.191205 -138.54737) (xy 355.160432 -138.593883)
			(xy 355.123215 -138.63542) (xy 355.080347 -138.671095) (xy 355.032741 -138.700149) (xy 354.981412 -138.721961)
			(xy 354.927455 -138.736067) (xy 354.872018 -138.742167) (xy 354.816284 -138.74013) (xy 354.761441 -138.73)
			(xy 354.708657 -138.711993) (xy 354.659057 -138.686492) (xy 354.613699 -138.654041) (xy 354.57355 -138.615332)
			(xy 354.539464 -138.571189) (xy 354.512168 -138.522554) (xy 354.492245 -138.470463) (xy 354.480119 -138.416026)
			(xy 354.476048 -138.360404) (xy 317.798958 -138.360404) (xy 317.654178 -138.505184) (xy 317.635406 -138.523214)
			(xy 317.593288 -138.553788) (xy 317.546911 -138.577409) (xy 317.497415 -138.593496) (xy 317.446012 -138.601654)
			(xy 317.41999 -138.602212) (xy 315.29782 -138.602212) (xy 315.287757 -138.60265) (xy 315.269174 -138.610386)
			(xy 315.261752 -138.617198) (xy 315.054531 -138.824462) (xy 356.661972 -138.824462) (xy 356.666043 -138.76884)
			(xy 356.678169 -138.714403) (xy 356.698092 -138.662312) (xy 356.725388 -138.613677) (xy 356.759474 -138.569534)
			(xy 356.799623 -138.530825) (xy 356.844981 -138.498374) (xy 356.894581 -138.472873) (xy 356.947365 -138.454866)
			(xy 357.002208 -138.444736) (xy 357.057942 -138.442699) (xy 357.113379 -138.448799) (xy 357.167336 -138.462905)
			(xy 357.218665 -138.484717) (xy 357.266271 -138.513771) (xy 357.309139 -138.549446) (xy 357.346356 -138.590983)
			(xy 357.377129 -138.637496) (xy 357.400801 -138.687993) (xy 357.416869 -138.7414) (xy 357.424989 -138.796576)
			(xy 357.425498 -138.824462) (xy 357.424989 -138.852348) (xy 357.416869 -138.907524) (xy 357.400801 -138.960931)
			(xy 357.377129 -139.011428) (xy 357.346356 -139.057941) (xy 357.309139 -139.099478) (xy 357.266271 -139.135153)
			(xy 357.218665 -139.164207) (xy 357.167336 -139.186019) (xy 357.113379 -139.200125) (xy 357.057942 -139.206225)
			(xy 357.002208 -139.204188) (xy 356.947365 -139.194058) (xy 356.894581 -139.176051) (xy 356.844981 -139.15055)
			(xy 356.799623 -139.118099) (xy 356.759474 -139.07939) (xy 356.725388 -139.035247) (xy 356.698092 -138.986612)
			(xy 356.678169 -138.934521) (xy 356.666043 -138.880084) (xy 356.661972 -138.824462) (xy 315.054531 -138.824462)
			(xy 314.162669 -139.71651) (xy 314.991748 -139.71651) (xy 314.995819 -139.660888) (xy 315.007945 -139.606451)
			(xy 315.027868 -139.55436) (xy 315.055164 -139.505725) (xy 315.08925 -139.461582) (xy 315.129399 -139.422873)
			(xy 315.174757 -139.390422) (xy 315.224357 -139.364921) (xy 315.277141 -139.346914) (xy 315.331984 -139.336784)
			(xy 315.387718 -139.334747) (xy 315.443155 -139.340847) (xy 315.497112 -139.354953) (xy 315.548441 -139.376765)
			(xy 315.596047 -139.405819) (xy 315.638915 -139.441494) (xy 315.676132 -139.483031) (xy 315.706905 -139.529544)
			(xy 315.730577 -139.580041) (xy 315.746645 -139.633448) (xy 315.75386 -139.682474) (xy 337.716366 -139.682474)
			(xy 337.720437 -139.626852) (xy 337.732563 -139.572415) (xy 337.752486 -139.520324) (xy 337.779782 -139.471689)
			(xy 337.813868 -139.427546) (xy 337.854017 -139.388837) (xy 337.899375 -139.356386) (xy 337.948975 -139.330885)
			(xy 338.001759 -139.312878) (xy 338.056602 -139.302748) (xy 338.112336 -139.300711) (xy 338.167773 -139.306811)
			(xy 338.22173 -139.320917) (xy 338.273059 -139.342729) (xy 338.320665 -139.371783) (xy 338.326218 -139.376404)
			(xy 354.476048 -139.376404) (xy 354.480119 -139.320782) (xy 354.492245 -139.266345) (xy 354.512168 -139.214254)
			(xy 354.539464 -139.165619) (xy 354.57355 -139.121476) (xy 354.613699 -139.082767) (xy 354.659057 -139.050316)
			(xy 354.708657 -139.024815) (xy 354.761441 -139.006808) (xy 354.816284 -138.996678) (xy 354.872018 -138.994641)
			(xy 354.927455 -139.000741) (xy 354.981412 -139.014847) (xy 355.032741 -139.036659) (xy 355.080347 -139.065713)
			(xy 355.123215 -139.101388) (xy 355.160432 -139.142925) (xy 355.191205 -139.189438) (xy 355.214877 -139.239935)
			(xy 355.230945 -139.293342) (xy 355.239065 -139.348518) (xy 355.239574 -139.376404) (xy 355.239065 -139.40429)
			(xy 355.230945 -139.459466) (xy 355.214877 -139.512873) (xy 355.191205 -139.56337) (xy 355.160432 -139.609883)
			(xy 355.123215 -139.65142) (xy 355.080347 -139.687095) (xy 355.032741 -139.716149) (xy 354.981412 -139.737961)
			(xy 354.927455 -139.752067) (xy 354.872018 -139.758167) (xy 354.816284 -139.75613) (xy 354.761441 -139.746)
			(xy 354.708657 -139.727993) (xy 354.659057 -139.702492) (xy 354.613699 -139.670041) (xy 354.57355 -139.631332)
			(xy 354.539464 -139.587189) (xy 354.512168 -139.538554) (xy 354.492245 -139.486463) (xy 354.480119 -139.432026)
			(xy 354.476048 -139.376404) (xy 338.326218 -139.376404) (xy 338.363533 -139.407458) (xy 338.40075 -139.448995)
			(xy 338.431523 -139.495508) (xy 338.455195 -139.546005) (xy 338.471263 -139.599412) (xy 338.479383 -139.654588)
			(xy 338.479892 -139.682474) (xy 338.479383 -139.71036) (xy 338.471263 -139.765536) (xy 338.455195 -139.818943)
			(xy 338.431523 -139.86944) (xy 338.40075 -139.915953) (xy 338.363533 -139.95749) (xy 338.320665 -139.993165)
			(xy 338.273059 -140.022219) (xy 338.22173 -140.044031) (xy 338.167773 -140.058137) (xy 338.112336 -140.064237)
			(xy 338.056602 -140.0622) (xy 338.001759 -140.05207) (xy 337.948975 -140.034063) (xy 337.899375 -140.008562)
			(xy 337.854017 -139.976111) (xy 337.813868 -139.937402) (xy 337.779782 -139.893259) (xy 337.752486 -139.844624)
			(xy 337.732563 -139.792533) (xy 337.720437 -139.738096) (xy 337.716366 -139.682474) (xy 315.75386 -139.682474)
			(xy 315.754765 -139.688624) (xy 315.755274 -139.71651) (xy 315.754765 -139.744396) (xy 315.746645 -139.799572)
			(xy 315.730577 -139.852979) (xy 315.706905 -139.903476) (xy 315.676132 -139.949989) (xy 315.638915 -139.991526)
			(xy 315.596047 -140.027201) (xy 315.548441 -140.056255) (xy 315.497112 -140.078067) (xy 315.443155 -140.092173)
			(xy 315.387718 -140.098273) (xy 315.331984 -140.096236) (xy 315.277141 -140.086106) (xy 315.224357 -140.068099)
			(xy 315.174757 -140.042598) (xy 315.129399 -140.010147) (xy 315.08925 -139.971438) (xy 315.055164 -139.927295)
			(xy 315.027868 -139.87866) (xy 315.007945 -139.826569) (xy 314.995819 -139.772132) (xy 314.991748 -139.71651)
			(xy 314.162669 -139.71651) (xy 314.04306 -139.836144) (xy 314.041028 -139.842748) (xy 314.032842 -139.868718)
			(xy 314.010135 -139.918208) (xy 313.98063 -139.963972) (xy 313.944924 -140.005081) (xy 313.903741 -140.040703)
			(xy 313.857916 -140.070114) (xy 313.808379 -140.092718) (xy 313.756134 -140.108058) (xy 313.702239 -140.115821)
			(xy 313.675014 -140.116306) (xy 313.649598 -140.115883) (xy 313.599217 -140.109134) (xy 313.550174 -140.095766)
			(xy 313.503337 -140.076015) (xy 313.459531 -140.05023) (xy 313.419529 -140.018866) (xy 313.401456 -140.00099)
			(xy 313.394852 -139.993878) (xy 313.367166 -139.98194) (xy 313.362326 -139.979935) (xy 313.352083 -139.977753)
			(xy 313.346846 -139.977622) (xy 313.294014 -139.977622) (xy 313.288779 -139.977775) (xy 313.278534 -139.979941)
			(xy 313.273694 -139.98194) (xy 313.246008 -139.993878) (xy 313.239404 -140.00099) (xy 313.221362 -140.0189)
			(xy 313.181361 -140.050273) (xy 313.137551 -140.076061) (xy 313.090705 -140.095806) (xy 313.041654 -140.109159)
			(xy 312.991264 -140.115886) (xy 312.965846 -140.116306) (xy 312.938591 -140.115846) (xy 312.884636 -140.108094)
			(xy 312.832332 -140.092742) (xy 312.782747 -140.070102) (xy 312.736888 -140.040636) (xy 312.69569 -140.004942)
			(xy 312.659992 -139.963749) (xy 312.63052 -139.917894) (xy 312.607874 -139.868311) (xy 312.592516 -139.816009)
			(xy 312.584757 -139.762055) (xy 312.584757 -139.707545) (xy 312.592516 -139.653591) (xy 312.607874 -139.601289)
			(xy 312.63052 -139.551706) (xy 312.659992 -139.505851) (xy 312.69569 -139.464658) (xy 312.736888 -139.428964)
			(xy 312.782747 -139.399498) (xy 312.832332 -139.376858) (xy 312.884636 -139.361506) (xy 312.938591 -139.353754)
			(xy 312.965846 -139.35329) (xy 312.991263 -139.353711) (xy 313.041647 -139.360455) (xy 313.090693 -139.373819)
			(xy 313.137534 -139.393566) (xy 313.181344 -139.419348) (xy 313.221351 -139.45071) (xy 313.239404 -139.468606)
			(xy 313.246008 -139.475718) (xy 313.273694 -139.487656) (xy 313.278535 -139.489656) (xy 313.288778 -139.491825)
			(xy 313.294014 -139.491974) (xy 313.346846 -139.491974) (xy 313.35208 -139.491815) (xy 313.36232 -139.489638)
			(xy 313.367166 -139.487656) (xy 313.394598 -139.475718) (xy 313.398662 -139.471654) (xy 313.41031 -139.459666)
			(xy 313.435364 -139.437534) (xy 313.4487 -139.427458) (xy 313.474709 -139.409095) (xy 313.531521 -139.380363)
			(xy 313.56173 -139.370308) (xy 313.567572 -139.36853) (xy 313.578494 -139.36218) (xy 314.904628 -138.035792)
			(xy 314.9234 -138.017764) (xy 314.965519 -137.987192) (xy 315.011896 -137.963574) (xy 315.061393 -137.94749)
			(xy 315.112794 -137.939333) (xy 315.138816 -137.938764) (xy 317.260986 -137.938764) (xy 317.271048 -137.938324)
			(xy 317.289627 -137.930584) (xy 317.297054 -137.923778) (xy 320.094102 -135.12673) (xy 320.100937 -135.119328)
			(xy 320.108646 -135.100729) (xy 320.109088 -135.090662) (xy 320.109088 -116.157502) (xy 320.108665 -116.147432)
			(xy 320.10095 -116.128828) (xy 320.094102 -116.121434) (xy 319.749932 -115.777518) (xy 319.74558 -115.773349)
			(xy 319.735304 -115.767056) (xy 319.729612 -115.765072) (xy 319.729358 -115.765072) (xy 319.703798 -115.756638)
			(xy 319.65516 -115.733588) (xy 319.610244 -115.703932) (xy 319.569941 -115.668259) (xy 319.53505 -115.627277)
			(xy 319.506264 -115.581798) (xy 319.484155 -115.532726) (xy 319.46916 -115.481034) (xy 319.461578 -115.427747)
			(xy 319.461134 -115.400836) (xy 319.461746 -115.370173) (xy 319.47157 -115.309639) (xy 319.490969 -115.251461)
			(xy 319.519441 -115.197145) (xy 319.537334 -115.172236) (xy 319.540636 -115.167918) (xy 319.545462 -115.161568)
			(xy 319.548256 -115.153694) (xy 319.552066 -115.142772) (xy 319.552066 -115.119912) (xy 319.551898 -115.114251)
			(xy 319.549336 -115.103221) (xy 319.546986 -115.098068) (xy 319.512188 -115.024916) (xy 319.509967 -115.020504)
			(xy 319.504086 -115.012569) (xy 319.500504 -115.009168) (xy 319.493336 -115.003104) (xy 319.47585 -114.9963)
			(xy 319.466468 -114.99596) (xy 313.21883 -114.99596) (xy 313.208766 -114.995523) (xy 313.190184 -114.987786)
			(xy 313.182762 -114.980974) (xy 313.14898 -114.947192) (xy 313.146127 -114.944489) (xy 313.139746 -114.939902)
			(xy 313.13628 -114.938048) (xy 313.130854 -114.93546) (xy 313.119175 -114.932629) (xy 313.113166 -114.93246)
			(xy 307.699664 -114.93246) (xy 307.687472 -114.933984) (xy 307.676804 -114.936524) (xy 307.669946 -114.938048)
			(xy 307.653182 -114.946938) (xy 307.6448 -114.951256) (xy 307.635148 -114.961924) (xy 307.631338 -114.96675)
			(xy 307.627283 -114.973158) (xy 307.622757 -114.987622) (xy 307.622448 -114.995198) (xy 307.622448 -115.016788)
			(xy 307.622309 -115.022228) (xy 307.620008 -115.032863) (xy 307.617876 -115.03787) (xy 307.611526 -115.051332)
			(xy 307.607936 -115.059797) (xy 307.60642 -115.078106) (xy 307.611475 -115.095769) (xy 307.616606 -115.103402)
			(xy 307.619654 -115.106958) (xy 307.637778 -115.128048) (xy 307.668361 -115.174488) (xy 307.691885 -115.224873)
			(xy 307.707852 -115.278138) (xy 307.715924 -115.333155) (xy 307.716428 -115.360958) (xy 307.715968 -115.388213)
			(xy 307.708216 -115.44217) (xy 307.692864 -115.494474) (xy 307.670224 -115.544061) (xy 307.640757 -115.589921)
			(xy 307.605064 -115.63112) (xy 307.56387 -115.66682) (xy 307.518015 -115.696294) (xy 307.468432 -115.718942)
			(xy 307.416131 -115.734303) (xy 307.362175 -115.742064) (xy 307.33492 -115.742466) (xy 307.334412 -115.742466)
			(xy 307.308786 -115.742036) (xy 307.258 -115.735138) (xy 307.208598 -115.721491) (xy 307.161472 -115.701342)
			(xy 307.117474 -115.675056) (xy 307.097176 -115.659408) (xy 307.090318 -115.654074) (xy 307.082698 -115.651534)
			(xy 307.078641 -115.65016) (xy 307.070215 -115.648623) (xy 307.065934 -115.648486) (xy 307.04409 -115.648486)
			(xy 307.03865 -115.648345) (xy 307.028017 -115.646041) (xy 307.023008 -115.643914) (xy 307.009546 -115.637564)
			(xy 307.001079 -115.633962) (xy 306.982757 -115.632423) (xy 306.965072 -115.637454) (xy 306.957476 -115.642644)
			(xy 306.95392 -115.645692) (xy 306.932829 -115.663813) (xy 306.886387 -115.694391) (xy 306.836002 -115.717909)
			(xy 306.782738 -115.733872) (xy 306.727722 -115.741939) (xy 306.69992 -115.742466) (xy 306.672667 -115.742004)
			(xy 306.618716 -115.734249) (xy 306.566419 -115.718894) (xy 306.516839 -115.696252) (xy 306.470986 -115.666784)
			(xy 306.429794 -115.63109) (xy 306.394102 -115.589896) (xy 306.364637 -115.544042) (xy 306.341998 -115.494461)
			(xy 306.326646 -115.442162) (xy 306.318894 -115.388211) (xy 306.318412 -115.360958) (xy 306.318412 -115.36045)
			(xy 306.318839 -115.334823) (xy 306.325733 -115.284035) (xy 306.339375 -115.234629) (xy 306.359519 -115.1875)
			(xy 306.385802 -115.143497) (xy 306.40147 -115.123214) (xy 306.406804 -115.116356) (xy 306.409344 -115.108736)
			(xy 306.410712 -115.104678) (xy 306.412236 -115.096252) (xy 306.412392 -115.091972) (xy 306.412392 -115.06962)
			(xy 306.412554 -115.064387) (xy 306.41474 -115.054151) (xy 306.41671 -115.0493) (xy 306.423568 -115.034314)
			(xy 306.427328 -115.02487) (xy 306.427857 -115.004567) (xy 306.424584 -114.994944) (xy 306.423264 -114.99163)
			(xy 306.419825 -114.985381) (xy 306.417726 -114.982498) (xy 306.415186 -114.979704) (xy 306.411122 -114.975132)
			(xy 306.410614 -114.974624) (xy 306.399184 -114.960908) (xy 306.395374 -114.956082) (xy 306.386992 -114.949478)
			(xy 306.363116 -114.937794) (xy 306.357789 -114.935338) (xy 306.346373 -114.932655) (xy 306.34051 -114.93246)
			(xy 304.82921 -114.93246) (xy 304.821797 -114.932713) (xy 304.807597 -114.936972) (xy 304.80127 -114.940842)
			(xy 304.795174 -114.944906) (xy 304.785776 -114.956082) (xy 304.782728 -114.963194) (xy 304.771295 -114.988528)
			(xy 304.742174 -115.035869) (xy 304.706493 -115.078483) (xy 304.665005 -115.115468) (xy 304.61859 -115.146042)
			(xy 304.568229 -115.169558) (xy 304.51499 -115.185517) (xy 304.459998 -115.193582) (xy 304.404418 -115.193582)
			(xy 304.349426 -115.185517) (xy 304.296187 -115.169558) (xy 304.245826 -115.146042) (xy 304.199411 -115.115468)
			(xy 304.157923 -115.078483) (xy 304.122242 -115.035869) (xy 304.093121 -114.988528) (xy 304.081688 -114.963194)
			(xy 304.081688 -114.96294) (xy 304.07853 -114.956216) (xy 304.068976 -114.94485) (xy 304.062892 -114.940588)
			(xy 304.056796 -114.936524) (xy 304.042826 -114.93246) (xy 300.131226 -114.93246) (xy 300.127155 -114.932516)
			(xy 300.119114 -114.933797) (xy 300.115224 -114.935) (xy 300.093126 -114.942366) (xy 300.089062 -114.94516)
			(xy 300.070386 -114.958138) (xy 300.030526 -114.980037) (xy 300.00956 -114.988848) (xy 299.993111 -114.995296)
			(xy 299.959272 -115.005468) (xy 299.941996 -115.009168) (xy 299.936154 -115.010184) (xy 299.930566 -115.011454)
			(xy 299.921422 -115.018312) (xy 299.917111 -115.021725) (xy 299.909929 -115.03005) (xy 299.907198 -115.034822)
			(xy 299.870876 -115.102132) (xy 299.867076 -115.10973) (xy 299.864228 -115.126469) (xy 299.865288 -115.134898)
			(xy 299.866812 -115.143788) (xy 299.868844 -115.148614) (xy 299.876891 -115.170531) (xy 299.888196 -115.215832)
			(xy 299.893883 -115.262175) (xy 299.894244 -115.28552) (xy 299.894244 -115.285774) (xy 299.893758 -115.313025)
			(xy 299.886002 -115.366973) (xy 299.870647 -115.419268) (xy 299.848005 -115.468845) (xy 299.818539 -115.514695)
			(xy 299.782848 -115.555886) (xy 299.741657 -115.591577) (xy 299.695807 -115.621043) (xy 299.64623 -115.643685)
			(xy 299.593935 -115.65904) (xy 299.539987 -115.666796) (xy 299.485485 -115.666796) (xy 299.431537 -115.65904)
			(xy 299.379242 -115.643685) (xy 299.329665 -115.621043) (xy 299.283815 -115.591577) (xy 299.242624 -115.555886)
			(xy 299.206933 -115.514695) (xy 299.177467 -115.468845) (xy 299.154825 -115.419268) (xy 299.13947 -115.366973)
			(xy 299.131714 -115.313025) (xy 299.131228 -115.285774) (xy 299.131642 -115.26017) (xy 299.138489 -115.209423)
			(xy 299.152056 -115.160046) (xy 299.1721 -115.112925) (xy 299.184822 -115.090702) (xy 299.187108 -115.086638)
			(xy 299.194474 -115.060476) (xy 299.194304 -115.053974) (xy 299.191084 -115.041376) (xy 299.188124 -115.035584)
			(xy 299.14469 -114.958368) (xy 299.139967 -114.95073) (xy 299.126298 -114.939099) (xy 299.109466 -114.93287)
			(xy 299.100494 -114.93246) (xy 299.031406 -114.93246) (xy 299.022262 -114.936016) (xy 298.995263 -114.946168)
			(xy 298.939061 -114.959139) (xy 298.881546 -114.963496) (xy 298.824031 -114.959139) (xy 298.767829 -114.946168)
			(xy 298.74083 -114.936016) (xy 298.731686 -114.93246) (xy 270.919448 -114.93246) (xy 270.91076 -114.932815)
			(xy 270.894403 -114.938674) (xy 270.887444 -114.94389) (xy 270.883634 -114.947192) (xy 270.876522 -114.954304)
			(xy 270.869664 -114.962686) (xy 270.83766 -115.012724) (xy 270.833342 -115.021106) (xy 270.831939 -115.024778)
			(xy 270.830152 -115.032432) (xy 270.829786 -115.036346) (xy 270.829786 -115.085114) (xy 270.833342 -115.094004)
			(xy 270.84179 -115.116403) (xy 270.853673 -115.162778) (xy 270.85966 -115.210275) (xy 270.860012 -115.234212)
			(xy 270.860012 -115.235228) (xy 270.859471 -115.264113) (xy 270.850746 -115.321221) (xy 270.833516 -115.376362)
			(xy 270.808172 -115.428277) (xy 270.775295 -115.47578) (xy 270.735636 -115.517786) (xy 270.690099 -115.553336)
			(xy 270.639725 -115.581619) (xy 270.585664 -115.601987) (xy 270.529151 -115.613976) (xy 270.500348 -115.616228)
			(xy 270.489172 -115.616736) (xy 270.47952 -115.621816) (xy 270.474951 -115.624443) (xy 270.466881 -115.63122)
			(xy 270.463518 -115.635278) (xy 270.439896 -115.66525) (xy 270.41602 -115.695476) (xy 270.412822 -115.699701)
			(xy 270.408095 -115.709182) (xy 270.406622 -115.714272) (xy 270.404082 -115.724686) (xy 270.406114 -115.735608)
			(xy 270.408945 -115.752356) (xy 270.41092 -115.774216) (xy 288.047174 -115.774216) (xy 288.051245 -115.718594)
			(xy 288.063371 -115.664157) (xy 288.083294 -115.612066) (xy 288.11059 -115.563431) (xy 288.144676 -115.519288)
			(xy 288.184825 -115.480579) (xy 288.230183 -115.448128) (xy 288.279783 -115.422627) (xy 288.332567 -115.40462)
			(xy 288.38741 -115.39449) (xy 288.443144 -115.392453) (xy 288.498581 -115.398553) (xy 288.552538 -115.412659)
			(xy 288.603867 -115.434471) (xy 288.651473 -115.463525) (xy 288.694341 -115.4992) (xy 288.731558 -115.540737)
			(xy 288.762331 -115.58725) (xy 288.786003 -115.637747) (xy 288.802071 -115.691154) (xy 288.810191 -115.74633)
			(xy 288.8107 -115.774216) (xy 288.810191 -115.802102) (xy 288.802071 -115.857278) (xy 288.78847 -115.902486)
			(xy 296.391074 -115.902486) (xy 296.395145 -115.846864) (xy 296.407271 -115.792427) (xy 296.427194 -115.740336)
			(xy 296.45449 -115.691701) (xy 296.488576 -115.647558) (xy 296.528725 -115.608849) (xy 296.574083 -115.576398)
			(xy 296.623683 -115.550897) (xy 296.676467 -115.53289) (xy 296.73131 -115.52276) (xy 296.787044 -115.520723)
			(xy 296.842481 -115.526823) (xy 296.896438 -115.540929) (xy 296.947767 -115.562741) (xy 296.995373 -115.591795)
			(xy 297.038241 -115.62747) (xy 297.075458 -115.669007) (xy 297.106231 -115.71552) (xy 297.129903 -115.766017)
			(xy 297.145971 -115.819424) (xy 297.154091 -115.8746) (xy 297.1546 -115.902486) (xy 297.154091 -115.930372)
			(xy 297.145971 -115.985548) (xy 297.129903 -116.038955) (xy 297.106231 -116.089452) (xy 297.075458 -116.135965)
			(xy 297.038241 -116.177502) (xy 296.995373 -116.213177) (xy 296.947767 -116.242231) (xy 296.896438 -116.264043)
			(xy 296.842481 -116.278149) (xy 296.787044 -116.284249) (xy 296.73131 -116.282212) (xy 296.676467 -116.272082)
			(xy 296.623683 -116.254075) (xy 296.574083 -116.228574) (xy 296.528725 -116.196123) (xy 296.488576 -116.157414)
			(xy 296.45449 -116.113271) (xy 296.427194 -116.064636) (xy 296.407271 -116.012545) (xy 296.395145 -115.958108)
			(xy 296.391074 -115.902486) (xy 288.78847 -115.902486) (xy 288.786003 -115.910685) (xy 288.762331 -115.961182)
			(xy 288.731558 -116.007695) (xy 288.694341 -116.049232) (xy 288.651473 -116.084907) (xy 288.603867 -116.113961)
			(xy 288.552538 -116.135773) (xy 288.498581 -116.149879) (xy 288.443144 -116.155979) (xy 288.38741 -116.153942)
			(xy 288.332567 -116.143812) (xy 288.279783 -116.125805) (xy 288.230183 -116.100304) (xy 288.184825 -116.067853)
			(xy 288.144676 -116.029144) (xy 288.11059 -115.985001) (xy 288.083294 -115.936366) (xy 288.063371 -115.884275)
			(xy 288.051245 -115.829838) (xy 288.047174 -115.774216) (xy 270.41092 -115.774216) (xy 270.412001 -115.786188)
			(xy 270.41221 -115.803172) (xy 270.41221 -115.803934) (xy 270.411768 -115.830301) (xy 270.404511 -115.882534)
			(xy 270.390124 -115.933269) (xy 270.368884 -115.981537) (xy 270.341195 -116.026417) (xy 270.307586 -116.067054)
			(xy 270.268697 -116.102672) (xy 270.225272 -116.132591) (xy 270.201898 -116.144802) (xy 270.192754 -116.149628)
			(xy 270.166084 -116.181124) (xy 270.162782 -116.191792) (xy 270.148812 -116.242084) (xy 270.147034 -116.255292)
			(xy 270.147034 -116.270532) (xy 270.147542 -116.276882) (xy 270.14805 -116.2812) (xy 270.14932 -116.288566)
			(xy 270.152368 -116.298218) (xy 270.156178 -116.304314) (xy 270.170837 -116.327655) (xy 270.194007 -116.377666)
			(xy 270.209728 -116.430494) (xy 270.212215 -116.44757) (xy 298.357034 -116.44757) (xy 298.361105 -116.391948)
			(xy 298.373231 -116.337511) (xy 298.393154 -116.28542) (xy 298.42045 -116.236785) (xy 298.454536 -116.192642)
			(xy 298.494685 -116.153933) (xy 298.540043 -116.121482) (xy 298.589643 -116.095981) (xy 298.642427 -116.077974)
			(xy 298.69727 -116.067844) (xy 298.753004 -116.065807) (xy 298.808441 -116.071907) (xy 298.862398 -116.086013)
			(xy 298.913727 -116.107825) (xy 298.961333 -116.136879) (xy 299.004201 -116.172554) (xy 299.041418 -116.214091)
			(xy 299.072191 -116.260604) (xy 299.095863 -116.311101) (xy 299.111931 -116.364508) (xy 299.120051 -116.419684)
			(xy 299.12056 -116.44757) (xy 299.120051 -116.475456) (xy 299.119781 -116.477288) (xy 303.504344 -116.477288)
			(xy 303.508415 -116.421666) (xy 303.520541 -116.367229) (xy 303.540464 -116.315138) (xy 303.56776 -116.266503)
			(xy 303.601846 -116.22236) (xy 303.641995 -116.183651) (xy 303.687353 -116.1512) (xy 303.736953 -116.125699)
			(xy 303.789737 -116.107692) (xy 303.84458 -116.097562) (xy 303.900314 -116.095525) (xy 303.955751 -116.101625)
			(xy 304.009708 -116.115731) (xy 304.061037 -116.137543) (xy 304.108643 -116.166597) (xy 304.151511 -116.202272)
			(xy 304.188728 -116.243809) (xy 304.219501 -116.290322) (xy 304.243173 -116.340819) (xy 304.259241 -116.394226)
			(xy 304.267361 -116.449402) (xy 304.26787 -116.477288) (xy 304.267361 -116.505174) (xy 304.259241 -116.56035)
			(xy 304.243173 -116.613757) (xy 304.219501 -116.664254) (xy 304.188728 -116.710767) (xy 304.151511 -116.752304)
			(xy 304.108643 -116.787979) (xy 304.061037 -116.817033) (xy 304.009708 -116.838845) (xy 303.955751 -116.852951)
			(xy 303.900314 -116.859051) (xy 303.84458 -116.857014) (xy 303.789737 -116.846884) (xy 303.736953 -116.828877)
			(xy 303.687353 -116.803376) (xy 303.641995 -116.770925) (xy 303.601846 -116.732216) (xy 303.56776 -116.688073)
			(xy 303.540464 -116.639438) (xy 303.520541 -116.587347) (xy 303.508415 -116.53291) (xy 303.504344 -116.477288)
			(xy 299.119781 -116.477288) (xy 299.111931 -116.530632) (xy 299.095863 -116.584039) (xy 299.072191 -116.634536)
			(xy 299.041418 -116.681049) (xy 299.004201 -116.722586) (xy 298.961333 -116.758261) (xy 298.913727 -116.787315)
			(xy 298.862398 -116.809127) (xy 298.808441 -116.823233) (xy 298.753004 -116.829333) (xy 298.69727 -116.827296)
			(xy 298.642427 -116.817166) (xy 298.589643 -116.799159) (xy 298.540043 -116.773658) (xy 298.494685 -116.741207)
			(xy 298.454536 -116.702498) (xy 298.42045 -116.658355) (xy 298.393154 -116.60972) (xy 298.373231 -116.557629)
			(xy 298.361105 -116.503192) (xy 298.357034 -116.44757) (xy 270.212215 -116.44757) (xy 270.217672 -116.485035)
			(xy 270.218154 -116.512594) (xy 270.217669 -116.539847) (xy 270.209913 -116.593798) (xy 270.194559 -116.646096)
			(xy 270.171919 -116.695677) (xy 270.142453 -116.741531) (xy 270.106763 -116.782726) (xy 270.065573 -116.818422)
			(xy 270.019722 -116.847894) (xy 269.970144 -116.870541) (xy 269.917848 -116.885902) (xy 269.863899 -116.893665)
			(xy 269.836646 -116.894102) (xy 269.811128 -116.893672) (xy 269.760548 -116.886864) (xy 269.711327 -116.873377)
			(xy 269.664342 -116.85345) (xy 269.620431 -116.82744) (xy 269.580378 -116.795811) (xy 269.562326 -116.77777)
			(xy 269.555468 -116.770658) (xy 269.52829 -116.75872) (xy 269.518384 -116.754402) (xy 269.46098 -116.754402)
			(xy 269.45336 -116.755164) (xy 269.440152 -116.75745) (xy 269.434056 -116.758466) (xy 269.406624 -116.770658)
			(xy 269.399512 -116.778024) (xy 269.381476 -116.79604) (xy 269.34145 -116.827614) (xy 269.297576 -116.853574)
			(xy 269.250634 -116.873459) (xy 269.201462 -116.886913) (xy 269.150936 -116.893697) (xy 269.125446 -116.894102)
			(xy 269.098191 -116.893642) (xy 269.044236 -116.88589) (xy 268.991934 -116.870538) (xy 268.942349 -116.847899)
			(xy 268.896491 -116.818433) (xy 268.855293 -116.78274) (xy 268.819595 -116.741546) (xy 268.790123 -116.695692)
			(xy 268.767478 -116.646109) (xy 268.75212 -116.593809) (xy 268.744361 -116.539855) (xy 268.744361 -116.485345)
			(xy 268.75212 -116.431391) (xy 268.767478 -116.379091) (xy 268.790123 -116.329508) (xy 268.819595 -116.283654)
			(xy 268.855293 -116.24246) (xy 268.896491 -116.206767) (xy 268.942349 -116.177301) (xy 268.991934 -116.154662)
			(xy 269.044236 -116.13931) (xy 269.098191 -116.131558) (xy 269.125446 -116.131086) (xy 269.150964 -116.131515)
			(xy 269.201545 -116.138322) (xy 269.250767 -116.151809) (xy 269.297753 -116.171734) (xy 269.341665 -116.197743)
			(xy 269.38172 -116.229371) (xy 269.399766 -116.247418) (xy 269.406624 -116.25453) (xy 269.433548 -116.266468)
			(xy 269.438388 -116.268472) (xy 269.448632 -116.27065) (xy 269.453868 -116.270786) (xy 269.501874 -116.270786)
			(xy 269.511018 -116.270024) (xy 269.52829 -116.266468) (xy 269.53337 -116.264182) (xy 269.551658 -116.256308)
			(xy 269.5575 -116.251482) (xy 269.56131 -116.248434) (xy 269.563596 -116.246148) (xy 269.586255 -116.223839)
			(xy 269.637576 -116.186301) (xy 269.665704 -116.171472) (xy 269.675102 -116.1669) (xy 269.702534 -116.134134)
			(xy 269.705328 -116.122958) (xy 269.721076 -116.063014) (xy 269.721076 -116.062506) (xy 269.723108 -116.05514)
			(xy 269.722854 -116.047774) (xy 269.72265 -116.043951) (xy 269.721254 -116.036425) (xy 269.72006 -116.032788)
			(xy 269.71498 -116.01831) (xy 269.711932 -116.01323) (xy 269.71117 -116.012214) (xy 269.696507 -115.988874)
			(xy 269.673331 -115.938864) (xy 269.657604 -115.886036) (xy 269.649655 -115.831493) (xy 269.649194 -115.803934)
			(xy 269.649731 -115.775046) (xy 269.658448 -115.717931) (xy 269.675673 -115.662783) (xy 269.701013 -115.61086)
			(xy 269.733888 -115.56335) (xy 269.773549 -115.521336) (xy 269.819088 -115.48578) (xy 269.869465 -115.457493)
			(xy 269.923531 -115.437121) (xy 269.980049 -115.42513) (xy 270.008858 -115.422934) (xy 270.020034 -115.422426)
			(xy 270.029686 -115.417346) (xy 270.034254 -115.414717) (xy 270.042318 -115.407936) (xy 270.045688 -115.403884)
			(xy 270.069564 -115.374166) (xy 270.069564 -115.373658) (xy 270.093186 -115.343686) (xy 270.096324 -115.339451)
			(xy 270.100926 -115.329971) (xy 270.10233 -115.32489) (xy 270.105124 -115.314476) (xy 270.103092 -115.303554)
			(xy 270.100248 -115.286744) (xy 270.097196 -115.252784) (xy 270.096996 -115.235736) (xy 270.096996 -115.233958)
			(xy 270.097449 -115.207496) (xy 270.104763 -115.155079) (xy 270.119244 -115.104175) (xy 270.129508 -115.07978)
			(xy 270.13154 -115.075208) (xy 270.133826 -115.065302) (xy 270.135096 -115.052856) (xy 270.134842 -115.041426)
			(xy 270.127984 -115.026948) (xy 270.125952 -115.024154) (xy 270.083788 -114.957352) (xy 270.07947 -114.953288)
			(xy 270.073374 -114.947192) (xy 270.069564 -114.94389) (xy 270.062602 -114.938686) (xy 270.046244 -114.932843)
			(xy 270.03756 -114.93246) (xy 244.840252 -114.93246) (xy 244.835576 -114.932542) (xy 244.826373 -114.934203)
			(xy 244.821964 -114.935762) (xy 244.797326 -114.945414) (xy 244.790722 -114.951002) (xy 244.769909 -114.968087)
			(xy 244.724391 -114.996853) (xy 244.675284 -115.018942) (xy 244.623562 -115.033918) (xy 244.570249 -115.041482)
			(xy 244.543326 -115.041934) (xy 244.513067 -115.04135) (xy 244.453308 -115.031787) (xy 244.395808 -115.012912)
			(xy 244.342007 -114.985199) (xy 244.317266 -114.967766) (xy 244.310662 -114.96294) (xy 244.303296 -114.9604)
			(xy 244.299288 -114.95912) (xy 244.290992 -114.957722) (xy 244.286786 -114.957606) (xy 244.275356 -114.957606)
			(xy 244.265392 -114.958088) (xy 244.246963 -114.965671) (xy 244.239542 -114.972338) (xy 243.635784 -115.576096)
			(xy 243.63308 -115.578948) (xy 243.628491 -115.585329) (xy 243.62664 -115.588796) (xy 243.624061 -115.594224)
			(xy 243.621247 -115.605903) (xy 243.621052 -115.61191) (xy 243.621052 -117.434106) (xy 245.576852 -117.434106)
			(xy 245.577309 -117.406735) (xy 245.585127 -117.352555) (xy 245.600618 -117.300052) (xy 245.623462 -117.250305)
			(xy 245.653189 -117.204339) (xy 245.670832 -117.183408) (xy 245.671086 -117.183154) (xy 245.676655 -117.176055)
			(xy 245.682913 -117.159148) (xy 245.683278 -117.150134) (xy 245.683278 -117.083078) (xy 245.682936 -117.074059)
			(xy 245.676679 -117.057142) (xy 245.671086 -117.050058) (xy 245.670832 -117.050058) (xy 245.670832 -117.049804)
			(xy 245.653197 -117.028867) (xy 245.623472 -116.9829) (xy 245.600626 -116.933154) (xy 245.585129 -116.880653)
			(xy 245.577299 -116.826475) (xy 245.577299 -116.771734) (xy 245.585127 -116.717556) (xy 245.600622 -116.665054)
			(xy 245.623467 -116.615308) (xy 245.653192 -116.569341) (xy 245.670832 -116.548408) (xy 245.671086 -116.548154)
			(xy 245.676655 -116.541055) (xy 245.682913 -116.524148) (xy 245.683278 -116.515134) (xy 245.683278 -116.448078)
			(xy 245.682936 -116.439059) (xy 245.676679 -116.422142) (xy 245.671086 -116.415058) (xy 245.670832 -116.415058)
			(xy 245.670832 -116.414804) (xy 245.653186 -116.393877) (xy 245.623474 -116.347903) (xy 245.600639 -116.298155)
			(xy 245.58515 -116.245653) (xy 245.577324 -116.191476) (xy 245.576852 -116.164106) (xy 245.577383 -116.136857)
			(xy 245.585138 -116.082913) (xy 245.60049 -116.030621) (xy 245.623128 -115.981047) (xy 245.65259 -115.935198)
			(xy 245.688276 -115.894009) (xy 245.729461 -115.858317) (xy 245.775306 -115.82885) (xy 245.824878 -115.806206)
			(xy 245.877168 -115.790848) (xy 245.931111 -115.783087) (xy 245.95836 -115.782598) (xy 245.985729 -115.783088)
			(xy 246.039907 -115.7909) (xy 246.09241 -115.806384) (xy 246.142157 -115.82922) (xy 246.188125 -115.858939)
			(xy 246.209058 -115.876578) (xy 246.209312 -115.876832) (xy 246.216388 -115.882433) (xy 246.233313 -115.88867)
			(xy 246.242332 -115.889024) (xy 246.309388 -115.889024) (xy 246.318404 -115.888656) (xy 246.33532 -115.882415)
			(xy 246.342408 -115.876832) (xy 246.342408 -115.876578) (xy 246.342662 -115.876578) (xy 246.363595 -115.85894)
			(xy 246.409568 -115.829229) (xy 246.459315 -115.806393) (xy 246.511815 -115.790901) (xy 246.565991 -115.783073)
			(xy 246.59336 -115.782598) (xy 246.620612 -115.783093) (xy 246.674562 -115.790844) (xy 246.72686 -115.806195)
			(xy 246.77644 -115.828834) (xy 246.822294 -115.858298) (xy 246.863487 -115.893989) (xy 246.899181 -115.935179)
			(xy 246.92865 -115.98103) (xy 246.951293 -116.030608) (xy 246.966649 -116.082904) (xy 246.974405 -116.136854)
			(xy 246.974868 -116.164106) (xy 246.974413 -116.191477) (xy 246.966594 -116.245657) (xy 246.951103 -116.29816)
			(xy 246.928258 -116.347907) (xy 246.898531 -116.393873) (xy 246.880888 -116.414804) (xy 246.880634 -116.415058)
			(xy 246.875051 -116.422147) (xy 246.868804 -116.439062) (xy 246.868442 -116.448078) (xy 246.868442 -116.515134)
			(xy 246.868774 -116.524154) (xy 246.875038 -116.541071) (xy 246.880634 -116.548154) (xy 246.880888 -116.548154)
			(xy 246.880888 -116.548408) (xy 246.898534 -116.569336) (xy 246.928257 -116.615305) (xy 246.951101 -116.665052)
			(xy 246.966597 -116.717555) (xy 246.974424 -116.771734) (xy 246.974424 -116.826475) (xy 246.966595 -116.880654)
			(xy 246.951098 -116.933156) (xy 246.928253 -116.982903) (xy 246.898528 -117.028871) (xy 246.880888 -117.049804)
			(xy 246.880634 -117.050058) (xy 246.875051 -117.057147) (xy 246.868804 -117.074062) (xy 246.868442 -117.083078)
			(xy 246.868442 -117.150134) (xy 246.868774 -117.159154) (xy 246.875038 -117.176071) (xy 246.880634 -117.183154)
			(xy 246.880888 -117.183154) (xy 246.880888 -117.183408) (xy 246.898542 -117.204328) (xy 246.928252 -117.250304)
			(xy 246.951086 -117.300054) (xy 246.966573 -117.352558) (xy 246.974397 -117.406736) (xy 246.974868 -117.434106)
			(xy 246.97473 -117.442234) (xy 247.85904 -117.442234) (xy 247.863111 -117.386612) (xy 247.875237 -117.332175)
			(xy 247.89516 -117.280084) (xy 247.922456 -117.231449) (xy 247.956542 -117.187306) (xy 247.996691 -117.148597)
			(xy 248.042049 -117.116146) (xy 248.091649 -117.090645) (xy 248.144433 -117.072638) (xy 248.199276 -117.062508)
			(xy 248.25501 -117.060471) (xy 248.310447 -117.066571) (xy 248.364404 -117.080677) (xy 248.415733 -117.102489)
			(xy 248.463339 -117.131543) (xy 248.506207 -117.167218) (xy 248.543424 -117.208755) (xy 248.574197 -117.255268)
			(xy 248.597869 -117.305765) (xy 248.613937 -117.359172) (xy 248.622057 -117.414348) (xy 248.622566 -117.442234)
			(xy 248.622057 -117.47012) (xy 248.613937 -117.525296) (xy 248.597869 -117.578703) (xy 248.574197 -117.6292)
			(xy 248.543424 -117.675713) (xy 248.506207 -117.71725) (xy 248.463339 -117.752925) (xy 248.415733 -117.781979)
			(xy 248.364404 -117.803791) (xy 248.310447 -117.817897) (xy 248.25501 -117.823997) (xy 248.199276 -117.82196)
			(xy 248.144433 -117.81183) (xy 248.091649 -117.793823) (xy 248.042049 -117.768322) (xy 247.996691 -117.735871)
			(xy 247.956542 -117.697162) (xy 247.922456 -117.653019) (xy 247.89516 -117.604384) (xy 247.875237 -117.552293)
			(xy 247.863111 -117.497856) (xy 247.85904 -117.442234) (xy 246.97473 -117.442234) (xy 246.974416 -117.460663)
			(xy 246.967047 -117.513262) (xy 246.952452 -117.564331) (xy 246.942102 -117.588792) (xy 246.937753 -117.60016)
			(xy 246.939101 -117.624434) (xy 246.944642 -117.635274) (xy 246.986044 -117.706394) (xy 246.99276 -117.716478)
			(xy 247.013181 -117.729461) (xy 247.02516 -117.731286) (xy 247.053143 -117.73446) (xy 247.107807 -117.747998)
			(xy 247.159886 -117.769425) (xy 247.208249 -117.798277) (xy 247.251844 -117.833926) (xy 247.289724 -117.875598)
			(xy 247.321066 -117.922386) (xy 247.345188 -117.973274) (xy 247.361565 -118.027155) (xy 247.367007 -118.063772)
			(xy 249.006104 -118.063772) (xy 249.010175 -118.00815) (xy 249.022301 -117.953713) (xy 249.042224 -117.901622)
			(xy 249.06952 -117.852987) (xy 249.103606 -117.808844) (xy 249.143755 -117.770135) (xy 249.189113 -117.737684)
			(xy 249.238713 -117.712183) (xy 249.291497 -117.694176) (xy 249.34634 -117.684046) (xy 249.402074 -117.682009)
			(xy 249.457511 -117.688109) (xy 249.511468 -117.702215) (xy 249.562797 -117.724027) (xy 249.610403 -117.753081)
			(xy 249.653271 -117.788756) (xy 249.690488 -117.830293) (xy 249.721261 -117.876806) (xy 249.744933 -117.927303)
			(xy 249.761001 -117.98071) (xy 249.76702 -118.021608) (xy 249.885454 -118.021608) (xy 249.885912 -117.994237)
			(xy 249.893729 -117.940057) (xy 249.90922 -117.887554) (xy 249.932064 -117.837807) (xy 249.961791 -117.791841)
			(xy 249.979434 -117.77091) (xy 249.979688 -117.770656) (xy 249.985256 -117.763557) (xy 249.991514 -117.74665)
			(xy 249.99188 -117.737636) (xy 249.99188 -117.67058) (xy 249.991537 -117.661562) (xy 249.98528 -117.644645)
			(xy 249.979688 -117.63756) (xy 249.979434 -117.63756) (xy 249.979434 -117.637306) (xy 249.961801 -117.616367)
			(xy 249.932075 -117.570401) (xy 249.909229 -117.520655) (xy 249.893732 -117.468154) (xy 249.885902 -117.413976)
			(xy 249.885901 -117.359236) (xy 249.893729 -117.305058) (xy 249.909225 -117.252556) (xy 249.932069 -117.20281)
			(xy 249.961794 -117.156843) (xy 249.979434 -117.13591) (xy 249.979688 -117.135656) (xy 249.985256 -117.128557)
			(xy 249.991514 -117.11165) (xy 249.99188 -117.102636) (xy 249.99188 -117.03558) (xy 249.991537 -117.026562)
			(xy 249.98528 -117.009645) (xy 249.979688 -117.00256) (xy 249.979434 -117.00256) (xy 249.979434 -117.002306)
			(xy 249.96179 -116.981378) (xy 249.932077 -116.935405) (xy 249.909242 -116.885656) (xy 249.893752 -116.833154)
			(xy 249.885926 -116.778978) (xy 249.885454 -116.751608) (xy 249.885985 -116.724359) (xy 249.89374 -116.670415)
			(xy 249.909092 -116.618123) (xy 249.931729 -116.568548) (xy 249.961191 -116.5227) (xy 249.996878 -116.48151)
			(xy 250.038063 -116.445819) (xy 250.083908 -116.416351) (xy 250.13348 -116.393708) (xy 250.18577 -116.378349)
			(xy 250.239713 -116.370588) (xy 250.266962 -116.3701) (xy 250.294331 -116.370588) (xy 250.34851 -116.378401)
			(xy 250.401012 -116.393885) (xy 250.45076 -116.416721) (xy 250.496728 -116.446441) (xy 250.51766 -116.46408)
			(xy 250.517914 -116.464334) (xy 250.52499 -116.469936) (xy 250.541915 -116.476172) (xy 250.550934 -116.476526)
			(xy 250.61799 -116.476526) (xy 250.627006 -116.476158) (xy 250.643922 -116.469918) (xy 250.65101 -116.464334)
			(xy 250.65101 -116.46408) (xy 250.651264 -116.46408) (xy 250.672196 -116.446441) (xy 250.718169 -116.41673)
			(xy 250.767917 -116.393894) (xy 250.820417 -116.378403) (xy 250.874593 -116.370574) (xy 250.901962 -116.3701)
			(xy 250.929214 -116.370591) (xy 250.983165 -116.378343) (xy 251.035462 -116.393694) (xy 251.085043 -116.416333)
			(xy 251.130897 -116.445798) (xy 251.17209 -116.481489) (xy 251.207784 -116.522679) (xy 251.237253 -116.568531)
			(xy 251.259895 -116.618109) (xy 251.275251 -116.670406) (xy 251.283007 -116.724356) (xy 251.28347 -116.751608)
			(xy 251.283016 -116.778979) (xy 251.275196 -116.833159) (xy 251.259705 -116.885662) (xy 251.23686 -116.935409)
			(xy 251.207133 -116.981375) (xy 251.18949 -117.002306) (xy 251.189236 -117.00256) (xy 251.183652 -117.009648)
			(xy 251.177406 -117.026564) (xy 251.177044 -117.03558) (xy 251.177044 -117.102636) (xy 251.177374 -117.111656)
			(xy 251.183639 -117.128573) (xy 251.189236 -117.135656) (xy 251.18949 -117.135656) (xy 251.18949 -117.13591)
			(xy 251.207138 -117.156837) (xy 251.236861 -117.202806) (xy 251.259705 -117.252553) (xy 251.2752 -117.305056)
			(xy 251.283027 -117.359235) (xy 251.283026 -117.413977) (xy 251.275197 -117.468156) (xy 251.259701 -117.520658)
			(xy 251.236855 -117.570405) (xy 251.207131 -117.616373) (xy 251.18949 -117.637306) (xy 251.189236 -117.63756)
			(xy 251.183652 -117.644648) (xy 251.177406 -117.661564) (xy 251.177044 -117.67058) (xy 251.177044 -117.737636)
			(xy 251.177374 -117.746656) (xy 251.180242 -117.7544) (xy 269.288004 -117.7544) (xy 269.292075 -117.698778)
			(xy 269.304201 -117.644341) (xy 269.324124 -117.59225) (xy 269.35142 -117.543615) (xy 269.385506 -117.499472)
			(xy 269.425655 -117.460763) (xy 269.471013 -117.428312) (xy 269.520613 -117.402811) (xy 269.573397 -117.384804)
			(xy 269.62824 -117.374674) (xy 269.683974 -117.372637) (xy 269.739411 -117.378737) (xy 269.793368 -117.392843)
			(xy 269.844697 -117.414655) (xy 269.892303 -117.443709) (xy 269.935171 -117.479384) (xy 269.972388 -117.520921)
			(xy 270.003161 -117.567434) (xy 270.026833 -117.617931) (xy 270.042901 -117.671338) (xy 270.050602 -117.723666)
			(xy 301.889666 -117.723666) (xy 301.893737 -117.668044) (xy 301.905863 -117.613607) (xy 301.925786 -117.561516)
			(xy 301.953082 -117.512881) (xy 301.987168 -117.468738) (xy 302.027317 -117.430029) (xy 302.072675 -117.397578)
			(xy 302.122275 -117.372077) (xy 302.175059 -117.35407) (xy 302.229902 -117.34394) (xy 302.285636 -117.341903)
			(xy 302.341073 -117.348003) (xy 302.39503 -117.362109) (xy 302.446359 -117.383921) (xy 302.493965 -117.412975)
			(xy 302.536833 -117.44865) (xy 302.57405 -117.490187) (xy 302.604823 -117.5367) (xy 302.628495 -117.587197)
			(xy 302.644563 -117.640604) (xy 302.652683 -117.69578) (xy 302.653192 -117.723666) (xy 302.652683 -117.751552)
			(xy 302.644563 -117.806728) (xy 302.628495 -117.860135) (xy 302.604823 -117.910632) (xy 302.57405 -117.957145)
			(xy 302.536833 -117.998682) (xy 302.493965 -118.034357) (xy 302.446359 -118.063411) (xy 302.39503 -118.085223)
			(xy 302.341073 -118.099329) (xy 302.285636 -118.105429) (xy 302.229902 -118.103392) (xy 302.175059 -118.093262)
			(xy 302.122275 -118.075255) (xy 302.072675 -118.049754) (xy 302.027317 -118.017303) (xy 301.987168 -117.978594)
			(xy 301.953082 -117.934451) (xy 301.925786 -117.885816) (xy 301.905863 -117.833725) (xy 301.893737 -117.779288)
			(xy 301.889666 -117.723666) (xy 270.050602 -117.723666) (xy 270.051021 -117.726514) (xy 270.05153 -117.7544)
			(xy 270.051021 -117.782286) (xy 270.042901 -117.837462) (xy 270.026833 -117.890869) (xy 270.003161 -117.941366)
			(xy 269.972388 -117.987879) (xy 269.935171 -118.029416) (xy 269.892303 -118.065091) (xy 269.844697 -118.094145)
			(xy 269.793368 -118.115957) (xy 269.739411 -118.130063) (xy 269.683974 -118.136163) (xy 269.62824 -118.134126)
			(xy 269.573397 -118.123996) (xy 269.520613 -118.105989) (xy 269.471013 -118.080488) (xy 269.425655 -118.048037)
			(xy 269.385506 -118.009328) (xy 269.35142 -117.965185) (xy 269.324124 -117.91655) (xy 269.304201 -117.864459)
			(xy 269.292075 -117.810022) (xy 269.288004 -117.7544) (xy 251.180242 -117.7544) (xy 251.183639 -117.763573)
			(xy 251.189236 -117.770656) (xy 251.18949 -117.770656) (xy 251.18949 -117.77091) (xy 251.207146 -117.791829)
			(xy 251.236855 -117.837805) (xy 251.259688 -117.887556) (xy 251.275175 -117.94006) (xy 251.282999 -117.994238)
			(xy 251.28347 -118.021608) (xy 251.283052 -118.048863) (xy 251.275293 -118.102817) (xy 251.259934 -118.155118)
			(xy 251.237288 -118.204701) (xy 251.208202 -118.249954) (xy 287.813748 -118.249954) (xy 287.817819 -118.194332)
			(xy 287.829945 -118.139895) (xy 287.849868 -118.087804) (xy 287.877164 -118.039169) (xy 287.91125 -117.995026)
			(xy 287.951399 -117.956317) (xy 287.996757 -117.923866) (xy 288.046357 -117.898365) (xy 288.099141 -117.880358)
			(xy 288.153984 -117.870228) (xy 288.209718 -117.868191) (xy 288.265155 -117.874291) (xy 288.319112 -117.888397)
			(xy 288.370441 -117.910209) (xy 288.418047 -117.939263) (xy 288.460915 -117.974938) (xy 288.498132 -118.016475)
			(xy 288.528905 -118.062988) (xy 288.552577 -118.113485) (xy 288.568645 -118.166892) (xy 288.576765 -118.222068)
			(xy 288.577274 -118.249954) (xy 288.576765 -118.27784) (xy 288.568795 -118.331996) (xy 295.095674 -118.331996)
			(xy 295.099745 -118.276374) (xy 295.111871 -118.221937) (xy 295.131794 -118.169846) (xy 295.15909 -118.121211)
			(xy 295.193176 -118.077068) (xy 295.233325 -118.038359) (xy 295.278683 -118.005908) (xy 295.328283 -117.980407)
			(xy 295.381067 -117.9624) (xy 295.43591 -117.95227) (xy 295.491644 -117.950233) (xy 295.547081 -117.956333)
			(xy 295.601038 -117.970439) (xy 295.652367 -117.992251) (xy 295.699973 -118.021305) (xy 295.742841 -118.05698)
			(xy 295.780058 -118.098517) (xy 295.810831 -118.14503) (xy 295.834503 -118.195527) (xy 295.850571 -118.248934)
			(xy 295.858691 -118.30411) (xy 295.8592 -118.331996) (xy 295.858691 -118.359882) (xy 295.850571 -118.415058)
			(xy 295.834503 -118.468465) (xy 295.810831 -118.518962) (xy 295.780058 -118.565475) (xy 295.742841 -118.607012)
			(xy 295.699973 -118.642687) (xy 295.652367 -118.671741) (xy 295.601038 -118.693553) (xy 295.547081 -118.707659)
			(xy 295.491644 -118.713759) (xy 295.43591 -118.711722) (xy 295.381067 -118.701592) (xy 295.328283 -118.683585)
			(xy 295.278683 -118.658084) (xy 295.233325 -118.625633) (xy 295.193176 -118.586924) (xy 295.15909 -118.542781)
			(xy 295.131794 -118.494146) (xy 295.111871 -118.442055) (xy 295.099745 -118.387618) (xy 295.095674 -118.331996)
			(xy 288.568795 -118.331996) (xy 288.568645 -118.333016) (xy 288.552577 -118.386423) (xy 288.528905 -118.43692)
			(xy 288.498132 -118.483433) (xy 288.460915 -118.52497) (xy 288.418047 -118.560645) (xy 288.370441 -118.589699)
			(xy 288.319112 -118.611511) (xy 288.265155 -118.625617) (xy 288.209718 -118.631717) (xy 288.153984 -118.62968)
			(xy 288.099141 -118.61955) (xy 288.046357 -118.601543) (xy 287.996757 -118.576042) (xy 287.951399 -118.543591)
			(xy 287.91125 -118.504882) (xy 287.877164 -118.460739) (xy 287.849868 -118.412104) (xy 287.829945 -118.360013)
			(xy 287.817819 -118.305576) (xy 287.813748 -118.249954) (xy 251.208202 -118.249954) (xy 251.207815 -118.250556)
			(xy 251.172117 -118.291749) (xy 251.130919 -118.327443) (xy 251.085061 -118.35691) (xy 251.035475 -118.37955)
			(xy 250.983172 -118.394903) (xy 250.929217 -118.402655) (xy 250.901962 -118.403116) (xy 250.874592 -118.402634)
			(xy 250.820413 -118.394823) (xy 250.767909 -118.379339) (xy 250.718162 -118.3565) (xy 250.672195 -118.326777)
			(xy 250.651264 -118.309136) (xy 250.65101 -118.308882) (xy 250.643926 -118.303291) (xy 250.627007 -118.297048)
			(xy 250.61799 -118.29669) (xy 250.550934 -118.29669) (xy 250.541919 -118.297065) (xy 250.525002 -118.3033)
			(xy 250.517914 -118.308882) (xy 250.517914 -118.309136) (xy 250.51766 -118.309136) (xy 250.496721 -118.326766)
			(xy 250.450749 -118.356478) (xy 250.401004 -118.379315) (xy 250.348505 -118.394808) (xy 250.294331 -118.40264)
			(xy 250.266962 -118.403116) (xy 250.23971 -118.402658) (xy 250.185762 -118.394896) (xy 250.133467 -118.379537)
			(xy 250.08389 -118.356892) (xy 250.03804 -118.327422) (xy 249.996851 -118.291728) (xy 249.96116 -118.250535)
			(xy 249.931694 -118.204683) (xy 249.909053 -118.155105) (xy 249.893698 -118.102809) (xy 249.88594 -118.04886)
			(xy 249.885454 -118.021608) (xy 249.76702 -118.021608) (xy 249.769121 -118.035886) (xy 249.76963 -118.063772)
			(xy 249.769121 -118.091658) (xy 249.761001 -118.146834) (xy 249.744933 -118.200241) (xy 249.721261 -118.250738)
			(xy 249.690488 -118.297251) (xy 249.653271 -118.338788) (xy 249.610403 -118.374463) (xy 249.562797 -118.403517)
			(xy 249.511468 -118.425329) (xy 249.457511 -118.439435) (xy 249.402074 -118.445535) (xy 249.34634 -118.443498)
			(xy 249.291497 -118.433368) (xy 249.238713 -118.415361) (xy 249.189113 -118.38986) (xy 249.143755 -118.357409)
			(xy 249.103606 -118.3187) (xy 249.06952 -118.274557) (xy 249.042224 -118.225922) (xy 249.022301 -118.173831)
			(xy 249.010175 -118.119394) (xy 249.006104 -118.063772) (xy 247.367007 -118.063772) (xy 247.369843 -118.082858)
			(xy 247.370346 -118.111016) (xy 247.36986 -118.138267) (xy 247.362104 -118.192215) (xy 247.346749 -118.24451)
			(xy 247.324107 -118.294087) (xy 247.294641 -118.339937) (xy 247.25895 -118.381128) (xy 247.217759 -118.416819)
			(xy 247.171909 -118.446285) (xy 247.122332 -118.468927) (xy 247.070037 -118.484282) (xy 247.016089 -118.492038)
			(xy 246.961587 -118.492038) (xy 246.907639 -118.484282) (xy 246.855344 -118.468927) (xy 246.805767 -118.446285)
			(xy 246.759917 -118.416819) (xy 246.718726 -118.381128) (xy 246.683035 -118.339937) (xy 246.653569 -118.294087)
			(xy 246.630927 -118.24451) (xy 246.615572 -118.192215) (xy 246.607816 -118.138267) (xy 246.60733 -118.111016)
			(xy 246.60779 -118.08446) (xy 246.615156 -118.03186) (xy 246.629747 -117.980791) (xy 246.640096 -117.95633)
			(xy 246.644431 -117.944957) (xy 246.643093 -117.920688) (xy 246.637556 -117.909848) (xy 246.596154 -117.838728)
			(xy 246.58941 -117.828667) (xy 246.569009 -117.815676) (xy 246.557038 -117.813836) (xy 246.527564 -117.810453)
			(xy 246.470096 -117.795736) (xy 246.415599 -117.772298) (xy 246.365389 -117.740703) (xy 246.342662 -117.721634)
			(xy 246.342408 -117.72138) (xy 246.335325 -117.715788) (xy 246.318405 -117.709545) (xy 246.309388 -117.709188)
			(xy 246.242332 -117.709188) (xy 246.233317 -117.709563) (xy 246.2164 -117.715798) (xy 246.209312 -117.72138)
			(xy 246.209312 -117.721634) (xy 246.209058 -117.721634) (xy 246.188119 -117.739265) (xy 246.142148 -117.768977)
			(xy 246.092402 -117.791814) (xy 246.039903 -117.807307) (xy 245.985729 -117.815138) (xy 245.95836 -117.815614)
			(xy 245.931108 -117.815159) (xy 245.87716 -117.807398) (xy 245.824865 -117.792038) (xy 245.775288 -117.769392)
			(xy 245.729438 -117.739922) (xy 245.688248 -117.704228) (xy 245.652557 -117.663035) (xy 245.623091 -117.617183)
			(xy 245.60045 -117.567604) (xy 245.585095 -117.515307) (xy 245.577338 -117.461358) (xy 245.576852 -117.434106)
			(xy 243.621052 -117.434106) (xy 243.621052 -117.962426) (xy 244.427246 -117.962426) (xy 244.431317 -117.906804)
			(xy 244.443443 -117.852367) (xy 244.463366 -117.800276) (xy 244.490662 -117.751641) (xy 244.524748 -117.707498)
			(xy 244.564897 -117.668789) (xy 244.610255 -117.636338) (xy 244.659855 -117.610837) (xy 244.712639 -117.59283)
			(xy 244.767482 -117.5827) (xy 244.823216 -117.580663) (xy 244.878653 -117.586763) (xy 244.93261 -117.600869)
			(xy 244.983939 -117.622681) (xy 245.031545 -117.651735) (xy 245.074413 -117.68741) (xy 245.11163 -117.728947)
			(xy 245.142403 -117.77546) (xy 245.166075 -117.825957) (xy 245.182143 -117.879364) (xy 245.190263 -117.93454)
			(xy 245.190772 -117.962426) (xy 245.190263 -117.990312) (xy 245.182143 -118.045488) (xy 245.166075 -118.098895)
			(xy 245.142403 -118.149392) (xy 245.11163 -118.195905) (xy 245.074413 -118.237442) (xy 245.031545 -118.273117)
			(xy 244.983939 -118.302171) (xy 244.93261 -118.323983) (xy 244.878653 -118.338089) (xy 244.823216 -118.344189)
			(xy 244.767482 -118.342152) (xy 244.712639 -118.332022) (xy 244.659855 -118.314015) (xy 244.610255 -118.288514)
			(xy 244.564897 -118.256063) (xy 244.524748 -118.217354) (xy 244.490662 -118.173211) (xy 244.463366 -118.124576)
			(xy 244.443443 -118.072485) (xy 244.431317 -118.018048) (xy 244.427246 -117.962426) (xy 243.621052 -117.962426)
			(xy 243.621052 -119.640096) (xy 243.621052 -119.642382) (xy 243.621912 -119.652024) (xy 243.629888 -119.669643)
			(xy 243.636546 -119.676672) (xy 243.697252 -119.728996) (xy 243.701384 -119.732364) (xy 243.710732 -119.737485)
			(xy 243.715794 -119.739156) (xy 243.7257 -119.742204) (xy 243.737384 -119.740426) (xy 243.751085 -119.738532)
			(xy 243.778671 -119.736501) (xy 243.792502 -119.736362) (xy 243.793264 -119.736362) (xy 243.820521 -119.736822)
			(xy 243.87448 -119.744576) (xy 243.926786 -119.75993) (xy 243.976375 -119.782572) (xy 244.022236 -119.812042)
			(xy 244.063436 -119.847738) (xy 244.099137 -119.888935) (xy 244.12861 -119.934794) (xy 244.151257 -119.98438)
			(xy 244.166616 -120.036685) (xy 244.174375 -120.090643) (xy 244.174375 -120.11787) (xy 244.427246 -120.11787)
			(xy 244.431317 -120.062248) (xy 244.443443 -120.007811) (xy 244.463366 -119.95572) (xy 244.490662 -119.907085)
			(xy 244.524748 -119.862942) (xy 244.564897 -119.824233) (xy 244.610255 -119.791782) (xy 244.659855 -119.766281)
			(xy 244.712639 -119.748274) (xy 244.767482 -119.738144) (xy 244.823216 -119.736107) (xy 244.878653 -119.742207)
			(xy 244.93261 -119.756313) (xy 244.983939 -119.778125) (xy 245.031545 -119.807179) (xy 245.074413 -119.842854)
			(xy 245.11163 -119.884391) (xy 245.142403 -119.930904) (xy 245.166075 -119.981401) (xy 245.182143 -120.034808)
			(xy 245.190263 -120.089984) (xy 245.190772 -120.11787) (xy 245.190263 -120.145756) (xy 245.189134 -120.15343)
			(xy 247.62282 -120.15343) (xy 247.626891 -120.097808) (xy 247.639017 -120.043371) (xy 247.65894 -119.99128)
			(xy 247.686236 -119.942645) (xy 247.720322 -119.898502) (xy 247.760471 -119.859793) (xy 247.805829 -119.827342)
			(xy 247.855429 -119.801841) (xy 247.908213 -119.783834) (xy 247.963056 -119.773704) (xy 248.01879 -119.771667)
			(xy 248.074227 -119.777767) (xy 248.128184 -119.791873) (xy 248.179513 -119.813685) (xy 248.227119 -119.842739)
			(xy 248.269987 -119.878414) (xy 248.307204 -119.919951) (xy 248.337977 -119.966464) (xy 248.361649 -120.016961)
			(xy 248.377717 -120.070368) (xy 248.380297 -120.087898) (xy 266.86764 -120.087898) (xy 266.86764 -119.224298)
			(xy 266.86813 -119.194314) (xy 266.875958 -119.134858) (xy 266.891479 -119.076933) (xy 266.914428 -119.021529)
			(xy 266.944412 -118.969595) (xy 266.980918 -118.922019) (xy 267.023323 -118.879614) (xy 267.070899 -118.843108)
			(xy 267.122833 -118.813124) (xy 267.178237 -118.790175) (xy 267.236162 -118.774654) (xy 267.295618 -118.766826)
			(xy 267.355586 -118.766826) (xy 267.415042 -118.774654) (xy 267.472967 -118.790175) (xy 267.528371 -118.813124)
			(xy 267.580305 -118.843108) (xy 267.627881 -118.879614) (xy 267.670286 -118.922019) (xy 267.706792 -118.969595)
			(xy 267.736776 -119.021529) (xy 267.759725 -119.076933) (xy 267.775246 -119.134858) (xy 267.783074 -119.194314)
			(xy 267.783564 -119.224298) (xy 267.783564 -120.086374) (xy 285.8389 -120.086374) (xy 285.8389 -119.222774)
			(xy 285.83939 -119.19279) (xy 285.847218 -119.133334) (xy 285.862739 -119.075409) (xy 285.885688 -119.020005)
			(xy 285.915672 -118.968071) (xy 285.952178 -118.920495) (xy 285.994583 -118.87809) (xy 286.042159 -118.841584)
			(xy 286.094093 -118.8116) (xy 286.149497 -118.788651) (xy 286.207422 -118.77313) (xy 286.266878 -118.765302)
			(xy 286.326846 -118.765302) (xy 286.386302 -118.77313) (xy 286.444227 -118.788651) (xy 286.499631 -118.8116)
			(xy 286.551565 -118.841584) (xy 286.599141 -118.87809) (xy 286.641546 -118.920495) (xy 286.678052 -118.968071)
			(xy 286.708036 -119.020005) (xy 286.730985 -119.075409) (xy 286.746506 -119.133334) (xy 286.754334 -119.19279)
			(xy 286.754824 -119.222774) (xy 286.754824 -119.567198) (xy 298.799504 -119.567198) (xy 298.799504 -118.703598)
			(xy 298.799994 -118.67363) (xy 298.807817 -118.614208) (xy 298.82333 -118.556315) (xy 298.846266 -118.500942)
			(xy 298.876233 -118.449036) (xy 298.91272 -118.401486) (xy 298.9551 -118.359106) (xy 299.00265 -118.322619)
			(xy 299.054556 -118.292652) (xy 299.109929 -118.269716) (xy 299.167822 -118.254203) (xy 299.227244 -118.24638)
			(xy 299.28718 -118.24638) (xy 299.346602 -118.254203) (xy 299.404495 -118.269716) (xy 299.459868 -118.292652)
			(xy 299.511774 -118.322619) (xy 299.559324 -118.359106) (xy 299.601704 -118.401486) (xy 299.638191 -118.449036)
			(xy 299.668158 -118.500942) (xy 299.691094 -118.556315) (xy 299.706607 -118.614208) (xy 299.71443 -118.67363)
			(xy 299.71492 -118.703598) (xy 299.71492 -119.567198) (xy 299.71443 -119.597166) (xy 299.706607 -119.656588)
			(xy 299.691094 -119.714481) (xy 299.668158 -119.769854) (xy 299.638191 -119.82176) (xy 299.601704 -119.86931)
			(xy 299.559324 -119.91169) (xy 299.511774 -119.948177) (xy 299.459868 -119.978144) (xy 299.404495 -120.00108)
			(xy 299.346602 -120.016593) (xy 299.28718 -120.024416) (xy 299.227244 -120.024416) (xy 299.167822 -120.016593)
			(xy 299.109929 -120.00108) (xy 299.054556 -119.978144) (xy 299.00265 -119.948177) (xy 298.9551 -119.91169)
			(xy 298.91272 -119.86931) (xy 298.876233 -119.82176) (xy 298.846266 -119.769854) (xy 298.82333 -119.714481)
			(xy 298.807817 -119.656588) (xy 298.799994 -119.597166) (xy 298.799504 -119.567198) (xy 286.754824 -119.567198)
			(xy 286.754824 -120.086374) (xy 286.754334 -120.116358) (xy 286.746506 -120.175814) (xy 286.730985 -120.233739)
			(xy 286.708036 -120.289143) (xy 286.678052 -120.341077) (xy 286.641546 -120.388653) (xy 286.599141 -120.431058)
			(xy 286.551565 -120.467564) (xy 286.499631 -120.497548) (xy 286.444227 -120.520497) (xy 286.386302 -120.536018)
			(xy 286.326846 -120.543846) (xy 286.266878 -120.543846) (xy 286.207422 -120.536018) (xy 286.149497 -120.520497)
			(xy 286.094093 -120.497548) (xy 286.042159 -120.467564) (xy 285.994583 -120.431058) (xy 285.952178 -120.388653)
			(xy 285.915672 -120.341077) (xy 285.885688 -120.289143) (xy 285.862739 -120.233739) (xy 285.847218 -120.175814)
			(xy 285.83939 -120.116358) (xy 285.8389 -120.086374) (xy 267.783564 -120.086374) (xy 267.783564 -120.087898)
			(xy 267.783074 -120.117882) (xy 267.775246 -120.177338) (xy 267.759725 -120.235263) (xy 267.736776 -120.290667)
			(xy 267.706792 -120.342601) (xy 267.670286 -120.390177) (xy 267.627881 -120.432582) (xy 267.580305 -120.469088)
			(xy 267.528371 -120.499072) (xy 267.472967 -120.522021) (xy 267.415042 -120.537542) (xy 267.355586 -120.54537)
			(xy 267.295618 -120.54537) (xy 267.236162 -120.537542) (xy 267.178237 -120.522021) (xy 267.122833 -120.499072)
			(xy 267.070899 -120.469088) (xy 267.023323 -120.432582) (xy 266.980918 -120.390177) (xy 266.944412 -120.342601)
			(xy 266.914428 -120.290667) (xy 266.891479 -120.235263) (xy 266.875958 -120.177338) (xy 266.86813 -120.117882)
			(xy 266.86764 -120.087898) (xy 248.380297 -120.087898) (xy 248.385837 -120.125544) (xy 248.386346 -120.15343)
			(xy 248.385837 -120.181316) (xy 248.377717 -120.236492) (xy 248.361649 -120.289899) (xy 248.337977 -120.340396)
			(xy 248.307204 -120.386909) (xy 248.269987 -120.428446) (xy 248.227119 -120.464121) (xy 248.179513 -120.493175)
			(xy 248.128184 -120.514987) (xy 248.074227 -120.529093) (xy 248.01879 -120.535193) (xy 247.963056 -120.533156)
			(xy 247.908213 -120.523026) (xy 247.855429 -120.505019) (xy 247.805829 -120.479518) (xy 247.760471 -120.447067)
			(xy 247.720322 -120.408358) (xy 247.686236 -120.364215) (xy 247.65894 -120.31558) (xy 247.639017 -120.263489)
			(xy 247.626891 -120.209052) (xy 247.62282 -120.15343) (xy 245.189134 -120.15343) (xy 245.182143 -120.200932)
			(xy 245.166075 -120.254339) (xy 245.142403 -120.304836) (xy 245.11163 -120.351349) (xy 245.074413 -120.392886)
			(xy 245.031545 -120.428561) (xy 244.983939 -120.457615) (xy 244.93261 -120.479427) (xy 244.878653 -120.493533)
			(xy 244.823216 -120.499633) (xy 244.767482 -120.497596) (xy 244.712639 -120.487466) (xy 244.659855 -120.469459)
			(xy 244.610255 -120.443958) (xy 244.564897 -120.411507) (xy 244.524748 -120.372798) (xy 244.490662 -120.328655)
			(xy 244.463366 -120.28002) (xy 244.443443 -120.227929) (xy 244.431317 -120.173492) (xy 244.427246 -120.11787)
			(xy 244.174375 -120.11787) (xy 244.174375 -120.145157) (xy 244.166616 -120.199115) (xy 244.151257 -120.25142)
			(xy 244.12861 -120.301006) (xy 244.099137 -120.346865) (xy 244.063436 -120.388062) (xy 244.022236 -120.423758)
			(xy 243.976375 -120.453228) (xy 243.926786 -120.47587) (xy 243.87448 -120.491224) (xy 243.820521 -120.498978)
			(xy 243.793264 -120.499378) (xy 243.789454 -120.499378) (xy 243.776331 -120.499274) (xy 243.750146 -120.497492)
			(xy 243.73713 -120.495822) (xy 243.733828 -120.495314) (xy 243.72951 -120.495314) (xy 243.720493 -120.495672)
			(xy 243.703576 -120.501918) (xy 243.69649 -120.507506) (xy 243.63934 -120.556528) (xy 243.634721 -120.560702)
			(xy 243.627514 -120.570849) (xy 243.625116 -120.576594) (xy 243.621052 -120.587008) (xy 243.621052 -121.57075)
			(xy 245.81993 -121.57075) (xy 245.820355 -121.544434) (xy 245.827597 -121.492304) (xy 245.841924 -121.44166)
			(xy 245.863064 -121.393461) (xy 245.890618 -121.348618) (xy 245.924065 -121.307981) (xy 245.94312 -121.289826)
			(xy 245.950515 -121.282299) (xy 245.959043 -121.263023) (xy 245.95963 -121.252488) (xy 245.95963 -121.177812)
			(xy 245.959099 -121.167263) (xy 245.950564 -121.147968) (xy 245.94312 -121.140474) (xy 245.924063 -121.12232)
			(xy 245.890605 -121.081691) (xy 245.863046 -121.03685) (xy 245.841907 -120.988649) (xy 245.827591 -120.938001)
			(xy 245.820368 -120.885866) (xy 245.81993 -120.85955) (xy 245.820416 -120.832299) (xy 245.828172 -120.778351)
			(xy 245.843527 -120.726056) (xy 245.866169 -120.676479) (xy 245.895635 -120.630629) (xy 245.931326 -120.589438)
			(xy 245.972517 -120.553747) (xy 246.018367 -120.524281) (xy 246.067944 -120.501639) (xy 246.120239 -120.486284)
			(xy 246.174187 -120.478528) (xy 246.228689 -120.478528) (xy 246.282637 -120.486284) (xy 246.334932 -120.501639)
			(xy 246.384509 -120.524281) (xy 246.430359 -120.553747) (xy 246.47155 -120.589438) (xy 246.507241 -120.630629)
			(xy 246.536707 -120.676479) (xy 246.559349 -120.726056) (xy 246.574704 -120.778351) (xy 246.58246 -120.832299)
			(xy 246.582946 -120.85955) (xy 246.582529 -120.885866) (xy 246.575286 -120.937997) (xy 246.560959 -120.988642)
			(xy 246.539817 -121.036841) (xy 246.512261 -121.081683) (xy 246.478812 -121.12232) (xy 246.459756 -121.140474)
			(xy 246.452372 -121.148011) (xy 246.443836 -121.167279) (xy 246.443246 -121.177812) (xy 246.443246 -121.252488)
			(xy 246.443754 -121.26304) (xy 246.452303 -121.282337) (xy 246.459756 -121.289826) (xy 246.478828 -121.307965)
			(xy 246.512281 -121.348599) (xy 246.539837 -121.393444) (xy 246.560972 -121.441647) (xy 246.575286 -121.492297)
			(xy 246.582509 -121.544433) (xy 246.582946 -121.57075) (xy 246.58246 -121.598001) (xy 246.574704 -121.651949)
			(xy 246.559349 -121.704244) (xy 246.536707 -121.753821) (xy 246.507241 -121.799671) (xy 246.47155 -121.840862)
			(xy 246.430359 -121.876553) (xy 246.402673 -121.894346) (xy 269.509748 -121.894346) (xy 269.509748 -121.030746)
			(xy 269.510238 -121.000762) (xy 269.518066 -120.941306) (xy 269.533587 -120.883381) (xy 269.556536 -120.827977)
			(xy 269.58652 -120.776043) (xy 269.623026 -120.728467) (xy 269.665431 -120.686062) (xy 269.713007 -120.649556)
			(xy 269.764941 -120.619572) (xy 269.820345 -120.596623) (xy 269.87827 -120.581102) (xy 269.937726 -120.573274)
			(xy 269.997694 -120.573274) (xy 270.05715 -120.581102) (xy 270.115075 -120.596623) (xy 270.170479 -120.619572)
			(xy 270.222413 -120.649556) (xy 270.269989 -120.686062) (xy 270.312394 -120.728467) (xy 270.3489 -120.776043)
			(xy 270.378884 -120.827977) (xy 270.401833 -120.883381) (xy 270.417354 -120.941306) (xy 270.425182 -121.000762)
			(xy 270.425672 -121.030746) (xy 270.425672 -121.886472) (xy 283.9847 -121.886472) (xy 283.9847 -121.022872)
			(xy 283.98519 -120.992888) (xy 283.993018 -120.933432) (xy 284.008539 -120.875507) (xy 284.031488 -120.820103)
			(xy 284.061472 -120.768169) (xy 284.097978 -120.720593) (xy 284.140383 -120.678188) (xy 284.187959 -120.641682)
			(xy 284.239893 -120.611698) (xy 284.295297 -120.588749) (xy 284.353222 -120.573228) (xy 284.412678 -120.5654)
			(xy 284.472646 -120.5654) (xy 284.532102 -120.573228) (xy 284.590027 -120.588749) (xy 284.645431 -120.611698)
			(xy 284.697365 -120.641682) (xy 284.744941 -120.678188) (xy 284.787346 -120.720593) (xy 284.823852 -120.768169)
			(xy 284.853836 -120.820103) (xy 284.876785 -120.875507) (xy 284.892306 -120.933432) (xy 284.900134 -120.992888)
			(xy 284.900624 -121.022872) (xy 284.900624 -121.367296) (xy 296.945304 -121.367296) (xy 296.945304 -120.503696)
			(xy 296.945794 -120.473728) (xy 296.953617 -120.414306) (xy 296.96913 -120.356413) (xy 296.992066 -120.30104)
			(xy 297.022033 -120.249134) (xy 297.05852 -120.201584) (xy 297.1009 -120.159204) (xy 297.14845 -120.122717)
			(xy 297.200356 -120.09275) (xy 297.255729 -120.069814) (xy 297.313622 -120.054301) (xy 297.373044 -120.046478)
			(xy 297.43298 -120.046478) (xy 297.492402 -120.054301) (xy 297.550295 -120.069814) (xy 297.605668 -120.09275)
			(xy 297.657574 -120.122717) (xy 297.705124 -120.159204) (xy 297.747504 -120.201584) (xy 297.783991 -120.249134)
			(xy 297.813958 -120.30104) (xy 297.836894 -120.356413) (xy 297.852407 -120.414306) (xy 297.86023 -120.473728)
			(xy 297.86072 -120.503696) (xy 297.86072 -121.367296) (xy 297.86023 -121.397264) (xy 297.852407 -121.456686)
			(xy 297.836894 -121.514579) (xy 297.813958 -121.569952) (xy 297.783991 -121.621858) (xy 297.747504 -121.669408)
			(xy 297.705124 -121.711788) (xy 297.657574 -121.748275) (xy 297.605668 -121.778242) (xy 297.550295 -121.801178)
			(xy 297.492402 -121.816691) (xy 297.43298 -121.824514) (xy 297.373044 -121.824514) (xy 297.313622 -121.816691)
			(xy 297.255729 -121.801178) (xy 297.200356 -121.778242) (xy 297.14845 -121.748275) (xy 297.1009 -121.711788)
			(xy 297.05852 -121.669408) (xy 297.022033 -121.621858) (xy 296.992066 -121.569952) (xy 296.96913 -121.514579)
			(xy 296.953617 -121.456686) (xy 296.945794 -121.397264) (xy 296.945304 -121.367296) (xy 284.900624 -121.367296)
			(xy 284.900624 -121.886472) (xy 284.900134 -121.916456) (xy 284.892306 -121.975912) (xy 284.876785 -122.033837)
			(xy 284.853836 -122.089241) (xy 284.823852 -122.141175) (xy 284.787346 -122.188751) (xy 284.744941 -122.231156)
			(xy 284.697365 -122.267662) (xy 284.645431 -122.297646) (xy 284.590027 -122.320595) (xy 284.532102 -122.336116)
			(xy 284.472646 -122.343944) (xy 284.412678 -122.343944) (xy 284.353222 -122.336116) (xy 284.295297 -122.320595)
			(xy 284.239893 -122.297646) (xy 284.187959 -122.267662) (xy 284.140383 -122.231156) (xy 284.097978 -122.188751)
			(xy 284.061472 -122.141175) (xy 284.031488 -122.089241) (xy 284.008539 -122.033837) (xy 283.993018 -121.975912)
			(xy 283.98519 -121.916456) (xy 283.9847 -121.886472) (xy 270.425672 -121.886472) (xy 270.425672 -121.894346)
			(xy 270.425182 -121.92433) (xy 270.417354 -121.983786) (xy 270.401833 -122.041711) (xy 270.378884 -122.097115)
			(xy 270.3489 -122.149049) (xy 270.312394 -122.196625) (xy 270.269989 -122.23903) (xy 270.222413 -122.275536)
			(xy 270.170479 -122.30552) (xy 270.115075 -122.328469) (xy 270.05715 -122.34399) (xy 269.997694 -122.351818)
			(xy 269.937726 -122.351818) (xy 269.87827 -122.34399) (xy 269.820345 -122.328469) (xy 269.764941 -122.30552)
			(xy 269.713007 -122.275536) (xy 269.665431 -122.23903) (xy 269.623026 -122.196625) (xy 269.58652 -122.149049)
			(xy 269.556536 -122.097115) (xy 269.533587 -122.041711) (xy 269.518066 -121.983786) (xy 269.510238 -121.92433)
			(xy 269.509748 -121.894346) (xy 246.402673 -121.894346) (xy 246.384509 -121.906019) (xy 246.334932 -121.928661)
			(xy 246.282637 -121.944016) (xy 246.228689 -121.951772) (xy 246.174187 -121.951772) (xy 246.120239 -121.944016)
			(xy 246.067944 -121.928661) (xy 246.018367 -121.906019) (xy 245.972517 -121.876553) (xy 245.931326 -121.840862)
			(xy 245.895635 -121.799671) (xy 245.866169 -121.753821) (xy 245.843527 -121.704244) (xy 245.828172 -121.651949)
			(xy 245.820416 -121.598001) (xy 245.81993 -121.57075) (xy 243.621052 -121.57075) (xy 243.621052 -122.049794)
			(xy 243.621342 -122.057463) (xy 243.625986 -122.072081) (xy 243.630196 -122.078496) (xy 243.645182 -122.10034)
			(xy 243.649448 -122.106129) (xy 243.660533 -122.115283) (xy 243.667026 -122.118374) (xy 243.66728 -122.118374)
			(xy 243.692841 -122.12969) (xy 243.740619 -122.158704) (xy 243.783652 -122.194382) (xy 243.821016 -122.235958)
			(xy 243.851911 -122.282542) (xy 243.875677 -122.333137) (xy 243.891804 -122.386658) (xy 243.899947 -122.441961)
			(xy 243.900452 -122.46991) (xy 243.89993 -122.498753) (xy 243.89126 -122.555784) (xy 243.874103 -122.61086)
			(xy 243.848851 -122.662725) (xy 243.816079 -122.710198) (xy 243.776535 -122.752197) (xy 243.731118 -122.787764)
			(xy 243.680865 -122.816089) (xy 243.654072 -122.82678) (xy 243.653564 -122.82678) (xy 243.65331 -122.827034)
			(xy 243.64637 -122.83) (xy 243.634497 -122.839303) (xy 243.629942 -122.845322) (xy 243.625624 -122.851926)
			(xy 243.621052 -122.86615) (xy 243.621052 -123.249752) (xy 244.109967 -123.249752) (xy 244.109967 -123.195248)
			(xy 244.117724 -123.141299) (xy 244.13308 -123.089002) (xy 244.155722 -123.039423) (xy 244.185189 -122.993572)
			(xy 244.220882 -122.95238) (xy 244.262073 -122.916688) (xy 244.307925 -122.887221) (xy 244.357504 -122.864579)
			(xy 244.4098 -122.849224) (xy 244.46375 -122.841467) (xy 244.491002 -122.841004) (xy 244.518032 -122.841498)
			(xy 244.571549 -122.849136) (xy 244.623451 -122.864259) (xy 244.672695 -122.886564) (xy 244.718294 -122.915602)
			(xy 244.759332 -122.950791) (xy 244.777514 -122.970798) (xy 244.777768 -122.971052) (xy 244.785208 -122.978703)
			(xy 244.804695 -122.987369) (xy 244.81536 -122.987816) (xy 244.90299 -122.988324) (xy 244.922548 -122.979688)
			(xy 244.929914 -122.971306) (xy 244.948074 -122.951582) (xy 244.988975 -122.916918) (xy 245.034331 -122.88833)
			(xy 245.083246 -122.866381) (xy 245.134755 -122.851505) (xy 245.187841 -122.843997) (xy 245.214648 -122.843544)
			(xy 245.242018 -122.84403) (xy 245.296196 -122.851841) (xy 245.3487 -122.867325) (xy 245.398447 -122.890163)
			(xy 245.444414 -122.919884) (xy 245.465346 -122.937524) (xy 245.4656 -122.937778) (xy 245.472676 -122.94338)
			(xy 245.489601 -122.949615) (xy 245.49862 -122.94997) (xy 245.565676 -122.94997) (xy 245.574692 -122.949608)
			(xy 245.59161 -122.943364) (xy 245.598696 -122.937778) (xy 245.598696 -122.937524) (xy 245.59895 -122.937524)
			(xy 245.619883 -122.919883) (xy 245.665851 -122.890159) (xy 245.715597 -122.867313) (xy 245.768099 -122.851817)
			(xy 245.822277 -122.843988) (xy 245.877019 -122.843988) (xy 245.931197 -122.851817) (xy 245.983699 -122.867313)
			(xy 246.033445 -122.890159) (xy 246.079413 -122.919883) (xy 246.100346 -122.937524) (xy 246.1006 -122.937778)
			(xy 246.107676 -122.94338) (xy 246.124601 -122.949615) (xy 246.13362 -122.94997) (xy 246.200676 -122.94997)
			(xy 246.209692 -122.949608) (xy 246.22661 -122.943364) (xy 246.233696 -122.937778) (xy 246.234204 -122.937524)
			(xy 246.246938 -122.926579) (xy 246.274029 -122.906738) (xy 246.288306 -122.8979) (xy 246.297196 -122.892566)
			(xy 246.309388 -122.875548) (xy 246.329708 -122.78233) (xy 246.32539 -122.761756) (xy 246.319548 -122.75312)
			(xy 246.303548 -122.729056) (xy 246.278207 -122.677124) (xy 246.260982 -122.621966) (xy 246.252266 -122.564842)
			(xy 246.25173 -122.53595) (xy 246.252216 -122.508699) (xy 246.259972 -122.454751) (xy 246.275327 -122.402456)
			(xy 246.297969 -122.352879) (xy 246.327435 -122.307029) (xy 246.363126 -122.265838) (xy 246.404317 -122.230147)
			(xy 246.450167 -122.200681) (xy 246.499744 -122.178039) (xy 246.552039 -122.162684) (xy 246.605987 -122.154928)
			(xy 246.660489 -122.154928) (xy 246.714437 -122.162684) (xy 246.766732 -122.178039) (xy 246.816309 -122.200681)
			(xy 246.862159 -122.230147) (xy 246.90335 -122.265838) (xy 246.939041 -122.307029) (xy 246.968507 -122.352879)
			(xy 246.991149 -122.402456) (xy 247.006504 -122.454751) (xy 247.01426 -122.508699) (xy 247.014746 -122.53595)
			(xy 247.014198 -122.56404) (xy 247.005979 -122.619614) (xy 246.989696 -122.673381) (xy 246.965702 -122.724178)
			(xy 246.934515 -122.770905) (xy 246.896812 -122.812552) (xy 246.853407 -122.848217) (xy 246.82958 -122.863102)
			(xy 246.82069 -122.868436) (xy 246.808498 -122.885454) (xy 246.788178 -122.978672) (xy 246.792496 -122.999246)
			(xy 246.798338 -123.007882) (xy 246.814337 -123.031946) (xy 246.839679 -123.083878) (xy 246.856905 -123.139036)
			(xy 246.865621 -123.19616) (xy 246.866156 -123.225052) (xy 246.865577 -123.2523) (xy 246.857829 -123.306242)
			(xy 246.842482 -123.358532) (xy 246.81985 -123.408106) (xy 246.790393 -123.453954) (xy 246.754711 -123.495143)
			(xy 246.713531 -123.530836) (xy 246.66769 -123.560304) (xy 246.618122 -123.582948) (xy 246.565836 -123.598308)
			(xy 246.511896 -123.60607) (xy 246.484648 -123.60656) (xy 246.457278 -123.606076) (xy 246.4031 -123.598264)
			(xy 246.350596 -123.582779) (xy 246.300849 -123.559942) (xy 246.254882 -123.53022) (xy 246.23395 -123.51258)
			(xy 246.233696 -123.512326) (xy 246.226621 -123.506723) (xy 246.209695 -123.500488) (xy 246.200676 -123.500134)
			(xy 246.13362 -123.500134) (xy 246.124603 -123.500493) (xy 246.107686 -123.506739) (xy 246.1006 -123.512326)
			(xy 246.100346 -123.51258) (xy 246.079413 -123.530221) (xy 246.033445 -123.559945) (xy 245.983699 -123.582791)
			(xy 245.931197 -123.598287) (xy 245.877019 -123.606116) (xy 245.822277 -123.606116) (xy 245.768099 -123.598287)
			(xy 245.715597 -123.582791) (xy 245.665851 -123.559945) (xy 245.619883 -123.530221) (xy 245.59895 -123.51258)
			(xy 245.598696 -123.512326) (xy 245.591621 -123.506723) (xy 245.574695 -123.500488) (xy 245.565676 -123.500134)
			(xy 245.49862 -123.500134) (xy 245.489603 -123.500493) (xy 245.472686 -123.506739) (xy 245.4656 -123.512326)
			(xy 245.4656 -123.51258) (xy 245.465346 -123.51258) (xy 245.444405 -123.530208) (xy 245.398435 -123.559922)
			(xy 245.34869 -123.582761) (xy 245.296191 -123.598254) (xy 245.242017 -123.606085) (xy 245.214648 -123.60656)
			(xy 245.187618 -123.606078) (xy 245.134101 -123.598435) (xy 245.0822 -123.583308) (xy 245.032957 -123.561001)
			(xy 244.987358 -123.531961) (xy 244.946319 -123.496772) (xy 244.928136 -123.476766) (xy 244.927882 -123.476512)
			(xy 244.920414 -123.468893) (xy 244.900949 -123.460207) (xy 244.89029 -123.459748) (xy 244.80266 -123.45924)
			(xy 244.783102 -123.467876) (xy 244.775736 -123.476258) (xy 244.757564 -123.49597) (xy 244.716664 -123.530633)
			(xy 244.67131 -123.559221) (xy 244.622398 -123.581172) (xy 244.570891 -123.59605) (xy 244.517808 -123.603564)
			(xy 244.491002 -123.60402) (xy 244.46375 -123.603533) (xy 244.4098 -123.595776) (xy 244.357504 -123.580421)
			(xy 244.307925 -123.557779) (xy 244.262073 -123.528312) (xy 244.220882 -123.49262) (xy 244.185189 -123.451428)
			(xy 244.155722 -123.405577) (xy 244.13308 -123.355998) (xy 244.117724 -123.303701) (xy 244.109967 -123.249752)
			(xy 243.621052 -123.249752) (xy 243.621052 -123.68784) (xy 266.86764 -123.68784) (xy 266.86764 -122.82424)
			(xy 266.86813 -122.794256) (xy 266.875958 -122.7348) (xy 266.891479 -122.676875) (xy 266.914428 -122.621471)
			(xy 266.944412 -122.569537) (xy 266.980918 -122.521961) (xy 267.023323 -122.479556) (xy 267.070899 -122.44305)
			(xy 267.122833 -122.413066) (xy 267.178237 -122.390117) (xy 267.236162 -122.374596) (xy 267.295618 -122.366768)
			(xy 267.355586 -122.366768) (xy 267.415042 -122.374596) (xy 267.472967 -122.390117) (xy 267.528371 -122.413066)
			(xy 267.580305 -122.44305) (xy 267.627881 -122.479556) (xy 267.670286 -122.521961) (xy 267.706792 -122.569537)
			(xy 267.736776 -122.621471) (xy 267.759725 -122.676875) (xy 267.775246 -122.7348) (xy 267.783074 -122.794256)
			(xy 267.783564 -122.82424) (xy 267.783564 -123.686316) (xy 285.8389 -123.686316) (xy 285.8389 -122.822716)
			(xy 285.83939 -122.792732) (xy 285.847218 -122.733276) (xy 285.862739 -122.675351) (xy 285.885688 -122.619947)
			(xy 285.915672 -122.568013) (xy 285.952178 -122.520437) (xy 285.994583 -122.478032) (xy 286.042159 -122.441526)
			(xy 286.094093 -122.411542) (xy 286.149497 -122.388593) (xy 286.207422 -122.373072) (xy 286.266878 -122.365244)
			(xy 286.326846 -122.365244) (xy 286.386302 -122.373072) (xy 286.444227 -122.388593) (xy 286.499631 -122.411542)
			(xy 286.551565 -122.441526) (xy 286.599141 -122.478032) (xy 286.641546 -122.520437) (xy 286.678052 -122.568013)
			(xy 286.708036 -122.619947) (xy 286.730985 -122.675351) (xy 286.746506 -122.733276) (xy 286.754334 -122.792732)
			(xy 286.754824 -122.822716) (xy 286.754824 -123.16714) (xy 298.799504 -123.16714) (xy 298.799504 -122.30354)
			(xy 298.799994 -122.273572) (xy 298.807817 -122.21415) (xy 298.82333 -122.156257) (xy 298.846266 -122.100884)
			(xy 298.876233 -122.048978) (xy 298.91272 -122.001428) (xy 298.9551 -121.959048) (xy 299.00265 -121.922561)
			(xy 299.054556 -121.892594) (xy 299.109929 -121.869658) (xy 299.167822 -121.854145) (xy 299.227244 -121.846322)
			(xy 299.28718 -121.846322) (xy 299.346602 -121.854145) (xy 299.404495 -121.869658) (xy 299.459868 -121.892594)
			(xy 299.511774 -121.922561) (xy 299.559324 -121.959048) (xy 299.601704 -122.001428) (xy 299.638191 -122.048978)
			(xy 299.668158 -122.100884) (xy 299.691094 -122.156257) (xy 299.706607 -122.21415) (xy 299.71443 -122.273572)
			(xy 299.71492 -122.30354) (xy 299.71492 -123.16714) (xy 299.71443 -123.197108) (xy 299.706607 -123.25653)
			(xy 299.691094 -123.314423) (xy 299.668158 -123.369796) (xy 299.638191 -123.421702) (xy 299.601704 -123.469252)
			(xy 299.559324 -123.511632) (xy 299.511774 -123.548119) (xy 299.459868 -123.578086) (xy 299.404495 -123.601022)
			(xy 299.346602 -123.616535) (xy 299.28718 -123.624358) (xy 299.227244 -123.624358) (xy 299.167822 -123.616535)
			(xy 299.109929 -123.601022) (xy 299.054556 -123.578086) (xy 299.00265 -123.548119) (xy 298.9551 -123.511632)
			(xy 298.91272 -123.469252) (xy 298.876233 -123.421702) (xy 298.846266 -123.369796) (xy 298.82333 -123.314423)
			(xy 298.807817 -123.25653) (xy 298.799994 -123.197108) (xy 298.799504 -123.16714) (xy 286.754824 -123.16714)
			(xy 286.754824 -123.686316) (xy 286.754334 -123.7163) (xy 286.746506 -123.775756) (xy 286.730985 -123.833681)
			(xy 286.708036 -123.889085) (xy 286.678052 -123.941019) (xy 286.641546 -123.988595) (xy 286.599141 -124.031)
			(xy 286.551565 -124.067506) (xy 286.499631 -124.09749) (xy 286.444227 -124.120439) (xy 286.386302 -124.13596)
			(xy 286.326846 -124.143788) (xy 286.266878 -124.143788) (xy 286.207422 -124.13596) (xy 286.149497 -124.120439)
			(xy 286.094093 -124.09749) (xy 286.042159 -124.067506) (xy 285.994583 -124.031) (xy 285.952178 -123.988595)
			(xy 285.915672 -123.941019) (xy 285.885688 -123.889085) (xy 285.862739 -123.833681) (xy 285.847218 -123.775756)
			(xy 285.83939 -123.7163) (xy 285.8389 -123.686316) (xy 267.783564 -123.686316) (xy 267.783564 -123.68784)
			(xy 267.783074 -123.717824) (xy 267.775246 -123.77728) (xy 267.759725 -123.835205) (xy 267.736776 -123.890609)
			(xy 267.706792 -123.942543) (xy 267.670286 -123.990119) (xy 267.627881 -124.032524) (xy 267.580305 -124.06903)
			(xy 267.528371 -124.099014) (xy 267.472967 -124.121963) (xy 267.415042 -124.137484) (xy 267.355586 -124.145312)
			(xy 267.295618 -124.145312) (xy 267.236162 -124.137484) (xy 267.178237 -124.121963) (xy 267.122833 -124.099014)
			(xy 267.070899 -124.06903) (xy 267.023323 -124.032524) (xy 266.980918 -123.990119) (xy 266.944412 -123.942543)
			(xy 266.914428 -123.890609) (xy 266.891479 -123.835205) (xy 266.875958 -123.77728) (xy 266.86813 -123.717824)
			(xy 266.86764 -123.68784) (xy 243.621052 -123.68784) (xy 243.621052 -124.440188) (xy 243.621814 -124.448824)
			(xy 243.624354 -124.463302) (xy 243.626894 -124.469144) (xy 243.633498 -124.484384) (xy 243.63807 -124.489972)
			(xy 243.655167 -124.511427) (xy 243.683672 -124.558301) (xy 243.705164 -124.608777) (xy 243.719199 -124.661812)
			(xy 243.725487 -124.716311) (xy 243.723897 -124.771149) (xy 243.714464 -124.825192) (xy 243.706396 -124.851414)
			(xy 243.705126 -124.855224) (xy 243.704364 -124.859288) (xy 243.702078 -124.870718) (xy 243.707666 -124.893324)
			(xy 243.709952 -124.89815) (xy 243.721057 -124.923307) (xy 243.736745 -124.976013) (xy 243.74472 -125.030422)
			(xy 243.745258 -125.057916) (xy 243.745258 -125.078236) (xy 243.743988 -125.090174) (xy 243.741301 -125.116504)
			(xy 243.729577 -125.168115) (xy 243.710823 -125.217607) (xy 243.685401 -125.264027) (xy 243.653799 -125.306482)
			(xy 243.63553 -125.325632) (xy 243.628418 -125.332744) (xy 243.624608 -125.341888) (xy 243.622902 -125.346461)
			(xy 243.62112 -125.356057) (xy 243.621052 -125.360938) (xy 243.621052 -125.403356) (xy 247.744234 -125.403356)
			(xy 247.744725 -125.375987) (xy 247.752535 -125.321808) (xy 247.768018 -125.269305) (xy 247.790855 -125.219558)
			(xy 247.820575 -125.17359) (xy 247.838214 -125.152658) (xy 247.838468 -125.152404) (xy 247.844067 -125.145326)
			(xy 247.850304 -125.128402) (xy 247.85066 -125.119384) (xy 247.85066 -125.052328) (xy 247.850298 -125.043311)
			(xy 247.844055 -125.026394) (xy 247.838468 -125.019308) (xy 247.838214 -125.019308) (xy 247.838214 -125.019054)
			(xy 247.820589 -124.998111) (xy 247.790875 -124.952141) (xy 247.768036 -124.902397) (xy 247.752541 -124.849898)
			(xy 247.74471 -124.795724) (xy 247.744234 -124.768356) (xy 247.74472 -124.741105) (xy 247.752476 -124.687157)
			(xy 247.767831 -124.634862) (xy 247.790473 -124.585285) (xy 247.819939 -124.539435) (xy 247.85563 -124.498244)
			(xy 247.896821 -124.462553) (xy 247.942671 -124.433087) (xy 247.992248 -124.410445) (xy 248.044543 -124.39509)
			(xy 248.098491 -124.387334) (xy 248.152993 -124.387334) (xy 248.206941 -124.39509) (xy 248.259236 -124.410445)
			(xy 248.308813 -124.433087) (xy 248.354663 -124.462553) (xy 248.395854 -124.498244) (xy 248.431545 -124.539435)
			(xy 248.461011 -124.585285) (xy 248.483653 -124.634862) (xy 248.499008 -124.687157) (xy 248.506764 -124.741105)
			(xy 248.50725 -124.768356) (xy 248.50677 -124.795726) (xy 248.498958 -124.849905) (xy 248.483472 -124.902408)
			(xy 248.460633 -124.952155) (xy 248.430911 -124.998122) (xy 248.41327 -125.019054) (xy 248.413016 -125.019308)
			(xy 248.407422 -125.026389) (xy 248.401179 -125.04331) (xy 248.400824 -125.052328) (xy 248.400824 -125.119384)
			(xy 248.401184 -125.128401) (xy 248.407429 -125.145318) (xy 248.413016 -125.152404) (xy 248.41327 -125.152404)
			(xy 248.41327 -125.152658) (xy 248.430898 -125.173599) (xy 248.460613 -125.219569) (xy 248.483451 -125.269314)
			(xy 248.498945 -125.321813) (xy 248.506775 -125.375987) (xy 248.50725 -125.403356) (xy 248.506764 -125.430607)
			(xy 248.499008 -125.484555) (xy 248.483653 -125.53685) (xy 248.461011 -125.586427) (xy 248.431545 -125.632277)
			(xy 248.395854 -125.673468) (xy 248.354663 -125.709159) (xy 248.308813 -125.738625) (xy 248.259236 -125.761267)
			(xy 248.206941 -125.776622) (xy 248.152993 -125.784378) (xy 248.098491 -125.784378) (xy 248.044543 -125.776622)
			(xy 247.992248 -125.761267) (xy 247.942671 -125.738625) (xy 247.896821 -125.709159) (xy 247.85563 -125.673468)
			(xy 247.819939 -125.632277) (xy 247.790473 -125.586427) (xy 247.767831 -125.53685) (xy 247.752476 -125.484555)
			(xy 247.74472 -125.430607) (xy 247.744234 -125.403356) (xy 243.621052 -125.403356) (xy 243.621052 -125.430026)
			(xy 243.621814 -125.438408) (xy 243.62333 -125.446012) (xy 243.63032 -125.459843) (xy 243.63553 -125.465586)
			(xy 243.64061 -125.470666) (xy 243.706142 -125.519942) (xy 243.715775 -125.526545) (xy 243.738667 -125.53104)
			(xy 243.750084 -125.528578) (xy 243.757196 -125.526546) (xy 243.781559 -125.520375) (xy 243.83138 -125.513751)
			(xy 243.85651 -125.513338) (xy 243.883761 -125.513802) (xy 243.937709 -125.52156) (xy 243.990003 -125.536918)
			(xy 244.039579 -125.559561) (xy 244.085427 -125.58903) (xy 244.126615 -125.624725) (xy 244.162303 -125.665918)
			(xy 244.191765 -125.711771) (xy 244.214402 -125.76135) (xy 244.229751 -125.813646) (xy 244.235505 -125.853698)
			(xy 248.684796 -125.853698) (xy 248.685262 -125.826328) (xy 248.69308 -125.772149) (xy 248.708569 -125.719646)
			(xy 248.731411 -125.669899) (xy 248.761135 -125.623932) (xy 248.778776 -125.603) (xy 248.77903 -125.602746)
			(xy 248.784607 -125.595653) (xy 248.790858 -125.578741) (xy 248.791222 -125.569726) (xy 248.791222 -125.50267)
			(xy 248.790875 -125.493652) (xy 248.78462 -125.476736) (xy 248.77903 -125.46965) (xy 248.778776 -125.46965)
			(xy 248.778776 -125.469396) (xy 248.761118 -125.448479) (xy 248.73141 -125.402502) (xy 248.708578 -125.35275)
			(xy 248.693091 -125.300247) (xy 248.685268 -125.246068) (xy 248.684796 -125.218698) (xy 248.685282 -125.191447)
			(xy 248.693038 -125.137499) (xy 248.708393 -125.085204) (xy 248.731035 -125.035627) (xy 248.760501 -124.989777)
			(xy 248.796192 -124.948586) (xy 248.837383 -124.912895) (xy 248.883233 -124.883429) (xy 248.93281 -124.860787)
			(xy 248.985105 -124.845432) (xy 249.039053 -124.837676) (xy 249.093555 -124.837676) (xy 249.147503 -124.845432)
			(xy 249.199798 -124.860787) (xy 249.249375 -124.883429) (xy 249.295225 -124.912895) (xy 249.336416 -124.948586)
			(xy 249.372107 -124.989777) (xy 249.401573 -125.035627) (xy 249.424215 -125.085204) (xy 249.43957 -125.137499)
			(xy 249.447326 -125.191447) (xy 249.447812 -125.218698) (xy 249.447342 -125.246068) (xy 249.439525 -125.300247)
			(xy 249.424036 -125.35275) (xy 249.401196 -125.402497) (xy 249.371472 -125.448464) (xy 249.353832 -125.469396)
			(xy 249.353578 -125.46965) (xy 249.348004 -125.476745) (xy 249.34175 -125.493655) (xy 249.341386 -125.50267)
			(xy 249.341386 -125.569726) (xy 249.341734 -125.578744) (xy 249.347988 -125.59566) (xy 249.353578 -125.602746)
			(xy 249.353832 -125.602746) (xy 249.353832 -125.603) (xy 249.37149 -125.623917) (xy 249.401198 -125.669895)
			(xy 249.424029 -125.719646) (xy 249.439516 -125.77215) (xy 249.44734 -125.826328) (xy 249.447812 -125.853698)
			(xy 249.447326 -125.880949) (xy 249.43957 -125.934897) (xy 249.424215 -125.987192) (xy 249.401573 -126.036769)
			(xy 249.372107 -126.082619) (xy 249.336416 -126.12381) (xy 249.295225 -126.159501) (xy 249.249375 -126.188967)
			(xy 249.199798 -126.211609) (xy 249.147503 -126.226964) (xy 249.093555 -126.23472) (xy 249.039053 -126.23472)
			(xy 248.985105 -126.226964) (xy 248.93281 -126.211609) (xy 248.883233 -126.188967) (xy 248.837383 -126.159501)
			(xy 248.796192 -126.12381) (xy 248.760501 -126.082619) (xy 248.731035 -126.036769) (xy 248.708393 -125.987192)
			(xy 248.693038 -125.934897) (xy 248.685282 -125.880949) (xy 248.684796 -125.853698) (xy 244.235505 -125.853698)
			(xy 244.237502 -125.867595) (xy 244.238018 -125.894846) (xy 244.237447 -125.925044) (xy 244.227938 -125.984685)
			(xy 244.209149 -126.042083) (xy 244.181548 -126.095803) (xy 244.145827 -126.144502) (xy 244.124734 -126.166118)
			(xy 244.119682 -126.171403) (xy 244.112595 -126.184185) (xy 244.110764 -126.191264) (xy 244.103984 -126.21904)
			(xy 244.08324 -126.272317) (xy 244.054787 -126.321907) (xy 244.019259 -126.366702) (xy 243.977451 -126.4057)
			(xy 243.930297 -126.43803) (xy 243.87885 -126.46297) (xy 243.82426 -126.479962) (xy 243.767747 -126.488627)
			(xy 243.739162 -126.489206) (xy 243.738654 -126.489206) (xy 243.737892 -126.489206) (xy 243.737638 -126.489206)
			(xy 243.735352 -126.488952) (xy 243.7257 -126.488952) (xy 243.712108 -126.488968) (xy 243.685695 -126.495332)
			(xy 243.661896 -126.50844) (xy 243.642398 -126.527361) (xy 243.640631 -126.530354) (xy 249.893328 -126.530354)
			(xy 249.893869 -126.50269) (xy 249.901862 -126.447941) (xy 249.917672 -126.39492) (xy 249.94097 -126.344735)
			(xy 249.971267 -126.298439) (xy 250.007929 -126.257001) (xy 250.050188 -126.221287) (xy 250.073414 -126.20625)
			(xy 250.083065 -126.199582) (xy 250.095524 -126.179744) (xy 250.09729 -126.16815) (xy 250.105164 -126.08814)
			(xy 250.105759 -126.076503) (xy 250.097704 -126.054668) (xy 250.08967 -126.04623) (xy 250.089416 -126.045976)
			(xy 250.070844 -126.027886) (xy 250.038264 -125.987556) (xy 250.011449 -125.943184) (xy 249.990895 -125.895587)
			(xy 249.97698 -125.845644) (xy 249.969961 -125.794277) (xy 249.969528 -125.768354) (xy 249.969935 -125.7411)
			(xy 249.977699 -125.687148) (xy 249.993062 -125.634849) (xy 250.015711 -125.585269) (xy 250.045185 -125.539417)
			(xy 250.080885 -125.498227) (xy 250.122083 -125.462536) (xy 250.167941 -125.433071) (xy 250.217526 -125.410433)
			(xy 250.269828 -125.395081) (xy 250.323782 -125.387329) (xy 250.351036 -125.386846) (xy 250.378408 -125.38728)
			(xy 250.432588 -125.395104) (xy 250.485092 -125.4106) (xy 250.534839 -125.433449) (xy 250.580804 -125.463181)
			(xy 250.601734 -125.480826) (xy 250.601988 -125.48108) (xy 250.609067 -125.486677) (xy 250.62599 -125.492915)
			(xy 250.635008 -125.493272) (xy 250.702064 -125.493272) (xy 250.71108 -125.492904) (xy 250.727997 -125.486665)
			(xy 250.735084 -125.48108) (xy 250.735084 -125.480826) (xy 250.735338 -125.480826) (xy 250.756286 -125.463207)
			(xy 250.802254 -125.433491) (xy 250.851997 -125.410651) (xy 250.904495 -125.395155) (xy 250.958668 -125.387322)
			(xy 250.986036 -125.386846) (xy 251.013286 -125.387344) (xy 251.067231 -125.395104) (xy 251.119523 -125.410462)
			(xy 251.169097 -125.433104) (xy 251.214945 -125.462569) (xy 251.256134 -125.498259) (xy 251.291824 -125.539447)
			(xy 251.321291 -125.585294) (xy 251.343935 -125.634868) (xy 251.359293 -125.687159) (xy 251.367055 -125.741104)
			(xy 251.367544 -125.768354) (xy 251.367014 -125.797271) (xy 251.35829 -125.854442) (xy 251.341036 -125.909642)
			(xy 251.315647 -125.961604) (xy 251.282704 -126.009138) (xy 251.242964 -126.051155) (xy 251.220478 -126.069344)
			(xy 251.211657 -126.076938) (xy 251.201482 -126.097849) (xy 251.20092 -126.109476) (xy 251.20092 -126.189232)
			(xy 251.201448 -126.200865) (xy 251.211644 -126.221775) (xy 251.220478 -126.229364) (xy 251.24294 -126.247581)
			(xy 251.282677 -126.289595) (xy 251.315619 -126.337124) (xy 251.341012 -126.38908) (xy 251.358273 -126.444273)
			(xy 251.367006 -126.501439) (xy 251.367544 -126.530354) (xy 251.367002 -126.557604) (xy 251.359252 -126.61155)
			(xy 251.347151 -126.652782) (xy 251.638816 -126.652782) (xy 251.639268 -126.625411) (xy 251.647088 -126.571231)
			(xy 251.662581 -126.518728) (xy 251.685426 -126.468981) (xy 251.715153 -126.423015) (xy 251.732796 -126.402084)
			(xy 251.73305 -126.40183) (xy 251.738636 -126.394743) (xy 251.744882 -126.377826) (xy 251.745242 -126.36881)
			(xy 251.745242 -126.301754) (xy 251.744872 -126.292738) (xy 251.738635 -126.27582) (xy 251.73305 -126.268734)
			(xy 251.732796 -126.268734) (xy 251.732796 -126.26848) (xy 251.715139 -126.247561) (xy 251.685417 -126.20159)
			(xy 251.662575 -126.151841) (xy 251.647081 -126.099337) (xy 251.639255 -126.045158) (xy 251.639257 -125.990415)
			(xy 251.647087 -125.936236) (xy 251.662584 -125.883733) (xy 251.68543 -125.833986) (xy 251.715155 -125.788017)
			(xy 251.732796 -125.767084) (xy 251.73305 -125.76683) (xy 251.738636 -125.759743) (xy 251.744882 -125.742826)
			(xy 251.745242 -125.73381) (xy 251.745242 -125.666754) (xy 251.744872 -125.657738) (xy 251.738635 -125.64082)
			(xy 251.73305 -125.633734) (xy 251.732796 -125.633734) (xy 251.732796 -125.63348) (xy 251.715139 -125.612561)
			(xy 251.685417 -125.56659) (xy 251.662575 -125.516841) (xy 251.647081 -125.464337) (xy 251.639255 -125.410158)
			(xy 251.639257 -125.355415) (xy 251.647087 -125.301236) (xy 251.662584 -125.248733) (xy 251.68543 -125.198986)
			(xy 251.715155 -125.153017) (xy 251.732796 -125.132084) (xy 251.73305 -125.13183) (xy 251.738636 -125.124743)
			(xy 251.744882 -125.107826) (xy 251.745242 -125.09881) (xy 251.745242 -125.031754) (xy 251.744872 -125.022738)
			(xy 251.738635 -125.00582) (xy 251.73305 -124.998734) (xy 251.732796 -124.998734) (xy 251.732796 -124.99848)
			(xy 251.71518 -124.977529) (xy 251.685465 -124.931561) (xy 251.662625 -124.881819) (xy 251.647128 -124.829322)
			(xy 251.639294 -124.77515) (xy 251.638816 -124.747782) (xy 251.639302 -124.720531) (xy 251.647058 -124.666583)
			(xy 251.662413 -124.614288) (xy 251.685055 -124.564711) (xy 251.714521 -124.518861) (xy 251.750212 -124.47767)
			(xy 251.791403 -124.441979) (xy 251.837253 -124.412513) (xy 251.88683 -124.389871) (xy 251.939125 -124.374516)
			(xy 251.993073 -124.36676) (xy 252.047575 -124.36676) (xy 252.101523 -124.374516) (xy 252.153818 -124.389871)
			(xy 252.203395 -124.412513) (xy 252.249245 -124.441979) (xy 252.290436 -124.47767) (xy 252.326127 -124.518861)
			(xy 252.355593 -124.564711) (xy 252.378235 -124.614288) (xy 252.39359 -124.666583) (xy 252.401346 -124.720531)
			(xy 252.401832 -124.747782) (xy 252.401372 -124.775153) (xy 252.393555 -124.829333) (xy 252.378066 -124.881836)
			(xy 252.355222 -124.931583) (xy 252.325495 -124.977549) (xy 252.307852 -124.99848) (xy 252.307598 -124.998734)
			(xy 252.302033 -125.005835) (xy 252.295773 -125.022741) (xy 252.295406 -125.031754) (xy 252.295406 -125.09881)
			(xy 252.295757 -125.107828) (xy 252.302009 -125.124744) (xy 252.307598 -125.13183) (xy 252.307852 -125.13183)
			(xy 252.307852 -125.132084) (xy 252.325476 -125.153031) (xy 252.355203 -125.198995) (xy 252.378051 -125.248739)
			(xy 252.393549 -125.301239) (xy 252.40138 -125.355416) (xy 252.401382 -125.410156) (xy 252.393555 -125.464334)
			(xy 252.384639 -125.494542) (xy 269.509748 -125.494542) (xy 269.509748 -124.630942) (xy 269.510238 -124.600958)
			(xy 269.518066 -124.541502) (xy 269.533587 -124.483577) (xy 269.556536 -124.428173) (xy 269.58652 -124.376239)
			(xy 269.623026 -124.328663) (xy 269.665431 -124.286258) (xy 269.713007 -124.249752) (xy 269.764941 -124.219768)
			(xy 269.820345 -124.196819) (xy 269.87827 -124.181298) (xy 269.937726 -124.17347) (xy 269.997694 -124.17347)
			(xy 270.05715 -124.181298) (xy 270.115075 -124.196819) (xy 270.170479 -124.219768) (xy 270.222413 -124.249752)
			(xy 270.269989 -124.286258) (xy 270.312394 -124.328663) (xy 270.3489 -124.376239) (xy 270.378884 -124.428173)
			(xy 270.401833 -124.483577) (xy 270.417354 -124.541502) (xy 270.425182 -124.600958) (xy 270.425672 -124.630942)
			(xy 270.425672 -125.486414) (xy 283.9847 -125.486414) (xy 283.9847 -124.622814) (xy 283.98519 -124.59283)
			(xy 283.993018 -124.533374) (xy 284.008539 -124.475449) (xy 284.031488 -124.420045) (xy 284.061472 -124.368111)
			(xy 284.097978 -124.320535) (xy 284.140383 -124.27813) (xy 284.187959 -124.241624) (xy 284.239893 -124.21164)
			(xy 284.295297 -124.188691) (xy 284.353222 -124.17317) (xy 284.412678 -124.165342) (xy 284.472646 -124.165342)
			(xy 284.532102 -124.17317) (xy 284.590027 -124.188691) (xy 284.645431 -124.21164) (xy 284.697365 -124.241624)
			(xy 284.744941 -124.27813) (xy 284.787346 -124.320535) (xy 284.823852 -124.368111) (xy 284.853836 -124.420045)
			(xy 284.876785 -124.475449) (xy 284.892306 -124.533374) (xy 284.900134 -124.59283) (xy 284.900624 -124.622814)
			(xy 284.900624 -124.967238) (xy 296.945304 -124.967238) (xy 296.945304 -124.103638) (xy 296.945794 -124.07367)
			(xy 296.953617 -124.014248) (xy 296.96913 -123.956355) (xy 296.992066 -123.900982) (xy 297.022033 -123.849076)
			(xy 297.05852 -123.801526) (xy 297.1009 -123.759146) (xy 297.14845 -123.722659) (xy 297.200356 -123.692692)
			(xy 297.255729 -123.669756) (xy 297.313622 -123.654243) (xy 297.373044 -123.64642) (xy 297.43298 -123.64642)
			(xy 297.492402 -123.654243) (xy 297.550295 -123.669756) (xy 297.605668 -123.692692) (xy 297.657574 -123.722659)
			(xy 297.705124 -123.759146) (xy 297.747504 -123.801526) (xy 297.783991 -123.849076) (xy 297.813958 -123.900982)
			(xy 297.836894 -123.956355) (xy 297.852407 -124.014248) (xy 297.86023 -124.07367) (xy 297.86072 -124.103638)
			(xy 297.86072 -124.967238) (xy 297.86023 -124.997206) (xy 297.852407 -125.056628) (xy 297.836894 -125.114521)
			(xy 297.813958 -125.169894) (xy 297.783991 -125.2218) (xy 297.747504 -125.26935) (xy 297.705124 -125.31173)
			(xy 297.657574 -125.348217) (xy 297.605668 -125.378184) (xy 297.550295 -125.40112) (xy 297.492402 -125.416633)
			(xy 297.43298 -125.424456) (xy 297.373044 -125.424456) (xy 297.313622 -125.416633) (xy 297.255729 -125.40112)
			(xy 297.200356 -125.378184) (xy 297.14845 -125.348217) (xy 297.1009 -125.31173) (xy 297.05852 -125.26935)
			(xy 297.022033 -125.2218) (xy 296.992066 -125.169894) (xy 296.96913 -125.114521) (xy 296.953617 -125.056628)
			(xy 296.945794 -124.997206) (xy 296.945304 -124.967238) (xy 284.900624 -124.967238) (xy 284.900624 -125.486414)
			(xy 284.900134 -125.516398) (xy 284.892306 -125.575854) (xy 284.876785 -125.633779) (xy 284.853836 -125.689183)
			(xy 284.823852 -125.741117) (xy 284.787346 -125.788693) (xy 284.744941 -125.831098) (xy 284.697365 -125.867604)
			(xy 284.645431 -125.897588) (xy 284.590027 -125.920537) (xy 284.532102 -125.936058) (xy 284.472646 -125.943886)
			(xy 284.412678 -125.943886) (xy 284.353222 -125.936058) (xy 284.295297 -125.920537) (xy 284.239893 -125.897588)
			(xy 284.187959 -125.867604) (xy 284.140383 -125.831098) (xy 284.097978 -125.788693) (xy 284.061472 -125.741117)
			(xy 284.031488 -125.689183) (xy 284.008539 -125.633779) (xy 283.993018 -125.575854) (xy 283.98519 -125.516398)
			(xy 283.9847 -125.486414) (xy 270.425672 -125.486414) (xy 270.425672 -125.494542) (xy 270.425182 -125.524526)
			(xy 270.417354 -125.583982) (xy 270.401833 -125.641907) (xy 270.378884 -125.697311) (xy 270.3489 -125.749245)
			(xy 270.312394 -125.796821) (xy 270.269989 -125.839226) (xy 270.222413 -125.875732) (xy 270.170479 -125.905716)
			(xy 270.115075 -125.928665) (xy 270.05715 -125.944186) (xy 269.997694 -125.952014) (xy 269.937726 -125.952014)
			(xy 269.87827 -125.944186) (xy 269.820345 -125.928665) (xy 269.764941 -125.905716) (xy 269.713007 -125.875732)
			(xy 269.665431 -125.839226) (xy 269.623026 -125.796821) (xy 269.58652 -125.749245) (xy 269.556536 -125.697311)
			(xy 269.533587 -125.641907) (xy 269.518066 -125.583982) (xy 269.510238 -125.524526) (xy 269.509748 -125.494542)
			(xy 252.384639 -125.494542) (xy 252.37806 -125.516835) (xy 252.355216 -125.566581) (xy 252.325492 -125.612548)
			(xy 252.307852 -125.63348) (xy 252.307598 -125.633734) (xy 252.302033 -125.640835) (xy 252.295773 -125.657741)
			(xy 252.295406 -125.666754) (xy 252.295406 -125.73381) (xy 252.295757 -125.742828) (xy 252.302009 -125.759744)
			(xy 252.307598 -125.76683) (xy 252.307852 -125.76683) (xy 252.307852 -125.767084) (xy 252.325476 -125.788031)
			(xy 252.355203 -125.833995) (xy 252.378051 -125.883739) (xy 252.393549 -125.936239) (xy 252.40138 -125.990416)
			(xy 252.401382 -126.045156) (xy 252.393555 -126.099334) (xy 252.37806 -126.151835) (xy 252.355216 -126.201581)
			(xy 252.325492 -126.247548) (xy 252.307852 -126.26848) (xy 252.307598 -126.268734) (xy 252.302033 -126.275835)
			(xy 252.295773 -126.292741) (xy 252.295406 -126.301754) (xy 252.295406 -126.36881) (xy 252.295757 -126.377828)
			(xy 252.302009 -126.394744) (xy 252.307598 -126.40183) (xy 252.307852 -126.40183) (xy 252.307852 -126.402084)
			(xy 252.32549 -126.423017) (xy 252.355203 -126.468989) (xy 252.37804 -126.518736) (xy 252.393532 -126.571237)
			(xy 252.401359 -126.625413) (xy 252.401832 -126.652782) (xy 252.401346 -126.680033) (xy 252.39359 -126.733981)
			(xy 252.378235 -126.786276) (xy 252.355593 -126.835853) (xy 252.326127 -126.881703) (xy 252.290436 -126.922894)
			(xy 252.249245 -126.958585) (xy 252.203395 -126.988051) (xy 252.153818 -127.010693) (xy 252.101523 -127.026048)
			(xy 252.047575 -127.033804) (xy 251.993073 -127.033804) (xy 251.939125 -127.026048) (xy 251.88683 -127.010693)
			(xy 251.837253 -126.988051) (xy 251.791403 -126.958585) (xy 251.750212 -126.922894) (xy 251.714521 -126.881703)
			(xy 251.685055 -126.835853) (xy 251.662413 -126.786276) (xy 251.647058 -126.733981) (xy 251.639302 -126.680033)
			(xy 251.638816 -126.652782) (xy 251.347151 -126.652782) (xy 251.343904 -126.663845) (xy 251.321269 -126.713422)
			(xy 251.291809 -126.759274) (xy 251.256124 -126.800466) (xy 251.214939 -126.83616) (xy 251.169094 -126.86563)
			(xy 251.119521 -126.888275) (xy 251.067231 -126.903635) (xy 251.013286 -126.911396) (xy 250.986036 -126.911862)
			(xy 250.95972 -126.911449) (xy 250.907589 -126.904205) (xy 250.856944 -126.889876) (xy 250.808745 -126.868733)
			(xy 250.763903 -126.841177) (xy 250.723267 -126.807728) (xy 250.705112 -126.788672) (xy 250.697578 -126.781284)
			(xy 250.678308 -126.772749) (xy 250.667774 -126.772162) (xy 250.593098 -126.772162) (xy 250.582548 -126.772688)
			(xy 250.563254 -126.781227) (xy 250.55576 -126.788672) (xy 250.537611 -126.807735) (xy 250.496981 -126.841192)
			(xy 250.452139 -126.868751) (xy 250.403937 -126.889888) (xy 250.353288 -126.904204) (xy 250.301153 -126.911425)
			(xy 250.274836 -126.911862) (xy 250.247582 -126.911411) (xy 250.193628 -126.903658) (xy 250.141327 -126.888304)
			(xy 250.091744 -126.865662) (xy 250.045889 -126.836194) (xy 250.004694 -126.800499) (xy 249.969 -126.759303)
			(xy 249.939533 -126.713447) (xy 249.916892 -126.663863) (xy 249.90154 -126.611562) (xy 249.893788 -126.557608)
			(xy 249.893328 -126.530354) (xy 243.640631 -126.530354) (xy 243.628583 -126.550756) (xy 243.621428 -126.576967)
			(xy 243.621052 -126.590552) (xy 243.621052 -126.783338) (xy 243.621088 -126.787473) (xy 243.622371 -126.795643)
			(xy 243.623592 -126.799594) (xy 243.631212 -126.821946) (xy 243.63553 -126.828042) (xy 243.650676 -126.849805)
			(xy 243.675454 -126.896682) (xy 243.693501 -126.946538) (xy 243.70447 -126.998412) (xy 243.708149 -127.051306)
			(xy 243.704468 -127.1042) (xy 243.693497 -127.156075) (xy 243.675448 -127.20593) (xy 243.650669 -127.252806)
			(xy 243.63553 -127.274574) (xy 243.631212 -127.28067) (xy 243.623592 -127.303022) (xy 243.622395 -127.306978)
			(xy 243.621121 -127.315145) (xy 243.621052 -127.319278) (xy 243.621052 -127.803402) (xy 243.621354 -127.81207)
			(xy 243.627069 -127.828434) (xy 243.632228 -127.835406) (xy 243.637562 -127.84201) (xy 243.652294 -127.851154)
			(xy 243.66093 -127.852932) (xy 243.687423 -127.859224) (xy 243.73842 -127.878306) (xy 243.786185 -127.904445)
			(xy 243.829749 -127.937111) (xy 243.868225 -127.975639) (xy 243.900832 -128.019247) (xy 243.926907 -128.067047)
			(xy 243.945921 -128.11807) (xy 243.957487 -128.171278) (xy 243.961369 -128.225589) (xy 243.95749 -128.279901)
			(xy 243.945927 -128.33311) (xy 243.926916 -128.384133) (xy 243.900844 -128.431935) (xy 243.868239 -128.475545)
			(xy 243.829765 -128.514075) (xy 243.786203 -128.546743) (xy 243.738439 -128.572885) (xy 243.695315 -128.589024)
			(xy 285.77997 -128.589024) (xy 285.784041 -128.533402) (xy 285.796167 -128.478965) (xy 285.81609 -128.426874)
			(xy 285.843386 -128.378239) (xy 285.877472 -128.334096) (xy 285.917621 -128.295387) (xy 285.962979 -128.262936)
			(xy 286.012579 -128.237435) (xy 286.065363 -128.219428) (xy 286.120206 -128.209298) (xy 286.17594 -128.207261)
			(xy 286.231377 -128.213361) (xy 286.285334 -128.227467) (xy 286.336663 -128.249279) (xy 286.384269 -128.278333)
			(xy 286.427137 -128.314008) (xy 286.464354 -128.355545) (xy 286.495127 -128.402058) (xy 286.518799 -128.452555)
			(xy 286.534867 -128.505962) (xy 286.542987 -128.561138) (xy 286.543496 -128.589024) (xy 286.542987 -128.61691)
			(xy 286.534867 -128.672086) (xy 286.518799 -128.725493) (xy 286.495127 -128.77599) (xy 286.464354 -128.822503)
			(xy 286.427137 -128.86404) (xy 286.384269 -128.899715) (xy 286.336663 -128.928769) (xy 286.285334 -128.950581)
			(xy 286.231377 -128.964687) (xy 286.17594 -128.970787) (xy 286.120206 -128.96875) (xy 286.065363 -128.95862)
			(xy 286.012579 -128.940613) (xy 285.962979 -128.915112) (xy 285.917621 -128.882661) (xy 285.877472 -128.843952)
			(xy 285.843386 -128.799809) (xy 285.81609 -128.751174) (xy 285.796167 -128.699083) (xy 285.784041 -128.644646)
			(xy 285.77997 -128.589024) (xy 243.695315 -128.589024) (xy 243.687443 -128.59197) (xy 243.66093 -128.598168)
			(xy 243.652575 -128.600356) (xy 243.637893 -128.60943) (xy 243.632228 -128.615948) (xy 243.626894 -128.622552)
			(xy 243.621052 -128.638808) (xy 243.621052 -131.001516) (xy 243.621429 -131.009875) (xy 243.626864 -131.02569)
			(xy 243.63172 -131.032504) (xy 243.642134 -131.045966) (xy 243.652294 -131.048506) (xy 243.660168 -131.050538)
			(xy 243.687086 -131.058021) (xy 243.738544 -131.079779) (xy 243.786279 -131.108808) (xy 243.82927 -131.144487)
			(xy 243.8666 -131.186055) (xy 243.897469 -131.232621) (xy 243.921218 -131.283191) (xy 243.925661 -131.297934)
			(xy 266.86764 -131.297934) (xy 266.86764 -130.434334) (xy 266.86813 -130.40435) (xy 266.875958 -130.344894)
			(xy 266.891479 -130.286969) (xy 266.914428 -130.231565) (xy 266.944412 -130.179631) (xy 266.980918 -130.132055)
			(xy 267.023323 -130.08965) (xy 267.070899 -130.053144) (xy 267.122833 -130.02316) (xy 267.178237 -130.000211)
			(xy 267.236162 -129.98469) (xy 267.295618 -129.976862) (xy 267.355586 -129.976862) (xy 267.415042 -129.98469)
			(xy 267.472967 -130.000211) (xy 267.528371 -130.02316) (xy 267.580305 -130.053144) (xy 267.627881 -130.08965)
			(xy 267.670286 -130.132055) (xy 267.706792 -130.179631) (xy 267.736776 -130.231565) (xy 267.759725 -130.286969)
			(xy 267.775246 -130.344894) (xy 267.783074 -130.40435) (xy 267.783564 -130.434334) (xy 267.783564 -131.29641)
			(xy 285.8389 -131.29641) (xy 285.8389 -130.43281) (xy 285.83939 -130.402826) (xy 285.847218 -130.34337)
			(xy 285.862739 -130.285445) (xy 285.885688 -130.230041) (xy 285.915672 -130.178107) (xy 285.952178 -130.130531)
			(xy 285.994583 -130.088126) (xy 286.042159 -130.05162) (xy 286.094093 -130.021636) (xy 286.149497 -129.998687)
			(xy 286.207422 -129.983166) (xy 286.266878 -129.975338) (xy 286.326846 -129.975338) (xy 286.386302 -129.983166)
			(xy 286.444227 -129.998687) (xy 286.499631 -130.021636) (xy 286.551565 -130.05162) (xy 286.599141 -130.088126)
			(xy 286.641546 -130.130531) (xy 286.678052 -130.178107) (xy 286.708036 -130.230041) (xy 286.730985 -130.285445)
			(xy 286.746506 -130.34337) (xy 286.754334 -130.402826) (xy 286.754824 -130.43281) (xy 286.754824 -130.777234)
			(xy 298.799504 -130.777234) (xy 298.799504 -129.913634) (xy 298.799994 -129.883666) (xy 298.807817 -129.824244)
			(xy 298.82333 -129.766351) (xy 298.846266 -129.710978) (xy 298.876233 -129.659072) (xy 298.91272 -129.611522)
			(xy 298.9551 -129.569142) (xy 299.00265 -129.532655) (xy 299.054556 -129.502688) (xy 299.109929 -129.479752)
			(xy 299.167822 -129.464239) (xy 299.227244 -129.456416) (xy 299.28718 -129.456416) (xy 299.346602 -129.464239)
			(xy 299.404495 -129.479752) (xy 299.459868 -129.502688) (xy 299.511774 -129.532655) (xy 299.559324 -129.569142)
			(xy 299.601704 -129.611522) (xy 299.638191 -129.659072) (xy 299.668158 -129.710978) (xy 299.691094 -129.766351)
			(xy 299.706607 -129.824244) (xy 299.71443 -129.883666) (xy 299.71492 -129.913634) (xy 299.71492 -130.777234)
			(xy 299.71443 -130.807202) (xy 299.706607 -130.866624) (xy 299.691094 -130.924517) (xy 299.668158 -130.97989)
			(xy 299.638191 -131.031796) (xy 299.601704 -131.079346) (xy 299.559324 -131.121726) (xy 299.511774 -131.158213)
			(xy 299.459868 -131.18818) (xy 299.404495 -131.211116) (xy 299.346602 -131.226629) (xy 299.28718 -131.234452)
			(xy 299.227244 -131.234452) (xy 299.167822 -131.226629) (xy 299.109929 -131.211116) (xy 299.054556 -131.18818)
			(xy 299.00265 -131.158213) (xy 298.9551 -131.121726) (xy 298.91272 -131.079346) (xy 298.876233 -131.031796)
			(xy 298.846266 -130.97989) (xy 298.82333 -130.924517) (xy 298.807817 -130.866624) (xy 298.799994 -130.807202)
			(xy 298.799504 -130.777234) (xy 286.754824 -130.777234) (xy 286.754824 -131.29641) (xy 286.754334 -131.326394)
			(xy 286.746506 -131.38585) (xy 286.730985 -131.443775) (xy 286.708036 -131.499179) (xy 286.678052 -131.551113)
			(xy 286.641546 -131.598689) (xy 286.599141 -131.641094) (xy 286.551565 -131.6776) (xy 286.499631 -131.707584)
			(xy 286.444227 -131.730533) (xy 286.386302 -131.746054) (xy 286.326846 -131.753882) (xy 286.266878 -131.753882)
			(xy 286.207422 -131.746054) (xy 286.149497 -131.730533) (xy 286.094093 -131.707584) (xy 286.042159 -131.6776)
			(xy 285.994583 -131.641094) (xy 285.952178 -131.598689) (xy 285.915672 -131.551113) (xy 285.885688 -131.499179)
			(xy 285.862739 -131.443775) (xy 285.847218 -131.38585) (xy 285.83939 -131.326394) (xy 285.8389 -131.29641)
			(xy 267.783564 -131.29641) (xy 267.783564 -131.297934) (xy 267.783074 -131.327918) (xy 267.775246 -131.387374)
			(xy 267.759725 -131.445299) (xy 267.736776 -131.500703) (xy 267.706792 -131.552637) (xy 267.670286 -131.600213)
			(xy 267.627881 -131.642618) (xy 267.580305 -131.679124) (xy 267.528371 -131.709108) (xy 267.472967 -131.732057)
			(xy 267.415042 -131.747578) (xy 267.355586 -131.755406) (xy 267.295618 -131.755406) (xy 267.236162 -131.747578)
			(xy 267.178237 -131.732057) (xy 267.122833 -131.709108) (xy 267.070899 -131.679124) (xy 267.023323 -131.642618)
			(xy 266.980918 -131.600213) (xy 266.944412 -131.552637) (xy 266.914428 -131.500703) (xy 266.891479 -131.445299)
			(xy 266.875958 -131.387374) (xy 266.86813 -131.327918) (xy 266.86764 -131.297934) (xy 243.925661 -131.297934)
			(xy 243.937339 -131.336683) (xy 243.945487 -131.391954) (xy 243.945489 -131.447823) (xy 243.937344 -131.503095)
			(xy 243.921226 -131.556588) (xy 243.89748 -131.607159) (xy 243.866614 -131.653727) (xy 243.829287 -131.695297)
			(xy 243.786297 -131.730979) (xy 243.738564 -131.760011) (xy 243.687108 -131.781772) (xy 243.660168 -131.78917)
			(xy 243.652294 -131.791202) (xy 243.642134 -131.793742) (xy 243.63172 -131.807204) (xy 243.626808 -131.81399)
			(xy 243.621357 -131.829821) (xy 243.621052 -131.838192) (xy 243.621052 -132.249672) (xy 243.621814 -132.258054)
			(xy 243.623273 -132.265488) (xy 243.629994 -132.279057) (xy 243.635022 -132.284724) (xy 243.677186 -132.328666)
			(xy 243.680617 -132.332113) (xy 243.688548 -132.337739) (xy 243.692934 -132.339842) (xy 243.709952 -132.347462)
			(xy 243.714133 -132.349236) (xy 243.722951 -132.351409) (xy 243.727478 -132.35178) (xy 243.75733 -132.35418)
			(xy 243.815803 -132.367102) (xy 243.871543 -132.388995) (xy 243.923181 -132.419321) (xy 243.94668 -132.437886)
			(xy 243.968878 -132.456871) (xy 244.007804 -132.500417) (xy 244.039652 -132.549379) (xy 244.063679 -132.602616)
			(xy 244.079327 -132.658889) (xy 244.083332 -132.687822) (xy 244.08384 -132.692902) (xy 244.08479 -132.702653)
			(xy 244.085805 -132.722221) (xy 244.085872 -132.732018) (xy 244.085872 -132.732526) (xy 244.085444 -132.758044)
			(xy 244.078639 -132.808626) (xy 244.065153 -132.857849) (xy 244.045228 -132.904835) (xy 244.019219 -132.948747)
			(xy 243.987589 -132.988801) (xy 243.96954 -133.006846) (xy 243.962428 -133.013958) (xy 243.95049 -133.040882)
			(xy 243.946172 -133.050788) (xy 243.946172 -133.104382) (xy 269.509748 -133.104382) (xy 269.509748 -132.240782)
			(xy 269.510238 -132.210798) (xy 269.518066 -132.151342) (xy 269.533587 -132.093417) (xy 269.556536 -132.038013)
			(xy 269.58652 -131.986079) (xy 269.623026 -131.938503) (xy 269.665431 -131.896098) (xy 269.713007 -131.859592)
			(xy 269.764941 -131.829608) (xy 269.820345 -131.806659) (xy 269.87827 -131.791138) (xy 269.937726 -131.78331)
			(xy 269.997694 -131.78331) (xy 270.05715 -131.791138) (xy 270.115075 -131.806659) (xy 270.170479 -131.829608)
			(xy 270.222413 -131.859592) (xy 270.269989 -131.896098) (xy 270.312394 -131.938503) (xy 270.3489 -131.986079)
			(xy 270.378884 -132.038013) (xy 270.401833 -132.093417) (xy 270.417354 -132.151342) (xy 270.425182 -132.210798)
			(xy 270.425672 -132.240782) (xy 270.425672 -133.096508) (xy 283.9847 -133.096508) (xy 283.9847 -132.232908)
			(xy 283.98519 -132.202924) (xy 283.993018 -132.143468) (xy 284.008539 -132.085543) (xy 284.031488 -132.030139)
			(xy 284.061472 -131.978205) (xy 284.097978 -131.930629) (xy 284.140383 -131.888224) (xy 284.187959 -131.851718)
			(xy 284.239893 -131.821734) (xy 284.295297 -131.798785) (xy 284.353222 -131.783264) (xy 284.412678 -131.775436)
			(xy 284.472646 -131.775436) (xy 284.532102 -131.783264) (xy 284.590027 -131.798785) (xy 284.645431 -131.821734)
			(xy 284.697365 -131.851718) (xy 284.744941 -131.888224) (xy 284.787346 -131.930629) (xy 284.823852 -131.978205)
			(xy 284.853836 -132.030139) (xy 284.876785 -132.085543) (xy 284.892306 -132.143468) (xy 284.900134 -132.202924)
			(xy 284.900624 -132.232908) (xy 284.900624 -132.577332) (xy 296.945304 -132.577332) (xy 296.945304 -131.713732)
			(xy 296.945794 -131.683764) (xy 296.953617 -131.624342) (xy 296.96913 -131.566449) (xy 296.992066 -131.511076)
			(xy 297.022033 -131.45917) (xy 297.05852 -131.41162) (xy 297.1009 -131.36924) (xy 297.14845 -131.332753)
			(xy 297.200356 -131.302786) (xy 297.255729 -131.27985) (xy 297.313622 -131.264337) (xy 297.373044 -131.256514)
			(xy 297.43298 -131.256514) (xy 297.492402 -131.264337) (xy 297.550295 -131.27985) (xy 297.605668 -131.302786)
			(xy 297.657574 -131.332753) (xy 297.705124 -131.36924) (xy 297.747504 -131.41162) (xy 297.783991 -131.45917)
			(xy 297.813958 -131.511076) (xy 297.836894 -131.566449) (xy 297.852407 -131.624342) (xy 297.86023 -131.683764)
			(xy 297.86072 -131.713732) (xy 297.86072 -132.577332) (xy 297.86023 -132.6073) (xy 297.852407 -132.666722)
			(xy 297.836894 -132.724615) (xy 297.813958 -132.779988) (xy 297.783991 -132.831894) (xy 297.747504 -132.879444)
			(xy 297.705124 -132.921824) (xy 297.657574 -132.958311) (xy 297.605668 -132.988278) (xy 297.550295 -133.011214)
			(xy 297.492402 -133.026727) (xy 297.43298 -133.03455) (xy 297.373044 -133.03455) (xy 297.313622 -133.026727)
			(xy 297.255729 -133.011214) (xy 297.200356 -132.988278) (xy 297.14845 -132.958311) (xy 297.1009 -132.921824)
			(xy 297.05852 -132.879444) (xy 297.022033 -132.831894) (xy 296.992066 -132.779988) (xy 296.96913 -132.724615)
			(xy 296.953617 -132.666722) (xy 296.945794 -132.6073) (xy 296.945304 -132.577332) (xy 284.900624 -132.577332)
			(xy 284.900624 -133.096508) (xy 284.900134 -133.126492) (xy 284.892306 -133.185948) (xy 284.876785 -133.243873)
			(xy 284.853836 -133.299277) (xy 284.823852 -133.351211) (xy 284.787346 -133.398787) (xy 284.744941 -133.441192)
			(xy 284.697365 -133.477698) (xy 284.645431 -133.507682) (xy 284.590027 -133.530631) (xy 284.532102 -133.546152)
			(xy 284.472646 -133.55398) (xy 284.412678 -133.55398) (xy 284.353222 -133.546152) (xy 284.295297 -133.530631)
			(xy 284.239893 -133.507682) (xy 284.187959 -133.477698) (xy 284.140383 -133.441192) (xy 284.097978 -133.398787)
			(xy 284.061472 -133.351211) (xy 284.031488 -133.299277) (xy 284.008539 -133.243873) (xy 283.993018 -133.185948)
			(xy 283.98519 -133.126492) (xy 283.9847 -133.096508) (xy 270.425672 -133.096508) (xy 270.425672 -133.104382)
			(xy 270.425182 -133.134366) (xy 270.417354 -133.193822) (xy 270.401833 -133.251747) (xy 270.378884 -133.307151)
			(xy 270.3489 -133.359085) (xy 270.312394 -133.406661) (xy 270.269989 -133.449066) (xy 270.222413 -133.485572)
			(xy 270.170479 -133.515556) (xy 270.115075 -133.538505) (xy 270.05715 -133.554026) (xy 269.997694 -133.561854)
			(xy 269.937726 -133.561854) (xy 269.87827 -133.554026) (xy 269.820345 -133.538505) (xy 269.764941 -133.515556)
			(xy 269.713007 -133.485572) (xy 269.665431 -133.449066) (xy 269.623026 -133.406661) (xy 269.58652 -133.359085)
			(xy 269.556536 -133.307151) (xy 269.533587 -133.251747) (xy 269.518066 -133.193822) (xy 269.510238 -133.134366)
			(xy 269.509748 -133.104382) (xy 243.946172 -133.104382) (xy 243.946172 -133.10997) (xy 243.946934 -133.118352)
			(xy 243.95049 -133.134608) (xy 243.952776 -133.139942) (xy 243.962428 -133.162548) (xy 243.969794 -133.16966)
			(xy 243.987808 -133.187697) (xy 244.019376 -133.227724) (xy 244.04533 -133.271599) (xy 244.065207 -133.318541)
			(xy 244.078653 -133.367713) (xy 244.085428 -133.418237) (xy 244.085872 -133.443726) (xy 244.085409 -133.47033)
			(xy 244.078012 -133.523022) (xy 244.063367 -133.574176) (xy 244.041757 -133.622798) (xy 244.0136 -133.667946)
			(xy 243.979444 -133.708745) (xy 243.939951 -133.744402) (xy 243.895887 -133.774226) (xy 243.848106 -133.797639)
			(xy 243.797536 -133.814186) (xy 243.745157 -133.823547) (xy 243.718588 -133.82498) (xy 243.708682 -133.825488)
			(xy 243.69903 -133.829806) (xy 243.695209 -133.831707) (xy 243.68819 -133.836558) (xy 243.68506 -133.839458)
			(xy 243.635276 -133.891274) (xy 243.628164 -133.89864) (xy 243.624608 -133.907276) (xy 243.622901 -133.911849)
			(xy 243.621116 -133.921445) (xy 243.621052 -133.926326) (xy 243.621052 -134.694168) (xy 243.621052 -134.695184)
			(xy 243.621579 -134.704149) (xy 243.628098 -134.720869) (xy 243.639986 -134.734312) (xy 243.647722 -134.738872)
			(xy 243.726462 -134.781036) (xy 243.732676 -134.784119) (xy 243.746195 -134.787209) (xy 243.753132 -134.787132)
			(xy 243.767102 -134.78637) (xy 243.778786 -134.778496) (xy 243.783358 -134.775448) (xy 243.791994 -134.770114)
			(xy 243.808758 -134.745984) (xy 243.811592 -134.741811) (xy 243.815697 -134.732598) (xy 243.816886 -134.727696)
			(xy 243.821458 -134.707122) (xy 243.822474 -134.696454) (xy 243.822474 -134.642098) (xy 243.82095 -134.629906)
			(xy 243.818664 -134.620762) (xy 243.816886 -134.617968) (xy 243.814092 -134.61365) (xy 243.813076 -134.611872)
			(xy 243.81206 -134.610094) (xy 243.811552 -134.609586) (xy 243.798346 -134.587365) (xy 243.777386 -134.540114)
			(xy 243.762989 -134.490469) (xy 243.755417 -134.439336) (xy 243.754656 -134.413498) (xy 243.754656 -134.406132)
			(xy 243.75533 -134.379012) (xy 243.763406 -134.325367) (xy 243.779 -134.273407) (xy 243.801798 -134.224181)
			(xy 243.831341 -134.178681) (xy 243.867031 -134.137826) (xy 243.90815 -134.10244) (xy 243.953868 -134.073236)
			(xy 244.003262 -134.050804) (xy 244.055336 -134.035596) (xy 244.109039 -134.027919) (xy 244.136164 -134.027418)
			(xy 244.163418 -134.027879) (xy 244.217371 -134.035632) (xy 244.269672 -134.050985) (xy 244.319255 -134.073626)
			(xy 244.365111 -134.103093) (xy 244.406306 -134.138787) (xy 244.442001 -134.179981) (xy 244.471469 -134.225836)
			(xy 244.494111 -134.275419) (xy 244.509466 -134.327719) (xy 244.51722 -134.381672) (xy 244.517672 -134.408926)
			(xy 244.517174 -134.437019) (xy 244.508948 -134.492599) (xy 244.492677 -134.546377) (xy 244.468712 -134.597196)
			(xy 244.437567 -134.64396) (xy 244.399915 -134.685663) (xy 244.356565 -134.721407) (xy 244.33276 -134.736332)
			(xy 244.332252 -134.736586) (xy 244.323362 -134.742174) (xy 244.317266 -134.750556) (xy 244.314916 -134.753962)
			(xy 244.311219 -134.761365) (xy 244.3099 -134.765288) (xy 244.3099 -134.766304) (xy 244.308884 -134.769352)
			(xy 244.29339 -134.841234) (xy 244.292398 -134.846325) (xy 244.292277 -134.856693) (xy 244.293136 -134.861808)
			(xy 244.295168 -134.871968) (xy 244.301264 -134.880604) (xy 244.30863 -134.891526) (xy 244.312555 -134.897876)
			(xy 266.86764 -134.897876) (xy 266.86764 -134.034276) (xy 266.86813 -134.004292) (xy 266.875958 -133.944836)
			(xy 266.891479 -133.886911) (xy 266.914428 -133.831507) (xy 266.944412 -133.779573) (xy 266.980918 -133.731997)
			(xy 267.023323 -133.689592) (xy 267.070899 -133.653086) (xy 267.122833 -133.623102) (xy 267.178237 -133.600153)
			(xy 267.236162 -133.584632) (xy 267.295618 -133.576804) (xy 267.355586 -133.576804) (xy 267.415042 -133.584632)
			(xy 267.472967 -133.600153) (xy 267.528371 -133.623102) (xy 267.580305 -133.653086) (xy 267.627881 -133.689592)
			(xy 267.670286 -133.731997) (xy 267.706792 -133.779573) (xy 267.736776 -133.831507) (xy 267.759725 -133.886911)
			(xy 267.775246 -133.944836) (xy 267.783074 -134.004292) (xy 267.783564 -134.034276) (xy 267.783564 -134.897876)
			(xy 267.783074 -134.92786) (xy 267.775246 -134.987316) (xy 267.759725 -135.045241) (xy 267.736776 -135.100645)
			(xy 267.706792 -135.152579) (xy 267.670286 -135.200155) (xy 267.627881 -135.24256) (xy 267.580305 -135.279066)
			(xy 267.528371 -135.30905) (xy 267.472967 -135.331999) (xy 267.415042 -135.34752) (xy 267.355586 -135.355348)
			(xy 267.295618 -135.355348) (xy 267.236162 -135.34752) (xy 267.178237 -135.331999) (xy 267.122833 -135.30905)
			(xy 267.070899 -135.279066) (xy 267.023323 -135.24256) (xy 266.980918 -135.200155) (xy 266.944412 -135.152579)
			(xy 266.914428 -135.100645) (xy 266.891479 -135.045241) (xy 266.875958 -134.987316) (xy 266.86813 -134.92786)
			(xy 266.86764 -134.897876) (xy 244.312555 -134.897876) (xy 244.322963 -134.914712) (xy 244.345629 -134.964284)
			(xy 244.361021 -135.016574) (xy 244.368826 -135.07052) (xy 244.369336 -135.097774) (xy 244.369336 -135.098282)
			(xy 244.368066 -135.127238) (xy 244.367558 -135.130794) (xy 244.364602 -135.158971) (xy 244.351426 -135.214073)
			(xy 244.330247 -135.26662) (xy 244.301532 -135.315459) (xy 244.265911 -135.359514) (xy 244.224168 -135.397819)
			(xy 244.17722 -135.429531) (xy 244.126099 -135.453952) (xy 244.071929 -135.470547) (xy 244.015901 -135.478949)
			(xy 243.987574 -135.479536) (xy 243.987066 -135.479536) (xy 243.961441 -135.479103) (xy 243.910658 -135.472199)
			(xy 243.86126 -135.458546) (xy 243.814139 -135.438392) (xy 243.770147 -135.412101) (xy 243.74983 -135.396478)
			(xy 243.742972 -135.391144) (xy 243.735352 -135.388604) (xy 243.731294 -135.387234) (xy 243.722868 -135.385706)
			(xy 243.718588 -135.385556) (xy 243.696744 -135.385556) (xy 243.691305 -135.38541) (xy 243.680677 -135.383096)
			(xy 243.675662 -135.380984) (xy 243.66347 -135.374888) (xy 243.658144 -135.372426) (xy 243.646728 -135.369732)
			(xy 243.640864 -135.369554) (xy 243.626132 -135.369554) (xy 243.613178 -135.377174) (xy 243.611908 -135.377936)
			(xy 243.606828 -135.382508) (xy 243.599208 -135.389112) (xy 243.5987 -135.38962) (xy 243.595652 -135.39216)
			(xy 243.59489 -135.392922) (xy 243.57345 -135.409849) (xy 243.526693 -135.438093) (xy 243.476395 -135.4594)
			(xy 243.45011 -135.466836) (xy 243.436882 -135.470206) (xy 243.410059 -135.47529) (xy 243.396516 -135.476996)
			(xy 243.394992 -135.47725) (xy 243.382292 -135.479536) (xy 243.374926 -135.483092) (xy 243.371373 -135.484975)
			(xy 243.364867 -135.489699) (xy 243.361972 -135.49249) (xy 242.14709 -136.707372) (xy 242.139692 -136.71422)
			(xy 242.121094 -136.721955) (xy 242.111022 -136.722358) (xy 238.776002 -136.722358) (xy 238.766633 -136.72278)
			(xy 238.749145 -136.729511) (xy 238.735243 -136.742075) (xy 238.726782 -136.758795) (xy 238.725456 -136.768078)
			(xy 238.725456 -137.44829) (xy 240.54511 -137.44829) (xy 240.549181 -137.392668) (xy 240.561307 -137.338231)
			(xy 240.58123 -137.28614) (xy 240.608526 -137.237505) (xy 240.642612 -137.193362) (xy 240.682761 -137.154653)
			(xy 240.728119 -137.122202) (xy 240.777719 -137.096701) (xy 240.830503 -137.078694) (xy 240.885346 -137.068564)
			(xy 240.94108 -137.066527) (xy 240.996517 -137.072627) (xy 241.050474 -137.086733) (xy 241.101803 -137.108545)
			(xy 241.149409 -137.137599) (xy 241.192277 -137.173274) (xy 241.229494 -137.214811) (xy 241.260267 -137.261324)
			(xy 241.267302 -137.276332) (xy 245.24716 -137.276332) (xy 245.247563 -137.250016) (xy 245.254808 -137.197884)
			(xy 245.269139 -137.147239) (xy 245.290283 -137.09904) (xy 245.317842 -137.054198) (xy 245.351292 -137.013562)
			(xy 245.37035 -136.995408) (xy 245.377743 -136.987879) (xy 245.386274 -136.968605) (xy 245.38686 -136.95807)
			(xy 245.38686 -136.883394) (xy 245.386359 -136.872841) (xy 245.377805 -136.853545) (xy 245.37035 -136.846056)
			(xy 245.351271 -136.827925) (xy 245.317818 -136.787289) (xy 245.290263 -136.742443) (xy 245.269129 -136.694238)
			(xy 245.254816 -136.643586) (xy 245.247596 -136.591449) (xy 245.24716 -136.565132) (xy 245.247646 -136.537881)
			(xy 245.255402 -136.483933) (xy 245.270757 -136.431638) (xy 245.293399 -136.382061) (xy 245.322865 -136.336211)
			(xy 245.358556 -136.29502) (xy 245.399747 -136.259329) (xy 245.445597 -136.229863) (xy 245.495174 -136.207221)
			(xy 245.547469 -136.191866) (xy 245.601417 -136.18411) (xy 245.655919 -136.18411) (xy 245.709867 -136.191866)
			(xy 245.762162 -136.207221) (xy 245.811739 -136.229863) (xy 245.857589 -136.259329) (xy 245.89878 -136.29502)
			(xy 245.934471 -136.336211) (xy 245.963937 -136.382061) (xy 245.986579 -136.431638) (xy 246.001934 -136.483933)
			(xy 246.00969 -136.537881) (xy 246.010176 -136.565132) (xy 246.009738 -136.591447) (xy 246.002498 -136.643577)
			(xy 245.988174 -136.694221) (xy 245.967036 -136.74242) (xy 245.939484 -136.787262) (xy 245.90604 -136.827901)
			(xy 245.886986 -136.846056) (xy 245.8796 -136.85359) (xy 245.871067 -136.872861) (xy 245.870476 -136.883394)
			(xy 245.870476 -136.95807) (xy 245.871015 -136.968618) (xy 245.879544 -136.987913) (xy 245.886986 -136.995408)
			(xy 245.906036 -137.013569) (xy 245.939494 -137.054198) (xy 245.967054 -137.099036) (xy 245.988194 -137.147236)
			(xy 246.002512 -137.197883) (xy 246.009737 -137.250016) (xy 246.010176 -137.276332) (xy 246.00969 -137.303583)
			(xy 246.001934 -137.357531) (xy 245.986579 -137.409826) (xy 245.963937 -137.459403) (xy 245.934471 -137.505253)
			(xy 245.89878 -137.546444) (xy 245.857589 -137.582135) (xy 245.811739 -137.611601) (xy 245.762162 -137.634243)
			(xy 245.709867 -137.649598) (xy 245.655919 -137.657354) (xy 245.601417 -137.657354) (xy 245.547469 -137.649598)
			(xy 245.495174 -137.634243) (xy 245.445597 -137.611601) (xy 245.399747 -137.582135) (xy 245.358556 -137.546444)
			(xy 245.322865 -137.505253) (xy 245.293399 -137.459403) (xy 245.270757 -137.409826) (xy 245.255402 -137.357531)
			(xy 245.247646 -137.303583) (xy 245.24716 -137.276332) (xy 241.267302 -137.276332) (xy 241.283939 -137.311821)
			(xy 241.300007 -137.365228) (xy 241.308127 -137.420404) (xy 241.308636 -137.44829) (xy 241.308127 -137.476176)
			(xy 241.300007 -137.531352) (xy 241.283939 -137.584759) (xy 241.260267 -137.635256) (xy 241.229494 -137.681769)
			(xy 241.192277 -137.723306) (xy 241.18823 -137.726674) (xy 246.187722 -137.726674) (xy 246.188167 -137.699303)
			(xy 246.195989 -137.645123) (xy 246.211483 -137.592619) (xy 246.234329 -137.542873) (xy 246.264059 -137.496907)
			(xy 246.281702 -137.475976) (xy 246.281956 -137.475722) (xy 246.287546 -137.468638) (xy 246.293789 -137.451719)
			(xy 246.294148 -137.442702) (xy 246.294148 -137.375646) (xy 246.29378 -137.36663) (xy 246.287541 -137.349712)
			(xy 246.281956 -137.342626) (xy 246.281702 -137.342626) (xy 246.281702 -137.342372) (xy 246.264084 -137.321423)
			(xy 246.234369 -137.275455) (xy 246.211529 -137.225712) (xy 246.196033 -137.173215) (xy 246.188199 -137.119042)
			(xy 246.187722 -137.091674) (xy 246.188208 -137.064423) (xy 246.195964 -137.010475) (xy 246.211319 -136.95818)
			(xy 246.233961 -136.908603) (xy 246.263427 -136.862753) (xy 246.299118 -136.821562) (xy 246.340309 -136.785871)
			(xy 246.386159 -136.756405) (xy 246.435736 -136.733763) (xy 246.488031 -136.718408) (xy 246.541979 -136.710652)
			(xy 246.596481 -136.710652) (xy 246.650429 -136.718408) (xy 246.702724 -136.733763) (xy 246.752301 -136.756405)
			(xy 246.798151 -136.785871) (xy 246.839342 -136.821562) (xy 246.875033 -136.862753) (xy 246.904499 -136.908603)
			(xy 246.927141 -136.95818) (xy 246.942496 -137.010475) (xy 246.950252 -137.064423) (xy 246.950738 -137.091674)
			(xy 246.950272 -137.119044) (xy 246.942456 -137.173224) (xy 246.926968 -137.225728) (xy 246.904126 -137.275475)
			(xy 246.8744 -137.321441) (xy 246.856758 -137.342372) (xy 246.856504 -137.342626) (xy 246.850943 -137.34973)
			(xy 246.844681 -137.366633) (xy 246.844312 -137.375646) (xy 246.844312 -137.442702) (xy 246.844665 -137.451719)
			(xy 246.850915 -137.468636) (xy 246.856504 -137.475722) (xy 246.856758 -137.475722) (xy 246.856758 -137.475976)
			(xy 246.874393 -137.496912) (xy 246.904107 -137.542883) (xy 246.926944 -137.592629) (xy 246.942436 -137.645129)
			(xy 246.950264 -137.699305) (xy 246.950738 -137.726674) (xy 246.950252 -137.753925) (xy 246.942496 -137.807873)
			(xy 246.927141 -137.860168) (xy 246.904499 -137.909745) (xy 246.875033 -137.955595) (xy 246.839342 -137.996786)
			(xy 246.798151 -138.032477) (xy 246.752301 -138.061943) (xy 246.702724 -138.084585) (xy 246.650429 -138.09994)
			(xy 246.596481 -138.107696) (xy 246.541979 -138.107696) (xy 246.488031 -138.09994) (xy 246.435736 -138.084585)
			(xy 246.386159 -138.061943) (xy 246.340309 -138.032477) (xy 246.299118 -137.996786) (xy 246.263427 -137.955595)
			(xy 246.233961 -137.909745) (xy 246.211319 -137.860168) (xy 246.195964 -137.807873) (xy 246.188208 -137.753925)
			(xy 246.187722 -137.726674) (xy 241.18823 -137.726674) (xy 241.149409 -137.758981) (xy 241.101803 -137.788035)
			(xy 241.050474 -137.809847) (xy 240.996517 -137.823953) (xy 240.94108 -137.830053) (xy 240.885346 -137.828016)
			(xy 240.830503 -137.817886) (xy 240.777719 -137.799879) (xy 240.728119 -137.774378) (xy 240.682761 -137.741927)
			(xy 240.642612 -137.703218) (xy 240.608526 -137.659075) (xy 240.58123 -137.61044) (xy 240.561307 -137.558349)
			(xy 240.549181 -137.503912) (xy 240.54511 -137.44829) (xy 238.725456 -137.44829) (xy 238.725456 -137.922254)
			(xy 238.726483 -137.930167) (xy 238.732822 -137.944803) (xy 238.737902 -137.950956) (xy 238.750602 -137.963656)
			(xy 238.75873 -137.967974) (xy 238.777526 -137.976864) (xy 238.783368 -137.978134) (xy 238.793782 -137.98042)
			(xy 238.79683 -137.980674) (xy 238.824797 -137.984019) (xy 238.879387 -137.997882) (xy 238.931347 -138.019619)
			(xy 238.979547 -138.048757) (xy 239.02294 -138.084665) (xy 239.060583 -138.126561) (xy 239.091659 -138.173536)
			(xy 239.115492 -138.224568) (xy 239.131564 -138.278549) (xy 239.139526 -138.334307) (xy 239.139206 -138.390629)
			(xy 239.137244 -138.40333) (xy 247.396254 -138.40333) (xy 247.396765 -138.375665) (xy 247.404761 -138.320914)
			(xy 247.420576 -138.267891) (xy 247.443879 -138.217707) (xy 247.474181 -138.171411) (xy 247.510848 -138.129973)
			(xy 247.553112 -138.094262) (xy 247.57634 -138.079226) (xy 247.586005 -138.072575) (xy 247.598456 -138.052725)
			(xy 247.600216 -138.041126) (xy 247.60809 -137.961116) (xy 247.608693 -137.949479) (xy 247.600631 -137.927644)
			(xy 247.592596 -137.919206) (xy 247.592342 -137.918952) (xy 247.573763 -137.900868) (xy 247.541183 -137.860538)
			(xy 247.514369 -137.816164) (xy 247.493815 -137.768566) (xy 247.479902 -137.718622) (xy 247.472885 -137.667253)
			(xy 247.472454 -137.64133) (xy 247.473006 -137.614081) (xy 247.480757 -137.560138) (xy 247.496107 -137.507847)
			(xy 247.518742 -137.458272) (xy 247.548201 -137.412424) (xy 247.583886 -137.371234) (xy 247.625069 -137.335542)
			(xy 247.670913 -137.306074) (xy 247.720483 -137.283431) (xy 247.772771 -137.268072) (xy 247.826713 -137.260311)
			(xy 247.853962 -137.259822) (xy 247.881332 -137.260305) (xy 247.93551 -137.268118) (xy 247.988013 -137.283603)
			(xy 248.037761 -137.306441) (xy 248.083728 -137.336162) (xy 248.10466 -137.353802) (xy 248.104914 -137.354056)
			(xy 248.111988 -137.359661) (xy 248.128915 -137.365895) (xy 248.137934 -137.366248) (xy 248.20499 -137.366248)
			(xy 248.214008 -137.365897) (xy 248.230925 -137.359647) (xy 248.23801 -137.354056) (xy 248.23801 -137.353802)
			(xy 248.238264 -137.353802) (xy 248.259199 -137.336167) (xy 248.305171 -137.306454) (xy 248.354918 -137.283617)
			(xy 248.407418 -137.268126) (xy 248.461593 -137.260296) (xy 248.488962 -137.259822) (xy 248.516215 -137.260291)
			(xy 248.570168 -137.268043) (xy 248.622467 -137.283396) (xy 248.672049 -137.306036) (xy 248.717904 -137.335503)
			(xy 248.759098 -137.371197) (xy 248.794792 -137.41239) (xy 248.82426 -137.458244) (xy 248.846901 -137.507825)
			(xy 248.862255 -137.560125) (xy 248.870009 -137.614077) (xy 248.87047 -137.64133) (xy 248.869913 -137.670246)
			(xy 248.861194 -137.727416) (xy 248.843944 -137.782614) (xy 248.81856 -137.834576) (xy 248.785623 -137.882111)
			(xy 248.745887 -137.924129) (xy 248.723404 -137.94232) (xy 248.714598 -137.949929) (xy 248.704414 -137.970828)
			(xy 248.703846 -137.982452) (xy 248.703846 -138.062208) (xy 248.704379 -138.073841) (xy 248.71457 -138.094752)
			(xy 248.723404 -138.10234) (xy 248.745907 -138.120507) (xy 248.785641 -138.162532) (xy 248.818578 -138.210072)
			(xy 248.843963 -138.262038) (xy 248.861215 -138.31724) (xy 248.869938 -138.374413) (xy 248.87047 -138.40333)
			(xy 248.870073 -138.430585) (xy 248.862311 -138.484541) (xy 248.850205 -138.525758) (xy 249.141742 -138.525758)
			(xy 249.142232 -138.498389) (xy 249.150042 -138.44421) (xy 249.165525 -138.391707) (xy 249.188362 -138.341959)
			(xy 249.218082 -138.295992) (xy 249.235722 -138.27506) (xy 249.235976 -138.274806) (xy 249.241575 -138.267728)
			(xy 249.247812 -138.250804) (xy 249.248168 -138.241786) (xy 249.248168 -138.17473) (xy 249.247803 -138.165714)
			(xy 249.241562 -138.148796) (xy 249.235976 -138.14171) (xy 249.235722 -138.14171) (xy 249.235722 -138.141456)
			(xy 249.21804 -138.120556) (xy 249.188318 -138.074583) (xy 249.165475 -138.024831) (xy 249.149982 -137.972324)
			(xy 249.142158 -137.918141) (xy 249.142162 -137.863396) (xy 249.149996 -137.809214) (xy 249.165497 -137.75671)
			(xy 249.188348 -137.706962) (xy 249.218079 -137.660993) (xy 249.235722 -137.64006) (xy 249.235976 -137.639806)
			(xy 249.241575 -137.632728) (xy 249.247812 -137.615804) (xy 249.248168 -137.606786) (xy 249.248168 -137.53973)
			(xy 249.247803 -137.530714) (xy 249.241562 -137.513796) (xy 249.235976 -137.50671) (xy 249.235722 -137.50671)
			(xy 249.235722 -137.506456) (xy 249.21804 -137.485556) (xy 249.188318 -137.439583) (xy 249.165475 -137.389831)
			(xy 249.149982 -137.337324) (xy 249.142158 -137.283141) (xy 249.142162 -137.228396) (xy 249.149996 -137.174214)
			(xy 249.165497 -137.12171) (xy 249.188348 -137.071962) (xy 249.218079 -137.025993) (xy 249.235722 -137.00506)
			(xy 249.235976 -137.004806) (xy 249.241575 -136.997728) (xy 249.247812 -136.980804) (xy 249.248168 -136.971786)
			(xy 249.248168 -136.90473) (xy 249.247803 -136.895714) (xy 249.241562 -136.878796) (xy 249.235976 -136.87171)
			(xy 249.235722 -136.87171) (xy 249.235722 -136.871456) (xy 249.218099 -136.850511) (xy 249.188384 -136.804542)
			(xy 249.165545 -136.754798) (xy 249.15005 -136.7023) (xy 249.142218 -136.648126) (xy 249.141742 -136.620758)
			(xy 249.142228 -136.593507) (xy 249.149984 -136.539559) (xy 249.165339 -136.487264) (xy 249.187981 -136.437687)
			(xy 249.217447 -136.391837) (xy 249.253138 -136.350646) (xy 249.294329 -136.314955) (xy 249.340179 -136.285489)
			(xy 249.389756 -136.262847) (xy 249.442051 -136.247492) (xy 249.495999 -136.239736) (xy 249.550501 -136.239736)
			(xy 249.604449 -136.247492) (xy 249.656744 -136.262847) (xy 249.706321 -136.285489) (xy 249.752171 -136.314955)
			(xy 249.793362 -136.350646) (xy 249.829053 -136.391837) (xy 249.858519 -136.437687) (xy 249.881161 -136.487264)
			(xy 249.896516 -136.539559) (xy 249.904272 -136.593507) (xy 249.904758 -136.620758) (xy 249.904278 -136.648128)
			(xy 249.896465 -136.702307) (xy 249.89587 -136.704324) (xy 269.509748 -136.704324) (xy 269.509748 -135.840724)
			(xy 269.510238 -135.81074) (xy 269.518066 -135.751284) (xy 269.533587 -135.693359) (xy 269.556536 -135.637955)
			(xy 269.58652 -135.586021) (xy 269.623026 -135.538445) (xy 269.665431 -135.49604) (xy 269.713007 -135.459534)
			(xy 269.764941 -135.42955) (xy 269.820345 -135.406601) (xy 269.87827 -135.39108) (xy 269.937726 -135.383252)
			(xy 269.997694 -135.383252) (xy 270.05715 -135.39108) (xy 270.115075 -135.406601) (xy 270.170479 -135.42955)
			(xy 270.222413 -135.459534) (xy 270.269989 -135.49604) (xy 270.312394 -135.538445) (xy 270.3489 -135.586021)
			(xy 270.378884 -135.637955) (xy 270.401833 -135.693359) (xy 270.417354 -135.751284) (xy 270.425182 -135.81074)
			(xy 270.425672 -135.840724) (xy 270.425672 -136.704324) (xy 270.425182 -136.734308) (xy 270.417354 -136.793764)
			(xy 270.401833 -136.851689) (xy 270.378884 -136.907093) (xy 270.3489 -136.959027) (xy 270.312394 -137.006603)
			(xy 270.269989 -137.049008) (xy 270.222413 -137.085514) (xy 270.170479 -137.115498) (xy 270.115075 -137.138447)
			(xy 270.05715 -137.153968) (xy 269.997694 -137.161796) (xy 269.937726 -137.161796) (xy 269.87827 -137.153968)
			(xy 269.820345 -137.138447) (xy 269.764941 -137.115498) (xy 269.713007 -137.085514) (xy 269.665431 -137.049008)
			(xy 269.623026 -137.006603) (xy 269.58652 -136.959027) (xy 269.556536 -136.907093) (xy 269.533587 -136.851689)
			(xy 269.518066 -136.793764) (xy 269.510238 -136.734308) (xy 269.509748 -136.704324) (xy 249.89587 -136.704324)
			(xy 249.88098 -136.75481) (xy 249.858141 -136.804557) (xy 249.828418 -136.850524) (xy 249.810778 -136.871456)
			(xy 249.810524 -136.87171) (xy 249.804918 -136.878783) (xy 249.798685 -136.895711) (xy 249.798332 -136.90473)
			(xy 249.798332 -136.971786) (xy 249.798689 -136.980803) (xy 249.804936 -136.99772) (xy 249.810524 -137.004806)
			(xy 249.810778 -137.004806) (xy 249.810778 -137.00506) (xy 249.828377 -137.026026) (xy 249.858103 -137.071988)
			(xy 249.880951 -137.121729) (xy 249.89645 -137.174226) (xy 249.904283 -137.2284) (xy 249.904287 -137.283137)
			(xy 249.896464 -137.337312) (xy 249.880973 -137.389812) (xy 249.858134 -137.439556) (xy 249.828415 -137.485523)
			(xy 249.810778 -137.506456) (xy 249.810524 -137.50671) (xy 249.804918 -137.513783) (xy 249.798685 -137.530711)
			(xy 249.798332 -137.53973) (xy 249.798332 -137.606786) (xy 249.798689 -137.615803) (xy 249.804936 -137.63272)
			(xy 249.810524 -137.639806) (xy 249.810778 -137.639806) (xy 249.810778 -137.64006) (xy 249.828377 -137.661026)
			(xy 249.858103 -137.706988) (xy 249.880951 -137.756729) (xy 249.89645 -137.809226) (xy 249.904283 -137.8634)
			(xy 249.904287 -137.918137) (xy 249.896464 -137.972312) (xy 249.880973 -138.024812) (xy 249.858134 -138.074556)
			(xy 249.828415 -138.120523) (xy 249.810778 -138.141456) (xy 249.810524 -138.14171) (xy 249.804918 -138.148783)
			(xy 249.798685 -138.165711) (xy 249.798332 -138.17473) (xy 249.798332 -138.241786) (xy 249.798689 -138.250803)
			(xy 249.804936 -138.26772) (xy 249.810524 -138.274806) (xy 249.810778 -138.274806) (xy 249.810778 -138.27506)
			(xy 249.828408 -138.295999) (xy 249.858122 -138.34197) (xy 249.88096 -138.391715) (xy 249.896453 -138.444215)
			(xy 249.904283 -138.498389) (xy 249.904758 -138.525758) (xy 249.904257 -138.554374) (xy 249.895719 -138.610964)
			(xy 249.878815 -138.665642) (xy 249.853924 -138.717177) (xy 249.821605 -138.764409) (xy 249.782587 -138.806278)
			(xy 249.760486 -138.824462) (xy 249.760232 -138.824716) (xy 249.751694 -138.832326) (xy 249.741807 -138.852918)
			(xy 249.741182 -138.86434) (xy 249.74169 -138.94435) (xy 249.742292 -138.955914) (xy 249.752465 -138.976685)
			(xy 249.761248 -138.984228) (xy 249.77725 -138.997436) (xy 249.777504 -138.99769) (xy 249.784586 -139.003283)
			(xy 249.801506 -139.009526) (xy 249.810524 -139.009882) (xy 249.87758 -139.009882) (xy 249.886596 -139.00952)
			(xy 249.903514 -139.003276) (xy 249.9106 -138.99769) (xy 249.9106 -138.997436) (xy 249.910854 -138.997436)
			(xy 249.931787 -138.979795) (xy 249.977755 -138.950071) (xy 250.027501 -138.927225) (xy 250.080003 -138.911729)
			(xy 250.134181 -138.9039) (xy 250.188923 -138.9039) (xy 250.243101 -138.911729) (xy 250.295603 -138.927225)
			(xy 250.345349 -138.950071) (xy 250.391317 -138.979795) (xy 250.41225 -138.997436) (xy 250.412504 -138.99769)
			(xy 250.419586 -139.003283) (xy 250.436506 -139.009526) (xy 250.445524 -139.009882) (xy 250.51258 -139.009882)
			(xy 250.521596 -139.00952) (xy 250.538514 -139.003276) (xy 250.5456 -138.99769) (xy 250.5456 -138.997436)
			(xy 250.545854 -138.997436) (xy 250.566787 -138.979795) (xy 250.612755 -138.950071) (xy 250.662501 -138.927225)
			(xy 250.715003 -138.911729) (xy 250.769181 -138.9039) (xy 250.823923 -138.9039) (xy 250.878101 -138.911729)
			(xy 250.930603 -138.927225) (xy 250.980349 -138.950071) (xy 251.026317 -138.979795) (xy 251.04725 -138.997436)
			(xy 251.047504 -138.99769) (xy 251.054586 -139.003283) (xy 251.071506 -139.009526) (xy 251.080524 -139.009882)
			(xy 251.14758 -139.009882) (xy 251.156596 -139.00952) (xy 251.173514 -139.003276) (xy 251.1806 -138.99769)
			(xy 251.1806 -138.997436) (xy 251.180854 -138.997436) (xy 251.201797 -138.979811) (xy 251.247766 -138.950095)
			(xy 251.297511 -138.927256) (xy 251.350009 -138.911762) (xy 251.404183 -138.903931) (xy 251.431552 -138.903456)
			(xy 251.458805 -138.903988) (xy 251.512756 -138.911739) (xy 251.565054 -138.927089) (xy 251.614636 -138.949727)
			(xy 251.660491 -138.979191) (xy 251.701685 -139.014881) (xy 251.737381 -139.056071) (xy 251.76685 -139.101922)
			(xy 251.789494 -139.151501) (xy 251.804851 -139.203797) (xy 251.812609 -139.257748) (xy 251.812609 -139.312252)
			(xy 251.804851 -139.366203) (xy 251.789494 -139.418499) (xy 251.76685 -139.468078) (xy 251.737381 -139.513929)
			(xy 251.701685 -139.555119) (xy 251.660491 -139.590809) (xy 251.614636 -139.620273) (xy 251.565054 -139.642911)
			(xy 251.512756 -139.658261) (xy 251.458805 -139.666012) (xy 251.431552 -139.666472) (xy 251.404183 -139.665982)
			(xy 251.350004 -139.658171) (xy 251.297501 -139.642688) (xy 251.247754 -139.619851) (xy 251.201786 -139.590131)
			(xy 251.180854 -139.572492) (xy 251.1806 -139.572238) (xy 251.173523 -139.566638) (xy 251.156599 -139.560401)
			(xy 251.14758 -139.560046) (xy 251.080524 -139.560046) (xy 251.071507 -139.560405) (xy 251.05459 -139.56665)
			(xy 251.047504 -139.572238) (xy 251.04725 -139.572492) (xy 251.026317 -139.590133) (xy 250.980349 -139.619857)
			(xy 250.930603 -139.642703) (xy 250.878101 -139.658199) (xy 250.823923 -139.666028) (xy 250.769181 -139.666028)
			(xy 250.715003 -139.658199) (xy 250.662501 -139.642703) (xy 250.612755 -139.619857) (xy 250.566787 -139.590133)
			(xy 250.545854 -139.572492) (xy 250.5456 -139.572238) (xy 250.538523 -139.566638) (xy 250.521599 -139.560401)
			(xy 250.51258 -139.560046) (xy 250.445524 -139.560046) (xy 250.436507 -139.560405) (xy 250.41959 -139.56665)
			(xy 250.412504 -139.572238) (xy 250.412504 -139.572492) (xy 250.41225 -139.572492) (xy 250.391317 -139.590133)
			(xy 250.345349 -139.619857) (xy 250.295603 -139.642703) (xy 250.243101 -139.658199) (xy 250.188923 -139.666028)
			(xy 250.134181 -139.666028) (xy 250.080003 -139.658199) (xy 250.027501 -139.642703) (xy 249.977755 -139.619857)
			(xy 249.931787 -139.590133) (xy 249.910854 -139.572492) (xy 249.9106 -139.572238) (xy 249.903523 -139.566638)
			(xy 249.886599 -139.560401) (xy 249.87758 -139.560046) (xy 249.810524 -139.560046) (xy 249.801507 -139.560405)
			(xy 249.78459 -139.56665) (xy 249.777504 -139.572238) (xy 249.777504 -139.572492) (xy 249.77725 -139.572492)
			(xy 249.756309 -139.59012) (xy 249.710339 -139.619834) (xy 249.660593 -139.642672) (xy 249.608095 -139.658166)
			(xy 249.553921 -139.665997) (xy 249.526552 -139.666472) (xy 249.499298 -139.666067) (xy 249.445345 -139.658303)
			(xy 249.393047 -139.64294) (xy 249.343467 -139.62029) (xy 249.297615 -139.590816) (xy 249.256425 -139.555116)
			(xy 249.220734 -139.513917) (xy 249.191269 -139.468059) (xy 249.168631 -139.418474) (xy 249.153279 -139.366172)
			(xy 249.145527 -139.312218) (xy 249.145044 -139.284964) (xy 249.14556 -139.256349) (xy 249.154094 -139.199759)
			(xy 249.170996 -139.145081) (xy 249.195884 -139.093547) (xy 249.2282 -139.046313) (xy 249.267216 -139.004444)
			(xy 249.289316 -138.98626) (xy 249.28957 -138.986006) (xy 249.298099 -138.978387) (xy 249.307991 -138.957802)
			(xy 249.30862 -138.946382) (xy 249.308112 -138.866372) (xy 249.307496 -138.85481) (xy 249.297333 -138.834039)
			(xy 249.288554 -138.826494) (xy 249.266101 -138.808313) (xy 249.226429 -138.766317) (xy 249.193545 -138.718817)
			(xy 249.168202 -138.666901) (xy 249.150979 -138.611756) (xy 249.142272 -138.554644) (xy 249.141742 -138.525758)
			(xy 248.850205 -138.525758) (xy 248.846949 -138.536842) (xy 248.8243 -138.586425) (xy 248.794826 -138.63228)
			(xy 248.759125 -138.673473) (xy 248.717925 -138.709166) (xy 248.672065 -138.738633) (xy 248.622478 -138.761273)
			(xy 248.570174 -138.776625) (xy 248.516217 -138.784378) (xy 248.488962 -138.784838) (xy 248.462646 -138.784416)
			(xy 248.410515 -138.777174) (xy 248.359871 -138.762848) (xy 248.311671 -138.741707) (xy 248.266829 -138.714152)
			(xy 248.226192 -138.680704) (xy 248.208038 -138.661648) (xy 248.200498 -138.654268) (xy 248.181232 -138.64573)
			(xy 248.1707 -138.645138) (xy 248.096024 -138.645138) (xy 248.085473 -138.645655) (xy 248.066177 -138.654197)
			(xy 248.058686 -138.661648) (xy 248.04054 -138.680712) (xy 247.999907 -138.714167) (xy 247.955064 -138.741724)
			(xy 247.906862 -138.76286) (xy 247.856213 -138.777176) (xy 247.804079 -138.7844) (xy 247.777762 -138.784838)
			(xy 247.750511 -138.784358) (xy 247.696565 -138.776597) (xy 247.644272 -138.761238) (xy 247.594696 -138.738595)
			(xy 247.548848 -138.709127) (xy 247.507659 -138.673436) (xy 247.471968 -138.632246) (xy 247.442501 -138.586397)
			(xy 247.419859 -138.536821) (xy 247.404502 -138.484527) (xy 247.396742 -138.430581) (xy 247.396254 -138.40333)
			(xy 239.137244 -138.40333) (xy 239.130609 -138.446293) (xy 239.113924 -138.500088) (xy 239.089512 -138.550846)
			(xy 239.057904 -138.597463) (xy 239.019786 -138.638929) (xy 238.975988 -138.67434) (xy 238.927459 -138.702928)
			(xy 238.875255 -138.724073) (xy 238.820511 -138.737313) (xy 238.792512 -138.740388) (xy 238.783622 -138.74115)
			(xy 238.750856 -138.75639) (xy 238.744252 -138.763248) (xy 238.73968 -138.768074) (xy 238.736249 -138.771693)
			(xy 238.730753 -138.780013) (xy 238.728758 -138.784584) (xy 238.725456 -138.792712) (xy 238.725456 -138.824462)
			(xy 240.561874 -138.824462) (xy 240.565945 -138.76884) (xy 240.578071 -138.714403) (xy 240.597994 -138.662312)
			(xy 240.62529 -138.613677) (xy 240.659376 -138.569534) (xy 240.699525 -138.530825) (xy 240.744883 -138.498374)
			(xy 240.794483 -138.472873) (xy 240.847267 -138.454866) (xy 240.90211 -138.444736) (xy 240.957844 -138.442699)
			(xy 241.013281 -138.448799) (xy 241.067238 -138.462905) (xy 241.118567 -138.484717) (xy 241.166173 -138.513771)
			(xy 241.209041 -138.549446) (xy 241.246258 -138.590983) (xy 241.277031 -138.637496) (xy 241.300703 -138.687993)
			(xy 241.316771 -138.7414) (xy 241.324891 -138.796576) (xy 241.3254 -138.824462) (xy 241.324891 -138.852348)
			(xy 241.316771 -138.907524) (xy 241.300703 -138.960931) (xy 241.277031 -139.011428) (xy 241.246258 -139.057941)
			(xy 241.209041 -139.099478) (xy 241.166173 -139.135153) (xy 241.118567 -139.164207) (xy 241.067238 -139.186019)
			(xy 241.013281 -139.200125) (xy 240.957844 -139.206225) (xy 240.90211 -139.204188) (xy 240.847267 -139.194058)
			(xy 240.794483 -139.176051) (xy 240.744883 -139.15055) (xy 240.699525 -139.118099) (xy 240.659376 -139.07939)
			(xy 240.62529 -139.035247) (xy 240.597994 -138.986612) (xy 240.578071 -138.934521) (xy 240.565945 -138.880084)
			(xy 240.561874 -138.824462) (xy 238.725456 -138.824462) (xy 238.725456 -138.938254) (xy 238.726483 -138.946167)
			(xy 238.732822 -138.960803) (xy 238.737902 -138.966956) (xy 238.750602 -138.979656) (xy 238.75873 -138.983974)
			(xy 238.777526 -138.992864) (xy 238.783368 -138.994134) (xy 238.793782 -138.99642) (xy 238.79683 -138.996674)
			(xy 238.824797 -139.000019) (xy 238.879387 -139.013882) (xy 238.931347 -139.035619) (xy 238.979547 -139.064757)
			(xy 239.02294 -139.100665) (xy 239.060583 -139.142561) (xy 239.091659 -139.189536) (xy 239.115492 -139.240568)
			(xy 239.131564 -139.294549) (xy 239.139526 -139.350307) (xy 239.139206 -139.406629) (xy 239.130609 -139.462293)
			(xy 239.113924 -139.516088) (xy 239.089512 -139.566846) (xy 239.057904 -139.613463) (xy 239.019786 -139.654929)
			(xy 238.975988 -139.69034) (xy 238.927459 -139.718928) (xy 238.875255 -139.740073) (xy 238.820511 -139.753313)
			(xy 238.792512 -139.756388) (xy 238.783622 -139.75715) (xy 238.750856 -139.77239) (xy 238.744252 -139.779248)
			(xy 238.73968 -139.784074) (xy 238.736249 -139.787693) (xy 238.730753 -139.796013) (xy 238.728758 -139.800584)
			(xy 238.725456 -139.808712) (xy 238.725456 -140.392404) (xy 240.567716 -140.392404) (xy 240.571787 -140.336782)
			(xy 240.583913 -140.282345) (xy 240.603836 -140.230254) (xy 240.631132 -140.181619) (xy 240.665218 -140.137476)
			(xy 240.705367 -140.098767) (xy 240.750725 -140.066316) (xy 240.800325 -140.040815) (xy 240.853109 -140.022808)
			(xy 240.907952 -140.012678) (xy 240.963686 -140.010641) (xy 241.019123 -140.016741) (xy 241.07308 -140.030847)
			(xy 241.124409 -140.052659) (xy 241.172015 -140.081713) (xy 241.214883 -140.117388) (xy 241.2521 -140.158925)
			(xy 241.282873 -140.205438) (xy 241.306545 -140.255935) (xy 241.322613 -140.309342) (xy 241.330733 -140.364518)
			(xy 241.331242 -140.392404) (xy 241.330733 -140.42029) (xy 241.322613 -140.475466) (xy 241.306545 -140.528873)
			(xy 241.282873 -140.57937) (xy 241.2521 -140.625883) (xy 241.214883 -140.66742) (xy 241.172015 -140.703095)
			(xy 241.124409 -140.732149) (xy 241.07308 -140.753961) (xy 241.019123 -140.768067) (xy 240.963686 -140.774167)
			(xy 240.907952 -140.77213) (xy 240.853109 -140.762) (xy 240.800325 -140.743993) (xy 240.750725 -140.718492)
			(xy 240.705367 -140.686041) (xy 240.665218 -140.647332) (xy 240.631132 -140.603189) (xy 240.603836 -140.554554)
			(xy 240.583913 -140.502463) (xy 240.571787 -140.448026) (xy 240.567716 -140.392404) (xy 238.725456 -140.392404)
			(xy 238.725456 -141.046551) (xy 242.955054 -141.046551) (xy 242.955054 -140.992049) (xy 242.96281 -140.938101)
			(xy 242.978164 -140.885806) (xy 243.000804 -140.836228) (xy 243.030269 -140.790376) (xy 243.065959 -140.749184)
			(xy 243.107147 -140.71349) (xy 243.152996 -140.684021) (xy 243.202572 -140.661377) (xy 243.254865 -140.646017)
			(xy 243.308813 -140.638256) (xy 243.336064 -140.637768) (xy 243.362379 -140.638203) (xy 243.414508 -140.645446)
			(xy 243.465151 -140.659772) (xy 243.51335 -140.680911) (xy 243.558193 -140.708462) (xy 243.598832 -140.741905)
			(xy 243.616988 -140.760958) (xy 243.624518 -140.76835) (xy 243.643791 -140.776881) (xy 243.654326 -140.777468)
			(xy 243.729002 -140.777468) (xy 243.739555 -140.776963) (xy 243.75885 -140.768412) (xy 243.76634 -140.760958)
			(xy 243.784475 -140.741882) (xy 243.82511 -140.708428) (xy 243.869955 -140.680873) (xy 243.91816 -140.659738)
			(xy 243.96881 -140.645425) (xy 244.020947 -140.638204) (xy 244.047264 -140.637768) (xy 244.074517 -140.638277)
			(xy 244.128468 -140.646029) (xy 244.180767 -140.661381) (xy 244.230349 -140.68402) (xy 244.276203 -140.713485)
			(xy 244.317398 -140.749177) (xy 244.353093 -140.790368) (xy 244.382563 -140.83622) (xy 244.405206 -140.885799)
			(xy 244.420563 -140.938097) (xy 244.428321 -140.992047) (xy 244.428321 -141.046553) (xy 244.420563 -141.100503)
			(xy 244.405206 -141.152801) (xy 244.382563 -141.20238) (xy 244.353093 -141.248232) (xy 244.317398 -141.289423)
			(xy 244.276203 -141.325115) (xy 244.230349 -141.35458) (xy 244.180767 -141.377219) (xy 244.128468 -141.392571)
			(xy 244.074517 -141.400323) (xy 244.047264 -141.400784) (xy 244.020949 -141.400346) (xy 243.968819 -141.393106)
			(xy 243.918176 -141.378781) (xy 243.869977 -141.357643) (xy 243.825134 -141.330092) (xy 243.784496 -141.296648)
			(xy 243.76634 -141.277594) (xy 243.758806 -141.270207) (xy 243.739535 -141.261675) (xy 243.729002 -141.261084)
			(xy 243.654326 -141.261084) (xy 243.643777 -141.261619) (xy 243.624482 -141.270151) (xy 243.616988 -141.277594)
			(xy 243.59883 -141.296647) (xy 243.558201 -141.330105) (xy 243.513361 -141.357664) (xy 243.465161 -141.378803)
			(xy 243.414514 -141.393121) (xy 243.36238 -141.400346) (xy 243.336064 -141.400784) (xy 243.308813 -141.400344)
			(xy 243.254865 -141.392583) (xy 243.202572 -141.377223) (xy 243.152996 -141.354579) (xy 243.107147 -141.32511)
			(xy 243.065959 -141.289416) (xy 243.030269 -141.248224) (xy 243.000804 -141.202372) (xy 242.978164 -141.152794)
			(xy 242.96281 -141.100499) (xy 242.955054 -141.046551) (xy 238.725456 -141.046551) (xy 238.725456 -143.078551)
			(xy 242.955054 -143.078551) (xy 242.955054 -143.024049) (xy 242.96281 -142.970101) (xy 242.978164 -142.917806)
			(xy 243.000804 -142.868228) (xy 243.030269 -142.822376) (xy 243.065959 -142.781184) (xy 243.107147 -142.74549)
			(xy 243.152996 -142.716021) (xy 243.202572 -142.693377) (xy 243.254865 -142.678017) (xy 243.308813 -142.670256)
			(xy 243.336064 -142.669768) (xy 243.362379 -142.670203) (xy 243.414508 -142.677446) (xy 243.465151 -142.691772)
			(xy 243.51335 -142.712911) (xy 243.558193 -142.740462) (xy 243.598832 -142.773905) (xy 243.616988 -142.792958)
			(xy 243.624518 -142.80035) (xy 243.643791 -142.808881) (xy 243.654326 -142.809468) (xy 243.729002 -142.809468)
			(xy 243.739555 -142.808963) (xy 243.75885 -142.800412) (xy 243.76634 -142.792958) (xy 243.784475 -142.773882)
			(xy 243.82511 -142.740428) (xy 243.869955 -142.712873) (xy 243.91816 -142.691738) (xy 243.96881 -142.677425)
			(xy 244.020947 -142.670204) (xy 244.047264 -142.669768) (xy 244.074517 -142.670277) (xy 244.128468 -142.678029)
			(xy 244.180767 -142.693381) (xy 244.230349 -142.71602) (xy 244.276203 -142.745485) (xy 244.317398 -142.781177)
			(xy 244.353093 -142.822368) (xy 244.382563 -142.86822) (xy 244.405206 -142.917799) (xy 244.420563 -142.970097)
			(xy 244.428321 -143.024047) (xy 244.428321 -143.078553) (xy 244.420563 -143.132503) (xy 244.405206 -143.184801)
			(xy 244.382563 -143.23438) (xy 244.353093 -143.280232) (xy 244.317398 -143.321423) (xy 244.276203 -143.357115)
			(xy 244.230349 -143.38658) (xy 244.180767 -143.409219) (xy 244.128468 -143.424571) (xy 244.074517 -143.432323)
			(xy 244.047264 -143.432784) (xy 244.020949 -143.432346) (xy 243.968819 -143.425106) (xy 243.918176 -143.410781)
			(xy 243.869977 -143.389643) (xy 243.825134 -143.362092) (xy 243.784496 -143.328648) (xy 243.76634 -143.309594)
			(xy 243.758806 -143.302207) (xy 243.739535 -143.293675) (xy 243.729002 -143.293084) (xy 243.654326 -143.293084)
			(xy 243.643777 -143.293619) (xy 243.624482 -143.302151) (xy 243.616988 -143.309594) (xy 243.59883 -143.328647)
			(xy 243.558201 -143.362105) (xy 243.513361 -143.389664) (xy 243.465161 -143.410803) (xy 243.414514 -143.425121)
			(xy 243.36238 -143.432346) (xy 243.336064 -143.432784) (xy 243.308813 -143.432344) (xy 243.254865 -143.424583)
			(xy 243.202572 -143.409223) (xy 243.152996 -143.386579) (xy 243.107147 -143.35711) (xy 243.065959 -143.321416)
			(xy 243.030269 -143.280224) (xy 243.000804 -143.234372) (xy 242.978164 -143.184794) (xy 242.96281 -143.132499)
			(xy 242.955054 -143.078551) (xy 238.725456 -143.078551) (xy 238.725456 -143.966438) (xy 251.664216 -143.966438)
			(xy 251.664626 -143.940462) (xy 251.671676 -143.88899) (xy 251.685652 -143.838952) (xy 251.706293 -143.791276)
			(xy 251.733218 -143.746845) (xy 251.765928 -143.706483) (xy 251.803816 -143.670936) (xy 251.824744 -143.655542)
			(xy 251.834235 -143.64791) (xy 251.84538 -143.626298) (xy 251.84608 -143.61414) (xy 251.84608 -143.531336)
			(xy 251.845388 -143.519174) (xy 251.834248 -143.497553) (xy 251.824744 -143.489934) (xy 251.803825 -143.474531)
			(xy 251.765949 -143.438978) (xy 251.733248 -143.398614) (xy 251.70633 -143.354184) (xy 251.685691 -143.306511)
			(xy 251.671714 -143.256479) (xy 251.664658 -143.205012) (xy 251.664216 -143.179038) (xy 251.664724 -143.150299)
			(xy 251.673354 -143.093472) (xy 251.690409 -143.038582) (xy 251.715503 -142.98687) (xy 251.748069 -142.939507)
			(xy 251.76734 -142.91818) (xy 251.773944 -142.911322) (xy 251.781056 -142.893288) (xy 251.781056 -142.804388)
			(xy 251.773944 -142.786354) (xy 251.76734 -142.779496) (xy 251.748106 -142.758137) (xy 251.715538 -142.71078)
			(xy 251.690444 -142.659074) (xy 251.67339 -142.604188) (xy 251.664763 -142.547365) (xy 251.664759 -142.489891)
			(xy 251.673378 -142.433066) (xy 251.690423 -142.378178) (xy 251.71551 -142.326468) (xy 251.748071 -142.279106)
			(xy 251.76734 -142.25778) (xy 251.773944 -142.250922) (xy 251.781056 -142.232888) (xy 251.781056 -142.143988)
			(xy 251.773944 -142.125954) (xy 251.76734 -142.119096) (xy 251.748106 -142.097737) (xy 251.715538 -142.05038)
			(xy 251.690444 -141.998674) (xy 251.67339 -141.943788) (xy 251.664763 -141.886965) (xy 251.664759 -141.829491)
			(xy 251.673378 -141.772666) (xy 251.690423 -141.717778) (xy 251.71551 -141.666068) (xy 251.748071 -141.618706)
			(xy 251.76734 -141.59738) (xy 251.773944 -141.590522) (xy 251.781056 -141.572488) (xy 251.781056 -141.483588)
			(xy 251.773944 -141.465554) (xy 251.76734 -141.458696) (xy 251.748106 -141.437337) (xy 251.715538 -141.38998)
			(xy 251.690444 -141.338274) (xy 251.67339 -141.283388) (xy 251.664763 -141.226565) (xy 251.664759 -141.169091)
			(xy 251.673378 -141.112266) (xy 251.690423 -141.057378) (xy 251.71551 -141.005668) (xy 251.748071 -140.958306)
			(xy 251.76734 -140.93698) (xy 251.773944 -140.930122) (xy 251.781056 -140.912088) (xy 251.781056 -140.823188)
			(xy 251.773944 -140.805154) (xy 251.76734 -140.798296) (xy 251.748088 -140.776953) (xy 251.715519 -140.729595)
			(xy 251.690423 -140.677888) (xy 251.673368 -140.623001) (xy 251.66474 -140.566176) (xy 251.664216 -140.537438)
			(xy 251.664702 -140.510187) (xy 251.672458 -140.456239) (xy 251.687813 -140.403944) (xy 251.710455 -140.354367)
			(xy 251.739921 -140.308517) (xy 251.775612 -140.267326) (xy 251.816803 -140.231635) (xy 251.862653 -140.202169)
			(xy 251.91223 -140.179527) (xy 251.964525 -140.164172) (xy 252.018473 -140.156416) (xy 252.072975 -140.156416)
			(xy 252.126923 -140.164172) (xy 252.179218 -140.179527) (xy 252.228795 -140.202169) (xy 252.274645 -140.231635)
			(xy 252.315836 -140.267326) (xy 252.351527 -140.308517) (xy 252.380993 -140.354367) (xy 252.403635 -140.403944)
			(xy 252.41899 -140.456239) (xy 252.426746 -140.510187) (xy 252.427232 -140.537438) (xy 252.426723 -140.566177)
			(xy 252.418095 -140.623005) (xy 252.401041 -140.677896) (xy 252.375947 -140.729607) (xy 252.34338 -140.776969)
			(xy 252.324108 -140.798296) (xy 252.317504 -140.805154) (xy 252.310392 -140.823188) (xy 252.310392 -140.85697)
			(xy 267.812772 -140.85697) (xy 267.816843 -140.801348) (xy 267.828969 -140.746911) (xy 267.848892 -140.69482)
			(xy 267.876188 -140.646185) (xy 267.910274 -140.602042) (xy 267.950423 -140.563333) (xy 267.995781 -140.530882)
			(xy 268.045381 -140.505381) (xy 268.098165 -140.487374) (xy 268.153008 -140.477244) (xy 268.208742 -140.475207)
			(xy 268.264179 -140.481307) (xy 268.318136 -140.495413) (xy 268.369465 -140.517225) (xy 268.417071 -140.546279)
			(xy 268.459939 -140.581954) (xy 268.497156 -140.623491) (xy 268.527929 -140.670004) (xy 268.551601 -140.720501)
			(xy 268.567669 -140.773908) (xy 268.575789 -140.829084) (xy 268.576298 -140.85697) (xy 268.575789 -140.884856)
			(xy 268.567669 -140.940032) (xy 268.551601 -140.993439) (xy 268.527929 -141.043936) (xy 268.497156 -141.090449)
			(xy 268.459939 -141.131986) (xy 268.417071 -141.167661) (xy 268.369465 -141.196715) (xy 268.318136 -141.218527)
			(xy 268.264179 -141.232633) (xy 268.208742 -141.238733) (xy 268.153008 -141.236696) (xy 268.098165 -141.226566)
			(xy 268.045381 -141.208559) (xy 267.995781 -141.183058) (xy 267.950423 -141.150607) (xy 267.910274 -141.111898)
			(xy 267.876188 -141.067755) (xy 267.848892 -141.01912) (xy 267.828969 -140.967029) (xy 267.816843 -140.912592)
			(xy 267.812772 -140.85697) (xy 252.310392 -140.85697) (xy 252.310392 -140.912088) (xy 252.317504 -140.930122)
			(xy 252.324108 -140.93698) (xy 252.343415 -140.958275) (xy 252.375976 -141.005644) (xy 252.401064 -141.057361)
			(xy 252.418109 -141.112256) (xy 252.426728 -141.169087) (xy 252.426724 -141.226568) (xy 252.418097 -141.283398)
			(xy 252.401043 -141.338291) (xy 252.375948 -141.390004) (xy 252.34338 -141.437368) (xy 252.324108 -141.458696)
			(xy 252.317504 -141.465554) (xy 252.310392 -141.483588) (xy 252.310392 -141.572488) (xy 252.317504 -141.590522)
			(xy 252.324108 -141.59738) (xy 252.343415 -141.618675) (xy 252.375976 -141.666044) (xy 252.401064 -141.717761)
			(xy 252.418109 -141.772656) (xy 252.426728 -141.829487) (xy 252.426724 -141.886968) (xy 252.418097 -141.943798)
			(xy 252.401043 -141.998691) (xy 252.375948 -142.050404) (xy 252.34338 -142.097768) (xy 252.324108 -142.119096)
			(xy 252.317504 -142.125954) (xy 252.310392 -142.143988) (xy 252.310392 -142.232888) (xy 252.317504 -142.250922)
			(xy 252.324108 -142.25778) (xy 252.343415 -142.279075) (xy 252.375976 -142.326444) (xy 252.401064 -142.378161)
			(xy 252.418109 -142.433056) (xy 252.426728 -142.489887) (xy 252.426724 -142.547368) (xy 252.418097 -142.604198)
			(xy 252.401043 -142.659091) (xy 252.375948 -142.710804) (xy 252.34338 -142.758168) (xy 252.324108 -142.779496)
			(xy 252.317504 -142.786354) (xy 252.310392 -142.804388) (xy 252.310392 -142.893288) (xy 252.317504 -142.911322)
			(xy 252.324108 -142.91818) (xy 252.343387 -142.9395) (xy 252.375954 -142.986863) (xy 252.401046 -143.038576)
			(xy 252.418094 -143.093469) (xy 252.426713 -143.150298) (xy 252.427232 -143.179038) (xy 252.426826 -143.205015)
			(xy 252.419777 -143.256488) (xy 252.405803 -143.306526) (xy 252.385161 -143.354203) (xy 252.358235 -143.398634)
			(xy 252.325524 -143.438996) (xy 252.287633 -143.474541) (xy 252.266704 -143.489934) (xy 252.257233 -143.497587)
			(xy 252.246075 -143.519183) (xy 252.245368 -143.531336) (xy 252.245368 -143.61414) (xy 252.246056 -143.626303)
			(xy 252.257197 -143.647925) (xy 252.266704 -143.655542) (xy 252.287622 -143.670946) (xy 252.325497 -143.7065)
			(xy 252.358195 -143.746865) (xy 252.385113 -143.791295) (xy 252.405752 -143.838966) (xy 252.41973 -143.888998)
			(xy 252.426789 -143.940464) (xy 252.427232 -143.966438) (xy 252.426746 -143.993689) (xy 252.41899 -144.047637)
			(xy 252.403635 -144.099932) (xy 252.380993 -144.149509) (xy 252.351527 -144.195359) (xy 252.315836 -144.23655)
			(xy 252.274645 -144.272241) (xy 252.228795 -144.301707) (xy 252.179218 -144.324349) (xy 252.126923 -144.339704)
			(xy 252.072975 -144.34746) (xy 252.018473 -144.34746) (xy 251.964525 -144.339704) (xy 251.91223 -144.324349)
			(xy 251.862653 -144.301707) (xy 251.816803 -144.272241) (xy 251.775612 -144.23655) (xy 251.739921 -144.195359)
			(xy 251.710455 -144.149509) (xy 251.687813 -144.099932) (xy 251.672458 -144.047637) (xy 251.664702 -143.993689)
			(xy 251.664216 -143.966438) (xy 238.725456 -143.966438) (xy 238.725456 -145.110551) (xy 242.955054 -145.110551)
			(xy 242.955054 -145.056049) (xy 242.96281 -145.002101) (xy 242.978164 -144.949806) (xy 243.000804 -144.900228)
			(xy 243.030269 -144.854376) (xy 243.065959 -144.813184) (xy 243.107147 -144.77749) (xy 243.152996 -144.748021)
			(xy 243.202572 -144.725377) (xy 243.254865 -144.710017) (xy 243.308813 -144.702256) (xy 243.336064 -144.701768)
			(xy 243.362379 -144.702203) (xy 243.414508 -144.709446) (xy 243.465151 -144.723772) (xy 243.51335 -144.744911)
			(xy 243.558193 -144.772462) (xy 243.598832 -144.805905) (xy 243.616988 -144.824958) (xy 243.624518 -144.83235)
			(xy 243.643791 -144.840881) (xy 243.654326 -144.841468) (xy 243.729002 -144.841468) (xy 243.739555 -144.840963)
			(xy 243.75885 -144.832412) (xy 243.76634 -144.824958) (xy 243.784475 -144.805882) (xy 243.82511 -144.772428)
			(xy 243.869955 -144.744873) (xy 243.91816 -144.723738) (xy 243.96881 -144.709425) (xy 244.020947 -144.702204)
			(xy 244.047264 -144.701768) (xy 244.074517 -144.702277) (xy 244.128468 -144.710029) (xy 244.180767 -144.725381)
			(xy 244.230349 -144.74802) (xy 244.276203 -144.777485) (xy 244.317398 -144.813177) (xy 244.353093 -144.854368)
			(xy 244.382563 -144.90022) (xy 244.405206 -144.949799) (xy 244.406511 -144.954244) (xy 250.138946 -144.954244)
			(xy 250.139519 -144.926996) (xy 250.147268 -144.873054) (xy 250.162616 -144.820764) (xy 250.185248 -144.77119)
			(xy 250.214706 -144.725341) (xy 250.250388 -144.684152) (xy 250.291569 -144.64846) (xy 250.337411 -144.618991)
			(xy 250.386979 -144.596347) (xy 250.439266 -144.580988) (xy 250.493206 -144.573225) (xy 250.520454 -144.572736)
			(xy 250.549228 -144.573258) (xy 250.606123 -144.581908) (xy 250.661074 -144.599005) (xy 250.712834 -144.624159)
			(xy 250.76023 -144.656801) (xy 250.781566 -144.676114) (xy 250.78944 -144.68348) (xy 250.809252 -144.690592)
			(xy 250.905518 -144.683226) (xy 250.924314 -144.67332) (xy 250.930918 -144.664938) (xy 250.949154 -144.642763)
			(xy 250.991086 -144.603551) (xy 251.03842 -144.571064) (xy 251.090085 -144.546034) (xy 251.144918 -144.529026)
			(xy 251.201679 -144.520423) (xy 251.230384 -144.519904) (xy 251.257637 -144.52037) (xy 251.311588 -144.528125)
			(xy 251.363887 -144.54348) (xy 251.413468 -144.566121) (xy 251.459322 -144.595589) (xy 251.500515 -144.631282)
			(xy 251.536209 -144.672475) (xy 251.565677 -144.718329) (xy 251.588319 -144.767909) (xy 251.603674 -144.820208)
			(xy 251.611429 -144.874159) (xy 251.611892 -144.901412) (xy 251.611444 -144.928315) (xy 251.603871 -144.981586)
			(xy 251.588889 -145.033265) (xy 251.566797 -145.082327) (xy 251.538032 -145.127799) (xy 251.503165 -145.16878)
			(xy 251.462887 -145.204457) (xy 251.440696 -145.219674) (xy 251.429774 -145.226786) (xy 251.417836 -145.249646)
			(xy 251.419868 -145.361914) (xy 251.432822 -145.384266) (xy 251.443998 -145.391124) (xy 251.467599 -145.406047)
			(xy 251.510551 -145.441725) (xy 251.547844 -145.483283) (xy 251.578682 -145.529833) (xy 251.602406 -145.58038)
			(xy 251.618508 -145.633846) (xy 251.626646 -145.689087) (xy 251.627132 -145.717006) (xy 251.626677 -145.744)
			(xy 251.61907 -145.797448) (xy 251.604009 -145.849292) (xy 251.581793 -145.898496) (xy 251.552867 -145.94408)
			(xy 251.535692 -145.96491) (xy 251.52858 -145.973038) (xy 251.522484 -145.993612) (xy 251.533406 -146.078956)
			(xy 251.535196 -146.089497) (xy 251.546239 -146.107781) (xy 251.554742 -146.114262) (xy 251.575947 -146.129649)
			(xy 251.614401 -146.16523) (xy 251.647622 -146.205741) (xy 251.674984 -146.250418) (xy 251.695972 -146.298421)
			(xy 251.71019 -146.348845) (xy 251.717371 -146.400741) (xy 251.71781 -146.426936) (xy 251.717324 -146.454187)
			(xy 251.709568 -146.508135) (xy 251.694213 -146.56043) (xy 251.671571 -146.610007) (xy 251.642105 -146.655857)
			(xy 251.606414 -146.697048) (xy 251.565223 -146.732739) (xy 251.519373 -146.762205) (xy 251.469796 -146.784847)
			(xy 251.417501 -146.800202) (xy 251.363553 -146.807958) (xy 251.309051 -146.807958) (xy 251.255103 -146.800202)
			(xy 251.202808 -146.784847) (xy 251.153231 -146.762205) (xy 251.107381 -146.732739) (xy 251.06619 -146.697048)
			(xy 251.030499 -146.655857) (xy 251.001033 -146.610007) (xy 250.978391 -146.56043) (xy 250.963036 -146.508135)
			(xy 250.95528 -146.454187) (xy 250.954794 -146.426936) (xy 250.955291 -146.399944) (xy 250.96289 -146.346498)
			(xy 250.977943 -146.294656) (xy 251.000149 -146.245451) (xy 251.029064 -146.199864) (xy 251.046234 -146.179032)
			(xy 251.053346 -146.170904) (xy 251.059442 -146.15033) (xy 251.04852 -146.064986) (xy 251.046749 -146.054441)
			(xy 251.035691 -146.036159) (xy 251.027184 -146.02968) (xy 251.002883 -146.012068) (xy 250.959624 -145.970472)
			(xy 250.941078 -145.946876) (xy 250.935236 -145.939002) (xy 250.91771 -145.928588) (xy 250.827286 -145.91538)
			(xy 250.807982 -145.920206) (xy 250.800108 -145.926048) (xy 250.799854 -145.926048) (xy 250.775111 -145.943553)
			(xy 250.721258 -145.971356) (xy 250.663686 -145.990292) (xy 250.603843 -145.999883) (xy 250.57354 -146.00047)
			(xy 250.546286 -146.000007) (xy 250.492333 -145.992255) (xy 250.440033 -145.976902) (xy 250.390451 -145.954261)
			(xy 250.344596 -145.924794) (xy 250.303401 -145.8891) (xy 250.267707 -145.847906) (xy 250.23824 -145.802051)
			(xy 250.215599 -145.752469) (xy 250.200246 -145.700168) (xy 250.192493 -145.646216) (xy 250.192032 -145.618962)
			(xy 250.192467 -145.592928) (xy 250.199559 -145.541345) (xy 250.213591 -145.491203) (xy 250.234305 -145.443433)
			(xy 250.261315 -145.398918) (xy 250.277376 -145.378424) (xy 250.283116 -145.370666) (xy 250.288858 -145.352256)
			(xy 250.288552 -145.34261) (xy 250.282202 -145.262854) (xy 250.273566 -145.245074) (xy 250.2662 -145.238724)
			(xy 250.246561 -145.220536) (xy 250.212035 -145.179632) (xy 250.183562 -145.134305) (xy 250.161703 -145.085445)
			(xy 250.146885 -145.034009) (xy 250.1394 -144.981008) (xy 250.138946 -144.954244) (xy 244.406511 -144.954244)
			(xy 244.420563 -145.002097) (xy 244.428321 -145.056047) (xy 244.428321 -145.110553) (xy 244.420563 -145.164503)
			(xy 244.405206 -145.216801) (xy 244.382563 -145.26638) (xy 244.353093 -145.312232) (xy 244.317398 -145.353423)
			(xy 244.276203 -145.389115) (xy 244.230349 -145.41858) (xy 244.180767 -145.441219) (xy 244.128468 -145.456571)
			(xy 244.074517 -145.464323) (xy 244.047264 -145.464784) (xy 244.020949 -145.464346) (xy 243.968819 -145.457106)
			(xy 243.918176 -145.442781) (xy 243.869977 -145.421643) (xy 243.825134 -145.394092) (xy 243.784496 -145.360648)
			(xy 243.76634 -145.341594) (xy 243.758806 -145.334207) (xy 243.739535 -145.325675) (xy 243.729002 -145.325084)
			(xy 243.654326 -145.325084) (xy 243.643777 -145.325619) (xy 243.624482 -145.334151) (xy 243.616988 -145.341594)
			(xy 243.59883 -145.360647) (xy 243.558201 -145.394105) (xy 243.513361 -145.421664) (xy 243.465161 -145.442803)
			(xy 243.414514 -145.457121) (xy 243.36238 -145.464346) (xy 243.336064 -145.464784) (xy 243.308813 -145.464344)
			(xy 243.254865 -145.456583) (xy 243.202572 -145.441223) (xy 243.152996 -145.418579) (xy 243.107147 -145.38911)
			(xy 243.065959 -145.353416) (xy 243.030269 -145.312224) (xy 243.000804 -145.266372) (xy 242.978164 -145.216794)
			(xy 242.96281 -145.164499) (xy 242.955054 -145.110551) (xy 238.725456 -145.110551) (xy 238.725456 -145.883884)
			(xy 238.7265 -145.89155) (xy 238.732578 -145.905769) (xy 238.737394 -145.911824) (xy 238.81461 -145.989294)
			(xy 239.222026 -146.39671) (xy 239.22863 -146.403568) (xy 239.37849 -146.553428) (xy 239.385333 -146.560828)
			(xy 239.393059 -146.579426) (xy 239.393476 -146.589496) (xy 239.393476 -146.91487) (xy 251.816106 -146.91487)
			(xy 251.820177 -146.859248) (xy 251.832303 -146.804811) (xy 251.852226 -146.75272) (xy 251.879522 -146.704085)
			(xy 251.913608 -146.659942) (xy 251.953757 -146.621233) (xy 251.999115 -146.588782) (xy 252.048715 -146.563281)
			(xy 252.101499 -146.545274) (xy 252.156342 -146.535144) (xy 252.212076 -146.533107) (xy 252.267513 -146.539207)
			(xy 252.32147 -146.553313) (xy 252.372799 -146.575125) (xy 252.420405 -146.604179) (xy 252.463273 -146.639854)
			(xy 252.50049 -146.681391) (xy 252.531263 -146.727904) (xy 252.554935 -146.778401) (xy 252.571003 -146.831808)
			(xy 252.579123 -146.886984) (xy 252.579632 -146.91487) (xy 252.579123 -146.942756) (xy 252.571003 -146.997932)
			(xy 252.554935 -147.051339) (xy 252.549729 -147.062444) (xy 253.19431 -147.062444) (xy 253.198381 -147.006822)
			(xy 253.210507 -146.952385) (xy 253.23043 -146.900294) (xy 253.257726 -146.851659) (xy 253.291812 -146.807516)
			(xy 253.331961 -146.768807) (xy 253.377319 -146.736356) (xy 253.426919 -146.710855) (xy 253.479703 -146.692848)
			(xy 253.534546 -146.682718) (xy 253.59028 -146.680681) (xy 253.645717 -146.686781) (xy 253.699674 -146.700887)
			(xy 253.751003 -146.722699) (xy 253.798609 -146.751753) (xy 253.841477 -146.787428) (xy 253.878694 -146.828965)
			(xy 253.909467 -146.875478) (xy 253.933139 -146.925975) (xy 253.949207 -146.979382) (xy 253.957327 -147.034558)
			(xy 253.957836 -147.062444) (xy 253.957327 -147.09033) (xy 253.949207 -147.145506) (xy 253.933139 -147.198913)
			(xy 253.909467 -147.24941) (xy 253.878694 -147.295923) (xy 253.841477 -147.33746) (xy 253.798609 -147.373135)
			(xy 253.751003 -147.402189) (xy 253.699674 -147.424001) (xy 253.645717 -147.438107) (xy 253.59028 -147.444207)
			(xy 253.534546 -147.44217) (xy 253.479703 -147.43204) (xy 253.426919 -147.414033) (xy 253.377319 -147.388532)
			(xy 253.331961 -147.356081) (xy 253.291812 -147.317372) (xy 253.257726 -147.273229) (xy 253.23043 -147.224594)
			(xy 253.210507 -147.172503) (xy 253.198381 -147.118066) (xy 253.19431 -147.062444) (xy 252.549729 -147.062444)
			(xy 252.531263 -147.101836) (xy 252.50049 -147.148349) (xy 252.463273 -147.189886) (xy 252.420405 -147.225561)
			(xy 252.372799 -147.254615) (xy 252.32147 -147.276427) (xy 252.267513 -147.290533) (xy 252.212076 -147.296633)
			(xy 252.156342 -147.294596) (xy 252.101499 -147.284466) (xy 252.048715 -147.266459) (xy 251.999115 -147.240958)
			(xy 251.953757 -147.208507) (xy 251.913608 -147.169798) (xy 251.879522 -147.125655) (xy 251.852226 -147.07702)
			(xy 251.832303 -147.024929) (xy 251.820177 -146.970492) (xy 251.816106 -146.91487) (xy 239.393476 -146.91487)
			(xy 239.393476 -147.657656) (xy 243.350443 -147.657656) (xy 243.350443 -147.603144) (xy 243.358201 -147.549188)
			(xy 243.37356 -147.496885) (xy 243.396206 -147.447301) (xy 243.425679 -147.401444) (xy 243.461379 -147.360249)
			(xy 243.502578 -147.324554) (xy 243.548437 -147.295086) (xy 243.598024 -147.272445) (xy 243.650329 -147.257092)
			(xy 243.704286 -147.24934) (xy 243.731542 -147.24888) (xy 243.757857 -147.249326) (xy 243.809986 -147.256566)
			(xy 243.860629 -147.27089) (xy 243.908827 -147.292026) (xy 243.95367 -147.319576) (xy 243.99431 -147.353017)
			(xy 244.012466 -147.37207) (xy 244.020002 -147.379454) (xy 244.039271 -147.38799) (xy 244.049804 -147.38858)
			(xy 244.12448 -147.38858) (xy 244.135031 -147.38806) (xy 244.154327 -147.379519) (xy 244.161818 -147.37207)
			(xy 244.181638 -147.351282) (xy 244.22641 -147.315307) (xy 244.276068 -147.286447) (xy 244.32949 -147.265354)
			(xy 244.385469 -147.252505) (xy 244.442742 -147.24819) (xy 244.500015 -147.252505) (xy 244.555994 -147.265354)
			(xy 244.609416 -147.286447) (xy 244.659074 -147.315307) (xy 244.703846 -147.351282) (xy 244.723666 -147.37207)
			(xy 244.731202 -147.379454) (xy 244.750471 -147.38799) (xy 244.761004 -147.38858) (xy 244.83568 -147.38858)
			(xy 244.846231 -147.38806) (xy 244.865527 -147.379519) (xy 244.873018 -147.37207) (xy 244.891166 -147.353007)
			(xy 244.931798 -147.319552) (xy 244.97664 -147.291994) (xy 245.024842 -147.270857) (xy 245.075491 -147.256542)
			(xy 245.127626 -147.249318) (xy 245.153942 -147.24888) (xy 245.18119 -147.249393) (xy 245.235132 -147.257154)
			(xy 245.28742 -147.272512) (xy 245.33699 -147.295155) (xy 245.382834 -147.324622) (xy 245.424018 -147.360312)
			(xy 245.459703 -147.4015) (xy 245.489165 -147.447347) (xy 245.511802 -147.49692) (xy 245.527155 -147.549209)
			(xy 245.53491 -147.603152) (xy 245.53491 -147.657648) (xy 245.527155 -147.711591) (xy 245.511802 -147.76388)
			(xy 245.489165 -147.813453) (xy 245.459703 -147.8593) (xy 245.424018 -147.900488) (xy 245.382834 -147.936178)
			(xy 245.33699 -147.965645) (xy 245.28742 -147.988288) (xy 245.235132 -148.003646) (xy 245.18119 -148.011407)
			(xy 245.153942 -148.011896) (xy 245.127627 -148.011469) (xy 245.075496 -148.004226) (xy 245.024853 -147.989899)
			(xy 244.976654 -147.968759) (xy 244.931811 -147.941206) (xy 244.891174 -147.907761) (xy 244.873018 -147.888706)
			(xy 244.865491 -147.881311) (xy 244.846215 -147.872783) (xy 244.83568 -147.872196) (xy 244.761004 -147.872196)
			(xy 244.750453 -147.872715) (xy 244.731158 -147.881257) (xy 244.723666 -147.888706) (xy 244.703846 -147.909494)
			(xy 244.659074 -147.945469) (xy 244.609416 -147.974329) (xy 244.555994 -147.995422) (xy 244.500015 -148.008271)
			(xy 244.442742 -148.012586) (xy 244.385469 -148.008271) (xy 244.32949 -147.995422) (xy 244.276068 -147.974329)
			(xy 244.22641 -147.945469) (xy 244.181638 -147.909494) (xy 244.161818 -147.888706) (xy 244.154291 -147.881311)
			(xy 244.135015 -147.872783) (xy 244.12448 -147.872196) (xy 244.049804 -147.872196) (xy 244.039253 -147.872715)
			(xy 244.019958 -147.881257) (xy 244.012466 -147.888706) (xy 243.994321 -147.907772) (xy 243.953689 -147.941228)
			(xy 243.908846 -147.968786) (xy 243.860644 -147.989922) (xy 243.809994 -148.004237) (xy 243.757859 -148.011459)
			(xy 243.731542 -148.011896) (xy 243.704286 -148.01146) (xy 243.650329 -148.003708) (xy 243.598024 -147.988355)
			(xy 243.548437 -147.965714) (xy 243.502578 -147.936246) (xy 243.461379 -147.900551) (xy 243.425679 -147.859356)
			(xy 243.396206 -147.813499) (xy 243.37356 -147.763915) (xy 243.358201 -147.711612) (xy 243.350443 -147.657656)
			(xy 239.393476 -147.657656) (xy 239.393476 -148.017738) (xy 248.177556 -148.017738) (xy 248.181627 -147.962116)
			(xy 248.193753 -147.907679) (xy 248.213676 -147.855588) (xy 248.240972 -147.806953) (xy 248.275058 -147.76281)
			(xy 248.315207 -147.724101) (xy 248.360565 -147.69165) (xy 248.410165 -147.666149) (xy 248.462949 -147.648142)
			(xy 248.517792 -147.638012) (xy 248.573526 -147.635975) (xy 248.628963 -147.642075) (xy 248.68292 -147.656181)
			(xy 248.734249 -147.677993) (xy 248.781855 -147.707047) (xy 248.823118 -147.741386) (xy 254.081532 -147.741386)
			(xy 254.085603 -147.685764) (xy 254.097729 -147.631327) (xy 254.117652 -147.579236) (xy 254.144948 -147.530601)
			(xy 254.179034 -147.486458) (xy 254.219183 -147.447749) (xy 254.264541 -147.415298) (xy 254.314141 -147.389797)
			(xy 254.366925 -147.37179) (xy 254.421768 -147.36166) (xy 254.477502 -147.359623) (xy 254.532939 -147.365723)
			(xy 254.586896 -147.379829) (xy 254.638225 -147.401641) (xy 254.685831 -147.430695) (xy 254.728699 -147.46637)
			(xy 254.765916 -147.507907) (xy 254.796689 -147.55442) (xy 254.820361 -147.604917) (xy 254.836429 -147.658324)
			(xy 254.844549 -147.7135) (xy 254.845058 -147.741386) (xy 254.844549 -147.769272) (xy 254.836429 -147.824448)
			(xy 254.820361 -147.877855) (xy 254.796689 -147.928352) (xy 254.765916 -147.974865) (xy 254.728699 -148.016402)
			(xy 254.685831 -148.052077) (xy 254.638225 -148.081131) (xy 254.586896 -148.102943) (xy 254.532939 -148.117049)
			(xy 254.477502 -148.123149) (xy 254.421768 -148.121112) (xy 254.366925 -148.110982) (xy 254.314141 -148.092975)
			(xy 254.264541 -148.067474) (xy 254.219183 -148.035023) (xy 254.179034 -147.996314) (xy 254.144948 -147.952171)
			(xy 254.117652 -147.903536) (xy 254.097729 -147.851445) (xy 254.085603 -147.797008) (xy 254.081532 -147.741386)
			(xy 248.823118 -147.741386) (xy 248.824723 -147.742722) (xy 248.86194 -147.784259) (xy 248.892713 -147.830772)
			(xy 248.916385 -147.881269) (xy 248.932453 -147.934676) (xy 248.940573 -147.989852) (xy 248.941082 -148.017738)
			(xy 248.940573 -148.045624) (xy 248.932453 -148.1008) (xy 248.916385 -148.154207) (xy 248.892713 -148.204704)
			(xy 248.86194 -148.251217) (xy 248.824723 -148.292754) (xy 248.781855 -148.328429) (xy 248.734249 -148.357483)
			(xy 248.68292 -148.379295) (xy 248.628963 -148.393401) (xy 248.573526 -148.399501) (xy 248.517792 -148.397464)
			(xy 248.462949 -148.387334) (xy 248.410165 -148.369327) (xy 248.360565 -148.343826) (xy 248.315207 -148.311375)
			(xy 248.275058 -148.272666) (xy 248.240972 -148.228523) (xy 248.213676 -148.179888) (xy 248.193753 -148.127797)
			(xy 248.181627 -148.07336) (xy 248.177556 -148.017738) (xy 239.393476 -148.017738) (xy 239.393476 -149.73046)
			(xy 239.394238 -149.738842) (xy 239.395743 -149.746453) (xy 239.402712 -149.760303) (xy 239.407954 -149.76602)
			(xy 239.473486 -149.831552) (xy 239.476534 -149.834346) (xy 239.48134 -149.838228) (xy 239.492389 -149.84375)
			(xy 239.498378 -149.845268) (xy 239.503926 -149.846304) (xy 239.515208 -149.846177) (xy 239.52073 -149.845014)
			(xy 239.53724 -149.840188) (xy 239.54232 -149.837394) (xy 239.564017 -149.825459) (xy 239.609832 -149.806668)
			(xy 239.657691 -149.793953) (xy 239.706791 -149.787525) (xy 239.73155 -149.787102) (xy 239.760032 -149.787626)
			(xy 239.816364 -149.796087) (xy 239.870813 -149.812827) (xy 239.922168 -149.837476) (xy 239.969289 -149.869485)
			(xy 240.011128 -149.908143) (xy 240.046755 -149.952591) (xy 240.075379 -150.001841) (xy 240.096363 -150.054799)
			(xy 240.109242 -150.110288) (xy 240.112042 -150.138638) (xy 240.113312 -150.154386) (xy 240.113566 -150.158704)
			(xy 240.12779 -150.171912) (xy 240.135078 -150.178202) (xy 240.152969 -150.185268) (xy 240.162588 -150.185628)
			(xy 243.300504 -150.185628) (xy 243.310112 -150.18521) (xy 243.327989 -150.178159) (xy 243.335302 -150.171912)
			(xy 243.349526 -150.158704) (xy 243.34978 -150.154386) (xy 243.35105 -150.138638) (xy 243.353819 -150.110278)
			(xy 243.366696 -150.054772) (xy 243.387679 -150.001795) (xy 243.416302 -149.952525) (xy 243.451928 -149.908056)
			(xy 243.493768 -149.869375) (xy 243.540891 -149.83734) (xy 243.592251 -149.812664) (xy 243.646708 -149.795895)
			(xy 243.703052 -149.787404) (xy 243.731542 -149.786848) (xy 243.757123 -149.787256) (xy 243.807827 -149.794085)
			(xy 243.857163 -149.807628) (xy 243.904247 -149.827643) (xy 243.948235 -149.85377) (xy 243.988336 -149.885541)
			(xy 244.00637 -149.903688) (xy 244.013228 -149.9108) (xy 244.039644 -149.922484) (xy 244.044484 -149.924487)
			(xy 244.054728 -149.926666) (xy 244.059964 -149.926802) (xy 244.106192 -149.926802) (xy 244.11559 -149.92604)
			(xy 244.133878 -149.922484) (xy 244.13972 -149.919944) (xy 244.15242 -149.914356) (xy 244.156706 -149.912343)
			(xy 244.164502 -149.906971) (xy 244.167914 -149.903688) (xy 244.16893 -149.902672) (xy 244.188657 -149.88307)
			(xy 244.232773 -149.849211) (xy 244.281337 -149.822115) (xy 244.33332 -149.802357) (xy 244.387621 -149.790356)
			(xy 244.443089 -149.786365) (xy 244.498549 -149.790469) (xy 244.552825 -149.802581) (xy 244.604768 -149.822444)
			(xy 244.653277 -149.849639) (xy 244.697323 -149.883587) (xy 244.717062 -149.90318) (xy 244.72392 -149.910546)
			(xy 244.750844 -149.922484) (xy 244.755684 -149.924487) (xy 244.765928 -149.926666) (xy 244.771164 -149.926802)
			(xy 244.820186 -149.926802) (xy 244.828568 -149.92604) (xy 244.844824 -149.922484) (xy 244.850158 -149.920198)
			(xy 244.872256 -149.9108) (xy 244.879368 -149.903434) (xy 244.897403 -149.885331) (xy 244.937477 -149.853624)
			(xy 244.981426 -149.827552) (xy 245.028463 -149.807583) (xy 245.077746 -149.794075) (xy 245.128392 -149.787269)
			(xy 245.153942 -149.786848) (xy 245.181209 -149.787337) (xy 245.235188 -149.795104) (xy 245.287512 -149.810473)
			(xy 245.337116 -149.833132) (xy 245.382991 -149.862619) (xy 245.424203 -149.898334) (xy 245.459912 -149.939551)
			(xy 245.489393 -149.98543) (xy 245.512045 -150.035037) (xy 245.520388 -150.063454) (xy 248.03811 -150.063454)
			(xy 248.042181 -150.007832) (xy 248.054307 -149.953395) (xy 248.07423 -149.901304) (xy 248.101526 -149.852669)
			(xy 248.135612 -149.808526) (xy 248.175761 -149.769817) (xy 248.221119 -149.737366) (xy 248.270719 -149.711865)
			(xy 248.323503 -149.693858) (xy 248.378346 -149.683728) (xy 248.43408 -149.681691) (xy 248.489517 -149.687791)
			(xy 248.543474 -149.701897) (xy 248.594803 -149.723709) (xy 248.642409 -149.752763) (xy 248.685277 -149.788438)
			(xy 248.722494 -149.829975) (xy 248.753267 -149.876488) (xy 248.776939 -149.926985) (xy 248.793007 -149.980392)
			(xy 248.801127 -150.035568) (xy 248.801636 -150.063454) (xy 248.801127 -150.09134) (xy 248.793007 -150.146516)
			(xy 248.776939 -150.199923) (xy 248.753267 -150.25042) (xy 248.722494 -150.296933) (xy 248.685277 -150.33847)
			(xy 248.642409 -150.374145) (xy 248.594803 -150.403199) (xy 248.543474 -150.425011) (xy 248.489517 -150.439117)
			(xy 248.43408 -150.445217) (xy 248.378346 -150.44318) (xy 248.323503 -150.43305) (xy 248.270719 -150.415043)
			(xy 248.221119 -150.389542) (xy 248.175761 -150.357091) (xy 248.135612 -150.318382) (xy 248.101526 -150.274239)
			(xy 248.07423 -150.225604) (xy 248.054307 -150.173513) (xy 248.042181 -150.119076) (xy 248.03811 -150.063454)
			(xy 245.520388 -150.063454) (xy 245.527407 -150.087363) (xy 245.535166 -150.141343) (xy 245.535704 -150.16861)
			(xy 245.53522 -150.196253) (xy 245.527255 -150.250963) (xy 245.511478 -150.30395) (xy 245.48822 -150.354107)
			(xy 245.457967 -150.400382) (xy 245.421353 -150.441807) (xy 245.379145 -150.477514) (xy 245.332226 -150.506757)
			(xy 245.281577 -150.528924) (xy 245.255034 -150.536656) (xy 245.240524 -150.541215) (xy 245.214865 -150.557514)
			(xy 245.195132 -150.580637) (xy 245.183071 -150.60854) (xy 245.179748 -150.638755) (xy 245.185456 -150.668613)
			(xy 245.199691 -150.695472) (xy 245.210076 -150.706582) (xy 246.174611 -151.67102) (xy 247.99366 -151.67102)
			(xy 247.997731 -151.615398) (xy 248.009857 -151.560961) (xy 248.02978 -151.50887) (xy 248.057076 -151.460235)
			(xy 248.091162 -151.416092) (xy 248.131311 -151.377383) (xy 248.176669 -151.344932) (xy 248.226269 -151.319431)
			(xy 248.279053 -151.301424) (xy 248.333896 -151.291294) (xy 248.38963 -151.289257) (xy 248.445067 -151.295357)
			(xy 248.499024 -151.309463) (xy 248.550353 -151.331275) (xy 248.597959 -151.360329) (xy 248.640827 -151.396004)
			(xy 248.678044 -151.437541) (xy 248.708817 -151.484054) (xy 248.732489 -151.534551) (xy 248.748557 -151.587958)
			(xy 248.756677 -151.643134) (xy 248.757186 -151.67102) (xy 248.756713 -151.696928) (xy 249.00966 -151.696928)
			(xy 249.013731 -151.641306) (xy 249.025857 -151.586869) (xy 249.04578 -151.534778) (xy 249.073076 -151.486143)
			(xy 249.107162 -151.442) (xy 249.147311 -151.403291) (xy 249.192669 -151.37084) (xy 249.242269 -151.345339)
			(xy 249.295053 -151.327332) (xy 249.349896 -151.317202) (xy 249.40563 -151.315165) (xy 249.461067 -151.321265)
			(xy 249.515024 -151.335371) (xy 249.566353 -151.357183) (xy 249.613959 -151.386237) (xy 249.638435 -151.406606)
			(xy 250.236734 -151.406606) (xy 250.240805 -151.350984) (xy 250.252931 -151.296547) (xy 250.272854 -151.244456)
			(xy 250.30015 -151.195821) (xy 250.334236 -151.151678) (xy 250.374385 -151.112969) (xy 250.419743 -151.080518)
			(xy 250.469343 -151.055017) (xy 250.522127 -151.03701) (xy 250.57697 -151.02688) (xy 250.632704 -151.024843)
			(xy 250.688141 -151.030943) (xy 250.742098 -151.045049) (xy 250.793427 -151.066861) (xy 250.841033 -151.095915)
			(xy 250.883901 -151.13159) (xy 250.921118 -151.173127) (xy 250.951891 -151.21964) (xy 250.975563 -151.270137)
			(xy 250.991631 -151.323544) (xy 250.999751 -151.37872) (xy 251.00026 -151.406606) (xy 250.999751 -151.434492)
			(xy 250.991631 -151.489668) (xy 250.975563 -151.543075) (xy 250.957021 -151.582628) (xy 251.56236 -151.582628)
			(xy 251.566431 -151.527006) (xy 251.578557 -151.472569) (xy 251.59848 -151.420478) (xy 251.625776 -151.371843)
			(xy 251.659862 -151.3277) (xy 251.700011 -151.288991) (xy 251.745369 -151.25654) (xy 251.794969 -151.231039)
			(xy 251.847753 -151.213032) (xy 251.902596 -151.202902) (xy 251.95833 -151.200865) (xy 252.013767 -151.206965)
			(xy 252.067724 -151.221071) (xy 252.119053 -151.242883) (xy 252.166659 -151.271937) (xy 252.209527 -151.307612)
			(xy 252.246744 -151.349149) (xy 252.277517 -151.395662) (xy 252.301189 -151.446159) (xy 252.317257 -151.499566)
			(xy 252.325377 -151.554742) (xy 252.32564 -151.569166) (xy 253.07366 -151.569166) (xy 253.077731 -151.513544)
			(xy 253.089857 -151.459107) (xy 253.10978 -151.407016) (xy 253.137076 -151.358381) (xy 253.171162 -151.314238)
			(xy 253.211311 -151.275529) (xy 253.256669 -151.243078) (xy 253.306269 -151.217577) (xy 253.359053 -151.19957)
			(xy 253.413896 -151.18944) (xy 253.46963 -151.187403) (xy 253.525067 -151.193503) (xy 253.579024 -151.207609)
			(xy 253.630353 -151.229421) (xy 253.677959 -151.258475) (xy 253.720827 -151.29415) (xy 253.758044 -151.335687)
			(xy 253.788817 -151.3822) (xy 253.812489 -151.432697) (xy 253.828557 -151.486104) (xy 253.836677 -151.54128)
			(xy 253.837186 -151.569166) (xy 253.836677 -151.597052) (xy 253.828557 -151.652228) (xy 253.812489 -151.705635)
			(xy 253.788817 -151.756132) (xy 253.758044 -151.802645) (xy 253.720827 -151.844182) (xy 253.677959 -151.879857)
			(xy 253.630353 -151.908911) (xy 253.579024 -151.930723) (xy 253.525067 -151.944829) (xy 253.46963 -151.950929)
			(xy 253.413896 -151.948892) (xy 253.359053 -151.938762) (xy 253.306269 -151.920755) (xy 253.256669 -151.895254)
			(xy 253.211311 -151.862803) (xy 253.171162 -151.824094) (xy 253.137076 -151.779951) (xy 253.10978 -151.731316)
			(xy 253.089857 -151.679225) (xy 253.077731 -151.624788) (xy 253.07366 -151.569166) (xy 252.32564 -151.569166)
			(xy 252.325886 -151.582628) (xy 252.325377 -151.610514) (xy 252.317257 -151.66569) (xy 252.301189 -151.719097)
			(xy 252.277517 -151.769594) (xy 252.246744 -151.816107) (xy 252.209527 -151.857644) (xy 252.166659 -151.893319)
			(xy 252.119053 -151.922373) (xy 252.067724 -151.944185) (xy 252.013767 -151.958291) (xy 251.95833 -151.964391)
			(xy 251.902596 -151.962354) (xy 251.847753 -151.952224) (xy 251.794969 -151.934217) (xy 251.745369 -151.908716)
			(xy 251.700011 -151.876265) (xy 251.659862 -151.837556) (xy 251.625776 -151.793413) (xy 251.59848 -151.744778)
			(xy 251.578557 -151.692687) (xy 251.566431 -151.63825) (xy 251.56236 -151.582628) (xy 250.957021 -151.582628)
			(xy 250.951891 -151.593572) (xy 250.921118 -151.640085) (xy 250.883901 -151.681622) (xy 250.841033 -151.717297)
			(xy 250.793427 -151.746351) (xy 250.742098 -151.768163) (xy 250.688141 -151.782269) (xy 250.632704 -151.788369)
			(xy 250.57697 -151.786332) (xy 250.522127 -151.776202) (xy 250.469343 -151.758195) (xy 250.419743 -151.732694)
			(xy 250.374385 -151.700243) (xy 250.334236 -151.661534) (xy 250.30015 -151.617391) (xy 250.272854 -151.568756)
			(xy 250.252931 -151.516665) (xy 250.240805 -151.462228) (xy 250.236734 -151.406606) (xy 249.638435 -151.406606)
			(xy 249.656827 -151.421912) (xy 249.694044 -151.463449) (xy 249.724817 -151.509962) (xy 249.748489 -151.560459)
			(xy 249.764557 -151.613866) (xy 249.772677 -151.669042) (xy 249.773186 -151.696928) (xy 249.772677 -151.724814)
			(xy 249.764557 -151.77999) (xy 249.748489 -151.833397) (xy 249.724817 -151.883894) (xy 249.694044 -151.930407)
			(xy 249.656827 -151.971944) (xy 249.613959 -152.007619) (xy 249.566353 -152.036673) (xy 249.515024 -152.058485)
			(xy 249.461067 -152.072591) (xy 249.40563 -152.078691) (xy 249.349896 -152.076654) (xy 249.295053 -152.066524)
			(xy 249.242269 -152.048517) (xy 249.192669 -152.023016) (xy 249.147311 -151.990565) (xy 249.107162 -151.951856)
			(xy 249.073076 -151.907713) (xy 249.04578 -151.859078) (xy 249.025857 -151.806987) (xy 249.013731 -151.75255)
			(xy 249.00966 -151.696928) (xy 248.756713 -151.696928) (xy 248.756677 -151.698906) (xy 248.748557 -151.754082)
			(xy 248.732489 -151.807489) (xy 248.708817 -151.857986) (xy 248.678044 -151.904499) (xy 248.640827 -151.946036)
			(xy 248.597959 -151.981711) (xy 248.550353 -152.010765) (xy 248.499024 -152.032577) (xy 248.445067 -152.046683)
			(xy 248.38963 -152.052783) (xy 248.333896 -152.050746) (xy 248.279053 -152.040616) (xy 248.226269 -152.022609)
			(xy 248.176669 -151.997108) (xy 248.131311 -151.964657) (xy 248.091162 -151.925948) (xy 248.057076 -151.881805)
			(xy 248.02978 -151.83317) (xy 248.009857 -151.781079) (xy 247.997731 -151.726642) (xy 247.99366 -151.67102)
			(xy 246.174611 -151.67102) (xy 247.728994 -153.225246) (xy 247.736908 -153.232335) (xy 247.756722 -153.239937)
			(xy 247.767348 -153.239978) (xy 247.776565 -153.239126) (xy 247.793508 -153.231712) (xy 247.800368 -153.2255)
			(xy 247.814338 -153.211784) (xy 247.814592 -153.21153) (xy 247.822 -153.204841) (xy 247.840436 -153.197251)
			(xy 247.850406 -153.196798) (xy 248.062496 -153.196798) (xy 248.071894 -153.196544) (xy 248.375678 -153.196544)
			(xy 248.41117 -153.197067) (xy 248.481633 -153.205652) (xy 248.550542 -153.222686) (xy 248.61689 -153.24792)
			(xy 248.679703 -153.280984) (xy 248.738061 -153.321394) (xy 248.791111 -153.368558) (xy 248.838074 -153.421786)
			(xy 248.878263 -153.480297) (xy 248.911089 -153.543235) (xy 248.924064 -153.576274) (xy 248.924064 -153.576782)
			(xy 248.926712 -153.583063) (xy 248.934829 -153.594008) (xy 248.940066 -153.598372) (xy 248.945515 -153.602449)
			(xy 248.958004 -153.607842) (xy 248.964704 -153.60904) (xy 249.040904 -153.619454) (xy 249.047612 -153.620189)
			(xy 249.060998 -153.618512) (xy 249.06732 -153.616152) (xy 249.073416 -153.613612) (xy 249.08383 -153.605738)
			(xy 249.088148 -153.60015) (xy 249.10635 -153.577248) (xy 249.148538 -153.536725) (xy 249.196408 -153.503104)
			(xy 249.248843 -153.477171) (xy 249.304618 -153.459532) (xy 249.362429 -153.450599) (xy 249.391678 -153.450036)
			(xy 249.41895 -153.450498) (xy 249.472939 -153.458258) (xy 249.525275 -153.473622) (xy 249.574891 -153.496278)
			(xy 249.620777 -153.525765) (xy 249.662 -153.561483) (xy 249.69772 -153.602703) (xy 249.72721 -153.648588)
			(xy 249.74987 -153.698203) (xy 249.765237 -153.750537) (xy 249.769836 -153.782522) (xy 252.05766 -153.782522)
			(xy 252.061731 -153.7269) (xy 252.073857 -153.672463) (xy 252.09378 -153.620372) (xy 252.121076 -153.571737)
			(xy 252.155162 -153.527594) (xy 252.195311 -153.488885) (xy 252.240669 -153.456434) (xy 252.290269 -153.430933)
			(xy 252.343053 -153.412926) (xy 252.397896 -153.402796) (xy 252.45363 -153.400759) (xy 252.509067 -153.406859)
			(xy 252.563024 -153.420965) (xy 252.614353 -153.442777) (xy 252.661959 -153.471831) (xy 252.704827 -153.507506)
			(xy 252.742044 -153.549043) (xy 252.772817 -153.595556) (xy 252.796489 -153.646053) (xy 252.812557 -153.69946)
			(xy 252.820677 -153.754636) (xy 252.821186 -153.782522) (xy 254.08966 -153.782522) (xy 254.093731 -153.7269)
			(xy 254.105857 -153.672463) (xy 254.12578 -153.620372) (xy 254.153076 -153.571737) (xy 254.187162 -153.527594)
			(xy 254.227311 -153.488885) (xy 254.272669 -153.456434) (xy 254.322269 -153.430933) (xy 254.375053 -153.412926)
			(xy 254.429896 -153.402796) (xy 254.48563 -153.400759) (xy 254.541067 -153.406859) (xy 254.595024 -153.420965)
			(xy 254.646353 -153.442777) (xy 254.693959 -153.471831) (xy 254.736827 -153.507506) (xy 254.774044 -153.549043)
			(xy 254.804817 -153.595556) (xy 254.828489 -153.646053) (xy 254.844557 -153.69946) (xy 254.852677 -153.754636)
			(xy 254.853186 -153.782522) (xy 254.852677 -153.810408) (xy 254.844557 -153.865584) (xy 254.828489 -153.918991)
			(xy 254.804817 -153.969488) (xy 254.774044 -154.016001) (xy 254.736827 -154.057538) (xy 254.693959 -154.093213)
			(xy 254.646353 -154.122267) (xy 254.595024 -154.144079) (xy 254.541067 -154.158185) (xy 254.48563 -154.164285)
			(xy 254.429896 -154.162248) (xy 254.375053 -154.152118) (xy 254.322269 -154.134111) (xy 254.272669 -154.10861)
			(xy 254.227311 -154.076159) (xy 254.187162 -154.03745) (xy 254.153076 -153.993307) (xy 254.12578 -153.944672)
			(xy 254.105857 -153.892581) (xy 254.093731 -153.838144) (xy 254.08966 -153.782522) (xy 252.821186 -153.782522)
			(xy 252.820677 -153.810408) (xy 252.812557 -153.865584) (xy 252.796489 -153.918991) (xy 252.772817 -153.969488)
			(xy 252.742044 -154.016001) (xy 252.704827 -154.057538) (xy 252.661959 -154.093213) (xy 252.614353 -154.122267)
			(xy 252.563024 -154.144079) (xy 252.509067 -154.158185) (xy 252.45363 -154.164285) (xy 252.397896 -154.162248)
			(xy 252.343053 -154.152118) (xy 252.290269 -154.134111) (xy 252.240669 -154.10861) (xy 252.195311 -154.076159)
			(xy 252.155162 -154.03745) (xy 252.121076 -153.993307) (xy 252.09378 -153.944672) (xy 252.073857 -153.892581)
			(xy 252.061731 -153.838144) (xy 252.05766 -153.782522) (xy 249.769836 -153.782522) (xy 249.773 -153.804526)
			(xy 249.77344 -153.831798) (xy 249.77217 -153.86431) (xy 249.77217 -153.864564) (xy 249.771154 -153.873962)
			(xy 249.766074 -153.90876) (xy 249.760251 -153.936056) (xy 249.741762 -153.988716) (xy 249.729244 -154.013662)
			(xy 249.72645 -154.018996) (xy 249.724926 -154.025092) (xy 249.723656 -154.032458) (xy 249.723656 -154.139646)
			(xy 249.723402 -154.148282) (xy 249.723402 -154.255978) (xy 249.722964 -154.266042) (xy 249.71523 -154.284626)
			(xy 249.708416 -154.292046) (xy 249.63247 -154.367992) (xy 249.626374 -154.374342) (xy 248.69902 -155.301696)
			(xy 248.69267 -155.307792) (xy 248.601738 -155.398724) (xy 248.587768 -155.398724) (xy 248.570496 -155.415996)
			(xy 248.552311 -155.433456) (xy 248.511515 -155.463066) (xy 248.466598 -155.485949) (xy 248.418661 -155.501543)
			(xy 248.368878 -155.509466) (xy 248.343674 -155.509976) (xy 247.402604 -155.509976) (xy 247.377403 -155.509441)
			(xy 247.32763 -155.501498) (xy 247.279702 -155.485898) (xy 247.234789 -155.463022) (xy 247.193988 -155.433429)
			(xy 247.175782 -155.415996) (xy 247.173242 -155.413456) (xy 247.169432 -155.410154) (xy 247.162468 -155.404957)
			(xy 247.146109 -155.399128) (xy 247.137428 -155.398724) (xy 247.050814 -155.398724) (xy 247.040764 -155.398217)
			(xy 247.022205 -155.390494) (xy 247.014746 -155.383738) (xy 246.9388 -155.307792) (xy 246.93245 -155.301696)
			(xy 246.258334 -154.62758) (xy 246.250858 -154.621682) (xy 246.232885 -154.615429) (xy 246.213872 -154.616197)
			(xy 246.196462 -154.623877) (xy 246.1895 -154.630374) (xy 246.186706 -154.633168) (xy 246.173752 -154.646376)
			(xy 246.16664 -154.653234) (xy 246.154956 -154.679904) (xy 246.150638 -154.68981) (xy 246.150638 -154.748992)
			(xy 246.1514 -154.757374) (xy 246.154956 -154.77363) (xy 246.157242 -154.778964) (xy 246.16664 -154.801062)
			(xy 246.174006 -154.808174) (xy 246.192111 -154.826208) (xy 246.223823 -154.86628) (xy 246.249898 -154.910229)
			(xy 246.269869 -154.957266) (xy 246.283379 -155.00655) (xy 246.290185 -155.057197) (xy 246.290592 -155.082748)
			(xy 246.290102 -155.110016) (xy 246.282335 -155.163996) (xy 246.266966 -155.216321) (xy 246.244308 -155.265927)
			(xy 246.214821 -155.311804) (xy 246.179106 -155.353019) (xy 246.13789 -155.388732) (xy 246.092012 -155.418216)
			(xy 246.042405 -155.440872) (xy 245.990078 -155.456239) (xy 245.936098 -155.464004) (xy 245.90883 -155.46451)
			(xy 245.88325 -155.4641) (xy 245.832549 -155.457267) (xy 245.783216 -155.44372) (xy 245.736136 -155.423701)
			(xy 245.692153 -155.39757) (xy 245.652057 -155.365795) (xy 245.634002 -155.34767) (xy 245.627144 -155.340558)
			(xy 245.600474 -155.328874) (xy 245.590568 -155.324556) (xy 245.532656 -155.324556) (xy 245.523004 -155.325572)
			(xy 245.506494 -155.32862) (xy 245.500906 -155.33116) (xy 245.479316 -155.340558) (xy 245.472204 -155.347924)
			(xy 245.454169 -155.366027) (xy 245.414096 -155.397735) (xy 245.370147 -155.423807) (xy 245.323109 -155.443774)
			(xy 245.273826 -155.457281) (xy 245.22318 -155.464083) (xy 245.19763 -155.46451) (xy 245.172112 -155.464079)
			(xy 245.121534 -155.457269) (xy 245.072313 -155.44378) (xy 245.025329 -155.423853) (xy 244.98142 -155.397842)
			(xy 244.941368 -155.366213) (xy 244.92331 -155.348178) (xy 244.916452 -155.340812) (xy 244.889274 -155.328874)
			(xy 244.879368 -155.324556) (xy 244.821456 -155.324556) (xy 244.811804 -155.325572) (xy 244.795294 -155.32862)
			(xy 244.789706 -155.33116) (xy 244.768116 -155.340558) (xy 244.761004 -155.347924) (xy 244.742969 -155.366027)
			(xy 244.702896 -155.397735) (xy 244.658947 -155.423807) (xy 244.611909 -155.443774) (xy 244.562626 -155.457281)
			(xy 244.51198 -155.464083) (xy 244.48643 -155.46451) (xy 244.460912 -155.464079) (xy 244.410334 -155.457269)
			(xy 244.361113 -155.44378) (xy 244.314129 -155.423853) (xy 244.27022 -155.397842) (xy 244.230168 -155.366213)
			(xy 244.21211 -155.348178) (xy 244.205252 -155.340812) (xy 244.178074 -155.328874) (xy 244.168168 -155.324556)
			(xy 244.110764 -155.324556) (xy 244.103144 -155.325318) (xy 244.089936 -155.327604) (xy 244.08384 -155.32862)
			(xy 244.056916 -155.340558) (xy 244.050058 -155.34767) (xy 244.032009 -155.3658) (xy 243.991904 -155.397562)
			(xy 243.947918 -155.423685) (xy 243.900838 -155.443702) (xy 243.851508 -155.457256) (xy 243.800809 -155.464102)
			(xy 243.77523 -155.46451) (xy 243.747958 -155.464026) (xy 243.693969 -155.456268) (xy 243.641633 -155.440905)
			(xy 243.592016 -155.418252) (xy 243.546128 -155.388767) (xy 243.504902 -155.353053) (xy 243.469179 -155.311835)
			(xy 243.439686 -155.265953) (xy 243.417022 -155.21634) (xy 243.401649 -155.164008) (xy 243.39388 -155.11002)
			(xy 243.393468 -155.082748) (xy 243.393876 -155.057168) (xy 243.400707 -155.006465) (xy 243.414252 -154.957129)
			(xy 243.434268 -154.910047) (xy 243.460397 -154.866061) (xy 243.49217 -154.825962) (xy 243.510308 -154.80792)
			(xy 243.51742 -154.801062) (xy 243.529104 -154.774646) (xy 243.531106 -154.769806) (xy 243.533281 -154.759562)
			(xy 243.533422 -154.754326) (xy 243.533422 -154.707082) (xy 243.53266 -154.699462) (xy 243.530374 -154.686254)
			(xy 243.529358 -154.680158) (xy 243.51742 -154.653234) (xy 243.510308 -154.646376) (xy 243.492178 -154.628327)
			(xy 243.460416 -154.588222) (xy 243.434293 -154.544236) (xy 243.414274 -154.497156) (xy 243.400719 -154.447826)
			(xy 243.393871 -154.397127) (xy 243.393468 -154.371548) (xy 243.393928 -154.344276) (xy 243.401685 -154.290285)
			(xy 243.417047 -154.237948) (xy 243.439703 -154.188331) (xy 243.469189 -154.142444) (xy 243.504907 -154.10122)
			(xy 243.546129 -154.0655) (xy 243.592015 -154.036011) (xy 243.641631 -154.013354) (xy 243.693967 -153.997989)
			(xy 243.747958 -153.99023) (xy 243.77523 -153.989786) (xy 243.800811 -153.990193) (xy 243.851515 -153.997022)
			(xy 243.900851 -154.010565) (xy 243.947935 -154.03058) (xy 243.991922 -154.056708) (xy 244.032022 -154.088481)
			(xy 244.050058 -154.106626) (xy 244.056916 -154.113738) (xy 244.083332 -154.125422) (xy 244.088172 -154.127425)
			(xy 244.098416 -154.129604) (xy 244.103652 -154.12974) (xy 244.14988 -154.12974) (xy 244.159278 -154.128978)
			(xy 244.177566 -154.125422) (xy 244.183408 -154.122882) (xy 244.196108 -154.117294) (xy 244.200396 -154.115283)
			(xy 244.208196 -154.109916) (xy 244.211602 -154.106626) (xy 244.212618 -154.10561) (xy 244.232345 -154.086005)
			(xy 244.276459 -154.052142) (xy 244.325024 -154.025042) (xy 244.377008 -154.00528) (xy 244.43131 -153.993276)
			(xy 244.486781 -153.989283) (xy 244.542243 -153.993386) (xy 244.596521 -154.005499) (xy 244.648466 -154.025364)
			(xy 244.696976 -154.05256) (xy 244.741023 -154.086512) (xy 244.76075 -154.106118) (xy 244.767608 -154.113484)
			(xy 244.794532 -154.125422) (xy 244.799372 -154.127425) (xy 244.809616 -154.129604) (xy 244.814852 -154.12974)
			(xy 244.86108 -154.12974) (xy 244.870478 -154.128978) (xy 244.888766 -154.125422) (xy 244.894608 -154.122882)
			(xy 244.907308 -154.117294) (xy 244.911596 -154.115283) (xy 244.919396 -154.109916) (xy 244.922802 -154.106626)
			(xy 244.923818 -154.10561) (xy 244.943545 -154.086005) (xy 244.987659 -154.052142) (xy 245.036224 -154.025042)
			(xy 245.088208 -154.00528) (xy 245.14251 -153.993276) (xy 245.197981 -153.989283) (xy 245.253443 -153.993386)
			(xy 245.307721 -154.005499) (xy 245.359666 -154.025364) (xy 245.408176 -154.05256) (xy 245.452223 -154.086512)
			(xy 245.47195 -154.106118) (xy 245.478808 -154.113484) (xy 245.505732 -154.125422) (xy 245.510572 -154.127425)
			(xy 245.520816 -154.129604) (xy 245.526052 -154.12974) (xy 245.575074 -154.12974) (xy 245.583456 -154.128978)
			(xy 245.599712 -154.125422) (xy 245.605046 -154.123136) (xy 245.627144 -154.113738) (xy 245.63451 -154.106118)
			(xy 245.641729 -154.098716) (xy 245.65685 -154.084611) (xy 245.664736 -154.077924) (xy 245.67261 -154.07132)
			(xy 245.686326 -154.044904) (xy 245.688641 -154.040122) (xy 245.691451 -154.029877) (xy 245.691914 -154.024584)
			(xy 245.694962 -153.975308) (xy 245.694962 -153.974292) (xy 245.695724 -153.958036) (xy 245.695504 -153.947733)
			(xy 245.687901 -153.928598) (xy 245.680992 -153.920952) (xy 243.896896 -152.136856) (xy 243.893165 -152.133335)
			(xy 243.88459 -152.127707) (xy 243.879878 -152.12568) (xy 243.871242 -152.122124) (xy 238.999268 -152.122124)
			(xy 238.9892 -152.121696) (xy 238.970602 -152.113976) (xy 238.9632 -152.107138) (xy 238.887254 -152.031192)
			(xy 238.880904 -152.025096) (xy 237.800642 -150.94458) (xy 237.793047 -150.937587) (xy 237.773931 -150.929844)
			(xy 237.753312 -150.930289) (xy 237.743746 -150.934166) (xy 237.657132 -150.973028) (xy 237.647941 -150.977641)
			(xy 237.633957 -150.992693) (xy 237.626996 -151.012024) (xy 237.62716 -151.022304) (xy 237.62716 -151.022558)
			(xy 237.628176 -151.050498) (xy 237.628176 -151.914098) (xy 237.627686 -151.944082) (xy 237.619858 -152.003538)
			(xy 237.604337 -152.061463) (xy 237.581388 -152.116867) (xy 237.551404 -152.168801) (xy 237.514898 -152.216377)
			(xy 237.472493 -152.258782) (xy 237.424917 -152.295288) (xy 237.372983 -152.325272) (xy 237.317579 -152.348221)
			(xy 237.259654 -152.363742) (xy 237.200198 -152.37157) (xy 237.14023 -152.37157) (xy 237.080774 -152.363742)
			(xy 237.022849 -152.348221) (xy 236.967445 -152.325272) (xy 236.915511 -152.295288) (xy 236.867935 -152.258782)
			(xy 236.82553 -152.216377) (xy 236.789024 -152.168801) (xy 236.75904 -152.116867) (xy 236.736091 -152.061463)
			(xy 236.72057 -152.003538) (xy 236.712742 -151.944082) (xy 236.712252 -151.914098) (xy 236.712252 -151.050498)
			(xy 236.712721 -151.020513) (xy 236.720549 -150.961055) (xy 236.736071 -150.903128) (xy 236.759022 -150.847723)
			(xy 236.789008 -150.795788) (xy 236.825516 -150.74821) (xy 236.867922 -150.705806) (xy 236.915501 -150.669299)
			(xy 236.967438 -150.639315) (xy 237.022844 -150.616366) (xy 237.080771 -150.600846) (xy 237.140229 -150.59302)
			(xy 237.170214 -150.592536) (xy 237.201327 -150.593078) (xy 237.262977 -150.601537) (xy 237.322916 -150.618257)
			(xy 237.380043 -150.642931) (xy 237.406942 -150.658576) (xy 237.419134 -150.664164) (xy 237.4392 -150.669752)
			(xy 237.449597 -150.669241) (xy 237.468682 -150.660982) (xy 237.482948 -150.645852) (xy 237.49007 -150.626314)
			(xy 237.49 -150.615904) (xy 237.49 -150.204932) (xy 237.489333 -150.192284) (xy 237.477347 -150.17001)
			(xy 237.46714 -150.162514) (xy 237.385352 -150.108412) (xy 237.359952 -150.10638) (xy 237.348014 -150.11146)
			(xy 237.319264 -150.123316) (xy 237.259363 -150.140033) (xy 237.197752 -150.148494) (xy 237.166658 -150.149052)
			(xy 237.16615 -150.149052) (xy 237.136179 -150.148559) (xy 237.076749 -150.140732) (xy 237.018849 -150.125218)
			(xy 236.963468 -150.102281) (xy 236.911553 -150.072315) (xy 236.863991 -150.035832) (xy 236.821596 -149.993455)
			(xy 236.785093 -149.945909) (xy 236.755105 -149.894006) (xy 236.732145 -149.838635) (xy 236.716606 -149.780741)
			(xy 236.708753 -149.721315) (xy 236.708188 -149.691344) (xy 236.708188 -148.827744) (xy 236.708655 -148.797762)
			(xy 236.716479 -148.738312) (xy 236.731999 -148.680392) (xy 236.75495 -148.624995) (xy 236.784938 -148.573069)
			(xy 236.821449 -148.525504) (xy 236.863859 -148.483113) (xy 236.911441 -148.446623) (xy 236.96338 -148.416659)
			(xy 237.018788 -148.393733) (xy 237.076714 -148.378239) (xy 237.136168 -148.370442) (xy 237.16615 -148.370036)
			(xy 237.197332 -148.370541) (xy 237.259122 -148.378969) (xy 237.319193 -148.395717) (xy 237.348014 -148.407628)
			(xy 237.359952 -148.412708) (xy 237.385352 -148.410676) (xy 237.46714 -148.356574) (xy 237.477336 -148.349061)
			(xy 237.489353 -148.326803) (xy 237.49 -148.314156) (xy 237.49 -147.418552) (xy 237.489647 -147.409863)
			(xy 237.483794 -147.393501) (xy 237.47857 -147.386548) (xy 237.475268 -147.382738) (xy 237.02772 -146.93519)
			(xy 237.019808 -146.928095) (xy 236.999993 -146.920481) (xy 236.989366 -146.920458) (xy 236.978952 -146.92122)
			(xy 236.974676 -146.921738) (xy 236.966378 -146.924043) (xy 236.962442 -146.925792) (xy 236.945424 -146.934682)
			(xy 236.94136 -146.936968) (xy 236.927644 -146.94789) (xy 236.924088 -146.952208) (xy 236.923834 -146.952208)
			(xy 236.922818 -146.953478) (xy 236.904611 -146.973972) (xy 236.863328 -147.01004) (xy 236.817308 -147.039828)
			(xy 236.767498 -147.062721) (xy 236.714923 -147.078248) (xy 236.660668 -147.086089) (xy 236.633258 -147.086574)
			(xy 236.60599 -147.086085) (xy 236.552009 -147.078318) (xy 236.499683 -147.062948) (xy 236.450076 -147.040289)
			(xy 236.404199 -147.010801) (xy 236.362985 -146.975085) (xy 236.327274 -146.933867) (xy 236.297791 -146.887987)
			(xy 236.275137 -146.838378) (xy 236.259773 -146.78605) (xy 236.252012 -146.732068) (xy 236.252012 -146.677532)
			(xy 236.259773 -146.62355) (xy 236.275137 -146.571222) (xy 236.297791 -146.521613) (xy 236.327274 -146.475733)
			(xy 236.362985 -146.434515) (xy 236.404199 -146.398799) (xy 236.450076 -146.369311) (xy 236.499683 -146.346652)
			(xy 236.552009 -146.331282) (xy 236.60599 -146.323515) (xy 236.633258 -146.32305) (xy 236.65694 -146.323404)
			(xy 236.703941 -146.329259) (xy 236.726984 -146.334734) (xy 236.742064 -146.337995) (xy 236.772855 -146.336299)
			(xy 236.801741 -146.325502) (xy 236.826095 -146.306585) (xy 236.843703 -146.281268) (xy 236.852964 -146.251854)
			(xy 236.853476 -146.236436) (xy 236.853476 -146.157188) (xy 236.852895 -146.14178) (xy 236.843627 -146.112388)
			(xy 236.826027 -146.08709) (xy 236.801692 -146.06818) (xy 236.77283 -146.057375) (xy 236.74206 -146.055655)
			(xy 236.726984 -146.05889) (xy 236.703939 -146.064355) (xy 236.656939 -146.070209) (xy 236.633258 -146.070574)
			(xy 236.60599 -146.070085) (xy 236.552009 -146.062318) (xy 236.499683 -146.046948) (xy 236.450076 -146.024289)
			(xy 236.404199 -145.994801) (xy 236.362985 -145.959085) (xy 236.327274 -145.917867) (xy 236.297791 -145.871987)
			(xy 236.275137 -145.822378) (xy 236.259773 -145.77005) (xy 236.252012 -145.716068) (xy 236.252012 -145.661532)
			(xy 236.259773 -145.60755) (xy 236.275137 -145.555222) (xy 236.297791 -145.505613) (xy 236.327274 -145.459733)
			(xy 236.362985 -145.418515) (xy 236.404199 -145.382799) (xy 236.450076 -145.353311) (xy 236.499683 -145.330652)
			(xy 236.552009 -145.315282) (xy 236.60599 -145.307515) (xy 236.633258 -145.30705) (xy 236.65694 -145.307404)
			(xy 236.703941 -145.313259) (xy 236.726984 -145.318734) (xy 236.742064 -145.321995) (xy 236.772855 -145.320299)
			(xy 236.801741 -145.309502) (xy 236.826095 -145.290585) (xy 236.843703 -145.265268) (xy 236.852964 -145.235854)
			(xy 236.853476 -145.220436) (xy 236.853476 -145.141188) (xy 236.852895 -145.12578) (xy 236.843627 -145.096388)
			(xy 236.826027 -145.07109) (xy 236.801692 -145.05218) (xy 236.77283 -145.041375) (xy 236.74206 -145.039655)
			(xy 236.726984 -145.04289) (xy 236.703939 -145.048355) (xy 236.656939 -145.054209) (xy 236.633258 -145.054574)
			(xy 236.60599 -145.054085) (xy 236.552009 -145.046318) (xy 236.499683 -145.030948) (xy 236.450076 -145.008289)
			(xy 236.404199 -144.978801) (xy 236.362985 -144.943085) (xy 236.327274 -144.901867) (xy 236.297791 -144.855987)
			(xy 236.275137 -144.806378) (xy 236.259773 -144.75405) (xy 236.252012 -144.700068) (xy 236.252012 -144.645532)
			(xy 236.259773 -144.59155) (xy 236.275137 -144.539222) (xy 236.297791 -144.489613) (xy 236.327274 -144.443733)
			(xy 236.362985 -144.402515) (xy 236.404199 -144.366799) (xy 236.450076 -144.337311) (xy 236.499683 -144.314652)
			(xy 236.552009 -144.299282) (xy 236.60599 -144.291515) (xy 236.633258 -144.29105) (xy 236.65694 -144.291404)
			(xy 236.703941 -144.297259) (xy 236.726984 -144.302734) (xy 236.742064 -144.305995) (xy 236.772855 -144.304299)
			(xy 236.801741 -144.293502) (xy 236.826095 -144.274585) (xy 236.843703 -144.249268) (xy 236.852964 -144.219854)
			(xy 236.853476 -144.204436) (xy 236.853476 -142.108936) (xy 236.852902 -142.093523) (xy 236.843642 -142.064118)
			(xy 236.826043 -142.038807) (xy 236.801704 -142.019886) (xy 236.772833 -142.009076) (xy 236.742053 -142.007356)
			(xy 236.726984 -142.010638) (xy 236.70394 -142.016108) (xy 236.65694 -142.021962) (xy 236.633258 -142.022322)
			(xy 236.606008 -142.021833) (xy 236.552063 -142.014072) (xy 236.499771 -141.998712) (xy 236.450197 -141.976068)
			(xy 236.40435 -141.946599) (xy 236.363164 -141.910907) (xy 236.327475 -141.869716) (xy 236.298012 -141.823866)
			(xy 236.275373 -141.77429) (xy 236.260019 -141.721996) (xy 236.252264 -141.66805) (xy 236.252264 -141.61355)
			(xy 236.260019 -141.559604) (xy 236.275373 -141.50731) (xy 236.298012 -141.457734) (xy 236.327475 -141.411884)
			(xy 236.363164 -141.370693) (xy 236.40435 -141.335001) (xy 236.450197 -141.305532) (xy 236.499771 -141.282888)
			(xy 236.552063 -141.267528) (xy 236.606008 -141.259767) (xy 236.633258 -141.259306) (xy 236.656939 -141.259666)
			(xy 236.703938 -141.265529) (xy 236.726984 -141.27099) (xy 236.742062 -141.274251) (xy 236.772849 -141.272556)
			(xy 236.80173 -141.261758) (xy 236.826078 -141.24284) (xy 236.843678 -141.217522) (xy 236.852927 -141.188108)
			(xy 236.853476 -141.172692) (xy 236.853476 -136.403842) (xy 236.85246 -136.393936) (xy 236.850756 -136.386777)
			(xy 236.843923 -136.37375) (xy 236.838998 -136.368282) (xy 234.991656 -134.521194) (xy 234.988039 -134.51776)
			(xy 234.979721 -134.512258) (xy 234.975146 -134.510272) (xy 234.96651 -134.506716) (xy 228.919024 -134.506716)
			(xy 228.910535 -134.507019) (xy 228.894489 -134.512566) (xy 228.881162 -134.523083) (xy 228.876352 -134.530084)
			(xy 228.83495 -134.5946) (xy 228.831288 -134.60066) (xy 228.82716 -134.614198) (xy 228.826822 -134.62127)
			(xy 228.826822 -134.650734) (xy 228.830886 -134.660132) (xy 228.840756 -134.684092) (xy 228.854663 -134.734011)
			(xy 228.861684 -134.785352) (xy 228.862128 -134.811262) (xy 228.862128 -134.811516) (xy 228.861671 -134.837553)
			(xy 228.854563 -134.889141) (xy 228.840507 -134.939283) (xy 228.819766 -134.987049) (xy 228.792723 -135.031552)
			(xy 228.759882 -135.071966) (xy 228.721852 -135.10754) (xy 228.700838 -135.12292) (xy 228.697282 -135.12546)
			(xy 228.690678 -135.132064) (xy 228.682876 -135.140678) (xy 228.675336 -135.162638) (xy 228.6762 -135.174228)
			(xy 228.686106 -135.255254) (xy 228.687415 -135.263606) (xy 228.69481 -135.278798) (xy 228.700584 -135.284972)
			(xy 228.715316 -135.299704) (xy 228.721158 -135.303006) (xy 228.725476 -135.305546) (xy 228.72827 -135.306816)
			(xy 228.728778 -135.30707) (xy 228.75453 -135.318313) (xy 228.802694 -135.347253) (xy 228.846094 -135.382942)
			(xy 228.883792 -135.424609) (xy 228.914974 -135.471353) (xy 228.938965 -135.522163) (xy 228.955247 -135.575942)
			(xy 228.963468 -135.631527) (xy 228.963982 -135.659622) (xy 228.963496 -135.686873) (xy 228.95574 -135.740821)
			(xy 228.940385 -135.793116) (xy 228.917743 -135.842693) (xy 228.888277 -135.888543) (xy 228.852586 -135.929734)
			(xy 228.811395 -135.965425) (xy 228.765545 -135.994891) (xy 228.715968 -136.017533) (xy 228.663673 -136.032888)
			(xy 228.609725 -136.040644) (xy 228.555223 -136.040644) (xy 228.501275 -136.032888) (xy 228.44898 -136.017533)
			(xy 228.399403 -135.994891) (xy 228.353553 -135.965425) (xy 228.312362 -135.929734) (xy 228.276671 -135.888543)
			(xy 228.247205 -135.842693) (xy 228.224563 -135.793116) (xy 228.209208 -135.740821) (xy 228.201452 -135.686873)
			(xy 228.200966 -135.659622) (xy 228.201408 -135.633567) (xy 228.208493 -135.58194) (xy 228.222536 -135.531758)
			(xy 228.243275 -135.483952) (xy 228.270324 -135.439412) (xy 228.303181 -135.398965) (xy 228.341234 -135.363364)
			(xy 228.362256 -135.347964) (xy 228.365812 -135.345424) (xy 228.372416 -135.33882) (xy 228.380216 -135.330205)
			(xy 228.38775 -135.308246) (xy 228.386894 -135.296656) (xy 228.376988 -135.21563) (xy 228.375677 -135.207279)
			(xy 228.368278 -135.192092) (xy 228.36251 -135.185912) (xy 228.347778 -135.17118) (xy 228.341936 -135.167878)
			(xy 228.337618 -135.165338) (xy 228.334824 -135.164068) (xy 228.334316 -135.163814) (xy 228.308565 -135.15257)
			(xy 228.260403 -135.123629) (xy 228.217005 -135.08794) (xy 228.179309 -135.046273) (xy 228.14813 -134.999529)
			(xy 228.124141 -134.948719) (xy 228.107862 -134.89494) (xy 228.099643 -134.839356) (xy 228.099112 -134.811262)
			(xy 228.099602 -134.783682) (xy 228.107554 -134.729097) (xy 228.123287 -134.676227) (xy 228.134418 -134.650988)
			(xy 228.13697 -134.645039) (xy 228.139292 -134.632308) (xy 228.13899 -134.625842) (xy 228.138228 -134.613396)
			(xy 228.130862 -134.60222) (xy 228.130862 -134.601712) (xy 228.086412 -134.531862) (xy 228.08057 -134.524242)
			(xy 228.075236 -134.518654) (xy 228.068632 -134.51459) (xy 228.066346 -134.51332) (xy 228.060698 -134.510319)
			(xy 228.048353 -134.506987) (xy 228.041962 -134.506716) (xy 217.706448 -134.506716) (xy 217.701557 -134.506853)
			(xy 217.691965 -134.508771) (xy 217.687398 -134.510526) (xy 217.678508 -134.514082) (xy 216.532968 -135.659622)
			(xy 224.644456 -135.659622) (xy 224.648527 -135.604) (xy 224.660653 -135.549563) (xy 224.680576 -135.497472)
			(xy 224.707872 -135.448837) (xy 224.741958 -135.404694) (xy 224.782107 -135.365985) (xy 224.827465 -135.333534)
			(xy 224.877065 -135.308033) (xy 224.929849 -135.290026) (xy 224.984692 -135.279896) (xy 225.040426 -135.277859)
			(xy 225.095863 -135.283959) (xy 225.14982 -135.298065) (xy 225.201149 -135.319877) (xy 225.248755 -135.348931)
			(xy 225.291623 -135.384606) (xy 225.32884 -135.426143) (xy 225.359613 -135.472656) (xy 225.383285 -135.523153)
			(xy 225.399353 -135.57656) (xy 225.407473 -135.631736) (xy 225.407982 -135.659622) (xy 226.422456 -135.659622)
			(xy 226.426527 -135.604) (xy 226.438653 -135.549563) (xy 226.458576 -135.497472) (xy 226.485872 -135.448837)
			(xy 226.519958 -135.404694) (xy 226.560107 -135.365985) (xy 226.605465 -135.333534) (xy 226.655065 -135.308033)
			(xy 226.707849 -135.290026) (xy 226.762692 -135.279896) (xy 226.818426 -135.277859) (xy 226.873863 -135.283959)
			(xy 226.92782 -135.298065) (xy 226.979149 -135.319877) (xy 227.026755 -135.348931) (xy 227.069623 -135.384606)
			(xy 227.10684 -135.426143) (xy 227.137613 -135.472656) (xy 227.161285 -135.523153) (xy 227.177353 -135.57656)
			(xy 227.185473 -135.631736) (xy 227.185982 -135.659622) (xy 227.185473 -135.687508) (xy 227.177353 -135.742684)
			(xy 227.161285 -135.796091) (xy 227.137613 -135.846588) (xy 227.10684 -135.893101) (xy 227.069623 -135.934638)
			(xy 227.026755 -135.970313) (xy 226.979149 -135.999367) (xy 226.92782 -136.021179) (xy 226.873863 -136.035285)
			(xy 226.818426 -136.041385) (xy 226.762692 -136.039348) (xy 226.707849 -136.029218) (xy 226.655065 -136.011211)
			(xy 226.605465 -135.98571) (xy 226.560107 -135.953259) (xy 226.519958 -135.91455) (xy 226.485872 -135.870407)
			(xy 226.458576 -135.821772) (xy 226.438653 -135.769681) (xy 226.426527 -135.715244) (xy 226.422456 -135.659622)
			(xy 225.407982 -135.659622) (xy 225.407473 -135.687508) (xy 225.399353 -135.742684) (xy 225.383285 -135.796091)
			(xy 225.359613 -135.846588) (xy 225.32884 -135.893101) (xy 225.291623 -135.934638) (xy 225.248755 -135.970313)
			(xy 225.201149 -135.999367) (xy 225.14982 -136.021179) (xy 225.095863 -136.035285) (xy 225.040426 -136.041385)
			(xy 224.984692 -136.039348) (xy 224.929849 -136.029218) (xy 224.877065 -136.011211) (xy 224.827465 -135.98571)
			(xy 224.782107 -135.953259) (xy 224.741958 -135.91455) (xy 224.707872 -135.870407) (xy 224.680576 -135.821772)
			(xy 224.660653 -135.769681) (xy 224.648527 -135.715244) (xy 224.644456 -135.659622) (xy 216.532968 -135.659622)
			(xy 215.234774 -136.957816) (xy 223.695512 -136.957816) (xy 223.699583 -136.902194) (xy 223.711709 -136.847757)
			(xy 223.731632 -136.795666) (xy 223.758928 -136.747031) (xy 223.793014 -136.702888) (xy 223.833163 -136.664179)
			(xy 223.878521 -136.631728) (xy 223.928121 -136.606227) (xy 223.980905 -136.58822) (xy 224.035748 -136.57809)
			(xy 224.091482 -136.576053) (xy 224.146919 -136.582153) (xy 224.200876 -136.596259) (xy 224.252205 -136.618071)
			(xy 224.299811 -136.647125) (xy 224.342679 -136.6828) (xy 224.379896 -136.724337) (xy 224.410669 -136.77085)
			(xy 224.434341 -136.821347) (xy 224.450409 -136.874754) (xy 224.458529 -136.92993) (xy 224.459038 -136.957816)
			(xy 224.458529 -136.985702) (xy 224.450409 -137.040878) (xy 224.434341 -137.094285) (xy 224.410669 -137.144782)
			(xy 224.379896 -137.191295) (xy 224.342679 -137.232832) (xy 224.299811 -137.268507) (xy 224.252205 -137.297561)
			(xy 224.200876 -137.319373) (xy 224.146919 -137.333479) (xy 224.091482 -137.339579) (xy 224.035748 -137.337542)
			(xy 223.980905 -137.327412) (xy 223.928121 -137.309405) (xy 223.878521 -137.283904) (xy 223.833163 -137.251453)
			(xy 223.793014 -137.212744) (xy 223.758928 -137.168601) (xy 223.731632 -137.119966) (xy 223.711709 -137.067875)
			(xy 223.699583 -137.013438) (xy 223.695512 -136.957816) (xy 215.234774 -136.957816) (xy 214.101934 -138.090656)
			(xy 224.549206 -138.090656) (xy 224.553277 -138.035034) (xy 224.565403 -137.980597) (xy 224.585326 -137.928506)
			(xy 224.612622 -137.879871) (xy 224.646708 -137.835728) (xy 224.686857 -137.797019) (xy 224.732215 -137.764568)
			(xy 224.781815 -137.739067) (xy 224.834599 -137.72106) (xy 224.889442 -137.71093) (xy 224.945176 -137.708893)
			(xy 225.000613 -137.714993) (xy 225.05457 -137.729099) (xy 225.105899 -137.750911) (xy 225.153505 -137.779965)
			(xy 225.196373 -137.81564) (xy 225.23359 -137.857177) (xy 225.264363 -137.90369) (xy 225.288035 -137.954187)
			(xy 225.304103 -138.007594) (xy 225.312223 -138.06277) (xy 225.312732 -138.090656) (xy 225.312223 -138.118542)
			(xy 225.304103 -138.173718) (xy 225.288035 -138.227125) (xy 225.273304 -138.25855) (xy 232.741976 -138.25855)
			(xy 232.746047 -138.202928) (xy 232.758173 -138.148491) (xy 232.778096 -138.0964) (xy 232.805392 -138.047765)
			(xy 232.839478 -138.003622) (xy 232.879627 -137.964913) (xy 232.924985 -137.932462) (xy 232.974585 -137.906961)
			(xy 233.027369 -137.888954) (xy 233.082212 -137.878824) (xy 233.137946 -137.876787) (xy 233.193383 -137.882887)
			(xy 233.24734 -137.896993) (xy 233.298669 -137.918805) (xy 233.346275 -137.947859) (xy 233.389143 -137.983534)
			(xy 233.42636 -138.025071) (xy 233.457133 -138.071584) (xy 233.480805 -138.122081) (xy 233.496873 -138.175488)
			(xy 233.504993 -138.230664) (xy 233.505502 -138.25855) (xy 233.504993 -138.286436) (xy 233.496873 -138.341612)
			(xy 233.480805 -138.395019) (xy 233.457133 -138.445516) (xy 233.42636 -138.492029) (xy 233.389143 -138.533566)
			(xy 233.346275 -138.569241) (xy 233.298669 -138.598295) (xy 233.24734 -138.620107) (xy 233.193383 -138.634213)
			(xy 233.137946 -138.640313) (xy 233.082212 -138.638276) (xy 233.027369 -138.628146) (xy 232.974585 -138.610139)
			(xy 232.924985 -138.584638) (xy 232.879627 -138.552187) (xy 232.839478 -138.513478) (xy 232.805392 -138.469335)
			(xy 232.778096 -138.4207) (xy 232.758173 -138.368609) (xy 232.746047 -138.314172) (xy 232.741976 -138.25855)
			(xy 225.273304 -138.25855) (xy 225.264363 -138.277622) (xy 225.23359 -138.324135) (xy 225.196373 -138.365672)
			(xy 225.153505 -138.401347) (xy 225.105899 -138.430401) (xy 225.05457 -138.452213) (xy 225.000613 -138.466319)
			(xy 224.945176 -138.472419) (xy 224.889442 -138.470382) (xy 224.834599 -138.460252) (xy 224.781815 -138.442245)
			(xy 224.732215 -138.416744) (xy 224.686857 -138.384293) (xy 224.646708 -138.345584) (xy 224.612622 -138.301441)
			(xy 224.585326 -138.252806) (xy 224.565403 -138.200715) (xy 224.553277 -138.146278) (xy 224.549206 -138.090656)
			(xy 214.101934 -138.090656) (xy 213.687406 -138.505184) (xy 221.778828 -138.505184) (xy 221.782899 -138.449562)
			(xy 221.795025 -138.395125) (xy 221.814948 -138.343034) (xy 221.842244 -138.294399) (xy 221.87633 -138.250256)
			(xy 221.916479 -138.211547) (xy 221.961837 -138.179096) (xy 222.011437 -138.153595) (xy 222.064221 -138.135588)
			(xy 222.119064 -138.125458) (xy 222.174798 -138.123421) (xy 222.230235 -138.129521) (xy 222.284192 -138.143627)
			(xy 222.335521 -138.165439) (xy 222.383127 -138.194493) (xy 222.425995 -138.230168) (xy 222.463212 -138.271705)
			(xy 222.493985 -138.318218) (xy 222.517657 -138.368715) (xy 222.533725 -138.422122) (xy 222.541845 -138.477298)
			(xy 222.542354 -138.505184) (xy 222.541845 -138.53307) (xy 222.533725 -138.588246) (xy 222.517657 -138.641653)
			(xy 222.493985 -138.69215) (xy 222.463212 -138.738663) (xy 222.425995 -138.7802) (xy 222.383127 -138.815875)
			(xy 222.335521 -138.844929) (xy 222.284192 -138.866741) (xy 222.230235 -138.880847) (xy 222.174798 -138.886947)
			(xy 222.119064 -138.88491) (xy 222.064221 -138.87478) (xy 222.011437 -138.856773) (xy 221.961837 -138.831272)
			(xy 221.916479 -138.798821) (xy 221.87633 -138.760112) (xy 221.842244 -138.715969) (xy 221.814948 -138.667334)
			(xy 221.795025 -138.615243) (xy 221.782899 -138.560806) (xy 221.778828 -138.505184) (xy 213.687406 -138.505184)
			(xy 213.135135 -139.057455) (xy 226.046957 -139.057455) (xy 226.046957 -139.002945) (xy 226.054716 -138.948991)
			(xy 226.070074 -138.896689) (xy 226.09272 -138.847106) (xy 226.122192 -138.801251) (xy 226.15789 -138.760058)
			(xy 226.199088 -138.724364) (xy 226.244947 -138.694898) (xy 226.294532 -138.672258) (xy 226.346836 -138.656906)
			(xy 226.400791 -138.649154) (xy 226.428046 -138.648694) (xy 226.455415 -138.649193) (xy 226.509593 -138.657003)
			(xy 226.562095 -138.672485) (xy 226.611843 -138.695319) (xy 226.657811 -138.725036) (xy 226.678744 -138.742674)
			(xy 226.678998 -138.742928) (xy 226.686079 -138.748523) (xy 226.703 -138.754764) (xy 226.712018 -138.75512)
			(xy 226.779074 -138.75512) (xy 226.788089 -138.754746) (xy 226.805006 -138.74851) (xy 226.812094 -138.742928)
			(xy 226.812094 -138.742674) (xy 226.812348 -138.742674) (xy 226.833286 -138.725042) (xy 226.879257 -138.69533)
			(xy 226.929003 -138.672493) (xy 226.981503 -138.657) (xy 227.035677 -138.64917) (xy 227.063046 -138.648694)
			(xy 227.090295 -138.649179) (xy 227.144238 -138.656941) (xy 227.196528 -138.6723) (xy 227.246099 -138.694944)
			(xy 227.291944 -138.724412) (xy 227.333129 -138.760103) (xy 227.368816 -138.801293) (xy 227.398278 -138.847141)
			(xy 227.420916 -138.896715) (xy 227.436269 -138.949007) (xy 227.444024 -139.002951) (xy 227.444024 -139.057449)
			(xy 227.436269 -139.111393) (xy 227.420916 -139.163685) (xy 227.398278 -139.213259) (xy 227.368816 -139.259107)
			(xy 227.333129 -139.300297) (xy 227.291944 -139.335988) (xy 227.246099 -139.365456) (xy 227.196528 -139.3881)
			(xy 227.144238 -139.403459) (xy 227.090295 -139.411221) (xy 227.063046 -139.41171) (xy 227.035677 -139.411215)
			(xy 226.981499 -139.403403) (xy 226.928996 -139.387921) (xy 226.879249 -139.365086) (xy 226.833281 -139.335368)
			(xy 226.812348 -139.31773) (xy 226.812094 -139.317476) (xy 226.805015 -139.311878) (xy 226.788092 -139.305639)
			(xy 226.779074 -139.305284) (xy 226.712018 -139.305284) (xy 226.703002 -139.305653) (xy 226.686086 -139.311893)
			(xy 226.678998 -139.317476) (xy 226.678998 -139.31773) (xy 226.678744 -139.31773) (xy 226.65781 -139.335367)
			(xy 226.611837 -139.365078) (xy 226.56209 -139.387914) (xy 226.50959 -139.403405) (xy 226.455415 -139.411235)
			(xy 226.428046 -139.41171) (xy 226.400791 -139.411246) (xy 226.346836 -139.403494) (xy 226.294532 -139.388142)
			(xy 226.244947 -139.365502) (xy 226.199088 -139.336036) (xy 226.15789 -139.300342) (xy 226.122192 -139.259149)
			(xy 226.09272 -139.213294) (xy 226.070074 -139.163711) (xy 226.054716 -139.111409) (xy 226.046957 -139.057455)
			(xy 213.135135 -139.057455) (xy 212.550756 -139.641834) (xy 219.820234 -139.641834) (xy 219.824305 -139.586212)
			(xy 219.836431 -139.531775) (xy 219.856354 -139.479684) (xy 219.88365 -139.431049) (xy 219.917736 -139.386906)
			(xy 219.957885 -139.348197) (xy 220.003243 -139.315746) (xy 220.052843 -139.290245) (xy 220.105627 -139.272238)
			(xy 220.16047 -139.262108) (xy 220.216204 -139.260071) (xy 220.271641 -139.266171) (xy 220.325598 -139.280277)
			(xy 220.376927 -139.302089) (xy 220.424533 -139.331143) (xy 220.467401 -139.366818) (xy 220.504618 -139.408355)
			(xy 220.535391 -139.454868) (xy 220.559063 -139.505365) (xy 220.575131 -139.558772) (xy 220.583251 -139.613948)
			(xy 220.58376 -139.641834) (xy 220.583251 -139.66972) (xy 220.575131 -139.724896) (xy 220.559063 -139.778303)
			(xy 220.53683 -139.82573) (xy 231.704894 -139.82573) (xy 231.708965 -139.770108) (xy 231.721091 -139.715671)
			(xy 231.741014 -139.66358) (xy 231.76831 -139.614945) (xy 231.802396 -139.570802) (xy 231.842545 -139.532093)
			(xy 231.887903 -139.499642) (xy 231.937503 -139.474141) (xy 231.990287 -139.456134) (xy 232.04513 -139.446004)
			(xy 232.100864 -139.443967) (xy 232.156301 -139.450067) (xy 232.210258 -139.464173) (xy 232.261587 -139.485985)
			(xy 232.309193 -139.515039) (xy 232.352061 -139.550714) (xy 232.389278 -139.592251) (xy 232.420051 -139.638764)
			(xy 232.443723 -139.689261) (xy 232.459791 -139.742668) (xy 232.467911 -139.797844) (xy 232.46842 -139.82573)
			(xy 232.467911 -139.853616) (xy 232.459791 -139.908792) (xy 232.443723 -139.962199) (xy 232.420051 -140.012696)
			(xy 232.389278 -140.059209) (xy 232.352061 -140.100746) (xy 232.309193 -140.136421) (xy 232.261587 -140.165475)
			(xy 232.210258 -140.187287) (xy 232.156301 -140.201393) (xy 232.100864 -140.207493) (xy 232.04513 -140.205456)
			(xy 231.990287 -140.195326) (xy 231.937503 -140.177319) (xy 231.887903 -140.151818) (xy 231.842545 -140.119367)
			(xy 231.802396 -140.080658) (xy 231.76831 -140.036515) (xy 231.741014 -139.98788) (xy 231.721091 -139.935789)
			(xy 231.708965 -139.881352) (xy 231.704894 -139.82573) (xy 220.53683 -139.82573) (xy 220.535391 -139.8288)
			(xy 220.504618 -139.875313) (xy 220.467401 -139.91685) (xy 220.424533 -139.952525) (xy 220.376927 -139.981579)
			(xy 220.325598 -140.003391) (xy 220.271641 -140.017497) (xy 220.216204 -140.023597) (xy 220.16047 -140.02156)
			(xy 220.105627 -140.01143) (xy 220.052843 -139.993423) (xy 220.003243 -139.967922) (xy 219.957885 -139.935471)
			(xy 219.917736 -139.896762) (xy 219.88365 -139.852619) (xy 219.856354 -139.803984) (xy 219.836431 -139.751893)
			(xy 219.824305 -139.697456) (xy 219.820234 -139.641834) (xy 212.550756 -139.641834) (xy 212.052408 -140.140182)
			(xy 212.046058 -140.146278) (xy 211.970112 -140.222224) (xy 211.962718 -140.229081) (xy 211.944119 -140.236832)
			(xy 211.934044 -140.23721) (xy 211.826348 -140.23721) (xy 211.817712 -140.237464) (xy 202.627992 -140.237464)
			(xy 202.617218 -140.23906) (xy 202.598399 -140.249982) (xy 202.59167 -140.258546) (xy 202.550776 -140.316204)
			(xy 202.547326 -140.321313) (xy 202.542712 -140.33274) (xy 202.541632 -140.33881) (xy 202.540108 -140.350494)
			(xy 202.544172 -140.362178) (xy 202.5541 -140.392594) (xy 202.564825 -140.455666) (xy 202.565508 -140.487654)
			(xy 202.565022 -140.514905) (xy 202.557266 -140.568853) (xy 202.541911 -140.621148) (xy 202.519269 -140.670725)
			(xy 202.489803 -140.716575) (xy 202.454112 -140.757766) (xy 202.412921 -140.793457) (xy 202.367071 -140.822923)
			(xy 202.317494 -140.845565) (xy 202.265199 -140.86092) (xy 202.211251 -140.868676) (xy 202.156749 -140.868676)
			(xy 202.102801 -140.86092) (xy 202.050506 -140.845565) (xy 202.000929 -140.822923) (xy 201.955079 -140.793457)
			(xy 201.913888 -140.757766) (xy 201.878197 -140.716575) (xy 201.848731 -140.670725) (xy 201.826089 -140.621148)
			(xy 201.810734 -140.568853) (xy 201.802978 -140.514905) (xy 201.802492 -140.487654) (xy 201.80316 -140.455664)
			(xy 201.813879 -140.392589) (xy 201.823828 -140.362178) (xy 201.823828 -140.361924) (xy 201.825618 -140.356199)
			(xy 201.826774 -140.344263) (xy 201.826114 -140.338302) (xy 201.82459 -140.326364) (xy 201.77633 -140.258546)
			(xy 201.769609 -140.249972) (xy 201.750787 -140.239042) (xy 201.740008 -140.237464) (xy 197.963282 -140.237464)
			(xy 197.954761 -140.238652) (xy 197.939175 -140.245911) (xy 197.932802 -140.251688) (xy 197.927214 -140.25753)
			(xy 197.887082 -140.32103) (xy 197.887082 -140.321538) (xy 197.881748 -140.32992) (xy 197.87997 -140.339572)
			(xy 197.877938 -140.35024) (xy 197.882764 -140.371322) (xy 197.88505 -140.376402) (xy 197.895857 -140.401325)
			(xy 197.911113 -140.45346) (xy 197.918833 -140.50723) (xy 197.91934 -140.53439) (xy 197.91934 -140.534898)
			(xy 197.918854 -140.56215) (xy 197.911098 -140.6161) (xy 197.895744 -140.668397) (xy 197.873103 -140.717976)
			(xy 197.843637 -140.763829) (xy 197.807946 -140.805022) (xy 197.766756 -140.840717) (xy 197.720906 -140.870187)
			(xy 197.671329 -140.892832) (xy 197.665439 -140.894562) (xy 219.859604 -140.894562) (xy 219.863675 -140.83894)
			(xy 219.875801 -140.784503) (xy 219.895724 -140.732412) (xy 219.92302 -140.683777) (xy 219.957106 -140.639634)
			(xy 219.997255 -140.600925) (xy 220.042613 -140.568474) (xy 220.092213 -140.542973) (xy 220.144997 -140.524966)
			(xy 220.19984 -140.514836) (xy 220.255574 -140.512799) (xy 220.311011 -140.518899) (xy 220.364968 -140.533005)
			(xy 220.416297 -140.554817) (xy 220.463903 -140.583871) (xy 220.506771 -140.619546) (xy 220.543988 -140.661083)
			(xy 220.574761 -140.707596) (xy 220.598433 -140.758093) (xy 220.614501 -140.8115) (xy 220.622621 -140.866676)
			(xy 220.62313 -140.894562) (xy 220.622621 -140.922448) (xy 220.617791 -140.955268) (xy 222.72701 -140.955268)
			(xy 222.731081 -140.899646) (xy 222.743207 -140.845209) (xy 222.76313 -140.793118) (xy 222.790426 -140.744483)
			(xy 222.824512 -140.70034) (xy 222.864661 -140.661631) (xy 222.910019 -140.62918) (xy 222.959619 -140.603679)
			(xy 223.012403 -140.585672) (xy 223.067246 -140.575542) (xy 223.12298 -140.573505) (xy 223.178417 -140.579605)
			(xy 223.232374 -140.593711) (xy 223.283703 -140.615523) (xy 223.331309 -140.644577) (xy 223.374177 -140.680252)
			(xy 223.397787 -140.706602) (xy 224.801428 -140.706602) (xy 224.805499 -140.65098) (xy 224.817625 -140.596543)
			(xy 224.837548 -140.544452) (xy 224.864844 -140.495817) (xy 224.89893 -140.451674) (xy 224.939079 -140.412965)
			(xy 224.984437 -140.380514) (xy 225.034037 -140.355013) (xy 225.086821 -140.337006) (xy 225.141664 -140.326876)
			(xy 225.197398 -140.324839) (xy 225.252835 -140.330939) (xy 225.306792 -140.345045) (xy 225.358121 -140.366857)
			(xy 225.405727 -140.395911) (xy 225.448595 -140.431586) (xy 225.485812 -140.473123) (xy 225.516585 -140.519636)
			(xy 225.540257 -140.570133) (xy 225.556325 -140.62354) (xy 225.564445 -140.678716) (xy 225.564954 -140.706602)
			(xy 225.564445 -140.734488) (xy 225.556325 -140.789664) (xy 225.540257 -140.843071) (xy 225.516585 -140.893568)
			(xy 225.485812 -140.940081) (xy 225.448595 -140.981618) (xy 225.405727 -141.017293) (xy 225.358121 -141.046347)
			(xy 225.306792 -141.068159) (xy 225.252835 -141.082265) (xy 225.197398 -141.088365) (xy 225.141664 -141.086328)
			(xy 225.086821 -141.076198) (xy 225.034037 -141.058191) (xy 224.984437 -141.03269) (xy 224.939079 -141.000239)
			(xy 224.89893 -140.96153) (xy 224.864844 -140.917387) (xy 224.837548 -140.868752) (xy 224.817625 -140.816661)
			(xy 224.805499 -140.762224) (xy 224.801428 -140.706602) (xy 223.397787 -140.706602) (xy 223.411394 -140.721789)
			(xy 223.442167 -140.768302) (xy 223.465839 -140.818799) (xy 223.481907 -140.872206) (xy 223.490027 -140.927382)
			(xy 223.490536 -140.955268) (xy 223.490027 -140.983154) (xy 223.481907 -141.03833) (xy 223.465839 -141.091737)
			(xy 223.442167 -141.142234) (xy 223.411394 -141.188747) (xy 223.374177 -141.230284) (xy 223.331309 -141.265959)
			(xy 223.283703 -141.295013) (xy 223.232374 -141.316825) (xy 223.178417 -141.330931) (xy 223.12298 -141.337031)
			(xy 223.067246 -141.334994) (xy 223.012403 -141.324864) (xy 222.959619 -141.306857) (xy 222.910019 -141.281356)
			(xy 222.864661 -141.248905) (xy 222.824512 -141.210196) (xy 222.790426 -141.166053) (xy 222.76313 -141.117418)
			(xy 222.743207 -141.065327) (xy 222.731081 -141.01089) (xy 222.72701 -140.955268) (xy 220.617791 -140.955268)
			(xy 220.614501 -140.977624) (xy 220.598433 -141.031031) (xy 220.574761 -141.081528) (xy 220.543988 -141.128041)
			(xy 220.506771 -141.169578) (xy 220.463903 -141.205253) (xy 220.416297 -141.234307) (xy 220.364968 -141.256119)
			(xy 220.311011 -141.270225) (xy 220.255574 -141.276325) (xy 220.19984 -141.274288) (xy 220.144997 -141.264158)
			(xy 220.092213 -141.246151) (xy 220.042613 -141.22065) (xy 219.997255 -141.188199) (xy 219.957106 -141.14949)
			(xy 219.92302 -141.105347) (xy 219.895724 -141.056712) (xy 219.875801 -141.004621) (xy 219.863675 -140.950184)
			(xy 219.859604 -140.894562) (xy 197.665439 -140.894562) (xy 197.619033 -140.908191) (xy 197.565084 -140.915952)
			(xy 197.537832 -140.916406) (xy 197.510683 -140.91593) (xy 197.456933 -140.908236) (xy 197.404817 -140.892999)
			(xy 197.355388 -140.870526) (xy 197.309645 -140.841273) (xy 197.268511 -140.805829) (xy 197.232818 -140.764911)
			(xy 197.203287 -140.719346) (xy 197.180515 -140.670054) (xy 197.164962 -140.618032) (xy 197.156942 -140.56433)
			(xy 197.156324 -140.537184) (xy 197.156324 -140.534644) (xy 197.156803 -140.507482) (xy 197.164518 -140.453708)
			(xy 197.179797 -140.401576) (xy 197.190614 -140.376656) (xy 197.1929 -140.37183) (xy 197.19544 -140.362178)
			(xy 197.197256 -140.353248) (xy 197.195168 -140.335159) (xy 197.191376 -140.326872) (xy 197.188836 -140.321792)
			(xy 197.148196 -140.258038) (xy 197.141433 -140.249771) (xy 197.12293 -140.239149) (xy 197.112382 -140.237464)
			(xy 196.522086 -140.237464) (xy 196.51345 -140.23721) (xy 196.405754 -140.23721) (xy 196.395687 -140.236779)
			(xy 196.377094 -140.229054) (xy 196.369686 -140.222224) (xy 196.324982 -140.17752) (xy 196.32041 -140.174472)
			(xy 196.30681 -140.165277) (xy 196.281357 -140.144538) (xy 196.26961 -140.13307) (xy 195.065396 -138.928856)
			(xy 195.061665 -138.925335) (xy 195.05309 -138.919707) (xy 195.048378 -138.91768) (xy 195.039742 -138.914124)
			(xy 181.996842 -138.914124) (xy 181.988154 -138.914479) (xy 181.971795 -138.920336) (xy 181.964838 -138.925554)
			(xy 181.961028 -138.928856) (xy 181.234842 -139.655296) (xy 181.228492 -139.661392) (xy 181.152546 -139.737338)
			(xy 181.145148 -139.744183) (xy 181.126549 -139.751907) (xy 181.116478 -139.752324) (xy 180.296566 -139.752324)
			(xy 180.286498 -139.751895) (xy 180.2679 -139.744175) (xy 180.260498 -139.737338) (xy 180.184552 -139.661392)
			(xy 180.178202 -139.655296) (xy 179.775104 -139.252198) (xy 179.769008 -139.245848) (xy 179.693062 -139.169902)
			(xy 179.686208 -139.162507) (xy 179.678463 -139.143908) (xy 179.678076 -139.133834) (xy 179.678076 -138.893042)
			(xy 179.67706 -138.883136) (xy 179.675356 -138.875977) (xy 179.668523 -138.86295) (xy 179.663598 -138.857482)
			(xy 178.87442 -138.068558) (xy 178.87188 -138.066272) (xy 178.860323 -138.056858) (xy 178.833182 -138.044571)
			(xy 178.803646 -138.040663) (xy 178.774243 -138.04547) (xy 178.760628 -138.05154) (xy 178.76012 -138.05154)
			(xy 178.75132 -138.056252) (xy 178.735585 -138.068531) (xy 178.728878 -138.075924) (xy 178.724306 -138.081258)
			(xy 178.706153 -138.10402) (xy 178.664107 -138.144287) (xy 178.616424 -138.177689) (xy 178.564215 -138.203447)
			(xy 178.508694 -138.220962) (xy 178.451155 -138.229827) (xy 178.422046 -138.230356) (xy 178.421792 -138.230356)
			(xy 178.39454 -138.22987) (xy 178.34059 -138.222113) (xy 178.288294 -138.206757) (xy 178.238715 -138.184116)
			(xy 178.192862 -138.154651) (xy 178.151669 -138.11896) (xy 178.115973 -138.07777) (xy 178.086503 -138.03192)
			(xy 178.063857 -137.982344) (xy 178.048496 -137.930049) (xy 178.040733 -137.8761) (xy 178.040284 -137.848848)
			(xy 178.040822 -137.819933) (xy 178.049555 -137.762766) (xy 178.066814 -137.707571) (xy 178.092204 -137.655612)
			(xy 178.125143 -137.608079) (xy 178.164876 -137.56606) (xy 178.18735 -137.547858) (xy 178.188366 -137.547096)
			(xy 178.199349 -137.538407) (xy 178.216467 -137.516257) (xy 178.226924 -137.490289) (xy 178.229935 -137.462457)
			(xy 178.225271 -137.434854) (xy 178.213285 -137.409556) (xy 178.204368 -137.39876) (xy 178.202082 -137.39622)
			(xy 177.808636 -137.002774) (xy 177.805017 -136.999342) (xy 177.796698 -136.993845) (xy 177.792126 -136.991852)
			(xy 177.78349 -136.988296) (xy 173.690788 -136.988296) (xy 173.678343 -136.988982) (xy 173.65637 -137.000689)
			(xy 173.648878 -137.010648) (xy 173.602142 -137.083038) (xy 173.598851 -137.088365) (xy 173.594737 -137.100187)
			(xy 173.594014 -137.106406) (xy 173.592998 -137.119106) (xy 173.598332 -137.131044) (xy 173.608854 -137.155682)
			(xy 173.623672 -137.207164) (xy 173.631148 -137.260213) (xy 173.631606 -137.287) (xy 173.63112 -137.314269)
			(xy 173.623358 -137.368253) (xy 173.607993 -137.420583) (xy 173.585336 -137.470193) (xy 173.55585 -137.516074)
			(xy 173.520135 -137.557291) (xy 173.478918 -137.593006) (xy 173.433037 -137.622492) (xy 173.383427 -137.645149)
			(xy 173.331097 -137.660514) (xy 173.277113 -137.668276) (xy 173.222575 -137.668276) (xy 173.168591 -137.660514)
			(xy 173.116261 -137.645149) (xy 173.066651 -137.622492) (xy 173.02077 -137.593006) (xy 172.979553 -137.557291)
			(xy 172.943838 -137.516074) (xy 172.914352 -137.470193) (xy 172.891695 -137.420583) (xy 172.87633 -137.368253)
			(xy 172.868568 -137.314269) (xy 172.868082 -137.287) (xy 172.868485 -137.261828) (xy 172.875103 -137.211922)
			(xy 172.888223 -137.163319) (xy 172.897546 -137.139934) (xy 172.90161 -137.130536) (xy 172.90161 -137.104882)
			(xy 172.901356 -137.099548) (xy 172.89907 -137.089134) (xy 172.89526 -137.078466) (xy 172.851318 -137.01141)
			(xy 172.851318 -137.011156) (xy 172.84771 -137.00602) (xy 172.838458 -136.997543) (xy 172.83303 -136.994392)
			(xy 172.827442 -136.991344) (xy 172.815504 -136.988296) (xy 172.711364 -136.988296) (xy 172.706473 -136.988431)
			(xy 172.696879 -136.990346) (xy 172.692314 -136.992106) (xy 172.683424 -136.995662) (xy 170.722036 -138.95705)
			(xy 172.614336 -138.95705) (xy 172.614822 -138.929799) (xy 172.622578 -138.875851) (xy 172.637933 -138.823556)
			(xy 172.660575 -138.773979) (xy 172.690041 -138.728129) (xy 172.725732 -138.686938) (xy 172.766923 -138.651247)
			(xy 172.812773 -138.621781) (xy 172.86235 -138.599139) (xy 172.914645 -138.583784) (xy 172.968593 -138.576028)
			(xy 173.023095 -138.576028) (xy 173.077043 -138.583784) (xy 173.129338 -138.599139) (xy 173.178915 -138.621781)
			(xy 173.224765 -138.651247) (xy 173.265956 -138.686938) (xy 173.301647 -138.728129) (xy 173.331113 -138.773979)
			(xy 173.353755 -138.823556) (xy 173.365879 -138.864848) (xy 178.039774 -138.864848) (xy 178.043845 -138.809226)
			(xy 178.055971 -138.754789) (xy 178.075894 -138.702698) (xy 178.10319 -138.654063) (xy 178.137276 -138.60992)
			(xy 178.177425 -138.571211) (xy 178.222783 -138.53876) (xy 178.272383 -138.513259) (xy 178.325167 -138.495252)
			(xy 178.38001 -138.485122) (xy 178.435744 -138.483085) (xy 178.491181 -138.489185) (xy 178.545138 -138.503291)
			(xy 178.596467 -138.525103) (xy 178.644073 -138.554157) (xy 178.686941 -138.589832) (xy 178.724158 -138.631369)
			(xy 178.754931 -138.677882) (xy 178.778603 -138.728379) (xy 178.794671 -138.781786) (xy 178.802791 -138.836962)
			(xy 178.8033 -138.864848) (xy 178.802791 -138.892734) (xy 178.794671 -138.94791) (xy 178.778603 -139.001317)
			(xy 178.754931 -139.051814) (xy 178.724158 -139.098327) (xy 178.686941 -139.139864) (xy 178.644073 -139.175539)
			(xy 178.596467 -139.204593) (xy 178.545138 -139.226405) (xy 178.491181 -139.240511) (xy 178.435744 -139.246611)
			(xy 178.38001 -139.244574) (xy 178.325167 -139.234444) (xy 178.272383 -139.216437) (xy 178.222783 -139.190936)
			(xy 178.177425 -139.158485) (xy 178.137276 -139.119776) (xy 178.10319 -139.075633) (xy 178.075894 -139.026998)
			(xy 178.055971 -138.974907) (xy 178.043845 -138.92047) (xy 178.039774 -138.864848) (xy 173.365879 -138.864848)
			(xy 173.36911 -138.875851) (xy 173.376866 -138.929799) (xy 173.377352 -138.95705) (xy 173.376854 -138.98483)
			(xy 173.368781 -139.039801) (xy 173.352811 -139.093017) (xy 173.329285 -139.14335) (xy 173.298701 -139.189735)
			(xy 173.280578 -139.210796) (xy 173.280324 -139.21105) (xy 173.274021 -139.218931) (xy 173.267603 -139.238047)
			(xy 173.267878 -139.248134) (xy 173.273212 -139.321286) (xy 173.27438 -139.331363) (xy 173.283553 -139.34944)
			(xy 173.290992 -139.356338) (xy 173.291246 -139.356592) (xy 173.312272 -139.3748) (xy 173.349311 -139.416293)
			(xy 173.379938 -139.46272) (xy 173.403506 -139.5131) (xy 173.419516 -139.566366) (xy 173.427628 -139.621391)
			(xy 173.428152 -139.6492) (xy 173.427666 -139.676451) (xy 173.41991 -139.730399) (xy 173.404555 -139.782694)
			(xy 173.381913 -139.832271) (xy 173.352447 -139.878121) (xy 173.316756 -139.919312) (xy 173.275565 -139.955003)
			(xy 173.229715 -139.984469) (xy 173.180138 -140.007111) (xy 173.127843 -140.022466) (xy 173.073895 -140.030222)
			(xy 173.019393 -140.030222) (xy 172.965445 -140.022466) (xy 172.91315 -140.007111) (xy 172.863573 -139.984469)
			(xy 172.817723 -139.955003) (xy 172.776532 -139.919312) (xy 172.740841 -139.878121) (xy 172.711375 -139.832271)
			(xy 172.688733 -139.782694) (xy 172.673378 -139.730399) (xy 172.665622 -139.676451) (xy 172.665136 -139.6492)
			(xy 172.665667 -139.621421) (xy 172.673733 -139.566452) (xy 172.689695 -139.513237) (xy 172.713214 -139.462903)
			(xy 172.743791 -139.416516) (xy 172.76191 -139.395454) (xy 172.762164 -139.3952) (xy 172.768489 -139.387334)
			(xy 172.774894 -139.368207) (xy 172.77461 -139.358116) (xy 172.769276 -139.284964) (xy 172.768136 -139.274881)
			(xy 172.758943 -139.256807) (xy 172.751496 -139.249912) (xy 172.751242 -139.249658) (xy 172.730238 -139.231426)
			(xy 172.693198 -139.189938) (xy 172.662568 -139.143515) (xy 172.638996 -139.093141) (xy 172.622982 -139.039879)
			(xy 172.614864 -138.984858) (xy 172.614336 -138.95705) (xy 170.722036 -138.95705) (xy 170.562524 -139.116562)
			(xy 170.556174 -139.122658) (xy 170.480228 -139.198604) (xy 170.472825 -139.205439) (xy 170.454227 -139.213146)
			(xy 170.44416 -139.21359) (xy 170.336464 -139.21359) (xy 170.327828 -139.213844) (xy 168.95445 -139.213844)
			(xy 168.948862 -139.21867) (xy 168.468802 -139.69873) (xy 168.455916 -139.711333) (xy 168.42778 -139.733865)
			(xy 168.412668 -139.743688) (xy 168.41216 -139.744196) (xy 168.403758 -139.750158) (xy 168.392214 -139.767199)
			(xy 168.389808 -139.777216) (xy 168.387268 -139.793218) (xy 168.387014 -139.798552) (xy 168.387014 -139.87526)
			(xy 168.387083 -139.879066) (xy 168.388236 -139.886591) (xy 168.3893 -139.890246) (xy 168.391586 -139.897612)
			(xy 168.396666 -139.90447) (xy 168.413595 -139.928946) (xy 168.440451 -139.98205) (xy 168.45872 -140.038685)
			(xy 168.467957 -140.097473) (xy 168.468548 -140.127228) (xy 168.468548 -140.127482) (xy 168.468062 -140.154733)
			(xy 168.460306 -140.208681) (xy 168.444951 -140.260976) (xy 168.422309 -140.310553) (xy 168.392843 -140.356403)
			(xy 168.357152 -140.397594) (xy 168.315961 -140.433285) (xy 168.270111 -140.462751) (xy 168.220534 -140.485393)
			(xy 168.168239 -140.500748) (xy 168.114291 -140.508504) (xy 168.059789 -140.508504) (xy 168.005841 -140.500748)
			(xy 167.953546 -140.485393) (xy 167.903969 -140.462751) (xy 167.858119 -140.433285) (xy 167.816928 -140.397594)
			(xy 167.781237 -140.356403) (xy 167.751771 -140.310553) (xy 167.729129 -140.260976) (xy 167.713774 -140.208681)
			(xy 167.706018 -140.154733) (xy 167.705532 -140.127482) (xy 167.706028 -140.099807) (xy 167.714034 -140.045039)
			(xy 167.729875 -139.992005) (xy 167.741092 -139.9667) (xy 167.743642 -139.96075) (xy 167.745964 -139.94802)
			(xy 167.745664 -139.941554) (xy 167.744902 -139.929108) (xy 167.737536 -139.917932) (xy 167.737536 -139.917424)
			(xy 167.693086 -139.847574) (xy 167.687244 -139.839954) (xy 167.68191 -139.834366) (xy 167.675306 -139.830302)
			(xy 167.67302 -139.829032) (xy 167.667374 -139.826022) (xy 167.655029 -139.822671) (xy 167.648636 -139.822428)
			(xy 167.138604 -139.822428) (xy 167.128533 -139.822006) (xy 167.109925 -139.814296) (xy 167.102536 -139.807442)
			(xy 166.496746 -139.201652) (xy 166.493897 -139.198943) (xy 166.487522 -139.194344) (xy 166.484046 -139.192508)
			(xy 166.478619 -139.189926) (xy 166.466939 -139.187104) (xy 166.460932 -139.18692) (xy 161.505646 -139.18692)
			(xy 161.496502 -139.187682) (xy 161.47796 -139.191492) (xy 161.472372 -139.194032) (xy 161.4551 -139.201906)
			(xy 161.450528 -139.205462) (xy 161.444686 -139.20978) (xy 161.440876 -139.214098) (xy 161.440622 -139.214352)
			(xy 161.439606 -139.215622) (xy 161.421365 -139.235854) (xy 161.380136 -139.271457) (xy 161.334268 -139.300841)
			(xy 161.284691 -139.323412) (xy 161.23241 -139.338711) (xy 161.178486 -139.346428) (xy 161.124013 -139.346407)
			(xy 161.070095 -139.338647) (xy 161.017826 -139.323307) (xy 160.968266 -139.300697) (xy 160.922421 -139.271276)
			(xy 160.881221 -139.235641) (xy 160.863026 -139.215368) (xy 160.85947 -139.210796) (xy 160.854644 -139.206986)
			(xy 160.845246 -139.201398) (xy 160.824164 -139.191238) (xy 160.819384 -139.189256) (xy 160.80927 -139.18708)
			(xy 160.804098 -139.18692) (xy 159.652208 -139.18692) (xy 159.647331 -139.18702) (xy 159.637744 -139.188814)
			(xy 159.633158 -139.190476) (xy 159.624014 -139.194286) (xy 158.763462 -140.054838) (xy 158.760757 -140.057689)
			(xy 158.756166 -140.064069) (xy 158.754318 -140.067538) (xy 158.751733 -140.072965) (xy 158.748908 -140.084644)
			(xy 158.74873 -140.090652) (xy 158.74873 -140.565378) (xy 159.689546 -140.565378) (xy 159.689988 -140.538007)
			(xy 159.69781 -140.483826) (xy 159.713304 -140.431322) (xy 159.736151 -140.381576) (xy 159.765882 -140.33561)
			(xy 159.783526 -140.31468) (xy 159.78378 -140.314426) (xy 159.789371 -140.307343) (xy 159.795613 -140.290423)
			(xy 159.795972 -140.281406) (xy 159.795972 -140.21435) (xy 159.795597 -140.205335) (xy 159.789363 -140.188417)
			(xy 159.78378 -140.18133) (xy 159.783526 -140.18133) (xy 159.783526 -140.181076) (xy 159.765913 -140.160123)
			(xy 159.736196 -140.114156) (xy 159.713355 -140.064414) (xy 159.697858 -140.011918) (xy 159.690023 -139.957746)
			(xy 159.689546 -139.930378) (xy 159.690057 -139.903128) (xy 159.697816 -139.849184) (xy 159.713171 -139.796892)
			(xy 159.735811 -139.747318) (xy 159.765276 -139.70147) (xy 159.800964 -139.660281) (xy 159.842151 -139.62459)
			(xy 159.887997 -139.595123) (xy 159.93757 -139.572479) (xy 159.98986 -139.557121) (xy 160.043804 -139.549359)
			(xy 160.071054 -139.54887) (xy 160.098424 -139.549346) (xy 160.152603 -139.557159) (xy 160.205107 -139.572645)
			(xy 160.254854 -139.595485) (xy 160.300821 -139.625209) (xy 160.321752 -139.64285) (xy 160.322006 -139.643104)
			(xy 160.329086 -139.6487) (xy 160.346008 -139.654941) (xy 160.355026 -139.655296) (xy 160.422082 -139.655296)
			(xy 160.431098 -139.654931) (xy 160.448015 -139.648689) (xy 160.455102 -139.643104) (xy 160.455102 -139.64285)
			(xy 160.455356 -139.64285) (xy 160.4763 -139.625226) (xy 160.522269 -139.59551) (xy 160.572013 -139.57267)
			(xy 160.624512 -139.557176) (xy 160.678686 -139.549345) (xy 160.706054 -139.54887) (xy 160.733305 -139.549398)
			(xy 160.787252 -139.557148) (xy 160.839547 -139.572497) (xy 160.889126 -139.595133) (xy 160.934978 -139.624594)
			(xy 160.976171 -139.660281) (xy 161.011865 -139.701467) (xy 161.041335 -139.747314) (xy 161.063979 -139.796889)
			(xy 161.079337 -139.849181) (xy 161.087097 -139.903127) (xy 161.087562 -139.930378) (xy 161.087092 -139.957748)
			(xy 161.079277 -140.011928) (xy 161.063789 -140.064431) (xy 161.040948 -140.114178) (xy 161.011223 -140.160145)
			(xy 160.993582 -140.181076) (xy 160.993328 -140.18133) (xy 160.987756 -140.188426) (xy 160.981503 -140.205336)
			(xy 160.981136 -140.21435) (xy 160.981136 -140.281406) (xy 160.981482 -140.290424) (xy 160.987736 -140.307341)
			(xy 160.993328 -140.314426) (xy 160.993582 -140.314426) (xy 160.993582 -140.31468) (xy 161.011222 -140.335611)
			(xy 161.040935 -140.381584) (xy 161.063771 -140.431332) (xy 161.079261 -140.483833) (xy 161.087089 -140.538009)
			(xy 161.087562 -140.565378) (xy 161.087124 -140.592632) (xy 161.079369 -140.646587) (xy 161.064013 -140.698888)
			(xy 161.04137 -140.748471) (xy 161.0119 -140.794326) (xy 160.976203 -140.83552) (xy 160.935007 -140.871214)
			(xy 160.88915 -140.900682) (xy 160.839565 -140.923322) (xy 160.787263 -140.938674) (xy 160.733308 -140.946426)
			(xy 160.706054 -140.946886) (xy 160.678685 -140.946392) (xy 160.624507 -140.938581) (xy 160.572004 -140.923099)
			(xy 160.522256 -140.900263) (xy 160.476288 -140.870545) (xy 160.455356 -140.852906) (xy 160.455102 -140.852652)
			(xy 160.448023 -140.847054) (xy 160.4311 -140.840815) (xy 160.422082 -140.84046) (xy 160.355026 -140.84046)
			(xy 160.346009 -140.840816) (xy 160.329091 -140.847063) (xy 160.322006 -140.852652) (xy 160.322006 -140.852906)
			(xy 160.321752 -140.852906) (xy 160.300812 -140.870535) (xy 160.254841 -140.900248) (xy 160.205096 -140.923086)
			(xy 160.152597 -140.938579) (xy 160.098423 -140.94641) (xy 160.071054 -140.946886) (xy 160.043801 -140.946465)
			(xy 159.989849 -140.938702) (xy 159.937552 -140.923339) (xy 159.887973 -140.900691) (xy 159.842122 -140.871218)
			(xy 159.800932 -140.83552) (xy 159.765241 -140.794323) (xy 159.735776 -140.748467) (xy 159.713137 -140.698884)
			(xy 159.697784 -140.646584) (xy 159.69003 -140.592631) (xy 159.689546 -140.565378) (xy 158.74873 -140.565378)
			(xy 158.74873 -142.60068) (xy 167.705532 -142.60068) (xy 167.705995 -142.573275) (xy 167.713846 -142.51903)
			(xy 167.729383 -142.466469) (xy 167.752287 -142.416674) (xy 167.782085 -142.370671) (xy 167.799766 -142.349728)
			(xy 167.80002 -142.349474) (xy 167.805584 -142.342372) (xy 167.811844 -142.325467) (xy 167.812212 -142.316454)
			(xy 167.812212 -142.249144) (xy 167.811831 -142.24013) (xy 167.8056 -142.223213) (xy 167.80002 -142.216124)
			(xy 167.799512 -142.215616) (xy 167.781869 -142.194687) (xy 167.752157 -142.148714) (xy 167.729322 -142.098965)
			(xy 167.713832 -142.046464) (xy 167.706005 -141.992287) (xy 167.705532 -141.964918) (xy 167.706018 -141.937667)
			(xy 167.713774 -141.883719) (xy 167.729129 -141.831424) (xy 167.751771 -141.781847) (xy 167.781237 -141.735997)
			(xy 167.816928 -141.694806) (xy 167.858119 -141.659115) (xy 167.903969 -141.629649) (xy 167.953546 -141.607007)
			(xy 168.005841 -141.591652) (xy 168.059789 -141.583896) (xy 168.114291 -141.583896) (xy 168.168239 -141.591652)
			(xy 168.220534 -141.607007) (xy 168.270111 -141.629649) (xy 168.315961 -141.659115) (xy 168.357152 -141.694806)
			(xy 168.392843 -141.735997) (xy 168.422309 -141.781847) (xy 168.444951 -141.831424) (xy 168.460306 -141.883719)
			(xy 168.467707 -141.9352) (xy 172.623986 -141.9352) (xy 172.628057 -141.879578) (xy 172.640183 -141.825141)
			(xy 172.660106 -141.77305) (xy 172.687402 -141.724415) (xy 172.721488 -141.680272) (xy 172.761637 -141.641563)
			(xy 172.806995 -141.609112) (xy 172.856595 -141.583611) (xy 172.909379 -141.565604) (xy 172.964222 -141.555474)
			(xy 173.019956 -141.553437) (xy 173.075393 -141.559537) (xy 173.12935 -141.573643) (xy 173.180679 -141.595455)
			(xy 173.228285 -141.624509) (xy 173.271153 -141.660184) (xy 173.30837 -141.701721) (xy 173.339143 -141.748234)
			(xy 173.34856 -141.768322) (xy 231.849166 -141.768322) (xy 231.853237 -141.7127) (xy 231.865363 -141.658263)
			(xy 231.885286 -141.606172) (xy 231.912582 -141.557537) (xy 231.946668 -141.513394) (xy 231.986817 -141.474685)
			(xy 232.032175 -141.442234) (xy 232.081775 -141.416733) (xy 232.134559 -141.398726) (xy 232.189402 -141.388596)
			(xy 232.245136 -141.386559) (xy 232.300573 -141.392659) (xy 232.35453 -141.406765) (xy 232.405859 -141.428577)
			(xy 232.453465 -141.457631) (xy 232.496333 -141.493306) (xy 232.53355 -141.534843) (xy 232.564323 -141.581356)
			(xy 232.587995 -141.631853) (xy 232.604063 -141.68526) (xy 232.612183 -141.740436) (xy 232.612692 -141.768322)
			(xy 232.612183 -141.796208) (xy 232.604063 -141.851384) (xy 232.587995 -141.904791) (xy 232.564323 -141.955288)
			(xy 232.53355 -142.001801) (xy 232.496333 -142.043338) (xy 232.453465 -142.079013) (xy 232.405859 -142.108067)
			(xy 232.35453 -142.129879) (xy 232.300573 -142.143985) (xy 232.245136 -142.150085) (xy 232.189402 -142.148048)
			(xy 232.134559 -142.137918) (xy 232.081775 -142.119911) (xy 232.032175 -142.09441) (xy 231.986817 -142.061959)
			(xy 231.946668 -142.02325) (xy 231.912582 -141.979107) (xy 231.885286 -141.930472) (xy 231.865363 -141.878381)
			(xy 231.853237 -141.823944) (xy 231.849166 -141.768322) (xy 173.34856 -141.768322) (xy 173.362815 -141.798731)
			(xy 173.378883 -141.852138) (xy 173.387003 -141.907314) (xy 173.387512 -141.9352) (xy 173.387003 -141.963086)
			(xy 173.378883 -142.018262) (xy 173.362815 -142.071669) (xy 173.339143 -142.122166) (xy 173.30837 -142.168679)
			(xy 173.271153 -142.210216) (xy 173.228285 -142.245891) (xy 173.180679 -142.274945) (xy 173.12935 -142.296757)
			(xy 173.075393 -142.310863) (xy 173.019956 -142.316963) (xy 172.964222 -142.314926) (xy 172.909379 -142.304796)
			(xy 172.856595 -142.286789) (xy 172.806995 -142.261288) (xy 172.761637 -142.228837) (xy 172.721488 -142.190128)
			(xy 172.687402 -142.145985) (xy 172.660106 -142.09735) (xy 172.640183 -142.045259) (xy 172.628057 -141.990822)
			(xy 172.623986 -141.9352) (xy 168.467707 -141.9352) (xy 168.468062 -141.937667) (xy 168.468548 -141.964918)
			(xy 168.468089 -141.992323) (xy 168.460238 -142.046568) (xy 168.4447 -142.09913) (xy 168.421795 -142.148925)
			(xy 168.391996 -142.194927) (xy 168.374314 -142.21587) (xy 168.37406 -142.216124) (xy 168.368452 -142.223196)
			(xy 168.362219 -142.240124) (xy 168.361868 -142.249144) (xy 168.361868 -142.316454) (xy 168.362254 -142.325468)
			(xy 168.368482 -142.342385) (xy 168.37406 -142.349474) (xy 168.374568 -142.349982) (xy 168.392207 -142.370914)
			(xy 168.42192 -142.416886) (xy 168.444757 -142.466634) (xy 168.460247 -142.519135) (xy 168.468075 -142.573311)
			(xy 168.468548 -142.60068) (xy 168.468062 -142.627931) (xy 168.460306 -142.681879) (xy 168.444951 -142.734174)
			(xy 168.422309 -142.783751) (xy 168.392843 -142.829601) (xy 168.357152 -142.870792) (xy 168.315961 -142.906483)
			(xy 168.270111 -142.935949) (xy 168.236717 -142.9512) (xy 172.640242 -142.9512) (xy 172.644313 -142.895578)
			(xy 172.656439 -142.841141) (xy 172.676362 -142.78905) (xy 172.703658 -142.740415) (xy 172.737744 -142.696272)
			(xy 172.777893 -142.657563) (xy 172.823251 -142.625112) (xy 172.872851 -142.599611) (xy 172.925635 -142.581604)
			(xy 172.980478 -142.571474) (xy 173.036212 -142.569437) (xy 173.091649 -142.575537) (xy 173.145606 -142.589643)
			(xy 173.196935 -142.611455) (xy 173.244541 -142.640509) (xy 173.287409 -142.676184) (xy 173.324626 -142.717721)
			(xy 173.355399 -142.764234) (xy 173.379071 -142.814731) (xy 173.395139 -142.868138) (xy 173.403259 -142.923314)
			(xy 173.403768 -142.9512) (xy 173.403259 -142.979086) (xy 173.395139 -143.034262) (xy 173.379071 -143.087669)
			(xy 173.355399 -143.138166) (xy 173.324626 -143.184679) (xy 173.287409 -143.226216) (xy 173.244541 -143.261891)
			(xy 173.196935 -143.290945) (xy 173.145606 -143.312757) (xy 173.091649 -143.326863) (xy 173.036212 -143.332963)
			(xy 172.980478 -143.330926) (xy 172.925635 -143.320796) (xy 172.872851 -143.302789) (xy 172.823251 -143.277288)
			(xy 172.777893 -143.244837) (xy 172.737744 -143.206128) (xy 172.703658 -143.161985) (xy 172.676362 -143.11335)
			(xy 172.656439 -143.061259) (xy 172.644313 -143.006822) (xy 172.640242 -142.9512) (xy 168.236717 -142.9512)
			(xy 168.220534 -142.958591) (xy 168.168239 -142.973946) (xy 168.114291 -142.981702) (xy 168.059789 -142.981702)
			(xy 168.005841 -142.973946) (xy 167.953546 -142.958591) (xy 167.903969 -142.935949) (xy 167.858119 -142.906483)
			(xy 167.816928 -142.870792) (xy 167.781237 -142.829601) (xy 167.751771 -142.783751) (xy 167.729129 -142.734174)
			(xy 167.713774 -142.681879) (xy 167.706018 -142.627931) (xy 167.705532 -142.60068) (xy 158.74873 -142.60068)
			(xy 158.74873 -143.368014) (xy 158.748305 -143.378084) (xy 158.740591 -143.396687) (xy 158.733744 -143.404082)
			(xy 158.650686 -143.48714) (xy 182.69966 -143.48714) (xy 182.69966 -142.62354) (xy 182.70015 -142.593572)
			(xy 182.707973 -142.53415) (xy 182.723486 -142.476257) (xy 182.746422 -142.420884) (xy 182.776389 -142.368978)
			(xy 182.812876 -142.321428) (xy 182.855256 -142.279048) (xy 182.902806 -142.242561) (xy 182.954712 -142.212594)
			(xy 183.010085 -142.189658) (xy 183.067978 -142.174145) (xy 183.1274 -142.166322) (xy 183.187336 -142.166322)
			(xy 183.246758 -142.174145) (xy 183.304651 -142.189658) (xy 183.360024 -142.212594) (xy 183.41193 -142.242561)
			(xy 183.45948 -142.279048) (xy 183.50186 -142.321428) (xy 183.538347 -142.368978) (xy 183.568314 -142.420884)
			(xy 183.59125 -142.476257) (xy 183.606763 -142.53415) (xy 183.614586 -142.593572) (xy 183.615076 -142.62354)
			(xy 183.615076 -143.479266) (xy 197.174612 -143.479266) (xy 197.174612 -142.615666) (xy 197.175102 -142.585698)
			(xy 197.182925 -142.526276) (xy 197.198438 -142.468383) (xy 197.221374 -142.41301) (xy 197.251341 -142.361104)
			(xy 197.287828 -142.313554) (xy 197.330208 -142.271174) (xy 197.377758 -142.234687) (xy 197.429664 -142.20472)
			(xy 197.485037 -142.181784) (xy 197.54293 -142.166271) (xy 197.602352 -142.158448) (xy 197.662288 -142.158448)
			(xy 197.72171 -142.166271) (xy 197.779603 -142.181784) (xy 197.834976 -142.20472) (xy 197.886882 -142.234687)
			(xy 197.900095 -142.244826) (xy 228.06736 -142.244826) (xy 228.071431 -142.189204) (xy 228.083557 -142.134767)
			(xy 228.10348 -142.082676) (xy 228.130776 -142.034041) (xy 228.164862 -141.989898) (xy 228.205011 -141.951189)
			(xy 228.250369 -141.918738) (xy 228.299969 -141.893237) (xy 228.352753 -141.87523) (xy 228.407596 -141.8651)
			(xy 228.46333 -141.863063) (xy 228.518767 -141.869163) (xy 228.572724 -141.883269) (xy 228.624053 -141.905081)
			(xy 228.671659 -141.934135) (xy 228.714527 -141.96981) (xy 228.751744 -142.011347) (xy 228.782517 -142.05786)
			(xy 228.806189 -142.108357) (xy 228.822257 -142.161764) (xy 228.830377 -142.21694) (xy 228.830886 -142.244826)
			(xy 228.830399 -142.271496) (xy 230.464866 -142.271496) (xy 230.468937 -142.215874) (xy 230.481063 -142.161437)
			(xy 230.500986 -142.109346) (xy 230.528282 -142.060711) (xy 230.562368 -142.016568) (xy 230.602517 -141.977859)
			(xy 230.647875 -141.945408) (xy 230.697475 -141.919907) (xy 230.750259 -141.9019) (xy 230.805102 -141.89177)
			(xy 230.860836 -141.889733) (xy 230.916273 -141.895833) (xy 230.97023 -141.909939) (xy 231.021559 -141.931751)
			(xy 231.069165 -141.960805) (xy 231.112033 -141.99648) (xy 231.14925 -142.038017) (xy 231.180023 -142.08453)
			(xy 231.203695 -142.135027) (xy 231.219763 -142.188434) (xy 231.227883 -142.24361) (xy 231.228392 -142.271496)
			(xy 231.227883 -142.299382) (xy 231.219763 -142.354558) (xy 231.203695 -142.407965) (xy 231.180023 -142.458462)
			(xy 231.14925 -142.504975) (xy 231.112033 -142.546512) (xy 231.069165 -142.582187) (xy 231.021559 -142.611241)
			(xy 230.97023 -142.633053) (xy 230.940551 -142.640812) (xy 234.22305 -142.640812) (xy 234.227121 -142.58519)
			(xy 234.239247 -142.530753) (xy 234.25917 -142.478662) (xy 234.286466 -142.430027) (xy 234.320552 -142.385884)
			(xy 234.360701 -142.347175) (xy 234.406059 -142.314724) (xy 234.455659 -142.289223) (xy 234.508443 -142.271216)
			(xy 234.563286 -142.261086) (xy 234.61902 -142.259049) (xy 234.674457 -142.265149) (xy 234.728414 -142.279255)
			(xy 234.779743 -142.301067) (xy 234.827349 -142.330121) (xy 234.870217 -142.365796) (xy 234.907434 -142.407333)
			(xy 234.938207 -142.453846) (xy 234.961879 -142.504343) (xy 234.977947 -142.55775) (xy 234.986067 -142.612926)
			(xy 234.986576 -142.640812) (xy 234.986067 -142.668698) (xy 234.977947 -142.723874) (xy 234.961879 -142.777281)
			(xy 234.938207 -142.827778) (xy 234.907434 -142.874291) (xy 234.870217 -142.915828) (xy 234.827349 -142.951503)
			(xy 234.779743 -142.980557) (xy 234.728414 -143.002369) (xy 234.674457 -143.016475) (xy 234.61902 -143.022575)
			(xy 234.563286 -143.020538) (xy 234.508443 -143.010408) (xy 234.455659 -142.992401) (xy 234.406059 -142.9669)
			(xy 234.360701 -142.934449) (xy 234.320552 -142.89574) (xy 234.286466 -142.851597) (xy 234.25917 -142.802962)
			(xy 234.239247 -142.750871) (xy 234.227121 -142.696434) (xy 234.22305 -142.640812) (xy 230.940551 -142.640812)
			(xy 230.916273 -142.647159) (xy 230.860836 -142.653259) (xy 230.805102 -142.651222) (xy 230.750259 -142.641092)
			(xy 230.697475 -142.623085) (xy 230.647875 -142.597584) (xy 230.602517 -142.565133) (xy 230.562368 -142.526424)
			(xy 230.528282 -142.482281) (xy 230.500986 -142.433646) (xy 230.481063 -142.381555) (xy 230.468937 -142.327118)
			(xy 230.464866 -142.271496) (xy 228.830399 -142.271496) (xy 228.830377 -142.272712) (xy 228.822257 -142.327888)
			(xy 228.806189 -142.381295) (xy 228.782517 -142.431792) (xy 228.751744 -142.478305) (xy 228.714527 -142.519842)
			(xy 228.671659 -142.555517) (xy 228.624053 -142.584571) (xy 228.572724 -142.606383) (xy 228.518767 -142.620489)
			(xy 228.46333 -142.626589) (xy 228.407596 -142.624552) (xy 228.352753 -142.614422) (xy 228.299969 -142.596415)
			(xy 228.250369 -142.570914) (xy 228.205011 -142.538463) (xy 228.164862 -142.499754) (xy 228.130776 -142.455611)
			(xy 228.10348 -142.406976) (xy 228.083557 -142.354885) (xy 228.071431 -142.300448) (xy 228.06736 -142.244826)
			(xy 197.900095 -142.244826) (xy 197.934432 -142.271174) (xy 197.976812 -142.313554) (xy 198.013299 -142.361104)
			(xy 198.043266 -142.41301) (xy 198.066202 -142.468383) (xy 198.081715 -142.526276) (xy 198.089538 -142.585698)
			(xy 198.090028 -142.615666) (xy 198.090028 -143.479266) (xy 198.089538 -143.509234) (xy 198.081715 -143.568656)
			(xy 198.066202 -143.626549) (xy 198.043266 -143.681922) (xy 198.013299 -143.733828) (xy 197.976812 -143.781378)
			(xy 197.934432 -143.823758) (xy 197.886882 -143.860245) (xy 197.834976 -143.890212) (xy 197.779603 -143.913148)
			(xy 197.72171 -143.928661) (xy 197.662288 -143.936484) (xy 197.602352 -143.936484) (xy 197.54293 -143.928661)
			(xy 197.485037 -143.913148) (xy 197.429664 -143.890212) (xy 197.377758 -143.860245) (xy 197.330208 -143.823758)
			(xy 197.287828 -143.781378) (xy 197.251341 -143.733828) (xy 197.221374 -143.681922) (xy 197.198438 -143.626549)
			(xy 197.182925 -143.568656) (xy 197.175102 -143.509234) (xy 197.174612 -143.479266) (xy 183.615076 -143.479266)
			(xy 183.615076 -143.48714) (xy 183.614586 -143.517108) (xy 183.606763 -143.57653) (xy 183.59125 -143.634423)
			(xy 183.568314 -143.689796) (xy 183.538347 -143.741702) (xy 183.50186 -143.789252) (xy 183.45948 -143.831632)
			(xy 183.41193 -143.868119) (xy 183.360024 -143.898086) (xy 183.304651 -143.921022) (xy 183.246758 -143.936535)
			(xy 183.187336 -143.944358) (xy 183.1274 -143.944358) (xy 183.067978 -143.936535) (xy 183.010085 -143.921022)
			(xy 182.954712 -143.898086) (xy 182.902806 -143.868119) (xy 182.855256 -143.831632) (xy 182.812876 -143.789252)
			(xy 182.776389 -143.741702) (xy 182.746422 -143.689796) (xy 182.723486 -143.634423) (xy 182.707973 -143.57653)
			(xy 182.70015 -143.517108) (xy 182.69966 -143.48714) (xy 158.650686 -143.48714) (xy 156.832046 -145.30578)
			(xy 159.238442 -145.30578) (xy 159.238881 -145.278444) (xy 159.246663 -145.224329) (xy 159.262091 -145.17188)
			(xy 159.284852 -145.122172) (xy 159.314476 -145.076223) (xy 159.350359 -145.034975) (xy 159.391764 -144.999273)
			(xy 159.437843 -144.96985) (xy 159.48765 -144.947308) (xy 159.513778 -144.939258) (xy 159.522649 -144.936279)
			(xy 159.537626 -144.925083) (xy 159.542988 -144.917414) (xy 159.583882 -144.852136) (xy 159.587438 -144.834356)
			(xy 159.585914 -144.825212) (xy 159.585914 -144.824704) (xy 159.583429 -144.809074) (xy 159.58076 -144.777537)
			(xy 159.58058 -144.761712) (xy 159.581089 -144.734462) (xy 159.588844 -144.680515) (xy 159.604197 -144.628222)
			(xy 159.626836 -144.578646) (xy 159.6563 -144.532796) (xy 159.691989 -144.491606) (xy 159.733177 -144.455914)
			(xy 159.779024 -144.426447) (xy 159.828599 -144.403805) (xy 159.880892 -144.388449) (xy 159.934838 -144.380691)
			(xy 159.962088 -144.380204) (xy 159.974059 -144.380319) (xy 159.997952 -144.381842) (xy 160.00984 -144.383252)
			(xy 160.010094 -144.383252) (xy 160.019268 -144.383962) (xy 160.037111 -144.379527) (xy 160.044892 -144.374616)
			(xy 160.101026 -144.3355) (xy 160.108433 -144.329918) (xy 160.11898 -144.314679) (xy 160.1216 -144.305782)
			(xy 160.1216 -144.305528) (xy 160.128585 -144.277974) (xy 160.14962 -144.225167) (xy 160.17826 -144.176067)
			(xy 160.21387 -144.131762) (xy 160.255663 -144.093233) (xy 160.302711 -144.061335) (xy 160.353973 -144.036774)
			(xy 160.408313 -144.020093) (xy 160.464527 -144.011663) (xy 160.492948 -144.011142) (xy 160.517619 -144.011555)
			(xy 160.566545 -144.017955) (xy 160.61424 -144.030605) (xy 160.63722 -144.03959) (xy 160.648323 -144.043494)
			(xy 160.671765 -144.041773) (xy 160.682178 -144.036288) (xy 160.752028 -143.994632) (xy 160.761804 -143.988159)
			(xy 160.774658 -143.968589) (xy 160.776666 -143.95704) (xy 160.776666 -143.956532) (xy 160.780373 -143.928978)
			(xy 160.794634 -143.875244) (xy 160.816545 -143.82415) (xy 160.845644 -143.776779) (xy 160.881313 -143.734136)
			(xy 160.922795 -143.697124) (xy 160.969212 -143.666528) (xy 161.01958 -143.642995) (xy 161.072831 -143.627026)
			(xy 161.127837 -143.618959) (xy 161.155634 -143.618458) (xy 161.182885 -143.618946) (xy 161.23683 -143.626706)
			(xy 161.289123 -143.642064) (xy 161.338698 -143.664707) (xy 161.384547 -143.694173) (xy 161.425736 -143.729864)
			(xy 161.461427 -143.771053) (xy 161.490893 -143.816902) (xy 161.513536 -143.866477) (xy 161.528894 -143.91877)
			(xy 161.536654 -143.972715) (xy 161.537142 -143.999966) (xy 161.536665 -144.026547) (xy 161.529283 -144.079193)
			(xy 161.514658 -144.130303) (xy 161.493074 -144.178885) (xy 161.464949 -144.223997) (xy 161.43083 -144.264764)
			(xy 161.423092 -144.272) (xy 172.486826 -144.272) (xy 172.490897 -144.216378) (xy 172.503023 -144.161941)
			(xy 172.522946 -144.10985) (xy 172.550242 -144.061215) (xy 172.584328 -144.017072) (xy 172.624477 -143.978363)
			(xy 172.669835 -143.945912) (xy 172.719435 -143.920411) (xy 172.772219 -143.902404) (xy 172.827062 -143.892274)
			(xy 172.882796 -143.890237) (xy 172.938233 -143.896337) (xy 172.99219 -143.910443) (xy 173.043519 -143.932255)
			(xy 173.064569 -143.945102) (xy 225.0219 -143.945102) (xy 225.025971 -143.88948) (xy 225.038097 -143.835043)
			(xy 225.05802 -143.782952) (xy 225.085316 -143.734317) (xy 225.119402 -143.690174) (xy 225.159551 -143.651465)
			(xy 225.204909 -143.619014) (xy 225.254509 -143.593513) (xy 225.307293 -143.575506) (xy 225.362136 -143.565376)
			(xy 225.41787 -143.563339) (xy 225.473307 -143.569439) (xy 225.527264 -143.583545) (xy 225.578593 -143.605357)
			(xy 225.626199 -143.634411) (xy 225.669067 -143.670086) (xy 225.706284 -143.711623) (xy 225.737057 -143.758136)
			(xy 225.760729 -143.808633) (xy 225.776797 -143.86204) (xy 225.784917 -143.917216) (xy 225.785426 -143.945102)
			(xy 225.784917 -143.972988) (xy 225.776797 -144.028164) (xy 225.760729 -144.081571) (xy 225.737057 -144.132068)
			(xy 225.706284 -144.178581) (xy 225.669067 -144.220118) (xy 225.626199 -144.255793) (xy 225.578593 -144.284847)
			(xy 225.527264 -144.306659) (xy 225.473307 -144.320765) (xy 225.41787 -144.326865) (xy 225.362136 -144.324828)
			(xy 225.307293 -144.314698) (xy 225.254509 -144.296691) (xy 225.204909 -144.27119) (xy 225.159551 -144.238739)
			(xy 225.119402 -144.20003) (xy 225.085316 -144.155887) (xy 225.05802 -144.107252) (xy 225.038097 -144.055161)
			(xy 225.025971 -144.000724) (xy 225.0219 -143.945102) (xy 173.064569 -143.945102) (xy 173.091125 -143.961309)
			(xy 173.133993 -143.996984) (xy 173.17121 -144.038521) (xy 173.201983 -144.085034) (xy 173.225655 -144.135531)
			(xy 173.241723 -144.188938) (xy 173.249843 -144.244114) (xy 173.250352 -144.272) (xy 173.249843 -144.299886)
			(xy 173.241723 -144.355062) (xy 173.225655 -144.408469) (xy 173.201983 -144.458966) (xy 173.17121 -144.505479)
			(xy 173.133993 -144.547016) (xy 173.091125 -144.582691) (xy 173.043519 -144.611745) (xy 172.99219 -144.633557)
			(xy 172.938233 -144.647663) (xy 172.882796 -144.653763) (xy 172.827062 -144.651726) (xy 172.772219 -144.641596)
			(xy 172.719435 -144.623589) (xy 172.669835 -144.598088) (xy 172.624477 -144.565637) (xy 172.584328 -144.526928)
			(xy 172.550242 -144.482785) (xy 172.522946 -144.43415) (xy 172.503023 -144.382059) (xy 172.490897 -144.327622)
			(xy 172.486826 -144.272) (xy 161.423092 -144.272) (xy 161.411412 -144.282922) (xy 161.404814 -144.28939)
			(xy 161.396354 -144.305801) (xy 161.394902 -144.314926) (xy 161.387536 -144.381474) (xy 161.386788 -144.39065)
			(xy 161.391233 -144.408501) (xy 161.396172 -144.416272) (xy 161.412288 -144.440397) (xy 161.437822 -144.492491)
			(xy 161.455179 -144.547849) (xy 161.463958 -144.605196) (xy 161.464498 -144.634204) (xy 161.464048 -144.661457)
			(xy 161.456291 -144.715409) (xy 161.440934 -144.767708) (xy 161.41829 -144.817289) (xy 161.38882 -144.863142)
			(xy 161.353125 -144.904335) (xy 161.311931 -144.940029) (xy 161.266077 -144.969497) (xy 161.216495 -144.992138)
			(xy 161.164196 -145.007494) (xy 161.110243 -145.015249) (xy 161.08299 -145.015712) (xy 161.082482 -145.015712)
			(xy 161.072685 -145.015648) (xy 161.053117 -145.014631) (xy 161.043366 -145.01368) (xy 161.043112 -145.01368)
			(xy 161.033722 -145.013065) (xy 161.015584 -145.018034) (xy 161.007806 -145.023332) (xy 160.944814 -145.070068)
			(xy 160.934908 -145.08607) (xy 160.93313 -145.095722) (xy 160.927734 -145.121559) (xy 160.910803 -145.17155)
			(xy 160.887143 -145.21873) (xy 160.857206 -145.262199) (xy 160.83428 -145.287238) (xy 180.84546 -145.287238)
			(xy 180.84546 -144.423638) (xy 180.84595 -144.39367) (xy 180.853773 -144.334248) (xy 180.869286 -144.276355)
			(xy 180.892222 -144.220982) (xy 180.922189 -144.169076) (xy 180.958676 -144.121526) (xy 181.001056 -144.079146)
			(xy 181.048606 -144.042659) (xy 181.100512 -144.012692) (xy 181.155885 -143.989756) (xy 181.213778 -143.974243)
			(xy 181.2732 -143.96642) (xy 181.333136 -143.96642) (xy 181.392558 -143.974243) (xy 181.450451 -143.989756)
			(xy 181.505824 -144.012692) (xy 181.55773 -144.042659) (xy 181.60528 -144.079146) (xy 181.64766 -144.121526)
			(xy 181.684147 -144.169076) (xy 181.714114 -144.220982) (xy 181.73705 -144.276355) (xy 181.752563 -144.334248)
			(xy 181.760386 -144.39367) (xy 181.760876 -144.423638) (xy 181.760876 -145.285714) (xy 199.81672 -145.285714)
			(xy 199.81672 -144.422114) (xy 199.81721 -144.392146) (xy 199.825033 -144.332724) (xy 199.840546 -144.274831)
			(xy 199.863482 -144.219458) (xy 199.893449 -144.167552) (xy 199.929936 -144.120002) (xy 199.972316 -144.077622)
			(xy 200.019866 -144.041135) (xy 200.071772 -144.011168) (xy 200.127145 -143.988232) (xy 200.185038 -143.972719)
			(xy 200.24446 -143.964896) (xy 200.304396 -143.964896) (xy 200.363818 -143.972719) (xy 200.421711 -143.988232)
			(xy 200.477084 -144.011168) (xy 200.52899 -144.041135) (xy 200.57654 -144.077622) (xy 200.61892 -144.120002)
			(xy 200.655407 -144.167552) (xy 200.685374 -144.219458) (xy 200.70831 -144.274831) (xy 200.723823 -144.332724)
			(xy 200.731646 -144.392146) (xy 200.732136 -144.422114) (xy 200.732136 -144.672812) (xy 234.175044 -144.672812)
			(xy 234.179115 -144.61719) (xy 234.191241 -144.562753) (xy 234.211164 -144.510662) (xy 234.23846 -144.462027)
			(xy 234.272546 -144.417884) (xy 234.312695 -144.379175) (xy 234.358053 -144.346724) (xy 234.407653 -144.321223)
			(xy 234.460437 -144.303216) (xy 234.51528 -144.293086) (xy 234.571014 -144.291049) (xy 234.626451 -144.297149)
			(xy 234.680408 -144.311255) (xy 234.731737 -144.333067) (xy 234.779343 -144.362121) (xy 234.822211 -144.397796)
			(xy 234.859428 -144.439333) (xy 234.890201 -144.485846) (xy 234.913873 -144.536343) (xy 234.929941 -144.58975)
			(xy 234.938061 -144.644926) (xy 234.93857 -144.672812) (xy 234.938061 -144.700698) (xy 234.929941 -144.755874)
			(xy 234.913873 -144.809281) (xy 234.890201 -144.859778) (xy 234.859428 -144.906291) (xy 234.822211 -144.947828)
			(xy 234.779343 -144.983503) (xy 234.731737 -145.012557) (xy 234.680408 -145.034369) (xy 234.626451 -145.048475)
			(xy 234.571014 -145.054575) (xy 234.51528 -145.052538) (xy 234.460437 -145.042408) (xy 234.407653 -145.024401)
			(xy 234.358053 -144.9989) (xy 234.312695 -144.966449) (xy 234.272546 -144.92774) (xy 234.23846 -144.883597)
			(xy 234.211164 -144.834962) (xy 234.191241 -144.782871) (xy 234.179115 -144.728434) (xy 234.175044 -144.672812)
			(xy 200.732136 -144.672812) (xy 200.732136 -145.140426) (xy 222.363028 -145.140426) (xy 222.367099 -145.084804)
			(xy 222.379225 -145.030367) (xy 222.399148 -144.978276) (xy 222.426444 -144.929641) (xy 222.46053 -144.885498)
			(xy 222.500679 -144.846789) (xy 222.546037 -144.814338) (xy 222.595637 -144.788837) (xy 222.648421 -144.77083)
			(xy 222.703264 -144.7607) (xy 222.758998 -144.758663) (xy 222.814435 -144.764763) (xy 222.868392 -144.778869)
			(xy 222.919721 -144.800681) (xy 222.967327 -144.829735) (xy 223.010195 -144.86541) (xy 223.047412 -144.906947)
			(xy 223.078185 -144.95346) (xy 223.101857 -145.003957) (xy 223.117925 -145.057364) (xy 223.126045 -145.11254)
			(xy 223.126554 -145.140426) (xy 223.126045 -145.168312) (xy 223.117925 -145.223488) (xy 223.101857 -145.276895)
			(xy 223.078185 -145.327392) (xy 223.047412 -145.373905) (xy 223.010195 -145.415442) (xy 222.967327 -145.451117)
			(xy 222.919721 -145.480171) (xy 222.868392 -145.501983) (xy 222.814435 -145.516089) (xy 222.758998 -145.522189)
			(xy 222.703264 -145.520152) (xy 222.648421 -145.510022) (xy 222.595637 -145.492015) (xy 222.546037 -145.466514)
			(xy 222.500679 -145.434063) (xy 222.46053 -145.395354) (xy 222.426444 -145.351211) (xy 222.399148 -145.302576)
			(xy 222.379225 -145.250485) (xy 222.367099 -145.196048) (xy 222.363028 -145.140426) (xy 200.732136 -145.140426)
			(xy 200.732136 -145.285714) (xy 200.731646 -145.315682) (xy 200.723823 -145.375104) (xy 200.70831 -145.432997)
			(xy 200.685374 -145.48837) (xy 200.655407 -145.540276) (xy 200.61892 -145.587826) (xy 200.57654 -145.630206)
			(xy 200.52899 -145.666693) (xy 200.477084 -145.69666) (xy 200.421711 -145.719596) (xy 200.363818 -145.735109)
			(xy 200.304396 -145.742932) (xy 200.24446 -145.742932) (xy 200.185038 -145.735109) (xy 200.127145 -145.719596)
			(xy 200.071772 -145.69666) (xy 200.019866 -145.666693) (xy 199.972316 -145.630206) (xy 199.929936 -145.587826)
			(xy 199.893449 -145.540276) (xy 199.863482 -145.48837) (xy 199.840546 -145.432997) (xy 199.825033 -145.375104)
			(xy 199.81721 -145.315682) (xy 199.81672 -145.285714) (xy 181.760876 -145.285714) (xy 181.760876 -145.287238)
			(xy 181.760386 -145.317206) (xy 181.752563 -145.376628) (xy 181.73705 -145.434521) (xy 181.714114 -145.489894)
			(xy 181.684147 -145.5418) (xy 181.64766 -145.58935) (xy 181.60528 -145.63173) (xy 181.55773 -145.668217)
			(xy 181.505824 -145.698184) (xy 181.450451 -145.72112) (xy 181.392558 -145.736633) (xy 181.333136 -145.744456)
			(xy 181.2732 -145.744456) (xy 181.213778 -145.736633) (xy 181.155885 -145.72112) (xy 181.100512 -145.698184)
			(xy 181.048606 -145.668217) (xy 181.001056 -145.63173) (xy 180.958676 -145.58935) (xy 180.922189 -145.5418)
			(xy 180.892222 -145.489894) (xy 180.869286 -145.434521) (xy 180.853773 -145.376628) (xy 180.84595 -145.317206)
			(xy 180.84546 -145.287238) (xy 160.83428 -145.287238) (xy 160.821564 -145.301126) (xy 160.780896 -145.33477)
			(xy 160.73598 -145.362487) (xy 160.687672 -145.383749) (xy 160.636894 -145.39815) (xy 160.584616 -145.405415)
			(xy 160.558226 -145.405856) (xy 160.530675 -145.405407) (xy 160.476146 -145.397484) (xy 160.423324 -145.381797)
			(xy 160.373308 -145.358674) (xy 160.32714 -145.328596) (xy 160.285779 -145.292189) (xy 160.250086 -145.25021)
			(xy 160.220804 -145.203532) (xy 160.20923 -145.178526) (xy 160.20542 -145.16989) (xy 160.191958 -145.156428)
			(xy 160.111694 -145.121122) (xy 160.093152 -145.120106) (xy 160.084262 -145.1229) (xy 160.083246 -145.123408)
			(xy 160.06826 -145.128234) (xy 160.059395 -145.13123) (xy 160.044415 -145.142414) (xy 160.03905 -145.150078)
			(xy 159.998156 -145.215356) (xy 159.9946 -145.233136) (xy 159.996124 -145.24228) (xy 159.996124 -145.242788)
			(xy 159.998608 -145.258418) (xy 160.001277 -145.289955) (xy 160.001458 -145.30578) (xy 160.000972 -145.333031)
			(xy 159.993216 -145.386979) (xy 159.977861 -145.439274) (xy 159.955219 -145.488851) (xy 159.925753 -145.534701)
			(xy 159.890062 -145.575892) (xy 159.848871 -145.611583) (xy 159.803021 -145.641049) (xy 159.753444 -145.663691)
			(xy 159.701149 -145.679046) (xy 159.647201 -145.686802) (xy 159.592699 -145.686802) (xy 159.538751 -145.679046)
			(xy 159.486456 -145.663691) (xy 159.436879 -145.641049) (xy 159.391029 -145.611583) (xy 159.349838 -145.575892)
			(xy 159.314147 -145.534701) (xy 159.284681 -145.488851) (xy 159.262039 -145.439274) (xy 159.246684 -145.386979)
			(xy 159.238928 -145.333031) (xy 159.238442 -145.30578) (xy 156.832046 -145.30578) (xy 156.574744 -145.563082)
			(xy 156.567343 -145.569921) (xy 156.548745 -145.577638) (xy 156.538676 -145.578068) (xy 153.558494 -145.578068)
			(xy 153.553618 -145.578169) (xy 153.544032 -145.579968) (xy 153.539444 -145.581624) (xy 153.5303 -145.585434)
			(xy 152.57272 -146.543014) (xy 152.570015 -146.545866) (xy 152.565425 -146.552246) (xy 152.563576 -146.555714)
			(xy 152.560991 -146.561141) (xy 152.558162 -146.57282) (xy 152.557988 -146.578828) (xy 152.557988 -146.739864)
			(xy 165.009828 -146.739864) (xy 165.013899 -146.684242) (xy 165.026025 -146.629805) (xy 165.045948 -146.577714)
			(xy 165.073244 -146.529079) (xy 165.10733 -146.484936) (xy 165.147479 -146.446227) (xy 165.192837 -146.413776)
			(xy 165.242437 -146.388275) (xy 165.295221 -146.370268) (xy 165.350064 -146.360138) (xy 165.405798 -146.358101)
			(xy 165.461235 -146.364201) (xy 165.515192 -146.378307) (xy 165.566521 -146.400119) (xy 165.614127 -146.429173)
			(xy 165.656995 -146.464848) (xy 165.694212 -146.506385) (xy 165.724985 -146.552898) (xy 165.748657 -146.603395)
			(xy 165.764725 -146.656802) (xy 165.772845 -146.711978) (xy 165.773354 -146.739864) (xy 165.772845 -146.76775)
			(xy 165.768688 -146.795998) (xy 166.643556 -146.795998) (xy 166.647627 -146.740376) (xy 166.659753 -146.685939)
			(xy 166.679676 -146.633848) (xy 166.706972 -146.585213) (xy 166.741058 -146.54107) (xy 166.781207 -146.502361)
			(xy 166.826565 -146.46991) (xy 166.876165 -146.444409) (xy 166.928949 -146.426402) (xy 166.983792 -146.416272)
			(xy 167.039526 -146.414235) (xy 167.094963 -146.420335) (xy 167.14892 -146.434441) (xy 167.200249 -146.456253)
			(xy 167.247855 -146.485307) (xy 167.290723 -146.520982) (xy 167.32794 -146.562519) (xy 167.358713 -146.609032)
			(xy 167.382385 -146.659529) (xy 167.398453 -146.712936) (xy 167.406573 -146.768112) (xy 167.407082 -146.795998)
			(xy 167.406573 -146.823884) (xy 167.398453 -146.87906) (xy 167.382385 -146.932467) (xy 167.358713 -146.982964)
			(xy 167.32794 -147.029477) (xy 167.290723 -147.071014) (xy 167.27111 -147.087336) (xy 182.69966 -147.087336)
			(xy 182.69966 -146.223736) (xy 182.70015 -146.193768) (xy 182.707973 -146.134346) (xy 182.723486 -146.076453)
			(xy 182.746422 -146.02108) (xy 182.776389 -145.969174) (xy 182.812876 -145.921624) (xy 182.855256 -145.879244)
			(xy 182.902806 -145.842757) (xy 182.954712 -145.81279) (xy 183.010085 -145.789854) (xy 183.067978 -145.774341)
			(xy 183.1274 -145.766518) (xy 183.187336 -145.766518) (xy 183.246758 -145.774341) (xy 183.304651 -145.789854)
			(xy 183.360024 -145.81279) (xy 183.41193 -145.842757) (xy 183.45948 -145.879244) (xy 183.50186 -145.921624)
			(xy 183.538347 -145.969174) (xy 183.568314 -146.02108) (xy 183.59125 -146.076453) (xy 183.606763 -146.134346)
			(xy 183.614586 -146.193768) (xy 183.615076 -146.223736) (xy 183.615076 -147.079208) (xy 197.174612 -147.079208)
			(xy 197.174612 -146.215608) (xy 197.175102 -146.18564) (xy 197.182925 -146.126218) (xy 197.198438 -146.068325)
			(xy 197.221374 -146.012952) (xy 197.251341 -145.961046) (xy 197.287828 -145.913496) (xy 197.330208 -145.871116)
			(xy 197.377758 -145.834629) (xy 197.429664 -145.804662) (xy 197.485037 -145.781726) (xy 197.54293 -145.766213)
			(xy 197.602352 -145.75839) (xy 197.662288 -145.75839) (xy 197.72171 -145.766213) (xy 197.779603 -145.781726)
			(xy 197.834976 -145.804662) (xy 197.886882 -145.834629) (xy 197.934432 -145.871116) (xy 197.976812 -145.913496)
			(xy 198.013299 -145.961046) (xy 198.021102 -145.974562) (xy 219.859604 -145.974562) (xy 219.863675 -145.91894)
			(xy 219.875801 -145.864503) (xy 219.895724 -145.812412) (xy 219.92302 -145.763777) (xy 219.957106 -145.719634)
			(xy 219.997255 -145.680925) (xy 220.042613 -145.648474) (xy 220.092213 -145.622973) (xy 220.144997 -145.604966)
			(xy 220.19984 -145.594836) (xy 220.255574 -145.592799) (xy 220.311011 -145.598899) (xy 220.364968 -145.613005)
			(xy 220.416297 -145.634817) (xy 220.463903 -145.663871) (xy 220.506771 -145.699546) (xy 220.543988 -145.741083)
			(xy 220.574761 -145.787596) (xy 220.598433 -145.838093) (xy 220.614501 -145.8915) (xy 220.622621 -145.946676)
			(xy 220.62313 -145.974562) (xy 220.622621 -146.002448) (xy 220.614501 -146.057624) (xy 220.598433 -146.111031)
			(xy 220.574761 -146.161528) (xy 220.543988 -146.208041) (xy 220.506771 -146.249578) (xy 220.463903 -146.285253)
			(xy 220.416297 -146.314307) (xy 220.364968 -146.336119) (xy 220.311011 -146.350225) (xy 220.255574 -146.356325)
			(xy 220.19984 -146.354288) (xy 220.144997 -146.344158) (xy 220.092213 -146.326151) (xy 220.042613 -146.30065)
			(xy 219.997255 -146.268199) (xy 219.957106 -146.22949) (xy 219.92302 -146.185347) (xy 219.895724 -146.136712)
			(xy 219.875801 -146.084621) (xy 219.863675 -146.030184) (xy 219.859604 -145.974562) (xy 198.021102 -145.974562)
			(xy 198.043266 -146.012952) (xy 198.066202 -146.068325) (xy 198.081715 -146.126218) (xy 198.089538 -146.18564)
			(xy 198.090028 -146.215608) (xy 198.090028 -146.990562) (xy 221.941642 -146.990562) (xy 221.945713 -146.93494)
			(xy 221.957839 -146.880503) (xy 221.977762 -146.828412) (xy 222.005058 -146.779777) (xy 222.039144 -146.735634)
			(xy 222.079293 -146.696925) (xy 222.124651 -146.664474) (xy 222.174251 -146.638973) (xy 222.227035 -146.620966)
			(xy 222.281878 -146.610836) (xy 222.337612 -146.608799) (xy 222.393049 -146.614899) (xy 222.447006 -146.629005)
			(xy 222.48852 -146.646646) (xy 223.425256 -146.646646) (xy 223.429327 -146.591024) (xy 223.441453 -146.536587)
			(xy 223.461376 -146.484496) (xy 223.488672 -146.435861) (xy 223.522758 -146.391718) (xy 223.562907 -146.353009)
			(xy 223.608265 -146.320558) (xy 223.657865 -146.295057) (xy 223.710649 -146.27705) (xy 223.765492 -146.26692)
			(xy 223.821226 -146.264883) (xy 223.876663 -146.270983) (xy 223.93062 -146.285089) (xy 223.981949 -146.306901)
			(xy 224.029555 -146.335955) (xy 224.072423 -146.37163) (xy 224.10964 -146.413167) (xy 224.140413 -146.45968)
			(xy 224.164085 -146.510177) (xy 224.180153 -146.563584) (xy 224.188273 -146.61876) (xy 224.188782 -146.646646)
			(xy 224.188273 -146.674532) (xy 224.180153 -146.729708) (xy 224.164085 -146.783115) (xy 224.140413 -146.833612)
			(xy 224.10964 -146.880125) (xy 224.072423 -146.921662) (xy 224.029555 -146.957337) (xy 223.981949 -146.986391)
			(xy 223.93062 -147.008203) (xy 223.876663 -147.022309) (xy 223.821226 -147.028409) (xy 223.765492 -147.026372)
			(xy 223.710649 -147.016242) (xy 223.657865 -146.998235) (xy 223.608265 -146.972734) (xy 223.562907 -146.940283)
			(xy 223.522758 -146.901574) (xy 223.488672 -146.857431) (xy 223.461376 -146.808796) (xy 223.441453 -146.756705)
			(xy 223.429327 -146.702268) (xy 223.425256 -146.646646) (xy 222.48852 -146.646646) (xy 222.498335 -146.650817)
			(xy 222.545941 -146.679871) (xy 222.588809 -146.715546) (xy 222.626026 -146.757083) (xy 222.656799 -146.803596)
			(xy 222.680471 -146.854093) (xy 222.696539 -146.9075) (xy 222.704659 -146.962676) (xy 222.705168 -146.990562)
			(xy 222.704659 -147.018448) (xy 222.696539 -147.073624) (xy 222.680471 -147.127031) (xy 222.656799 -147.177528)
			(xy 222.649045 -147.189248) (xy 233.05469 -147.189248) (xy 233.05469 -147.134752) (xy 233.062445 -147.08081)
			(xy 233.077797 -147.028521) (xy 233.100434 -146.978948) (xy 233.129895 -146.933102) (xy 233.16558 -146.891914)
			(xy 233.206763 -146.856224) (xy 233.252606 -146.826757) (xy 233.302176 -146.804114) (xy 233.354463 -146.788755)
			(xy 233.408404 -146.780994) (xy 233.435652 -146.780504) (xy 233.467273 -146.781113) (xy 233.529646 -146.791567)
			(xy 233.589436 -146.812179) (xy 233.617516 -146.826732) (xy 233.625869 -146.830746) (xy 233.644237 -146.833091)
			(xy 233.65333 -146.831304) (xy 233.728514 -146.813524) (xy 233.744262 -146.802856) (xy 233.749342 -146.795236)
			(xy 233.764731 -146.773932) (xy 233.80036 -146.735302) (xy 233.840952 -146.701925) (xy 233.885739 -146.674433)
			(xy 233.933874 -146.653344) (xy 233.984447 -146.639058) (xy 234.036502 -146.631846) (xy 234.062778 -146.631406)
			(xy 234.090033 -146.631839) (xy 234.143988 -146.639594) (xy 234.196291 -146.654949) (xy 234.245876 -146.677591)
			(xy 234.291733 -146.707059) (xy 234.33293 -146.742754) (xy 234.368627 -146.783949) (xy 234.398099 -146.829805)
			(xy 234.420743 -146.879389) (xy 234.436101 -146.93169) (xy 234.443859 -146.985645) (xy 234.443859 -147.040155)
			(xy 234.436101 -147.09411) (xy 234.420743 -147.146411) (xy 234.398099 -147.195995) (xy 234.368627 -147.241851)
			(xy 234.33293 -147.283046) (xy 234.291733 -147.318741) (xy 234.245876 -147.348209) (xy 234.196291 -147.370851)
			(xy 234.143988 -147.386206) (xy 234.090033 -147.393961) (xy 234.062778 -147.394422) (xy 234.031157 -147.393809)
			(xy 233.968784 -147.383359) (xy 233.908994 -147.362748) (xy 233.880914 -147.348194) (xy 233.872555 -147.344195)
			(xy 233.854192 -147.34184) (xy 233.8451 -147.343622) (xy 233.769916 -147.361402) (xy 233.754168 -147.37207)
			(xy 233.749088 -147.37969) (xy 233.733751 -147.401032) (xy 233.698112 -147.43966) (xy 233.657511 -147.473033)
			(xy 233.612715 -147.500521) (xy 233.564572 -147.521603) (xy 233.513991 -147.535881) (xy 233.461931 -147.543085)
			(xy 233.435652 -147.54352) (xy 233.408404 -147.543006) (xy 233.354463 -147.535245) (xy 233.302176 -147.519886)
			(xy 233.252606 -147.497243) (xy 233.206763 -147.467776) (xy 233.16558 -147.432086) (xy 233.129895 -147.390898)
			(xy 233.100434 -147.345052) (xy 233.077797 -147.295479) (xy 233.062445 -147.24319) (xy 233.05469 -147.189248)
			(xy 222.649045 -147.189248) (xy 222.626026 -147.224041) (xy 222.588809 -147.265578) (xy 222.545941 -147.301253)
			(xy 222.498335 -147.330307) (xy 222.447006 -147.352119) (xy 222.393049 -147.366225) (xy 222.337612 -147.372325)
			(xy 222.281878 -147.370288) (xy 222.227035 -147.360158) (xy 222.174251 -147.342151) (xy 222.124651 -147.31665)
			(xy 222.079293 -147.284199) (xy 222.039144 -147.24549) (xy 222.005058 -147.201347) (xy 221.977762 -147.152712)
			(xy 221.957839 -147.100621) (xy 221.945713 -147.046184) (xy 221.941642 -146.990562) (xy 198.090028 -146.990562)
			(xy 198.090028 -147.079208) (xy 198.089538 -147.109176) (xy 198.081715 -147.168598) (xy 198.066202 -147.226491)
			(xy 198.043266 -147.281864) (xy 198.013299 -147.33377) (xy 197.976812 -147.38132) (xy 197.934432 -147.4237)
			(xy 197.886882 -147.460187) (xy 197.834976 -147.490154) (xy 197.779603 -147.51309) (xy 197.72171 -147.528603)
			(xy 197.662288 -147.536426) (xy 197.602352 -147.536426) (xy 197.54293 -147.528603) (xy 197.485037 -147.51309)
			(xy 197.429664 -147.490154) (xy 197.377758 -147.460187) (xy 197.330208 -147.4237) (xy 197.287828 -147.38132)
			(xy 197.251341 -147.33377) (xy 197.221374 -147.281864) (xy 197.198438 -147.226491) (xy 197.182925 -147.168598)
			(xy 197.175102 -147.109176) (xy 197.174612 -147.079208) (xy 183.615076 -147.079208) (xy 183.615076 -147.087336)
			(xy 183.614586 -147.117304) (xy 183.606763 -147.176726) (xy 183.59125 -147.234619) (xy 183.568314 -147.289992)
			(xy 183.538347 -147.341898) (xy 183.50186 -147.389448) (xy 183.45948 -147.431828) (xy 183.41193 -147.468315)
			(xy 183.360024 -147.498282) (xy 183.304651 -147.521218) (xy 183.246758 -147.536731) (xy 183.187336 -147.544554)
			(xy 183.1274 -147.544554) (xy 183.067978 -147.536731) (xy 183.010085 -147.521218) (xy 182.954712 -147.498282)
			(xy 182.902806 -147.468315) (xy 182.855256 -147.431828) (xy 182.812876 -147.389448) (xy 182.776389 -147.341898)
			(xy 182.746422 -147.289992) (xy 182.723486 -147.234619) (xy 182.707973 -147.176726) (xy 182.70015 -147.117304)
			(xy 182.69966 -147.087336) (xy 167.27111 -147.087336) (xy 167.247855 -147.106689) (xy 167.200249 -147.135743)
			(xy 167.14892 -147.157555) (xy 167.094963 -147.171661) (xy 167.039526 -147.177761) (xy 166.983792 -147.175724)
			(xy 166.928949 -147.165594) (xy 166.876165 -147.147587) (xy 166.826565 -147.122086) (xy 166.781207 -147.089635)
			(xy 166.741058 -147.050926) (xy 166.706972 -147.006783) (xy 166.679676 -146.958148) (xy 166.659753 -146.906057)
			(xy 166.647627 -146.85162) (xy 166.643556 -146.795998) (xy 165.768688 -146.795998) (xy 165.764725 -146.822926)
			(xy 165.748657 -146.876333) (xy 165.724985 -146.92683) (xy 165.694212 -146.973343) (xy 165.656995 -147.01488)
			(xy 165.614127 -147.050555) (xy 165.566521 -147.079609) (xy 165.515192 -147.101421) (xy 165.461235 -147.115527)
			(xy 165.405798 -147.121627) (xy 165.350064 -147.11959) (xy 165.295221 -147.10946) (xy 165.242437 -147.091453)
			(xy 165.192837 -147.065952) (xy 165.147479 -147.033501) (xy 165.10733 -146.994792) (xy 165.073244 -146.950649)
			(xy 165.045948 -146.902014) (xy 165.026025 -146.849923) (xy 165.013899 -146.795486) (xy 165.009828 -146.739864)
			(xy 152.557988 -146.739864) (xy 152.557988 -148.887434) (xy 180.84546 -148.887434) (xy 180.84546 -148.023834)
			(xy 180.84595 -147.993866) (xy 180.853773 -147.934444) (xy 180.869286 -147.876551) (xy 180.892222 -147.821178)
			(xy 180.922189 -147.769272) (xy 180.958676 -147.721722) (xy 181.001056 -147.679342) (xy 181.048606 -147.642855)
			(xy 181.100512 -147.612888) (xy 181.155885 -147.589952) (xy 181.213778 -147.574439) (xy 181.2732 -147.566616)
			(xy 181.333136 -147.566616) (xy 181.392558 -147.574439) (xy 181.450451 -147.589952) (xy 181.505824 -147.612888)
			(xy 181.55773 -147.642855) (xy 181.60528 -147.679342) (xy 181.64766 -147.721722) (xy 181.684147 -147.769272)
			(xy 181.714114 -147.821178) (xy 181.73705 -147.876551) (xy 181.752563 -147.934444) (xy 181.760386 -147.993866)
			(xy 181.760876 -148.023834) (xy 181.760876 -148.88591) (xy 199.81672 -148.88591) (xy 199.81672 -148.02231)
			(xy 199.81721 -147.992342) (xy 199.825033 -147.93292) (xy 199.840546 -147.875027) (xy 199.863482 -147.819654)
			(xy 199.893449 -147.767748) (xy 199.929936 -147.720198) (xy 199.972316 -147.677818) (xy 200.019866 -147.641331)
			(xy 200.071772 -147.611364) (xy 200.127145 -147.588428) (xy 200.185038 -147.572915) (xy 200.24446 -147.565092)
			(xy 200.304396 -147.565092) (xy 200.363818 -147.572915) (xy 200.421711 -147.588428) (xy 200.477084 -147.611364)
			(xy 200.52899 -147.641331) (xy 200.57654 -147.677818) (xy 200.61892 -147.720198) (xy 200.619391 -147.720812)
			(xy 234.212128 -147.720812) (xy 234.216199 -147.66519) (xy 234.228325 -147.610753) (xy 234.248248 -147.558662)
			(xy 234.275544 -147.510027) (xy 234.30963 -147.465884) (xy 234.349779 -147.427175) (xy 234.395137 -147.394724)
			(xy 234.444737 -147.369223) (xy 234.497521 -147.351216) (xy 234.552364 -147.341086) (xy 234.608098 -147.339049)
			(xy 234.663535 -147.345149) (xy 234.717492 -147.359255) (xy 234.768821 -147.381067) (xy 234.816427 -147.410121)
			(xy 234.859295 -147.445796) (xy 234.896512 -147.487333) (xy 234.927285 -147.533846) (xy 234.950957 -147.584343)
			(xy 234.967025 -147.63775) (xy 234.975145 -147.692926) (xy 234.975654 -147.720812) (xy 236.25124 -147.720812)
			(xy 236.255311 -147.66519) (xy 236.267437 -147.610753) (xy 236.28736 -147.558662) (xy 236.314656 -147.510027)
			(xy 236.348742 -147.465884) (xy 236.388891 -147.427175) (xy 236.434249 -147.394724) (xy 236.483849 -147.369223)
			(xy 236.536633 -147.351216) (xy 236.591476 -147.341086) (xy 236.64721 -147.339049) (xy 236.702647 -147.345149)
			(xy 236.756604 -147.359255) (xy 236.807933 -147.381067) (xy 236.855539 -147.410121) (xy 236.898407 -147.445796)
			(xy 236.935624 -147.487333) (xy 236.966397 -147.533846) (xy 236.990069 -147.584343) (xy 237.006137 -147.63775)
			(xy 237.014257 -147.692926) (xy 237.014766 -147.720812) (xy 237.014257 -147.748698) (xy 237.006137 -147.803874)
			(xy 236.990069 -147.857281) (xy 236.966397 -147.907778) (xy 236.935624 -147.954291) (xy 236.898407 -147.995828)
			(xy 236.855539 -148.031503) (xy 236.807933 -148.060557) (xy 236.756604 -148.082369) (xy 236.702647 -148.096475)
			(xy 236.64721 -148.102575) (xy 236.591476 -148.100538) (xy 236.536633 -148.090408) (xy 236.483849 -148.072401)
			(xy 236.434249 -148.0469) (xy 236.388891 -148.014449) (xy 236.348742 -147.97574) (xy 236.314656 -147.931597)
			(xy 236.28736 -147.882962) (xy 236.267437 -147.830871) (xy 236.255311 -147.776434) (xy 236.25124 -147.720812)
			(xy 234.975654 -147.720812) (xy 234.975145 -147.748698) (xy 234.967025 -147.803874) (xy 234.950957 -147.857281)
			(xy 234.927285 -147.907778) (xy 234.896512 -147.954291) (xy 234.859295 -147.995828) (xy 234.816427 -148.031503)
			(xy 234.768821 -148.060557) (xy 234.717492 -148.082369) (xy 234.663535 -148.096475) (xy 234.608098 -148.102575)
			(xy 234.552364 -148.100538) (xy 234.497521 -148.090408) (xy 234.444737 -148.072401) (xy 234.395137 -148.0469)
			(xy 234.349779 -148.014449) (xy 234.30963 -147.97574) (xy 234.275544 -147.931597) (xy 234.248248 -147.882962)
			(xy 234.228325 -147.830871) (xy 234.216199 -147.776434) (xy 234.212128 -147.720812) (xy 200.619391 -147.720812)
			(xy 200.655407 -147.767748) (xy 200.685374 -147.819654) (xy 200.70831 -147.875027) (xy 200.723823 -147.93292)
			(xy 200.731646 -147.992342) (xy 200.732136 -148.02231) (xy 200.732136 -148.88591) (xy 200.731646 -148.915878)
			(xy 200.723823 -148.9753) (xy 200.70831 -149.033193) (xy 200.699562 -149.054312) (xy 219.859604 -149.054312)
			(xy 219.863675 -148.99869) (xy 219.875801 -148.944253) (xy 219.895724 -148.892162) (xy 219.92302 -148.843527)
			(xy 219.957106 -148.799384) (xy 219.997255 -148.760675) (xy 220.042613 -148.728224) (xy 220.092213 -148.702723)
			(xy 220.144997 -148.684716) (xy 220.19984 -148.674586) (xy 220.255574 -148.672549) (xy 220.311011 -148.678649)
			(xy 220.364968 -148.692755) (xy 220.416297 -148.714567) (xy 220.463903 -148.743621) (xy 220.506771 -148.779296)
			(xy 220.543988 -148.820833) (xy 220.574761 -148.867346) (xy 220.598433 -148.917843) (xy 220.614501 -148.97125)
			(xy 220.622621 -149.026426) (xy 220.62313 -149.054312) (xy 220.622621 -149.082198) (xy 220.614501 -149.137374)
			(xy 220.598433 -149.190781) (xy 220.574761 -149.241278) (xy 220.543988 -149.287791) (xy 220.506771 -149.329328)
			(xy 220.463903 -149.365003) (xy 220.416297 -149.394057) (xy 220.394527 -149.403308) (xy 223.512886 -149.403308)
			(xy 223.516957 -149.347686) (xy 223.529083 -149.293249) (xy 223.549006 -149.241158) (xy 223.576302 -149.192523)
			(xy 223.610388 -149.14838) (xy 223.650537 -149.109671) (xy 223.695895 -149.07722) (xy 223.745495 -149.051719)
			(xy 223.798279 -149.033712) (xy 223.853122 -149.023582) (xy 223.908856 -149.021545) (xy 223.964293 -149.027645)
			(xy 224.01825 -149.041751) (xy 224.069579 -149.063563) (xy 224.117185 -149.092617) (xy 224.160053 -149.128292)
			(xy 224.19727 -149.169829) (xy 224.228043 -149.216342) (xy 224.251715 -149.266839) (xy 224.258038 -149.287857)
			(xy 233.065215 -149.287857) (xy 233.065215 -149.233343) (xy 233.072973 -149.179385) (xy 233.088332 -149.12708)
			(xy 233.110978 -149.077493) (xy 233.140451 -149.031634) (xy 233.176151 -148.990437) (xy 233.21735 -148.954739)
			(xy 233.263211 -148.925269) (xy 233.312799 -148.902625) (xy 233.365105 -148.887269) (xy 233.419063 -148.879514)
			(xy 233.44632 -148.879052) (xy 233.473193 -148.879488) (xy 233.526406 -148.887047) (xy 233.578032 -148.901998)
			(xy 233.627049 -148.924046) (xy 233.672487 -148.952753) (xy 233.713447 -148.987553) (xy 233.749118 -149.027757)
			(xy 233.778795 -149.072568) (xy 233.80189 -149.1211) (xy 233.817946 -149.172393) (xy 233.822748 -149.198838)
			(xy 233.824272 -149.208744) (xy 233.834686 -149.225508) (xy 233.899964 -149.273514) (xy 233.908092 -149.278969)
			(xy 233.927045 -149.283799) (xy 233.936794 -149.282912) (xy 233.937048 -149.282912) (xy 233.949938 -149.281253)
			(xy 233.975868 -149.279475) (xy 233.988864 -149.279356) (xy 233.989118 -149.279356) (xy 234.016366 -149.279915)
			(xy 234.070306 -149.287673) (xy 234.122594 -149.303028) (xy 234.172164 -149.325668) (xy 234.218008 -149.355132)
			(xy 234.259192 -149.390821) (xy 234.294878 -149.432006) (xy 234.32434 -149.477852) (xy 234.346978 -149.527423)
			(xy 234.362331 -149.579711) (xy 234.370086 -149.633652) (xy 234.370086 -149.688148) (xy 234.362331 -149.742089)
			(xy 234.346978 -149.794377) (xy 234.32434 -149.843948) (xy 234.294878 -149.889794) (xy 234.259192 -149.930979)
			(xy 234.218008 -149.966668) (xy 234.172164 -149.996131) (xy 234.122594 -150.018772) (xy 234.070306 -150.034127)
			(xy 234.016366 -150.041885) (xy 233.989118 -150.042372) (xy 233.962247 -150.041881) (xy 233.909037 -150.034328)
			(xy 233.857413 -150.019383) (xy 233.808398 -149.997342) (xy 233.762961 -149.96864) (xy 233.722001 -149.933846)
			(xy 233.686329 -149.893649) (xy 233.65665 -149.848843) (xy 233.633553 -149.800316) (xy 233.617494 -149.749029)
			(xy 233.61269 -149.722586) (xy 233.611166 -149.71268) (xy 233.600752 -149.695916) (xy 233.535474 -149.64791)
			(xy 233.527334 -149.642476) (xy 233.508391 -149.637632) (xy 233.498644 -149.638512) (xy 233.49839 -149.638512)
			(xy 233.4855 -149.640167) (xy 233.45957 -149.641948) (xy 233.446574 -149.642068) (xy 233.44632 -149.642068)
			(xy 233.419063 -149.641686) (xy 233.365105 -149.633931) (xy 233.312799 -149.618575) (xy 233.263211 -149.595931)
			(xy 233.21735 -149.566461) (xy 233.176151 -149.530763) (xy 233.140451 -149.489566) (xy 233.110978 -149.443707)
			(xy 233.088332 -149.39412) (xy 233.072973 -149.341815) (xy 233.065215 -149.287857) (xy 224.258038 -149.287857)
			(xy 224.267783 -149.320246) (xy 224.275903 -149.375422) (xy 224.276412 -149.403308) (xy 224.275903 -149.431194)
			(xy 224.267783 -149.48637) (xy 224.251715 -149.539777) (xy 224.228043 -149.590274) (xy 224.19727 -149.636787)
			(xy 224.160053 -149.678324) (xy 224.117185 -149.713999) (xy 224.069579 -149.743053) (xy 224.01825 -149.764865)
			(xy 223.964293 -149.778971) (xy 223.908856 -149.785071) (xy 223.853122 -149.783034) (xy 223.798279 -149.772904)
			(xy 223.745495 -149.754897) (xy 223.695895 -149.729396) (xy 223.650537 -149.696945) (xy 223.610388 -149.658236)
			(xy 223.576302 -149.614093) (xy 223.549006 -149.565458) (xy 223.529083 -149.513367) (xy 223.516957 -149.45893)
			(xy 223.512886 -149.403308) (xy 220.394527 -149.403308) (xy 220.364968 -149.415869) (xy 220.311011 -149.429975)
			(xy 220.255574 -149.436075) (xy 220.19984 -149.434038) (xy 220.144997 -149.423908) (xy 220.092213 -149.405901)
			(xy 220.042613 -149.3804) (xy 219.997255 -149.347949) (xy 219.957106 -149.30924) (xy 219.92302 -149.265097)
			(xy 219.895724 -149.216462) (xy 219.875801 -149.164371) (xy 219.863675 -149.109934) (xy 219.859604 -149.054312)
			(xy 200.699562 -149.054312) (xy 200.685374 -149.088566) (xy 200.655407 -149.140472) (xy 200.61892 -149.188022)
			(xy 200.57654 -149.230402) (xy 200.52899 -149.266889) (xy 200.477084 -149.296856) (xy 200.421711 -149.319792)
			(xy 200.363818 -149.335305) (xy 200.304396 -149.343128) (xy 200.24446 -149.343128) (xy 200.185038 -149.335305)
			(xy 200.127145 -149.319792) (xy 200.071772 -149.296856) (xy 200.019866 -149.266889) (xy 199.972316 -149.230402)
			(xy 199.929936 -149.188022) (xy 199.893449 -149.140472) (xy 199.863482 -149.088566) (xy 199.840546 -149.033193)
			(xy 199.825033 -148.9753) (xy 199.81721 -148.915878) (xy 199.81672 -148.88591) (xy 181.760876 -148.88591)
			(xy 181.760876 -148.887434) (xy 181.760386 -148.917402) (xy 181.752563 -148.976824) (xy 181.73705 -149.034717)
			(xy 181.714114 -149.09009) (xy 181.684147 -149.141996) (xy 181.64766 -149.189546) (xy 181.60528 -149.231926)
			(xy 181.55773 -149.268413) (xy 181.505824 -149.29838) (xy 181.450451 -149.321316) (xy 181.392558 -149.336829)
			(xy 181.333136 -149.344652) (xy 181.2732 -149.344652) (xy 181.213778 -149.336829) (xy 181.155885 -149.321316)
			(xy 181.100512 -149.29838) (xy 181.048606 -149.268413) (xy 181.001056 -149.231926) (xy 180.958676 -149.189546)
			(xy 180.922189 -149.141996) (xy 180.892222 -149.09009) (xy 180.869286 -149.034717) (xy 180.853773 -148.976824)
			(xy 180.84595 -148.917402) (xy 180.84546 -148.887434) (xy 152.557988 -148.887434) (xy 152.557988 -150.687278)
			(xy 182.69966 -150.687278) (xy 182.69966 -149.823678) (xy 182.70015 -149.79371) (xy 182.707973 -149.734288)
			(xy 182.723486 -149.676395) (xy 182.746422 -149.621022) (xy 182.776389 -149.569116) (xy 182.812876 -149.521566)
			(xy 182.855256 -149.479186) (xy 182.902806 -149.442699) (xy 182.954712 -149.412732) (xy 183.010085 -149.389796)
			(xy 183.067978 -149.374283) (xy 183.1274 -149.36646) (xy 183.187336 -149.36646) (xy 183.246758 -149.374283)
			(xy 183.304651 -149.389796) (xy 183.360024 -149.412732) (xy 183.41193 -149.442699) (xy 183.45948 -149.479186)
			(xy 183.50186 -149.521566) (xy 183.538347 -149.569116) (xy 183.568314 -149.621022) (xy 183.59125 -149.676395)
			(xy 183.606763 -149.734288) (xy 183.614586 -149.79371) (xy 183.615076 -149.823678) (xy 183.615076 -150.67915)
			(xy 197.174612 -150.67915) (xy 197.174612 -149.81555) (xy 197.175102 -149.785582) (xy 197.182925 -149.72616)
			(xy 197.198438 -149.668267) (xy 197.221374 -149.612894) (xy 197.251341 -149.560988) (xy 197.287828 -149.513438)
			(xy 197.330208 -149.471058) (xy 197.377758 -149.434571) (xy 197.429664 -149.404604) (xy 197.485037 -149.381668)
			(xy 197.54293 -149.366155) (xy 197.602352 -149.358332) (xy 197.662288 -149.358332) (xy 197.72171 -149.366155)
			(xy 197.779603 -149.381668) (xy 197.834976 -149.404604) (xy 197.886882 -149.434571) (xy 197.934432 -149.471058)
			(xy 197.976812 -149.513438) (xy 198.013299 -149.560988) (xy 198.043266 -149.612894) (xy 198.066202 -149.668267)
			(xy 198.081715 -149.72616) (xy 198.089538 -149.785582) (xy 198.090028 -149.81555) (xy 198.090028 -150.67915)
			(xy 198.089538 -150.709118) (xy 198.081715 -150.76854) (xy 198.066202 -150.826433) (xy 198.043266 -150.881806)
			(xy 198.013299 -150.933712) (xy 197.976812 -150.981262) (xy 197.934432 -151.023642) (xy 197.886882 -151.060129)
			(xy 197.834976 -151.090096) (xy 197.779603 -151.113032) (xy 197.72171 -151.128545) (xy 197.662288 -151.136368)
			(xy 197.602352 -151.136368) (xy 197.54293 -151.128545) (xy 197.485037 -151.113032) (xy 197.429664 -151.090096)
			(xy 197.377758 -151.060129) (xy 197.330208 -151.023642) (xy 197.287828 -150.981262) (xy 197.251341 -150.933712)
			(xy 197.221374 -150.881806) (xy 197.198438 -150.826433) (xy 197.182925 -150.76854) (xy 197.175102 -150.709118)
			(xy 197.174612 -150.67915) (xy 183.615076 -150.67915) (xy 183.615076 -150.687278) (xy 183.614586 -150.717246)
			(xy 183.606763 -150.776668) (xy 183.59125 -150.834561) (xy 183.568314 -150.889934) (xy 183.538347 -150.94184)
			(xy 183.50186 -150.98939) (xy 183.45948 -151.03177) (xy 183.41193 -151.068257) (xy 183.360024 -151.098224)
			(xy 183.304651 -151.12116) (xy 183.246758 -151.136673) (xy 183.187336 -151.144496) (xy 183.1274 -151.144496)
			(xy 183.067978 -151.136673) (xy 183.010085 -151.12116) (xy 182.954712 -151.098224) (xy 182.902806 -151.068257)
			(xy 182.855256 -151.03177) (xy 182.812876 -150.98939) (xy 182.776389 -150.94184) (xy 182.746422 -150.889934)
			(xy 182.723486 -150.834561) (xy 182.707973 -150.776668) (xy 182.70015 -150.717246) (xy 182.69966 -150.687278)
			(xy 152.557988 -150.687278) (xy 152.557988 -151.257) (xy 168.676826 -151.257) (xy 168.680897 -151.201378)
			(xy 168.693023 -151.146941) (xy 168.712946 -151.09485) (xy 168.740242 -151.046215) (xy 168.774328 -151.002072)
			(xy 168.814477 -150.963363) (xy 168.859835 -150.930912) (xy 168.909435 -150.905411) (xy 168.962219 -150.887404)
			(xy 169.017062 -150.877274) (xy 169.072796 -150.875237) (xy 169.128233 -150.881337) (xy 169.18219 -150.895443)
			(xy 169.233519 -150.917255) (xy 169.281125 -150.946309) (xy 169.323993 -150.981984) (xy 169.36121 -151.023521)
			(xy 169.391983 -151.070034) (xy 169.415655 -151.120531) (xy 169.431723 -151.173938) (xy 169.439843 -151.229114)
			(xy 169.440352 -151.257) (xy 169.439843 -151.284886) (xy 169.431723 -151.340062) (xy 169.415655 -151.393469)
			(xy 169.391983 -151.443966) (xy 169.36121 -151.490479) (xy 169.323993 -151.532016) (xy 169.281125 -151.567691)
			(xy 169.233519 -151.596745) (xy 169.18219 -151.618557) (xy 169.128233 -151.632663) (xy 169.072796 -151.638763)
			(xy 169.017062 -151.636726) (xy 168.962219 -151.626596) (xy 168.909435 -151.608589) (xy 168.859835 -151.583088)
			(xy 168.814477 -151.550637) (xy 168.774328 -151.511928) (xy 168.740242 -151.467785) (xy 168.712946 -151.41915)
			(xy 168.693023 -151.367059) (xy 168.680897 -151.312622) (xy 168.676826 -151.257) (xy 152.557988 -151.257)
			(xy 152.557988 -152.487376) (xy 180.84546 -152.487376) (xy 180.84546 -151.623776) (xy 180.84595 -151.593808)
			(xy 180.853773 -151.534386) (xy 180.869286 -151.476493) (xy 180.892222 -151.42112) (xy 180.922189 -151.369214)
			(xy 180.958676 -151.321664) (xy 181.001056 -151.279284) (xy 181.048606 -151.242797) (xy 181.100512 -151.21283)
			(xy 181.155885 -151.189894) (xy 181.213778 -151.174381) (xy 181.2732 -151.166558) (xy 181.333136 -151.166558)
			(xy 181.392558 -151.174381) (xy 181.450451 -151.189894) (xy 181.505824 -151.21283) (xy 181.55773 -151.242797)
			(xy 181.60528 -151.279284) (xy 181.64766 -151.321664) (xy 181.684147 -151.369214) (xy 181.714114 -151.42112)
			(xy 181.73705 -151.476493) (xy 181.752563 -151.534386) (xy 181.760386 -151.593808) (xy 181.760876 -151.623776)
			(xy 181.760876 -152.485852) (xy 199.81672 -152.485852) (xy 199.81672 -151.622252) (xy 199.81721 -151.592284)
			(xy 199.825033 -151.532862) (xy 199.840546 -151.474969) (xy 199.863482 -151.419596) (xy 199.893449 -151.36769)
			(xy 199.929936 -151.32014) (xy 199.972316 -151.27776) (xy 200.019866 -151.241273) (xy 200.071772 -151.211306)
			(xy 200.127145 -151.18837) (xy 200.185038 -151.172857) (xy 200.24446 -151.165034) (xy 200.304396 -151.165034)
			(xy 200.363818 -151.172857) (xy 200.421711 -151.18837) (xy 200.477084 -151.211306) (xy 200.52899 -151.241273)
			(xy 200.57654 -151.27776) (xy 200.61892 -151.32014) (xy 200.655407 -151.36769) (xy 200.685374 -151.419596)
			(xy 200.70831 -151.474969) (xy 200.723823 -151.532862) (xy 200.731646 -151.592284) (xy 200.732136 -151.622252)
			(xy 200.732136 -151.664162) (xy 231.773474 -151.664162) (xy 231.777545 -151.60854) (xy 231.789671 -151.554103)
			(xy 231.809594 -151.502012) (xy 231.83689 -151.453377) (xy 231.870976 -151.409234) (xy 231.911125 -151.370525)
			(xy 231.956483 -151.338074) (xy 232.006083 -151.312573) (xy 232.058867 -151.294566) (xy 232.11371 -151.284436)
			(xy 232.169444 -151.282399) (xy 232.224881 -151.288499) (xy 232.278838 -151.302605) (xy 232.330167 -151.324417)
			(xy 232.377773 -151.353471) (xy 232.420641 -151.389146) (xy 232.457858 -151.430683) (xy 232.488631 -151.477196)
			(xy 232.512303 -151.527693) (xy 232.528371 -151.5811) (xy 232.536491 -151.636276) (xy 232.537 -151.664162)
			(xy 232.536491 -151.692048) (xy 232.528371 -151.747224) (xy 232.512303 -151.800631) (xy 232.488631 -151.851128)
			(xy 232.457858 -151.897641) (xy 232.420641 -151.939178) (xy 232.377773 -151.974853) (xy 232.330167 -152.003907)
			(xy 232.278838 -152.025719) (xy 232.224881 -152.039825) (xy 232.169444 -152.045925) (xy 232.11371 -152.043888)
			(xy 232.058867 -152.033758) (xy 232.006083 -152.015751) (xy 231.956483 -151.99025) (xy 231.911125 -151.957799)
			(xy 231.870976 -151.91909) (xy 231.83689 -151.874947) (xy 231.809594 -151.826312) (xy 231.789671 -151.774221)
			(xy 231.777545 -151.719784) (xy 231.773474 -151.664162) (xy 200.732136 -151.664162) (xy 200.732136 -152.412446)
			(xy 226.102924 -152.412446) (xy 226.106995 -152.356824) (xy 226.119121 -152.302387) (xy 226.139044 -152.250296)
			(xy 226.16634 -152.201661) (xy 226.200426 -152.157518) (xy 226.240575 -152.118809) (xy 226.285933 -152.086358)
			(xy 226.335533 -152.060857) (xy 226.388317 -152.04285) (xy 226.44316 -152.03272) (xy 226.498894 -152.030683)
			(xy 226.554331 -152.036783) (xy 226.608288 -152.050889) (xy 226.659617 -152.072701) (xy 226.707223 -152.101755)
			(xy 226.750091 -152.13743) (xy 226.787308 -152.178967) (xy 226.818081 -152.22548) (xy 226.841753 -152.275977)
			(xy 226.857821 -152.329384) (xy 226.864139 -152.372314) (xy 227.76256 -152.372314) (xy 227.766631 -152.316692)
			(xy 227.778757 -152.262255) (xy 227.79868 -152.210164) (xy 227.825976 -152.161529) (xy 227.860062 -152.117386)
			(xy 227.900211 -152.078677) (xy 227.945569 -152.046226) (xy 227.995169 -152.020725) (xy 228.047953 -152.002718)
			(xy 228.102796 -151.992588) (xy 228.15853 -151.990551) (xy 228.213967 -151.996651) (xy 228.267924 -152.010757)
			(xy 228.319253 -152.032569) (xy 228.366859 -152.061623) (xy 228.38462 -152.076404) (xy 230.958388 -152.076404)
			(xy 230.962459 -152.020782) (xy 230.974585 -151.966345) (xy 230.994508 -151.914254) (xy 231.021804 -151.865619)
			(xy 231.05589 -151.821476) (xy 231.096039 -151.782767) (xy 231.141397 -151.750316) (xy 231.190997 -151.724815)
			(xy 231.243781 -151.706808) (xy 231.298624 -151.696678) (xy 231.354358 -151.694641) (xy 231.409795 -151.700741)
			(xy 231.463752 -151.714847) (xy 231.515081 -151.736659) (xy 231.562687 -151.765713) (xy 231.605555 -151.801388)
			(xy 231.642772 -151.842925) (xy 231.673545 -151.889438) (xy 231.697217 -151.939935) (xy 231.713285 -151.993342)
			(xy 231.721405 -152.048518) (xy 231.721914 -152.076404) (xy 231.721405 -152.10429) (xy 231.713285 -152.159466)
			(xy 231.697217 -152.212873) (xy 231.673545 -152.26337) (xy 231.642772 -152.309883) (xy 231.605555 -152.35142)
			(xy 231.562687 -152.387095) (xy 231.515081 -152.416149) (xy 231.463752 -152.437961) (xy 231.409795 -152.452067)
			(xy 231.354358 -152.458167) (xy 231.298624 -152.45613) (xy 231.243781 -152.446) (xy 231.190997 -152.427993)
			(xy 231.141397 -152.402492) (xy 231.096039 -152.370041) (xy 231.05589 -152.331332) (xy 231.021804 -152.287189)
			(xy 230.994508 -152.238554) (xy 230.974585 -152.186463) (xy 230.962459 -152.132026) (xy 230.958388 -152.076404)
			(xy 228.38462 -152.076404) (xy 228.409727 -152.097298) (xy 228.446944 -152.138835) (xy 228.477717 -152.185348)
			(xy 228.501389 -152.235845) (xy 228.517457 -152.289252) (xy 228.525577 -152.344428) (xy 228.526086 -152.372314)
			(xy 228.525577 -152.4002) (xy 228.517457 -152.455376) (xy 228.501389 -152.508783) (xy 228.477717 -152.55928)
			(xy 228.446944 -152.605793) (xy 228.409727 -152.64733) (xy 228.366859 -152.683005) (xy 228.319253 -152.712059)
			(xy 228.267924 -152.733871) (xy 228.213967 -152.747977) (xy 228.15853 -152.754077) (xy 228.102796 -152.75204)
			(xy 228.047953 -152.74191) (xy 227.995169 -152.723903) (xy 227.945569 -152.698402) (xy 227.900211 -152.665951)
			(xy 227.860062 -152.627242) (xy 227.825976 -152.583099) (xy 227.79868 -152.534464) (xy 227.778757 -152.482373)
			(xy 227.766631 -152.427936) (xy 227.76256 -152.372314) (xy 226.864139 -152.372314) (xy 226.865941 -152.38456)
			(xy 226.86645 -152.412446) (xy 226.865941 -152.440332) (xy 226.857821 -152.495508) (xy 226.841753 -152.548915)
			(xy 226.818081 -152.599412) (xy 226.787308 -152.645925) (xy 226.750091 -152.687462) (xy 226.707223 -152.723137)
			(xy 226.659617 -152.752191) (xy 226.608288 -152.774003) (xy 226.554331 -152.788109) (xy 226.498894 -152.794209)
			(xy 226.44316 -152.792172) (xy 226.388317 -152.782042) (xy 226.335533 -152.764035) (xy 226.285933 -152.738534)
			(xy 226.240575 -152.706083) (xy 226.200426 -152.667374) (xy 226.16634 -152.623231) (xy 226.139044 -152.574596)
			(xy 226.119121 -152.522505) (xy 226.106995 -152.468068) (xy 226.102924 -152.412446) (xy 200.732136 -152.412446)
			(xy 200.732136 -152.485852) (xy 200.731646 -152.51582) (xy 200.723823 -152.575242) (xy 200.70831 -152.633135)
			(xy 200.685374 -152.688508) (xy 200.655407 -152.740414) (xy 200.61892 -152.787964) (xy 200.57654 -152.830344)
			(xy 200.52899 -152.866831) (xy 200.477084 -152.896798) (xy 200.421711 -152.919734) (xy 200.363818 -152.935247)
			(xy 200.304396 -152.94307) (xy 200.24446 -152.94307) (xy 200.185038 -152.935247) (xy 200.127145 -152.919734)
			(xy 200.071772 -152.896798) (xy 200.019866 -152.866831) (xy 199.972316 -152.830344) (xy 199.929936 -152.787964)
			(xy 199.893449 -152.740414) (xy 199.863482 -152.688508) (xy 199.840546 -152.633135) (xy 199.825033 -152.575242)
			(xy 199.81721 -152.51582) (xy 199.81672 -152.485852) (xy 181.760876 -152.485852) (xy 181.760876 -152.487376)
			(xy 181.760386 -152.517344) (xy 181.752563 -152.576766) (xy 181.73705 -152.634659) (xy 181.714114 -152.690032)
			(xy 181.684147 -152.741938) (xy 181.64766 -152.789488) (xy 181.60528 -152.831868) (xy 181.55773 -152.868355)
			(xy 181.505824 -152.898322) (xy 181.450451 -152.921258) (xy 181.392558 -152.936771) (xy 181.333136 -152.944594)
			(xy 181.2732 -152.944594) (xy 181.213778 -152.936771) (xy 181.155885 -152.921258) (xy 181.100512 -152.898322)
			(xy 181.048606 -152.868355) (xy 181.001056 -152.831868) (xy 180.958676 -152.789488) (xy 180.922189 -152.741938)
			(xy 180.892222 -152.690032) (xy 180.869286 -152.634659) (xy 180.853773 -152.576766) (xy 180.84595 -152.517344)
			(xy 180.84546 -152.487376) (xy 152.557988 -152.487376) (xy 152.557988 -153.3144) (xy 153.290776 -153.3144)
			(xy 153.294847 -153.258778) (xy 153.306973 -153.204341) (xy 153.326896 -153.15225) (xy 153.354192 -153.103615)
			(xy 153.388278 -153.059472) (xy 153.428427 -153.020763) (xy 153.473785 -152.988312) (xy 153.523385 -152.962811)
			(xy 153.576169 -152.944804) (xy 153.631012 -152.934674) (xy 153.686746 -152.932637) (xy 153.742183 -152.938737)
			(xy 153.79614 -152.952843) (xy 153.847469 -152.974655) (xy 153.895075 -153.003709) (xy 153.937943 -153.039384)
			(xy 153.97516 -153.080921) (xy 154.005933 -153.127434) (xy 154.029605 -153.177931) (xy 154.045673 -153.231338)
			(xy 154.053793 -153.286514) (xy 154.054302 -153.3144) (xy 154.053793 -153.342286) (xy 154.045673 -153.397462)
			(xy 154.029605 -153.450869) (xy 154.005933 -153.501366) (xy 153.97516 -153.547879) (xy 153.964284 -153.560018)
			(xy 168.549826 -153.560018) (xy 168.553897 -153.504396) (xy 168.566023 -153.449959) (xy 168.585946 -153.397868)
			(xy 168.613242 -153.349233) (xy 168.647328 -153.30509) (xy 168.687477 -153.266381) (xy 168.732835 -153.23393)
			(xy 168.782435 -153.208429) (xy 168.835219 -153.190422) (xy 168.890062 -153.180292) (xy 168.945796 -153.178255)
			(xy 169.001233 -153.184355) (xy 169.05519 -153.198461) (xy 169.106519 -153.220273) (xy 169.154125 -153.249327)
			(xy 169.196993 -153.285002) (xy 169.23421 -153.326539) (xy 169.264983 -153.373052) (xy 169.288655 -153.423549)
			(xy 169.304723 -153.476956) (xy 169.312843 -153.532132) (xy 169.313352 -153.560018) (xy 169.312843 -153.587904)
			(xy 169.304723 -153.64308) (xy 169.288655 -153.696487) (xy 169.264983 -153.746984) (xy 169.23421 -153.793497)
			(xy 169.196993 -153.835034) (xy 169.154125 -153.870709) (xy 169.106519 -153.899763) (xy 169.05519 -153.921575)
			(xy 169.001233 -153.935681) (xy 168.945796 -153.941781) (xy 168.890062 -153.939744) (xy 168.835219 -153.929614)
			(xy 168.782435 -153.911607) (xy 168.732835 -153.886106) (xy 168.687477 -153.853655) (xy 168.647328 -153.814946)
			(xy 168.613242 -153.770803) (xy 168.585946 -153.722168) (xy 168.566023 -153.670077) (xy 168.553897 -153.61564)
			(xy 168.549826 -153.560018) (xy 153.964284 -153.560018) (xy 153.937943 -153.589416) (xy 153.895075 -153.625091)
			(xy 153.847469 -153.654145) (xy 153.79614 -153.675957) (xy 153.742183 -153.690063) (xy 153.686746 -153.696163)
			(xy 153.631012 -153.694126) (xy 153.576169 -153.683996) (xy 153.523385 -153.665989) (xy 153.473785 -153.640488)
			(xy 153.428427 -153.608037) (xy 153.388278 -153.569328) (xy 153.354192 -153.525185) (xy 153.326896 -153.47655)
			(xy 153.306973 -153.424459) (xy 153.294847 -153.370022) (xy 153.290776 -153.3144) (xy 152.557988 -153.3144)
			(xy 152.557988 -154.159966) (xy 167.406826 -154.159966) (xy 167.410897 -154.104344) (xy 167.423023 -154.049907)
			(xy 167.442946 -153.997816) (xy 167.470242 -153.949181) (xy 167.504328 -153.905038) (xy 167.544477 -153.866329)
			(xy 167.589835 -153.833878) (xy 167.639435 -153.808377) (xy 167.692219 -153.79037) (xy 167.747062 -153.78024)
			(xy 167.802796 -153.778203) (xy 167.858233 -153.784303) (xy 167.91219 -153.798409) (xy 167.963519 -153.820221)
			(xy 168.011125 -153.849275) (xy 168.053993 -153.88495) (xy 168.09121 -153.926487) (xy 168.121983 -153.973)
			(xy 168.145655 -154.023497) (xy 168.161723 -154.076904) (xy 168.169843 -154.13208) (xy 168.170352 -154.159966)
			(xy 168.169843 -154.187852) (xy 168.161723 -154.243028) (xy 168.148427 -154.28722) (xy 182.69966 -154.28722)
			(xy 182.69966 -153.42362) (xy 182.70015 -153.393652) (xy 182.707973 -153.33423) (xy 182.723486 -153.276337)
			(xy 182.746422 -153.220964) (xy 182.776389 -153.169058) (xy 182.812876 -153.121508) (xy 182.855256 -153.079128)
			(xy 182.902806 -153.042641) (xy 182.954712 -153.012674) (xy 183.010085 -152.989738) (xy 183.067978 -152.974225)
			(xy 183.1274 -152.966402) (xy 183.187336 -152.966402) (xy 183.246758 -152.974225) (xy 183.304651 -152.989738)
			(xy 183.360024 -153.012674) (xy 183.41193 -153.042641) (xy 183.45948 -153.079128) (xy 183.50186 -153.121508)
			(xy 183.538347 -153.169058) (xy 183.568314 -153.220964) (xy 183.59125 -153.276337) (xy 183.606763 -153.33423)
			(xy 183.614586 -153.393652) (xy 183.615076 -153.42362) (xy 183.615076 -154.279346) (xy 197.174612 -154.279346)
			(xy 197.174612 -153.415746) (xy 197.175102 -153.385778) (xy 197.182925 -153.326356) (xy 197.198438 -153.268463)
			(xy 197.221374 -153.21309) (xy 197.251341 -153.161184) (xy 197.287828 -153.113634) (xy 197.330208 -153.071254)
			(xy 197.377758 -153.034767) (xy 197.429664 -153.0048) (xy 197.485037 -152.981864) (xy 197.54293 -152.966351)
			(xy 197.602352 -152.958528) (xy 197.662288 -152.958528) (xy 197.72171 -152.966351) (xy 197.779603 -152.981864)
			(xy 197.834976 -153.0048) (xy 197.886882 -153.034767) (xy 197.934432 -153.071254) (xy 197.976812 -153.113634)
			(xy 198.013299 -153.161184) (xy 198.043266 -153.21309) (xy 198.066202 -153.268463) (xy 198.081715 -153.326356)
			(xy 198.089538 -153.385778) (xy 198.090028 -153.415746) (xy 198.090028 -153.675842) (xy 222.211136 -153.675842)
			(xy 222.215207 -153.62022) (xy 222.227333 -153.565783) (xy 222.247256 -153.513692) (xy 222.274552 -153.465057)
			(xy 222.308638 -153.420914) (xy 222.348787 -153.382205) (xy 222.394145 -153.349754) (xy 222.443745 -153.324253)
			(xy 222.496529 -153.306246) (xy 222.551372 -153.296116) (xy 222.607106 -153.294079) (xy 222.662543 -153.300179)
			(xy 222.7165 -153.314285) (xy 222.767829 -153.336097) (xy 222.815435 -153.365151) (xy 222.858303 -153.400826)
			(xy 222.89552 -153.442363) (xy 222.926293 -153.488876) (xy 222.949965 -153.539373) (xy 222.966033 -153.59278)
			(xy 222.974153 -153.647956) (xy 222.974662 -153.675842) (xy 222.974153 -153.703728) (xy 222.966033 -153.758904)
			(xy 222.949965 -153.812311) (xy 222.926293 -153.862808) (xy 222.89552 -153.909321) (xy 222.858303 -153.950858)
			(xy 222.815435 -153.986533) (xy 222.767829 -154.015587) (xy 222.7165 -154.037399) (xy 222.662543 -154.051505)
			(xy 222.607106 -154.057605) (xy 222.551372 -154.055568) (xy 222.496529 -154.045438) (xy 222.443745 -154.027431)
			(xy 222.394145 -154.00193) (xy 222.348787 -153.969479) (xy 222.308638 -153.93077) (xy 222.274552 -153.886627)
			(xy 222.247256 -153.837992) (xy 222.227333 -153.785901) (xy 222.215207 -153.731464) (xy 222.211136 -153.675842)
			(xy 198.090028 -153.675842) (xy 198.090028 -154.279346) (xy 198.089538 -154.309314) (xy 198.081715 -154.368736)
			(xy 198.066202 -154.426629) (xy 198.043266 -154.482002) (xy 198.013299 -154.533908) (xy 197.989562 -154.564842)
			(xy 222.211136 -154.564842) (xy 222.215207 -154.50922) (xy 222.227333 -154.454783) (xy 222.247256 -154.402692)
			(xy 222.274552 -154.354057) (xy 222.308638 -154.309914) (xy 222.348787 -154.271205) (xy 222.394145 -154.238754)
			(xy 222.443745 -154.213253) (xy 222.496529 -154.195246) (xy 222.551372 -154.185116) (xy 222.607106 -154.183079)
			(xy 222.662543 -154.189179) (xy 222.7165 -154.203285) (xy 222.767829 -154.225097) (xy 222.815435 -154.254151)
			(xy 222.858303 -154.289826) (xy 222.89552 -154.331363) (xy 222.926293 -154.377876) (xy 222.949965 -154.428373)
			(xy 222.966033 -154.48178) (xy 222.974153 -154.536956) (xy 222.974662 -154.564842) (xy 222.974153 -154.592728)
			(xy 222.966033 -154.647904) (xy 222.949965 -154.701311) (xy 222.926293 -154.751808) (xy 222.89552 -154.798321)
			(xy 222.858303 -154.839858) (xy 222.830755 -154.862784) (xy 227.184964 -154.862784) (xy 227.189035 -154.807162)
			(xy 227.201161 -154.752725) (xy 227.221084 -154.700634) (xy 227.24838 -154.651999) (xy 227.282466 -154.607856)
			(xy 227.322615 -154.569147) (xy 227.367973 -154.536696) (xy 227.417573 -154.511195) (xy 227.470357 -154.493188)
			(xy 227.5252 -154.483058) (xy 227.580934 -154.481021) (xy 227.636371 -154.487121) (xy 227.690328 -154.501227)
			(xy 227.741657 -154.523039) (xy 227.789263 -154.552093) (xy 227.832131 -154.587768) (xy 227.869348 -154.629305)
			(xy 227.883835 -154.651202) (xy 234.809028 -154.651202) (xy 234.813099 -154.59558) (xy 234.825225 -154.541143)
			(xy 234.845148 -154.489052) (xy 234.872444 -154.440417) (xy 234.90653 -154.396274) (xy 234.946679 -154.357565)
			(xy 234.992037 -154.325114) (xy 235.041637 -154.299613) (xy 235.094421 -154.281606) (xy 235.149264 -154.271476)
			(xy 235.204998 -154.269439) (xy 235.260435 -154.275539) (xy 235.314392 -154.289645) (xy 235.365721 -154.311457)
			(xy 235.413327 -154.340511) (xy 235.456195 -154.376186) (xy 235.493412 -154.417723) (xy 235.524185 -154.464236)
			(xy 235.547857 -154.514733) (xy 235.563925 -154.56814) (xy 235.572045 -154.623316) (xy 235.572554 -154.651202)
			(xy 235.572045 -154.679088) (xy 235.563925 -154.734264) (xy 235.547857 -154.787671) (xy 235.524185 -154.838168)
			(xy 235.493412 -154.884681) (xy 235.456195 -154.926218) (xy 235.413327 -154.961893) (xy 235.365721 -154.990947)
			(xy 235.314392 -155.012759) (xy 235.260435 -155.026865) (xy 235.204998 -155.032965) (xy 235.149264 -155.030928)
			(xy 235.094421 -155.020798) (xy 235.041637 -155.002791) (xy 234.992037 -154.97729) (xy 234.946679 -154.944839)
			(xy 234.90653 -154.90613) (xy 234.872444 -154.861987) (xy 234.845148 -154.813352) (xy 234.825225 -154.761261)
			(xy 234.813099 -154.706824) (xy 234.809028 -154.651202) (xy 227.883835 -154.651202) (xy 227.900121 -154.675818)
			(xy 227.923793 -154.726315) (xy 227.939861 -154.779722) (xy 227.947981 -154.834898) (xy 227.94849 -154.862784)
			(xy 227.947981 -154.89067) (xy 227.939861 -154.945846) (xy 227.923793 -154.999253) (xy 227.900121 -155.04975)
			(xy 227.869348 -155.096263) (xy 227.832131 -155.1378) (xy 227.789263 -155.173475) (xy 227.741657 -155.202529)
			(xy 227.690328 -155.224341) (xy 227.636371 -155.238447) (xy 227.580934 -155.244547) (xy 227.5252 -155.24251)
			(xy 227.470357 -155.23238) (xy 227.417573 -155.214373) (xy 227.367973 -155.188872) (xy 227.322615 -155.156421)
			(xy 227.282466 -155.117712) (xy 227.24838 -155.073569) (xy 227.221084 -155.024934) (xy 227.201161 -154.972843)
			(xy 227.189035 -154.918406) (xy 227.184964 -154.862784) (xy 222.830755 -154.862784) (xy 222.815435 -154.875533)
			(xy 222.767829 -154.904587) (xy 222.7165 -154.926399) (xy 222.662543 -154.940505) (xy 222.607106 -154.946605)
			(xy 222.551372 -154.944568) (xy 222.496529 -154.934438) (xy 222.443745 -154.916431) (xy 222.394145 -154.89093)
			(xy 222.348787 -154.858479) (xy 222.308638 -154.81977) (xy 222.274552 -154.775627) (xy 222.247256 -154.726992)
			(xy 222.227333 -154.674901) (xy 222.215207 -154.620464) (xy 222.211136 -154.564842) (xy 197.989562 -154.564842)
			(xy 197.976812 -154.581458) (xy 197.934432 -154.623838) (xy 197.886882 -154.660325) (xy 197.834976 -154.690292)
			(xy 197.779603 -154.713228) (xy 197.72171 -154.728741) (xy 197.662288 -154.736564) (xy 197.602352 -154.736564)
			(xy 197.54293 -154.728741) (xy 197.485037 -154.713228) (xy 197.429664 -154.690292) (xy 197.377758 -154.660325)
			(xy 197.330208 -154.623838) (xy 197.287828 -154.581458) (xy 197.251341 -154.533908) (xy 197.221374 -154.482002)
			(xy 197.198438 -154.426629) (xy 197.182925 -154.368736) (xy 197.175102 -154.309314) (xy 197.174612 -154.279346)
			(xy 183.615076 -154.279346) (xy 183.615076 -154.28722) (xy 183.614586 -154.317188) (xy 183.606763 -154.37661)
			(xy 183.59125 -154.434503) (xy 183.568314 -154.489876) (xy 183.538347 -154.541782) (xy 183.50186 -154.589332)
			(xy 183.45948 -154.631712) (xy 183.41193 -154.668199) (xy 183.360024 -154.698166) (xy 183.304651 -154.721102)
			(xy 183.246758 -154.736615) (xy 183.187336 -154.744438) (xy 183.1274 -154.744438) (xy 183.067978 -154.736615)
			(xy 183.010085 -154.721102) (xy 182.954712 -154.698166) (xy 182.902806 -154.668199) (xy 182.855256 -154.631712)
			(xy 182.812876 -154.589332) (xy 182.776389 -154.541782) (xy 182.746422 -154.489876) (xy 182.723486 -154.434503)
			(xy 182.707973 -154.37661) (xy 182.70015 -154.317188) (xy 182.69966 -154.28722) (xy 168.148427 -154.28722)
			(xy 168.145655 -154.296435) (xy 168.121983 -154.346932) (xy 168.09121 -154.393445) (xy 168.053993 -154.434982)
			(xy 168.011125 -154.470657) (xy 167.963519 -154.499711) (xy 167.91219 -154.521523) (xy 167.858233 -154.535629)
			(xy 167.802796 -154.541729) (xy 167.747062 -154.539692) (xy 167.692219 -154.529562) (xy 167.639435 -154.511555)
			(xy 167.589835 -154.486054) (xy 167.544477 -154.453603) (xy 167.504328 -154.414894) (xy 167.470242 -154.370751)
			(xy 167.442946 -154.322116) (xy 167.423023 -154.270025) (xy 167.410897 -154.215588) (xy 167.406826 -154.159966)
			(xy 152.557988 -154.159966) (xy 152.557988 -155.0416) (xy 164.263576 -155.0416) (xy 164.267647 -154.985978)
			(xy 164.279773 -154.931541) (xy 164.299696 -154.87945) (xy 164.326992 -154.830815) (xy 164.361078 -154.786672)
			(xy 164.401227 -154.747963) (xy 164.446585 -154.715512) (xy 164.496185 -154.690011) (xy 164.548969 -154.672004)
			(xy 164.603812 -154.661874) (xy 164.659546 -154.659837) (xy 164.714983 -154.665937) (xy 164.76894 -154.680043)
			(xy 164.820269 -154.701855) (xy 164.867875 -154.730909) (xy 164.910743 -154.766584) (xy 164.94796 -154.808121)
			(xy 164.978733 -154.854634) (xy 165.002405 -154.905131) (xy 165.018398 -154.958288) (xy 168.843958 -154.958288)
			(xy 168.848029 -154.902666) (xy 168.860155 -154.848229) (xy 168.880078 -154.796138) (xy 168.907374 -154.747503)
			(xy 168.94146 -154.70336) (xy 168.981609 -154.664651) (xy 169.026967 -154.6322) (xy 169.076567 -154.606699)
			(xy 169.129351 -154.588692) (xy 169.184194 -154.578562) (xy 169.239928 -154.576525) (xy 169.295365 -154.582625)
			(xy 169.349322 -154.596731) (xy 169.400651 -154.618543) (xy 169.448257 -154.647597) (xy 169.491125 -154.683272)
			(xy 169.528342 -154.724809) (xy 169.559115 -154.771322) (xy 169.582787 -154.821819) (xy 169.598855 -154.875226)
			(xy 169.606975 -154.930402) (xy 169.607484 -154.958288) (xy 169.606975 -154.986174) (xy 169.598855 -155.04135)
			(xy 169.582787 -155.094757) (xy 169.559115 -155.145254) (xy 169.528342 -155.191767) (xy 169.491125 -155.233304)
			(xy 169.448257 -155.268979) (xy 169.400651 -155.298033) (xy 169.349322 -155.319845) (xy 169.295365 -155.333951)
			(xy 169.239928 -155.340051) (xy 169.184194 -155.338014) (xy 169.129351 -155.327884) (xy 169.076567 -155.309877)
			(xy 169.026967 -155.284376) (xy 168.981609 -155.251925) (xy 168.94146 -155.213216) (xy 168.907374 -155.169073)
			(xy 168.880078 -155.120438) (xy 168.860155 -155.068347) (xy 168.848029 -155.01391) (xy 168.843958 -154.958288)
			(xy 165.018398 -154.958288) (xy 165.018473 -154.958538) (xy 165.026593 -155.013714) (xy 165.027102 -155.0416)
			(xy 165.026593 -155.069486) (xy 165.018473 -155.124662) (xy 165.002405 -155.178069) (xy 164.978733 -155.228566)
			(xy 164.94796 -155.275079) (xy 164.910743 -155.316616) (xy 164.867875 -155.352291) (xy 164.820269 -155.381345)
			(xy 164.76894 -155.403157) (xy 164.714983 -155.417263) (xy 164.659546 -155.423363) (xy 164.603812 -155.421326)
			(xy 164.548969 -155.411196) (xy 164.496185 -155.393189) (xy 164.446585 -155.367688) (xy 164.401227 -155.335237)
			(xy 164.361078 -155.296528) (xy 164.326992 -155.252385) (xy 164.299696 -155.20375) (xy 164.279773 -155.151659)
			(xy 164.267647 -155.097222) (xy 164.263576 -155.0416) (xy 152.557988 -155.0416) (xy 152.557988 -155.598368)
			(xy 167.46804 -155.598368) (xy 167.472111 -155.542746) (xy 167.484237 -155.488309) (xy 167.50416 -155.436218)
			(xy 167.531456 -155.387583) (xy 167.565542 -155.34344) (xy 167.605691 -155.304731) (xy 167.651049 -155.27228)
			(xy 167.700649 -155.246779) (xy 167.753433 -155.228772) (xy 167.808276 -155.218642) (xy 167.86401 -155.216605)
			(xy 167.919447 -155.222705) (xy 167.973404 -155.236811) (xy 168.024733 -155.258623) (xy 168.072339 -155.287677)
			(xy 168.115207 -155.323352) (xy 168.152424 -155.364889) (xy 168.183197 -155.411402) (xy 168.206869 -155.461899)
			(xy 168.222937 -155.515306) (xy 168.231057 -155.570482) (xy 168.231566 -155.598368) (xy 168.231057 -155.626254)
			(xy 168.222937 -155.68143) (xy 168.206869 -155.734837) (xy 168.183197 -155.785334) (xy 168.152424 -155.831847)
			(xy 168.115207 -155.873384) (xy 168.072339 -155.909059) (xy 168.024733 -155.938113) (xy 167.973404 -155.959925)
			(xy 167.919447 -155.974031) (xy 167.86401 -155.980131) (xy 167.808276 -155.978094) (xy 167.753433 -155.967964)
			(xy 167.700649 -155.949957) (xy 167.651049 -155.924456) (xy 167.605691 -155.892005) (xy 167.565542 -155.853296)
			(xy 167.531456 -155.809153) (xy 167.50416 -155.760518) (xy 167.484237 -155.708427) (xy 167.472111 -155.65399)
			(xy 167.46804 -155.598368) (xy 152.557988 -155.598368) (xy 152.557988 -156.087318) (xy 180.84546 -156.087318)
			(xy 180.84546 -155.223718) (xy 180.84595 -155.19375) (xy 180.853773 -155.134328) (xy 180.869286 -155.076435)
			(xy 180.892222 -155.021062) (xy 180.922189 -154.969156) (xy 180.958676 -154.921606) (xy 181.001056 -154.879226)
			(xy 181.048606 -154.842739) (xy 181.100512 -154.812772) (xy 181.155885 -154.789836) (xy 181.213778 -154.774323)
			(xy 181.2732 -154.7665) (xy 181.333136 -154.7665) (xy 181.392558 -154.774323) (xy 181.450451 -154.789836)
			(xy 181.505824 -154.812772) (xy 181.55773 -154.842739) (xy 181.60528 -154.879226) (xy 181.64766 -154.921606)
			(xy 181.684147 -154.969156) (xy 181.714114 -155.021062) (xy 181.73705 -155.076435) (xy 181.752563 -155.134328)
			(xy 181.760386 -155.19375) (xy 181.760876 -155.223718) (xy 181.760876 -156.085794) (xy 199.81672 -156.085794)
			(xy 199.81672 -155.222194) (xy 199.81721 -155.192226) (xy 199.825033 -155.132804) (xy 199.840546 -155.074911)
			(xy 199.863482 -155.019538) (xy 199.893449 -154.967632) (xy 199.929936 -154.920082) (xy 199.972316 -154.877702)
			(xy 200.019866 -154.841215) (xy 200.071772 -154.811248) (xy 200.127145 -154.788312) (xy 200.185038 -154.772799)
			(xy 200.24446 -154.764976) (xy 200.304396 -154.764976) (xy 200.363818 -154.772799) (xy 200.421711 -154.788312)
			(xy 200.477084 -154.811248) (xy 200.52899 -154.841215) (xy 200.57654 -154.877702) (xy 200.61892 -154.920082)
			(xy 200.655407 -154.967632) (xy 200.685374 -155.019538) (xy 200.70831 -155.074911) (xy 200.723823 -155.132804)
			(xy 200.731646 -155.192226) (xy 200.732136 -155.222194) (xy 200.732136 -155.540202) (xy 234.809028 -155.540202)
			(xy 234.813099 -155.48458) (xy 234.825225 -155.430143) (xy 234.845148 -155.378052) (xy 234.872444 -155.329417)
			(xy 234.90653 -155.285274) (xy 234.946679 -155.246565) (xy 234.992037 -155.214114) (xy 235.041637 -155.188613)
			(xy 235.094421 -155.170606) (xy 235.149264 -155.160476) (xy 235.204998 -155.158439) (xy 235.260435 -155.164539)
			(xy 235.314392 -155.178645) (xy 235.365721 -155.200457) (xy 235.38469 -155.212034) (xy 239.469166 -155.212034)
			(xy 239.473237 -155.156412) (xy 239.485363 -155.101975) (xy 239.505286 -155.049884) (xy 239.532582 -155.001249)
			(xy 239.566668 -154.957106) (xy 239.606817 -154.918397) (xy 239.652175 -154.885946) (xy 239.701775 -154.860445)
			(xy 239.754559 -154.842438) (xy 239.809402 -154.832308) (xy 239.865136 -154.830271) (xy 239.920573 -154.836371)
			(xy 239.97453 -154.850477) (xy 240.025859 -154.872289) (xy 240.073465 -154.901343) (xy 240.116333 -154.937018)
			(xy 240.15355 -154.978555) (xy 240.184323 -155.025068) (xy 240.207995 -155.075565) (xy 240.209086 -155.079192)
			(xy 242.069872 -155.079192) (xy 242.073943 -155.02357) (xy 242.086069 -154.969133) (xy 242.105992 -154.917042)
			(xy 242.133288 -154.868407) (xy 242.167374 -154.824264) (xy 242.207523 -154.785555) (xy 242.252881 -154.753104)
			(xy 242.302481 -154.727603) (xy 242.355265 -154.709596) (xy 242.410108 -154.699466) (xy 242.465842 -154.697429)
			(xy 242.521279 -154.703529) (xy 242.575236 -154.717635) (xy 242.626565 -154.739447) (xy 242.674171 -154.768501)
			(xy 242.717039 -154.804176) (xy 242.754256 -154.845713) (xy 242.785029 -154.892226) (xy 242.808701 -154.942723)
			(xy 242.824769 -154.99613) (xy 242.832889 -155.051306) (xy 242.833398 -155.079192) (xy 242.832889 -155.107078)
			(xy 242.824769 -155.162254) (xy 242.808701 -155.215661) (xy 242.785029 -155.266158) (xy 242.754256 -155.312671)
			(xy 242.717039 -155.354208) (xy 242.674171 -155.389883) (xy 242.626565 -155.418937) (xy 242.575236 -155.440749)
			(xy 242.521279 -155.454855) (xy 242.465842 -155.460955) (xy 242.410108 -155.458918) (xy 242.355265 -155.448788)
			(xy 242.302481 -155.430781) (xy 242.252881 -155.40528) (xy 242.207523 -155.372829) (xy 242.167374 -155.33412)
			(xy 242.133288 -155.289977) (xy 242.105992 -155.241342) (xy 242.086069 -155.189251) (xy 242.073943 -155.134814)
			(xy 242.069872 -155.079192) (xy 240.209086 -155.079192) (xy 240.224063 -155.128972) (xy 240.232183 -155.184148)
			(xy 240.232692 -155.212034) (xy 240.232183 -155.23992) (xy 240.224063 -155.295096) (xy 240.207995 -155.348503)
			(xy 240.184323 -155.399) (xy 240.15355 -155.445513) (xy 240.116333 -155.48705) (xy 240.073465 -155.522725)
			(xy 240.025859 -155.551779) (xy 239.97453 -155.573591) (xy 239.920573 -155.587697) (xy 239.865136 -155.593797)
			(xy 239.809402 -155.59176) (xy 239.754559 -155.58163) (xy 239.701775 -155.563623) (xy 239.652175 -155.538122)
			(xy 239.606817 -155.505671) (xy 239.566668 -155.466962) (xy 239.532582 -155.422819) (xy 239.505286 -155.374184)
			(xy 239.485363 -155.322093) (xy 239.473237 -155.267656) (xy 239.469166 -155.212034) (xy 235.38469 -155.212034)
			(xy 235.413327 -155.229511) (xy 235.456195 -155.265186) (xy 235.493412 -155.306723) (xy 235.524185 -155.353236)
			(xy 235.547857 -155.403733) (xy 235.563925 -155.45714) (xy 235.572045 -155.512316) (xy 235.572554 -155.540202)
			(xy 235.572045 -155.568088) (xy 235.563925 -155.623264) (xy 235.547857 -155.676671) (xy 235.524185 -155.727168)
			(xy 235.493412 -155.773681) (xy 235.456195 -155.815218) (xy 235.413327 -155.850893) (xy 235.365721 -155.879947)
			(xy 235.314392 -155.901759) (xy 235.260435 -155.915865) (xy 235.204998 -155.921965) (xy 235.149264 -155.919928)
			(xy 235.094421 -155.909798) (xy 235.041637 -155.891791) (xy 234.992037 -155.86629) (xy 234.946679 -155.833839)
			(xy 234.90653 -155.79513) (xy 234.872444 -155.750987) (xy 234.845148 -155.702352) (xy 234.825225 -155.650261)
			(xy 234.813099 -155.595824) (xy 234.809028 -155.540202) (xy 200.732136 -155.540202) (xy 200.732136 -156.085794)
			(xy 200.731646 -156.115762) (xy 200.723823 -156.175184) (xy 200.70831 -156.233077) (xy 200.685374 -156.28845)
			(xy 200.655407 -156.340356) (xy 200.61892 -156.387906) (xy 200.57654 -156.430286) (xy 200.52899 -156.466773)
			(xy 200.477084 -156.49674) (xy 200.421711 -156.519676) (xy 200.363818 -156.535189) (xy 200.304396 -156.543012)
			(xy 200.24446 -156.543012) (xy 200.185038 -156.535189) (xy 200.127145 -156.519676) (xy 200.071772 -156.49674)
			(xy 200.019866 -156.466773) (xy 199.972316 -156.430286) (xy 199.929936 -156.387906) (xy 199.893449 -156.340356)
			(xy 199.863482 -156.28845) (xy 199.840546 -156.233077) (xy 199.825033 -156.175184) (xy 199.81721 -156.115762)
			(xy 199.81672 -156.085794) (xy 181.760876 -156.085794) (xy 181.760876 -156.087318) (xy 181.760386 -156.117286)
			(xy 181.752563 -156.176708) (xy 181.73705 -156.234601) (xy 181.714114 -156.289974) (xy 181.684147 -156.34188)
			(xy 181.64766 -156.38943) (xy 181.60528 -156.43181) (xy 181.55773 -156.468297) (xy 181.505824 -156.498264)
			(xy 181.450451 -156.5212) (xy 181.392558 -156.536713) (xy 181.333136 -156.544536) (xy 181.2732 -156.544536)
			(xy 181.213778 -156.536713) (xy 181.155885 -156.5212) (xy 181.100512 -156.498264) (xy 181.048606 -156.468297)
			(xy 181.001056 -156.43181) (xy 180.958676 -156.38943) (xy 180.922189 -156.34188) (xy 180.892222 -156.289974)
			(xy 180.869286 -156.234601) (xy 180.853773 -156.176708) (xy 180.84595 -156.117286) (xy 180.84546 -156.087318)
			(xy 152.557988 -156.087318) (xy 152.557988 -156.544518) (xy 168.827702 -156.544518) (xy 168.831773 -156.488896)
			(xy 168.843899 -156.434459) (xy 168.863822 -156.382368) (xy 168.891118 -156.333733) (xy 168.925204 -156.28959)
			(xy 168.965353 -156.250881) (xy 169.010711 -156.21843) (xy 169.060311 -156.192929) (xy 169.113095 -156.174922)
			(xy 169.167938 -156.164792) (xy 169.223672 -156.162755) (xy 169.279109 -156.168855) (xy 169.333066 -156.182961)
			(xy 169.384395 -156.204773) (xy 169.432001 -156.233827) (xy 169.474869 -156.269502) (xy 169.512086 -156.311039)
			(xy 169.542859 -156.357552) (xy 169.566531 -156.408049) (xy 169.582599 -156.461456) (xy 169.590719 -156.516632)
			(xy 169.591228 -156.544518) (xy 169.590719 -156.572404) (xy 169.582599 -156.62758) (xy 169.566531 -156.680987)
			(xy 169.542859 -156.731484) (xy 169.512086 -156.777997) (xy 169.474869 -156.819534) (xy 169.432001 -156.855209)
			(xy 169.384395 -156.884263) (xy 169.333066 -156.906075) (xy 169.279109 -156.920181) (xy 169.223672 -156.926281)
			(xy 169.167938 -156.924244) (xy 169.113095 -156.914114) (xy 169.060311 -156.896107) (xy 169.010711 -156.870606)
			(xy 168.965353 -156.838155) (xy 168.925204 -156.799446) (xy 168.891118 -156.755303) (xy 168.863822 -156.706668)
			(xy 168.843899 -156.654577) (xy 168.831773 -156.60014) (xy 168.827702 -156.544518) (xy 152.557988 -156.544518)
			(xy 152.557988 -157.3784) (xy 153.290776 -157.3784) (xy 153.294847 -157.322778) (xy 153.306973 -157.268341)
			(xy 153.326896 -157.21625) (xy 153.354192 -157.167615) (xy 153.388278 -157.123472) (xy 153.428427 -157.084763)
			(xy 153.473785 -157.052312) (xy 153.523385 -157.026811) (xy 153.576169 -157.008804) (xy 153.631012 -156.998674)
			(xy 153.686746 -156.996637) (xy 153.742183 -157.002737) (xy 153.79614 -157.016843) (xy 153.847469 -157.038655)
			(xy 153.895075 -157.067709) (xy 153.902154 -157.0736) (xy 167.396666 -157.0736) (xy 167.400737 -157.017978)
			(xy 167.412863 -156.963541) (xy 167.432786 -156.91145) (xy 167.460082 -156.862815) (xy 167.494168 -156.818672)
			(xy 167.534317 -156.779963) (xy 167.579675 -156.747512) (xy 167.629275 -156.722011) (xy 167.682059 -156.704004)
			(xy 167.736902 -156.693874) (xy 167.792636 -156.691837) (xy 167.848073 -156.697937) (xy 167.90203 -156.712043)
			(xy 167.953359 -156.733855) (xy 168.000965 -156.762909) (xy 168.043833 -156.798584) (xy 168.08105 -156.840121)
			(xy 168.111823 -156.886634) (xy 168.135495 -156.937131) (xy 168.151563 -156.990538) (xy 168.1596 -157.045152)
			(xy 178.526438 -157.045152) (xy 178.530509 -156.98953) (xy 178.542635 -156.935093) (xy 178.562558 -156.883002)
			(xy 178.589854 -156.834367) (xy 178.62394 -156.790224) (xy 178.664089 -156.751515) (xy 178.709447 -156.719064)
			(xy 178.759047 -156.693563) (xy 178.811831 -156.675556) (xy 178.866674 -156.665426) (xy 178.922408 -156.663389)
			(xy 178.977845 -156.669489) (xy 179.031802 -156.683595) (xy 179.083131 -156.705407) (xy 179.130737 -156.734461)
			(xy 179.173605 -156.770136) (xy 179.210822 -156.811673) (xy 179.241595 -156.858186) (xy 179.265267 -156.908683)
			(xy 179.281335 -156.96209) (xy 179.288139 -157.008322) (xy 226.168964 -157.008322) (xy 226.173035 -156.9527)
			(xy 226.185161 -156.898263) (xy 226.205084 -156.846172) (xy 226.23238 -156.797537) (xy 226.266466 -156.753394)
			(xy 226.306615 -156.714685) (xy 226.351973 -156.682234) (xy 226.401573 -156.656733) (xy 226.454357 -156.638726)
			(xy 226.5092 -156.628596) (xy 226.564934 -156.626559) (xy 226.620371 -156.632659) (xy 226.674328 -156.646765)
			(xy 226.725657 -156.668577) (xy 226.7671 -156.69387) (xy 241.0874 -156.69387) (xy 241.091471 -156.638248)
			(xy 241.103597 -156.583811) (xy 241.12352 -156.53172) (xy 241.150816 -156.483085) (xy 241.184902 -156.438942)
			(xy 241.225051 -156.400233) (xy 241.270409 -156.367782) (xy 241.320009 -156.342281) (xy 241.372793 -156.324274)
			(xy 241.427636 -156.314144) (xy 241.48337 -156.312107) (xy 241.538807 -156.318207) (xy 241.592764 -156.332313)
			(xy 241.644093 -156.354125) (xy 241.691699 -156.383179) (xy 241.734567 -156.418854) (xy 241.771784 -156.460391)
			(xy 241.802557 -156.506904) (xy 241.826229 -156.557401) (xy 241.842297 -156.610808) (xy 241.850417 -156.665984)
			(xy 241.850926 -156.69387) (xy 241.850417 -156.721756) (xy 241.842297 -156.776932) (xy 241.826229 -156.830339)
			(xy 241.802557 -156.880836) (xy 241.771784 -156.927349) (xy 241.734567 -156.968886) (xy 241.691699 -157.004561)
			(xy 241.644093 -157.033615) (xy 241.592764 -157.055427) (xy 241.538807 -157.069533) (xy 241.48337 -157.075633)
			(xy 241.427636 -157.073596) (xy 241.372793 -157.063466) (xy 241.320009 -157.045459) (xy 241.270409 -157.019958)
			(xy 241.225051 -156.987507) (xy 241.184902 -156.948798) (xy 241.150816 -156.904655) (xy 241.12352 -156.85602)
			(xy 241.103597 -156.803929) (xy 241.091471 -156.749492) (xy 241.0874 -156.69387) (xy 226.7671 -156.69387)
			(xy 226.773263 -156.697631) (xy 226.816131 -156.733306) (xy 226.853348 -156.774843) (xy 226.884121 -156.821356)
			(xy 226.907793 -156.871853) (xy 226.923861 -156.92526) (xy 226.931981 -156.980436) (xy 226.93249 -157.008322)
			(xy 226.931981 -157.036208) (xy 226.923861 -157.091384) (xy 226.907793 -157.144791) (xy 226.884121 -157.195288)
			(xy 226.853348 -157.241801) (xy 226.816131 -157.283338) (xy 226.773263 -157.319013) (xy 226.725657 -157.348067)
			(xy 226.674328 -157.369879) (xy 226.620371 -157.383985) (xy 226.564934 -157.390085) (xy 226.5092 -157.388048)
			(xy 226.454357 -157.377918) (xy 226.401573 -157.359911) (xy 226.351973 -157.33441) (xy 226.306615 -157.301959)
			(xy 226.266466 -157.26325) (xy 226.23238 -157.219107) (xy 226.205084 -157.170472) (xy 226.185161 -157.118381)
			(xy 226.173035 -157.063944) (xy 226.168964 -157.008322) (xy 179.288139 -157.008322) (xy 179.289455 -157.017266)
			(xy 179.289964 -157.045152) (xy 179.289455 -157.073038) (xy 179.281335 -157.128214) (xy 179.265267 -157.181621)
			(xy 179.241595 -157.232118) (xy 179.210822 -157.278631) (xy 179.173605 -157.320168) (xy 179.130737 -157.355843)
			(xy 179.083131 -157.384897) (xy 179.031802 -157.406709) (xy 178.977845 -157.420815) (xy 178.922408 -157.426915)
			(xy 178.866674 -157.424878) (xy 178.811831 -157.414748) (xy 178.759047 -157.396741) (xy 178.709447 -157.37124)
			(xy 178.664089 -157.338789) (xy 178.62394 -157.30008) (xy 178.589854 -157.255937) (xy 178.562558 -157.207302)
			(xy 178.542635 -157.155211) (xy 178.530509 -157.100774) (xy 178.526438 -157.045152) (xy 168.1596 -157.045152)
			(xy 168.159683 -157.045714) (xy 168.160192 -157.0736) (xy 168.159683 -157.101486) (xy 168.151563 -157.156662)
			(xy 168.135495 -157.210069) (xy 168.111823 -157.260566) (xy 168.08105 -157.307079) (xy 168.043833 -157.348616)
			(xy 168.000965 -157.384291) (xy 167.953359 -157.413345) (xy 167.90203 -157.435157) (xy 167.848073 -157.449263)
			(xy 167.792636 -157.455363) (xy 167.736902 -157.453326) (xy 167.682059 -157.443196) (xy 167.629275 -157.425189)
			(xy 167.579675 -157.399688) (xy 167.534317 -157.367237) (xy 167.494168 -157.328528) (xy 167.460082 -157.284385)
			(xy 167.432786 -157.23575) (xy 167.412863 -157.183659) (xy 167.400737 -157.129222) (xy 167.396666 -157.0736)
			(xy 153.902154 -157.0736) (xy 153.937943 -157.103384) (xy 153.97516 -157.144921) (xy 154.005933 -157.191434)
			(xy 154.029605 -157.241931) (xy 154.045673 -157.295338) (xy 154.053793 -157.350514) (xy 154.054302 -157.3784)
			(xy 154.053793 -157.406286) (xy 154.045673 -157.461462) (xy 154.029605 -157.514869) (xy 154.005933 -157.565366)
			(xy 153.97516 -157.611879) (xy 153.937943 -157.653416) (xy 153.895075 -157.689091) (xy 153.847469 -157.718145)
			(xy 153.79614 -157.739957) (xy 153.742183 -157.754063) (xy 153.686746 -157.760163) (xy 153.631012 -157.758126)
			(xy 153.576169 -157.747996) (xy 153.523385 -157.729989) (xy 153.473785 -157.704488) (xy 153.428427 -157.672037)
			(xy 153.388278 -157.633328) (xy 153.354192 -157.589185) (xy 153.326896 -157.54055) (xy 153.306973 -157.488459)
			(xy 153.294847 -157.434022) (xy 153.290776 -157.3784) (xy 152.557988 -157.3784) (xy 152.557988 -158.3944)
			(xy 153.290776 -158.3944) (xy 153.294847 -158.338778) (xy 153.306973 -158.284341) (xy 153.326896 -158.23225)
			(xy 153.354192 -158.183615) (xy 153.388278 -158.139472) (xy 153.428427 -158.100763) (xy 153.473785 -158.068312)
			(xy 153.523385 -158.042811) (xy 153.576169 -158.024804) (xy 153.631012 -158.014674) (xy 153.686746 -158.012637)
			(xy 153.742183 -158.018737) (xy 153.79614 -158.032843) (xy 153.847469 -158.054655) (xy 153.895075 -158.083709)
			(xy 153.937943 -158.119384) (xy 153.97516 -158.160921) (xy 154.005933 -158.207434) (xy 154.011659 -158.219648)
			(xy 197.282052 -158.219648) (xy 197.286123 -158.164026) (xy 197.298249 -158.109589) (xy 197.318172 -158.057498)
			(xy 197.345468 -158.008863) (xy 197.379554 -157.96472) (xy 197.419703 -157.926011) (xy 197.465061 -157.89356)
			(xy 197.514661 -157.868059) (xy 197.567445 -157.850052) (xy 197.622288 -157.839922) (xy 197.678022 -157.837885)
			(xy 197.733459 -157.843985) (xy 197.787416 -157.858091) (xy 197.838745 -157.879903) (xy 197.871783 -157.900066)
			(xy 228.314505 -157.900066) (xy 228.314505 -157.840134) (xy 228.322328 -157.780714) (xy 228.33784 -157.722823)
			(xy 228.360775 -157.667453) (xy 228.390741 -157.61555) (xy 228.427226 -157.568002) (xy 228.469605 -157.525624)
			(xy 228.517153 -157.489139) (xy 228.569056 -157.459173) (xy 228.624427 -157.436238) (xy 228.682318 -157.420727)
			(xy 228.741738 -157.412905) (xy 228.771704 -157.412436) (xy 229.635304 -157.412436) (xy 229.665274 -157.412838)
			(xy 229.724702 -157.420663) (xy 229.7826 -157.436177) (xy 229.837978 -157.459116) (xy 229.889888 -157.489086)
			(xy 229.937442 -157.525576) (xy 229.979827 -157.567961) (xy 230.016316 -157.615515) (xy 230.046286 -157.667425)
			(xy 230.069224 -157.722803) (xy 230.084738 -157.780702) (xy 230.092562 -157.84013) (xy 230.092562 -157.90007)
			(xy 230.089876 -157.920473) (xy 230.557725 -157.920473) (xy 230.557725 -157.860527) (xy 230.56555 -157.801095)
			(xy 230.581066 -157.743192) (xy 230.604007 -157.68781) (xy 230.633981 -157.635897) (xy 230.670475 -157.58834)
			(xy 230.712864 -157.545953) (xy 230.760423 -157.509463) (xy 230.812339 -157.479493) (xy 230.867722 -157.456555)
			(xy 230.925626 -157.441044) (xy 230.985059 -157.433223) (xy 231.015032 -157.432756) (xy 231.878632 -157.432756)
			(xy 231.908596 -157.43332) (xy 231.968011 -157.441146) (xy 232.025896 -157.45666) (xy 232.081261 -157.479596)
			(xy 232.133158 -157.509563) (xy 232.180701 -157.546046) (xy 232.223075 -157.588423) (xy 232.259555 -157.635968)
			(xy 232.289518 -157.687868) (xy 232.31245 -157.743235) (xy 232.32796 -157.801121) (xy 232.329523 -157.812994)
			(xy 238.850168 -157.812994) (xy 238.854239 -157.757372) (xy 238.866365 -157.702935) (xy 238.886288 -157.650844)
			(xy 238.913584 -157.602209) (xy 238.94767 -157.558066) (xy 238.987819 -157.519357) (xy 239.033177 -157.486906)
			(xy 239.082777 -157.461405) (xy 239.135561 -157.443398) (xy 239.190404 -157.433268) (xy 239.246138 -157.431231)
			(xy 239.301575 -157.437331) (xy 239.355532 -157.451437) (xy 239.406861 -157.473249) (xy 239.454467 -157.502303)
			(xy 239.497335 -157.537978) (xy 239.534552 -157.579515) (xy 239.565325 -157.626028) (xy 239.575575 -157.647894)
			(xy 243.21389 -157.647894) (xy 243.214426 -157.621251) (xy 243.222949 -157.568653) (xy 243.239806 -157.518105)
			(xy 243.264559 -157.470919) (xy 243.296567 -157.428318) (xy 243.334998 -157.391409) (xy 243.356638 -157.37586)
			(xy 243.367927 -157.367502) (xy 243.385779 -157.345826) (xy 243.397058 -157.320111) (xy 243.400914 -157.292297)
			(xy 243.397056 -157.264483) (xy 243.385775 -157.238768) (xy 243.367922 -157.217094) (xy 243.356638 -157.208728)
			(xy 243.335036 -157.193131) (xy 243.296621 -157.156218) (xy 243.264621 -157.113623) (xy 243.239863 -157.066449)
			(xy 243.222988 -157.015916) (xy 243.214432 -156.963332) (xy 243.21389 -156.936694) (xy 243.2144 -156.910707)
			(xy 243.22253 -156.859372) (xy 243.238591 -156.809942) (xy 243.262187 -156.763632) (xy 243.292737 -156.721584)
			(xy 243.329488 -156.684833) (xy 243.371536 -156.654283) (xy 243.417846 -156.630687) (xy 243.467276 -156.614626)
			(xy 243.518611 -156.606496) (xy 243.570585 -156.606496) (xy 243.62192 -156.614626) (xy 243.67135 -156.630687)
			(xy 243.71766 -156.654283) (xy 243.759708 -156.684833) (xy 243.796459 -156.721584) (xy 243.827009 -156.763632)
			(xy 243.850605 -156.809942) (xy 243.866666 -156.859372) (xy 243.874796 -156.910707) (xy 243.875306 -156.936694)
			(xy 243.874763 -156.963336) (xy 243.866242 -157.015935) (xy 243.849386 -157.066483) (xy 243.824634 -157.113669)
			(xy 243.792628 -157.156269) (xy 243.754198 -157.193179) (xy 243.732558 -157.208728) (xy 243.721281 -157.217101)
			(xy 243.70343 -157.238774) (xy 243.692151 -157.264486) (xy 243.688293 -157.292297) (xy 243.692149 -157.320108)
			(xy 243.703427 -157.34582) (xy 243.721276 -157.367494) (xy 243.732558 -157.37586) (xy 243.754153 -157.391465)
			(xy 243.792569 -157.428377) (xy 243.82457 -157.47097) (xy 243.849329 -157.518142) (xy 243.866205 -157.568673)
			(xy 243.874763 -157.621257) (xy 243.875306 -157.647894) (xy 244.113812 -157.647894) (xy 244.114338 -157.621251)
			(xy 244.122862 -157.568651) (xy 244.13972 -157.518103) (xy 244.164475 -157.470916) (xy 244.196485 -157.428316)
			(xy 244.234919 -157.391408) (xy 244.25656 -157.37586) (xy 244.267847 -157.3675) (xy 244.285695 -157.345824)
			(xy 244.296971 -157.320109) (xy 244.300827 -157.292297) (xy 244.29697 -157.264484) (xy 244.285691 -157.23877)
			(xy 244.267842 -157.217095) (xy 244.25656 -157.208728) (xy 244.234963 -157.193125) (xy 244.196547 -157.156213)
			(xy 244.164545 -157.11362) (xy 244.139786 -157.066447) (xy 244.122911 -157.015915) (xy 244.114354 -156.963332)
			(xy 244.113812 -156.936694) (xy 244.114322 -156.910707) (xy 244.122452 -156.859372) (xy 244.138513 -156.809942)
			(xy 244.162109 -156.763632) (xy 244.192659 -156.721584) (xy 244.22941 -156.684833) (xy 244.271458 -156.654283)
			(xy 244.317768 -156.630687) (xy 244.367198 -156.614626) (xy 244.418533 -156.606496) (xy 244.470507 -156.606496)
			(xy 244.521842 -156.614626) (xy 244.571272 -156.630687) (xy 244.617582 -156.654283) (xy 244.65963 -156.684833)
			(xy 244.696381 -156.721584) (xy 244.726931 -156.763632) (xy 244.750527 -156.809942) (xy 244.766588 -156.859372)
			(xy 244.774718 -156.910707) (xy 244.775228 -156.936694) (xy 244.774719 -156.963338) (xy 244.766195 -157.01594)
			(xy 244.749335 -157.06649) (xy 244.724577 -157.113677) (xy 244.692563 -157.156276) (xy 244.654124 -157.193182)
			(xy 244.63248 -157.208728) (xy 244.621201 -157.2171) (xy 244.603346 -157.238771) (xy 244.592064 -157.264484)
			(xy 244.588206 -157.292297) (xy 244.592063 -157.320109) (xy 244.603343 -157.345823) (xy 244.621196 -157.367495)
			(xy 244.63248 -157.37586) (xy 244.65408 -157.391459) (xy 244.692494 -157.428373) (xy 244.724494 -157.470967)
			(xy 244.749252 -157.518141) (xy 244.766128 -157.568673) (xy 244.774685 -157.621256) (xy 244.775228 -157.647894)
			(xy 245.013734 -157.647894) (xy 245.014251 -157.62125) (xy 245.022775 -157.56865) (xy 245.039635 -157.518101)
			(xy 245.064392 -157.470914) (xy 245.096403 -157.428315) (xy 245.134839 -157.391407) (xy 245.156482 -157.37586)
			(xy 245.167776 -157.367505) (xy 245.185637 -157.345832) (xy 245.196923 -157.320115) (xy 245.200782 -157.292297)
			(xy 245.196921 -157.264479) (xy 245.185634 -157.238763) (xy 245.167771 -157.217091) (xy 245.156482 -157.208728)
			(xy 245.13489 -157.193118) (xy 245.096472 -157.156209) (xy 245.06447 -157.113617) (xy 245.03971 -157.066446)
			(xy 245.022833 -157.015915) (xy 245.014276 -156.963331) (xy 245.013734 -156.936694) (xy 245.014244 -156.910707)
			(xy 245.022374 -156.859372) (xy 245.038435 -156.809942) (xy 245.062031 -156.763632) (xy 245.092581 -156.721584)
			(xy 245.129332 -156.684833) (xy 245.17138 -156.654283) (xy 245.21769 -156.630687) (xy 245.26712 -156.614626)
			(xy 245.318455 -156.606496) (xy 245.370429 -156.606496) (xy 245.421764 -156.614626) (xy 245.471194 -156.630687)
			(xy 245.517504 -156.654283) (xy 245.559552 -156.684833) (xy 245.596303 -156.721584) (xy 245.626853 -156.763632)
			(xy 245.650449 -156.809942) (xy 245.66651 -156.859372) (xy 245.67464 -156.910707) (xy 245.67515 -156.936694)
			(xy 245.674631 -156.963338) (xy 245.666108 -157.015938) (xy 245.649249 -157.066488) (xy 245.624493 -157.113675)
			(xy 245.592481 -157.156274) (xy 245.554045 -157.193181) (xy 245.532402 -157.208728) (xy 245.521121 -157.217099)
			(xy 245.503263 -157.238769) (xy 245.491978 -157.264483) (xy 245.488119 -157.292297) (xy 245.491976 -157.320111)
			(xy 245.503259 -157.345825) (xy 245.521116 -157.367496) (xy 245.532402 -157.37586) (xy 245.553985 -157.391482)
			(xy 245.592404 -157.428388) (xy 245.624408 -157.470977) (xy 245.64917 -157.518146) (xy 245.666048 -157.568676)
			(xy 245.674607 -157.621257) (xy 245.67515 -157.647894) (xy 245.91391 -157.647894) (xy 245.914437 -157.621251)
			(xy 245.922961 -157.568652) (xy 245.939819 -157.518103) (xy 245.964574 -157.470917) (xy 245.996583 -157.428317)
			(xy 246.035017 -157.391408) (xy 246.056658 -157.37586) (xy 246.067946 -157.3675) (xy 246.085793 -157.345824)
			(xy 246.09707 -157.320109) (xy 246.100926 -157.292297) (xy 246.097068 -157.264484) (xy 246.08579 -157.23877)
			(xy 246.067941 -157.217095) (xy 246.056658 -157.208728) (xy 246.035061 -157.193125) (xy 245.996645 -157.156214)
			(xy 245.964643 -157.11362) (xy 245.939884 -157.066447) (xy 245.923009 -157.015915) (xy 245.914452 -156.963332)
			(xy 245.91391 -156.936694) (xy 245.91442 -156.910707) (xy 245.92255 -156.859372) (xy 245.938611 -156.809942)
			(xy 245.962207 -156.763632) (xy 245.992757 -156.721584) (xy 246.029508 -156.684833) (xy 246.071556 -156.654283)
			(xy 246.117866 -156.630687) (xy 246.167296 -156.614626) (xy 246.218631 -156.606496) (xy 246.270605 -156.606496)
			(xy 246.32194 -156.614626) (xy 246.37137 -156.630687) (xy 246.41768 -156.654283) (xy 246.459728 -156.684833)
			(xy 246.496479 -156.721584) (xy 246.527029 -156.763632) (xy 246.550625 -156.809942) (xy 246.566686 -156.859372)
			(xy 246.574816 -156.910707) (xy 246.575326 -156.936694) (xy 246.574817 -156.963338) (xy 246.566294 -157.01594)
			(xy 246.549434 -157.06649) (xy 246.524675 -157.113677) (xy 246.492661 -157.156276) (xy 246.454222 -157.193182)
			(xy 246.432578 -157.208728) (xy 246.421299 -157.2171) (xy 246.403445 -157.238772) (xy 246.392163 -157.264484)
			(xy 246.388305 -157.292297) (xy 246.392161 -157.320109) (xy 246.403441 -157.345823) (xy 246.421294 -157.367495)
			(xy 246.432578 -157.37586) (xy 246.454178 -157.391459) (xy 246.492592 -157.428373) (xy 246.524592 -157.470967)
			(xy 246.54935 -157.518141) (xy 246.566226 -157.568673) (xy 246.574783 -157.621256) (xy 246.575285 -157.645862)
			(xy 247.52935 -157.645862) (xy 247.529776 -157.619546) (xy 247.537017 -157.567416) (xy 247.551343 -157.516771)
			(xy 247.572483 -157.468572) (xy 247.600038 -157.42373) (xy 247.633484 -157.383093) (xy 247.65254 -157.364938)
			(xy 247.659918 -157.357396) (xy 247.668458 -157.338132) (xy 247.66905 -157.3276) (xy 247.66905 -157.252924)
			(xy 247.668507 -157.242376) (xy 247.65998 -157.223082) (xy 247.65254 -157.215586) (xy 247.633473 -157.197442)
			(xy 247.600019 -157.156808) (xy 247.572463 -157.111965) (xy 247.551327 -157.063763) (xy 247.537012 -157.013114)
			(xy 247.529788 -156.960979) (xy 247.52935 -156.934662) (xy 247.529836 -156.907411) (xy 247.537592 -156.853463)
			(xy 247.552947 -156.801168) (xy 247.575589 -156.751591) (xy 247.605055 -156.705741) (xy 247.640746 -156.66455)
			(xy 247.681937 -156.628859) (xy 247.727787 -156.599393) (xy 247.777364 -156.576751) (xy 247.829659 -156.561396)
			(xy 247.883607 -156.55364) (xy 247.938109 -156.55364) (xy 247.992057 -156.561396) (xy 248.044352 -156.576751)
			(xy 248.093929 -156.599393) (xy 248.139779 -156.628859) (xy 248.158524 -156.645101) (xy 249.513918 -156.645101)
			(xy 249.518234 -156.587828) (xy 249.531084 -156.531849) (xy 249.552177 -156.478427) (xy 249.581038 -156.428769)
			(xy 249.617015 -156.383997) (xy 249.637804 -156.364178) (xy 249.645218 -156.356667) (xy 249.653735 -156.337379)
			(xy 249.654314 -156.32684) (xy 249.654314 -156.252164) (xy 249.65376 -156.241617) (xy 249.645242 -156.222322)
			(xy 249.637804 -156.214826) (xy 249.618769 -156.19665) (xy 249.58531 -156.156025) (xy 249.557748 -156.111189)
			(xy 249.536606 -156.062992) (xy 249.522284 -156.012348) (xy 249.515055 -155.960217) (xy 249.514614 -155.933902)
			(xy 249.5151 -155.906651) (xy 249.522856 -155.852703) (xy 249.538211 -155.800408) (xy 249.560853 -155.750831)
			(xy 249.590319 -155.704981) (xy 249.62601 -155.66379) (xy 249.667201 -155.628099) (xy 249.713051 -155.598633)
			(xy 249.762628 -155.575991) (xy 249.814923 -155.560636) (xy 249.868871 -155.55288) (xy 249.923373 -155.55288)
			(xy 249.977321 -155.560636) (xy 250.029616 -155.575991) (xy 250.079193 -155.598633) (xy 250.125043 -155.628099)
			(xy 250.166234 -155.66379) (xy 250.201925 -155.704981) (xy 250.231391 -155.750831) (xy 250.254033 -155.800408)
			(xy 250.269388 -155.852703) (xy 250.277144 -155.906651) (xy 250.27763 -155.933902) (xy 250.277154 -155.960216)
			(xy 250.26992 -156.012343) (xy 250.255602 -156.062986) (xy 250.234471 -156.111184) (xy 250.206927 -156.156028)
			(xy 250.17349 -156.196669) (xy 250.15444 -156.214826) (xy 250.147031 -156.222341) (xy 250.13851 -156.241626)
			(xy 250.13793 -156.252164) (xy 250.13793 -156.32684) (xy 250.138469 -156.337389) (xy 250.146996 -156.356685)
			(xy 250.15444 -156.364178) (xy 250.175229 -156.383997) (xy 250.211202 -156.42877) (xy 250.24006 -156.478428)
			(xy 250.261151 -156.53185) (xy 250.273999 -156.587829) (xy 250.278314 -156.645101) (xy 250.273999 -156.702374)
			(xy 250.272863 -156.707322) (xy 252.579727 -156.707322) (xy 252.584039 -156.650052) (xy 252.596884 -156.594076)
			(xy 252.617973 -156.540656) (xy 252.646828 -156.491) (xy 252.682798 -156.446228) (xy 252.703584 -156.426408)
			(xy 252.710982 -156.418883) (xy 252.719509 -156.399606) (xy 252.720094 -156.38907) (xy 252.720094 -156.314394)
			(xy 252.719584 -156.303842) (xy 252.711036 -156.284547) (xy 252.703584 -156.277056) (xy 252.684511 -156.258918)
			(xy 252.651056 -156.218284) (xy 252.6235 -156.17344) (xy 252.602364 -156.125236) (xy 252.588051 -156.074586)
			(xy 252.58083 -156.022449) (xy 252.580394 -155.996132) (xy 252.58088 -155.968881) (xy 252.588636 -155.914933)
			(xy 252.603991 -155.862638) (xy 252.626633 -155.813061) (xy 252.656099 -155.767211) (xy 252.69179 -155.72602)
			(xy 252.732981 -155.690329) (xy 252.778831 -155.660863) (xy 252.828408 -155.638221) (xy 252.880703 -155.622866)
			(xy 252.934651 -155.61511) (xy 252.989153 -155.61511) (xy 253.043101 -155.622866) (xy 253.095396 -155.638221)
			(xy 253.144973 -155.660863) (xy 253.190823 -155.690329) (xy 253.232014 -155.72602) (xy 253.267705 -155.767211)
			(xy 253.297171 -155.813061) (xy 253.319813 -155.862638) (xy 253.335168 -155.914933) (xy 253.342924 -155.968881)
			(xy 253.34341 -155.996132) (xy 253.342961 -156.022447) (xy 253.335722 -156.074576) (xy 253.321399 -156.125219)
			(xy 253.300263 -156.173417) (xy 253.272714 -156.218261) (xy 253.239273 -156.2589) (xy 253.22022 -156.277056)
			(xy 253.212839 -156.284595) (xy 253.204302 -156.303862) (xy 253.20371 -156.314394) (xy 253.20371 -156.38907)
			(xy 253.204239 -156.39962) (xy 253.212774 -156.418915) (xy 253.22022 -156.426408) (xy 253.24104 -156.446196)
			(xy 253.277014 -156.490973) (xy 253.305873 -156.540636) (xy 253.326964 -156.594062) (xy 253.33981 -156.650045)
			(xy 253.344123 -156.707322) (xy 253.339804 -156.764598) (xy 253.326951 -156.82058) (xy 253.305854 -156.874003)
			(xy 253.27699 -156.923663) (xy 253.24101 -156.968436) (xy 253.22022 -156.988256) (xy 253.212839 -156.995795)
			(xy 253.204302 -157.015062) (xy 253.20371 -157.025594) (xy 253.20371 -157.10027) (xy 253.204239 -157.11082)
			(xy 253.212774 -157.130115) (xy 253.22022 -157.137608) (xy 253.239276 -157.155763) (xy 253.272733 -157.196393)
			(xy 253.300291 -157.241234) (xy 253.321429 -157.289435) (xy 253.335746 -157.340082) (xy 253.342971 -157.392216)
			(xy 253.34341 -157.418532) (xy 253.342924 -157.445783) (xy 253.335168 -157.499731) (xy 253.319813 -157.552026)
			(xy 253.297171 -157.601603) (xy 253.267705 -157.647453) (xy 253.232014 -157.688644) (xy 253.190823 -157.724335)
			(xy 253.144973 -157.753801) (xy 253.095396 -157.776443) (xy 253.043101 -157.791798) (xy 252.989153 -157.799554)
			(xy 252.934651 -157.799554) (xy 252.880703 -157.791798) (xy 252.828408 -157.776443) (xy 252.778831 -157.753801)
			(xy 252.732981 -157.724335) (xy 252.69179 -157.688644) (xy 252.656099 -157.647453) (xy 252.626633 -157.601603)
			(xy 252.603991 -157.552026) (xy 252.588636 -157.499731) (xy 252.58088 -157.445783) (xy 252.580394 -157.418532)
			(xy 252.580818 -157.392217) (xy 252.588062 -157.340086) (xy 252.60239 -157.289443) (xy 252.62353 -157.241244)
			(xy 252.651084 -157.196402) (xy 252.684529 -157.155764) (xy 252.703584 -157.137608) (xy 252.710982 -157.130083)
			(xy 252.719509 -157.110806) (xy 252.720094 -157.10027) (xy 252.720094 -157.025594) (xy 252.719584 -157.015042)
			(xy 252.711036 -156.995747) (xy 252.703584 -156.988256) (xy 252.682828 -156.968404) (xy 252.646852 -156.923636)
			(xy 252.617991 -156.873983) (xy 252.596897 -156.820566) (xy 252.584045 -156.764591) (xy 252.579727 -156.707322)
			(xy 250.272863 -156.707322) (xy 250.26115 -156.758353) (xy 250.240059 -156.811774) (xy 250.2112 -156.861432)
			(xy 250.175227 -156.906205) (xy 250.15444 -156.926026) (xy 250.147031 -156.933541) (xy 250.13851 -156.952826)
			(xy 250.13793 -156.963364) (xy 250.13793 -157.03804) (xy 250.138469 -157.048589) (xy 250.146996 -157.067885)
			(xy 250.15444 -157.075378) (xy 250.173486 -157.093543) (xy 250.206942 -157.134172) (xy 250.234501 -157.17901)
			(xy 250.255641 -157.227209) (xy 250.269961 -157.277854) (xy 250.277189 -157.329987) (xy 250.27763 -157.356302)
			(xy 250.277144 -157.383553) (xy 250.269388 -157.437501) (xy 250.254033 -157.489796) (xy 250.231391 -157.539373)
			(xy 250.201925 -157.585223) (xy 250.166234 -157.626414) (xy 250.125043 -157.662105) (xy 250.079193 -157.691571)
			(xy 250.029616 -157.714213) (xy 249.977321 -157.729568) (xy 249.923373 -157.737324) (xy 249.868871 -157.737324)
			(xy 249.814923 -157.729568) (xy 249.762628 -157.714213) (xy 249.713051 -157.691571) (xy 249.667201 -157.662105)
			(xy 249.62601 -157.626414) (xy 249.590319 -157.585223) (xy 249.560853 -157.539373) (xy 249.538211 -157.489796)
			(xy 249.522856 -157.437501) (xy 249.5151 -157.383553) (xy 249.514614 -157.356302) (xy 249.515078 -157.329988)
			(xy 249.522313 -157.277859) (xy 249.536633 -157.227216) (xy 249.557766 -157.179017) (xy 249.585312 -157.134174)
			(xy 249.618752 -157.093534) (xy 249.637804 -157.075378) (xy 249.645218 -157.067867) (xy 249.653735 -157.048579)
			(xy 249.654314 -157.03804) (xy 249.654314 -156.963364) (xy 249.65376 -156.952817) (xy 249.645242 -156.933522)
			(xy 249.637804 -156.926026) (xy 249.617017 -156.906205) (xy 249.58104 -156.861433) (xy 249.552178 -156.811776)
			(xy 249.531084 -156.758354) (xy 249.518234 -156.702374) (xy 249.513918 -156.645101) (xy 248.158524 -156.645101)
			(xy 248.18097 -156.66455) (xy 248.216661 -156.705741) (xy 248.246127 -156.751591) (xy 248.268769 -156.801168)
			(xy 248.284124 -156.853463) (xy 248.29188 -156.907411) (xy 248.292366 -156.934662) (xy 248.291951 -156.960978)
			(xy 248.284707 -157.013109) (xy 248.270378 -157.063753) (xy 248.249236 -157.111952) (xy 248.22168 -157.156794)
			(xy 248.188232 -157.197431) (xy 248.169176 -157.215586) (xy 248.16179 -157.223121) (xy 248.153254 -157.24239)
			(xy 248.152666 -157.252924) (xy 248.152666 -157.3276) (xy 248.153192 -157.33815) (xy 248.16173 -157.357444)
			(xy 248.169176 -157.364938) (xy 248.188238 -157.383087) (xy 248.221696 -157.423717) (xy 248.249255 -157.468559)
			(xy 248.270392 -157.516761) (xy 248.284707 -157.56741) (xy 248.291929 -157.619545) (xy 248.292366 -157.645862)
			(xy 248.29188 -157.673113) (xy 248.284124 -157.727061) (xy 248.268769 -157.779356) (xy 248.246127 -157.828933)
			(xy 248.216661 -157.874783) (xy 248.18097 -157.915974) (xy 248.139779 -157.951665) (xy 248.093929 -157.981131)
			(xy 248.044352 -158.003773) (xy 247.992057 -158.019128) (xy 247.938109 -158.026884) (xy 247.883607 -158.026884)
			(xy 247.829659 -158.019128) (xy 247.777364 -158.003773) (xy 247.727787 -157.981131) (xy 247.681937 -157.951665)
			(xy 247.640746 -157.915974) (xy 247.605055 -157.874783) (xy 247.575589 -157.828933) (xy 247.552947 -157.779356)
			(xy 247.537592 -157.727061) (xy 247.529836 -157.673113) (xy 247.52935 -157.645862) (xy 246.575285 -157.645862)
			(xy 246.575326 -157.647894) (xy 246.574816 -157.673881) (xy 246.566686 -157.725216) (xy 246.550625 -157.774646)
			(xy 246.527029 -157.820956) (xy 246.496479 -157.863004) (xy 246.459728 -157.899755) (xy 246.41768 -157.930305)
			(xy 246.37137 -157.953901) (xy 246.32194 -157.969962) (xy 246.270605 -157.978092) (xy 246.218631 -157.978092)
			(xy 246.167296 -157.969962) (xy 246.117866 -157.953901) (xy 246.071556 -157.930305) (xy 246.029508 -157.899755)
			(xy 245.992757 -157.863004) (xy 245.962207 -157.820956) (xy 245.938611 -157.774646) (xy 245.92255 -157.725216)
			(xy 245.91442 -157.673881) (xy 245.91391 -157.647894) (xy 245.67515 -157.647894) (xy 245.67464 -157.673881)
			(xy 245.66651 -157.725216) (xy 245.650449 -157.774646) (xy 245.626853 -157.820956) (xy 245.596303 -157.863004)
			(xy 245.559552 -157.899755) (xy 245.517504 -157.930305) (xy 245.471194 -157.953901) (xy 245.421764 -157.969962)
			(xy 245.370429 -157.978092) (xy 245.318455 -157.978092) (xy 245.26712 -157.969962) (xy 245.21769 -157.953901)
			(xy 245.17138 -157.930305) (xy 245.129332 -157.899755) (xy 245.092581 -157.863004) (xy 245.062031 -157.820956)
			(xy 245.038435 -157.774646) (xy 245.022374 -157.725216) (xy 245.014244 -157.673881) (xy 245.013734 -157.647894)
			(xy 244.775228 -157.647894) (xy 244.774718 -157.673881) (xy 244.766588 -157.725216) (xy 244.750527 -157.774646)
			(xy 244.726931 -157.820956) (xy 244.696381 -157.863004) (xy 244.65963 -157.899755) (xy 244.617582 -157.930305)
			(xy 244.571272 -157.953901) (xy 244.521842 -157.969962) (xy 244.470507 -157.978092) (xy 244.418533 -157.978092)
			(xy 244.367198 -157.969962) (xy 244.317768 -157.953901) (xy 244.271458 -157.930305) (xy 244.22941 -157.899755)
			(xy 244.192659 -157.863004) (xy 244.162109 -157.820956) (xy 244.138513 -157.774646) (xy 244.122452 -157.725216)
			(xy 244.114322 -157.673881) (xy 244.113812 -157.647894) (xy 243.875306 -157.647894) (xy 243.874796 -157.673881)
			(xy 243.866666 -157.725216) (xy 243.850605 -157.774646) (xy 243.827009 -157.820956) (xy 243.796459 -157.863004)
			(xy 243.759708 -157.899755) (xy 243.71766 -157.930305) (xy 243.67135 -157.953901) (xy 243.62192 -157.969962)
			(xy 243.570585 -157.978092) (xy 243.518611 -157.978092) (xy 243.467276 -157.969962) (xy 243.417846 -157.953901)
			(xy 243.371536 -157.930305) (xy 243.329488 -157.899755) (xy 243.292737 -157.863004) (xy 243.262187 -157.820956)
			(xy 243.238591 -157.774646) (xy 243.22253 -157.725216) (xy 243.2144 -157.673881) (xy 243.21389 -157.647894)
			(xy 239.575575 -157.647894) (xy 239.588997 -157.676525) (xy 239.605065 -157.729932) (xy 239.613185 -157.785108)
			(xy 239.613694 -157.812994) (xy 239.613185 -157.84088) (xy 239.605065 -157.896056) (xy 239.588997 -157.949463)
			(xy 239.565325 -157.99996) (xy 239.534552 -158.046473) (xy 239.522082 -158.06039) (xy 241.039648 -158.06039)
			(xy 241.043719 -158.004768) (xy 241.055845 -157.950331) (xy 241.075768 -157.89824) (xy 241.103064 -157.849605)
			(xy 241.13715 -157.805462) (xy 241.177299 -157.766753) (xy 241.222657 -157.734302) (xy 241.272257 -157.708801)
			(xy 241.325041 -157.690794) (xy 241.379884 -157.680664) (xy 241.435618 -157.678627) (xy 241.491055 -157.684727)
			(xy 241.545012 -157.698833) (xy 241.596341 -157.720645) (xy 241.643947 -157.749699) (xy 241.686815 -157.785374)
			(xy 241.724032 -157.826911) (xy 241.754805 -157.873424) (xy 241.778477 -157.923921) (xy 241.794545 -157.977328)
			(xy 241.802665 -158.032504) (xy 241.803174 -158.06039) (xy 241.802665 -158.088276) (xy 241.794545 -158.143452)
			(xy 241.778477 -158.196859) (xy 241.754805 -158.247356) (xy 241.724032 -158.293869) (xy 241.686815 -158.335406)
			(xy 241.643947 -158.371081) (xy 241.596341 -158.400135) (xy 241.545012 -158.421947) (xy 241.491055 -158.436053)
			(xy 241.435618 -158.442153) (xy 241.379884 -158.440116) (xy 241.325041 -158.429986) (xy 241.272257 -158.411979)
			(xy 241.222657 -158.386478) (xy 241.177299 -158.354027) (xy 241.13715 -158.315318) (xy 241.103064 -158.271175)
			(xy 241.075768 -158.22254) (xy 241.055845 -158.170449) (xy 241.043719 -158.116012) (xy 241.039648 -158.06039)
			(xy 239.522082 -158.06039) (xy 239.497335 -158.08801) (xy 239.454467 -158.123685) (xy 239.406861 -158.152739)
			(xy 239.355532 -158.174551) (xy 239.301575 -158.188657) (xy 239.246138 -158.194757) (xy 239.190404 -158.19272)
			(xy 239.135561 -158.18259) (xy 239.082777 -158.164583) (xy 239.033177 -158.139082) (xy 238.987819 -158.106631)
			(xy 238.94767 -158.067922) (xy 238.913584 -158.023779) (xy 238.886288 -157.975144) (xy 238.866365 -157.923053)
			(xy 238.854239 -157.868616) (xy 238.850168 -157.812994) (xy 232.329523 -157.812994) (xy 232.335782 -157.860536)
			(xy 232.335782 -157.920464) (xy 232.32796 -157.979879) (xy 232.31245 -158.037765) (xy 232.289518 -158.093132)
			(xy 232.259555 -158.145032) (xy 232.223075 -158.192577) (xy 232.180701 -158.234954) (xy 232.133158 -158.271437)
			(xy 232.081261 -158.301404) (xy 232.025896 -158.32434) (xy 231.968011 -158.339854) (xy 231.908596 -158.34768)
			(xy 231.878632 -158.348172) (xy 231.015032 -158.348172) (xy 230.985059 -158.347777) (xy 230.925626 -158.339956)
			(xy 230.867722 -158.324445) (xy 230.812339 -158.301507) (xy 230.760423 -158.271537) (xy 230.712864 -158.235047)
			(xy 230.670475 -158.19266) (xy 230.633981 -158.145103) (xy 230.604007 -158.09319) (xy 230.581066 -158.037808)
			(xy 230.56555 -157.979905) (xy 230.557725 -157.920473) (xy 230.089876 -157.920473) (xy 230.084738 -157.959498)
			(xy 230.069224 -158.017397) (xy 230.046286 -158.072775) (xy 230.016316 -158.124685) (xy 229.979827 -158.172239)
			(xy 229.937442 -158.214624) (xy 229.889888 -158.251114) (xy 229.837978 -158.281084) (xy 229.7826 -158.304023)
			(xy 229.724702 -158.319537) (xy 229.665274 -158.327362) (xy 229.635304 -158.327852) (xy 228.771704 -158.327852)
			(xy 228.741738 -158.327295) (xy 228.682318 -158.319473) (xy 228.624427 -158.303962) (xy 228.569056 -158.281027)
			(xy 228.517153 -158.251061) (xy 228.469605 -158.214576) (xy 228.427226 -158.172198) (xy 228.390741 -158.12465)
			(xy 228.360775 -158.072747) (xy 228.33784 -158.017377) (xy 228.322328 -157.959486) (xy 228.314505 -157.900066)
			(xy 197.871783 -157.900066) (xy 197.886351 -157.908957) (xy 197.929219 -157.944632) (xy 197.966436 -157.986169)
			(xy 197.997209 -158.032682) (xy 198.020881 -158.083179) (xy 198.036949 -158.136586) (xy 198.045069 -158.191762)
			(xy 198.045578 -158.219648) (xy 198.045069 -158.247534) (xy 198.036949 -158.30271) (xy 198.020881 -158.356117)
			(xy 197.997209 -158.406614) (xy 197.966436 -158.453127) (xy 197.929219 -158.494664) (xy 197.886351 -158.530339)
			(xy 197.838745 -158.559393) (xy 197.787416 -158.581205) (xy 197.733459 -158.595311) (xy 197.678022 -158.601411)
			(xy 197.622288 -158.599374) (xy 197.567445 -158.589244) (xy 197.514661 -158.571237) (xy 197.465061 -158.545736)
			(xy 197.419703 -158.513285) (xy 197.379554 -158.474576) (xy 197.345468 -158.430433) (xy 197.318172 -158.381798)
			(xy 197.298249 -158.329707) (xy 197.286123 -158.27527) (xy 197.282052 -158.219648) (xy 154.011659 -158.219648)
			(xy 154.029605 -158.257931) (xy 154.045673 -158.311338) (xy 154.053793 -158.366514) (xy 154.054302 -158.3944)
			(xy 154.053793 -158.422286) (xy 154.045673 -158.477462) (xy 154.029605 -158.530869) (xy 154.005933 -158.581366)
			(xy 153.97516 -158.627879) (xy 153.937943 -158.669416) (xy 153.895075 -158.705091) (xy 153.847469 -158.734145)
			(xy 153.79614 -158.755957) (xy 153.742183 -158.770063) (xy 153.686746 -158.776163) (xy 153.631012 -158.774126)
			(xy 153.576169 -158.763996) (xy 153.523385 -158.745989) (xy 153.473785 -158.720488) (xy 153.428427 -158.688037)
			(xy 153.388278 -158.649328) (xy 153.354192 -158.605185) (xy 153.326896 -158.55655) (xy 153.306973 -158.504459)
			(xy 153.294847 -158.450022) (xy 153.290776 -158.3944) (xy 152.557988 -158.3944) (xy 152.557988 -158.828994)
			(xy 238.850168 -158.828994) (xy 238.854239 -158.773372) (xy 238.866365 -158.718935) (xy 238.886288 -158.666844)
			(xy 238.913584 -158.618209) (xy 238.94767 -158.574066) (xy 238.987819 -158.535357) (xy 239.033177 -158.502906)
			(xy 239.082777 -158.477405) (xy 239.135561 -158.459398) (xy 239.190404 -158.449268) (xy 239.246138 -158.447231)
			(xy 239.301575 -158.453331) (xy 239.355532 -158.467437) (xy 239.406861 -158.489249) (xy 239.454467 -158.518303)
			(xy 239.497335 -158.553978) (xy 239.534552 -158.595515) (xy 239.565325 -158.642028) (xy 239.588997 -158.692525)
			(xy 239.605065 -158.745932) (xy 239.60615 -158.753302) (xy 248.716544 -158.753302) (xy 248.720615 -158.69768)
			(xy 248.732741 -158.643243) (xy 248.752664 -158.591152) (xy 248.77996 -158.542517) (xy 248.814046 -158.498374)
			(xy 248.854195 -158.459665) (xy 248.899553 -158.427214) (xy 248.949153 -158.401713) (xy 249.001937 -158.383706)
			(xy 249.05678 -158.373576) (xy 249.112514 -158.371539) (xy 249.167951 -158.377639) (xy 249.221908 -158.391745)
			(xy 249.273237 -158.413557) (xy 249.320843 -158.442611) (xy 249.363711 -158.478286) (xy 249.400928 -158.519823)
			(xy 249.431701 -158.566336) (xy 249.455373 -158.616833) (xy 249.471441 -158.67024) (xy 249.479561 -158.725416)
			(xy 249.48007 -158.753302) (xy 249.479561 -158.781188) (xy 249.471441 -158.836364) (xy 249.455373 -158.889771)
			(xy 249.431701 -158.940268) (xy 249.400928 -158.986781) (xy 249.363711 -159.028318) (xy 249.320843 -159.063993)
			(xy 249.273237 -159.093047) (xy 249.221908 -159.114859) (xy 249.167951 -159.128965) (xy 249.112514 -159.135065)
			(xy 249.05678 -159.133028) (xy 249.001937 -159.122898) (xy 248.949153 -159.104891) (xy 248.899553 -159.07939)
			(xy 248.854195 -159.046939) (xy 248.814046 -159.00823) (xy 248.77996 -158.964087) (xy 248.752664 -158.915452)
			(xy 248.732741 -158.863361) (xy 248.720615 -158.808924) (xy 248.716544 -158.753302) (xy 239.60615 -158.753302)
			(xy 239.613185 -158.801108) (xy 239.613694 -158.828994) (xy 239.613185 -158.85688) (xy 239.605065 -158.912056)
			(xy 239.588997 -158.965463) (xy 239.565325 -159.01596) (xy 239.534552 -159.062473) (xy 239.497335 -159.10401)
			(xy 239.454467 -159.139685) (xy 239.406861 -159.168739) (xy 239.355532 -159.190551) (xy 239.301575 -159.204657)
			(xy 239.246138 -159.210757) (xy 239.190404 -159.20872) (xy 239.135561 -159.19859) (xy 239.082777 -159.180583)
			(xy 239.033177 -159.155082) (xy 238.987819 -159.122631) (xy 238.94767 -159.083922) (xy 238.913584 -159.039779)
			(xy 238.886288 -158.991144) (xy 238.866365 -158.939053) (xy 238.854239 -158.884616) (xy 238.850168 -158.828994)
			(xy 152.557988 -158.828994) (xy 152.557988 -160.1851) (xy 161.624277 -160.1851) (xy 161.628232 -160.093263)
			(xy 161.640067 -160.002106) (xy 161.659694 -159.912303) (xy 161.686968 -159.824521) (xy 161.721688 -159.739407)
			(xy 161.763596 -159.657594) (xy 161.812382 -159.579686) (xy 161.867685 -159.506261) (xy 161.929095 -159.437861)
			(xy 161.996157 -159.374994) (xy 162.068376 -159.318124) (xy 162.145216 -159.267673) (xy 162.226109 -159.224014)
			(xy 162.310455 -159.187471) (xy 162.397631 -159.158314) (xy 162.48699 -159.13676) (xy 162.577871 -159.122966)
			(xy 162.669602 -159.117036) (xy 162.761503 -159.119014) (xy 162.852894 -159.128885) (xy 162.943098 -159.146575)
			(xy 163.031447 -159.171955) (xy 163.117287 -159.204835) (xy 163.199983 -159.244973) (xy 163.278923 -159.292072)
			(xy 163.353521 -159.345782) (xy 163.423227 -159.405706) (xy 163.487522 -159.4714) (xy 163.545933 -159.542378)
			(xy 163.598025 -159.618115) (xy 163.643414 -159.69805) (xy 163.681764 -159.78159) (xy 163.712789 -159.868118)
			(xy 163.736262 -159.956993) (xy 163.752008 -160.047557) (xy 163.75991 -160.139139) (xy 163.760404 -160.1851)
			(xy 185.988973 -160.1851) (xy 185.992929 -160.093241) (xy 186.004766 -160.002062) (xy 186.024398 -159.912238)
			(xy 186.051679 -159.824435) (xy 186.086407 -159.739302) (xy 186.128325 -159.657469) (xy 186.177123 -159.579542)
			(xy 186.232438 -159.506099) (xy 186.293863 -159.437683) (xy 186.360942 -159.374801) (xy 186.433177 -159.317918)
			(xy 186.510036 -159.267455) (xy 186.590948 -159.223786) (xy 186.675314 -159.187234) (xy 186.76251 -159.15807)
			(xy 186.851891 -159.13651) (xy 186.942794 -159.122714) (xy 187.034547 -159.116782) (xy 187.126469 -159.118761)
			(xy 187.217882 -159.128634) (xy 187.308107 -159.146329) (xy 187.396478 -159.171714) (xy 187.482338 -159.204602)
			(xy 187.546301 -159.235648) (xy 197.448422 -159.235648) (xy 197.452493 -159.180026) (xy 197.464619 -159.125589)
			(xy 197.484542 -159.073498) (xy 197.511838 -159.024863) (xy 197.545924 -158.98072) (xy 197.586073 -158.942011)
			(xy 197.631431 -158.90956) (xy 197.681031 -158.884059) (xy 197.733815 -158.866052) (xy 197.788658 -158.855922)
			(xy 197.844392 -158.853885) (xy 197.899829 -158.859985) (xy 197.953786 -158.874091) (xy 198.005115 -158.895903)
			(xy 198.052721 -158.924957) (xy 198.095589 -158.960632) (xy 198.132806 -159.002169) (xy 198.163579 -159.048682)
			(xy 198.187251 -159.099179) (xy 198.203319 -159.152586) (xy 198.211439 -159.207762) (xy 198.211948 -159.235648)
			(xy 198.211439 -159.263534) (xy 198.203319 -159.31871) (xy 198.187251 -159.372117) (xy 198.163579 -159.422614)
			(xy 198.152671 -159.439102) (xy 241.107974 -159.439102) (xy 241.112045 -159.38348) (xy 241.124171 -159.329043)
			(xy 241.144094 -159.276952) (xy 241.17139 -159.228317) (xy 241.205476 -159.184174) (xy 241.245625 -159.145465)
			(xy 241.290983 -159.113014) (xy 241.340583 -159.087513) (xy 241.393367 -159.069506) (xy 241.44821 -159.059376)
			(xy 241.503944 -159.057339) (xy 241.559381 -159.063439) (xy 241.613338 -159.077545) (xy 241.664667 -159.099357)
			(xy 241.712273 -159.128411) (xy 241.755141 -159.164086) (xy 241.792358 -159.205623) (xy 241.823131 -159.252136)
			(xy 241.846803 -159.302633) (xy 241.862871 -159.35604) (xy 241.870991 -159.411216) (xy 241.8715 -159.439102)
			(xy 241.870991 -159.466988) (xy 241.862871 -159.522164) (xy 241.859968 -159.531812) (xy 244.312692 -159.531812)
			(xy 244.316763 -159.47619) (xy 244.328889 -159.421753) (xy 244.348812 -159.369662) (xy 244.376108 -159.321027)
			(xy 244.410194 -159.276884) (xy 244.450343 -159.238175) (xy 244.495701 -159.205724) (xy 244.545301 -159.180223)
			(xy 244.598085 -159.162216) (xy 244.652928 -159.152086) (xy 244.708662 -159.150049) (xy 244.764099 -159.156149)
			(xy 244.818056 -159.170255) (xy 244.869385 -159.192067) (xy 244.916991 -159.221121) (xy 244.959859 -159.256796)
			(xy 244.997076 -159.298333) (xy 245.027849 -159.344846) (xy 245.051521 -159.395343) (xy 245.067589 -159.44875)
			(xy 245.073458 -159.488632) (xy 246.595898 -159.488632) (xy 246.599969 -159.43301) (xy 246.612095 -159.378573)
			(xy 246.632018 -159.326482) (xy 246.659314 -159.277847) (xy 246.6934 -159.233704) (xy 246.733549 -159.194995)
			(xy 246.778907 -159.162544) (xy 246.828507 -159.137043) (xy 246.881291 -159.119036) (xy 246.936134 -159.108906)
			(xy 246.991868 -159.106869) (xy 247.047305 -159.112969) (xy 247.101262 -159.127075) (xy 247.152591 -159.148887)
			(xy 247.200197 -159.177941) (xy 247.243065 -159.213616) (xy 247.280282 -159.255153) (xy 247.311055 -159.301666)
			(xy 247.334727 -159.352163) (xy 247.350795 -159.40557) (xy 247.358915 -159.460746) (xy 247.359424 -159.488632)
			(xy 247.358915 -159.516518) (xy 247.350795 -159.571694) (xy 247.334727 -159.625101) (xy 247.311055 -159.675598)
			(xy 247.280282 -159.722111) (xy 247.243065 -159.763648) (xy 247.200197 -159.799323) (xy 247.152591 -159.828377)
			(xy 247.101262 -159.850189) (xy 247.047305 -159.864295) (xy 246.991868 -159.870395) (xy 246.936134 -159.868358)
			(xy 246.881291 -159.858228) (xy 246.828507 -159.840221) (xy 246.778907 -159.81472) (xy 246.733549 -159.782269)
			(xy 246.6934 -159.74356) (xy 246.659314 -159.699417) (xy 246.632018 -159.650782) (xy 246.612095 -159.598691)
			(xy 246.599969 -159.544254) (xy 246.595898 -159.488632) (xy 245.073458 -159.488632) (xy 245.075709 -159.503926)
			(xy 245.076218 -159.531812) (xy 245.075709 -159.559698) (xy 245.067589 -159.614874) (xy 245.051521 -159.668281)
			(xy 245.027849 -159.718778) (xy 244.997076 -159.765291) (xy 244.959859 -159.806828) (xy 244.916991 -159.842503)
			(xy 244.869385 -159.871557) (xy 244.818056 -159.893369) (xy 244.764099 -159.907475) (xy 244.708662 -159.913575)
			(xy 244.652928 -159.911538) (xy 244.598085 -159.901408) (xy 244.545301 -159.883401) (xy 244.495701 -159.8579)
			(xy 244.450343 -159.825449) (xy 244.410194 -159.78674) (xy 244.376108 -159.742597) (xy 244.348812 -159.693962)
			(xy 244.328889 -159.641871) (xy 244.316763 -159.587434) (xy 244.312692 -159.531812) (xy 241.859968 -159.531812)
			(xy 241.846803 -159.575571) (xy 241.823131 -159.626068) (xy 241.792358 -159.672581) (xy 241.755141 -159.714118)
			(xy 241.712273 -159.749793) (xy 241.664667 -159.778847) (xy 241.613338 -159.800659) (xy 241.559381 -159.814765)
			(xy 241.503944 -159.820865) (xy 241.44821 -159.818828) (xy 241.393367 -159.808698) (xy 241.340583 -159.790691)
			(xy 241.290983 -159.76519) (xy 241.245625 -159.732739) (xy 241.205476 -159.69403) (xy 241.17139 -159.649887)
			(xy 241.144094 -159.601252) (xy 241.124171 -159.549161) (xy 241.112045 -159.494724) (xy 241.107974 -159.439102)
			(xy 198.152671 -159.439102) (xy 198.132806 -159.469127) (xy 198.095589 -159.510664) (xy 198.052721 -159.546339)
			(xy 198.005115 -159.575393) (xy 197.953786 -159.597205) (xy 197.899829 -159.611311) (xy 197.844392 -159.617411)
			(xy 197.788658 -159.615374) (xy 197.733815 -159.605244) (xy 197.681031 -159.587237) (xy 197.631431 -159.561736)
			(xy 197.586073 -159.529285) (xy 197.545924 -159.490576) (xy 197.511838 -159.446433) (xy 197.484542 -159.397798)
			(xy 197.464619 -159.345707) (xy 197.452493 -159.29127) (xy 197.448422 -159.235648) (xy 187.546301 -159.235648)
			(xy 187.565054 -159.24475) (xy 187.644012 -159.291859) (xy 187.718629 -159.345582) (xy 187.78835 -159.40552)
			(xy 187.852661 -159.47123) (xy 187.911086 -159.542226) (xy 187.963191 -159.61798) (xy 188.00859 -159.697934)
			(xy 188.046949 -159.781494) (xy 188.077982 -159.868043) (xy 188.10146 -159.956939) (xy 188.11721 -160.047524)
			(xy 188.125114 -160.139128) (xy 188.125608 -160.1851) (xy 188.125114 -160.231072) (xy 188.11721 -160.322676)
			(xy 188.10146 -160.413261) (xy 188.077982 -160.502157) (xy 188.046949 -160.588706) (xy 188.00859 -160.672266)
			(xy 187.963191 -160.75222) (xy 187.911086 -160.827974) (xy 187.852661 -160.89897) (xy 187.78835 -160.96468)
			(xy 187.718629 -161.024618) (xy 187.644012 -161.078341) (xy 187.565054 -161.12545) (xy 187.482338 -161.165598)
			(xy 187.396478 -161.198486) (xy 187.308107 -161.223871) (xy 187.217882 -161.241566) (xy 187.126469 -161.251439)
			(xy 187.034547 -161.253418) (xy 186.942794 -161.247486) (xy 186.851891 -161.23369) (xy 186.76251 -161.21213)
			(xy 186.675314 -161.182966) (xy 186.590948 -161.146414) (xy 186.510036 -161.102745) (xy 186.433177 -161.052282)
			(xy 186.360942 -160.995399) (xy 186.293863 -160.932517) (xy 186.232438 -160.864101) (xy 186.177123 -160.790658)
			(xy 186.128325 -160.712731) (xy 186.086407 -160.630898) (xy 186.051679 -160.545765) (xy 186.024398 -160.457962)
			(xy 186.004766 -160.368138) (xy 185.992929 -160.276959) (xy 185.988973 -160.1851) (xy 163.760404 -160.1851)
			(xy 163.75991 -160.231061) (xy 163.752008 -160.322643) (xy 163.736262 -160.413207) (xy 163.712789 -160.502082)
			(xy 163.681764 -160.58861) (xy 163.643414 -160.67215) (xy 163.598025 -160.752085) (xy 163.545933 -160.827822)
			(xy 163.487522 -160.8988) (xy 163.423227 -160.964494) (xy 163.353521 -161.024418) (xy 163.278923 -161.078128)
			(xy 163.199983 -161.125227) (xy 163.117287 -161.165365) (xy 163.031447 -161.198245) (xy 162.943098 -161.223625)
			(xy 162.852894 -161.241315) (xy 162.761503 -161.251186) (xy 162.669602 -161.253164) (xy 162.577871 -161.247234)
			(xy 162.48699 -161.23344) (xy 162.397631 -161.211886) (xy 162.310455 -161.182729) (xy 162.226109 -161.146186)
			(xy 162.145216 -161.102527) (xy 162.068376 -161.052076) (xy 161.996157 -160.995206) (xy 161.929095 -160.932339)
			(xy 161.867685 -160.863939) (xy 161.812382 -160.790514) (xy 161.763596 -160.712606) (xy 161.721688 -160.630793)
			(xy 161.686968 -160.545679) (xy 161.659694 -160.457897) (xy 161.640067 -160.368094) (xy 161.628232 -160.276937)
			(xy 161.624277 -160.1851) (xy 152.557988 -160.1851) (xy 152.557988 -164.198046) (xy 166.809164 -164.198046)
			(xy 166.813235 -164.142424) (xy 166.825361 -164.087987) (xy 166.845284 -164.035896) (xy 166.87258 -163.987261)
			(xy 166.906666 -163.943118) (xy 166.946815 -163.904409) (xy 166.992173 -163.871958) (xy 167.041773 -163.846457)
			(xy 167.094557 -163.82845) (xy 167.1494 -163.81832) (xy 167.205134 -163.816283) (xy 167.260571 -163.822383)
			(xy 167.314528 -163.836489) (xy 167.365857 -163.858301) (xy 167.413463 -163.887355) (xy 167.456331 -163.92303)
			(xy 167.493548 -163.964567) (xy 167.524321 -164.01108) (xy 167.547993 -164.061577) (xy 167.558942 -164.09797)
			(xy 168.691304 -164.09797) (xy 168.695375 -164.042348) (xy 168.707501 -163.987911) (xy 168.727424 -163.93582)
			(xy 168.75472 -163.887185) (xy 168.788806 -163.843042) (xy 168.828955 -163.804333) (xy 168.874313 -163.771882)
			(xy 168.923913 -163.746381) (xy 168.976697 -163.728374) (xy 169.03154 -163.718244) (xy 169.087274 -163.716207)
			(xy 169.142711 -163.722307) (xy 169.196668 -163.736413) (xy 169.247997 -163.758225) (xy 169.295603 -163.787279)
			(xy 169.338471 -163.822954) (xy 169.375688 -163.864491) (xy 169.406461 -163.911004) (xy 169.430133 -163.961501)
			(xy 169.446201 -164.014908) (xy 169.454321 -164.070084) (xy 169.45483 -164.09797) (xy 169.454321 -164.125856)
			(xy 169.446201 -164.181032) (xy 169.430133 -164.234439) (xy 169.406461 -164.284936) (xy 169.375688 -164.331449)
			(xy 169.338471 -164.372986) (xy 169.295603 -164.408661) (xy 169.247997 -164.437715) (xy 169.196668 -164.459527)
			(xy 169.142711 -164.473633) (xy 169.087274 -164.479733) (xy 169.03154 -164.477696) (xy 168.976697 -164.467566)
			(xy 168.923913 -164.449559) (xy 168.874313 -164.424058) (xy 168.828955 -164.391607) (xy 168.788806 -164.352898)
			(xy 168.75472 -164.308755) (xy 168.727424 -164.26012) (xy 168.707501 -164.208029) (xy 168.695375 -164.153592)
			(xy 168.691304 -164.09797) (xy 167.558942 -164.09797) (xy 167.564061 -164.114984) (xy 167.572181 -164.17016)
			(xy 167.57269 -164.198046) (xy 167.572181 -164.225932) (xy 167.564061 -164.281108) (xy 167.547993 -164.334515)
			(xy 167.524321 -164.385012) (xy 167.493548 -164.431525) (xy 167.456331 -164.473062) (xy 167.413463 -164.508737)
			(xy 167.365857 -164.537791) (xy 167.314528 -164.559603) (xy 167.260571 -164.573709) (xy 167.205134 -164.579809)
			(xy 167.1494 -164.577772) (xy 167.094557 -164.567642) (xy 167.041773 -164.549635) (xy 166.992173 -164.524134)
			(xy 166.946815 -164.491683) (xy 166.906666 -164.452974) (xy 166.87258 -164.408831) (xy 166.845284 -164.360196)
			(xy 166.825361 -164.308105) (xy 166.813235 -164.253668) (xy 166.809164 -164.198046) (xy 152.557988 -164.198046)
			(xy 152.557988 -165.120066) (xy 152.559004 -165.129718) (xy 152.559118 -165.130226) (xy 166.766238 -165.130226)
			(xy 166.770309 -165.074604) (xy 166.782435 -165.020167) (xy 166.802358 -164.968076) (xy 166.829654 -164.919441)
			(xy 166.86374 -164.875298) (xy 166.903889 -164.836589) (xy 166.949247 -164.804138) (xy 166.998847 -164.778637)
			(xy 167.051631 -164.76063) (xy 167.106474 -164.7505) (xy 167.162208 -164.748463) (xy 167.217645 -164.754563)
			(xy 167.271602 -164.768669) (xy 167.322931 -164.790481) (xy 167.370537 -164.819535) (xy 167.413405 -164.85521)
			(xy 167.450622 -164.896747) (xy 167.481395 -164.94326) (xy 167.505067 -164.993757) (xy 167.521135 -165.047164)
			(xy 167.529255 -165.10234) (xy 167.529764 -165.130226) (xy 167.529255 -165.158112) (xy 167.521135 -165.213288)
			(xy 167.505067 -165.266695) (xy 167.481395 -165.317192) (xy 167.450622 -165.363705) (xy 167.413405 -165.405242)
			(xy 167.370537 -165.440917) (xy 167.322931 -165.469971) (xy 167.271602 -165.491783) (xy 167.217645 -165.505889)
			(xy 167.162208 -165.511989) (xy 167.106474 -165.509952) (xy 167.051631 -165.499822) (xy 166.998847 -165.481815)
			(xy 166.949247 -165.456314) (xy 166.903889 -165.423863) (xy 166.86374 -165.385154) (xy 166.829654 -165.341011)
			(xy 166.802358 -165.292376) (xy 166.782435 -165.240285) (xy 166.770309 -165.185848) (xy 166.766238 -165.130226)
			(xy 152.559118 -165.130226) (xy 152.560626 -165.136965) (xy 152.567459 -165.150143) (xy 152.572466 -165.155626)
			(xy 153.487466 -166.070534) (xy 180.295294 -166.070534) (xy 180.299365 -166.014912) (xy 180.311491 -165.960475)
			(xy 180.331414 -165.908384) (xy 180.35871 -165.859749) (xy 180.392796 -165.815606) (xy 180.432945 -165.776897)
			(xy 180.478303 -165.744446) (xy 180.527903 -165.718945) (xy 180.580687 -165.700938) (xy 180.63553 -165.690808)
			(xy 180.691264 -165.688771) (xy 180.746701 -165.694871) (xy 180.800658 -165.708977) (xy 180.851987 -165.730789)
			(xy 180.899593 -165.759843) (xy 180.942461 -165.795518) (xy 180.979678 -165.837055) (xy 181.010451 -165.883568)
			(xy 181.034123 -165.934065) (xy 181.050191 -165.987472) (xy 181.058311 -166.042648) (xy 181.05882 -166.070534)
			(xy 181.058311 -166.09842) (xy 181.050191 -166.153596) (xy 181.034123 -166.207003) (xy 181.010451 -166.2575)
			(xy 180.979678 -166.304013) (xy 180.942461 -166.34555) (xy 180.899593 -166.381225) (xy 180.851987 -166.410279)
			(xy 180.800658 -166.432091) (xy 180.746701 -166.446197) (xy 180.691264 -166.452297) (xy 180.63553 -166.45026)
			(xy 180.580687 -166.44013) (xy 180.527903 -166.422123) (xy 180.478303 -166.396622) (xy 180.432945 -166.364171)
			(xy 180.392796 -166.325462) (xy 180.35871 -166.281319) (xy 180.331414 -166.232684) (xy 180.311491 -166.180593)
			(xy 180.299365 -166.126156) (xy 180.295294 -166.070534) (xy 153.487466 -166.070534) (xy 154.12253 -166.705534)
			(xy 177.211734 -166.705534) (xy 177.215805 -166.649912) (xy 177.227931 -166.595475) (xy 177.247854 -166.543384)
			(xy 177.27515 -166.494749) (xy 177.309236 -166.450606) (xy 177.349385 -166.411897) (xy 177.394743 -166.379446)
			(xy 177.444343 -166.353945) (xy 177.497127 -166.335938) (xy 177.55197 -166.325808) (xy 177.607704 -166.323771)
			(xy 177.663141 -166.329871) (xy 177.717098 -166.343977) (xy 177.768427 -166.365789) (xy 177.816033 -166.394843)
			(xy 177.858901 -166.430518) (xy 177.896118 -166.472055) (xy 177.926891 -166.518568) (xy 177.950563 -166.569065)
			(xy 177.950966 -166.570406) (xy 178.787042 -166.570406) (xy 178.791113 -166.514784) (xy 178.803239 -166.460347)
			(xy 178.823162 -166.408256) (xy 178.850458 -166.359621) (xy 178.884544 -166.315478) (xy 178.924693 -166.276769)
			(xy 178.970051 -166.244318) (xy 179.019651 -166.218817) (xy 179.072435 -166.20081) (xy 179.127278 -166.19068)
			(xy 179.183012 -166.188643) (xy 179.238449 -166.194743) (xy 179.292406 -166.208849) (xy 179.343735 -166.230661)
			(xy 179.391341 -166.259715) (xy 179.434209 -166.29539) (xy 179.471426 -166.336927) (xy 179.502199 -166.38344)
			(xy 179.525871 -166.433937) (xy 179.541939 -166.487344) (xy 179.550059 -166.54252) (xy 179.550568 -166.570406)
			(xy 179.550059 -166.598292) (xy 179.541939 -166.653468) (xy 179.525871 -166.706875) (xy 179.502199 -166.757372)
			(xy 179.471426 -166.803885) (xy 179.434209 -166.845422) (xy 179.391341 -166.881097) (xy 179.343735 -166.910151)
			(xy 179.292406 -166.931963) (xy 179.238449 -166.946069) (xy 179.183012 -166.952169) (xy 179.127278 -166.950132)
			(xy 179.072435 -166.940002) (xy 179.019651 -166.921995) (xy 178.970051 -166.896494) (xy 178.924693 -166.864043)
			(xy 178.884544 -166.825334) (xy 178.850458 -166.781191) (xy 178.823162 -166.732556) (xy 178.803239 -166.680465)
			(xy 178.791113 -166.626028) (xy 178.787042 -166.570406) (xy 177.950966 -166.570406) (xy 177.966631 -166.622472)
			(xy 177.974751 -166.677648) (xy 177.97526 -166.705534) (xy 177.974751 -166.73342) (xy 177.966631 -166.788596)
			(xy 177.950563 -166.842003) (xy 177.926891 -166.8925) (xy 177.896118 -166.939013) (xy 177.858901 -166.98055)
			(xy 177.816033 -167.016225) (xy 177.768427 -167.045279) (xy 177.717098 -167.067091) (xy 177.663141 -167.081197)
			(xy 177.607704 -167.087297) (xy 177.55197 -167.08526) (xy 177.497127 -167.07513) (xy 177.444343 -167.057123)
			(xy 177.394743 -167.031622) (xy 177.349385 -166.999171) (xy 177.309236 -166.960462) (xy 177.27515 -166.916319)
			(xy 177.247854 -166.867684) (xy 177.227931 -166.815593) (xy 177.215805 -166.761156) (xy 177.211734 -166.705534)
			(xy 154.12253 -166.705534) (xy 155.097734 -167.68064) (xy 155.103235 -167.685624) (xy 155.116403 -167.69246)
			(xy 155.123642 -167.694102) (xy 155.133294 -167.695118) (xy 205.49616 -167.695118)
		)
		(stroke
			(width 0)
			(type solid)
		)
		(fill yes)
		(layer "In15.Cu")
		(net "GND")
	)
	(gr_poly
		(pts
			(xy 3.672332 -33.434528) (xy 3.694208 -33.426488) (xy 3.739423 -33.415181) (xy 3.78568 -33.409473)
			(xy 3.808984 -33.409128) (xy 3.832287 -33.409494) (xy 3.878541 -33.415202) (xy 3.923757 -33.426498)
			(xy 3.945636 -33.434528) (xy 3.954526 -33.43783) (xy 4.878324 -33.43783) (xy 4.887976 -33.433512)
			(xy 4.9125 -33.423069) (xy 4.963735 -33.408364) (xy 5.016518 -33.40094) (xy 5.069822 -33.40094) (xy 5.122605 -33.408364)
			(xy 5.17384 -33.423069) (xy 5.198364 -33.433512) (xy 5.208016 -33.43783) (xy 6.767576 -33.43783)
			(xy 6.773949 -33.437601) (xy 6.786287 -33.434393) (xy 6.79196 -33.43148) (xy 6.823202 -33.414462)
			(xy 6.826504 -33.409382) (xy 6.829806 -33.404302) (xy 6.83006 -33.404048) (xy 6.847122 -33.37942)
			(xy 6.886644 -33.334392) (xy 6.931703 -33.294905) (xy 6.981528 -33.261634) (xy 7.035269 -33.235148)
			(xy 7.092005 -33.215899) (xy 7.150767 -33.204216) (xy 7.210552 -33.2003) (xy 7.270337 -33.204216)
			(xy 7.329099 -33.215899) (xy 7.385835 -33.235148) (xy 7.439576 -33.261634) (xy 7.489401 -33.294905)
			(xy 7.53446 -33.334392) (xy 7.573982 -33.37942) (xy 7.591044 -33.404048) (xy 7.591298 -33.404302)
			(xy 7.5946 -33.409382) (xy 7.597902 -33.414462) (xy 7.629144 -33.43148) (xy 7.634808 -33.434417)
			(xy 7.647151 -33.437639) (xy 7.653528 -33.43783) (xy 20.887436 -33.43783) (xy 20.896356 -33.437438)
			(xy 20.91312 -33.43133) (xy 20.920202 -33.425892) (xy 20.92706 -33.42005) (xy 20.935696 -33.40481)
			(xy 20.93722 -33.395666) (xy 20.942151 -33.369354) (xy 20.958413 -33.318352) (xy 20.981646 -33.270124)
			(xy 21.011393 -33.225618) (xy 21.04707 -33.185707) (xy 21.087977 -33.151177) (xy 21.133309 -33.122704)
			(xy 21.182176 -33.100849) (xy 21.23362 -33.086041) (xy 21.286628 -33.07857) (xy 21.313394 -33.078166)
			(xy 21.321268 -33.078166) (xy 21.350128 -33.07927) (xy 21.407036 -33.089105) (xy 21.461812 -33.107406)
			(xy 21.513203 -33.133753) (xy 21.560037 -33.167545) (xy 21.601242 -33.20801) (xy 21.618956 -33.23082)
			(xy 21.624036 -33.237932) (xy 21.646388 -33.252664) (xy 21.650311 -33.255194) (xy 21.658876 -33.258903)
			(xy 21.663406 -33.26003) (xy 21.684996 -33.264856) (xy 21.694007 -33.266449) (xy 21.712104 -33.263841)
			(xy 21.720302 -33.259776) (xy 21.72081 -33.259522) (xy 21.739192 -33.249297) (xy 21.777481 -33.231872)
			(xy 21.797264 -33.224724) (xy 21.821465 -33.216682) (xy 21.871199 -33.205393) (xy 21.921879 -33.199695)
			(xy 21.947378 -33.199324) (xy 21.972878 -33.199684) (xy 22.023561 -33.205375) (xy 22.073296 -33.216666)
			(xy 22.097492 -33.224724) (xy 22.117277 -33.231868) (xy 22.155567 -33.24929) (xy 22.173946 -33.259522)
			(xy 22.174454 -33.259776) (xy 22.182653 -33.263838) (xy 22.20075 -33.266446) (xy 22.20976 -33.264856)
			(xy 22.23135 -33.26003) (xy 22.23587 -33.258875) (xy 22.24443 -33.255166) (xy 22.248368 -33.252664)
			(xy 22.27072 -33.237932) (xy 22.2758 -33.23082) (xy 22.293923 -33.207551) (xy 22.336132 -33.16636)
			(xy 22.384179 -33.132157) (xy 22.436919 -33.105759) (xy 22.493095 -33.087796) (xy 22.551365 -33.078694)
			(xy 22.580854 -33.078166) (xy 22.581362 -33.078166) (xy 22.608123 -33.078621) (xy 22.661118 -33.086108)
			(xy 22.712548 -33.100926) (xy 22.761403 -33.122784) (xy 22.806724 -33.151254) (xy 22.847623 -33.185777)
			(xy 22.883298 -33.225676) (xy 22.913047 -33.270168) (xy 22.936289 -33.31838) (xy 22.952566 -33.369366)
			(xy 22.957536 -33.395666) (xy 22.95906 -33.40481) (xy 22.967696 -33.42005) (xy 22.974554 -33.425892)
			(xy 22.981601 -33.431394) (xy 22.998386 -33.437518) (xy 23.00732 -33.43783) (xy 32.767524 -33.43783)
			(xy 32.773895 -33.437596) (xy 32.786228 -33.434377) (xy 32.791908 -33.43148) (xy 32.82315 -33.414462)
			(xy 32.826452 -33.409382) (xy 32.829754 -33.404302) (xy 32.830008 -33.404048) (xy 32.84707 -33.37942)
			(xy 32.886592 -33.334392) (xy 32.931651 -33.294905) (xy 32.981476 -33.261634) (xy 33.035217 -33.235148)
			(xy 33.091953 -33.215899) (xy 33.150715 -33.204216) (xy 33.2105 -33.2003) (xy 33.270285 -33.204216)
			(xy 33.329047 -33.215899) (xy 33.385783 -33.235148) (xy 33.439524 -33.261634) (xy 33.489349 -33.294905)
			(xy 33.534408 -33.334392) (xy 33.57393 -33.37942) (xy 33.590992 -33.404048) (xy 33.591246 -33.404302)
			(xy 33.594548 -33.409382) (xy 33.59785 -33.414462) (xy 33.629092 -33.43148) (xy 33.634757 -33.434412)
			(xy 33.6471 -33.437622) (xy 33.653476 -33.43783) (xy 46.887384 -33.43783) (xy 46.896301 -33.43743)
			(xy 46.913054 -33.43131) (xy 46.92015 -33.425892) (xy 46.927008 -33.42005) (xy 46.935644 -33.40481)
			(xy 46.937168 -33.395666) (xy 46.9421 -33.369356) (xy 46.958363 -33.318356) (xy 46.981596 -33.270132)
			(xy 47.011344 -33.225629) (xy 47.047022 -33.185723) (xy 47.087929 -33.151197) (xy 47.133261 -33.12273)
			(xy 47.182128 -33.100881) (xy 47.233571 -33.086078) (xy 47.286577 -33.078614) (xy 47.313342 -33.078166)
			(xy 47.321216 -33.078166) (xy 47.350074 -33.079273) (xy 47.406978 -33.089115) (xy 47.461749 -33.10742)
			(xy 47.513135 -33.133771) (xy 47.559963 -33.167566) (xy 47.601163 -33.208032) (xy 47.618904 -33.23082)
			(xy 47.623984 -33.237932) (xy 47.646336 -33.252664) (xy 47.65026 -33.255191) (xy 47.658827 -33.258891)
			(xy 47.663354 -33.26003) (xy 47.684944 -33.264856) (xy 47.693956 -33.266458) (xy 47.712062 -33.263866)
			(xy 47.72025 -33.259776) (xy 47.720758 -33.259522) (xy 47.739139 -33.249295) (xy 47.777426 -33.231866)
			(xy 47.797212 -33.224724) (xy 47.821412 -33.21668) (xy 47.871146 -33.205385) (xy 47.921826 -33.199681)
			(xy 47.947326 -33.199324) (xy 47.972826 -33.199687) (xy 48.023507 -33.205383) (xy 48.07324 -33.216679)
			(xy 48.09744 -33.224724) (xy 48.117224 -33.231869) (xy 48.155512 -33.249295) (xy 48.173894 -33.259522)
			(xy 48.174402 -33.259776) (xy 48.182602 -33.263829) (xy 48.200695 -33.266421) (xy 48.209708 -33.264856)
			(xy 48.231298 -33.26003) (xy 48.23582 -33.258879) (xy 48.244384 -33.255177) (xy 48.248316 -33.252664)
			(xy 48.270668 -33.237932) (xy 48.275748 -33.23082) (xy 48.293872 -33.207553) (xy 48.336083 -33.166368)
			(xy 48.384131 -33.132171) (xy 48.436871 -33.10578) (xy 48.493045 -33.087823) (xy 48.551315 -33.078729)
			(xy 48.580802 -33.078166) (xy 48.58131 -33.078166) (xy 48.608073 -33.078618) (xy 48.661074 -33.086098)
			(xy 48.712509 -33.100911) (xy 48.76137 -33.122767) (xy 48.806698 -33.151235) (xy 48.847603 -33.185757)
			(xy 48.883283 -33.225657) (xy 48.913038 -33.270151) (xy 48.936283 -33.318366) (xy 48.952564 -33.369356)
			(xy 48.957484 -33.395666) (xy 48.959008 -33.40481) (xy 48.967644 -33.42005) (xy 48.974502 -33.425892)
			(xy 48.981551 -33.431387) (xy 48.998336 -33.437495) (xy 49.007268 -33.43783) (xy 58.767472 -33.43783)
			(xy 58.773845 -33.437602) (xy 58.786184 -33.434394) (xy 58.791856 -33.43148) (xy 58.823098 -33.414462)
			(xy 58.8264 -33.409382) (xy 58.829702 -33.404302) (xy 58.829956 -33.404048) (xy 58.847018 -33.37942)
			(xy 58.88654 -33.334392) (xy 58.931599 -33.294905) (xy 58.981424 -33.261634) (xy 59.035165 -33.235148)
			(xy 59.091901 -33.215899) (xy 59.150663 -33.204216) (xy 59.210448 -33.2003) (xy 59.270233 -33.204216)
			(xy 59.328995 -33.215899) (xy 59.385731 -33.235148) (xy 59.439472 -33.261634) (xy 59.489297 -33.294905)
			(xy 59.534356 -33.334392) (xy 59.573878 -33.37942) (xy 59.59094 -33.404048) (xy 59.591194 -33.404302)
			(xy 59.594496 -33.409382) (xy 59.597798 -33.414462) (xy 59.62904 -33.43148) (xy 59.634704 -33.434418)
			(xy 59.647047 -33.437641) (xy 59.653424 -33.43783) (xy 72.887332 -33.43783) (xy 72.896253 -33.437438)
			(xy 72.913017 -33.431331) (xy 72.920098 -33.425892) (xy 72.926956 -33.42005) (xy 72.935592 -33.40481)
			(xy 72.937116 -33.395666) (xy 72.942048 -33.369357) (xy 72.958312 -33.318361) (xy 72.981546 -33.27014)
			(xy 73.011295 -33.225641) (xy 73.046973 -33.185739) (xy 73.087881 -33.151218) (xy 73.133213 -33.122756)
			(xy 73.18208 -33.100912) (xy 73.233522 -33.086116) (xy 73.286526 -33.078658) (xy 73.31329 -33.078166)
			(xy 73.321164 -33.078166) (xy 73.350024 -33.07927) (xy 73.406933 -33.089105) (xy 73.461709 -33.107404)
			(xy 73.513101 -33.133751) (xy 73.559935 -33.167543) (xy 73.60114 -33.208008) (xy 73.618852 -33.23082)
			(xy 73.623932 -33.237932) (xy 73.646284 -33.252664) (xy 73.650207 -33.255195) (xy 73.658772 -33.258904)
			(xy 73.663302 -33.26003) (xy 73.684892 -33.264856) (xy 73.693903 -33.26645) (xy 73.712 -33.263843)
			(xy 73.720198 -33.259776) (xy 73.720706 -33.259522) (xy 73.739088 -33.249297) (xy 73.777377 -33.231871)
			(xy 73.79716 -33.224724) (xy 73.821361 -33.216682) (xy 73.871095 -33.205392) (xy 73.921775 -33.199694)
			(xy 73.947274 -33.199324) (xy 73.972774 -33.199684) (xy 74.023457 -33.205374) (xy 74.073192 -33.216665)
			(xy 74.097388 -33.224724) (xy 74.117173 -33.231867) (xy 74.155463 -33.24929) (xy 74.173842 -33.259522)
			(xy 74.17435 -33.259776) (xy 74.182549 -33.263839) (xy 74.200646 -33.266448) (xy 74.209656 -33.264856)
			(xy 74.231246 -33.26003) (xy 74.235766 -33.258875) (xy 74.244326 -33.255167) (xy 74.248264 -33.252664)
			(xy 74.270616 -33.237932) (xy 74.275696 -33.23082) (xy 74.293821 -33.207556) (xy 74.336033 -33.166375)
			(xy 74.384082 -33.132185) (xy 74.436823 -33.1058) (xy 74.492996 -33.08785) (xy 74.551264 -33.078763)
			(xy 74.58075 -33.078166) (xy 74.581258 -33.078166) (xy 74.608019 -33.078621) (xy 74.661015 -33.086107)
			(xy 74.712445 -33.100925) (xy 74.7613 -33.122783) (xy 74.806622 -33.151252) (xy 74.847522 -33.185775)
			(xy 74.883197 -33.225674) (xy 74.912947 -33.270166) (xy 74.936189 -33.318379) (xy 74.952466 -33.369365)
			(xy 74.957432 -33.395666) (xy 74.958956 -33.40481) (xy 74.967592 -33.42005) (xy 74.97445 -33.425892)
			(xy 74.981497 -33.431394) (xy 74.998281 -33.43752) (xy 75.007216 -33.43783) (xy 84.76742 -33.43783)
			(xy 84.773792 -33.437596) (xy 84.786125 -33.434379) (xy 84.791804 -33.43148) (xy 84.823046 -33.414462)
			(xy 84.826348 -33.409382) (xy 84.82965 -33.404302) (xy 84.829904 -33.404048) (xy 84.846966 -33.37942)
			(xy 84.886488 -33.334392) (xy 84.931547 -33.294905) (xy 84.981372 -33.261634) (xy 85.035113 -33.235148)
			(xy 85.091849 -33.215899) (xy 85.150611 -33.204216) (xy 85.210396 -33.2003) (xy 85.270181 -33.204216)
			(xy 85.328943 -33.215899) (xy 85.385679 -33.235148) (xy 85.43942 -33.261634) (xy 85.489245 -33.294905)
			(xy 85.534304 -33.334392) (xy 85.573826 -33.37942) (xy 85.590888 -33.404048) (xy 85.591142 -33.404302)
			(xy 85.594444 -33.409382) (xy 85.597746 -33.414462) (xy 85.628988 -33.43148) (xy 85.634653 -33.434413)
			(xy 85.646996 -33.437624) (xy 85.653372 -33.43783) (xy 98.88728 -33.43783) (xy 98.896197 -33.43743)
			(xy 98.912951 -33.431311) (xy 98.920046 -33.425892) (xy 98.926904 -33.42005) (xy 98.93554 -33.40481)
			(xy 98.937064 -33.395666) (xy 98.941996 -33.369356) (xy 98.958258 -33.318356) (xy 98.981492 -33.270131)
			(xy 99.01124 -33.225628) (xy 99.046918 -33.185722) (xy 99.087824 -33.151196) (xy 99.133157 -33.122728)
			(xy 99.182024 -33.100878) (xy 99.233466 -33.086075) (xy 99.286473 -33.07861) (xy 99.313238 -33.078166)
			(xy 99.321112 -33.078166) (xy 99.34997 -33.079273) (xy 99.406875 -33.089114) (xy 99.461646 -33.107419)
			(xy 99.513033 -33.13377) (xy 99.559861 -33.167564) (xy 99.601061 -33.208031) (xy 99.6188 -33.23082)
			(xy 99.62388 -33.237932) (xy 99.646232 -33.252664) (xy 99.650156 -33.255191) (xy 99.658723 -33.258892)
			(xy 99.66325 -33.26003) (xy 99.68484 -33.264856) (xy 99.693852 -33.266459) (xy 99.711959 -33.263868)
			(xy 99.720146 -33.259776) (xy 99.720654 -33.259522) (xy 99.739035 -33.249295) (xy 99.777322 -33.231865)
			(xy 99.797108 -33.224724) (xy 99.821308 -33.216679) (xy 99.871042 -33.205384) (xy 99.921722 -33.19968)
			(xy 99.947222 -33.199324) (xy 99.972722 -33.199686) (xy 100.023403 -33.205382) (xy 100.073136 -33.216678)
			(xy 100.097336 -33.224724) (xy 100.11712 -33.231869) (xy 100.155409 -33.249295) (xy 100.17379 -33.259522)
			(xy 100.174298 -33.259776) (xy 100.182498 -33.26383) (xy 100.200591 -33.266423) (xy 100.209604 -33.264856)
			(xy 100.231194 -33.26003) (xy 100.235716 -33.25888) (xy 100.244281 -33.255178) (xy 100.248212 -33.252664)
			(xy 100.270564 -33.237932) (xy 100.275644 -33.23082) (xy 100.293768 -33.207553) (xy 100.335978 -33.166367)
			(xy 100.384027 -33.13217) (xy 100.436767 -33.105778) (xy 100.492941 -33.087821) (xy 100.551211 -33.078726)
			(xy 100.580698 -33.078166) (xy 100.581206 -33.078166) (xy 100.607965 -33.078624) (xy 100.660956 -33.086116)
			(xy 100.712381 -33.100938) (xy 100.76123 -33.122799) (xy 100.806547 -33.15127) (xy 100.847441 -33.185793)
			(xy 100.88311 -33.225692) (xy 100.912856 -33.270182) (xy 100.936094 -33.318392) (xy 100.952368 -33.369375)
			(xy 100.95738 -33.395666) (xy 100.958904 -33.40481) (xy 100.96754 -33.42005) (xy 100.974398 -33.425892)
			(xy 100.981447 -33.431387) (xy 100.998232 -33.437497) (xy 101.007164 -33.43783) (xy 122.867674 -33.43783)
			(xy 122.874047 -33.437602) (xy 122.886386 -33.434394) (xy 122.892058 -33.43148) (xy 122.9233 -33.414462)
			(xy 122.926602 -33.409382) (xy 122.929904 -33.404302) (xy 122.930158 -33.404048) (xy 122.94722 -33.37942)
			(xy 122.986742 -33.334392) (xy 123.031801 -33.294905) (xy 123.081626 -33.261634) (xy 123.135367 -33.235148)
			(xy 123.192103 -33.215899) (xy 123.250865 -33.204216) (xy 123.31065 -33.2003) (xy 123.370435 -33.204216)
			(xy 123.429197 -33.215899) (xy 123.485933 -33.235148) (xy 123.539674 -33.261634) (xy 123.589499 -33.294905)
			(xy 123.634558 -33.334392) (xy 123.67408 -33.37942) (xy 123.691142 -33.404048) (xy 123.691396 -33.404302)
			(xy 123.694698 -33.409382) (xy 123.698 -33.414462) (xy 123.729242 -33.43148) (xy 123.734906 -33.434418)
			(xy 123.747249 -33.43764) (xy 123.753626 -33.43783) (xy 136.987534 -33.43783) (xy 136.996455 -33.437438)
			(xy 137.013218 -33.43133) (xy 137.0203 -33.425892) (xy 137.027158 -33.42005) (xy 137.035794 -33.40481)
			(xy 137.037318 -33.395666) (xy 137.04225 -33.369357) (xy 137.058514 -33.318361) (xy 137.081748 -33.27014)
			(xy 137.111497 -33.225641) (xy 137.147176 -33.18574) (xy 137.188083 -33.151219) (xy 137.233416 -33.122757)
			(xy 137.282283 -33.100913) (xy 137.333724 -33.086117) (xy 137.386728 -33.078659) (xy 137.413492 -33.078166)
			(xy 137.421366 -33.078166) (xy 137.450226 -33.07927) (xy 137.507134 -33.089105) (xy 137.56191 -33.107405)
			(xy 137.613302 -33.133752) (xy 137.660136 -33.167544) (xy 137.701341 -33.208009) (xy 137.719054 -33.23082)
			(xy 137.724134 -33.237932) (xy 137.746486 -33.252664) (xy 137.750409 -33.255194) (xy 137.758974 -33.258903)
			(xy 137.763504 -33.26003) (xy 137.785094 -33.264856) (xy 137.794105 -33.266449) (xy 137.812202 -33.263842)
			(xy 137.8204 -33.259776) (xy 137.820908 -33.259522) (xy 137.83929 -33.249297) (xy 137.877579 -33.231872)
			(xy 137.897362 -33.224724) (xy 137.921563 -33.216682) (xy 137.971297 -33.205393) (xy 138.021977 -33.199695)
			(xy 138.047476 -33.199324) (xy 138.072976 -33.199684) (xy 138.123659 -33.205375) (xy 138.173394 -33.216666)
			(xy 138.19759 -33.224724) (xy 138.217375 -33.231868) (xy 138.255665 -33.24929) (xy 138.274044 -33.259522)
			(xy 138.274552 -33.259776) (xy 138.282751 -33.263838) (xy 138.300848 -33.266447) (xy 138.309858 -33.264856)
			(xy 138.331448 -33.26003) (xy 138.335968 -33.258875) (xy 138.344528 -33.255166) (xy 138.348466 -33.252664)
			(xy 138.370818 -33.237932) (xy 138.375898 -33.23082) (xy 138.394023 -33.207556) (xy 138.436235 -33.166376)
			(xy 138.484284 -33.132186) (xy 138.537025 -33.105801) (xy 138.593199 -33.087852) (xy 138.651466 -33.078765)
			(xy 138.680952 -33.078166) (xy 138.68146 -33.078166) (xy 138.708221 -33.078621) (xy 138.761217 -33.086107)
			(xy 138.812646 -33.100925) (xy 138.861502 -33.122783) (xy 138.906823 -33.151253) (xy 138.947723 -33.185776)
			(xy 138.983397 -33.225675) (xy 139.013147 -33.270167) (xy 139.036389 -33.318379) (xy 139.052666 -33.369366)
			(xy 139.057634 -33.395666) (xy 139.059158 -33.40481) (xy 139.067794 -33.42005) (xy 139.074652 -33.425892)
			(xy 139.081699 -33.431394) (xy 139.098484 -33.437519) (xy 139.107418 -33.43783) (xy 148.867622 -33.43783)
			(xy 148.873994 -33.437596) (xy 148.886326 -33.434378) (xy 148.892006 -33.43148) (xy 148.923248 -33.414462)
			(xy 148.92655 -33.409382) (xy 148.929852 -33.404302) (xy 148.930106 -33.404048) (xy 148.947168 -33.37942)
			(xy 148.98669 -33.334392) (xy 149.031749 -33.294905) (xy 149.081574 -33.261634) (xy 149.135315 -33.235148)
			(xy 149.192051 -33.215899) (xy 149.250813 -33.204216) (xy 149.310598 -33.2003) (xy 149.370383 -33.204216)
			(xy 149.429145 -33.215899) (xy 149.485881 -33.235148) (xy 149.539622 -33.261634) (xy 149.589447 -33.294905)
			(xy 149.634506 -33.334392) (xy 149.674028 -33.37942) (xy 149.69109 -33.404048) (xy 149.691344 -33.404302)
			(xy 149.694646 -33.409382) (xy 149.697948 -33.414462) (xy 149.72919 -33.43148) (xy 149.734855 -33.434412)
			(xy 149.747198 -33.437623) (xy 149.753574 -33.43783) (xy 162.987482 -33.43783) (xy 162.996399 -33.43743)
			(xy 163.013153 -33.43131) (xy 163.020248 -33.425892) (xy 163.027106 -33.42005) (xy 163.035742 -33.40481)
			(xy 163.037266 -33.395666) (xy 163.042198 -33.369356) (xy 163.058461 -33.318356) (xy 163.081694 -33.270131)
			(xy 163.111442 -33.225629) (xy 163.14712 -33.185722) (xy 163.188027 -33.151196) (xy 163.233359 -33.122729)
			(xy 163.282226 -33.100879) (xy 163.333668 -33.086077) (xy 163.386675 -33.078612) (xy 163.41344 -33.078166)
			(xy 163.421314 -33.078166) (xy 163.450172 -33.079273) (xy 163.507076 -33.089115) (xy 163.561848 -33.10742)
			(xy 163.613234 -33.133771) (xy 163.660062 -33.167565) (xy 163.701262 -33.208032) (xy 163.719002 -33.23082)
			(xy 163.724082 -33.237932) (xy 163.746434 -33.252664) (xy 163.750358 -33.255191) (xy 163.758925 -33.258892)
			(xy 163.763452 -33.26003) (xy 163.785042 -33.264856) (xy 163.794054 -33.266459) (xy 163.812161 -33.263867)
			(xy 163.820348 -33.259776) (xy 163.820856 -33.259522) (xy 163.839237 -33.249295) (xy 163.877524 -33.231866)
			(xy 163.89731 -33.224724) (xy 163.92151 -33.21668) (xy 163.971244 -33.205384) (xy 164.021924 -33.19968)
			(xy 164.047424 -33.199324) (xy 164.072924 -33.199687) (xy 164.123605 -33.205382) (xy 164.173338 -33.216678)
			(xy 164.197538 -33.224724) (xy 164.217322 -33.231869) (xy 164.25561 -33.249295) (xy 164.273992 -33.259522)
			(xy 164.2745 -33.259776) (xy 164.2827 -33.26383) (xy 164.300793 -33.266422) (xy 164.309806 -33.264856)
			(xy 164.331396 -33.26003) (xy 164.335918 -33.258879) (xy 164.344483 -33.255177) (xy 164.348414 -33.252664)
			(xy 164.370766 -33.237932) (xy 164.375846 -33.23082) (xy 164.39397 -33.207553) (xy 164.43618 -33.166367)
			(xy 164.484229 -33.132171) (xy 164.536969 -33.105779) (xy 164.593143 -33.087822) (xy 164.651413 -33.078727)
			(xy 164.6809 -33.078166) (xy 164.681408 -33.078166) (xy 164.708171 -33.078617) (xy 164.761172 -33.086098)
			(xy 164.812608 -33.100911) (xy 164.861469 -33.122766) (xy 164.906797 -33.151234) (xy 164.947702 -33.185756)
			(xy 164.983383 -33.225656) (xy 165.013137 -33.27015) (xy 165.036383 -33.318365) (xy 165.052664 -33.369355)
			(xy 165.057582 -33.395666) (xy 165.059106 -33.40481) (xy 165.067742 -33.42005) (xy 165.0746 -33.425892)
			(xy 165.081649 -33.431387) (xy 165.098434 -33.437496) (xy 165.107366 -33.43783) (xy 174.86757 -33.43783)
			(xy 174.873943 -33.437602) (xy 174.886282 -33.434395) (xy 174.891954 -33.43148) (xy 174.923196 -33.414462)
			(xy 174.926498 -33.409382) (xy 174.9298 -33.404302) (xy 174.930054 -33.404048) (xy 174.947116 -33.37942)
			(xy 174.986638 -33.334392) (xy 175.031697 -33.294905) (xy 175.081522 -33.261634) (xy 175.135263 -33.235148)
			(xy 175.191999 -33.215899) (xy 175.250761 -33.204216) (xy 175.310546 -33.2003) (xy 175.370331 -33.204216)
			(xy 175.429093 -33.215899) (xy 175.485829 -33.235148) (xy 175.53957 -33.261634) (xy 175.589395 -33.294905)
			(xy 175.634454 -33.334392) (xy 175.673976 -33.37942) (xy 175.691038 -33.404048) (xy 175.691292 -33.404302)
			(xy 175.694594 -33.409382) (xy 175.697896 -33.414462) (xy 175.729138 -33.43148) (xy 175.734802 -33.434418)
			(xy 175.747144 -33.437642) (xy 175.753522 -33.43783) (xy 188.98743 -33.43783) (xy 188.996351 -33.437439)
			(xy 189.013115 -33.431332) (xy 189.020196 -33.425892) (xy 189.027054 -33.42005) (xy 189.03569 -33.40481)
			(xy 189.037214 -33.395666) (xy 189.042146 -33.369357) (xy 189.05841 -33.318361) (xy 189.081644 -33.270139)
			(xy 189.111393 -33.22564) (xy 189.147071 -33.185738) (xy 189.187979 -33.151217) (xy 189.233311 -33.122755)
			(xy 189.282178 -33.100911) (xy 189.333619 -33.086114) (xy 189.386624 -33.078656) (xy 189.413388 -33.078166)
			(xy 189.421262 -33.078166) (xy 189.450122 -33.07927) (xy 189.507031 -33.089104) (xy 189.561807 -33.107404)
			(xy 189.6132 -33.133751) (xy 189.660034 -33.167543) (xy 189.70124 -33.208007) (xy 189.71895 -33.23082)
			(xy 189.72403 -33.237932) (xy 189.746382 -33.252664) (xy 189.750305 -33.255195) (xy 189.75887 -33.258904)
			(xy 189.7634 -33.26003) (xy 189.78499 -33.264856) (xy 189.794001 -33.26645) (xy 189.812099 -33.263844)
			(xy 189.820296 -33.259776) (xy 189.820804 -33.259522) (xy 189.839186 -33.249297) (xy 189.877475 -33.231871)
			(xy 189.897258 -33.224724) (xy 189.921459 -33.216682) (xy 189.971193 -33.205392) (xy 190.021873 -33.199693)
			(xy 190.047372 -33.199324) (xy 190.072872 -33.199684) (xy 190.123555 -33.205374) (xy 190.17329 -33.216665)
			(xy 190.197486 -33.224724) (xy 190.217271 -33.231867) (xy 190.255562 -33.249289) (xy 190.27394 -33.259522)
			(xy 190.274448 -33.259776) (xy 190.282647 -33.263839) (xy 190.300744 -33.266449) (xy 190.309754 -33.264856)
			(xy 190.331344 -33.26003) (xy 190.335864 -33.258876) (xy 190.344425 -33.255167) (xy 190.348362 -33.252664)
			(xy 190.370714 -33.237932) (xy 190.375794 -33.23082) (xy 190.393919 -33.207556) (xy 190.436131 -33.166375)
			(xy 190.48418 -33.132185) (xy 190.53692 -33.1058) (xy 190.593094 -33.087849) (xy 190.651362 -33.078762)
			(xy 190.680848 -33.078166) (xy 190.681356 -33.078166) (xy 190.708117 -33.078621) (xy 190.761113 -33.086107)
			(xy 190.812543 -33.100924) (xy 190.861399 -33.122782) (xy 190.906721 -33.151252) (xy 190.947621 -33.185775)
			(xy 190.983296 -33.225673) (xy 191.013046 -33.270166) (xy 191.036288 -33.318378) (xy 191.052566 -33.369365)
			(xy 191.05753 -33.395666) (xy 191.059054 -33.40481) (xy 191.06769 -33.42005) (xy 191.074548 -33.425892)
			(xy 191.081595 -33.431395) (xy 191.098379 -33.437521) (xy 191.107314 -33.43783) (xy 200.867518 -33.43783)
			(xy 200.87389 -33.437596) (xy 200.886223 -33.434379) (xy 200.891902 -33.43148) (xy 200.923144 -33.414462)
			(xy 200.926446 -33.409382) (xy 200.929748 -33.404302) (xy 200.930002 -33.404048) (xy 200.947064 -33.37942)
			(xy 200.986586 -33.334392) (xy 201.031645 -33.294905) (xy 201.08147 -33.261634) (xy 201.135211 -33.235148)
			(xy 201.191947 -33.215899) (xy 201.250709 -33.204216) (xy 201.310494 -33.2003) (xy 201.370279 -33.204216)
			(xy 201.429041 -33.215899) (xy 201.485777 -33.235148) (xy 201.539518 -33.261634) (xy 201.589343 -33.294905)
			(xy 201.634402 -33.334392) (xy 201.673924 -33.37942) (xy 201.690986 -33.404048) (xy 201.69124 -33.404302)
			(xy 201.694542 -33.409382) (xy 201.697844 -33.414462) (xy 201.729086 -33.43148) (xy 201.734751 -33.434413)
			(xy 201.747094 -33.437624) (xy 201.75347 -33.43783) (xy 214.987378 -33.43783) (xy 214.996296 -33.437431)
			(xy 215.01305 -33.431312) (xy 215.020144 -33.425892) (xy 215.027002 -33.42005) (xy 215.035638 -33.40481)
			(xy 215.037162 -33.395666) (xy 215.042094 -33.369355) (xy 215.058356 -33.318356) (xy 215.08159 -33.270131)
			(xy 215.111338 -33.225628) (xy 215.147015 -33.185721) (xy 215.187922 -33.151195) (xy 215.233255 -33.122727)
			(xy 215.282122 -33.100877) (xy 215.333564 -33.086074) (xy 215.386571 -33.078608) (xy 215.413336 -33.078166)
			(xy 215.42121 -33.078166) (xy 215.450068 -33.079273) (xy 215.506973 -33.089114) (xy 215.561744 -33.107419)
			(xy 215.613131 -33.133769) (xy 215.65996 -33.167564) (xy 215.70116 -33.20803) (xy 215.718898 -33.23082)
			(xy 215.723978 -33.237932) (xy 215.74633 -33.252664) (xy 215.750254 -33.255191) (xy 215.758821 -33.258893)
			(xy 215.763348 -33.26003) (xy 215.784938 -33.264856) (xy 215.79395 -33.266459) (xy 215.812058 -33.263869)
			(xy 215.820244 -33.259776) (xy 215.820752 -33.259522) (xy 215.839133 -33.249295) (xy 215.87742 -33.231865)
			(xy 215.897206 -33.224724) (xy 215.921406 -33.216679) (xy 215.97114 -33.205384) (xy 216.02182 -33.199679)
			(xy 216.04732 -33.199324) (xy 216.07282 -33.199686) (xy 216.123501 -33.205382) (xy 216.173234 -33.216677)
			(xy 216.197434 -33.224724) (xy 216.217218 -33.231869) (xy 216.255507 -33.249295) (xy 216.273888 -33.259522)
			(xy 216.274396 -33.259776) (xy 216.282596 -33.26383) (xy 216.300689 -33.266424) (xy 216.309702 -33.264856)
			(xy 216.331292 -33.26003) (xy 216.335814 -33.25888) (xy 216.344379 -33.255178) (xy 216.34831 -33.252664)
			(xy 216.370662 -33.237932) (xy 216.375742 -33.23082) (xy 216.393866 -33.207553) (xy 216.436076 -33.166367)
			(xy 216.484124 -33.132169) (xy 216.536865 -33.105777) (xy 216.593039 -33.08782) (xy 216.651309 -33.078724)
			(xy 216.680796 -33.078166) (xy 216.681304 -33.078166) (xy 216.708063 -33.078624) (xy 216.761054 -33.086115)
			(xy 216.812479 -33.100937) (xy 216.861329 -33.122798) (xy 216.906646 -33.151269) (xy 216.94754 -33.185793)
			(xy 216.98321 -33.225691) (xy 217.012955 -33.270181) (xy 217.036194 -33.318391) (xy 217.052468 -33.369375)
			(xy 217.057478 -33.395666) (xy 217.059002 -33.40481) (xy 217.067638 -33.42005) (xy 217.074496 -33.425892)
			(xy 217.081545 -33.431387) (xy 217.09833 -33.437498) (xy 217.107262 -33.43783) (xy 238.967518 -33.43783)
			(xy 238.97389 -33.437596) (xy 238.986223 -33.434379) (xy 238.991902 -33.43148) (xy 239.023144 -33.414462)
			(xy 239.026446 -33.409382) (xy 239.029748 -33.404302) (xy 239.030002 -33.404048) (xy 239.047064 -33.37942)
			(xy 239.086586 -33.334392) (xy 239.131645 -33.294905) (xy 239.18147 -33.261634) (xy 239.235211 -33.235148)
			(xy 239.291947 -33.215899) (xy 239.350709 -33.204216) (xy 239.410494 -33.2003) (xy 239.470279 -33.204216)
			(xy 239.529041 -33.215899) (xy 239.585777 -33.235148) (xy 239.639518 -33.261634) (xy 239.689343 -33.294905)
			(xy 239.734402 -33.334392) (xy 239.773924 -33.37942) (xy 239.790986 -33.404048) (xy 239.79124 -33.404302)
			(xy 239.794542 -33.409382) (xy 239.797844 -33.414462) (xy 239.829086 -33.43148) (xy 239.834751 -33.434413)
			(xy 239.847094 -33.437624) (xy 239.85347 -33.43783) (xy 253.087378 -33.43783) (xy 253.096296 -33.437431)
			(xy 253.11305 -33.431312) (xy 253.120144 -33.425892) (xy 253.127002 -33.42005) (xy 253.135638 -33.40481)
			(xy 253.137162 -33.395666) (xy 253.142094 -33.369355) (xy 253.158356 -33.318356) (xy 253.18159 -33.270131)
			(xy 253.211338 -33.225628) (xy 253.247015 -33.185721) (xy 253.287922 -33.151195) (xy 253.333255 -33.122727)
			(xy 253.382122 -33.100877) (xy 253.433564 -33.086074) (xy 253.486571 -33.078608) (xy 253.513336 -33.078166)
			(xy 253.52121 -33.078166) (xy 253.550068 -33.079273) (xy 253.606973 -33.089114) (xy 253.661744 -33.107419)
			(xy 253.713131 -33.133769) (xy 253.75996 -33.167564) (xy 253.80116 -33.20803) (xy 253.818898 -33.23082)
			(xy 253.823978 -33.237932) (xy 253.84633 -33.252664) (xy 253.850254 -33.255191) (xy 253.858821 -33.258893)
			(xy 253.863348 -33.26003) (xy 253.884938 -33.264856) (xy 253.89395 -33.266459) (xy 253.912058 -33.263869)
			(xy 253.920244 -33.259776) (xy 253.920752 -33.259522) (xy 253.939133 -33.249295) (xy 253.97742 -33.231865)
			(xy 253.997206 -33.224724) (xy 254.021406 -33.216679) (xy 254.07114 -33.205384) (xy 254.12182 -33.199679)
			(xy 254.14732 -33.199324) (xy 254.17282 -33.199686) (xy 254.223501 -33.205382) (xy 254.273234 -33.216677)
			(xy 254.297434 -33.224724) (xy 254.317218 -33.231869) (xy 254.355507 -33.249295) (xy 254.373888 -33.259522)
			(xy 254.374396 -33.259776) (xy 254.382596 -33.26383) (xy 254.400689 -33.266424) (xy 254.409702 -33.264856)
			(xy 254.431292 -33.26003) (xy 254.435814 -33.25888) (xy 254.444379 -33.255178) (xy 254.44831 -33.252664)
			(xy 254.470662 -33.237932) (xy 254.475742 -33.23082) (xy 254.493866 -33.207553) (xy 254.536076 -33.166367)
			(xy 254.584124 -33.132169) (xy 254.636865 -33.105777) (xy 254.693039 -33.08782) (xy 254.751309 -33.078724)
			(xy 254.780796 -33.078166) (xy 254.781304 -33.078166) (xy 254.808063 -33.078624) (xy 254.861054 -33.086115)
			(xy 254.912479 -33.100937) (xy 254.961329 -33.122798) (xy 255.006646 -33.151269) (xy 255.04754 -33.185793)
			(xy 255.08321 -33.225691) (xy 255.112955 -33.270181) (xy 255.136194 -33.318391) (xy 255.152468 -33.369375)
			(xy 255.157478 -33.395666) (xy 255.159002 -33.40481) (xy 255.167638 -33.42005) (xy 255.174496 -33.425892)
			(xy 255.181545 -33.431387) (xy 255.19833 -33.437498) (xy 255.207262 -33.43783) (xy 264.967466 -33.43783)
			(xy 264.973839 -33.437603) (xy 264.986179 -33.434396) (xy 264.99185 -33.43148) (xy 265.023092 -33.414462)
			(xy 265.026394 -33.409382) (xy 265.029696 -33.404302) (xy 265.02995 -33.404048) (xy 265.047012 -33.37942)
			(xy 265.086534 -33.334392) (xy 265.131593 -33.294905) (xy 265.181418 -33.261634) (xy 265.235159 -33.235148)
			(xy 265.291895 -33.215899) (xy 265.350657 -33.204216) (xy 265.410442 -33.2003) (xy 265.470227 -33.204216)
			(xy 265.528989 -33.215899) (xy 265.585725 -33.235148) (xy 265.639466 -33.261634) (xy 265.689291 -33.294905)
			(xy 265.73435 -33.334392) (xy 265.773872 -33.37942) (xy 265.790934 -33.404048) (xy 265.791188 -33.404302)
			(xy 265.79449 -33.409382) (xy 265.797792 -33.414462) (xy 265.829034 -33.43148) (xy 265.8347 -33.434407)
			(xy 265.847043 -33.437607) (xy 265.853418 -33.43783) (xy 279.087326 -33.43783) (xy 279.096247 -33.437439)
			(xy 279.113012 -33.431334) (xy 279.120092 -33.425892) (xy 279.12695 -33.42005) (xy 279.135586 -33.40481)
			(xy 279.13711 -33.395666) (xy 279.142042 -33.369357) (xy 279.158306 -33.31836) (xy 279.18154 -33.270139)
			(xy 279.211289 -33.225639) (xy 279.246967 -33.185737) (xy 279.287874 -33.151215) (xy 279.333207 -33.122753)
			(xy 279.382074 -33.100908) (xy 279.433515 -33.086111) (xy 279.48652 -33.078652) (xy 279.513284 -33.078166)
			(xy 279.521158 -33.078166) (xy 279.550018 -33.079269) (xy 279.606927 -33.089103) (xy 279.661704 -33.107403)
			(xy 279.713097 -33.133749) (xy 279.759931 -33.167541) (xy 279.801138 -33.208006) (xy 279.818846 -33.23082)
			(xy 279.823926 -33.237932) (xy 279.846278 -33.252664) (xy 279.8502 -33.255195) (xy 279.858765 -33.258905)
			(xy 279.863296 -33.26003) (xy 279.884886 -33.264856) (xy 279.893897 -33.266451) (xy 279.911996 -33.263846)
			(xy 279.920192 -33.259776) (xy 279.9207 -33.259522) (xy 279.939082 -33.249296) (xy 279.97737 -33.231871)
			(xy 279.997154 -33.224724) (xy 280.021355 -33.216682) (xy 280.071089 -33.205391) (xy 280.121769 -33.199692)
			(xy 280.147268 -33.199324) (xy 280.172767 -33.199689) (xy 280.223447 -33.205389) (xy 280.273178 -33.21669)
			(xy 280.297382 -33.224724) (xy 280.317165 -33.231871) (xy 280.355452 -33.2493) (xy 280.373836 -33.259522)
			(xy 280.374344 -33.259776) (xy 280.382543 -33.26384) (xy 280.40064 -33.266452) (xy 280.40965 -33.264856)
			(xy 280.43124 -33.26003) (xy 280.435761 -33.258876) (xy 280.444321 -33.255168) (xy 280.448258 -33.252664)
			(xy 280.47061 -33.237932) (xy 280.47569 -33.23082) (xy 280.493815 -33.207556) (xy 280.536027 -33.166374)
			(xy 280.584076 -33.132183) (xy 280.636816 -33.105798) (xy 280.69299 -33.087847) (xy 280.751258 -33.078759)
			(xy 280.780744 -33.078166) (xy 280.781252 -33.078166) (xy 280.808013 -33.07862) (xy 280.86101 -33.086106)
			(xy 280.912441 -33.100923) (xy 280.961296 -33.122781) (xy 281.006619 -33.15125) (xy 281.04752 -33.185773)
			(xy 281.083195 -33.225672) (xy 281.112946 -33.270164) (xy 281.136188 -33.318377) (xy 281.152466 -33.369364)
			(xy 281.157426 -33.395666) (xy 281.15895 -33.40481) (xy 281.167586 -33.42005) (xy 281.174444 -33.425892)
			(xy 281.181491 -33.431395) (xy 281.198275 -33.437523) (xy 281.20721 -33.43783) (xy 290.967414 -33.43783)
			(xy 290.973786 -33.437597) (xy 290.98612 -33.434381) (xy 290.991798 -33.43148) (xy 291.02304 -33.414462)
			(xy 291.026342 -33.409382) (xy 291.029644 -33.404302) (xy 291.029898 -33.404048) (xy 291.04696 -33.37942)
			(xy 291.086482 -33.334392) (xy 291.131541 -33.294905) (xy 291.181366 -33.261634) (xy 291.235107 -33.235148)
			(xy 291.291843 -33.215899) (xy 291.350605 -33.204216) (xy 291.41039 -33.2003) (xy 291.470175 -33.204216)
			(xy 291.528937 -33.215899) (xy 291.585673 -33.235148) (xy 291.639414 -33.261634) (xy 291.689239 -33.294905)
			(xy 291.734298 -33.334392) (xy 291.77382 -33.37942) (xy 291.790882 -33.404048) (xy 291.791136 -33.404302)
			(xy 291.794438 -33.409382) (xy 291.79774 -33.414462) (xy 291.828982 -33.43148) (xy 291.834647 -33.434413)
			(xy 291.84699 -33.437626) (xy 291.853366 -33.43783) (xy 305.087274 -33.43783) (xy 305.096192 -33.437431)
			(xy 305.112947 -33.431314) (xy 305.12004 -33.425892) (xy 305.126898 -33.42005) (xy 305.135534 -33.40481)
			(xy 305.137058 -33.395666) (xy 305.141928 -33.369721) (xy 305.157877 -33.319398) (xy 305.180611 -33.271755)
			(xy 305.209696 -33.2277) (xy 305.244576 -33.188075) (xy 305.284585 -33.153638) (xy 305.32896 -33.125044)
			(xy 305.376853 -33.102841) (xy 305.42735 -33.087452) (xy 305.479486 -33.079171) (xy 305.505866 -33.078166)
			(xy 305.513232 -33.078166) (xy 305.542758 -33.078705) (xy 305.601111 -33.087773) (xy 305.65737 -33.105719)
			(xy 305.710195 -33.132114) (xy 305.758325 -33.16633) (xy 305.800612 -33.207549) (xy 305.818794 -33.23082)
			(xy 305.823874 -33.237932) (xy 305.846226 -33.252664) (xy 305.85015 -33.255192) (xy 305.858717 -33.258894)
			(xy 305.863244 -33.26003) (xy 305.884834 -33.264856) (xy 305.893847 -33.26646) (xy 305.911954 -33.263871)
			(xy 305.92014 -33.259776) (xy 305.920648 -33.259522) (xy 305.939031 -33.249298) (xy 305.97732 -33.231876)
			(xy 305.997102 -33.224724) (xy 306.021302 -33.216679) (xy 306.071036 -33.205383) (xy 306.121716 -33.199678)
			(xy 306.147216 -33.199324) (xy 306.172716 -33.199686) (xy 306.223397 -33.205381) (xy 306.273131 -33.216676)
			(xy 306.29733 -33.224724) (xy 306.317114 -33.231869) (xy 306.355403 -33.249294) (xy 306.373784 -33.259522)
			(xy 306.374292 -33.259776) (xy 306.382492 -33.263831) (xy 306.400586 -33.266426) (xy 306.409598 -33.264856)
			(xy 306.431188 -33.26003) (xy 306.435707 -33.258872) (xy 306.444263 -33.255158) (xy 306.448206 -33.252664)
			(xy 306.470558 -33.237932) (xy 306.475638 -33.23082) (xy 306.493762 -33.207553) (xy 306.535972 -33.166366)
			(xy 306.58402 -33.132168) (xy 306.63676 -33.105776) (xy 306.692935 -33.087817) (xy 306.751204 -33.078721)
			(xy 306.780692 -33.078166) (xy 306.7812 -33.078166) (xy 306.807959 -33.078624) (xy 306.860951 -33.086115)
			(xy 306.912376 -33.100936) (xy 306.961227 -33.122797) (xy 307.006544 -33.151268) (xy 307.047438 -33.185791)
			(xy 307.083108 -33.225689) (xy 307.112855 -33.27018) (xy 307.136093 -33.31839) (xy 307.152368 -33.369374)
			(xy 307.157374 -33.395666) (xy 307.158898 -33.40481) (xy 307.167534 -33.42005) (xy 307.174392 -33.425892)
			(xy 307.181441 -33.431388) (xy 307.198226 -33.4375) (xy 307.207158 -33.43783) (xy 316.967362 -33.43783)
			(xy 316.973736 -33.437603) (xy 316.986075 -33.434398) (xy 316.991746 -33.43148) (xy 317.022988 -33.414462)
			(xy 317.02629 -33.409382) (xy 317.029592 -33.404302) (xy 317.029846 -33.404048) (xy 317.046908 -33.37942)
			(xy 317.08643 -33.334392) (xy 317.131489 -33.294905) (xy 317.181314 -33.261634) (xy 317.235055 -33.235148)
			(xy 317.291791 -33.215899) (xy 317.350553 -33.204216) (xy 317.410338 -33.2003) (xy 317.470123 -33.204216)
			(xy 317.528885 -33.215899) (xy 317.585621 -33.235148) (xy 317.639362 -33.261634) (xy 317.689187 -33.294905)
			(xy 317.734246 -33.334392) (xy 317.773768 -33.37942) (xy 317.79083 -33.404048) (xy 317.791084 -33.404302)
			(xy 317.794386 -33.409382) (xy 317.797688 -33.414462) (xy 317.82893 -33.43148) (xy 317.834596 -33.434408)
			(xy 317.846939 -33.437609) (xy 317.853314 -33.43783) (xy 331.087222 -33.43783) (xy 331.096143 -33.43744)
			(xy 331.112909 -33.431335) (xy 331.119988 -33.425892) (xy 331.126846 -33.42005) (xy 331.135482 -33.40481)
			(xy 331.137006 -33.395666) (xy 331.141938 -33.369357) (xy 331.158201 -33.31836) (xy 331.181436 -33.270138)
			(xy 331.211184 -33.225638) (xy 331.246863 -33.185736) (xy 331.28777 -33.151214) (xy 331.333103 -33.12275)
			(xy 331.38197 -33.100905) (xy 331.433411 -33.086108) (xy 331.486416 -33.078648) (xy 331.51318 -33.078166)
			(xy 331.513688 -33.078166) (xy 331.543173 -33.078737) (xy 331.601436 -33.08785) (xy 331.657605 -33.105814)
			(xy 331.710342 -33.132203) (xy 331.758395 -33.166388) (xy 331.800618 -33.207556) (xy 331.818742 -33.23082)
			(xy 331.823822 -33.237932) (xy 331.846174 -33.252664) (xy 331.850096 -33.255195) (xy 331.858661 -33.258906)
			(xy 331.863192 -33.26003) (xy 331.884782 -33.264856) (xy 331.893793 -33.266451) (xy 331.911893 -33.263848)
			(xy 331.920088 -33.259776) (xy 331.920596 -33.259522) (xy 331.938978 -33.249296) (xy 331.977266 -33.23187)
			(xy 331.99705 -33.224724) (xy 332.021251 -33.216682) (xy 332.070985 -33.205391) (xy 332.121665 -33.199691)
			(xy 332.147164 -33.199324) (xy 332.172663 -33.199689) (xy 332.223343 -33.205389) (xy 332.273075 -33.216689)
			(xy 332.297278 -33.224724) (xy 332.317061 -33.231871) (xy 332.355348 -33.2493) (xy 332.373732 -33.259522)
			(xy 332.37424 -33.259776) (xy 332.382439 -33.26384) (xy 332.400537 -33.266454) (xy 332.409546 -33.264856)
			(xy 332.431136 -33.26003) (xy 332.435657 -33.258876) (xy 332.444218 -33.255169) (xy 332.448154 -33.252664)
			(xy 332.470506 -33.237932) (xy 332.475586 -33.23082) (xy 332.493711 -33.207555) (xy 332.535923 -33.166374)
			(xy 332.583972 -33.132182) (xy 332.636712 -33.105796) (xy 332.692886 -33.087845) (xy 332.751154 -33.078756)
			(xy 332.78064 -33.078166) (xy 332.781148 -33.078166) (xy 332.807909 -33.07862) (xy 332.860906 -33.086105)
			(xy 332.912338 -33.100922) (xy 332.961194 -33.122779) (xy 333.006517 -33.151249) (xy 333.047418 -33.185772)
			(xy 333.083094 -33.225671) (xy 333.112845 -33.270163) (xy 333.136087 -33.318376) (xy 333.152365 -33.369363)
			(xy 333.157322 -33.395666) (xy 333.158846 -33.40481) (xy 333.167482 -33.42005) (xy 333.17434 -33.425892)
			(xy 333.181386 -33.431396) (xy 333.198171 -33.437525) (xy 333.207106 -33.43783) (xy 355.067616 -33.43783)
			(xy 355.073988 -33.437596) (xy 355.086321 -33.43438) (xy 355.092 -33.43148) (xy 355.123242 -33.414462)
			(xy 355.126544 -33.409382) (xy 355.129846 -33.404302) (xy 355.1301 -33.404048) (xy 355.147162 -33.37942)
			(xy 355.186684 -33.334392) (xy 355.231743 -33.294905) (xy 355.281568 -33.261634) (xy 355.335309 -33.235148)
			(xy 355.392045 -33.215899) (xy 355.450807 -33.204216) (xy 355.510592 -33.2003) (xy 355.570377 -33.204216)
			(xy 355.629139 -33.215899) (xy 355.685875 -33.235148) (xy 355.739616 -33.261634) (xy 355.789441 -33.294905)
			(xy 355.8345 -33.334392) (xy 355.874022 -33.37942) (xy 355.891084 -33.404048) (xy 355.891338 -33.404302)
			(xy 355.89464 -33.409382) (xy 355.897942 -33.414462) (xy 355.929184 -33.43148) (xy 355.934849 -33.434413)
			(xy 355.947192 -33.437625) (xy 355.953568 -33.43783) (xy 369.187476 -33.43783) (xy 369.196394 -33.437431)
			(xy 369.213148 -33.431313) (xy 369.220242 -33.425892) (xy 369.2271 -33.42005) (xy 369.235736 -33.40481)
			(xy 369.23726 -33.395666) (xy 369.242192 -33.369355) (xy 369.258454 -33.318356) (xy 369.281688 -33.27013)
			(xy 369.311435 -33.225627) (xy 369.347113 -33.18572) (xy 369.38802 -33.151194) (xy 369.433352 -33.122726)
			(xy 369.48222 -33.100875) (xy 369.533662 -33.086072) (xy 369.586669 -33.078606) (xy 369.613434 -33.078166)
			(xy 369.613942 -33.078166) (xy 369.643425 -33.078741) (xy 369.701684 -33.087861) (xy 369.757847 -33.105831)
			(xy 369.810578 -33.132224) (xy 369.858624 -33.166412) (xy 369.900841 -33.207582) (xy 369.918996 -33.23082)
			(xy 369.924076 -33.237932) (xy 369.946428 -33.252664) (xy 369.950352 -33.255191) (xy 369.958919 -33.258893)
			(xy 369.963446 -33.26003) (xy 369.985036 -33.264856) (xy 369.994049 -33.26646) (xy 370.012156 -33.26387)
			(xy 370.020342 -33.259776) (xy 370.02085 -33.259522) (xy 370.039231 -33.249295) (xy 370.077518 -33.231865)
			(xy 370.097304 -33.224724) (xy 370.121504 -33.216679) (xy 370.171238 -33.205383) (xy 370.221918 -33.199679)
			(xy 370.247418 -33.199324) (xy 370.272918 -33.199686) (xy 370.323599 -33.205381) (xy 370.373332 -33.216677)
			(xy 370.397532 -33.224724) (xy 370.417316 -33.231869) (xy 370.455605 -33.249295) (xy 370.473986 -33.259522)
			(xy 370.474494 -33.259776) (xy 370.482694 -33.263831) (xy 370.500787 -33.266425) (xy 370.5098 -33.264856)
			(xy 370.53139 -33.26003) (xy 370.535909 -33.258872) (xy 370.544465 -33.255157) (xy 370.548408 -33.252664)
			(xy 370.57076 -33.237932) (xy 370.57584 -33.23082) (xy 370.593964 -33.207553) (xy 370.636174 -33.166366)
			(xy 370.684222 -33.132169) (xy 370.736962 -33.105777) (xy 370.793137 -33.087818) (xy 370.851407 -33.078723)
			(xy 370.880894 -33.078166) (xy 370.881402 -33.078166) (xy 370.908161 -33.078624) (xy 370.961153 -33.086115)
			(xy 371.012578 -33.100937) (xy 371.061428 -33.122797) (xy 371.106745 -33.151269) (xy 371.147639 -33.185792)
			(xy 371.183309 -33.22569) (xy 371.213055 -33.270181) (xy 371.236293 -33.318391) (xy 371.252568 -33.369374)
			(xy 371.257576 -33.395666) (xy 371.2591 -33.40481) (xy 371.267736 -33.42005) (xy 371.274594 -33.425892)
			(xy 371.281643 -33.431388) (xy 371.298428 -33.437499) (xy 371.30736 -33.43783) (xy 381.067564 -33.43783)
			(xy 381.073938 -33.437603) (xy 381.086277 -33.434397) (xy 381.091948 -33.43148) (xy 381.12319 -33.414462)
			(xy 381.126492 -33.409382) (xy 381.129794 -33.404302) (xy 381.130048 -33.404048) (xy 381.14711 -33.37942)
			(xy 381.186632 -33.334392) (xy 381.231691 -33.294905) (xy 381.281516 -33.261634) (xy 381.335257 -33.235148)
			(xy 381.391993 -33.215899) (xy 381.450755 -33.204216) (xy 381.51054 -33.2003) (xy 381.570325 -33.204216)
			(xy 381.629087 -33.215899) (xy 381.685823 -33.235148) (xy 381.739564 -33.261634) (xy 381.789389 -33.294905)
			(xy 381.834448 -33.334392) (xy 381.87397 -33.37942) (xy 381.891032 -33.404048) (xy 381.891286 -33.404302)
			(xy 381.894588 -33.409382) (xy 381.89789 -33.414462) (xy 381.929132 -33.43148) (xy 381.934798 -33.434408)
			(xy 381.947141 -33.437608) (xy 381.953516 -33.43783) (xy 395.187424 -33.43783) (xy 395.196345 -33.43744)
			(xy 395.213111 -33.431335) (xy 395.22019 -33.425892) (xy 395.227048 -33.42005) (xy 395.235684 -33.40481)
			(xy 395.237208 -33.395666) (xy 395.24214 -33.369357) (xy 395.258404 -33.31836) (xy 395.281638 -33.270138)
			(xy 395.311386 -33.225639) (xy 395.347065 -33.185736) (xy 395.387972 -33.151214) (xy 395.433305 -33.122751)
			(xy 395.482172 -33.100907) (xy 395.533613 -33.086109) (xy 395.586618 -33.07865) (xy 395.613382 -33.078166)
			(xy 395.61389 -33.078166) (xy 395.643375 -33.078737) (xy 395.701638 -33.08785) (xy 395.757806 -33.105815)
			(xy 395.810544 -33.132204) (xy 395.858596 -33.166389) (xy 395.900819 -33.207557) (xy 395.918944 -33.23082)
			(xy 395.924024 -33.237932) (xy 395.946376 -33.252664) (xy 395.950298 -33.255195) (xy 395.958863 -33.258906)
			(xy 395.963394 -33.26003) (xy 395.984984 -33.264856) (xy 395.993995 -33.266451) (xy 396.012094 -33.263847)
			(xy 396.02029 -33.259776) (xy 396.020798 -33.259522) (xy 396.03918 -33.249296) (xy 396.077468 -33.23187)
			(xy 396.097252 -33.224724) (xy 396.121453 -33.216682) (xy 396.171187 -33.205391) (xy 396.221867 -33.199692)
			(xy 396.247366 -33.199324) (xy 396.272865 -33.199689) (xy 396.323545 -33.205389) (xy 396.373277 -33.216689)
			(xy 396.39748 -33.224724) (xy 396.417263 -33.231871) (xy 396.45555 -33.2493) (xy 396.473934 -33.259522)
			(xy 396.474442 -33.259776) (xy 396.482641 -33.26384) (xy 396.500738 -33.266453) (xy 396.509748 -33.264856)
			(xy 396.531338 -33.26003) (xy 396.535859 -33.258876) (xy 396.544419 -33.255168) (xy 396.548356 -33.252664)
			(xy 396.570708 -33.237932) (xy 396.575788 -33.23082) (xy 396.593913 -33.207555) (xy 396.636125 -33.166374)
			(xy 396.684174 -33.132183) (xy 396.736914 -33.105797) (xy 396.793088 -33.087846) (xy 396.851356 -33.078757)
			(xy 396.880842 -33.078166) (xy 396.88135 -33.078166) (xy 396.908111 -33.07862) (xy 396.961108 -33.086106)
			(xy 397.012539 -33.100922) (xy 397.061395 -33.12278) (xy 397.106718 -33.151249) (xy 397.147619 -33.185772)
			(xy 397.183294 -33.225671) (xy 397.213045 -33.270164) (xy 397.236288 -33.318376) (xy 397.252566 -33.369364)
			(xy 397.257524 -33.395666) (xy 397.259048 -33.40481) (xy 397.267684 -33.42005) (xy 397.274542 -33.425892)
			(xy 397.281589 -33.431396) (xy 397.298373 -33.437524) (xy 397.307308 -33.43783) (xy 407.067512 -33.43783)
			(xy 407.073884 -33.437597) (xy 407.086218 -33.434381) (xy 407.091896 -33.43148) (xy 407.123138 -33.414462)
			(xy 407.12644 -33.409382) (xy 407.129742 -33.404302) (xy 407.129996 -33.404048) (xy 407.147058 -33.37942)
			(xy 407.18658 -33.334392) (xy 407.231639 -33.294905) (xy 407.281464 -33.261634) (xy 407.335205 -33.235148)
			(xy 407.391941 -33.215899) (xy 407.450703 -33.204216) (xy 407.510488 -33.2003) (xy 407.570273 -33.204216)
			(xy 407.629035 -33.215899) (xy 407.685771 -33.235148) (xy 407.739512 -33.261634) (xy 407.789337 -33.294905)
			(xy 407.834396 -33.334392) (xy 407.873918 -33.37942) (xy 407.89098 -33.404048) (xy 407.891234 -33.404302)
			(xy 407.894536 -33.409382) (xy 407.897838 -33.414462) (xy 407.92908 -33.43148) (xy 407.934745 -33.434413)
			(xy 407.947088 -33.437627) (xy 407.953464 -33.43783) (xy 421.187372 -33.43783) (xy 421.19629 -33.437432)
			(xy 421.213045 -33.431315) (xy 421.220138 -33.425892) (xy 421.226996 -33.42005) (xy 421.235632 -33.40481)
			(xy 421.237156 -33.395666) (xy 421.242088 -33.369355) (xy 421.25835 -33.318355) (xy 421.281584 -33.27013)
			(xy 421.311331 -33.225626) (xy 421.347009 -33.185719) (xy 421.387916 -33.151192) (xy 421.433248 -33.122724)
			(xy 421.482115 -33.100873) (xy 421.533558 -33.086069) (xy 421.586565 -33.078603) (xy 421.61333 -33.078166)
			(xy 421.613838 -33.078166) (xy 421.643322 -33.078741) (xy 421.70158 -33.08786) (xy 421.757743 -33.10583)
			(xy 421.810475 -33.132223) (xy 421.858522 -33.16641) (xy 421.900739 -33.20758) (xy 421.918892 -33.23082)
			(xy 421.923972 -33.237932) (xy 421.946324 -33.252664) (xy 421.950248 -33.255192) (xy 421.958815 -33.258894)
			(xy 421.963342 -33.26003) (xy 421.984932 -33.264856) (xy 421.993941 -33.266442) (xy 422.012032 -33.263822)
			(xy 422.020238 -33.259776) (xy 422.020746 -33.259522) (xy 422.039129 -33.249298) (xy 422.077418 -33.231876)
			(xy 422.0972 -33.224724) (xy 422.1214 -33.216679) (xy 422.171134 -33.205383) (xy 422.221814 -33.199678)
			(xy 422.247314 -33.199324) (xy 422.272814 -33.199686) (xy 422.323495 -33.205381) (xy 422.373229 -33.216676)
			(xy 422.397428 -33.224724) (xy 422.417212 -33.231869) (xy 422.455501 -33.249294) (xy 422.473882 -33.259522)
			(xy 422.47439 -33.259776) (xy 422.48259 -33.263831) (xy 422.500684 -33.266427) (xy 422.509696 -33.264856)
			(xy 422.531286 -33.26003) (xy 422.535805 -33.258872) (xy 422.544361 -33.255158) (xy 422.548304 -33.252664)
			(xy 422.570656 -33.237932) (xy 422.575736 -33.23082) (xy 422.59386 -33.207553) (xy 422.63607 -33.166366)
			(xy 422.684118 -33.132168) (xy 422.736858 -33.105775) (xy 422.793033 -33.087816) (xy 422.851302 -33.07872)
			(xy 422.88079 -33.078166) (xy 422.881298 -33.078166) (xy 422.908057 -33.078623) (xy 422.961049 -33.086114)
			(xy 423.012475 -33.100935) (xy 423.061325 -33.122796) (xy 423.106642 -33.151267) (xy 423.147537 -33.18579)
			(xy 423.183208 -33.225689) (xy 423.212954 -33.270179) (xy 423.236193 -33.31839) (xy 423.252468 -33.369374)
			(xy 423.257472 -33.395666) (xy 423.258996 -33.40481) (xy 423.267632 -33.42005) (xy 423.27449 -33.425892)
			(xy 423.281539 -33.431388) (xy 423.298323 -33.437501) (xy 423.307256 -33.43783) (xy 433.06746 -33.43783)
			(xy 433.073834 -33.437603) (xy 433.086174 -33.434398) (xy 433.091844 -33.43148) (xy 433.123086 -33.414462)
			(xy 433.126388 -33.409382) (xy 433.12969 -33.404302) (xy 433.129944 -33.404048) (xy 433.147006 -33.37942)
			(xy 433.186528 -33.334392) (xy 433.231587 -33.294905) (xy 433.281412 -33.261634) (xy 433.335153 -33.235148)
			(xy 433.391889 -33.215899) (xy 433.450651 -33.204216) (xy 433.510436 -33.2003) (xy 433.570221 -33.204216)
			(xy 433.628983 -33.215899) (xy 433.685719 -33.235148) (xy 433.73946 -33.261634) (xy 433.789285 -33.294905)
			(xy 433.834344 -33.334392) (xy 433.873866 -33.37942) (xy 433.890928 -33.404048) (xy 433.891182 -33.404302)
			(xy 433.894484 -33.409382) (xy 433.897786 -33.414462) (xy 433.929028 -33.43148) (xy 433.934694 -33.434408)
			(xy 433.947037 -33.43761) (xy 433.953412 -33.43783) (xy 447.18732 -33.43783) (xy 447.196241 -33.43744)
			(xy 447.213008 -33.431336) (xy 447.220086 -33.425892) (xy 447.226944 -33.42005) (xy 447.23558 -33.40481)
			(xy 447.237104 -33.395666) (xy 447.242036 -33.369357) (xy 447.258299 -33.31836) (xy 447.281534 -33.270138)
			(xy 447.311282 -33.225638) (xy 447.346961 -33.185735) (xy 447.387868 -33.151213) (xy 447.4332 -33.122749)
			(xy 447.482067 -33.100904) (xy 447.533509 -33.086106) (xy 447.586514 -33.078647) (xy 447.613278 -33.078166)
			(xy 447.613786 -33.078166) (xy 447.643271 -33.078737) (xy 447.701535 -33.087849) (xy 447.757703 -33.105814)
			(xy 447.810441 -33.132202) (xy 447.858494 -33.166387) (xy 447.900717 -33.207555) (xy 447.91884 -33.23082)
			(xy 447.92392 -33.237932) (xy 447.946272 -33.252664) (xy 447.950194 -33.255196) (xy 447.958759 -33.258907)
			(xy 447.96329 -33.26003) (xy 447.98488 -33.264856) (xy 447.993891 -33.266452) (xy 448.011991 -33.263849)
			(xy 448.020186 -33.259776) (xy 448.020694 -33.259522) (xy 448.039076 -33.249296) (xy 448.077364 -33.23187)
			(xy 448.097148 -33.224724) (xy 448.121349 -33.216682) (xy 448.171083 -33.20539) (xy 448.221763 -33.199691)
			(xy 448.247262 -33.199324) (xy 448.272761 -33.199689) (xy 448.323441 -33.205388) (xy 448.373173 -33.216688)
			(xy 448.397376 -33.224724) (xy 448.417159 -33.231871) (xy 448.455446 -33.249299) (xy 448.47383 -33.259522)
			(xy 448.474338 -33.259776) (xy 448.482537 -33.263841) (xy 448.500635 -33.266455) (xy 448.509644 -33.264856)
			(xy 448.531234 -33.26003) (xy 448.535755 -33.258876) (xy 448.544316 -33.255169) (xy 448.548252 -33.252664)
			(xy 448.570604 -33.237932) (xy 448.575684 -33.23082) (xy 448.593809 -33.207555) (xy 448.63602 -33.166373)
			(xy 448.684069 -33.132182) (xy 448.73681 -33.105795) (xy 448.792984 -33.087844) (xy 448.851252 -33.078755)
			(xy 448.880738 -33.078166) (xy 448.881246 -33.078166) (xy 448.908007 -33.07862) (xy 448.961005 -33.086105)
			(xy 449.012436 -33.100921) (xy 449.061293 -33.122779) (xy 449.106616 -33.151248) (xy 449.147517 -33.185771)
			(xy 449.183193 -33.22567) (xy 449.212944 -33.270162) (xy 449.236187 -33.318375) (xy 449.252465 -33.369363)
			(xy 449.25742 -33.395666) (xy 449.258944 -33.40481) (xy 449.26758 -33.42005) (xy 449.274438 -33.425892)
			(xy 449.281484 -33.431396) (xy 449.298269 -33.437526) (xy 449.307204 -33.43783) (xy 449.438522 -33.43783)
			(xy 449.448174 -33.436814) (xy 449.455418 -33.435185) (xy 449.468587 -33.428344) (xy 449.474082 -33.423352)
			(xy 450.843142 -32.054292) (xy 450.848128 -32.048792) (xy 450.854971 -32.035626) (xy 450.856604 -32.028384)
			(xy 450.85762 -32.018732) (xy 450.85762 -28.829508) (xy 450.857136 -28.820067) (xy 450.850235 -28.802487)
			(xy 450.837467 -28.788571) (xy 450.829172 -28.784042) (xy 450.742812 -28.74518) (xy 450.735999 -28.742394)
			(xy 450.721414 -28.740462) (xy 450.71411 -28.74137) (xy 450.707252 -28.74264) (xy 450.694298 -28.748482)
			(xy 450.688456 -28.753816) (xy 450.667367 -28.771942) (xy 450.620928 -28.80253) (xy 450.570543 -28.826059)
			(xy 450.517278 -28.842029) (xy 450.46226 -28.850104) (xy 450.434456 -28.85059) (xy 450.407208 -28.850101)
			(xy 450.353268 -28.84234) (xy 450.300981 -28.826981) (xy 450.251412 -28.804339) (xy 450.205569 -28.774873)
			(xy 450.164386 -28.739183) (xy 450.128701 -28.697996) (xy 450.09924 -28.65215) (xy 450.076603 -28.602578)
			(xy 450.061251 -28.550289) (xy 450.053496 -28.496348) (xy 450.053496 -28.441852) (xy 450.061251 -28.387911)
			(xy 450.076603 -28.335622) (xy 450.09924 -28.28605) (xy 450.128701 -28.240204) (xy 450.164386 -28.199017)
			(xy 450.205569 -28.163327) (xy 450.251412 -28.133861) (xy 450.300981 -28.111219) (xy 450.353268 -28.09586)
			(xy 450.407208 -28.088099) (xy 450.434456 -28.087574) (xy 450.434456 -28.08732) (xy 450.462295 -28.087823)
			(xy 450.517382 -28.09591) (xy 450.570708 -28.111919) (xy 450.621141 -28.135511) (xy 450.667608 -28.166183)
			(xy 450.68871 -28.184348) (xy 450.688964 -28.184602) (xy 450.69456 -28.189253) (xy 450.707722 -28.195441)
			(xy 450.714872 -28.196794) (xy 450.721476 -28.19781) (xy 450.735954 -28.196032) (xy 450.829172 -28.154122)
			(xy 450.837507 -28.149632) (xy 450.850339 -28.135731) (xy 450.857237 -28.118115) (xy 450.85762 -28.108656)
			(xy 450.85762 -20.868132) (xy 450.857365 -20.860486) (xy 450.852844 -20.845879) (xy 450.84873 -20.83943)
			(xy 450.844666 -20.833588) (xy 450.832982 -20.823936) (xy 450.82587 -20.821142) (xy 450.799858 -20.810036)
			(xy 450.751164 -20.781268) (xy 450.707253 -20.745623) (xy 450.669089 -20.703883) (xy 450.637509 -20.656964)
			(xy 450.613206 -20.605894) (xy 450.596713 -20.551795) (xy 450.588392 -20.495853) (xy 450.587872 -20.467574)
			(xy 450.588354 -20.440092) (xy 450.596252 -20.385698) (xy 450.611879 -20.333002) (xy 450.634911 -20.283096)
			(xy 450.664872 -20.237015) (xy 450.70114 -20.195715) (xy 450.72173 -20.177506) (xy 450.722238 -20.176998)
			(xy 450.730112 -20.17014) (xy 450.73443 -20.16125) (xy 450.736722 -20.156403) (xy 450.739413 -20.146026)
			(xy 450.739764 -20.140676) (xy 450.742558 -20.062698) (xy 450.741895 -20.053061) (xy 450.734316 -20.03531)
			(xy 450.727826 -20.028154) (xy 450.228462 -19.52879) (xy 450.221066 -19.52194) (xy 450.202467 -19.514205)
			(xy 450.192394 -19.513804) (xy 449.358512 -19.513804) (xy 449.331334 -19.534632) (xy 449.32727 -19.550126)
			(xy 449.319676 -19.576931) (xy 449.297788 -19.628162) (xy 449.268688 -19.67567) (xy 449.232995 -19.718445)
			(xy 449.191466 -19.75558) (xy 449.144982 -19.786288) (xy 449.094529 -19.809915) (xy 449.041179 -19.825961)
			(xy 448.986063 -19.834086) (xy 448.958208 -19.834606) (xy 448.931345 -19.834148) (xy 448.878149 -19.826612)
			(xy 448.826538 -19.811686) (xy 448.77753 -19.789667) (xy 448.732097 -19.76099) (xy 448.691137 -19.726223)
			(xy 448.655459 -19.686053) (xy 448.62577 -19.641274) (xy 448.602657 -19.592773) (xy 448.586578 -19.541509)
			(xy 448.58178 -19.515074) (xy 448.579937 -19.506426) (xy 448.571258 -19.491037) (xy 448.55788 -19.479496)
			(xy 448.549776 -19.475958) (xy 448.520955 -19.464583) (xy 448.465671 -19.436598) (xy 448.413647 -19.402938)
			(xy 448.365464 -19.363979) (xy 448.343274 -19.342354) (xy 448.164712 -19.163538) (xy 448.157316 -19.156686)
			(xy 448.138718 -19.148941) (xy 448.128644 -19.148552) (xy 443.172088 -19.148552) (xy 443.163745 -19.148847)
			(xy 443.147935 -19.154171) (xy 443.1411 -19.158966) (xy 443.13475 -19.163792) (xy 443.125606 -19.177508)
			(xy 443.12332 -19.186144) (xy 443.114566 -19.215777) (xy 443.088822 -19.271945) (xy 443.054367 -19.323232)
			(xy 443.033658 -19.346164) (xy 443.027054 -19.353276) (xy 443.023752 -19.361658) (xy 443.021993 -19.366224)
			(xy 443.020065 -19.375817) (xy 443.019942 -19.380708) (xy 443.019942 -19.450304) (xy 443.020084 -19.455193)
			(xy 443.022013 -19.464782) (xy 443.023752 -19.469354) (xy 443.027054 -19.477736) (xy 443.033658 -19.484848)
			(xy 443.052929 -19.506174) (xy 443.085495 -19.553536) (xy 443.110587 -19.605248) (xy 443.127637 -19.660138)
			(xy 443.136259 -19.716966) (xy 443.136259 -19.774443) (xy 443.127635 -19.83127) (xy 443.110584 -19.88616)
			(xy 443.085491 -19.937871) (xy 443.052924 -19.985232) (xy 443.033658 -20.006564) (xy 443.027054 -20.013676)
			(xy 443.023752 -20.022058) (xy 443.021993 -20.026624) (xy 443.020065 -20.036217) (xy 443.019942 -20.041108)
			(xy 443.019942 -20.110704) (xy 443.020084 -20.115593) (xy 443.022013 -20.125182) (xy 443.023752 -20.129754)
			(xy 443.027054 -20.138136) (xy 443.033658 -20.145248) (xy 443.052929 -20.166574) (xy 443.085495 -20.213936)
			(xy 443.110587 -20.265648) (xy 443.127637 -20.320538) (xy 443.136259 -20.377366) (xy 443.136259 -20.434843)
			(xy 443.127635 -20.49167) (xy 443.110584 -20.54656) (xy 443.085491 -20.598271) (xy 443.052924 -20.645632)
			(xy 443.033658 -20.666964) (xy 443.027054 -20.674076) (xy 443.023752 -20.682458) (xy 443.021993 -20.687024)
			(xy 443.020065 -20.696617) (xy 443.019942 -20.701508) (xy 443.019942 -20.771104) (xy 443.020084 -20.775993)
			(xy 443.022013 -20.785582) (xy 443.023752 -20.790154) (xy 443.027054 -20.798536) (xy 443.033658 -20.805648)
			(xy 443.052929 -20.826974) (xy 443.085495 -20.874336) (xy 443.110587 -20.926048) (xy 443.127637 -20.980938)
			(xy 443.136259 -21.037766) (xy 443.136259 -21.095243) (xy 443.127635 -21.15207) (xy 443.110584 -21.20696)
			(xy 443.085491 -21.258671) (xy 443.052924 -21.306032) (xy 443.033658 -21.327364) (xy 443.027054 -21.334476)
			(xy 443.023752 -21.342858) (xy 443.021993 -21.347424) (xy 443.020065 -21.357017) (xy 443.019942 -21.361908)
			(xy 443.019942 -21.431504) (xy 443.020084 -21.436393) (xy 443.022013 -21.445982) (xy 443.023752 -21.450554)
			(xy 443.027054 -21.458936) (xy 443.033658 -21.466048) (xy 443.052925 -21.487377) (xy 443.085482 -21.534741)
			(xy 443.110568 -21.586453) (xy 443.127613 -21.641343) (xy 443.136233 -21.698168) (xy 443.136782 -21.726906)
			(xy 443.136296 -21.754157) (xy 443.12854 -21.808105) (xy 443.113185 -21.8604) (xy 443.090543 -21.909977)
			(xy 443.061077 -21.955827) (xy 443.025386 -21.997018) (xy 442.984195 -22.032709) (xy 442.938345 -22.062175)
			(xy 442.888768 -22.084817) (xy 442.836473 -22.100172) (xy 442.782525 -22.107928) (xy 442.728023 -22.107928)
			(xy 442.674075 -22.100172) (xy 442.62178 -22.084817) (xy 442.572203 -22.062175) (xy 442.526353 -22.032709)
			(xy 442.485162 -21.997018) (xy 442.449471 -21.955827) (xy 442.420005 -21.909977) (xy 442.397363 -21.8604)
			(xy 442.382008 -21.808105) (xy 442.374252 -21.754157) (xy 442.373766 -21.726906) (xy 442.374287 -21.698167)
			(xy 442.38291 -21.64134) (xy 442.399962 -21.58645) (xy 442.425056 -21.53474) (xy 442.457625 -21.487381)
			(xy 442.47689 -21.466048) (xy 442.483494 -21.458936) (xy 442.486796 -21.450554) (xy 442.488555 -21.445988)
			(xy 442.490483 -21.436395) (xy 442.490606 -21.431504) (xy 442.490606 -21.361908) (xy 442.490466 -21.357018)
			(xy 442.488541 -21.347428) (xy 442.486796 -21.342858) (xy 442.483494 -21.334476) (xy 442.47689 -21.327364)
			(xy 442.45762 -21.306036) (xy 442.425057 -21.258673) (xy 442.399967 -21.206961) (xy 442.382918 -21.15207)
			(xy 442.374295 -21.095243) (xy 442.374294 -21.037766) (xy 442.382916 -20.980938) (xy 442.399964 -20.926047)
			(xy 442.425053 -20.874335) (xy 442.457615 -20.82697) (xy 442.47689 -20.805648) (xy 442.483494 -20.798536)
			(xy 442.486796 -20.790154) (xy 442.488555 -20.785588) (xy 442.490483 -20.775995) (xy 442.490606 -20.771104)
			(xy 442.490606 -20.701508) (xy 442.490466 -20.696618) (xy 442.488541 -20.687028) (xy 442.486796 -20.682458)
			(xy 442.483494 -20.674076) (xy 442.47689 -20.666964) (xy 442.45762 -20.645636) (xy 442.425057 -20.598273)
			(xy 442.399967 -20.546561) (xy 442.382918 -20.49167) (xy 442.374295 -20.434843) (xy 442.374294 -20.377366)
			(xy 442.382916 -20.320538) (xy 442.399964 -20.265647) (xy 442.425053 -20.213935) (xy 442.457615 -20.16657)
			(xy 442.47689 -20.145248) (xy 442.483494 -20.138136) (xy 442.486796 -20.129754) (xy 442.488555 -20.125188)
			(xy 442.490483 -20.115595) (xy 442.490606 -20.110704) (xy 442.490606 -20.041108) (xy 442.490466 -20.036218)
			(xy 442.488541 -20.026628) (xy 442.486796 -20.022058) (xy 442.483494 -20.013676) (xy 442.47689 -20.006564)
			(xy 442.45762 -19.985236) (xy 442.425057 -19.937873) (xy 442.399967 -19.886161) (xy 442.382918 -19.83127)
			(xy 442.374295 -19.774443) (xy 442.374294 -19.716966) (xy 442.382916 -19.660138) (xy 442.399964 -19.605247)
			(xy 442.425053 -19.553535) (xy 442.457615 -19.50617) (xy 442.47689 -19.484848) (xy 442.483494 -19.477736)
			(xy 442.486796 -19.469354) (xy 442.488555 -19.464788) (xy 442.490483 -19.455195) (xy 442.490606 -19.450304)
			(xy 442.490606 -19.380708) (xy 442.490466 -19.375818) (xy 442.488541 -19.366228) (xy 442.486796 -19.361658)
			(xy 442.483494 -19.353276) (xy 442.47689 -19.346164) (xy 442.456195 -19.323222) (xy 442.421745 -19.271935)
			(xy 442.396006 -19.215769) (xy 442.387228 -19.186144) (xy 442.387228 -19.18589) (xy 442.38473 -19.177905)
			(xy 442.375397 -19.164033) (xy 442.36894 -19.158712) (xy 442.36259 -19.153886) (xy 442.347096 -19.148552)
			(xy 438.517792 -19.148552) (xy 438.509213 -19.148848) (xy 438.492995 -19.154439) (xy 438.486042 -19.159474)
			(xy 438.473088 -19.169888) (xy 438.470548 -19.17954) (xy 438.46877 -19.187414) (xy 438.461568 -19.214706)
			(xy 438.440222 -19.266956) (xy 438.411411 -19.315491) (xy 438.375763 -19.359252) (xy 438.334057 -19.397283)
			(xy 438.287203 -19.428755) (xy 438.236224 -19.45298) (xy 438.182232 -19.46943) (xy 438.126405 -19.477746)
			(xy 438.069963 -19.477746) (xy 438.014136 -19.46943) (xy 437.960144 -19.45298) (xy 437.909165 -19.428755)
			(xy 437.862311 -19.397283) (xy 437.820605 -19.359252) (xy 437.784957 -19.315491) (xy 437.756146 -19.266956)
			(xy 437.7348 -19.214706) (xy 437.727598 -19.187414) (xy 437.727598 -19.186906) (xy 437.727344 -19.186652)
			(xy 437.725032 -19.178669) (xy 437.716095 -19.164667) (xy 437.709818 -19.15922) (xy 437.70296 -19.153886)
			(xy 437.687212 -19.148298) (xy 435.29504 -19.148298) (xy 435.285771 -19.148688) (xy 435.268449 -19.155285)
			(xy 435.254643 -19.167653) (xy 435.250082 -19.17573) (xy 435.210458 -19.262344) (xy 435.207747 -19.269111)
			(xy 435.205803 -19.283552) (xy 435.206648 -19.290792) (xy 435.20868 -19.305524) (xy 435.251361 -19.35416)
			(xy 435.33143 -19.455828) (xy 435.40519 -19.562163) (xy 435.472368 -19.672774) (xy 435.532718 -19.787253)
			(xy 435.586017 -19.905179) (xy 435.632071 -20.02612) (xy 435.670708 -20.14963) (xy 435.701788 -20.275254)
			(xy 435.725196 -20.402532) (xy 435.740845 -20.530995) (xy 435.748679 -20.66017) (xy 435.749192 -20.724876)
			(xy 435.749192 -20.72513) (xy 435.748686 -20.790866) (xy 435.740593 -20.922087) (xy 435.724436 -21.052562)
			(xy 435.700279 -21.181795) (xy 435.668211 -21.309295) (xy 435.628355 -21.434579) (xy 435.580862 -21.557173)
			(xy 435.525913 -21.67661) (xy 435.463714 -21.792437) (xy 435.394504 -21.904216) (xy 435.318543 -22.011523)
			(xy 435.236121 -22.113949) (xy 435.147549 -22.211108) (xy 435.053164 -22.302629) (xy 434.953325 -22.388167)
			(xy 434.848408 -22.467396) (xy 434.738814 -22.540016) (xy 434.624956 -22.605751) (xy 434.507268 -22.664353)
			(xy 434.386196 -22.715599) (xy 434.262198 -22.759294) (xy 434.135746 -22.795273) (xy 434.007318 -22.823399)
			(xy 433.877403 -22.843565) (xy 433.746493 -22.855696) (xy 433.615084 -22.859745) (xy 433.483675 -22.855696)
			(xy 433.352765 -22.843565) (xy 433.22285 -22.823399) (xy 433.094422 -22.795273) (xy 432.96797 -22.759294)
			(xy 432.843972 -22.715599) (xy 432.7229 -22.664353) (xy 432.605212 -22.605751) (xy 432.491354 -22.540016)
			(xy 432.38176 -22.467396) (xy 432.276843 -22.388167) (xy 432.177004 -22.302629) (xy 432.082619 -22.211108)
			(xy 431.994047 -22.113949) (xy 431.911625 -22.011523) (xy 431.835664 -21.904216) (xy 431.766454 -21.792437)
			(xy 431.704255 -21.67661) (xy 431.649306 -21.557173) (xy 431.601813 -21.434579) (xy 431.561957 -21.309295)
			(xy 431.529889 -21.181795) (xy 431.505732 -21.052562) (xy 431.489575 -20.922087) (xy 431.481482 -20.790866)
			(xy 431.480976 -20.72513) (xy 431.481484 -20.67433) (xy 431.48123 -20.67433) (xy 431.483179 -20.611914)
			(xy 431.493466 -20.487449) (xy 431.511012 -20.363798) (xy 431.535756 -20.241385) (xy 431.567614 -20.120627)
			(xy 431.606476 -20.001938) (xy 431.652211 -19.885724) (xy 431.704661 -19.772382) (xy 431.763648 -19.6623)
			(xy 431.828969 -19.555855) (xy 431.9004 -19.453411) (xy 431.938684 -19.404076) (xy 431.938938 -19.403822)
			(xy 431.943236 -19.398122) (xy 431.948776 -19.384971) (xy 431.94986 -19.377914) (xy 431.950622 -19.371056)
			(xy 431.948082 -19.357086) (xy 431.929794 -19.319494) (xy 431.904902 -19.268186) (xy 431.900502 -19.260032)
			(xy 431.88704 -19.247322) (xy 431.869945 -19.240213) (xy 431.860706 -19.239484) (xy 423.697146 -19.239484)
			(xy 423.68708 -19.239916) (xy 423.668488 -19.247643) (xy 423.661078 -19.25447) (xy 423.573194 -19.342354)
			(xy 423.551008 -19.363983) (xy 423.502825 -19.402943) (xy 423.450799 -19.4366) (xy 423.395511 -19.464578)
			(xy 423.366692 -19.475958) (xy 423.358562 -19.47945) (xy 423.345171 -19.490992) (xy 423.336533 -19.506418)
			(xy 423.334688 -19.515074) (xy 423.329588 -19.542892) (xy 423.312263 -19.596727) (xy 423.287181 -19.647414)
			(xy 423.25489 -19.693843) (xy 423.216099 -19.734996) (xy 423.171657 -19.769972) (xy 423.12254 -19.798003)
			(xy 423.069822 -19.818477) (xy 423.014659 -19.830943) (xy 422.95826 -19.835129) (xy 422.901861 -19.830943)
			(xy 422.846698 -19.818477) (xy 422.79398 -19.798003) (xy 422.744863 -19.769972) (xy 422.700421 -19.734996)
			(xy 422.66163 -19.693843) (xy 422.629339 -19.647414) (xy 422.604257 -19.596727) (xy 422.586932 -19.542892)
			(xy 422.581832 -19.515074) (xy 422.579991 -19.506424) (xy 422.571316 -19.491027) (xy 422.557943 -19.479474)
			(xy 422.549828 -19.475958) (xy 422.521009 -19.464581) (xy 422.465727 -19.436592) (xy 422.413707 -19.40293)
			(xy 422.365526 -19.363968) (xy 422.343326 -19.342354) (xy 422.164256 -19.163284) (xy 422.156859 -19.156435)
			(xy 422.13826 -19.148703) (xy 422.128188 -19.148298) (xy 417.172394 -19.148298) (xy 417.164045 -19.148553)
			(xy 417.148224 -19.153884) (xy 417.141406 -19.158712) (xy 417.134802 -19.163792) (xy 417.125658 -19.177508)
			(xy 417.123372 -19.185636) (xy 417.114641 -19.215353) (xy 417.088911 -19.271691) (xy 417.054428 -19.323139)
			(xy 417.03371 -19.346164) (xy 417.027106 -19.353276) (xy 417.023804 -19.361658) (xy 417.022046 -19.366224)
			(xy 417.020121 -19.375817) (xy 417.019994 -19.380708) (xy 417.019994 -19.450304) (xy 417.020136 -19.455194)
			(xy 417.022063 -19.464782) (xy 417.023804 -19.469354) (xy 417.027106 -19.477736) (xy 417.03371 -19.484848)
			(xy 417.052979 -19.506176) (xy 417.08554 -19.553539) (xy 417.110629 -19.60525) (xy 417.127676 -19.66014)
			(xy 417.136297 -19.716966) (xy 417.136297 -19.774443) (xy 417.127674 -19.831268) (xy 417.110626 -19.886158)
			(xy 417.085536 -19.937869) (xy 417.052973 -19.985231) (xy 417.03371 -20.006564) (xy 417.027106 -20.013676)
			(xy 417.023804 -20.022058) (xy 417.022046 -20.026624) (xy 417.020121 -20.036217) (xy 417.019994 -20.041108)
			(xy 417.019994 -20.110704) (xy 417.020136 -20.115594) (xy 417.022063 -20.125182) (xy 417.023804 -20.129754)
			(xy 417.027106 -20.138136) (xy 417.03371 -20.145248) (xy 417.052979 -20.166576) (xy 417.08554 -20.213939)
			(xy 417.110629 -20.26565) (xy 417.127676 -20.32054) (xy 417.136297 -20.377366) (xy 417.136297 -20.434843)
			(xy 417.13133 -20.467574) (xy 424.587414 -20.467574) (xy 424.591485 -20.411952) (xy 424.603611 -20.357515)
			(xy 424.623534 -20.305424) (xy 424.65083 -20.256789) (xy 424.684916 -20.212646) (xy 424.725065 -20.173937)
			(xy 424.770423 -20.141486) (xy 424.820023 -20.115985) (xy 424.872807 -20.097978) (xy 424.92765 -20.087848)
			(xy 424.983384 -20.085811) (xy 425.038821 -20.091911) (xy 425.092778 -20.106017) (xy 425.144107 -20.127829)
			(xy 425.191713 -20.156883) (xy 425.234581 -20.192558) (xy 425.271798 -20.234095) (xy 425.302571 -20.280608)
			(xy 425.326243 -20.331105) (xy 425.342311 -20.384512) (xy 425.350431 -20.439688) (xy 425.35094 -20.467574)
			(xy 425.350431 -20.49546) (xy 425.342311 -20.550636) (xy 425.326243 -20.604043) (xy 425.302571 -20.65454)
			(xy 425.271798 -20.701053) (xy 425.234581 -20.74259) (xy 425.191713 -20.778265) (xy 425.144107 -20.807319)
			(xy 425.092778 -20.829131) (xy 425.038821 -20.843237) (xy 424.983384 -20.849337) (xy 424.92765 -20.8473)
			(xy 424.872807 -20.83717) (xy 424.820023 -20.819163) (xy 424.770423 -20.793662) (xy 424.725065 -20.761211)
			(xy 424.684916 -20.722502) (xy 424.65083 -20.678359) (xy 424.623534 -20.629724) (xy 424.603611 -20.577633)
			(xy 424.591485 -20.523196) (xy 424.587414 -20.467574) (xy 417.13133 -20.467574) (xy 417.127674 -20.491668)
			(xy 417.110626 -20.546558) (xy 417.085536 -20.598269) (xy 417.052973 -20.645631) (xy 417.03371 -20.666964)
			(xy 417.027106 -20.674076) (xy 417.023804 -20.682458) (xy 417.022046 -20.687024) (xy 417.020121 -20.696617)
			(xy 417.019994 -20.701508) (xy 417.019994 -20.771104) (xy 417.020136 -20.775994) (xy 417.022063 -20.785582)
			(xy 417.023804 -20.790154) (xy 417.027106 -20.798536) (xy 417.03371 -20.805648) (xy 417.052979 -20.826976)
			(xy 417.08554 -20.874339) (xy 417.110629 -20.92605) (xy 417.127676 -20.98094) (xy 417.136297 -21.037766)
			(xy 417.136297 -21.095243) (xy 417.127674 -21.152068) (xy 417.110626 -21.206958) (xy 417.085536 -21.258669)
			(xy 417.052973 -21.306031) (xy 417.03371 -21.327364) (xy 417.027106 -21.334476) (xy 417.023804 -21.342858)
			(xy 417.022046 -21.347424) (xy 417.020121 -21.357017) (xy 417.019994 -21.361908) (xy 417.019994 -21.431504)
			(xy 417.020136 -21.436394) (xy 417.022063 -21.445982) (xy 417.023804 -21.450554) (xy 417.027106 -21.458936)
			(xy 417.03371 -21.466048) (xy 417.052979 -21.487376) (xy 417.085541 -21.534739) (xy 417.110629 -21.586451)
			(xy 417.127677 -21.641341) (xy 417.136298 -21.698168) (xy 417.136834 -21.726906) (xy 417.136348 -21.754157)
			(xy 417.133255 -21.775674) (xy 426.235874 -21.775674) (xy 426.239945 -21.720052) (xy 426.252071 -21.665615)
			(xy 426.271994 -21.613524) (xy 426.29929 -21.564889) (xy 426.333376 -21.520746) (xy 426.373525 -21.482037)
			(xy 426.418883 -21.449586) (xy 426.468483 -21.424085) (xy 426.521267 -21.406078) (xy 426.57611 -21.395948)
			(xy 426.631844 -21.393911) (xy 426.687281 -21.400011) (xy 426.741238 -21.414117) (xy 426.792567 -21.435929)
			(xy 426.840173 -21.464983) (xy 426.883041 -21.500658) (xy 426.920258 -21.542195) (xy 426.951031 -21.588708)
			(xy 426.974703 -21.639205) (xy 426.990771 -21.692612) (xy 426.998891 -21.747788) (xy 426.9994 -21.775674)
			(xy 426.998891 -21.80356) (xy 426.99122 -21.855684) (xy 427.13859 -21.855684) (xy 427.142661 -21.800062)
			(xy 427.154787 -21.745625) (xy 427.17471 -21.693534) (xy 427.202006 -21.644899) (xy 427.236092 -21.600756)
			(xy 427.276241 -21.562047) (xy 427.321599 -21.529596) (xy 427.371199 -21.504095) (xy 427.423983 -21.486088)
			(xy 427.478826 -21.475958) (xy 427.53456 -21.473921) (xy 427.589997 -21.480021) (xy 427.643954 -21.494127)
			(xy 427.695283 -21.515939) (xy 427.742889 -21.544993) (xy 427.785757 -21.580668) (xy 427.822974 -21.622205)
			(xy 427.853747 -21.668718) (xy 427.877419 -21.719215) (xy 427.893487 -21.772622) (xy 427.901607 -21.827798)
			(xy 427.901958 -21.847048) (xy 428.372776 -21.847048) (xy 428.376847 -21.791426) (xy 428.388973 -21.736989)
			(xy 428.408896 -21.684898) (xy 428.436192 -21.636263) (xy 428.470278 -21.59212) (xy 428.510427 -21.553411)
			(xy 428.555785 -21.52096) (xy 428.605385 -21.495459) (xy 428.658169 -21.477452) (xy 428.713012 -21.467322)
			(xy 428.768746 -21.465285) (xy 428.824183 -21.471385) (xy 428.87814 -21.485491) (xy 428.929469 -21.507303)
			(xy 428.977075 -21.536357) (xy 429.019943 -21.572032) (xy 429.05716 -21.613569) (xy 429.087933 -21.660082)
			(xy 429.111605 -21.710579) (xy 429.127673 -21.763986) (xy 429.135793 -21.819162) (xy 429.136302 -21.847048)
			(xy 429.135793 -21.874934) (xy 429.127673 -21.93011) (xy 429.111605 -21.983517) (xy 429.087933 -22.034014)
			(xy 429.05716 -22.080527) (xy 429.019943 -22.122064) (xy 428.977075 -22.157739) (xy 428.929469 -22.186793)
			(xy 428.87814 -22.208605) (xy 428.824183 -22.222711) (xy 428.768746 -22.228811) (xy 428.713012 -22.226774)
			(xy 428.658169 -22.216644) (xy 428.605385 -22.198637) (xy 428.555785 -22.173136) (xy 428.510427 -22.140685)
			(xy 428.470278 -22.101976) (xy 428.436192 -22.057833) (xy 428.408896 -22.009198) (xy 428.388973 -21.957107)
			(xy 428.376847 -21.90267) (xy 428.372776 -21.847048) (xy 427.901958 -21.847048) (xy 427.902116 -21.855684)
			(xy 427.901607 -21.88357) (xy 427.893487 -21.938746) (xy 427.877419 -21.992153) (xy 427.853747 -22.04265)
			(xy 427.822974 -22.089163) (xy 427.785757 -22.1307) (xy 427.742889 -22.166375) (xy 427.695283 -22.195429)
			(xy 427.643954 -22.217241) (xy 427.589997 -22.231347) (xy 427.53456 -22.237447) (xy 427.478826 -22.23541)
			(xy 427.423983 -22.22528) (xy 427.371199 -22.207273) (xy 427.321599 -22.181772) (xy 427.276241 -22.149321)
			(xy 427.236092 -22.110612) (xy 427.202006 -22.066469) (xy 427.17471 -22.017834) (xy 427.154787 -21.965743)
			(xy 427.142661 -21.911306) (xy 427.13859 -21.855684) (xy 426.99122 -21.855684) (xy 426.990771 -21.858736)
			(xy 426.974703 -21.912143) (xy 426.951031 -21.96264) (xy 426.920258 -22.009153) (xy 426.883041 -22.05069)
			(xy 426.840173 -22.086365) (xy 426.792567 -22.115419) (xy 426.741238 -22.137231) (xy 426.687281 -22.151337)
			(xy 426.631844 -22.157437) (xy 426.57611 -22.1554) (xy 426.521267 -22.14527) (xy 426.468483 -22.127263)
			(xy 426.418883 -22.101762) (xy 426.373525 -22.069311) (xy 426.333376 -22.030602) (xy 426.29929 -21.986459)
			(xy 426.271994 -21.937824) (xy 426.252071 -21.885733) (xy 426.239945 -21.831296) (xy 426.235874 -21.775674)
			(xy 417.133255 -21.775674) (xy 417.128592 -21.808105) (xy 417.113237 -21.8604) (xy 417.090595 -21.909977)
			(xy 417.061129 -21.955827) (xy 417.025438 -21.997018) (xy 416.984247 -22.032709) (xy 416.938397 -22.062175)
			(xy 416.88882 -22.084817) (xy 416.836525 -22.100172) (xy 416.782577 -22.107928) (xy 416.728075 -22.107928)
			(xy 416.674127 -22.100172) (xy 416.621832 -22.084817) (xy 416.572255 -22.062175) (xy 416.526405 -22.032709)
			(xy 416.485214 -21.997018) (xy 416.449523 -21.955827) (xy 416.420057 -21.909977) (xy 416.397415 -21.8604)
			(xy 416.38206 -21.808105) (xy 416.374304 -21.754157) (xy 416.373818 -21.726906) (xy 416.374339 -21.698167)
			(xy 416.382961 -21.641339) (xy 416.400011 -21.586448) (xy 416.425103 -21.534736) (xy 416.457669 -21.487373)
			(xy 416.476942 -21.466048) (xy 416.483546 -21.458936) (xy 416.486848 -21.450554) (xy 416.488608 -21.445988)
			(xy 416.490538 -21.436396) (xy 416.490658 -21.431504) (xy 416.490658 -21.361908) (xy 416.490517 -21.357018)
			(xy 416.488591 -21.347429) (xy 416.486848 -21.342858) (xy 416.483546 -21.334476) (xy 416.476942 -21.327364)
			(xy 416.45767 -21.306038) (xy 416.425102 -21.258675) (xy 416.400009 -21.206963) (xy 416.382957 -21.152072)
			(xy 416.374333 -21.095244) (xy 416.374333 -21.037765) (xy 416.382955 -20.980936) (xy 416.400005 -20.926045)
			(xy 416.425098 -20.874332) (xy 416.457664 -20.826969) (xy 416.476942 -20.805648) (xy 416.483546 -20.798536)
			(xy 416.486848 -20.790154) (xy 416.488608 -20.785588) (xy 416.490538 -20.775996) (xy 416.490658 -20.771104)
			(xy 416.490658 -20.701508) (xy 416.490517 -20.696618) (xy 416.488591 -20.687029) (xy 416.486848 -20.682458)
			(xy 416.483546 -20.674076) (xy 416.476942 -20.666964) (xy 416.45767 -20.645638) (xy 416.425102 -20.598275)
			(xy 416.400009 -20.546563) (xy 416.382957 -20.491672) (xy 416.374333 -20.434844) (xy 416.374333 -20.377365)
			(xy 416.382955 -20.320536) (xy 416.400005 -20.265645) (xy 416.425098 -20.213932) (xy 416.457664 -20.166569)
			(xy 416.476942 -20.145248) (xy 416.483546 -20.138136) (xy 416.486848 -20.129754) (xy 416.488608 -20.125188)
			(xy 416.490538 -20.115596) (xy 416.490658 -20.110704) (xy 416.490658 -20.041108) (xy 416.490517 -20.036218)
			(xy 416.488591 -20.026629) (xy 416.486848 -20.022058) (xy 416.483546 -20.013676) (xy 416.476942 -20.006564)
			(xy 416.45767 -19.985238) (xy 416.425102 -19.937875) (xy 416.400009 -19.886163) (xy 416.382957 -19.831272)
			(xy 416.374333 -19.774444) (xy 416.374333 -19.716965) (xy 416.382955 -19.660136) (xy 416.400005 -19.605245)
			(xy 416.425098 -19.553532) (xy 416.457664 -19.506169) (xy 416.476942 -19.484848) (xy 416.483546 -19.477736)
			(xy 416.486848 -19.469354) (xy 416.488608 -19.464788) (xy 416.490538 -19.455196) (xy 416.490658 -19.450304)
			(xy 416.490658 -19.380708) (xy 416.490517 -19.375818) (xy 416.488591 -19.366229) (xy 416.486848 -19.361658)
			(xy 416.483546 -19.353276) (xy 416.476942 -19.346164) (xy 416.469576 -19.338036) (xy 416.463269 -19.331534)
			(xy 416.447258 -19.323089) (xy 416.438334 -19.321526) (xy 416.408108 -19.317462) (xy 416.398911 -19.316601)
			(xy 416.380927 -19.320757) (xy 416.373056 -19.32559) (xy 416.343981 -19.344578) (xy 416.282196 -19.376286)
			(xy 416.217094 -19.40046) (xy 416.149588 -19.416759) (xy 416.080627 -19.424955) (xy 416.045904 -19.425412)
			(xy 413.070548 -19.425412) (xy 413.037693 -19.424954) (xy 412.972396 -19.417603) (xy 412.908333 -19.402987)
			(xy 412.846309 -19.38129) (xy 412.787104 -19.352786) (xy 412.731463 -19.317832) (xy 412.680085 -19.276868)
			(xy 412.656528 -19.253962) (xy 412.56585 -19.163284) (xy 412.558453 -19.156436) (xy 412.539854 -19.148707)
			(xy 412.529782 -19.148298) (xy 412.518098 -19.148298) (xy 412.50952 -19.148594) (xy 412.493303 -19.154187)
			(xy 412.486348 -19.15922) (xy 412.479998 -19.164554) (xy 412.471108 -19.17827) (xy 412.468822 -19.18716)
			(xy 412.461635 -19.214459) (xy 412.440315 -19.266728) (xy 412.411525 -19.315285) (xy 412.375895 -19.359069)
			(xy 412.334202 -19.397125) (xy 412.287356 -19.428622) (xy 412.23638 -19.452872) (xy 412.182387 -19.469345)
			(xy 412.126557 -19.477683) (xy 412.070107 -19.477703) (xy 412.01427 -19.469404) (xy 411.960266 -19.452967)
			(xy 411.909274 -19.428753) (xy 411.862406 -19.397288) (xy 411.820686 -19.359261) (xy 411.785026 -19.315502)
			(xy 411.756203 -19.266965) (xy 411.734847 -19.214711) (xy 411.72765 -19.187414) (xy 411.72765 -19.186906)
			(xy 411.727396 -19.186652) (xy 411.725082 -19.17867) (xy 411.716139 -19.164675) (xy 411.70987 -19.15922)
			(xy 411.703012 -19.153886) (xy 411.687264 -19.148298) (xy 409.295092 -19.148298) (xy 409.285828 -19.148696)
			(xy 409.268519 -19.155303) (xy 409.254727 -19.167674) (xy 409.250134 -19.17573) (xy 409.21051 -19.262344)
			(xy 409.207801 -19.269111) (xy 409.205859 -19.283552) (xy 409.2067 -19.290792) (xy 409.208732 -19.305524)
			(xy 409.251413 -19.35416) (xy 409.331485 -19.455827) (xy 409.405246 -19.562162) (xy 409.472425 -19.672772)
			(xy 409.532777 -19.78725) (xy 409.586078 -19.905177) (xy 409.632132 -20.026118) (xy 409.67077 -20.149628)
			(xy 409.701851 -20.275253) (xy 409.725259 -20.402531) (xy 409.740909 -20.530994) (xy 409.748743 -20.66017)
			(xy 409.749244 -20.724876) (xy 409.749244 -20.72513) (xy 409.748738 -20.790866) (xy 409.740645 -20.922087)
			(xy 409.724488 -21.052562) (xy 409.700331 -21.181795) (xy 409.668263 -21.309295) (xy 409.628407 -21.434579)
			(xy 409.580914 -21.557173) (xy 409.525965 -21.67661) (xy 409.463766 -21.792437) (xy 409.394556 -21.904216)
			(xy 409.318595 -22.011523) (xy 409.236173 -22.113949) (xy 409.147601 -22.211108) (xy 409.053216 -22.302629)
			(xy 408.953377 -22.388167) (xy 408.84846 -22.467396) (xy 408.738866 -22.540016) (xy 408.712126 -22.555454)
			(xy 425.636434 -22.555454) (xy 425.640505 -22.499832) (xy 425.652631 -22.445395) (xy 425.672554 -22.393304)
			(xy 425.69985 -22.344669) (xy 425.733936 -22.300526) (xy 425.774085 -22.261817) (xy 425.819443 -22.229366)
			(xy 425.869043 -22.203865) (xy 425.921827 -22.185858) (xy 425.97667 -22.175728) (xy 426.032404 -22.173691)
			(xy 426.087841 -22.179791) (xy 426.141798 -22.193897) (xy 426.193127 -22.215709) (xy 426.240733 -22.244763)
			(xy 426.283601 -22.280438) (xy 426.320818 -22.321975) (xy 426.351591 -22.368488) (xy 426.375263 -22.418985)
			(xy 426.391331 -22.472392) (xy 426.399451 -22.527568) (xy 426.39996 -22.555454) (xy 426.399451 -22.58334)
			(xy 426.391331 -22.638516) (xy 426.375263 -22.691923) (xy 426.351591 -22.74242) (xy 426.320818 -22.788933)
			(xy 426.283601 -22.83047) (xy 426.240733 -22.866145) (xy 426.193127 -22.895199) (xy 426.141798 -22.917011)
			(xy 426.087841 -22.931117) (xy 426.032404 -22.937217) (xy 425.97667 -22.93518) (xy 425.921827 -22.92505)
			(xy 425.869043 -22.907043) (xy 425.819443 -22.881542) (xy 425.774085 -22.849091) (xy 425.733936 -22.810382)
			(xy 425.69985 -22.766239) (xy 425.672554 -22.717604) (xy 425.652631 -22.665513) (xy 425.640505 -22.611076)
			(xy 425.636434 -22.555454) (xy 408.712126 -22.555454) (xy 408.625008 -22.605751) (xy 408.50732 -22.664353)
			(xy 408.386248 -22.715599) (xy 408.26225 -22.759294) (xy 408.135798 -22.795273) (xy 408.00737 -22.823399)
			(xy 407.877455 -22.843565) (xy 407.746545 -22.855696) (xy 407.615136 -22.859745) (xy 407.483727 -22.855696)
			(xy 407.352817 -22.843565) (xy 407.222902 -22.823399) (xy 407.094474 -22.795273) (xy 406.968022 -22.759294)
			(xy 406.844024 -22.715599) (xy 406.722952 -22.664353) (xy 406.605264 -22.605751) (xy 406.491406 -22.540016)
			(xy 406.381812 -22.467396) (xy 406.276895 -22.388167) (xy 406.177056 -22.302629) (xy 406.082671 -22.211108)
			(xy 405.994099 -22.113949) (xy 405.911677 -22.011523) (xy 405.835716 -21.904216) (xy 405.766506 -21.792437)
			(xy 405.704307 -21.67661) (xy 405.649358 -21.557173) (xy 405.601865 -21.434579) (xy 405.562009 -21.309295)
			(xy 405.529941 -21.181795) (xy 405.505784 -21.052562) (xy 405.489627 -20.922087) (xy 405.481534 -20.790866)
			(xy 405.481028 -20.72513) (xy 405.481536 -20.67433) (xy 405.481282 -20.67433) (xy 405.483231 -20.611914)
			(xy 405.493518 -20.487449) (xy 405.511063 -20.363798) (xy 405.535807 -20.241384) (xy 405.567664 -20.120625)
			(xy 405.606526 -20.001936) (xy 405.65226 -19.885721) (xy 405.704709 -19.772379) (xy 405.763695 -19.662297)
			(xy 405.829014 -19.555851) (xy 405.900445 -19.453405) (xy 405.938736 -19.404076) (xy 405.93899 -19.403822)
			(xy 405.943285 -19.39812) (xy 405.948819 -19.384969) (xy 405.949912 -19.377914) (xy 405.950674 -19.371056)
			(xy 405.948134 -19.357086) (xy 405.929846 -19.319494) (xy 405.904954 -19.268186) (xy 405.900557 -19.260026)
			(xy 405.887097 -19.247302) (xy 405.870001 -19.240176) (xy 405.860758 -19.239484) (xy 397.428466 -19.239484)
			(xy 397.4211 -19.239992) (xy 397.411519 -19.24183) (xy 397.39466 -19.251616) (xy 397.388334 -19.259042)
			(xy 397.338804 -19.322034) (xy 397.335443 -19.326537) (xy 397.330577 -19.336664) (xy 397.329152 -19.3421)
			(xy 397.326612 -19.353022) (xy 397.32839 -19.360134) (xy 397.329406 -19.364706) (xy 397.334283 -19.386478)
			(xy 397.339504 -19.430789) (xy 397.33982 -19.453098) (xy 397.339334 -19.48035) (xy 397.331578 -19.534298)
			(xy 397.316223 -19.586594) (xy 397.293582 -19.636172) (xy 397.264116 -19.682024) (xy 397.228425 -19.723215)
			(xy 397.187235 -19.758908) (xy 397.141384 -19.788376) (xy 397.091807 -19.811018) (xy 397.039512 -19.826375)
			(xy 396.985564 -19.834133) (xy 396.958312 -19.834606) (xy 396.931277 -19.834137) (xy 396.877748 -19.826506)
			(xy 396.825831 -19.811396) (xy 396.776568 -19.789108) (xy 396.730944 -19.760091) (xy 396.689873 -19.724923)
			(xy 396.654177 -19.68431) (xy 396.624571 -19.639065) (xy 396.601648 -19.590094) (xy 396.585867 -19.538378)
			(xy 396.577545 -19.484952) (xy 396.576804 -19.457924) (xy 396.576804 -19.452844) (xy 396.577325 -19.424698)
			(xy 396.585628 -19.36902) (xy 396.602017 -19.315164) (xy 396.613634 -19.289522) (xy 396.61719 -19.279362)
			(xy 396.621254 -19.26209) (xy 396.61973 -19.249898) (xy 396.613126 -19.227038) (xy 396.611749 -19.222678)
			(xy 396.607652 -19.214505) (xy 396.604998 -19.210782) (xy 396.58925 -19.189446) (xy 396.58671 -19.187668)
			(xy 396.578595 -19.182312) (xy 396.562964 -19.170747) (xy 396.555468 -19.164554) (xy 396.550642 -19.160744)
			(xy 396.526258 -19.1516) (xy 396.521969 -19.150084) (xy 396.513025 -19.14843) (xy 396.508478 -19.148298)
			(xy 391.172446 -19.148298) (xy 391.164094 -19.148545) (xy 391.148263 -19.153863) (xy 391.141458 -19.158712)
			(xy 391.134854 -19.163792) (xy 391.12571 -19.177508) (xy 391.123424 -19.185636) (xy 391.114692 -19.215353)
			(xy 391.088959 -19.271688) (xy 391.054473 -19.323133) (xy 391.033762 -19.346164) (xy 391.027158 -19.353276)
			(xy 391.023856 -19.361658) (xy 391.0221 -19.366225) (xy 391.020176 -19.375817) (xy 391.020046 -19.380708)
			(xy 391.020046 -19.450304) (xy 391.020187 -19.455194) (xy 391.022113 -19.464783) (xy 391.023856 -19.469354)
			(xy 391.027158 -19.477736) (xy 391.033762 -19.484848) (xy 391.053033 -19.506174) (xy 391.085598 -19.553536)
			(xy 391.11069 -19.605248) (xy 391.12774 -19.660138) (xy 391.136362 -19.716966) (xy 391.136362 -19.774443)
			(xy 391.127738 -19.83127) (xy 391.110687 -19.88616) (xy 391.085594 -19.937871) (xy 391.053027 -19.985232)
			(xy 391.033762 -20.006564) (xy 391.027158 -20.013676) (xy 391.023856 -20.022058) (xy 391.0221 -20.026625)
			(xy 391.020176 -20.036217) (xy 391.020046 -20.041108) (xy 391.020046 -20.110704) (xy 391.020187 -20.115594)
			(xy 391.022113 -20.125183) (xy 391.023856 -20.129754) (xy 391.027158 -20.138136) (xy 391.033762 -20.145248)
			(xy 391.053033 -20.166574) (xy 391.085598 -20.213936) (xy 391.11069 -20.265648) (xy 391.12774 -20.320538)
			(xy 391.136362 -20.377366) (xy 391.136362 -20.434843) (xy 391.131395 -20.467574) (xy 398.587466 -20.467574)
			(xy 398.591537 -20.411952) (xy 398.603663 -20.357515) (xy 398.623586 -20.305424) (xy 398.650882 -20.256789)
			(xy 398.684968 -20.212646) (xy 398.725117 -20.173937) (xy 398.770475 -20.141486) (xy 398.820075 -20.115985)
			(xy 398.872859 -20.097978) (xy 398.927702 -20.087848) (xy 398.983436 -20.085811) (xy 399.038873 -20.091911)
			(xy 399.09283 -20.106017) (xy 399.144159 -20.127829) (xy 399.191765 -20.156883) (xy 399.234633 -20.192558)
			(xy 399.27185 -20.234095) (xy 399.302623 -20.280608) (xy 399.326295 -20.331105) (xy 399.342363 -20.384512)
			(xy 399.350483 -20.439688) (xy 399.350992 -20.467574) (xy 399.350483 -20.49546) (xy 399.342363 -20.550636)
			(xy 399.326295 -20.604043) (xy 399.302623 -20.65454) (xy 399.27185 -20.701053) (xy 399.234633 -20.74259)
			(xy 399.191765 -20.778265) (xy 399.144159 -20.807319) (xy 399.09283 -20.829131) (xy 399.038873 -20.843237)
			(xy 398.983436 -20.849337) (xy 398.927702 -20.8473) (xy 398.872859 -20.83717) (xy 398.820075 -20.819163)
			(xy 398.770475 -20.793662) (xy 398.725117 -20.761211) (xy 398.684968 -20.722502) (xy 398.650882 -20.678359)
			(xy 398.623586 -20.629724) (xy 398.603663 -20.577633) (xy 398.591537 -20.523196) (xy 398.587466 -20.467574)
			(xy 391.131395 -20.467574) (xy 391.127738 -20.49167) (xy 391.110687 -20.54656) (xy 391.085594 -20.598271)
			(xy 391.053027 -20.645632) (xy 391.033762 -20.666964) (xy 391.027158 -20.674076) (xy 391.023856 -20.682458)
			(xy 391.0221 -20.687025) (xy 391.020176 -20.696617) (xy 391.020046 -20.701508) (xy 391.020046 -20.771104)
			(xy 391.020187 -20.775994) (xy 391.022113 -20.785583) (xy 391.023856 -20.790154) (xy 391.027158 -20.798536)
			(xy 391.033762 -20.805648) (xy 391.053033 -20.826974) (xy 391.085598 -20.874336) (xy 391.11069 -20.926048)
			(xy 391.12774 -20.980938) (xy 391.136362 -21.037766) (xy 391.136362 -21.095243) (xy 391.127738 -21.15207)
			(xy 391.110687 -21.20696) (xy 391.085594 -21.258671) (xy 391.053027 -21.306032) (xy 391.033762 -21.327364)
			(xy 391.027158 -21.334476) (xy 391.023856 -21.342858) (xy 391.0221 -21.347425) (xy 391.020176 -21.357017)
			(xy 391.020046 -21.361908) (xy 391.020046 -21.431504) (xy 391.020187 -21.436394) (xy 391.022113 -21.445983)
			(xy 391.023856 -21.450554) (xy 391.027158 -21.458936) (xy 391.033762 -21.466048) (xy 391.053029 -21.487377)
			(xy 391.085586 -21.534742) (xy 391.110671 -21.586454) (xy 391.127716 -21.641343) (xy 391.136336 -21.698168)
			(xy 391.136886 -21.726906) (xy 391.1364 -21.754157) (xy 391.133307 -21.775674) (xy 400.235926 -21.775674)
			(xy 400.239997 -21.720052) (xy 400.252123 -21.665615) (xy 400.272046 -21.613524) (xy 400.299342 -21.564889)
			(xy 400.333428 -21.520746) (xy 400.373577 -21.482037) (xy 400.418935 -21.449586) (xy 400.468535 -21.424085)
			(xy 400.521319 -21.406078) (xy 400.576162 -21.395948) (xy 400.631896 -21.393911) (xy 400.687333 -21.400011)
			(xy 400.74129 -21.414117) (xy 400.792619 -21.435929) (xy 400.840225 -21.464983) (xy 400.883093 -21.500658)
			(xy 400.92031 -21.542195) (xy 400.951083 -21.588708) (xy 400.974755 -21.639205) (xy 400.990823 -21.692612)
			(xy 400.998943 -21.747788) (xy 400.999452 -21.775674) (xy 400.998943 -21.80356) (xy 400.991272 -21.855684)
			(xy 401.138642 -21.855684) (xy 401.142713 -21.800062) (xy 401.154839 -21.745625) (xy 401.174762 -21.693534)
			(xy 401.202058 -21.644899) (xy 401.236144 -21.600756) (xy 401.276293 -21.562047) (xy 401.321651 -21.529596)
			(xy 401.371251 -21.504095) (xy 401.424035 -21.486088) (xy 401.478878 -21.475958) (xy 401.534612 -21.473921)
			(xy 401.590049 -21.480021) (xy 401.644006 -21.494127) (xy 401.695335 -21.515939) (xy 401.742941 -21.544993)
			(xy 401.785809 -21.580668) (xy 401.823026 -21.622205) (xy 401.853799 -21.668718) (xy 401.877471 -21.719215)
			(xy 401.893539 -21.772622) (xy 401.901659 -21.827798) (xy 401.90201 -21.847048) (xy 402.372828 -21.847048)
			(xy 402.376899 -21.791426) (xy 402.389025 -21.736989) (xy 402.408948 -21.684898) (xy 402.436244 -21.636263)
			(xy 402.47033 -21.59212) (xy 402.510479 -21.553411) (xy 402.555837 -21.52096) (xy 402.605437 -21.495459)
			(xy 402.658221 -21.477452) (xy 402.713064 -21.467322) (xy 402.768798 -21.465285) (xy 402.824235 -21.471385)
			(xy 402.878192 -21.485491) (xy 402.929521 -21.507303) (xy 402.977127 -21.536357) (xy 403.019995 -21.572032)
			(xy 403.057212 -21.613569) (xy 403.087985 -21.660082) (xy 403.111657 -21.710579) (xy 403.127725 -21.763986)
			(xy 403.135845 -21.819162) (xy 403.136354 -21.847048) (xy 403.135845 -21.874934) (xy 403.127725 -21.93011)
			(xy 403.111657 -21.983517) (xy 403.087985 -22.034014) (xy 403.057212 -22.080527) (xy 403.019995 -22.122064)
			(xy 402.977127 -22.157739) (xy 402.929521 -22.186793) (xy 402.878192 -22.208605) (xy 402.824235 -22.222711)
			(xy 402.768798 -22.228811) (xy 402.713064 -22.226774) (xy 402.658221 -22.216644) (xy 402.605437 -22.198637)
			(xy 402.555837 -22.173136) (xy 402.510479 -22.140685) (xy 402.47033 -22.101976) (xy 402.436244 -22.057833)
			(xy 402.408948 -22.009198) (xy 402.389025 -21.957107) (xy 402.376899 -21.90267) (xy 402.372828 -21.847048)
			(xy 401.90201 -21.847048) (xy 401.902168 -21.855684) (xy 401.901659 -21.88357) (xy 401.893539 -21.938746)
			(xy 401.877471 -21.992153) (xy 401.853799 -22.04265) (xy 401.823026 -22.089163) (xy 401.785809 -22.1307)
			(xy 401.742941 -22.166375) (xy 401.695335 -22.195429) (xy 401.644006 -22.217241) (xy 401.590049 -22.231347)
			(xy 401.534612 -22.237447) (xy 401.478878 -22.23541) (xy 401.424035 -22.22528) (xy 401.371251 -22.207273)
			(xy 401.321651 -22.181772) (xy 401.276293 -22.149321) (xy 401.236144 -22.110612) (xy 401.202058 -22.066469)
			(xy 401.174762 -22.017834) (xy 401.154839 -21.965743) (xy 401.142713 -21.911306) (xy 401.138642 -21.855684)
			(xy 400.991272 -21.855684) (xy 400.990823 -21.858736) (xy 400.974755 -21.912143) (xy 400.951083 -21.96264)
			(xy 400.92031 -22.009153) (xy 400.883093 -22.05069) (xy 400.840225 -22.086365) (xy 400.792619 -22.115419)
			(xy 400.74129 -22.137231) (xy 400.687333 -22.151337) (xy 400.631896 -22.157437) (xy 400.576162 -22.1554)
			(xy 400.521319 -22.14527) (xy 400.468535 -22.127263) (xy 400.418935 -22.101762) (xy 400.373577 -22.069311)
			(xy 400.333428 -22.030602) (xy 400.299342 -21.986459) (xy 400.272046 -21.937824) (xy 400.252123 -21.885733)
			(xy 400.239997 -21.831296) (xy 400.235926 -21.775674) (xy 391.133307 -21.775674) (xy 391.128644 -21.808105)
			(xy 391.113289 -21.8604) (xy 391.090647 -21.909977) (xy 391.061181 -21.955827) (xy 391.02549 -21.997018)
			(xy 390.984299 -22.032709) (xy 390.938449 -22.062175) (xy 390.888872 -22.084817) (xy 390.836577 -22.100172)
			(xy 390.782629 -22.107928) (xy 390.728127 -22.107928) (xy 390.674179 -22.100172) (xy 390.621884 -22.084817)
			(xy 390.572307 -22.062175) (xy 390.526457 -22.032709) (xy 390.485266 -21.997018) (xy 390.449575 -21.955827)
			(xy 390.420109 -21.909977) (xy 390.397467 -21.8604) (xy 390.382112 -21.808105) (xy 390.374356 -21.754157)
			(xy 390.37387 -21.726906) (xy 390.374391 -21.698167) (xy 390.383014 -21.64134) (xy 390.400066 -21.58645)
			(xy 390.425161 -21.53474) (xy 390.45773 -21.487381) (xy 390.476994 -21.466048) (xy 390.483598 -21.458936)
			(xy 390.4869 -21.450554) (xy 390.488659 -21.445988) (xy 390.490586 -21.436395) (xy 390.49071 -21.431504)
			(xy 390.49071 -21.361908) (xy 390.49057 -21.357018) (xy 390.488645 -21.347428) (xy 390.4869 -21.342858)
			(xy 390.483598 -21.334476) (xy 390.476994 -21.327364) (xy 390.457724 -21.306037) (xy 390.42516 -21.258673)
			(xy 390.40007 -21.206961) (xy 390.383021 -21.15207) (xy 390.374398 -21.095243) (xy 390.374397 -21.037766)
			(xy 390.383019 -20.980938) (xy 390.400067 -20.926047) (xy 390.425156 -20.874334) (xy 390.457719 -20.82697)
			(xy 390.476994 -20.805648) (xy 390.483598 -20.798536) (xy 390.4869 -20.790154) (xy 390.488659 -20.785588)
			(xy 390.490586 -20.775995) (xy 390.49071 -20.771104) (xy 390.49071 -20.701508) (xy 390.49057 -20.696618)
			(xy 390.488645 -20.687028) (xy 390.4869 -20.682458) (xy 390.483598 -20.674076) (xy 390.476994 -20.666964)
			(xy 390.457724 -20.645637) (xy 390.42516 -20.598273) (xy 390.40007 -20.546561) (xy 390.383021 -20.49167)
			(xy 390.374398 -20.434843) (xy 390.374397 -20.377366) (xy 390.383019 -20.320538) (xy 390.400067 -20.265647)
			(xy 390.425156 -20.213934) (xy 390.457719 -20.16657) (xy 390.476994 -20.145248) (xy 390.483598 -20.138136)
			(xy 390.4869 -20.129754) (xy 390.488659 -20.125188) (xy 390.490586 -20.115595) (xy 390.49071 -20.110704)
			(xy 390.49071 -20.041108) (xy 390.49057 -20.036218) (xy 390.488645 -20.026628) (xy 390.4869 -20.022058)
			(xy 390.483598 -20.013676) (xy 390.476994 -20.006564) (xy 390.457724 -19.985237) (xy 390.425161 -19.937874)
			(xy 390.40007 -19.886162) (xy 390.383021 -19.831271) (xy 390.374398 -19.774445) (xy 390.37387 -19.745706)
			(xy 390.37387 -19.745198) (xy 390.374411 -19.716768) (xy 390.382885 -19.660544) (xy 390.399617 -19.606202)
			(xy 390.411462 -19.580352) (xy 390.41705 -19.568668) (xy 390.41578 -19.542506) (xy 390.362948 -19.458686)
			(xy 390.358107 -19.451553) (xy 390.344654 -19.440791) (xy 390.328384 -19.435126) (xy 390.319768 -19.43481)
			(xy 386.27558 -19.43481) (xy 386.267706 -19.43862) (xy 386.241949 -19.450795) (xy 386.187711 -19.468221)
			(xy 386.131484 -19.477387) (xy 386.07452 -19.47809) (xy 386.018084 -19.470315) (xy 385.963432 -19.454233)
			(xy 385.911779 -19.430203) (xy 385.864274 -19.39876) (xy 385.821973 -19.360601) (xy 385.785816 -19.316576)
			(xy 385.756609 -19.267665) (xy 385.734999 -19.214953) (xy 385.727702 -19.187414) (xy 385.727702 -19.186906)
			(xy 385.727448 -19.186652) (xy 385.725136 -19.178668) (xy 385.716199 -19.164667) (xy 385.709922 -19.15922)
			(xy 385.703064 -19.153886) (xy 385.687316 -19.148298) (xy 383.304288 -19.148298) (xy 383.304034 -19.148298)
			(xy 383.29163 -19.149129) (xy 383.269735 -19.160818) (xy 383.262124 -19.17065) (xy 383.25806 -19.17827)
			(xy 383.219706 -19.262598) (xy 383.217004 -19.269366) (xy 383.215077 -19.283804) (xy 383.215896 -19.291046)
			(xy 383.216912 -19.297904) (xy 383.222754 -19.310858) (xy 383.227834 -19.3167) (xy 383.269439 -19.36509)
			(xy 383.347469 -19.466088) (xy 383.419324 -19.571569) (xy 383.484746 -19.681156) (xy 383.543501 -19.794457)
			(xy 383.595379 -19.911068) (xy 383.640196 -20.03057) (xy 383.677789 -20.152537) (xy 383.708027 -20.276534)
			(xy 383.730799 -20.402115) (xy 383.746025 -20.528833) (xy 383.75365 -20.656235) (xy 383.754122 -20.72005)
			(xy 383.753616 -20.785786) (xy 383.745523 -20.917007) (xy 383.729366 -21.047482) (xy 383.705209 -21.176715)
			(xy 383.673141 -21.304215) (xy 383.633285 -21.429499) (xy 383.585792 -21.552093) (xy 383.530843 -21.67153)
			(xy 383.468644 -21.787357) (xy 383.399434 -21.899136) (xy 383.323473 -22.006443) (xy 383.241051 -22.108869)
			(xy 383.152479 -22.206028) (xy 383.058094 -22.297549) (xy 382.958255 -22.383087) (xy 382.853338 -22.462316)
			(xy 382.743744 -22.534936) (xy 382.708205 -22.555454) (xy 399.636486 -22.555454) (xy 399.640557 -22.499832)
			(xy 399.652683 -22.445395) (xy 399.672606 -22.393304) (xy 399.699902 -22.344669) (xy 399.733988 -22.300526)
			(xy 399.774137 -22.261817) (xy 399.819495 -22.229366) (xy 399.869095 -22.203865) (xy 399.921879 -22.185858)
			(xy 399.976722 -22.175728) (xy 400.032456 -22.173691) (xy 400.087893 -22.179791) (xy 400.14185 -22.193897)
			(xy 400.193179 -22.215709) (xy 400.240785 -22.244763) (xy 400.283653 -22.280438) (xy 400.32087 -22.321975)
			(xy 400.351643 -22.368488) (xy 400.375315 -22.418985) (xy 400.391383 -22.472392) (xy 400.399503 -22.527568)
			(xy 400.400012 -22.555454) (xy 400.399503 -22.58334) (xy 400.391383 -22.638516) (xy 400.375315 -22.691923)
			(xy 400.351643 -22.74242) (xy 400.32087 -22.788933) (xy 400.283653 -22.83047) (xy 400.240785 -22.866145)
			(xy 400.193179 -22.895199) (xy 400.14185 -22.917011) (xy 400.087893 -22.931117) (xy 400.032456 -22.937217)
			(xy 399.976722 -22.93518) (xy 399.921879 -22.92505) (xy 399.869095 -22.907043) (xy 399.819495 -22.881542)
			(xy 399.774137 -22.849091) (xy 399.733988 -22.810382) (xy 399.699902 -22.766239) (xy 399.672606 -22.717604)
			(xy 399.652683 -22.665513) (xy 399.640557 -22.611076) (xy 399.636486 -22.555454) (xy 382.708205 -22.555454)
			(xy 382.629886 -22.600671) (xy 382.512198 -22.659273) (xy 382.391126 -22.710519) (xy 382.267128 -22.754214)
			(xy 382.140676 -22.790193) (xy 382.012248 -22.818319) (xy 381.882333 -22.838485) (xy 381.751423 -22.850616)
			(xy 381.620014 -22.854665) (xy 381.488605 -22.850616) (xy 381.357695 -22.838485) (xy 381.22778 -22.818319)
			(xy 381.099352 -22.790193) (xy 380.9729 -22.754214) (xy 380.848902 -22.710519) (xy 380.72783 -22.659273)
			(xy 380.610142 -22.600671) (xy 380.496284 -22.534936) (xy 380.38669 -22.462316) (xy 380.281773 -22.383087)
			(xy 380.181934 -22.297549) (xy 380.087549 -22.206028) (xy 379.998977 -22.108869) (xy 379.916555 -22.006443)
			(xy 379.840594 -21.899136) (xy 379.771384 -21.787357) (xy 379.709185 -21.67153) (xy 379.654236 -21.552093)
			(xy 379.606743 -21.429499) (xy 379.566887 -21.304215) (xy 379.534819 -21.176715) (xy 379.510662 -21.047482)
			(xy 379.494505 -20.917007) (xy 379.486412 -20.785786) (xy 379.485906 -20.72005) (xy 379.486414 -20.66925)
			(xy 379.488536 -20.601972) (xy 379.500211 -20.467859) (xy 379.520319 -20.33475) (xy 379.54878 -20.203173)
			(xy 379.585479 -20.073652) (xy 379.630273 -19.946704) (xy 379.682981 -19.822832) (xy 379.743395 -19.702529)
			(xy 379.811274 -19.586276) (xy 379.886348 -19.474533) (xy 379.968318 -19.367747) (xy 380.012194 -19.3167)
			(xy 380.012448 -19.316446) (xy 380.016995 -19.310808) (xy 380.023053 -19.297658) (xy 380.024386 -19.290538)
			(xy 380.025402 -19.283934) (xy 380.02337 -19.269456) (xy 379.981968 -19.17827) (xy 379.977904 -19.17065)
			(xy 379.970425 -19.160669) (xy 379.948449 -19.148939) (xy 379.935994 -19.148298) (xy 371.396514 -19.148298)
			(xy 371.38442 -19.149041) (xy 371.362941 -19.160177) (xy 371.355366 -19.169634) (xy 371.307868 -19.244056)
			(xy 371.30455 -19.249509) (xy 371.300436 -19.261587) (xy 371.29974 -19.267932) (xy 371.298978 -19.280632)
			(xy 371.304566 -19.29257) (xy 371.315222 -19.316587) (xy 371.330576 -19.366834) (xy 371.338885 -19.418714)
			(xy 371.339872 -19.44497) (xy 371.339872 -19.457162) (xy 371.339111 -19.484224) (xy 371.330888 -19.537732)
			(xy 371.315184 -19.589541) (xy 371.292314 -19.63861) (xy 371.262737 -19.683953) (xy 371.227048 -19.72466)
			(xy 371.185964 -19.759913) (xy 371.140308 -19.789005) (xy 371.090998 -19.811351) (xy 371.039025 -19.826502)
			(xy 370.985432 -19.834155) (xy 370.931296 -19.834155) (xy 370.877703 -19.826502) (xy 370.82573 -19.811351)
			(xy 370.77642 -19.789005) (xy 370.730764 -19.759913) (xy 370.68968 -19.72466) (xy 370.653991 -19.683953)
			(xy 370.624414 -19.63861) (xy 370.601544 -19.589541) (xy 370.58584 -19.537732) (xy 370.577617 -19.484224)
			(xy 370.576856 -19.457162) (xy 370.576856 -19.45259) (xy 370.577356 -19.425051) (xy 370.585309 -19.37055)
			(xy 370.601021 -19.31776) (xy 370.612162 -19.29257) (xy 370.61471 -19.28662) (xy 370.617026 -19.27389)
			(xy 370.616734 -19.267424) (xy 370.615972 -19.254978) (xy 370.561362 -19.169634) (xy 370.553798 -19.160161)
			(xy 370.532314 -19.149009) (xy 370.520214 -19.148298) (xy 369.515136 -19.148298) (xy 369.505071 -19.148733)
			(xy 369.486483 -19.156463) (xy 369.479068 -19.163284) (xy 369.3922 -19.250152) (xy 369.368647 -19.273101)
			(xy 369.31725 -19.314129) (xy 369.26158 -19.349139) (xy 369.202338 -19.377693) (xy 369.14027 -19.399429)
			(xy 369.076158 -19.414075) (xy 369.010808 -19.421446) (xy 368.977926 -19.421856) (xy 365.407448 -19.421856)
			(xy 365.364783 -19.421035) (xy 365.280371 -19.408545) (xy 365.2393 -19.396964) (xy 365.22533 -19.3929)
			(xy 365.197898 -19.400266) (xy 365.115348 -19.487388) (xy 365.109506 -19.51482) (xy 365.111792 -19.521678)
			(xy 365.120891 -19.546745) (xy 365.132795 -19.598727) (xy 365.137344 -19.65186) (xy 365.13445 -19.705109)
			(xy 365.124167 -19.757436) (xy 365.106698 -19.807821) (xy 365.082383 -19.855282) (xy 365.051694 -19.898894)
			(xy 365.033814 -19.91868) (xy 365.02721 -19.925792) (xy 365.023908 -19.934174) (xy 365.022151 -19.938741)
			(xy 365.020229 -19.948333) (xy 365.020098 -19.953224) (xy 365.020098 -20.02282) (xy 365.020232 -20.027711)
			(xy 365.022144 -20.037306) (xy 365.023908 -20.04187) (xy 365.02721 -20.050252) (xy 365.033814 -20.057364)
			(xy 365.053081 -20.078692) (xy 365.08564 -20.126054) (xy 365.110726 -20.177765) (xy 365.127771 -20.232654)
			(xy 365.13639 -20.289479) (xy 365.136388 -20.346953) (xy 365.127764 -20.403777) (xy 365.110714 -20.458664)
			(xy 365.106391 -20.467574) (xy 372.587518 -20.467574) (xy 372.591589 -20.411952) (xy 372.603715 -20.357515)
			(xy 372.623638 -20.305424) (xy 372.650934 -20.256789) (xy 372.68502 -20.212646) (xy 372.725169 -20.173937)
			(xy 372.770527 -20.141486) (xy 372.820127 -20.115985) (xy 372.872911 -20.097978) (xy 372.927754 -20.087848)
			(xy 372.983488 -20.085811) (xy 373.038925 -20.091911) (xy 373.092882 -20.106017) (xy 373.144211 -20.127829)
			(xy 373.191817 -20.156883) (xy 373.234685 -20.192558) (xy 373.271902 -20.234095) (xy 373.302675 -20.280608)
			(xy 373.326347 -20.331105) (xy 373.342415 -20.384512) (xy 373.350535 -20.439688) (xy 373.351044 -20.467574)
			(xy 373.350535 -20.49546) (xy 373.342415 -20.550636) (xy 373.326347 -20.604043) (xy 373.302675 -20.65454)
			(xy 373.271902 -20.701053) (xy 373.234685 -20.74259) (xy 373.191817 -20.778265) (xy 373.144211 -20.807319)
			(xy 373.092882 -20.829131) (xy 373.038925 -20.843237) (xy 372.983488 -20.849337) (xy 372.927754 -20.8473)
			(xy 372.872911 -20.83717) (xy 372.820127 -20.819163) (xy 372.770527 -20.793662) (xy 372.725169 -20.761211)
			(xy 372.68502 -20.722502) (xy 372.650934 -20.678359) (xy 372.623638 -20.629724) (xy 372.603715 -20.577633)
			(xy 372.591589 -20.523196) (xy 372.587518 -20.467574) (xy 365.106391 -20.467574) (xy 365.085624 -20.510373)
			(xy 365.053061 -20.557733) (xy 365.033814 -20.57908) (xy 365.02721 -20.586192) (xy 365.023908 -20.594574)
			(xy 365.022151 -20.599141) (xy 365.020229 -20.608733) (xy 365.020098 -20.613624) (xy 365.020098 -20.68322)
			(xy 365.020232 -20.688111) (xy 365.022144 -20.697706) (xy 365.023908 -20.70227) (xy 365.02721 -20.710652)
			(xy 365.033814 -20.717764) (xy 365.053081 -20.739092) (xy 365.08564 -20.786454) (xy 365.110726 -20.838165)
			(xy 365.127771 -20.893054) (xy 365.13639 -20.949879) (xy 365.136388 -21.007353) (xy 365.127764 -21.064177)
			(xy 365.110714 -21.119064) (xy 365.085624 -21.170773) (xy 365.053061 -21.218133) (xy 365.033814 -21.23948)
			(xy 365.02721 -21.246592) (xy 365.023908 -21.254974) (xy 365.022151 -21.259541) (xy 365.020229 -21.269133)
			(xy 365.020098 -21.274024) (xy 365.020098 -21.34362) (xy 365.020232 -21.348511) (xy 365.022144 -21.358106)
			(xy 365.023908 -21.36267) (xy 365.02721 -21.371052) (xy 365.033814 -21.378164) (xy 365.053082 -21.399492)
			(xy 365.085641 -21.446856) (xy 365.110727 -21.498568) (xy 365.127772 -21.553458) (xy 365.136391 -21.610284)
			(xy 365.136938 -21.639022) (xy 365.136452 -21.666273) (xy 365.128696 -21.720221) (xy 365.113341 -21.772516)
			(xy 365.111899 -21.775674) (xy 374.235978 -21.775674) (xy 374.240049 -21.720052) (xy 374.252175 -21.665615)
			(xy 374.272098 -21.613524) (xy 374.299394 -21.564889) (xy 374.33348 -21.520746) (xy 374.373629 -21.482037)
			(xy 374.418987 -21.449586) (xy 374.468587 -21.424085) (xy 374.521371 -21.406078) (xy 374.576214 -21.395948)
			(xy 374.631948 -21.393911) (xy 374.687385 -21.400011) (xy 374.741342 -21.414117) (xy 374.792671 -21.435929)
			(xy 374.840277 -21.464983) (xy 374.883145 -21.500658) (xy 374.920362 -21.542195) (xy 374.951135 -21.588708)
			(xy 374.974807 -21.639205) (xy 374.990875 -21.692612) (xy 374.998995 -21.747788) (xy 374.999504 -21.775674)
			(xy 374.998995 -21.80356) (xy 374.991324 -21.855684) (xy 375.138694 -21.855684) (xy 375.142765 -21.800062)
			(xy 375.154891 -21.745625) (xy 375.174814 -21.693534) (xy 375.20211 -21.644899) (xy 375.236196 -21.600756)
			(xy 375.276345 -21.562047) (xy 375.321703 -21.529596) (xy 375.371303 -21.504095) (xy 375.424087 -21.486088)
			(xy 375.47893 -21.475958) (xy 375.534664 -21.473921) (xy 375.590101 -21.480021) (xy 375.644058 -21.494127)
			(xy 375.695387 -21.515939) (xy 375.742993 -21.544993) (xy 375.785861 -21.580668) (xy 375.823078 -21.622205)
			(xy 375.853851 -21.668718) (xy 375.877523 -21.719215) (xy 375.893591 -21.772622) (xy 375.901711 -21.827798)
			(xy 375.902062 -21.847048) (xy 376.37288 -21.847048) (xy 376.376951 -21.791426) (xy 376.389077 -21.736989)
			(xy 376.409 -21.684898) (xy 376.436296 -21.636263) (xy 376.470382 -21.59212) (xy 376.510531 -21.553411)
			(xy 376.555889 -21.52096) (xy 376.605489 -21.495459) (xy 376.658273 -21.477452) (xy 376.713116 -21.467322)
			(xy 376.76885 -21.465285) (xy 376.824287 -21.471385) (xy 376.878244 -21.485491) (xy 376.929573 -21.507303)
			(xy 376.977179 -21.536357) (xy 377.020047 -21.572032) (xy 377.057264 -21.613569) (xy 377.088037 -21.660082)
			(xy 377.111709 -21.710579) (xy 377.127777 -21.763986) (xy 377.135897 -21.819162) (xy 377.136406 -21.847048)
			(xy 377.135897 -21.874934) (xy 377.127777 -21.93011) (xy 377.111709 -21.983517) (xy 377.088037 -22.034014)
			(xy 377.057264 -22.080527) (xy 377.020047 -22.122064) (xy 376.977179 -22.157739) (xy 376.929573 -22.186793)
			(xy 376.878244 -22.208605) (xy 376.824287 -22.222711) (xy 376.76885 -22.228811) (xy 376.713116 -22.226774)
			(xy 376.658273 -22.216644) (xy 376.605489 -22.198637) (xy 376.555889 -22.173136) (xy 376.510531 -22.140685)
			(xy 376.470382 -22.101976) (xy 376.436296 -22.057833) (xy 376.409 -22.009198) (xy 376.389077 -21.957107)
			(xy 376.376951 -21.90267) (xy 376.37288 -21.847048) (xy 375.902062 -21.847048) (xy 375.90222 -21.855684)
			(xy 375.901711 -21.88357) (xy 375.893591 -21.938746) (xy 375.877523 -21.992153) (xy 375.853851 -22.04265)
			(xy 375.823078 -22.089163) (xy 375.785861 -22.1307) (xy 375.742993 -22.166375) (xy 375.695387 -22.195429)
			(xy 375.644058 -22.217241) (xy 375.590101 -22.231347) (xy 375.534664 -22.237447) (xy 375.47893 -22.23541)
			(xy 375.424087 -22.22528) (xy 375.371303 -22.207273) (xy 375.321703 -22.181772) (xy 375.276345 -22.149321)
			(xy 375.236196 -22.110612) (xy 375.20211 -22.066469) (xy 375.174814 -22.017834) (xy 375.154891 -21.965743)
			(xy 375.142765 -21.911306) (xy 375.138694 -21.855684) (xy 374.991324 -21.855684) (xy 374.990875 -21.858736)
			(xy 374.974807 -21.912143) (xy 374.951135 -21.96264) (xy 374.920362 -22.009153) (xy 374.883145 -22.05069)
			(xy 374.840277 -22.086365) (xy 374.792671 -22.115419) (xy 374.741342 -22.137231) (xy 374.687385 -22.151337)
			(xy 374.631948 -22.157437) (xy 374.576214 -22.1554) (xy 374.521371 -22.14527) (xy 374.468587 -22.127263)
			(xy 374.418987 -22.101762) (xy 374.373629 -22.069311) (xy 374.33348 -22.030602) (xy 374.299394 -21.986459)
			(xy 374.272098 -21.937824) (xy 374.252175 -21.885733) (xy 374.240049 -21.831296) (xy 374.235978 -21.775674)
			(xy 365.111899 -21.775674) (xy 365.090699 -21.822093) (xy 365.061233 -21.867943) (xy 365.025542 -21.909134)
			(xy 364.984351 -21.944825) (xy 364.938501 -21.974291) (xy 364.888924 -21.996933) (xy 364.836629 -22.012288)
			(xy 364.782681 -22.020044) (xy 364.728179 -22.020044) (xy 364.674231 -22.012288) (xy 364.621936 -21.996933)
			(xy 364.572359 -21.974291) (xy 364.526509 -21.944825) (xy 364.485318 -21.909134) (xy 364.449627 -21.867943)
			(xy 364.420161 -21.822093) (xy 364.397519 -21.772516) (xy 364.382164 -21.720221) (xy 364.374408 -21.666273)
			(xy 364.373922 -21.639022) (xy 364.374441 -21.610282) (xy 364.383062 -21.553453) (xy 364.40011 -21.498561)
			(xy 364.425201 -21.446847) (xy 364.457766 -21.399483) (xy 364.477046 -21.378164) (xy 364.48365 -21.371052)
			(xy 364.486952 -21.36267) (xy 364.488705 -21.358103) (xy 364.490618 -21.34851) (xy 364.490762 -21.34362)
			(xy 364.490762 -21.274024) (xy 364.490623 -21.269134) (xy 364.488699 -21.259544) (xy 364.486952 -21.254974)
			(xy 364.48365 -21.246592) (xy 364.477046 -21.23948) (xy 364.457773 -21.218154) (xy 364.425202 -21.170791)
			(xy 364.400106 -21.119079) (xy 364.383052 -21.064186) (xy 364.374426 -21.007356) (xy 364.374424 -20.949876)
			(xy 364.383045 -20.893045) (xy 364.400094 -20.838151) (xy 364.425186 -20.786437) (xy 364.457752 -20.739071)
			(xy 364.477046 -20.717764) (xy 364.48365 -20.710652) (xy 364.486952 -20.70227) (xy 364.488705 -20.697703)
			(xy 364.490618 -20.68811) (xy 364.490762 -20.68322) (xy 364.490762 -20.613624) (xy 364.490623 -20.608734)
			(xy 364.488699 -20.599144) (xy 364.486952 -20.594574) (xy 364.48365 -20.586192) (xy 364.477046 -20.57908)
			(xy 364.457773 -20.557754) (xy 364.425202 -20.510391) (xy 364.400106 -20.458679) (xy 364.383052 -20.403786)
			(xy 364.374426 -20.346956) (xy 364.374424 -20.289476) (xy 364.383045 -20.232645) (xy 364.400094 -20.177751)
			(xy 364.425186 -20.126037) (xy 364.457752 -20.078671) (xy 364.477046 -20.057364) (xy 364.48365 -20.050252)
			(xy 364.486952 -20.04187) (xy 364.488705 -20.037303) (xy 364.490618 -20.02771) (xy 364.490762 -20.02282)
			(xy 364.490762 -19.953224) (xy 364.490623 -19.948334) (xy 364.488699 -19.938744) (xy 364.486952 -19.934174)
			(xy 364.48365 -19.925792) (xy 364.477046 -19.91868) (xy 364.457777 -19.897352) (xy 364.425216 -19.849988)
			(xy 364.400127 -19.798276) (xy 364.383077 -19.743386) (xy 364.374453 -19.68656) (xy 364.373922 -19.657822)
			(xy 364.373922 -19.657568) (xy 364.374106 -19.640519) (xy 364.377163 -19.606559) (xy 364.380018 -19.58975)
			(xy 364.382304 -19.577304) (xy 364.374938 -19.553682) (xy 364.297722 -19.47672) (xy 364.2741 -19.469354)
			(xy 364.261654 -19.47164) (xy 364.235408 -19.476159) (xy 364.182367 -19.480996) (xy 364.155736 -19.481292)
			(xy 361.126532 -19.481292) (xy 361.093678 -19.480834) (xy 361.028382 -19.47348) (xy 360.96432 -19.458862)
			(xy 360.902298 -19.437164) (xy 360.843095 -19.408658) (xy 360.787456 -19.373702) (xy 360.73608 -19.332737)
			(xy 360.712512 -19.309842) (xy 360.565954 -19.163284) (xy 360.558557 -19.156436) (xy 360.539958 -19.148705)
			(xy 360.529886 -19.148298) (xy 360.518202 -19.148298) (xy 360.509623 -19.148594) (xy 360.493406 -19.154186)
			(xy 360.486452 -19.15922) (xy 360.480102 -19.164554) (xy 360.471212 -19.17827) (xy 360.468926 -19.18716)
			(xy 360.461739 -19.21446) (xy 360.440419 -19.266729) (xy 360.411629 -19.315286) (xy 360.375999 -19.359071)
			(xy 360.334305 -19.397128) (xy 360.287459 -19.428625) (xy 360.236482 -19.452875) (xy 360.182489 -19.469349)
			(xy 360.126658 -19.477687) (xy 360.070207 -19.477706) (xy 360.01437 -19.469408) (xy 359.960366 -19.452971)
			(xy 359.909373 -19.428757) (xy 359.862504 -19.397292) (xy 359.820784 -19.359265) (xy 359.785123 -19.315505)
			(xy 359.7563 -19.266967) (xy 359.734943 -19.214713) (xy 359.727754 -19.187414) (xy 359.727754 -19.186906)
			(xy 359.7275 -19.186652) (xy 359.725186 -19.17867) (xy 359.716244 -19.164675) (xy 359.709974 -19.15922)
			(xy 359.703116 -19.153886) (xy 359.687368 -19.148298) (xy 357.295196 -19.148298) (xy 357.285931 -19.148695)
			(xy 357.268621 -19.155302) (xy 357.254828 -19.167672) (xy 357.250238 -19.17573) (xy 357.210614 -19.262344)
			(xy 357.207905 -19.269111) (xy 357.205963 -19.283552) (xy 357.206804 -19.290792) (xy 357.208836 -19.305524)
			(xy 357.251517 -19.35416) (xy 357.331588 -19.455827) (xy 357.405349 -19.562162) (xy 357.472529 -19.672772)
			(xy 357.53288 -19.787251) (xy 357.586181 -19.905177) (xy 357.632235 -20.026118) (xy 357.670874 -20.149628)
			(xy 357.701954 -20.275253) (xy 357.725362 -20.402531) (xy 357.741012 -20.530994) (xy 357.748846 -20.66017)
			(xy 357.749348 -20.724876) (xy 357.749348 -20.72513) (xy 357.748842 -20.790866) (xy 357.740749 -20.922087)
			(xy 357.724592 -21.052562) (xy 357.700435 -21.181795) (xy 357.668367 -21.309295) (xy 357.628511 -21.434579)
			(xy 357.581018 -21.557173) (xy 357.526069 -21.67661) (xy 357.46387 -21.792437) (xy 357.39466 -21.904216)
			(xy 357.318699 -22.011523) (xy 357.236277 -22.113949) (xy 357.147705 -22.211108) (xy 357.05332 -22.302629)
			(xy 356.953481 -22.388167) (xy 356.848564 -22.467396) (xy 356.73897 -22.540016) (xy 356.71223 -22.555454)
			(xy 373.636538 -22.555454) (xy 373.640609 -22.499832) (xy 373.652735 -22.445395) (xy 373.672658 -22.393304)
			(xy 373.699954 -22.344669) (xy 373.73404 -22.300526) (xy 373.774189 -22.261817) (xy 373.819547 -22.229366)
			(xy 373.869147 -22.203865) (xy 373.921931 -22.185858) (xy 373.976774 -22.175728) (xy 374.032508 -22.173691)
			(xy 374.087945 -22.179791) (xy 374.141902 -22.193897) (xy 374.193231 -22.215709) (xy 374.240837 -22.244763)
			(xy 374.283705 -22.280438) (xy 374.320922 -22.321975) (xy 374.351695 -22.368488) (xy 374.375367 -22.418985)
			(xy 374.391435 -22.472392) (xy 374.399555 -22.527568) (xy 374.400064 -22.555454) (xy 374.399555 -22.58334)
			(xy 374.391435 -22.638516) (xy 374.375367 -22.691923) (xy 374.351695 -22.74242) (xy 374.320922 -22.788933)
			(xy 374.283705 -22.83047) (xy 374.240837 -22.866145) (xy 374.193231 -22.895199) (xy 374.141902 -22.917011)
			(xy 374.087945 -22.931117) (xy 374.032508 -22.937217) (xy 373.976774 -22.93518) (xy 373.921931 -22.92505)
			(xy 373.869147 -22.907043) (xy 373.819547 -22.881542) (xy 373.774189 -22.849091) (xy 373.73404 -22.810382)
			(xy 373.699954 -22.766239) (xy 373.672658 -22.717604) (xy 373.652735 -22.665513) (xy 373.640609 -22.611076)
			(xy 373.636538 -22.555454) (xy 356.71223 -22.555454) (xy 356.625112 -22.605751) (xy 356.507424 -22.664353)
			(xy 356.386352 -22.715599) (xy 356.262354 -22.759294) (xy 356.135902 -22.795273) (xy 356.007474 -22.823399)
			(xy 355.877559 -22.843565) (xy 355.746649 -22.855696) (xy 355.61524 -22.859745) (xy 355.483831 -22.855696)
			(xy 355.352921 -22.843565) (xy 355.223006 -22.823399) (xy 355.094578 -22.795273) (xy 354.968126 -22.759294)
			(xy 354.844128 -22.715599) (xy 354.723056 -22.664353) (xy 354.605368 -22.605751) (xy 354.49151 -22.540016)
			(xy 354.381916 -22.467396) (xy 354.276999 -22.388167) (xy 354.17716 -22.302629) (xy 354.082775 -22.211108)
			(xy 353.994203 -22.113949) (xy 353.911781 -22.011523) (xy 353.83582 -21.904216) (xy 353.76661 -21.792437)
			(xy 353.704411 -21.67661) (xy 353.649462 -21.557173) (xy 353.601969 -21.434579) (xy 353.562113 -21.309295)
			(xy 353.530045 -21.181795) (xy 353.505888 -21.052562) (xy 353.489731 -20.922087) (xy 353.481638 -20.790866)
			(xy 353.481132 -20.72513) (xy 353.481669 -20.658095) (xy 353.490102 -20.524292) (xy 353.506913 -20.39128)
			(xy 353.532036 -20.259586) (xy 353.548188 -20.194524) (xy 353.549961 -20.186317) (xy 353.548679 -20.169587)
			(xy 353.545648 -20.161758) (xy 353.542346 -20.154138) (xy 353.531424 -20.141946) (xy 353.438968 -20.089114)
			(xy 353.429079 -20.084113) (xy 353.407023 -20.082243) (xy 353.386218 -20.089803) (xy 353.378008 -20.097242)
			(xy 350.45015 -23.0251) (xy 359.662474 -23.0251) (xy 359.666545 -22.969478) (xy 359.678671 -22.915041)
			(xy 359.698594 -22.86295) (xy 359.72589 -22.814315) (xy 359.759976 -22.770172) (xy 359.800125 -22.731463)
			(xy 359.845483 -22.699012) (xy 359.895083 -22.673511) (xy 359.947867 -22.655504) (xy 360.00271 -22.645374)
			(xy 360.058444 -22.643337) (xy 360.113881 -22.649437) (xy 360.167838 -22.663543) (xy 360.219167 -22.685355)
			(xy 360.266773 -22.714409) (xy 360.309641 -22.750084) (xy 360.346858 -22.791621) (xy 360.377631 -22.838134)
			(xy 360.401303 -22.888631) (xy 360.417371 -22.942038) (xy 360.425491 -22.997214) (xy 360.425838 -23.01621)
			(xy 361.011722 -23.01621) (xy 361.015793 -22.960588) (xy 361.027919 -22.906151) (xy 361.047842 -22.85406)
			(xy 361.075138 -22.805425) (xy 361.109224 -22.761282) (xy 361.149373 -22.722573) (xy 361.194731 -22.690122)
			(xy 361.244331 -22.664621) (xy 361.297115 -22.646614) (xy 361.351958 -22.636484) (xy 361.407692 -22.634447)
			(xy 361.463129 -22.640547) (xy 361.517086 -22.654653) (xy 361.568415 -22.676465) (xy 361.616021 -22.705519)
			(xy 361.658889 -22.741194) (xy 361.696106 -22.782731) (xy 361.726879 -22.829244) (xy 361.750551 -22.879741)
			(xy 361.766619 -22.933148) (xy 361.774739 -22.988324) (xy 361.775248 -23.01621) (xy 361.775086 -23.0251)
			(xy 385.662422 -23.0251) (xy 385.666493 -22.969478) (xy 385.678619 -22.915041) (xy 385.698542 -22.86295)
			(xy 385.725838 -22.814315) (xy 385.759924 -22.770172) (xy 385.800073 -22.731463) (xy 385.845431 -22.699012)
			(xy 385.895031 -22.673511) (xy 385.947815 -22.655504) (xy 386.002658 -22.645374) (xy 386.058392 -22.643337)
			(xy 386.113829 -22.649437) (xy 386.167786 -22.663543) (xy 386.219115 -22.685355) (xy 386.266721 -22.714409)
			(xy 386.309589 -22.750084) (xy 386.346806 -22.791621) (xy 386.377579 -22.838134) (xy 386.401251 -22.888631)
			(xy 386.417319 -22.942038) (xy 386.425439 -22.997214) (xy 386.425786 -23.01621) (xy 387.01167 -23.01621)
			(xy 387.015741 -22.960588) (xy 387.027867 -22.906151) (xy 387.04779 -22.85406) (xy 387.075086 -22.805425)
			(xy 387.109172 -22.761282) (xy 387.149321 -22.722573) (xy 387.194679 -22.690122) (xy 387.244279 -22.664621)
			(xy 387.297063 -22.646614) (xy 387.351906 -22.636484) (xy 387.40764 -22.634447) (xy 387.463077 -22.640547)
			(xy 387.517034 -22.654653) (xy 387.568363 -22.676465) (xy 387.615969 -22.705519) (xy 387.658837 -22.741194)
			(xy 387.696054 -22.782731) (xy 387.726827 -22.829244) (xy 387.750499 -22.879741) (xy 387.766567 -22.933148)
			(xy 387.774687 -22.988324) (xy 387.775196 -23.01621) (xy 387.775034 -23.0251) (xy 411.66237 -23.0251)
			(xy 411.666441 -22.969478) (xy 411.678567 -22.915041) (xy 411.69849 -22.86295) (xy 411.725786 -22.814315)
			(xy 411.759872 -22.770172) (xy 411.800021 -22.731463) (xy 411.845379 -22.699012) (xy 411.894979 -22.673511)
			(xy 411.947763 -22.655504) (xy 412.002606 -22.645374) (xy 412.05834 -22.643337) (xy 412.113777 -22.649437)
			(xy 412.167734 -22.663543) (xy 412.219063 -22.685355) (xy 412.266669 -22.714409) (xy 412.309537 -22.750084)
			(xy 412.346754 -22.791621) (xy 412.377527 -22.838134) (xy 412.401199 -22.888631) (xy 412.417267 -22.942038)
			(xy 412.425387 -22.997214) (xy 412.425734 -23.01621) (xy 413.011618 -23.01621) (xy 413.015689 -22.960588)
			(xy 413.027815 -22.906151) (xy 413.047738 -22.85406) (xy 413.075034 -22.805425) (xy 413.10912 -22.761282)
			(xy 413.149269 -22.722573) (xy 413.194627 -22.690122) (xy 413.244227 -22.664621) (xy 413.297011 -22.646614)
			(xy 413.351854 -22.636484) (xy 413.407588 -22.634447) (xy 413.463025 -22.640547) (xy 413.516982 -22.654653)
			(xy 413.568311 -22.676465) (xy 413.615917 -22.705519) (xy 413.658785 -22.741194) (xy 413.696002 -22.782731)
			(xy 413.726775 -22.829244) (xy 413.750447 -22.879741) (xy 413.766515 -22.933148) (xy 413.774635 -22.988324)
			(xy 413.775144 -23.01621) (xy 413.774982 -23.0251) (xy 437.662318 -23.0251) (xy 437.666389 -22.969478)
			(xy 437.678515 -22.915041) (xy 437.698438 -22.86295) (xy 437.725734 -22.814315) (xy 437.75982 -22.770172)
			(xy 437.799969 -22.731463) (xy 437.845327 -22.699012) (xy 437.894927 -22.673511) (xy 437.947711 -22.655504)
			(xy 438.002554 -22.645374) (xy 438.058288 -22.643337) (xy 438.113725 -22.649437) (xy 438.167682 -22.663543)
			(xy 438.219011 -22.685355) (xy 438.266617 -22.714409) (xy 438.309485 -22.750084) (xy 438.346702 -22.791621)
			(xy 438.377475 -22.838134) (xy 438.401147 -22.888631) (xy 438.417215 -22.942038) (xy 438.425335 -22.997214)
			(xy 438.425682 -23.01621) (xy 439.011566 -23.01621) (xy 439.015637 -22.960588) (xy 439.027763 -22.906151)
			(xy 439.047686 -22.85406) (xy 439.074982 -22.805425) (xy 439.109068 -22.761282) (xy 439.149217 -22.722573)
			(xy 439.194575 -22.690122) (xy 439.244175 -22.664621) (xy 439.296959 -22.646614) (xy 439.351802 -22.636484)
			(xy 439.407536 -22.634447) (xy 439.462973 -22.640547) (xy 439.51693 -22.654653) (xy 439.568259 -22.676465)
			(xy 439.615865 -22.705519) (xy 439.658733 -22.741194) (xy 439.69595 -22.782731) (xy 439.726723 -22.829244)
			(xy 439.750395 -22.879741) (xy 439.766463 -22.933148) (xy 439.774583 -22.988324) (xy 439.775092 -23.01621)
			(xy 439.774583 -23.044096) (xy 439.766463 -23.099272) (xy 439.750395 -23.152679) (xy 439.726723 -23.203176)
			(xy 439.69595 -23.249689) (xy 439.658733 -23.291226) (xy 439.615865 -23.326901) (xy 439.568259 -23.355955)
			(xy 439.51693 -23.377767) (xy 439.462973 -23.391873) (xy 439.407536 -23.397973) (xy 439.351802 -23.395936)
			(xy 439.296959 -23.385806) (xy 439.244175 -23.367799) (xy 439.194575 -23.342298) (xy 439.149217 -23.309847)
			(xy 439.109068 -23.271138) (xy 439.074982 -23.226995) (xy 439.047686 -23.17836) (xy 439.027763 -23.126269)
			(xy 439.015637 -23.071832) (xy 439.011566 -23.01621) (xy 438.425682 -23.01621) (xy 438.425844 -23.0251)
			(xy 438.425335 -23.052986) (xy 438.417215 -23.108162) (xy 438.401147 -23.161569) (xy 438.377475 -23.212066)
			(xy 438.346702 -23.258579) (xy 438.309485 -23.300116) (xy 438.266617 -23.335791) (xy 438.219011 -23.364845)
			(xy 438.167682 -23.386657) (xy 438.113725 -23.400763) (xy 438.058288 -23.406863) (xy 438.002554 -23.404826)
			(xy 437.947711 -23.394696) (xy 437.894927 -23.376689) (xy 437.845327 -23.351188) (xy 437.799969 -23.318737)
			(xy 437.75982 -23.280028) (xy 437.725734 -23.235885) (xy 437.698438 -23.18725) (xy 437.678515 -23.135159)
			(xy 437.666389 -23.080722) (xy 437.662318 -23.0251) (xy 413.774982 -23.0251) (xy 413.774635 -23.044096)
			(xy 413.766515 -23.099272) (xy 413.750447 -23.152679) (xy 413.726775 -23.203176) (xy 413.696002 -23.249689)
			(xy 413.658785 -23.291226) (xy 413.615917 -23.326901) (xy 413.568311 -23.355955) (xy 413.516982 -23.377767)
			(xy 413.463025 -23.391873) (xy 413.407588 -23.397973) (xy 413.351854 -23.395936) (xy 413.297011 -23.385806)
			(xy 413.244227 -23.367799) (xy 413.194627 -23.342298) (xy 413.149269 -23.309847) (xy 413.10912 -23.271138)
			(xy 413.075034 -23.226995) (xy 413.047738 -23.17836) (xy 413.027815 -23.126269) (xy 413.015689 -23.071832)
			(xy 413.011618 -23.01621) (xy 412.425734 -23.01621) (xy 412.425896 -23.0251) (xy 412.425387 -23.052986)
			(xy 412.417267 -23.108162) (xy 412.401199 -23.161569) (xy 412.377527 -23.212066) (xy 412.346754 -23.258579)
			(xy 412.309537 -23.300116) (xy 412.266669 -23.335791) (xy 412.219063 -23.364845) (xy 412.167734 -23.386657)
			(xy 412.113777 -23.400763) (xy 412.05834 -23.406863) (xy 412.002606 -23.404826) (xy 411.947763 -23.394696)
			(xy 411.894979 -23.376689) (xy 411.845379 -23.351188) (xy 411.800021 -23.318737) (xy 411.759872 -23.280028)
			(xy 411.725786 -23.235885) (xy 411.69849 -23.18725) (xy 411.678567 -23.135159) (xy 411.666441 -23.080722)
			(xy 411.66237 -23.0251) (xy 387.775034 -23.0251) (xy 387.774687 -23.044096) (xy 387.766567 -23.099272)
			(xy 387.750499 -23.152679) (xy 387.726827 -23.203176) (xy 387.696054 -23.249689) (xy 387.658837 -23.291226)
			(xy 387.615969 -23.326901) (xy 387.568363 -23.355955) (xy 387.517034 -23.377767) (xy 387.463077 -23.391873)
			(xy 387.40764 -23.397973) (xy 387.351906 -23.395936) (xy 387.297063 -23.385806) (xy 387.244279 -23.367799)
			(xy 387.194679 -23.342298) (xy 387.149321 -23.309847) (xy 387.109172 -23.271138) (xy 387.075086 -23.226995)
			(xy 387.04779 -23.17836) (xy 387.027867 -23.126269) (xy 387.015741 -23.071832) (xy 387.01167 -23.01621)
			(xy 386.425786 -23.01621) (xy 386.425948 -23.0251) (xy 386.425439 -23.052986) (xy 386.417319 -23.108162)
			(xy 386.401251 -23.161569) (xy 386.377579 -23.212066) (xy 386.346806 -23.258579) (xy 386.309589 -23.300116)
			(xy 386.266721 -23.335791) (xy 386.219115 -23.364845) (xy 386.167786 -23.386657) (xy 386.113829 -23.400763)
			(xy 386.058392 -23.406863) (xy 386.002658 -23.404826) (xy 385.947815 -23.394696) (xy 385.895031 -23.376689)
			(xy 385.845431 -23.351188) (xy 385.800073 -23.318737) (xy 385.759924 -23.280028) (xy 385.725838 -23.235885)
			(xy 385.698542 -23.18725) (xy 385.678619 -23.135159) (xy 385.666493 -23.080722) (xy 385.662422 -23.0251)
			(xy 361.775086 -23.0251) (xy 361.774739 -23.044096) (xy 361.766619 -23.099272) (xy 361.750551 -23.152679)
			(xy 361.726879 -23.203176) (xy 361.696106 -23.249689) (xy 361.658889 -23.291226) (xy 361.616021 -23.326901)
			(xy 361.568415 -23.355955) (xy 361.517086 -23.377767) (xy 361.463129 -23.391873) (xy 361.407692 -23.397973)
			(xy 361.351958 -23.395936) (xy 361.297115 -23.385806) (xy 361.244331 -23.367799) (xy 361.194731 -23.342298)
			(xy 361.149373 -23.309847) (xy 361.109224 -23.271138) (xy 361.075138 -23.226995) (xy 361.047842 -23.17836)
			(xy 361.027919 -23.126269) (xy 361.015793 -23.071832) (xy 361.011722 -23.01621) (xy 360.425838 -23.01621)
			(xy 360.426 -23.0251) (xy 360.425491 -23.052986) (xy 360.417371 -23.108162) (xy 360.401303 -23.161569)
			(xy 360.377631 -23.212066) (xy 360.346858 -23.258579) (xy 360.309641 -23.300116) (xy 360.266773 -23.335791)
			(xy 360.219167 -23.364845) (xy 360.167838 -23.386657) (xy 360.113881 -23.400763) (xy 360.058444 -23.406863)
			(xy 360.00271 -23.404826) (xy 359.947867 -23.394696) (xy 359.895083 -23.376689) (xy 359.845483 -23.351188)
			(xy 359.800125 -23.318737) (xy 359.759976 -23.280028) (xy 359.72589 -23.235885) (xy 359.698594 -23.18725)
			(xy 359.678671 -23.135159) (xy 359.666545 -23.080722) (xy 359.662474 -23.0251) (xy 350.45015 -23.0251)
			(xy 349.885254 -23.589996) (xy 364.384588 -23.589996) (xy 364.388659 -23.534374) (xy 364.400785 -23.479937)
			(xy 364.420708 -23.427846) (xy 364.448004 -23.379211) (xy 364.48209 -23.335068) (xy 364.522239 -23.296359)
			(xy 364.567597 -23.263908) (xy 364.617197 -23.238407) (xy 364.669981 -23.2204) (xy 364.724824 -23.21027)
			(xy 364.780558 -23.208233) (xy 364.835995 -23.214333) (xy 364.889952 -23.228439) (xy 364.941281 -23.250251)
			(xy 364.988887 -23.279305) (xy 365.031755 -23.31498) (xy 365.068972 -23.356517) (xy 365.099745 -23.40303)
			(xy 365.123417 -23.453527) (xy 365.139485 -23.506934) (xy 365.147605 -23.56211) (xy 365.148114 -23.589996)
			(xy 365.147605 -23.617882) (xy 365.139485 -23.673058) (xy 365.123417 -23.726465) (xy 365.099745 -23.776962)
			(xy 365.068972 -23.823475) (xy 365.031755 -23.865012) (xy 364.988887 -23.900687) (xy 364.941281 -23.929741)
			(xy 364.889952 -23.951553) (xy 364.837927 -23.965154) (xy 374.377456 -23.965154) (xy 374.381527 -23.909532)
			(xy 374.393653 -23.855095) (xy 374.413576 -23.803004) (xy 374.440872 -23.754369) (xy 374.474958 -23.710226)
			(xy 374.515107 -23.671517) (xy 374.560465 -23.639066) (xy 374.610065 -23.613565) (xy 374.662849 -23.595558)
			(xy 374.717692 -23.585428) (xy 374.773426 -23.583391) (xy 374.828863 -23.589491) (xy 374.88282 -23.603597)
			(xy 374.934149 -23.625409) (xy 374.981755 -23.654463) (xy 375.024623 -23.690138) (xy 375.06184 -23.731675)
			(xy 375.092613 -23.778188) (xy 375.116285 -23.828685) (xy 375.132353 -23.882092) (xy 375.140473 -23.937268)
			(xy 375.140648 -23.946866) (xy 375.380502 -23.946866) (xy 375.384573 -23.891244) (xy 375.396699 -23.836807)
			(xy 375.416622 -23.784716) (xy 375.443918 -23.736081) (xy 375.478004 -23.691938) (xy 375.518153 -23.653229)
			(xy 375.563511 -23.620778) (xy 375.613111 -23.595277) (xy 375.665895 -23.57727) (xy 375.720738 -23.56714)
			(xy 375.776472 -23.565103) (xy 375.831909 -23.571203) (xy 375.885866 -23.585309) (xy 375.937195 -23.607121)
			(xy 375.984801 -23.636175) (xy 376.027669 -23.67185) (xy 376.064886 -23.713387) (xy 376.095659 -23.7599)
			(xy 376.119331 -23.810397) (xy 376.135399 -23.863804) (xy 376.143519 -23.91898) (xy 376.144028 -23.946866)
			(xy 376.143588 -23.970996) (xy 376.37288 -23.970996) (xy 376.376951 -23.915374) (xy 376.389077 -23.860937)
			(xy 376.409 -23.808846) (xy 376.436296 -23.760211) (xy 376.470382 -23.716068) (xy 376.510531 -23.677359)
			(xy 376.555889 -23.644908) (xy 376.605489 -23.619407) (xy 376.658273 -23.6014) (xy 376.713116 -23.59127)
			(xy 376.76885 -23.589233) (xy 376.775784 -23.589996) (xy 390.384536 -23.589996) (xy 390.388607 -23.534374)
			(xy 390.400733 -23.479937) (xy 390.420656 -23.427846) (xy 390.447952 -23.379211) (xy 390.482038 -23.335068)
			(xy 390.522187 -23.296359) (xy 390.567545 -23.263908) (xy 390.617145 -23.238407) (xy 390.669929 -23.2204)
			(xy 390.724772 -23.21027) (xy 390.780506 -23.208233) (xy 390.835943 -23.214333) (xy 390.8899 -23.228439)
			(xy 390.941229 -23.250251) (xy 390.988835 -23.279305) (xy 391.031703 -23.31498) (xy 391.06892 -23.356517)
			(xy 391.099693 -23.40303) (xy 391.123365 -23.453527) (xy 391.139433 -23.506934) (xy 391.147553 -23.56211)
			(xy 391.148062 -23.589996) (xy 391.147553 -23.617882) (xy 391.139433 -23.673058) (xy 391.123365 -23.726465)
			(xy 391.099693 -23.776962) (xy 391.06892 -23.823475) (xy 391.031703 -23.865012) (xy 390.988835 -23.900687)
			(xy 390.941229 -23.929741) (xy 390.8899 -23.951553) (xy 390.837875 -23.965154) (xy 400.377404 -23.965154)
			(xy 400.381475 -23.909532) (xy 400.393601 -23.855095) (xy 400.413524 -23.803004) (xy 400.44082 -23.754369)
			(xy 400.474906 -23.710226) (xy 400.515055 -23.671517) (xy 400.560413 -23.639066) (xy 400.610013 -23.613565)
			(xy 400.662797 -23.595558) (xy 400.71764 -23.585428) (xy 400.773374 -23.583391) (xy 400.828811 -23.589491)
			(xy 400.882768 -23.603597) (xy 400.934097 -23.625409) (xy 400.981703 -23.654463) (xy 401.024571 -23.690138)
			(xy 401.061788 -23.731675) (xy 401.092561 -23.778188) (xy 401.116233 -23.828685) (xy 401.132301 -23.882092)
			(xy 401.140421 -23.937268) (xy 401.140596 -23.946866) (xy 401.38045 -23.946866) (xy 401.384521 -23.891244)
			(xy 401.396647 -23.836807) (xy 401.41657 -23.784716) (xy 401.443866 -23.736081) (xy 401.477952 -23.691938)
			(xy 401.518101 -23.653229) (xy 401.563459 -23.620778) (xy 401.613059 -23.595277) (xy 401.665843 -23.57727)
			(xy 401.720686 -23.56714) (xy 401.77642 -23.565103) (xy 401.831857 -23.571203) (xy 401.885814 -23.585309)
			(xy 401.937143 -23.607121) (xy 401.984749 -23.636175) (xy 402.027617 -23.67185) (xy 402.064834 -23.713387)
			(xy 402.095607 -23.7599) (xy 402.119279 -23.810397) (xy 402.135347 -23.863804) (xy 402.143467 -23.91898)
			(xy 402.143976 -23.946866) (xy 402.143536 -23.970996) (xy 402.372828 -23.970996) (xy 402.376899 -23.915374)
			(xy 402.389025 -23.860937) (xy 402.408948 -23.808846) (xy 402.436244 -23.760211) (xy 402.47033 -23.716068)
			(xy 402.510479 -23.677359) (xy 402.555837 -23.644908) (xy 402.605437 -23.619407) (xy 402.658221 -23.6014)
			(xy 402.713064 -23.59127) (xy 402.768798 -23.589233) (xy 402.775732 -23.589996) (xy 416.384484 -23.589996)
			(xy 416.388555 -23.534374) (xy 416.400681 -23.479937) (xy 416.420604 -23.427846) (xy 416.4479 -23.379211)
			(xy 416.481986 -23.335068) (xy 416.522135 -23.296359) (xy 416.567493 -23.263908) (xy 416.617093 -23.238407)
			(xy 416.669877 -23.2204) (xy 416.72472 -23.21027) (xy 416.780454 -23.208233) (xy 416.835891 -23.214333)
			(xy 416.889848 -23.228439) (xy 416.941177 -23.250251) (xy 416.988783 -23.279305) (xy 417.031651 -23.31498)
			(xy 417.068868 -23.356517) (xy 417.099641 -23.40303) (xy 417.123313 -23.453527) (xy 417.139381 -23.506934)
			(xy 417.147501 -23.56211) (xy 417.14801 -23.589996) (xy 417.147501 -23.617882) (xy 417.139381 -23.673058)
			(xy 417.123313 -23.726465) (xy 417.099641 -23.776962) (xy 417.068868 -23.823475) (xy 417.031651 -23.865012)
			(xy 416.988783 -23.900687) (xy 416.941177 -23.929741) (xy 416.889848 -23.951553) (xy 416.837823 -23.965154)
			(xy 426.377352 -23.965154) (xy 426.381423 -23.909532) (xy 426.393549 -23.855095) (xy 426.413472 -23.803004)
			(xy 426.440768 -23.754369) (xy 426.474854 -23.710226) (xy 426.515003 -23.671517) (xy 426.560361 -23.639066)
			(xy 426.609961 -23.613565) (xy 426.662745 -23.595558) (xy 426.717588 -23.585428) (xy 426.773322 -23.583391)
			(xy 426.828759 -23.589491) (xy 426.882716 -23.603597) (xy 426.934045 -23.625409) (xy 426.981651 -23.654463)
			(xy 427.024519 -23.690138) (xy 427.061736 -23.731675) (xy 427.092509 -23.778188) (xy 427.116181 -23.828685)
			(xy 427.132249 -23.882092) (xy 427.140369 -23.937268) (xy 427.140544 -23.946866) (xy 427.380398 -23.946866)
			(xy 427.384469 -23.891244) (xy 427.396595 -23.836807) (xy 427.416518 -23.784716) (xy 427.443814 -23.736081)
			(xy 427.4779 -23.691938) (xy 427.518049 -23.653229) (xy 427.563407 -23.620778) (xy 427.613007 -23.595277)
			(xy 427.665791 -23.57727) (xy 427.720634 -23.56714) (xy 427.776368 -23.565103) (xy 427.831805 -23.571203)
			(xy 427.885762 -23.585309) (xy 427.937091 -23.607121) (xy 427.984697 -23.636175) (xy 428.027565 -23.67185)
			(xy 428.064782 -23.713387) (xy 428.095555 -23.7599) (xy 428.119227 -23.810397) (xy 428.135295 -23.863804)
			(xy 428.143415 -23.91898) (xy 428.143924 -23.946866) (xy 428.143484 -23.970996) (xy 428.372776 -23.970996)
			(xy 428.376847 -23.915374) (xy 428.388973 -23.860937) (xy 428.408896 -23.808846) (xy 428.436192 -23.760211)
			(xy 428.470278 -23.716068) (xy 428.510427 -23.677359) (xy 428.555785 -23.644908) (xy 428.605385 -23.619407)
			(xy 428.658169 -23.6014) (xy 428.713012 -23.59127) (xy 428.768746 -23.589233) (xy 428.77568 -23.589996)
			(xy 442.384432 -23.589996) (xy 442.388503 -23.534374) (xy 442.400629 -23.479937) (xy 442.420552 -23.427846)
			(xy 442.447848 -23.379211) (xy 442.481934 -23.335068) (xy 442.522083 -23.296359) (xy 442.567441 -23.263908)
			(xy 442.617041 -23.238407) (xy 442.669825 -23.2204) (xy 442.724668 -23.21027) (xy 442.780402 -23.208233)
			(xy 442.835839 -23.214333) (xy 442.889796 -23.228439) (xy 442.941125 -23.250251) (xy 442.988731 -23.279305)
			(xy 443.031599 -23.31498) (xy 443.068816 -23.356517) (xy 443.099589 -23.40303) (xy 443.123261 -23.453527)
			(xy 443.139329 -23.506934) (xy 443.147449 -23.56211) (xy 443.147958 -23.589996) (xy 443.147449 -23.617882)
			(xy 443.139329 -23.673058) (xy 443.123261 -23.726465) (xy 443.099589 -23.776962) (xy 443.068816 -23.823475)
			(xy 443.031599 -23.865012) (xy 442.988731 -23.900687) (xy 442.941125 -23.929741) (xy 442.889796 -23.951553)
			(xy 442.835839 -23.965659) (xy 442.780402 -23.971759) (xy 442.724668 -23.969722) (xy 442.669825 -23.959592)
			(xy 442.617041 -23.941585) (xy 442.567441 -23.916084) (xy 442.522083 -23.883633) (xy 442.481934 -23.844924)
			(xy 442.447848 -23.800781) (xy 442.420552 -23.752146) (xy 442.400629 -23.700055) (xy 442.388503 -23.645618)
			(xy 442.384432 -23.589996) (xy 428.77568 -23.589996) (xy 428.824183 -23.595333) (xy 428.87814 -23.609439)
			(xy 428.929469 -23.631251) (xy 428.977075 -23.660305) (xy 429.019943 -23.69598) (xy 429.05716 -23.737517)
			(xy 429.087933 -23.78403) (xy 429.111605 -23.834527) (xy 429.127673 -23.887934) (xy 429.135793 -23.94311)
			(xy 429.136302 -23.970996) (xy 429.135793 -23.998882) (xy 429.127673 -24.054058) (xy 429.111605 -24.107465)
			(xy 429.087933 -24.157962) (xy 429.08778 -24.158194) (xy 433.750718 -24.158194) (xy 433.754789 -24.102572)
			(xy 433.766915 -24.048135) (xy 433.786838 -23.996044) (xy 433.814134 -23.947409) (xy 433.84822 -23.903266)
			(xy 433.888369 -23.864557) (xy 433.933727 -23.832106) (xy 433.983327 -23.806605) (xy 434.036111 -23.788598)
			(xy 434.090954 -23.778468) (xy 434.146688 -23.776431) (xy 434.202125 -23.782531) (xy 434.256082 -23.796637)
			(xy 434.307411 -23.818449) (xy 434.355017 -23.847503) (xy 434.397885 -23.883178) (xy 434.435102 -23.924715)
			(xy 434.465875 -23.971228) (xy 434.489547 -24.021725) (xy 434.505615 -24.075132) (xy 434.513735 -24.130308)
			(xy 434.514244 -24.158194) (xy 434.513735 -24.18608) (xy 434.513166 -24.189944) (xy 437.598818 -24.189944)
			(xy 437.602889 -24.134322) (xy 437.615015 -24.079885) (xy 437.634938 -24.027794) (xy 437.662234 -23.979159)
			(xy 437.69632 -23.935016) (xy 437.736469 -23.896307) (xy 437.781827 -23.863856) (xy 437.831427 -23.838355)
			(xy 437.884211 -23.820348) (xy 437.939054 -23.810218) (xy 437.994788 -23.808181) (xy 438.050225 -23.814281)
			(xy 438.104182 -23.828387) (xy 438.155511 -23.850199) (xy 438.203117 -23.879253) (xy 438.245985 -23.914928)
			(xy 438.283202 -23.956465) (xy 438.313975 -24.002978) (xy 438.337647 -24.053475) (xy 438.353715 -24.106882)
			(xy 438.361835 -24.162058) (xy 438.362344 -24.189944) (xy 440.1218 -24.189944) (xy 440.125871 -24.134322)
			(xy 440.137997 -24.079885) (xy 440.15792 -24.027794) (xy 440.185216 -23.979159) (xy 440.219302 -23.935016)
			(xy 440.259451 -23.896307) (xy 440.304809 -23.863856) (xy 440.354409 -23.838355) (xy 440.407193 -23.820348)
			(xy 440.462036 -23.810218) (xy 440.51777 -23.808181) (xy 440.573207 -23.814281) (xy 440.627164 -23.828387)
			(xy 440.678493 -23.850199) (xy 440.726099 -23.879253) (xy 440.768967 -23.914928) (xy 440.806184 -23.956465)
			(xy 440.836957 -24.002978) (xy 440.860629 -24.053475) (xy 440.876697 -24.106882) (xy 440.884817 -24.162058)
			(xy 440.885326 -24.189944) (xy 440.884817 -24.21783) (xy 440.876697 -24.273006) (xy 440.860629 -24.326413)
			(xy 440.836957 -24.37691) (xy 440.806184 -24.423423) (xy 440.768967 -24.46496) (xy 440.726099 -24.500635)
			(xy 440.678493 -24.529689) (xy 440.627164 -24.551501) (xy 440.573207 -24.565607) (xy 440.51777 -24.571707)
			(xy 440.462036 -24.56967) (xy 440.407193 -24.55954) (xy 440.354409 -24.541533) (xy 440.304809 -24.516032)
			(xy 440.259451 -24.483581) (xy 440.219302 -24.444872) (xy 440.185216 -24.400729) (xy 440.15792 -24.352094)
			(xy 440.137997 -24.300003) (xy 440.125871 -24.245566) (xy 440.1218 -24.189944) (xy 438.362344 -24.189944)
			(xy 438.361835 -24.21783) (xy 438.353715 -24.273006) (xy 438.337647 -24.326413) (xy 438.313975 -24.37691)
			(xy 438.283202 -24.423423) (xy 438.245985 -24.46496) (xy 438.203117 -24.500635) (xy 438.155511 -24.529689)
			(xy 438.104182 -24.551501) (xy 438.050225 -24.565607) (xy 437.994788 -24.571707) (xy 437.939054 -24.56967)
			(xy 437.884211 -24.55954) (xy 437.831427 -24.541533) (xy 437.781827 -24.516032) (xy 437.736469 -24.483581)
			(xy 437.69632 -24.444872) (xy 437.662234 -24.400729) (xy 437.634938 -24.352094) (xy 437.615015 -24.300003)
			(xy 437.602889 -24.245566) (xy 437.598818 -24.189944) (xy 434.513166 -24.189944) (xy 434.505615 -24.241256)
			(xy 434.489547 -24.294663) (xy 434.465875 -24.34516) (xy 434.435102 -24.391673) (xy 434.397885 -24.43321)
			(xy 434.355017 -24.468885) (xy 434.307411 -24.497939) (xy 434.256082 -24.519751) (xy 434.202125 -24.533857)
			(xy 434.146688 -24.539957) (xy 434.090954 -24.53792) (xy 434.036111 -24.52779) (xy 433.983327 -24.509783)
			(xy 433.933727 -24.484282) (xy 433.888369 -24.451831) (xy 433.84822 -24.413122) (xy 433.814134 -24.368979)
			(xy 433.786838 -24.320344) (xy 433.766915 -24.268253) (xy 433.754789 -24.213816) (xy 433.750718 -24.158194)
			(xy 429.08778 -24.158194) (xy 429.05716 -24.204475) (xy 429.019943 -24.246012) (xy 428.977075 -24.281687)
			(xy 428.929469 -24.310741) (xy 428.87814 -24.332553) (xy 428.824183 -24.346659) (xy 428.768746 -24.352759)
			(xy 428.713012 -24.350722) (xy 428.658169 -24.340592) (xy 428.605385 -24.322585) (xy 428.555785 -24.297084)
			(xy 428.510427 -24.264633) (xy 428.470278 -24.225924) (xy 428.436192 -24.181781) (xy 428.408896 -24.133146)
			(xy 428.388973 -24.081055) (xy 428.376847 -24.026618) (xy 428.372776 -23.970996) (xy 428.143484 -23.970996)
			(xy 428.143415 -23.974752) (xy 428.135295 -24.029928) (xy 428.119227 -24.083335) (xy 428.095555 -24.133832)
			(xy 428.064782 -24.180345) (xy 428.027565 -24.221882) (xy 427.984697 -24.257557) (xy 427.937091 -24.286611)
			(xy 427.885762 -24.308423) (xy 427.831805 -24.322529) (xy 427.776368 -24.328629) (xy 427.720634 -24.326592)
			(xy 427.665791 -24.316462) (xy 427.613007 -24.298455) (xy 427.563407 -24.272954) (xy 427.518049 -24.240503)
			(xy 427.4779 -24.201794) (xy 427.443814 -24.157651) (xy 427.416518 -24.109016) (xy 427.396595 -24.056925)
			(xy 427.384469 -24.002488) (xy 427.380398 -23.946866) (xy 427.140544 -23.946866) (xy 427.140878 -23.965154)
			(xy 427.140369 -23.99304) (xy 427.132249 -24.048216) (xy 427.116181 -24.101623) (xy 427.092509 -24.15212)
			(xy 427.061736 -24.198633) (xy 427.024519 -24.24017) (xy 426.981651 -24.275845) (xy 426.934045 -24.304899)
			(xy 426.882716 -24.326711) (xy 426.828759 -24.340817) (xy 426.773322 -24.346917) (xy 426.717588 -24.34488)
			(xy 426.662745 -24.33475) (xy 426.609961 -24.316743) (xy 426.560361 -24.291242) (xy 426.515003 -24.258791)
			(xy 426.474854 -24.220082) (xy 426.440768 -24.175939) (xy 426.413472 -24.127304) (xy 426.393549 -24.075213)
			(xy 426.381423 -24.020776) (xy 426.377352 -23.965154) (xy 416.837823 -23.965154) (xy 416.835891 -23.965659)
			(xy 416.780454 -23.971759) (xy 416.72472 -23.969722) (xy 416.669877 -23.959592) (xy 416.617093 -23.941585)
			(xy 416.567493 -23.916084) (xy 416.522135 -23.883633) (xy 416.481986 -23.844924) (xy 416.4479 -23.800781)
			(xy 416.420604 -23.752146) (xy 416.400681 -23.700055) (xy 416.388555 -23.645618) (xy 416.384484 -23.589996)
			(xy 402.775732 -23.589996) (xy 402.824235 -23.595333) (xy 402.878192 -23.609439) (xy 402.929521 -23.631251)
			(xy 402.977127 -23.660305) (xy 403.019995 -23.69598) (xy 403.057212 -23.737517) (xy 403.087985 -23.78403)
			(xy 403.111657 -23.834527) (xy 403.127725 -23.887934) (xy 403.135845 -23.94311) (xy 403.136354 -23.970996)
			(xy 403.135845 -23.998882) (xy 403.127725 -24.054058) (xy 403.111657 -24.107465) (xy 403.087985 -24.157962)
			(xy 403.087832 -24.158194) (xy 407.75077 -24.158194) (xy 407.754841 -24.102572) (xy 407.766967 -24.048135)
			(xy 407.78689 -23.996044) (xy 407.814186 -23.947409) (xy 407.848272 -23.903266) (xy 407.888421 -23.864557)
			(xy 407.933779 -23.832106) (xy 407.983379 -23.806605) (xy 408.036163 -23.788598) (xy 408.091006 -23.778468)
			(xy 408.14674 -23.776431) (xy 408.202177 -23.782531) (xy 408.256134 -23.796637) (xy 408.307463 -23.818449)
			(xy 408.355069 -23.847503) (xy 408.397937 -23.883178) (xy 408.435154 -23.924715) (xy 408.465927 -23.971228)
			(xy 408.489599 -24.021725) (xy 408.505667 -24.075132) (xy 408.513787 -24.130308) (xy 408.514296 -24.158194)
			(xy 408.513787 -24.18608) (xy 408.513218 -24.189944) (xy 411.59887 -24.189944) (xy 411.602941 -24.134322)
			(xy 411.615067 -24.079885) (xy 411.63499 -24.027794) (xy 411.662286 -23.979159) (xy 411.696372 -23.935016)
			(xy 411.736521 -23.896307) (xy 411.781879 -23.863856) (xy 411.831479 -23.838355) (xy 411.884263 -23.820348)
			(xy 411.939106 -23.810218) (xy 411.99484 -23.808181) (xy 412.050277 -23.814281) (xy 412.104234 -23.828387)
			(xy 412.155563 -23.850199) (xy 412.203169 -23.879253) (xy 412.246037 -23.914928) (xy 412.283254 -23.956465)
			(xy 412.314027 -24.002978) (xy 412.337699 -24.053475) (xy 412.353767 -24.106882) (xy 412.361887 -24.162058)
			(xy 412.362396 -24.189944) (xy 414.121852 -24.189944) (xy 414.125923 -24.134322) (xy 414.138049 -24.079885)
			(xy 414.157972 -24.027794) (xy 414.185268 -23.979159) (xy 414.219354 -23.935016) (xy 414.259503 -23.896307)
			(xy 414.304861 -23.863856) (xy 414.354461 -23.838355) (xy 414.407245 -23.820348) (xy 414.462088 -23.810218)
			(xy 414.517822 -23.808181) (xy 414.573259 -23.814281) (xy 414.627216 -23.828387) (xy 414.678545 -23.850199)
			(xy 414.726151 -23.879253) (xy 414.769019 -23.914928) (xy 414.806236 -23.956465) (xy 414.837009 -24.002978)
			(xy 414.860681 -24.053475) (xy 414.876749 -24.106882) (xy 414.884869 -24.162058) (xy 414.885378 -24.189944)
			(xy 414.884869 -24.21783) (xy 414.876749 -24.273006) (xy 414.860681 -24.326413) (xy 414.837009 -24.37691)
			(xy 414.806236 -24.423423) (xy 414.769019 -24.46496) (xy 414.726151 -24.500635) (xy 414.678545 -24.529689)
			(xy 414.627216 -24.551501) (xy 414.573259 -24.565607) (xy 414.517822 -24.571707) (xy 414.462088 -24.56967)
			(xy 414.407245 -24.55954) (xy 414.354461 -24.541533) (xy 414.304861 -24.516032) (xy 414.259503 -24.483581)
			(xy 414.219354 -24.444872) (xy 414.185268 -24.400729) (xy 414.157972 -24.352094) (xy 414.138049 -24.300003)
			(xy 414.125923 -24.245566) (xy 414.121852 -24.189944) (xy 412.362396 -24.189944) (xy 412.361887 -24.21783)
			(xy 412.353767 -24.273006) (xy 412.337699 -24.326413) (xy 412.314027 -24.37691) (xy 412.283254 -24.423423)
			(xy 412.246037 -24.46496) (xy 412.203169 -24.500635) (xy 412.155563 -24.529689) (xy 412.104234 -24.551501)
			(xy 412.050277 -24.565607) (xy 411.99484 -24.571707) (xy 411.939106 -24.56967) (xy 411.884263 -24.55954)
			(xy 411.831479 -24.541533) (xy 411.781879 -24.516032) (xy 411.736521 -24.483581) (xy 411.696372 -24.444872)
			(xy 411.662286 -24.400729) (xy 411.63499 -24.352094) (xy 411.615067 -24.300003) (xy 411.602941 -24.245566)
			(xy 411.59887 -24.189944) (xy 408.513218 -24.189944) (xy 408.505667 -24.241256) (xy 408.489599 -24.294663)
			(xy 408.465927 -24.34516) (xy 408.435154 -24.391673) (xy 408.397937 -24.43321) (xy 408.355069 -24.468885)
			(xy 408.307463 -24.497939) (xy 408.256134 -24.519751) (xy 408.202177 -24.533857) (xy 408.14674 -24.539957)
			(xy 408.091006 -24.53792) (xy 408.036163 -24.52779) (xy 407.983379 -24.509783) (xy 407.933779 -24.484282)
			(xy 407.888421 -24.451831) (xy 407.848272 -24.413122) (xy 407.814186 -24.368979) (xy 407.78689 -24.320344)
			(xy 407.766967 -24.268253) (xy 407.754841 -24.213816) (xy 407.75077 -24.158194) (xy 403.087832 -24.158194)
			(xy 403.057212 -24.204475) (xy 403.019995 -24.246012) (xy 402.977127 -24.281687) (xy 402.929521 -24.310741)
			(xy 402.878192 -24.332553) (xy 402.824235 -24.346659) (xy 402.768798 -24.352759) (xy 402.713064 -24.350722)
			(xy 402.658221 -24.340592) (xy 402.605437 -24.322585) (xy 402.555837 -24.297084) (xy 402.510479 -24.264633)
			(xy 402.47033 -24.225924) (xy 402.436244 -24.181781) (xy 402.408948 -24.133146) (xy 402.389025 -24.081055)
			(xy 402.376899 -24.026618) (xy 402.372828 -23.970996) (xy 402.143536 -23.970996) (xy 402.143467 -23.974752)
			(xy 402.135347 -24.029928) (xy 402.119279 -24.083335) (xy 402.095607 -24.133832) (xy 402.064834 -24.180345)
			(xy 402.027617 -24.221882) (xy 401.984749 -24.257557) (xy 401.937143 -24.286611) (xy 401.885814 -24.308423)
			(xy 401.831857 -24.322529) (xy 401.77642 -24.328629) (xy 401.720686 -24.326592) (xy 401.665843 -24.316462)
			(xy 401.613059 -24.298455) (xy 401.563459 -24.272954) (xy 401.518101 -24.240503) (xy 401.477952 -24.201794)
			(xy 401.443866 -24.157651) (xy 401.41657 -24.109016) (xy 401.396647 -24.056925) (xy 401.384521 -24.002488)
			(xy 401.38045 -23.946866) (xy 401.140596 -23.946866) (xy 401.14093 -23.965154) (xy 401.140421 -23.99304)
			(xy 401.132301 -24.048216) (xy 401.116233 -24.101623) (xy 401.092561 -24.15212) (xy 401.061788 -24.198633)
			(xy 401.024571 -24.24017) (xy 400.981703 -24.275845) (xy 400.934097 -24.304899) (xy 400.882768 -24.326711)
			(xy 400.828811 -24.340817) (xy 400.773374 -24.346917) (xy 400.71764 -24.34488) (xy 400.662797 -24.33475)
			(xy 400.610013 -24.316743) (xy 400.560413 -24.291242) (xy 400.515055 -24.258791) (xy 400.474906 -24.220082)
			(xy 400.44082 -24.175939) (xy 400.413524 -24.127304) (xy 400.393601 -24.075213) (xy 400.381475 -24.020776)
			(xy 400.377404 -23.965154) (xy 390.837875 -23.965154) (xy 390.835943 -23.965659) (xy 390.780506 -23.971759)
			(xy 390.724772 -23.969722) (xy 390.669929 -23.959592) (xy 390.617145 -23.941585) (xy 390.567545 -23.916084)
			(xy 390.522187 -23.883633) (xy 390.482038 -23.844924) (xy 390.447952 -23.800781) (xy 390.420656 -23.752146)
			(xy 390.400733 -23.700055) (xy 390.388607 -23.645618) (xy 390.384536 -23.589996) (xy 376.775784 -23.589996)
			(xy 376.824287 -23.595333) (xy 376.878244 -23.609439) (xy 376.929573 -23.631251) (xy 376.977179 -23.660305)
			(xy 377.020047 -23.69598) (xy 377.057264 -23.737517) (xy 377.088037 -23.78403) (xy 377.111709 -23.834527)
			(xy 377.127777 -23.887934) (xy 377.135897 -23.94311) (xy 377.136406 -23.970996) (xy 377.135897 -23.998882)
			(xy 377.127777 -24.054058) (xy 377.111709 -24.107465) (xy 377.088037 -24.157962) (xy 377.087884 -24.158194)
			(xy 381.750822 -24.158194) (xy 381.754893 -24.102572) (xy 381.767019 -24.048135) (xy 381.786942 -23.996044)
			(xy 381.814238 -23.947409) (xy 381.848324 -23.903266) (xy 381.888473 -23.864557) (xy 381.933831 -23.832106)
			(xy 381.983431 -23.806605) (xy 382.036215 -23.788598) (xy 382.091058 -23.778468) (xy 382.146792 -23.776431)
			(xy 382.202229 -23.782531) (xy 382.256186 -23.796637) (xy 382.307515 -23.818449) (xy 382.355121 -23.847503)
			(xy 382.397989 -23.883178) (xy 382.435206 -23.924715) (xy 382.465979 -23.971228) (xy 382.489651 -24.021725)
			(xy 382.505719 -24.075132) (xy 382.513839 -24.130308) (xy 382.514348 -24.158194) (xy 382.513839 -24.18608)
			(xy 382.51327 -24.189944) (xy 385.598922 -24.189944) (xy 385.602993 -24.134322) (xy 385.615119 -24.079885)
			(xy 385.635042 -24.027794) (xy 385.662338 -23.979159) (xy 385.696424 -23.935016) (xy 385.736573 -23.896307)
			(xy 385.781931 -23.863856) (xy 385.831531 -23.838355) (xy 385.884315 -23.820348) (xy 385.939158 -23.810218)
			(xy 385.994892 -23.808181) (xy 386.050329 -23.814281) (xy 386.104286 -23.828387) (xy 386.155615 -23.850199)
			(xy 386.203221 -23.879253) (xy 386.246089 -23.914928) (xy 386.283306 -23.956465) (xy 386.314079 -24.002978)
			(xy 386.337751 -24.053475) (xy 386.353819 -24.106882) (xy 386.361939 -24.162058) (xy 386.362448 -24.189944)
			(xy 388.121904 -24.189944) (xy 388.125975 -24.134322) (xy 388.138101 -24.079885) (xy 388.158024 -24.027794)
			(xy 388.18532 -23.979159) (xy 388.219406 -23.935016) (xy 388.259555 -23.896307) (xy 388.304913 -23.863856)
			(xy 388.354513 -23.838355) (xy 388.407297 -23.820348) (xy 388.46214 -23.810218) (xy 388.517874 -23.808181)
			(xy 388.573311 -23.814281) (xy 388.627268 -23.828387) (xy 388.678597 -23.850199) (xy 388.726203 -23.879253)
			(xy 388.769071 -23.914928) (xy 388.806288 -23.956465) (xy 388.837061 -24.002978) (xy 388.860733 -24.053475)
			(xy 388.876801 -24.106882) (xy 388.884921 -24.162058) (xy 388.88543 -24.189944) (xy 388.884921 -24.21783)
			(xy 388.876801 -24.273006) (xy 388.860733 -24.326413) (xy 388.837061 -24.37691) (xy 388.806288 -24.423423)
			(xy 388.769071 -24.46496) (xy 388.726203 -24.500635) (xy 388.678597 -24.529689) (xy 388.627268 -24.551501)
			(xy 388.573311 -24.565607) (xy 388.517874 -24.571707) (xy 388.46214 -24.56967) (xy 388.407297 -24.55954)
			(xy 388.354513 -24.541533) (xy 388.304913 -24.516032) (xy 388.259555 -24.483581) (xy 388.219406 -24.444872)
			(xy 388.18532 -24.400729) (xy 388.158024 -24.352094) (xy 388.138101 -24.300003) (xy 388.125975 -24.245566)
			(xy 388.121904 -24.189944) (xy 386.362448 -24.189944) (xy 386.361939 -24.21783) (xy 386.353819 -24.273006)
			(xy 386.337751 -24.326413) (xy 386.314079 -24.37691) (xy 386.283306 -24.423423) (xy 386.246089 -24.46496)
			(xy 386.203221 -24.500635) (xy 386.155615 -24.529689) (xy 386.104286 -24.551501) (xy 386.050329 -24.565607)
			(xy 385.994892 -24.571707) (xy 385.939158 -24.56967) (xy 385.884315 -24.55954) (xy 385.831531 -24.541533)
			(xy 385.781931 -24.516032) (xy 385.736573 -24.483581) (xy 385.696424 -24.444872) (xy 385.662338 -24.400729)
			(xy 385.635042 -24.352094) (xy 385.615119 -24.300003) (xy 385.602993 -24.245566) (xy 385.598922 -24.189944)
			(xy 382.51327 -24.189944) (xy 382.505719 -24.241256) (xy 382.489651 -24.294663) (xy 382.465979 -24.34516)
			(xy 382.435206 -24.391673) (xy 382.397989 -24.43321) (xy 382.355121 -24.468885) (xy 382.307515 -24.497939)
			(xy 382.256186 -24.519751) (xy 382.202229 -24.533857) (xy 382.146792 -24.539957) (xy 382.091058 -24.53792)
			(xy 382.036215 -24.52779) (xy 381.983431 -24.509783) (xy 381.933831 -24.484282) (xy 381.888473 -24.451831)
			(xy 381.848324 -24.413122) (xy 381.814238 -24.368979) (xy 381.786942 -24.320344) (xy 381.767019 -24.268253)
			(xy 381.754893 -24.213816) (xy 381.750822 -24.158194) (xy 377.087884 -24.158194) (xy 377.057264 -24.204475)
			(xy 377.020047 -24.246012) (xy 376.977179 -24.281687) (xy 376.929573 -24.310741) (xy 376.878244 -24.332553)
			(xy 376.824287 -24.346659) (xy 376.76885 -24.352759) (xy 376.713116 -24.350722) (xy 376.658273 -24.340592)
			(xy 376.605489 -24.322585) (xy 376.555889 -24.297084) (xy 376.510531 -24.264633) (xy 376.470382 -24.225924)
			(xy 376.436296 -24.181781) (xy 376.409 -24.133146) (xy 376.389077 -24.081055) (xy 376.376951 -24.026618)
			(xy 376.37288 -23.970996) (xy 376.143588 -23.970996) (xy 376.143519 -23.974752) (xy 376.135399 -24.029928)
			(xy 376.119331 -24.083335) (xy 376.095659 -24.133832) (xy 376.064886 -24.180345) (xy 376.027669 -24.221882)
			(xy 375.984801 -24.257557) (xy 375.937195 -24.286611) (xy 375.885866 -24.308423) (xy 375.831909 -24.322529)
			(xy 375.776472 -24.328629) (xy 375.720738 -24.326592) (xy 375.665895 -24.316462) (xy 375.613111 -24.298455)
			(xy 375.563511 -24.272954) (xy 375.518153 -24.240503) (xy 375.478004 -24.201794) (xy 375.443918 -24.157651)
			(xy 375.416622 -24.109016) (xy 375.396699 -24.056925) (xy 375.384573 -24.002488) (xy 375.380502 -23.946866)
			(xy 375.140648 -23.946866) (xy 375.140982 -23.965154) (xy 375.140473 -23.99304) (xy 375.132353 -24.048216)
			(xy 375.116285 -24.101623) (xy 375.092613 -24.15212) (xy 375.06184 -24.198633) (xy 375.024623 -24.24017)
			(xy 374.981755 -24.275845) (xy 374.934149 -24.304899) (xy 374.88282 -24.326711) (xy 374.828863 -24.340817)
			(xy 374.773426 -24.346917) (xy 374.717692 -24.34488) (xy 374.662849 -24.33475) (xy 374.610065 -24.316743)
			(xy 374.560465 -24.291242) (xy 374.515107 -24.258791) (xy 374.474958 -24.220082) (xy 374.440872 -24.175939)
			(xy 374.413576 -24.127304) (xy 374.393653 -24.075213) (xy 374.381527 -24.020776) (xy 374.377456 -23.965154)
			(xy 364.837927 -23.965154) (xy 364.835995 -23.965659) (xy 364.780558 -23.971759) (xy 364.724824 -23.969722)
			(xy 364.669981 -23.959592) (xy 364.617197 -23.941585) (xy 364.567597 -23.916084) (xy 364.522239 -23.883633)
			(xy 364.48209 -23.844924) (xy 364.448004 -23.800781) (xy 364.420708 -23.752146) (xy 364.400785 -23.700055)
			(xy 364.388659 -23.645618) (xy 364.384588 -23.589996) (xy 349.885254 -23.589996) (xy 349.317056 -24.158194)
			(xy 355.750874 -24.158194) (xy 355.754945 -24.102572) (xy 355.767071 -24.048135) (xy 355.786994 -23.996044)
			(xy 355.81429 -23.947409) (xy 355.848376 -23.903266) (xy 355.888525 -23.864557) (xy 355.933883 -23.832106)
			(xy 355.983483 -23.806605) (xy 356.036267 -23.788598) (xy 356.09111 -23.778468) (xy 356.146844 -23.776431)
			(xy 356.202281 -23.782531) (xy 356.256238 -23.796637) (xy 356.307567 -23.818449) (xy 356.355173 -23.847503)
			(xy 356.398041 -23.883178) (xy 356.435258 -23.924715) (xy 356.466031 -23.971228) (xy 356.489703 -24.021725)
			(xy 356.505771 -24.075132) (xy 356.513891 -24.130308) (xy 356.5144 -24.158194) (xy 356.513891 -24.18608)
			(xy 356.513322 -24.189944) (xy 359.598974 -24.189944) (xy 359.603045 -24.134322) (xy 359.615171 -24.079885)
			(xy 359.635094 -24.027794) (xy 359.66239 -23.979159) (xy 359.696476 -23.935016) (xy 359.736625 -23.896307)
			(xy 359.781983 -23.863856) (xy 359.831583 -23.838355) (xy 359.884367 -23.820348) (xy 359.93921 -23.810218)
			(xy 359.994944 -23.808181) (xy 360.050381 -23.814281) (xy 360.104338 -23.828387) (xy 360.155667 -23.850199)
			(xy 360.203273 -23.879253) (xy 360.246141 -23.914928) (xy 360.283358 -23.956465) (xy 360.314131 -24.002978)
			(xy 360.337803 -24.053475) (xy 360.353871 -24.106882) (xy 360.361991 -24.162058) (xy 360.3625 -24.189944)
			(xy 362.121956 -24.189944) (xy 362.126027 -24.134322) (xy 362.138153 -24.079885) (xy 362.158076 -24.027794)
			(xy 362.185372 -23.979159) (xy 362.219458 -23.935016) (xy 362.259607 -23.896307) (xy 362.304965 -23.863856)
			(xy 362.354565 -23.838355) (xy 362.407349 -23.820348) (xy 362.462192 -23.810218) (xy 362.517926 -23.808181)
			(xy 362.573363 -23.814281) (xy 362.62732 -23.828387) (xy 362.678649 -23.850199) (xy 362.726255 -23.879253)
			(xy 362.769123 -23.914928) (xy 362.80634 -23.956465) (xy 362.837113 -24.002978) (xy 362.860785 -24.053475)
			(xy 362.876853 -24.106882) (xy 362.884973 -24.162058) (xy 362.885482 -24.189944) (xy 362.884973 -24.21783)
			(xy 362.876853 -24.273006) (xy 362.860785 -24.326413) (xy 362.837113 -24.37691) (xy 362.80634 -24.423423)
			(xy 362.769123 -24.46496) (xy 362.726255 -24.500635) (xy 362.678649 -24.529689) (xy 362.62732 -24.551501)
			(xy 362.573363 -24.565607) (xy 362.517926 -24.571707) (xy 362.462192 -24.56967) (xy 362.407349 -24.55954)
			(xy 362.354565 -24.541533) (xy 362.304965 -24.516032) (xy 362.259607 -24.483581) (xy 362.219458 -24.444872)
			(xy 362.185372 -24.400729) (xy 362.158076 -24.352094) (xy 362.138153 -24.300003) (xy 362.126027 -24.245566)
			(xy 362.121956 -24.189944) (xy 360.3625 -24.189944) (xy 360.361991 -24.21783) (xy 360.353871 -24.273006)
			(xy 360.337803 -24.326413) (xy 360.314131 -24.37691) (xy 360.283358 -24.423423) (xy 360.246141 -24.46496)
			(xy 360.203273 -24.500635) (xy 360.155667 -24.529689) (xy 360.104338 -24.551501) (xy 360.050381 -24.565607)
			(xy 359.994944 -24.571707) (xy 359.93921 -24.56967) (xy 359.884367 -24.55954) (xy 359.831583 -24.541533)
			(xy 359.781983 -24.516032) (xy 359.736625 -24.483581) (xy 359.696476 -24.444872) (xy 359.66239 -24.400729)
			(xy 359.635094 -24.352094) (xy 359.615171 -24.300003) (xy 359.603045 -24.245566) (xy 359.598974 -24.189944)
			(xy 356.513322 -24.189944) (xy 356.505771 -24.241256) (xy 356.489703 -24.294663) (xy 356.466031 -24.34516)
			(xy 356.435258 -24.391673) (xy 356.398041 -24.43321) (xy 356.355173 -24.468885) (xy 356.307567 -24.497939)
			(xy 356.256238 -24.519751) (xy 356.202281 -24.533857) (xy 356.146844 -24.539957) (xy 356.09111 -24.53792)
			(xy 356.036267 -24.52779) (xy 355.983483 -24.509783) (xy 355.933883 -24.484282) (xy 355.888525 -24.451831)
			(xy 355.848376 -24.413122) (xy 355.81429 -24.368979) (xy 355.786994 -24.320344) (xy 355.767071 -24.268253)
			(xy 355.754945 -24.213816) (xy 355.750874 -24.158194) (xy 349.317056 -24.158194) (xy 348.828106 -24.647144)
			(xy 348.820711 -24.653997) (xy 348.802112 -24.661743) (xy 348.792038 -24.66213) (xy 348.215712 -24.66213)
			(xy 348.206332 -24.662493) (xy 348.188845 -24.669279) (xy 348.181676 -24.675338) (xy 348.154666 -24.699042)
			(xy 348.095885 -24.740383) (xy 348.032494 -24.774235) (xy 347.965442 -24.800089) (xy 347.9362 -24.807418)
			(xy 354.671374 -24.807418) (xy 354.675445 -24.751796) (xy 354.687571 -24.697359) (xy 354.707494 -24.645268)
			(xy 354.73479 -24.596633) (xy 354.768876 -24.55249) (xy 354.809025 -24.513781) (xy 354.854383 -24.48133)
			(xy 354.903983 -24.455829) (xy 354.956767 -24.437822) (xy 355.01161 -24.427692) (xy 355.067344 -24.425655)
			(xy 355.122781 -24.431755) (xy 355.176738 -24.445861) (xy 355.228067 -24.467673) (xy 355.275673 -24.496727)
			(xy 355.318541 -24.532402) (xy 355.355758 -24.573939) (xy 355.386531 -24.620452) (xy 355.410203 -24.670949)
			(xy 355.426271 -24.724356) (xy 355.434391 -24.779532) (xy 355.4349 -24.807418) (xy 356.92029 -24.807418)
			(xy 356.924361 -24.751796) (xy 356.936487 -24.697359) (xy 356.95641 -24.645268) (xy 356.983706 -24.596633)
			(xy 357.017792 -24.55249) (xy 357.057941 -24.513781) (xy 357.103299 -24.48133) (xy 357.152899 -24.455829)
			(xy 357.205683 -24.437822) (xy 357.260526 -24.427692) (xy 357.31626 -24.425655) (xy 357.371697 -24.431755)
			(xy 357.425654 -24.445861) (xy 357.476983 -24.467673) (xy 357.524589 -24.496727) (xy 357.567457 -24.532402)
			(xy 357.604674 -24.573939) (xy 357.635447 -24.620452) (xy 357.659119 -24.670949) (xy 357.675187 -24.724356)
			(xy 357.683307 -24.779532) (xy 357.683816 -24.807418) (xy 357.683307 -24.835304) (xy 357.675187 -24.89048)
			(xy 357.659119 -24.943887) (xy 357.635447 -24.994384) (xy 357.604674 -25.040897) (xy 357.567457 -25.082434)
			(xy 357.524589 -25.118109) (xy 357.476983 -25.147163) (xy 357.425654 -25.168975) (xy 357.371697 -25.183081)
			(xy 357.31626 -25.189181) (xy 357.260526 -25.187144) (xy 357.205683 -25.177014) (xy 357.152899 -25.159007)
			(xy 357.103299 -25.133506) (xy 357.057941 -25.101055) (xy 357.017792 -25.062346) (xy 356.983706 -25.018203)
			(xy 356.95641 -24.969568) (xy 356.936487 -24.917477) (xy 356.924361 -24.86304) (xy 356.92029 -24.807418)
			(xy 355.4349 -24.807418) (xy 355.434391 -24.835304) (xy 355.426271 -24.89048) (xy 355.410203 -24.943887)
			(xy 355.386531 -24.994384) (xy 355.355758 -25.040897) (xy 355.318541 -25.082434) (xy 355.275673 -25.118109)
			(xy 355.228067 -25.147163) (xy 355.176738 -25.168975) (xy 355.122781 -25.183081) (xy 355.067344 -25.189181)
			(xy 355.01161 -25.187144) (xy 354.956767 -25.177014) (xy 354.903983 -25.159007) (xy 354.854383 -25.133506)
			(xy 354.809025 -25.101055) (xy 354.768876 -25.062346) (xy 354.73479 -25.018203) (xy 354.707494 -24.969568)
			(xy 354.687571 -24.917477) (xy 354.675445 -24.86304) (xy 354.671374 -24.807418) (xy 347.9362 -24.807418)
			(xy 347.895735 -24.81756) (xy 347.824415 -24.826385) (xy 347.788484 -24.826976) (xy 332.694534 -24.826976)
			(xy 332.658598 -24.826437) (xy 332.587264 -24.817651) (xy 332.517544 -24.800194) (xy 332.450487 -24.77433)
			(xy 332.387102 -24.740448) (xy 332.328344 -24.699058) (xy 332.301342 -24.675338) (xy 332.294118 -24.669367)
			(xy 332.276666 -24.662577) (xy 332.267306 -24.66213) (xy 331.98181 -24.66213) (xy 331.971738 -24.66171)
			(xy 331.953128 -24.654001) (xy 331.945742 -24.647144) (xy 331.9018 -24.603202) (xy 331.894645 -24.596692)
			(xy 331.87687 -24.589101) (xy 331.857548 -24.588601) (xy 331.839404 -24.595261) (xy 331.83195 -24.601424)
			(xy 331.830172 -24.603202) (xy 331.825387 -24.608211) (xy 331.818428 -24.620184) (xy 331.816456 -24.626824)
			(xy 331.814932 -24.633174) (xy 331.814932 -24.646382) (xy 331.816964 -24.65324) (xy 331.823949 -24.679031)
			(xy 331.831464 -24.731934) (xy 331.83195 -24.75865) (xy 331.831464 -24.785901) (xy 331.823708 -24.839849)
			(xy 331.808353 -24.892144) (xy 331.785711 -24.941721) (xy 331.756245 -24.987571) (xy 331.720554 -25.028762)
			(xy 331.679363 -25.064453) (xy 331.633513 -25.093919) (xy 331.583936 -25.116561) (xy 331.531641 -25.131916)
			(xy 331.477693 -25.139672) (xy 331.423191 -25.139672) (xy 331.369243 -25.131916) (xy 331.316948 -25.116561)
			(xy 331.267371 -25.093919) (xy 331.221521 -25.064453) (xy 331.18033 -25.028762) (xy 331.144639 -24.987571)
			(xy 331.115173 -24.941721) (xy 331.092531 -24.892144) (xy 331.077176 -24.839849) (xy 331.06942 -24.785901)
			(xy 331.068934 -24.75865) (xy 331.069407 -24.73163) (xy 331.077038 -24.678132) (xy 331.092142 -24.626246)
			(xy 331.114415 -24.57701) (xy 331.143411 -24.531408) (xy 331.178552 -24.490354) (xy 331.219134 -24.454669)
			(xy 331.264344 -24.425067) (xy 331.313279 -24.40214) (xy 331.36496 -24.386346) (xy 331.418351 -24.378002)
			(xy 331.445362 -24.377142) (xy 331.450188 -24.376888) (xy 331.46238 -24.368252) (xy 331.468295 -24.36372)
			(xy 331.477459 -24.351978) (xy 331.480414 -24.345138) (xy 331.514196 -24.258524) (xy 331.515212 -24.25573)
			(xy 331.517646 -24.246782) (xy 331.516672 -24.228277) (xy 331.509232 -24.211306) (xy 331.50302 -24.204422)
			(xy 331.502766 -24.204168) (xy 327.16851 -19.869912) (xy 327.159662 -19.862003) (xy 327.137147 -19.854591)
			(xy 327.12533 -19.855688) (xy 327.071736 -19.865594) (xy 327.041002 -19.871182) (xy 327.034924 -19.87247)
			(xy 327.023619 -19.877612) (xy 327.01865 -19.881342) (xy 327.014078 -19.884898) (xy 327.006458 -19.894804)
			(xy 327.003918 -19.900646) (xy 326.990322 -19.929575) (xy 326.954952 -19.982813) (xy 326.93356 -20.006564)
			(xy 326.926956 -20.013676) (xy 326.923654 -20.022058) (xy 326.921895 -20.026624) (xy 326.919967 -20.036217)
			(xy 326.919844 -20.041108) (xy 326.919844 -20.110704) (xy 326.919986 -20.115593) (xy 326.921915 -20.125182)
			(xy 326.923654 -20.129754) (xy 326.926956 -20.138136) (xy 326.93356 -20.145248) (xy 326.952831 -20.166574)
			(xy 326.985397 -20.213936) (xy 327.010489 -20.265648) (xy 327.027539 -20.320538) (xy 327.036161 -20.377366)
			(xy 327.03616 -20.434843) (xy 327.027537 -20.49167) (xy 327.010485 -20.54656) (xy 326.985392 -20.598271)
			(xy 326.952826 -20.645632) (xy 326.93356 -20.666964) (xy 326.926956 -20.674076) (xy 326.923654 -20.682458)
			(xy 326.921895 -20.687024) (xy 326.919967 -20.696617) (xy 326.919844 -20.701508) (xy 326.919844 -20.771104)
			(xy 326.919986 -20.775993) (xy 326.921915 -20.785582) (xy 326.923654 -20.790154) (xy 326.926956 -20.798536)
			(xy 326.93356 -20.805648) (xy 326.952831 -20.826974) (xy 326.985397 -20.874336) (xy 327.010489 -20.926048)
			(xy 327.027539 -20.980938) (xy 327.036161 -21.037766) (xy 327.03616 -21.095243) (xy 327.027537 -21.15207)
			(xy 327.010485 -21.20696) (xy 326.985392 -21.258671) (xy 326.952826 -21.306032) (xy 326.93356 -21.327364)
			(xy 326.926956 -21.334476) (xy 326.923654 -21.342858) (xy 326.921895 -21.347424) (xy 326.919967 -21.357017)
			(xy 326.919844 -21.361908) (xy 326.919844 -21.431504) (xy 326.919986 -21.436393) (xy 326.921915 -21.445982)
			(xy 326.923654 -21.450554) (xy 326.926956 -21.458936) (xy 326.93356 -21.466048) (xy 326.952827 -21.487377)
			(xy 326.985384 -21.534741) (xy 327.010469 -21.586454) (xy 327.027515 -21.641343) (xy 327.036134 -21.698168)
			(xy 327.036684 -21.726906) (xy 327.036198 -21.754157) (xy 327.028442 -21.808105) (xy 327.013087 -21.8604)
			(xy 326.990445 -21.909977) (xy 326.960979 -21.955827) (xy 326.925288 -21.997018) (xy 326.884097 -22.032709)
			(xy 326.838247 -22.062175) (xy 326.78867 -22.084817) (xy 326.736375 -22.100172) (xy 326.682427 -22.107928)
			(xy 326.627925 -22.107928) (xy 326.573977 -22.100172) (xy 326.521682 -22.084817) (xy 326.472105 -22.062175)
			(xy 326.426255 -22.032709) (xy 326.385064 -21.997018) (xy 326.349373 -21.955827) (xy 326.319907 -21.909977)
			(xy 326.297265 -21.8604) (xy 326.28191 -21.808105) (xy 326.274154 -21.754157) (xy 326.273668 -21.726906)
			(xy 326.274189 -21.698167) (xy 326.282812 -21.64134) (xy 326.299864 -21.58645) (xy 326.324959 -21.53474)
			(xy 326.357528 -21.487381) (xy 326.376792 -21.466048) (xy 326.383396 -21.458936) (xy 326.386698 -21.450554)
			(xy 326.388457 -21.445988) (xy 326.390384 -21.436395) (xy 326.390508 -21.431504) (xy 326.390508 -21.361908)
			(xy 326.390368 -21.357018) (xy 326.388443 -21.347428) (xy 326.386698 -21.342858) (xy 326.383396 -21.334476)
			(xy 326.376792 -21.327364) (xy 326.357522 -21.306036) (xy 326.324959 -21.258673) (xy 326.299868 -21.206961)
			(xy 326.282819 -21.15207) (xy 326.274197 -21.095243) (xy 326.274196 -21.037766) (xy 326.282817 -20.980938)
			(xy 326.299865 -20.926047) (xy 326.324954 -20.874334) (xy 326.357517 -20.82697) (xy 326.376792 -20.805648)
			(xy 326.383396 -20.798536) (xy 326.386698 -20.790154) (xy 326.388457 -20.785588) (xy 326.390384 -20.775995)
			(xy 326.390508 -20.771104) (xy 326.390508 -20.701508) (xy 326.390368 -20.696618) (xy 326.388443 -20.687028)
			(xy 326.386698 -20.682458) (xy 326.383396 -20.674076) (xy 326.376792 -20.666964) (xy 326.357522 -20.645636)
			(xy 326.324959 -20.598273) (xy 326.299868 -20.546561) (xy 326.282819 -20.49167) (xy 326.274197 -20.434843)
			(xy 326.274196 -20.377366) (xy 326.282817 -20.320538) (xy 326.299865 -20.265647) (xy 326.324954 -20.213934)
			(xy 326.357517 -20.16657) (xy 326.376792 -20.145248) (xy 326.383396 -20.138136) (xy 326.386698 -20.129754)
			(xy 326.388457 -20.125188) (xy 326.390384 -20.115595) (xy 326.390508 -20.110704) (xy 326.390508 -20.041108)
			(xy 326.390368 -20.036218) (xy 326.388443 -20.026628) (xy 326.386698 -20.022058) (xy 326.383396 -20.013676)
			(xy 326.376792 -20.006564) (xy 326.357522 -19.985236) (xy 326.324959 -19.937873) (xy 326.299868 -19.886161)
			(xy 326.282819 -19.83127) (xy 326.274197 -19.774443) (xy 326.274196 -19.716966) (xy 326.282817 -19.660138)
			(xy 326.299865 -19.605247) (xy 326.324954 -19.553534) (xy 326.357517 -19.50617) (xy 326.376792 -19.484848)
			(xy 326.383396 -19.477736) (xy 326.386698 -19.469354) (xy 326.388457 -19.464788) (xy 326.390384 -19.455195)
			(xy 326.390508 -19.450304) (xy 326.390508 -19.434556) (xy 326.390012 -19.424554) (xy 326.382345 -19.406076)
			(xy 326.368194 -19.391935) (xy 326.349711 -19.384281) (xy 326.339708 -19.383756) (xy 326.331326 -19.383756)
			(xy 326.315324 -19.38909) (xy 326.30872 -19.394424) (xy 326.283103 -19.413591) (xy 326.228439 -19.446842)
			(xy 326.170474 -19.473934) (xy 326.109901 -19.494541) (xy 326.047442 -19.50842) (xy 325.983841 -19.515403)
			(xy 325.95185 -19.515836) (xy 323.25183 -19.515836) (xy 323.218976 -19.515377) (xy 323.153679 -19.508024)
			(xy 323.089617 -19.493407) (xy 323.027594 -19.47171) (xy 322.96839 -19.443205) (xy 322.912749 -19.408251)
			(xy 322.861371 -19.367288) (xy 322.83781 -19.344386) (xy 322.579238 -19.085814) (xy 322.571837 -19.078976)
			(xy 322.553238 -19.071262) (xy 322.54317 -19.070828) (xy 319.123822 -19.070828) (xy 319.11925 -19.071082)
			(xy 319.110286 -19.072261) (xy 319.09397 -19.080024) (xy 319.081342 -19.092948) (xy 319.07734 -19.101054)
			(xy 319.04051 -19.187668) (xy 319.03781 -19.194636) (xy 319.036146 -19.20948) (xy 319.037208 -19.216878)
			(xy 319.037208 -19.217132) (xy 319.038793 -19.224296) (xy 319.045502 -19.237338) (xy 319.050416 -19.242786)
			(xy 319.05067 -19.24304) (xy 319.094108 -19.288699) (xy 319.176144 -19.384386) (xy 319.252388 -19.484749)
			(xy 319.322575 -19.589437) (xy 319.38646 -19.698085) (xy 319.44382 -19.810315) (xy 319.494456 -19.925735)
			(xy 319.53819 -20.043943) (xy 319.574871 -20.164527) (xy 319.604369 -20.287065) (xy 319.626584 -20.411131)
			(xy 319.641436 -20.536291) (xy 319.648874 -20.662111) (xy 319.649348 -20.72513) (xy 319.648842 -20.790866)
			(xy 319.640749 -20.922087) (xy 319.624592 -21.052562) (xy 319.600435 -21.181795) (xy 319.568367 -21.309295)
			(xy 319.528511 -21.434579) (xy 319.481018 -21.557173) (xy 319.426069 -21.67661) (xy 319.36387 -21.792437)
			(xy 319.29466 -21.904216) (xy 319.218699 -22.011523) (xy 319.136277 -22.113949) (xy 319.047705 -22.211108)
			(xy 318.95332 -22.302629) (xy 318.853481 -22.388167) (xy 318.748564 -22.467396) (xy 318.63897 -22.540016)
			(xy 318.525112 -22.605751) (xy 318.407424 -22.664353) (xy 318.286352 -22.715599) (xy 318.162354 -22.759294)
			(xy 318.035902 -22.795273) (xy 317.907474 -22.823399) (xy 317.777559 -22.843565) (xy 317.646649 -22.855696)
			(xy 317.51524 -22.859745) (xy 317.383831 -22.855696) (xy 317.252921 -22.843565) (xy 317.123006 -22.823399)
			(xy 316.994578 -22.795273) (xy 316.868126 -22.759294) (xy 316.744128 -22.715599) (xy 316.623056 -22.664353)
			(xy 316.505368 -22.605751) (xy 316.39151 -22.540016) (xy 316.281916 -22.467396) (xy 316.176999 -22.388167)
			(xy 316.07716 -22.302629) (xy 315.982775 -22.211108) (xy 315.894203 -22.113949) (xy 315.811781 -22.011523)
			(xy 315.73582 -21.904216) (xy 315.66661 -21.792437) (xy 315.604411 -21.67661) (xy 315.549462 -21.557173)
			(xy 315.501969 -21.434579) (xy 315.462113 -21.309295) (xy 315.430045 -21.181795) (xy 315.405888 -21.052562)
			(xy 315.389731 -20.922087) (xy 315.381638 -20.790866) (xy 315.381132 -20.72513) (xy 315.381593 -20.66211)
			(xy 315.389031 -20.53629) (xy 315.403883 -20.411128) (xy 315.426097 -20.287062) (xy 315.455595 -20.164522)
			(xy 315.492276 -20.043938) (xy 315.53601 -19.925729) (xy 315.586646 -19.810308) (xy 315.644006 -19.698077)
			(xy 315.707891 -19.589427) (xy 315.778078 -19.484738) (xy 315.854322 -19.384375) (xy 315.936358 -19.288687)
			(xy 315.97981 -19.24304) (xy 315.980064 -19.242786) (xy 315.984918 -19.237295) (xy 315.991628 -19.224273)
			(xy 315.993272 -19.217132) (xy 315.993272 -19.216878) (xy 315.994364 -19.209481) (xy 315.992695 -19.19463)
			(xy 315.98997 -19.187668) (xy 315.95314 -19.101054) (xy 315.949158 -19.092927) (xy 315.936551 -19.07996)
			(xy 315.920209 -19.072213) (xy 315.91123 -19.071082) (xy 315.906658 -19.070828) (xy 307.377592 -19.070828)
			(xy 307.367606 -19.071367) (xy 307.349178 -19.079086) (xy 307.341778 -19.085814) (xy 307.282088 -19.145504)
			(xy 307.271047 -19.156254) (xy 307.247257 -19.175844) (xy 307.23459 -19.18462) (xy 307.227224 -19.189446)
			(xy 307.211476 -19.210782) (xy 307.208807 -19.214496) (xy 307.204711 -19.222672) (xy 307.203348 -19.227038)
			(xy 307.196744 -19.249898) (xy 307.19522 -19.26209) (xy 307.199284 -19.279362) (xy 307.20284 -19.289522)
			(xy 307.214456 -19.315166) (xy 307.230857 -19.369018) (xy 307.23916 -19.424697) (xy 307.23967 -19.452844)
			(xy 307.23967 -19.457924) (xy 307.238858 -19.48495) (xy 307.230548 -19.538377) (xy 307.214779 -19.590095)
			(xy 307.191867 -19.639068) (xy 307.16227 -19.684317) (xy 307.126581 -19.724934) (xy 307.085516 -19.760106)
			(xy 307.039897 -19.789128) (xy 306.990637 -19.811419) (xy 306.938723 -19.826533) (xy 306.885196 -19.834166)
			(xy 306.831128 -19.834166) (xy 306.777601 -19.826533) (xy 306.725687 -19.811419) (xy 306.676427 -19.789128)
			(xy 306.630808 -19.760106) (xy 306.589743 -19.724934) (xy 306.554054 -19.684317) (xy 306.524457 -19.639068)
			(xy 306.501545 -19.590095) (xy 306.485776 -19.538377) (xy 306.477466 -19.48495) (xy 306.476654 -19.457924)
			(xy 306.476654 -19.452844) (xy 306.477175 -19.424697) (xy 306.485477 -19.369019) (xy 306.501864 -19.315163)
			(xy 306.513484 -19.289522) (xy 306.51704 -19.279362) (xy 306.521104 -19.26209) (xy 306.51958 -19.249898)
			(xy 306.512976 -19.227038) (xy 306.5116 -19.222677) (xy 306.507507 -19.214502) (xy 306.504848 -19.210782)
			(xy 306.4891 -19.189446) (xy 306.481734 -19.18462) (xy 306.469055 -19.17586) (xy 306.445267 -19.156265)
			(xy 306.434236 -19.145504) (xy 306.374292 -19.08556) (xy 306.366933 -19.078917) (xy 306.348633 -19.071346)
			(xy 306.338732 -19.070828) (xy 306.009802 -19.070828) (xy 305.999732 -19.071251) (xy 305.98113 -19.078968)
			(xy 305.973734 -19.085814) (xy 305.915568 -19.14398) (xy 305.892014 -19.166927) (xy 305.840615 -19.20795)
			(xy 305.784945 -19.242956) (xy 305.725702 -19.271504) (xy 305.663635 -19.293236) (xy 305.599523 -19.307878)
			(xy 305.534175 -19.315245) (xy 305.501294 -19.315684) (xy 301.211234 -19.315684) (xy 301.173409 -19.315071)
			(xy 301.098392 -19.305303) (xy 301.025252 -19.285977) (xy 300.99 -19.27225) (xy 300.980602 -19.26844)
			(xy 300.927262 -19.26844) (xy 300.924722 -19.27098) (xy 300.923706 -19.273774) (xy 300.92195 -19.278341)
			(xy 300.920027 -19.287933) (xy 300.919896 -19.292824) (xy 300.919896 -19.36242) (xy 300.92003 -19.367311)
			(xy 300.921942 -19.376906) (xy 300.923706 -19.38147) (xy 300.927008 -19.389852) (xy 300.933612 -19.396964)
			(xy 300.95288 -19.418292) (xy 300.985439 -19.465654) (xy 301.010525 -19.517365) (xy 301.02757 -19.572254)
			(xy 301.036189 -19.629079) (xy 301.036186 -19.686553) (xy 301.027563 -19.743377) (xy 301.010513 -19.798265)
			(xy 300.985422 -19.849973) (xy 300.952859 -19.897334) (xy 300.933612 -19.91868) (xy 300.927008 -19.925792)
			(xy 300.923706 -19.934174) (xy 300.92195 -19.938741) (xy 300.920027 -19.948333) (xy 300.919896 -19.953224)
			(xy 300.919896 -20.02282) (xy 300.92003 -20.027711) (xy 300.921942 -20.037306) (xy 300.923706 -20.04187)
			(xy 300.927008 -20.050252) (xy 300.933612 -20.057364) (xy 300.95288 -20.078692) (xy 300.985439 -20.126054)
			(xy 301.010525 -20.177765) (xy 301.02757 -20.232654) (xy 301.036189 -20.289479) (xy 301.036186 -20.346953)
			(xy 301.027563 -20.403777) (xy 301.010513 -20.458665) (xy 301.00619 -20.467574) (xy 308.487316 -20.467574)
			(xy 308.491387 -20.411952) (xy 308.503513 -20.357515) (xy 308.523436 -20.305424) (xy 308.550732 -20.256789)
			(xy 308.584818 -20.212646) (xy 308.624967 -20.173937) (xy 308.670325 -20.141486) (xy 308.719925 -20.115985)
			(xy 308.772709 -20.097978) (xy 308.827552 -20.087848) (xy 308.883286 -20.085811) (xy 308.938723 -20.091911)
			(xy 308.99268 -20.106017) (xy 309.044009 -20.127829) (xy 309.091615 -20.156883) (xy 309.134483 -20.192558)
			(xy 309.1717 -20.234095) (xy 309.202473 -20.280608) (xy 309.226145 -20.331105) (xy 309.242213 -20.384512)
			(xy 309.250333 -20.439688) (xy 309.250842 -20.467574) (xy 309.250333 -20.49546) (xy 309.242213 -20.550636)
			(xy 309.226145 -20.604043) (xy 309.202473 -20.65454) (xy 309.1717 -20.701053) (xy 309.134483 -20.74259)
			(xy 309.091615 -20.778265) (xy 309.044009 -20.807319) (xy 308.99268 -20.829131) (xy 308.938723 -20.843237)
			(xy 308.883286 -20.849337) (xy 308.827552 -20.8473) (xy 308.772709 -20.83717) (xy 308.719925 -20.819163)
			(xy 308.670325 -20.793662) (xy 308.624967 -20.761211) (xy 308.584818 -20.722502) (xy 308.550732 -20.678359)
			(xy 308.523436 -20.629724) (xy 308.503513 -20.577633) (xy 308.491387 -20.523196) (xy 308.487316 -20.467574)
			(xy 301.00619 -20.467574) (xy 300.985422 -20.510373) (xy 300.952859 -20.557734) (xy 300.933612 -20.57908)
			(xy 300.927008 -20.586192) (xy 300.923706 -20.594574) (xy 300.92195 -20.599141) (xy 300.920027 -20.608733)
			(xy 300.919896 -20.613624) (xy 300.919896 -20.68322) (xy 300.92003 -20.688111) (xy 300.921942 -20.697706)
			(xy 300.923706 -20.70227) (xy 300.927008 -20.710652) (xy 300.933612 -20.717764) (xy 300.95288 -20.739092)
			(xy 300.985439 -20.786454) (xy 301.010525 -20.838165) (xy 301.02757 -20.893054) (xy 301.036189 -20.949879)
			(xy 301.036186 -21.007353) (xy 301.027563 -21.064177) (xy 301.010513 -21.119065) (xy 300.985422 -21.170773)
			(xy 300.952859 -21.218134) (xy 300.933612 -21.23948) (xy 300.927008 -21.246592) (xy 300.923706 -21.254974)
			(xy 300.92195 -21.259541) (xy 300.920027 -21.269133) (xy 300.919896 -21.274024) (xy 300.919896 -21.34362)
			(xy 300.92003 -21.348511) (xy 300.921942 -21.358106) (xy 300.923706 -21.36267) (xy 300.927008 -21.371052)
			(xy 300.933612 -21.378164) (xy 300.95288 -21.399492) (xy 300.985439 -21.446856) (xy 301.010526 -21.498568)
			(xy 301.027571 -21.553458) (xy 301.036189 -21.610284) (xy 301.036736 -21.639022) (xy 301.03625 -21.666273)
			(xy 301.028494 -21.720221) (xy 301.013139 -21.772516) (xy 301.011697 -21.775674) (xy 310.135776 -21.775674)
			(xy 310.139847 -21.720052) (xy 310.151973 -21.665615) (xy 310.171896 -21.613524) (xy 310.199192 -21.564889)
			(xy 310.233278 -21.520746) (xy 310.273427 -21.482037) (xy 310.318785 -21.449586) (xy 310.368385 -21.424085)
			(xy 310.421169 -21.406078) (xy 310.476012 -21.395948) (xy 310.531746 -21.393911) (xy 310.587183 -21.400011)
			(xy 310.64114 -21.414117) (xy 310.692469 -21.435929) (xy 310.740075 -21.464983) (xy 310.782943 -21.500658)
			(xy 310.82016 -21.542195) (xy 310.850933 -21.588708) (xy 310.874605 -21.639205) (xy 310.890673 -21.692612)
			(xy 310.898793 -21.747788) (xy 310.899302 -21.775674) (xy 310.898793 -21.80356) (xy 310.891122 -21.855684)
			(xy 311.038492 -21.855684) (xy 311.042563 -21.800062) (xy 311.054689 -21.745625) (xy 311.074612 -21.693534)
			(xy 311.101908 -21.644899) (xy 311.135994 -21.600756) (xy 311.176143 -21.562047) (xy 311.221501 -21.529596)
			(xy 311.271101 -21.504095) (xy 311.323885 -21.486088) (xy 311.378728 -21.475958) (xy 311.434462 -21.473921)
			(xy 311.489899 -21.480021) (xy 311.543856 -21.494127) (xy 311.595185 -21.515939) (xy 311.642791 -21.544993)
			(xy 311.685659 -21.580668) (xy 311.722876 -21.622205) (xy 311.753649 -21.668718) (xy 311.777321 -21.719215)
			(xy 311.793389 -21.772622) (xy 311.801509 -21.827798) (xy 311.80186 -21.847048) (xy 312.272678 -21.847048)
			(xy 312.276749 -21.791426) (xy 312.288875 -21.736989) (xy 312.308798 -21.684898) (xy 312.336094 -21.636263)
			(xy 312.37018 -21.59212) (xy 312.410329 -21.553411) (xy 312.455687 -21.52096) (xy 312.505287 -21.495459)
			(xy 312.558071 -21.477452) (xy 312.612914 -21.467322) (xy 312.668648 -21.465285) (xy 312.724085 -21.471385)
			(xy 312.778042 -21.485491) (xy 312.829371 -21.507303) (xy 312.876977 -21.536357) (xy 312.919845 -21.572032)
			(xy 312.957062 -21.613569) (xy 312.987835 -21.660082) (xy 313.011507 -21.710579) (xy 313.027575 -21.763986)
			(xy 313.035695 -21.819162) (xy 313.036204 -21.847048) (xy 313.035695 -21.874934) (xy 313.027575 -21.93011)
			(xy 313.011507 -21.983517) (xy 312.987835 -22.034014) (xy 312.957062 -22.080527) (xy 312.919845 -22.122064)
			(xy 312.876977 -22.157739) (xy 312.829371 -22.186793) (xy 312.778042 -22.208605) (xy 312.724085 -22.222711)
			(xy 312.668648 -22.228811) (xy 312.612914 -22.226774) (xy 312.558071 -22.216644) (xy 312.505287 -22.198637)
			(xy 312.455687 -22.173136) (xy 312.410329 -22.140685) (xy 312.37018 -22.101976) (xy 312.336094 -22.057833)
			(xy 312.308798 -22.009198) (xy 312.288875 -21.957107) (xy 312.276749 -21.90267) (xy 312.272678 -21.847048)
			(xy 311.80186 -21.847048) (xy 311.802018 -21.855684) (xy 311.801509 -21.88357) (xy 311.793389 -21.938746)
			(xy 311.777321 -21.992153) (xy 311.753649 -22.04265) (xy 311.722876 -22.089163) (xy 311.685659 -22.1307)
			(xy 311.642791 -22.166375) (xy 311.595185 -22.195429) (xy 311.543856 -22.217241) (xy 311.489899 -22.231347)
			(xy 311.434462 -22.237447) (xy 311.378728 -22.23541) (xy 311.323885 -22.22528) (xy 311.271101 -22.207273)
			(xy 311.221501 -22.181772) (xy 311.176143 -22.149321) (xy 311.135994 -22.110612) (xy 311.101908 -22.066469)
			(xy 311.074612 -22.017834) (xy 311.054689 -21.965743) (xy 311.042563 -21.911306) (xy 311.038492 -21.855684)
			(xy 310.891122 -21.855684) (xy 310.890673 -21.858736) (xy 310.874605 -21.912143) (xy 310.850933 -21.96264)
			(xy 310.82016 -22.009153) (xy 310.782943 -22.05069) (xy 310.740075 -22.086365) (xy 310.692469 -22.115419)
			(xy 310.64114 -22.137231) (xy 310.587183 -22.151337) (xy 310.531746 -22.157437) (xy 310.476012 -22.1554)
			(xy 310.421169 -22.14527) (xy 310.368385 -22.127263) (xy 310.318785 -22.101762) (xy 310.273427 -22.069311)
			(xy 310.233278 -22.030602) (xy 310.199192 -21.986459) (xy 310.171896 -21.937824) (xy 310.151973 -21.885733)
			(xy 310.139847 -21.831296) (xy 310.135776 -21.775674) (xy 301.011697 -21.775674) (xy 300.990497 -21.822093)
			(xy 300.961031 -21.867943) (xy 300.92534 -21.909134) (xy 300.884149 -21.944825) (xy 300.838299 -21.974291)
			(xy 300.788722 -21.996933) (xy 300.736427 -22.012288) (xy 300.682479 -22.020044) (xy 300.627977 -22.020044)
			(xy 300.574029 -22.012288) (xy 300.521734 -21.996933) (xy 300.472157 -21.974291) (xy 300.426307 -21.944825)
			(xy 300.385116 -21.909134) (xy 300.349425 -21.867943) (xy 300.319959 -21.822093) (xy 300.297317 -21.772516)
			(xy 300.281962 -21.720221) (xy 300.274206 -21.666273) (xy 300.27372 -21.639022) (xy 300.274239 -21.610282)
			(xy 300.282859 -21.553453) (xy 300.299908 -21.498561) (xy 300.324999 -21.446847) (xy 300.357564 -21.399483)
			(xy 300.376844 -21.378164) (xy 300.383448 -21.371052) (xy 300.38675 -21.36267) (xy 300.388503 -21.358103)
			(xy 300.390416 -21.34851) (xy 300.39056 -21.34362) (xy 300.39056 -21.274024) (xy 300.390421 -21.269134)
			(xy 300.388497 -21.259544) (xy 300.38675 -21.254974) (xy 300.383448 -21.246592) (xy 300.376844 -21.23948)
			(xy 300.357571 -21.218154) (xy 300.325 -21.170791) (xy 300.299904 -21.119078) (xy 300.28285 -21.064186)
			(xy 300.274225 -21.007356) (xy 300.274222 -20.949876) (xy 300.282843 -20.893045) (xy 300.299893 -20.838151)
			(xy 300.324984 -20.786437) (xy 300.35755 -20.739071) (xy 300.376844 -20.717764) (xy 300.383448 -20.710652)
			(xy 300.38675 -20.70227) (xy 300.388503 -20.697703) (xy 300.390416 -20.68811) (xy 300.39056 -20.68322)
			(xy 300.39056 -20.613624) (xy 300.390421 -20.608734) (xy 300.388497 -20.599144) (xy 300.38675 -20.594574)
			(xy 300.383448 -20.586192) (xy 300.376844 -20.57908) (xy 300.357571 -20.557754) (xy 300.325 -20.510391)
			(xy 300.299904 -20.458678) (xy 300.28285 -20.403786) (xy 300.274225 -20.346956) (xy 300.274222 -20.289476)
			(xy 300.282843 -20.232645) (xy 300.299893 -20.177751) (xy 300.324984 -20.126037) (xy 300.35755 -20.078671)
			(xy 300.376844 -20.057364) (xy 300.383448 -20.050252) (xy 300.38675 -20.04187) (xy 300.388503 -20.037303)
			(xy 300.390416 -20.02771) (xy 300.39056 -20.02282) (xy 300.39056 -19.953224) (xy 300.390421 -19.948334)
			(xy 300.388497 -19.938744) (xy 300.38675 -19.934174) (xy 300.383448 -19.925792) (xy 300.376844 -19.91868)
			(xy 300.359061 -19.899041) (xy 300.328532 -19.855741) (xy 300.30429 -19.808632) (xy 300.286803 -19.758622)
			(xy 300.276406 -19.706671) (xy 300.2733 -19.653782) (xy 300.277546 -19.600973) (xy 300.282864 -19.575018)
			(xy 300.282864 -19.574002) (xy 300.284134 -19.568414) (xy 300.274482 -19.541744) (xy 300.193456 -19.476212)
			(xy 300.186073 -19.470721) (xy 300.16863 -19.46491) (xy 300.150258 -19.465623) (xy 300.14164 -19.468846)
			(xy 300.105059 -19.483844) (xy 300.028874 -19.504977) (xy 299.950538 -19.515668) (xy 299.911008 -19.516344)
			(xy 297.268646 -19.516344) (xy 297.235769 -19.515865) (xy 297.170432 -19.50847) (xy 297.106332 -19.493813)
			(xy 297.044274 -19.472078) (xy 296.985036 -19.443537) (xy 296.929363 -19.40855) (xy 296.877953 -19.367554)
			(xy 296.854372 -19.34464) (xy 296.595546 -19.085814) (xy 296.588145 -19.078974) (xy 296.569547 -19.071257)
			(xy 296.559478 -19.070828) (xy 293.12362 -19.070828) (xy 293.119048 -19.071082) (xy 293.110084 -19.072261)
			(xy 293.093769 -19.080025) (xy 293.081142 -19.092948) (xy 293.077138 -19.101054) (xy 293.040308 -19.187668)
			(xy 293.037608 -19.194636) (xy 293.035944 -19.20948) (xy 293.037006 -19.216878) (xy 293.037006 -19.217132)
			(xy 293.038591 -19.224296) (xy 293.0453 -19.237338) (xy 293.050214 -19.242786) (xy 293.050468 -19.24304)
			(xy 293.093906 -19.288699) (xy 293.175942 -19.384386) (xy 293.252186 -19.484749) (xy 293.322373 -19.589437)
			(xy 293.386258 -19.698085) (xy 293.443619 -19.810315) (xy 293.494254 -19.925735) (xy 293.537989 -20.043943)
			(xy 293.574669 -20.164527) (xy 293.604168 -20.287065) (xy 293.626382 -20.411131) (xy 293.641234 -20.536291)
			(xy 293.648672 -20.662111) (xy 293.649146 -20.72513) (xy 293.64864 -20.790866) (xy 293.640547 -20.922087)
			(xy 293.62439 -21.052562) (xy 293.600233 -21.181795) (xy 293.568165 -21.309295) (xy 293.528309 -21.434579)
			(xy 293.480816 -21.557173) (xy 293.425867 -21.67661) (xy 293.363668 -21.792437) (xy 293.294458 -21.904216)
			(xy 293.218497 -22.011523) (xy 293.136075 -22.113949) (xy 293.047503 -22.211108) (xy 292.953118 -22.302629)
			(xy 292.853279 -22.388167) (xy 292.748362 -22.467396) (xy 292.638768 -22.540016) (xy 292.612028 -22.555454)
			(xy 309.536336 -22.555454) (xy 309.540407 -22.499832) (xy 309.552533 -22.445395) (xy 309.572456 -22.393304)
			(xy 309.599752 -22.344669) (xy 309.633838 -22.300526) (xy 309.673987 -22.261817) (xy 309.719345 -22.229366)
			(xy 309.768945 -22.203865) (xy 309.821729 -22.185858) (xy 309.876572 -22.175728) (xy 309.932306 -22.173691)
			(xy 309.987743 -22.179791) (xy 310.0417 -22.193897) (xy 310.093029 -22.215709) (xy 310.140635 -22.244763)
			(xy 310.183503 -22.280438) (xy 310.22072 -22.321975) (xy 310.251493 -22.368488) (xy 310.275165 -22.418985)
			(xy 310.291233 -22.472392) (xy 310.299353 -22.527568) (xy 310.299862 -22.555454) (xy 310.299353 -22.58334)
			(xy 310.291233 -22.638516) (xy 310.275165 -22.691923) (xy 310.251493 -22.74242) (xy 310.22072 -22.788933)
			(xy 310.183503 -22.83047) (xy 310.140635 -22.866145) (xy 310.093029 -22.895199) (xy 310.0417 -22.917011)
			(xy 309.987743 -22.931117) (xy 309.932306 -22.937217) (xy 309.876572 -22.93518) (xy 309.821729 -22.92505)
			(xy 309.768945 -22.907043) (xy 309.719345 -22.881542) (xy 309.673987 -22.849091) (xy 309.633838 -22.810382)
			(xy 309.599752 -22.766239) (xy 309.572456 -22.717604) (xy 309.552533 -22.665513) (xy 309.540407 -22.611076)
			(xy 309.536336 -22.555454) (xy 292.612028 -22.555454) (xy 292.52491 -22.605751) (xy 292.407222 -22.664353)
			(xy 292.28615 -22.715599) (xy 292.162152 -22.759294) (xy 292.0357 -22.795273) (xy 291.907272 -22.823399)
			(xy 291.777357 -22.843565) (xy 291.646447 -22.855696) (xy 291.515038 -22.859745) (xy 291.383629 -22.855696)
			(xy 291.252719 -22.843565) (xy 291.122804 -22.823399) (xy 290.994376 -22.795273) (xy 290.867924 -22.759294)
			(xy 290.743926 -22.715599) (xy 290.622854 -22.664353) (xy 290.505166 -22.605751) (xy 290.391308 -22.540016)
			(xy 290.281714 -22.467396) (xy 290.176797 -22.388167) (xy 290.076958 -22.302629) (xy 289.982573 -22.211108)
			(xy 289.894001 -22.113949) (xy 289.811579 -22.011523) (xy 289.735618 -21.904216) (xy 289.666408 -21.792437)
			(xy 289.604209 -21.67661) (xy 289.54926 -21.557173) (xy 289.501767 -21.434579) (xy 289.461911 -21.309295)
			(xy 289.429843 -21.181795) (xy 289.405686 -21.052562) (xy 289.389529 -20.922087) (xy 289.381436 -20.790866)
			(xy 289.38093 -20.72513) (xy 289.381391 -20.66211) (xy 289.388829 -20.53629) (xy 289.403681 -20.411128)
			(xy 289.425895 -20.287062) (xy 289.455393 -20.164522) (xy 289.492074 -20.043938) (xy 289.535808 -19.925729)
			(xy 289.586444 -19.810308) (xy 289.643804 -19.698077) (xy 289.707689 -19.589427) (xy 289.777876 -19.484738)
			(xy 289.85412 -19.384374) (xy 289.936155 -19.288686) (xy 289.979608 -19.24304) (xy 289.979862 -19.242786)
			(xy 289.984716 -19.237295) (xy 289.991426 -19.224274) (xy 289.99307 -19.217132) (xy 289.99307 -19.216878)
			(xy 289.994162 -19.209481) (xy 289.992493 -19.19463) (xy 289.989768 -19.187668) (xy 289.952938 -19.101054)
			(xy 289.948956 -19.092927) (xy 289.936349 -19.07996) (xy 289.920007 -19.072214) (xy 289.911028 -19.071082)
			(xy 289.906456 -19.070828) (xy 281.377644 -19.070828) (xy 281.367653 -19.071358) (xy 281.349213 -19.079063)
			(xy 281.34183 -19.085814) (xy 281.28214 -19.145504) (xy 281.271098 -19.156253) (xy 281.247306 -19.17584)
			(xy 281.234642 -19.18462) (xy 281.227276 -19.189446) (xy 281.211528 -19.210782) (xy 281.208861 -19.214497)
			(xy 281.204768 -19.222675) (xy 281.2034 -19.227038) (xy 281.196796 -19.249898) (xy 281.195272 -19.26209)
			(xy 281.199336 -19.279362) (xy 281.202892 -19.289522) (xy 281.214506 -19.315166) (xy 281.230905 -19.369019)
			(xy 281.239207 -19.424697) (xy 281.239722 -19.452844) (xy 281.239722 -19.457924) (xy 281.23891 -19.48495)
			(xy 281.2306 -19.538377) (xy 281.214831 -19.590095) (xy 281.191919 -19.639068) (xy 281.162322 -19.684317)
			(xy 281.126633 -19.724934) (xy 281.085568 -19.760106) (xy 281.039949 -19.789128) (xy 280.990689 -19.811419)
			(xy 280.938775 -19.826533) (xy 280.885248 -19.834166) (xy 280.83118 -19.834166) (xy 280.777653 -19.826533)
			(xy 280.725739 -19.811419) (xy 280.676479 -19.789128) (xy 280.63086 -19.760106) (xy 280.589795 -19.724934)
			(xy 280.554106 -19.684317) (xy 280.524509 -19.639068) (xy 280.501597 -19.590095) (xy 280.485828 -19.538377)
			(xy 280.477518 -19.48495) (xy 280.476706 -19.457924) (xy 280.476706 -19.452844) (xy 280.477227 -19.424698)
			(xy 280.48553 -19.36902) (xy 280.501919 -19.315165) (xy 280.513536 -19.289522) (xy 280.517092 -19.279362)
			(xy 280.521156 -19.26209) (xy 280.519632 -19.249898) (xy 280.513028 -19.227038) (xy 280.511651 -19.222678)
			(xy 280.507554 -19.214505) (xy 280.5049 -19.210782) (xy 280.489152 -19.189446) (xy 280.481786 -19.18462)
			(xy 280.469106 -19.175862) (xy 280.445315 -19.15627) (xy 280.434288 -19.145504) (xy 280.374344 -19.08556)
			(xy 280.366988 -19.078909) (xy 280.348688 -19.071319) (xy 280.338784 -19.070828) (xy 279.644602 -19.070828)
			(xy 279.634532 -19.071251) (xy 279.61593 -19.078968) (xy 279.608534 -19.085814) (xy 279.457658 -19.23669)
			(xy 279.434093 -19.259586) (xy 279.382709 -19.300538) (xy 279.327066 -19.335484) (xy 279.267862 -19.363985)
			(xy 279.205842 -19.385685) (xy 279.141784 -19.400309) (xy 279.076491 -19.407675) (xy 279.043638 -19.40814)
			(xy 275.3487 -19.40814) (xy 275.311453 -19.40754) (xy 275.237565 -19.398058) (xy 275.165475 -19.379287)
			(xy 275.096346 -19.351527) (xy 275.031294 -19.315228) (xy 275.000974 -19.293586) (xy 274.99437 -19.28876)
			(xy 274.97913 -19.28368) (xy 274.970748 -19.28368) (xy 274.960719 -19.284091) (xy 274.942182 -19.291752)
			(xy 274.92799 -19.305925) (xy 274.920305 -19.324451) (xy 274.919948 -19.33448) (xy 274.919948 -19.36242)
			(xy 274.920081 -19.367311) (xy 274.921992 -19.376907) (xy 274.923758 -19.38147) (xy 274.92706 -19.389852)
			(xy 274.933664 -19.396964) (xy 274.952934 -19.41829) (xy 274.985497 -19.465652) (xy 275.010586 -19.517363)
			(xy 275.027634 -19.572252) (xy 275.036254 -19.629078) (xy 275.036251 -19.686554) (xy 275.027626 -19.743379)
			(xy 275.010574 -19.798267) (xy 274.98548 -19.849976) (xy 274.952914 -19.897335) (xy 274.933664 -19.91868)
			(xy 274.92706 -19.925792) (xy 274.923758 -19.934174) (xy 274.922003 -19.938741) (xy 274.920082 -19.948333)
			(xy 274.919948 -19.953224) (xy 274.919948 -20.02282) (xy 274.920081 -20.027711) (xy 274.921992 -20.037307)
			(xy 274.923758 -20.04187) (xy 274.92706 -20.050252) (xy 274.933664 -20.057364) (xy 274.952934 -20.07869)
			(xy 274.985497 -20.126052) (xy 275.010586 -20.177763) (xy 275.027634 -20.232652) (xy 275.036254 -20.289478)
			(xy 275.036251 -20.346954) (xy 275.027626 -20.403779) (xy 275.010574 -20.458667) (xy 275.006251 -20.467574)
			(xy 282.487368 -20.467574) (xy 282.491439 -20.411952) (xy 282.503565 -20.357515) (xy 282.523488 -20.305424)
			(xy 282.550784 -20.256789) (xy 282.58487 -20.212646) (xy 282.625019 -20.173937) (xy 282.670377 -20.141486)
			(xy 282.719977 -20.115985) (xy 282.772761 -20.097978) (xy 282.827604 -20.087848) (xy 282.883338 -20.085811)
			(xy 282.938775 -20.091911) (xy 282.992732 -20.106017) (xy 283.044061 -20.127829) (xy 283.091667 -20.156883)
			(xy 283.134535 -20.192558) (xy 283.171752 -20.234095) (xy 283.202525 -20.280608) (xy 283.226197 -20.331105)
			(xy 283.242265 -20.384512) (xy 283.250385 -20.439688) (xy 283.250894 -20.467574) (xy 283.250385 -20.49546)
			(xy 283.242265 -20.550636) (xy 283.226197 -20.604043) (xy 283.202525 -20.65454) (xy 283.171752 -20.701053)
			(xy 283.134535 -20.74259) (xy 283.091667 -20.778265) (xy 283.044061 -20.807319) (xy 282.992732 -20.829131)
			(xy 282.938775 -20.843237) (xy 282.883338 -20.849337) (xy 282.827604 -20.8473) (xy 282.772761 -20.83717)
			(xy 282.719977 -20.819163) (xy 282.670377 -20.793662) (xy 282.625019 -20.761211) (xy 282.58487 -20.722502)
			(xy 282.550784 -20.678359) (xy 282.523488 -20.629724) (xy 282.503565 -20.577633) (xy 282.491439 -20.523196)
			(xy 282.487368 -20.467574) (xy 275.006251 -20.467574) (xy 274.98548 -20.510376) (xy 274.952914 -20.557735)
			(xy 274.933664 -20.57908) (xy 274.92706 -20.586192) (xy 274.923758 -20.594574) (xy 274.922003 -20.599141)
			(xy 274.920082 -20.608733) (xy 274.919948 -20.613624) (xy 274.919948 -20.68322) (xy 274.920081 -20.688111)
			(xy 274.921992 -20.697707) (xy 274.923758 -20.70227) (xy 274.92706 -20.710652) (xy 274.933664 -20.717764)
			(xy 274.952934 -20.73909) (xy 274.985497 -20.786452) (xy 275.010586 -20.838163) (xy 275.027634 -20.893052)
			(xy 275.036254 -20.949878) (xy 275.036251 -21.007354) (xy 275.027626 -21.064179) (xy 275.010574 -21.119067)
			(xy 274.98548 -21.170776) (xy 274.952914 -21.218135) (xy 274.933664 -21.23948) (xy 274.92706 -21.246592)
			(xy 274.923758 -21.254974) (xy 274.922003 -21.259541) (xy 274.920082 -21.269133) (xy 274.919948 -21.274024)
			(xy 274.919948 -21.34362) (xy 274.920081 -21.348511) (xy 274.921992 -21.358107) (xy 274.923758 -21.36267)
			(xy 274.92706 -21.371052) (xy 274.933664 -21.378164) (xy 274.952934 -21.399491) (xy 274.985498 -21.446854)
			(xy 275.010587 -21.498566) (xy 275.027634 -21.553456) (xy 275.036254 -21.610283) (xy 275.036788 -21.639022)
			(xy 275.036302 -21.666273) (xy 275.028546 -21.720221) (xy 275.013191 -21.772516) (xy 275.011749 -21.775674)
			(xy 284.135828 -21.775674) (xy 284.139899 -21.720052) (xy 284.152025 -21.665615) (xy 284.171948 -21.613524)
			(xy 284.199244 -21.564889) (xy 284.23333 -21.520746) (xy 284.273479 -21.482037) (xy 284.318837 -21.449586)
			(xy 284.368437 -21.424085) (xy 284.421221 -21.406078) (xy 284.476064 -21.395948) (xy 284.531798 -21.393911)
			(xy 284.587235 -21.400011) (xy 284.641192 -21.414117) (xy 284.692521 -21.435929) (xy 284.740127 -21.464983)
			(xy 284.782995 -21.500658) (xy 284.820212 -21.542195) (xy 284.850985 -21.588708) (xy 284.874657 -21.639205)
			(xy 284.890725 -21.692612) (xy 284.898845 -21.747788) (xy 284.899354 -21.775674) (xy 284.898845 -21.80356)
			(xy 284.891174 -21.855684) (xy 285.038544 -21.855684) (xy 285.042615 -21.800062) (xy 285.054741 -21.745625)
			(xy 285.074664 -21.693534) (xy 285.10196 -21.644899) (xy 285.136046 -21.600756) (xy 285.176195 -21.562047)
			(xy 285.221553 -21.529596) (xy 285.271153 -21.504095) (xy 285.323937 -21.486088) (xy 285.37878 -21.475958)
			(xy 285.434514 -21.473921) (xy 285.489951 -21.480021) (xy 285.543908 -21.494127) (xy 285.595237 -21.515939)
			(xy 285.642843 -21.544993) (xy 285.685711 -21.580668) (xy 285.722928 -21.622205) (xy 285.753701 -21.668718)
			(xy 285.777373 -21.719215) (xy 285.793441 -21.772622) (xy 285.801561 -21.827798) (xy 285.801912 -21.847048)
			(xy 286.27273 -21.847048) (xy 286.276801 -21.791426) (xy 286.288927 -21.736989) (xy 286.30885 -21.684898)
			(xy 286.336146 -21.636263) (xy 286.370232 -21.59212) (xy 286.410381 -21.553411) (xy 286.455739 -21.52096)
			(xy 286.505339 -21.495459) (xy 286.558123 -21.477452) (xy 286.612966 -21.467322) (xy 286.6687 -21.465285)
			(xy 286.724137 -21.471385) (xy 286.778094 -21.485491) (xy 286.829423 -21.507303) (xy 286.877029 -21.536357)
			(xy 286.919897 -21.572032) (xy 286.957114 -21.613569) (xy 286.987887 -21.660082) (xy 287.011559 -21.710579)
			(xy 287.027627 -21.763986) (xy 287.035747 -21.819162) (xy 287.036256 -21.847048) (xy 287.035747 -21.874934)
			(xy 287.027627 -21.93011) (xy 287.011559 -21.983517) (xy 286.987887 -22.034014) (xy 286.957114 -22.080527)
			(xy 286.919897 -22.122064) (xy 286.877029 -22.157739) (xy 286.829423 -22.186793) (xy 286.778094 -22.208605)
			(xy 286.724137 -22.222711) (xy 286.6687 -22.228811) (xy 286.612966 -22.226774) (xy 286.558123 -22.216644)
			(xy 286.505339 -22.198637) (xy 286.455739 -22.173136) (xy 286.410381 -22.140685) (xy 286.370232 -22.101976)
			(xy 286.336146 -22.057833) (xy 286.30885 -22.009198) (xy 286.288927 -21.957107) (xy 286.276801 -21.90267)
			(xy 286.27273 -21.847048) (xy 285.801912 -21.847048) (xy 285.80207 -21.855684) (xy 285.801561 -21.88357)
			(xy 285.793441 -21.938746) (xy 285.777373 -21.992153) (xy 285.753701 -22.04265) (xy 285.722928 -22.089163)
			(xy 285.685711 -22.1307) (xy 285.642843 -22.166375) (xy 285.595237 -22.195429) (xy 285.543908 -22.217241)
			(xy 285.489951 -22.231347) (xy 285.434514 -22.237447) (xy 285.37878 -22.23541) (xy 285.323937 -22.22528)
			(xy 285.271153 -22.207273) (xy 285.221553 -22.181772) (xy 285.176195 -22.149321) (xy 285.136046 -22.110612)
			(xy 285.10196 -22.066469) (xy 285.074664 -22.017834) (xy 285.054741 -21.965743) (xy 285.042615 -21.911306)
			(xy 285.038544 -21.855684) (xy 284.891174 -21.855684) (xy 284.890725 -21.858736) (xy 284.874657 -21.912143)
			(xy 284.850985 -21.96264) (xy 284.820212 -22.009153) (xy 284.782995 -22.05069) (xy 284.740127 -22.086365)
			(xy 284.692521 -22.115419) (xy 284.641192 -22.137231) (xy 284.587235 -22.151337) (xy 284.531798 -22.157437)
			(xy 284.476064 -22.1554) (xy 284.421221 -22.14527) (xy 284.368437 -22.127263) (xy 284.318837 -22.101762)
			(xy 284.273479 -22.069311) (xy 284.23333 -22.030602) (xy 284.199244 -21.986459) (xy 284.171948 -21.937824)
			(xy 284.152025 -21.885733) (xy 284.139899 -21.831296) (xy 284.135828 -21.775674) (xy 275.011749 -21.775674)
			(xy 274.990549 -21.822093) (xy 274.961083 -21.867943) (xy 274.925392 -21.909134) (xy 274.884201 -21.944825)
			(xy 274.838351 -21.974291) (xy 274.788774 -21.996933) (xy 274.736479 -22.012288) (xy 274.682531 -22.020044)
			(xy 274.628029 -22.020044) (xy 274.574081 -22.012288) (xy 274.521786 -21.996933) (xy 274.472209 -21.974291)
			(xy 274.426359 -21.944825) (xy 274.385168 -21.909134) (xy 274.349477 -21.867943) (xy 274.320011 -21.822093)
			(xy 274.297369 -21.772516) (xy 274.282014 -21.720221) (xy 274.274258 -21.666273) (xy 274.273772 -21.639022)
			(xy 274.274292 -21.610283) (xy 274.282913 -21.553455) (xy 274.299963 -21.498563) (xy 274.325057 -21.446852)
			(xy 274.357625 -21.399491) (xy 274.376896 -21.378164) (xy 274.3835 -21.371052) (xy 274.386802 -21.36267)
			(xy 274.388553 -21.358102) (xy 274.390465 -21.34851) (xy 274.390612 -21.34362) (xy 274.390612 -21.274024)
			(xy 274.390473 -21.269134) (xy 274.388551 -21.259543) (xy 274.386802 -21.254974) (xy 274.3835 -21.246592)
			(xy 274.376896 -21.23948) (xy 274.357625 -21.218153) (xy 274.325059 -21.170789) (xy 274.299966 -21.119076)
			(xy 274.282914 -21.064184) (xy 274.274289 -21.007356) (xy 274.274287 -20.949876) (xy 274.282907 -20.893047)
			(xy 274.299954 -20.838154) (xy 274.325042 -20.786439) (xy 274.357605 -20.739073) (xy 274.376896 -20.717764)
			(xy 274.3835 -20.710652) (xy 274.386802 -20.70227) (xy 274.388553 -20.697702) (xy 274.390465 -20.68811)
			(xy 274.390612 -20.68322) (xy 274.390612 -20.613624) (xy 274.390473 -20.608734) (xy 274.388551 -20.599143)
			(xy 274.386802 -20.594574) (xy 274.3835 -20.586192) (xy 274.376896 -20.57908) (xy 274.357625 -20.557753)
			(xy 274.325059 -20.510389) (xy 274.299966 -20.458676) (xy 274.282914 -20.403784) (xy 274.274289 -20.346956)
			(xy 274.274287 -20.289476) (xy 274.282907 -20.232647) (xy 274.299954 -20.177754) (xy 274.325042 -20.126039)
			(xy 274.357605 -20.078673) (xy 274.376896 -20.057364) (xy 274.3835 -20.050252) (xy 274.386802 -20.04187)
			(xy 274.388553 -20.037302) (xy 274.390465 -20.02771) (xy 274.390612 -20.02282) (xy 274.390612 -19.953224)
			(xy 274.390473 -19.948334) (xy 274.388551 -19.938743) (xy 274.386802 -19.934174) (xy 274.3835 -19.925792)
			(xy 274.376896 -19.91868) (xy 274.357625 -19.897353) (xy 274.325059 -19.849989) (xy 274.299966 -19.798276)
			(xy 274.282914 -19.743384) (xy 274.274289 -19.686556) (xy 274.274287 -19.629076) (xy 274.282907 -19.572247)
			(xy 274.299954 -19.517354) (xy 274.325042 -19.465639) (xy 274.357605 -19.418273) (xy 274.376896 -19.396964)
			(xy 274.3835 -19.389852) (xy 274.386802 -19.38147) (xy 274.388553 -19.376902) (xy 274.390465 -19.36731)
			(xy 274.390612 -19.36242) (xy 274.390612 -19.282918) (xy 274.38985 -19.281394) (xy 274.366228 -19.257264)
			(xy 274.362305 -19.25306) (xy 274.352944 -19.246384) (xy 274.347686 -19.244056) (xy 274.344892 -19.242786)
			(xy 274.31492 -19.248882) (xy 274.184618 -19.379184) (xy 274.161063 -19.402129) (xy 274.109663 -19.443147)
			(xy 274.053992 -19.478148) (xy 273.994749 -19.506691) (xy 273.932682 -19.528418) (xy 273.868571 -19.543054)
			(xy 273.803224 -19.550415) (xy 273.770344 -19.550888) (xy 271.245584 -19.550888) (xy 271.212706 -19.550411)
			(xy 271.147366 -19.54302) (xy 271.083263 -19.528368) (xy 271.021201 -19.506637) (xy 270.96196 -19.478101)
			(xy 270.906282 -19.443117) (xy 270.854866 -19.402125) (xy 270.83131 -19.379184) (xy 270.53794 -19.085814)
			(xy 270.530539 -19.078976) (xy 270.511941 -19.071261) (xy 270.501872 -19.070828) (xy 267.123672 -19.070828)
			(xy 267.1191 -19.071082) (xy 267.110141 -19.072268) (xy 267.093839 -19.080041) (xy 267.081224 -19.092966)
			(xy 267.07719 -19.101054) (xy 267.04036 -19.187668) (xy 267.037658 -19.194636) (xy 267.035992 -19.20948)
			(xy 267.037058 -19.216878) (xy 267.037058 -19.217132) (xy 267.038644 -19.224295) (xy 267.045358 -19.237332)
			(xy 267.050266 -19.242786) (xy 267.05052 -19.24304) (xy 267.093959 -19.288699) (xy 267.175996 -19.384385)
			(xy 267.252242 -19.484747) (xy 267.32243 -19.589435) (xy 267.386317 -19.698083) (xy 267.443679 -19.810313)
			(xy 267.494316 -19.925733) (xy 267.538051 -20.043941) (xy 267.574732 -20.164525) (xy 267.604232 -20.287063)
			(xy 267.626446 -20.411129) (xy 267.641299 -20.536291) (xy 267.648737 -20.66211) (xy 267.649198 -20.72513)
			(xy 267.648692 -20.790866) (xy 267.640599 -20.922087) (xy 267.624442 -21.052562) (xy 267.600285 -21.181795)
			(xy 267.568217 -21.309295) (xy 267.528361 -21.434579) (xy 267.480868 -21.557173) (xy 267.425919 -21.67661)
			(xy 267.36372 -21.792437) (xy 267.29451 -21.904216) (xy 267.218549 -22.011523) (xy 267.136127 -22.113949)
			(xy 267.047555 -22.211108) (xy 266.95317 -22.302629) (xy 266.853331 -22.388167) (xy 266.748414 -22.467396)
			(xy 266.63882 -22.540016) (xy 266.61208 -22.555454) (xy 283.536388 -22.555454) (xy 283.540459 -22.499832)
			(xy 283.552585 -22.445395) (xy 283.572508 -22.393304) (xy 283.599804 -22.344669) (xy 283.63389 -22.300526)
			(xy 283.674039 -22.261817) (xy 283.719397 -22.229366) (xy 283.768997 -22.203865) (xy 283.821781 -22.185858)
			(xy 283.876624 -22.175728) (xy 283.932358 -22.173691) (xy 283.987795 -22.179791) (xy 284.041752 -22.193897)
			(xy 284.093081 -22.215709) (xy 284.140687 -22.244763) (xy 284.183555 -22.280438) (xy 284.220772 -22.321975)
			(xy 284.251545 -22.368488) (xy 284.275217 -22.418985) (xy 284.291285 -22.472392) (xy 284.299405 -22.527568)
			(xy 284.299914 -22.555454) (xy 284.299405 -22.58334) (xy 284.291285 -22.638516) (xy 284.275217 -22.691923)
			(xy 284.251545 -22.74242) (xy 284.220772 -22.788933) (xy 284.183555 -22.83047) (xy 284.140687 -22.866145)
			(xy 284.093081 -22.895199) (xy 284.041752 -22.917011) (xy 283.987795 -22.931117) (xy 283.932358 -22.937217)
			(xy 283.876624 -22.93518) (xy 283.821781 -22.92505) (xy 283.768997 -22.907043) (xy 283.719397 -22.881542)
			(xy 283.674039 -22.849091) (xy 283.63389 -22.810382) (xy 283.599804 -22.766239) (xy 283.572508 -22.717604)
			(xy 283.552585 -22.665513) (xy 283.540459 -22.611076) (xy 283.536388 -22.555454) (xy 266.61208 -22.555454)
			(xy 266.524962 -22.605751) (xy 266.407274 -22.664353) (xy 266.286202 -22.715599) (xy 266.162204 -22.759294)
			(xy 266.035752 -22.795273) (xy 265.907324 -22.823399) (xy 265.777409 -22.843565) (xy 265.646499 -22.855696)
			(xy 265.51509 -22.859745) (xy 265.383681 -22.855696) (xy 265.252771 -22.843565) (xy 265.122856 -22.823399)
			(xy 264.994428 -22.795273) (xy 264.867976 -22.759294) (xy 264.743978 -22.715599) (xy 264.622906 -22.664353)
			(xy 264.505218 -22.605751) (xy 264.39136 -22.540016) (xy 264.281766 -22.467396) (xy 264.176849 -22.388167)
			(xy 264.07701 -22.302629) (xy 263.982625 -22.211108) (xy 263.894053 -22.113949) (xy 263.811631 -22.011523)
			(xy 263.73567 -21.904216) (xy 263.66646 -21.792437) (xy 263.604261 -21.67661) (xy 263.549312 -21.557173)
			(xy 263.501819 -21.434579) (xy 263.461963 -21.309295) (xy 263.429895 -21.181795) (xy 263.405738 -21.052562)
			(xy 263.389581 -20.922087) (xy 263.381488 -20.790866) (xy 263.380982 -20.72513) (xy 263.381443 -20.66211)
			(xy 263.388881 -20.53629) (xy 263.403732 -20.411128) (xy 263.425946 -20.28706) (xy 263.455444 -20.164521)
			(xy 263.492124 -20.043936) (xy 263.535857 -19.925727) (xy 263.586492 -19.810305) (xy 263.643851 -19.698073)
			(xy 263.707735 -19.589422) (xy 263.777921 -19.484732) (xy 263.854164 -19.384367) (xy 263.936198 -19.288678)
			(xy 263.97966 -19.24304) (xy 263.979914 -19.242786) (xy 263.984772 -19.237297) (xy 263.991488 -19.224277)
			(xy 263.993122 -19.217132) (xy 263.993122 -19.216878) (xy 263.994214 -19.209481) (xy 263.992544 -19.194631)
			(xy 263.98982 -19.187668) (xy 263.95299 -19.101054) (xy 263.949011 -19.092922) (xy 263.936407 -19.079943)
			(xy 263.920065 -19.07218) (xy 263.91108 -19.071082) (xy 263.906508 -19.070828) (xy 255.377696 -19.070828)
			(xy 255.367709 -19.071367) (xy 255.349281 -19.079084) (xy 255.341882 -19.085814) (xy 255.282192 -19.145504)
			(xy 255.271162 -19.156266) (xy 255.247371 -19.175858) (xy 255.234694 -19.18462) (xy 255.227328 -19.189446)
			(xy 255.21158 -19.210782) (xy 255.208911 -19.214496) (xy 255.204814 -19.222672) (xy 255.203452 -19.227038)
			(xy 255.196848 -19.249898) (xy 255.195324 -19.26209) (xy 255.199388 -19.279362) (xy 255.202944 -19.289522)
			(xy 255.21456 -19.315166) (xy 255.230961 -19.369018) (xy 255.239263 -19.424697) (xy 255.239774 -19.452844)
			(xy 255.239774 -19.457924) (xy 255.238962 -19.48495) (xy 255.230652 -19.538377) (xy 255.214883 -19.590095)
			(xy 255.191971 -19.639068) (xy 255.162374 -19.684317) (xy 255.126685 -19.724934) (xy 255.08562 -19.760106)
			(xy 255.040001 -19.789128) (xy 254.990741 -19.811419) (xy 254.938827 -19.826533) (xy 254.8853 -19.834166)
			(xy 254.831232 -19.834166) (xy 254.777705 -19.826533) (xy 254.725791 -19.811419) (xy 254.676531 -19.789128)
			(xy 254.630912 -19.760106) (xy 254.589847 -19.724934) (xy 254.554158 -19.684317) (xy 254.524561 -19.639068)
			(xy 254.501649 -19.590095) (xy 254.48588 -19.538377) (xy 254.47757 -19.48495) (xy 254.476758 -19.457924)
			(xy 254.476758 -19.452844) (xy 254.477279 -19.424697) (xy 254.485581 -19.369019) (xy 254.501968 -19.315163)
			(xy 254.513588 -19.289522) (xy 254.517144 -19.279362) (xy 254.521208 -19.26209) (xy 254.519684 -19.249898)
			(xy 254.51308 -19.227038) (xy 254.511704 -19.222677) (xy 254.507611 -19.214502) (xy 254.504952 -19.210782)
			(xy 254.489204 -19.189446) (xy 254.481838 -19.18462) (xy 254.469163 -19.175855) (xy 254.445372 -19.156264)
			(xy 254.43434 -19.145504) (xy 254.374396 -19.08556) (xy 254.367038 -19.078916) (xy 254.348737 -19.071344)
			(xy 254.338836 -19.070828) (xy 253.622048 -19.070828) (xy 253.611983 -19.071261) (xy 253.593394 -19.078992)
			(xy 253.58598 -19.085814) (xy 253.311406 -19.360388) (xy 253.287851 -19.383332) (xy 253.236451 -19.424349)
			(xy 253.180779 -19.459348) (xy 253.121536 -19.487891) (xy 253.059469 -19.509616) (xy 252.995358 -19.52425)
			(xy 252.930012 -19.53161) (xy 252.897132 -19.532092) (xy 249.316494 -19.532092) (xy 249.277541 -19.531453)
			(xy 249.200323 -19.521133) (xy 249.16257 -19.511518) (xy 249.150632 -19.508216) (xy 249.125994 -19.51355)
			(xy 249.042936 -19.583908) (xy 249.033538 -19.607022) (xy 249.034046 -19.611848) (xy 249.036895 -19.639495)
			(xy 249.035513 -19.695054) (xy 249.026085 -19.749826) (xy 249.008809 -19.802649) (xy 248.984052 -19.852408)
			(xy 248.952337 -19.898047) (xy 248.933716 -19.91868) (xy 248.927112 -19.925792) (xy 248.92381 -19.934174)
			(xy 248.922053 -19.938741) (xy 248.920131 -19.948333) (xy 248.92 -19.953224) (xy 248.92 -20.02282)
			(xy 248.920134 -20.027711) (xy 248.922046 -20.037306) (xy 248.92381 -20.04187) (xy 248.927112 -20.050252)
			(xy 248.933716 -20.057364) (xy 248.952983 -20.078692) (xy 248.985542 -20.126055) (xy 249.010628 -20.177766)
			(xy 249.027673 -20.232654) (xy 249.036292 -20.289479) (xy 249.036289 -20.346953) (xy 249.027666 -20.403777)
			(xy 249.010616 -20.458664) (xy 249.006293 -20.467574) (xy 256.48742 -20.467574) (xy 256.491491 -20.411952)
			(xy 256.503617 -20.357515) (xy 256.52354 -20.305424) (xy 256.550836 -20.256789) (xy 256.584922 -20.212646)
			(xy 256.625071 -20.173937) (xy 256.670429 -20.141486) (xy 256.720029 -20.115985) (xy 256.772813 -20.097978)
			(xy 256.827656 -20.087848) (xy 256.88339 -20.085811) (xy 256.938827 -20.091911) (xy 256.992784 -20.106017)
			(xy 257.044113 -20.127829) (xy 257.091719 -20.156883) (xy 257.134587 -20.192558) (xy 257.171804 -20.234095)
			(xy 257.202577 -20.280608) (xy 257.226249 -20.331105) (xy 257.242317 -20.384512) (xy 257.250437 -20.439688)
			(xy 257.250946 -20.467574) (xy 257.250437 -20.49546) (xy 257.242317 -20.550636) (xy 257.226249 -20.604043)
			(xy 257.202577 -20.65454) (xy 257.171804 -20.701053) (xy 257.134587 -20.74259) (xy 257.091719 -20.778265)
			(xy 257.044113 -20.807319) (xy 256.992784 -20.829131) (xy 256.938827 -20.843237) (xy 256.88339 -20.849337)
			(xy 256.827656 -20.8473) (xy 256.772813 -20.83717) (xy 256.720029 -20.819163) (xy 256.670429 -20.793662)
			(xy 256.625071 -20.761211) (xy 256.584922 -20.722502) (xy 256.550836 -20.678359) (xy 256.52354 -20.629724)
			(xy 256.503617 -20.577633) (xy 256.491491 -20.523196) (xy 256.48742 -20.467574) (xy 249.006293 -20.467574)
			(xy 248.985526 -20.510373) (xy 248.952963 -20.557733) (xy 248.933716 -20.57908) (xy 248.927112 -20.586192)
			(xy 248.92381 -20.594574) (xy 248.922053 -20.599141) (xy 248.920131 -20.608733) (xy 248.92 -20.613624)
			(xy 248.92 -20.68322) (xy 248.920134 -20.688111) (xy 248.922046 -20.697706) (xy 248.92381 -20.70227)
			(xy 248.927112 -20.710652) (xy 248.933716 -20.717764) (xy 248.952983 -20.739092) (xy 248.985542 -20.786455)
			(xy 249.010628 -20.838166) (xy 249.027673 -20.893054) (xy 249.036292 -20.949879) (xy 249.036289 -21.007353)
			(xy 249.027666 -21.064177) (xy 249.010616 -21.119064) (xy 248.985526 -21.170773) (xy 248.952963 -21.218133)
			(xy 248.933716 -21.23948) (xy 248.927112 -21.246592) (xy 248.92381 -21.254974) (xy 248.922053 -21.259541)
			(xy 248.920131 -21.269133) (xy 248.92 -21.274024) (xy 248.92 -21.34362) (xy 248.920134 -21.348511)
			(xy 248.922046 -21.358106) (xy 248.92381 -21.36267) (xy 248.927112 -21.371052) (xy 248.933716 -21.378164)
			(xy 248.952984 -21.399492) (xy 248.985543 -21.446856) (xy 249.010629 -21.498568) (xy 249.027674 -21.553458)
			(xy 249.036292 -21.610284) (xy 249.03684 -21.639022) (xy 249.036354 -21.666273) (xy 249.028598 -21.720221)
			(xy 249.013243 -21.772516) (xy 249.011801 -21.775674) (xy 258.13588 -21.775674) (xy 258.139951 -21.720052)
			(xy 258.152077 -21.665615) (xy 258.172 -21.613524) (xy 258.199296 -21.564889) (xy 258.233382 -21.520746)
			(xy 258.273531 -21.482037) (xy 258.318889 -21.449586) (xy 258.368489 -21.424085) (xy 258.421273 -21.406078)
			(xy 258.476116 -21.395948) (xy 258.53185 -21.393911) (xy 258.587287 -21.400011) (xy 258.641244 -21.414117)
			(xy 258.692573 -21.435929) (xy 258.740179 -21.464983) (xy 258.783047 -21.500658) (xy 258.820264 -21.542195)
			(xy 258.851037 -21.588708) (xy 258.874709 -21.639205) (xy 258.890777 -21.692612) (xy 258.898897 -21.747788)
			(xy 258.899406 -21.775674) (xy 258.898897 -21.80356) (xy 258.891226 -21.855684) (xy 259.038596 -21.855684)
			(xy 259.042667 -21.800062) (xy 259.054793 -21.745625) (xy 259.074716 -21.693534) (xy 259.102012 -21.644899)
			(xy 259.136098 -21.600756) (xy 259.176247 -21.562047) (xy 259.221605 -21.529596) (xy 259.271205 -21.504095)
			(xy 259.323989 -21.486088) (xy 259.378832 -21.475958) (xy 259.434566 -21.473921) (xy 259.490003 -21.480021)
			(xy 259.54396 -21.494127) (xy 259.595289 -21.515939) (xy 259.642895 -21.544993) (xy 259.685763 -21.580668)
			(xy 259.72298 -21.622205) (xy 259.753753 -21.668718) (xy 259.777425 -21.719215) (xy 259.793493 -21.772622)
			(xy 259.801613 -21.827798) (xy 259.801964 -21.847048) (xy 260.272782 -21.847048) (xy 260.276853 -21.791426)
			(xy 260.288979 -21.736989) (xy 260.308902 -21.684898) (xy 260.336198 -21.636263) (xy 260.370284 -21.59212)
			(xy 260.410433 -21.553411) (xy 260.455791 -21.52096) (xy 260.505391 -21.495459) (xy 260.558175 -21.477452)
			(xy 260.613018 -21.467322) (xy 260.668752 -21.465285) (xy 260.724189 -21.471385) (xy 260.778146 -21.485491)
			(xy 260.829475 -21.507303) (xy 260.877081 -21.536357) (xy 260.919949 -21.572032) (xy 260.957166 -21.613569)
			(xy 260.987939 -21.660082) (xy 261.011611 -21.710579) (xy 261.027679 -21.763986) (xy 261.035799 -21.819162)
			(xy 261.036308 -21.847048) (xy 261.035799 -21.874934) (xy 261.027679 -21.93011) (xy 261.011611 -21.983517)
			(xy 260.987939 -22.034014) (xy 260.957166 -22.080527) (xy 260.919949 -22.122064) (xy 260.877081 -22.157739)
			(xy 260.829475 -22.186793) (xy 260.778146 -22.208605) (xy 260.724189 -22.222711) (xy 260.668752 -22.228811)
			(xy 260.613018 -22.226774) (xy 260.558175 -22.216644) (xy 260.505391 -22.198637) (xy 260.455791 -22.173136)
			(xy 260.410433 -22.140685) (xy 260.370284 -22.101976) (xy 260.336198 -22.057833) (xy 260.308902 -22.009198)
			(xy 260.288979 -21.957107) (xy 260.276853 -21.90267) (xy 260.272782 -21.847048) (xy 259.801964 -21.847048)
			(xy 259.802122 -21.855684) (xy 259.801613 -21.88357) (xy 259.793493 -21.938746) (xy 259.777425 -21.992153)
			(xy 259.753753 -22.04265) (xy 259.72298 -22.089163) (xy 259.685763 -22.1307) (xy 259.642895 -22.166375)
			(xy 259.595289 -22.195429) (xy 259.54396 -22.217241) (xy 259.490003 -22.231347) (xy 259.434566 -22.237447)
			(xy 259.378832 -22.23541) (xy 259.323989 -22.22528) (xy 259.271205 -22.207273) (xy 259.221605 -22.181772)
			(xy 259.176247 -22.149321) (xy 259.136098 -22.110612) (xy 259.102012 -22.066469) (xy 259.074716 -22.017834)
			(xy 259.054793 -21.965743) (xy 259.042667 -21.911306) (xy 259.038596 -21.855684) (xy 258.891226 -21.855684)
			(xy 258.890777 -21.858736) (xy 258.874709 -21.912143) (xy 258.851037 -21.96264) (xy 258.820264 -22.009153)
			(xy 258.783047 -22.05069) (xy 258.740179 -22.086365) (xy 258.692573 -22.115419) (xy 258.641244 -22.137231)
			(xy 258.587287 -22.151337) (xy 258.53185 -22.157437) (xy 258.476116 -22.1554) (xy 258.421273 -22.14527)
			(xy 258.368489 -22.127263) (xy 258.318889 -22.101762) (xy 258.273531 -22.069311) (xy 258.233382 -22.030602)
			(xy 258.199296 -21.986459) (xy 258.172 -21.937824) (xy 258.152077 -21.885733) (xy 258.139951 -21.831296)
			(xy 258.13588 -21.775674) (xy 249.011801 -21.775674) (xy 248.990601 -21.822093) (xy 248.961135 -21.867943)
			(xy 248.925444 -21.909134) (xy 248.884253 -21.944825) (xy 248.838403 -21.974291) (xy 248.788826 -21.996933)
			(xy 248.736531 -22.012288) (xy 248.682583 -22.020044) (xy 248.628081 -22.020044) (xy 248.574133 -22.012288)
			(xy 248.521838 -21.996933) (xy 248.472261 -21.974291) (xy 248.426411 -21.944825) (xy 248.38522 -21.909134)
			(xy 248.349529 -21.867943) (xy 248.320063 -21.822093) (xy 248.297421 -21.772516) (xy 248.282066 -21.720221)
			(xy 248.27431 -21.666273) (xy 248.273824 -21.639022) (xy 248.274343 -21.610282) (xy 248.282964 -21.553453)
			(xy 248.300012 -21.498561) (xy 248.325103 -21.446847) (xy 248.357669 -21.399484) (xy 248.376948 -21.378164)
			(xy 248.383552 -21.371052) (xy 248.386854 -21.36267) (xy 248.388607 -21.358103) (xy 248.39052 -21.34851)
			(xy 248.390664 -21.34362) (xy 248.390664 -21.274024) (xy 248.390525 -21.269134) (xy 248.388601 -21.259544)
			(xy 248.386854 -21.254974) (xy 248.383552 -21.246592) (xy 248.376948 -21.23948) (xy 248.357674 -21.218154)
			(xy 248.325104 -21.170791) (xy 248.300008 -21.119079) (xy 248.282953 -21.064186) (xy 248.274328 -21.007356)
			(xy 248.274325 -20.949876) (xy 248.282946 -20.893045) (xy 248.299996 -20.838151) (xy 248.325088 -20.786436)
			(xy 248.357654 -20.739071) (xy 248.376948 -20.717764) (xy 248.383552 -20.710652) (xy 248.386854 -20.70227)
			(xy 248.388607 -20.697703) (xy 248.39052 -20.68811) (xy 248.390664 -20.68322) (xy 248.390664 -20.613624)
			(xy 248.390525 -20.608734) (xy 248.388601 -20.599144) (xy 248.386854 -20.594574) (xy 248.383552 -20.586192)
			(xy 248.376948 -20.57908) (xy 248.357674 -20.557754) (xy 248.325104 -20.510391) (xy 248.300008 -20.458679)
			(xy 248.282953 -20.403786) (xy 248.274328 -20.346956) (xy 248.274325 -20.289476) (xy 248.282946 -20.232645)
			(xy 248.299996 -20.177751) (xy 248.325088 -20.126036) (xy 248.357654 -20.078671) (xy 248.376948 -20.057364)
			(xy 248.383552 -20.050252) (xy 248.386854 -20.04187) (xy 248.388607 -20.037303) (xy 248.39052 -20.02771)
			(xy 248.390664 -20.02282) (xy 248.390664 -19.953224) (xy 248.390525 -19.948334) (xy 248.388601 -19.938744)
			(xy 248.386854 -19.934174) (xy 248.383552 -19.925792) (xy 248.376948 -19.91868) (xy 248.357679 -19.897352)
			(xy 248.325118 -19.849988) (xy 248.300028 -19.798276) (xy 248.282979 -19.743387) (xy 248.274355 -19.68656)
			(xy 248.273824 -19.657822) (xy 248.273824 -19.657314) (xy 248.274034 -19.639942) (xy 248.277215 -19.605345)
			(xy 248.280174 -19.588226) (xy 248.281496 -19.579452) (xy 248.278625 -19.561954) (xy 248.269916 -19.546508)
			(xy 248.26341 -19.540474) (xy 248.19737 -19.48307) (xy 248.190416 -19.477543) (xy 248.173844 -19.47119)
			(xy 248.156099 -19.470883) (xy 248.147586 -19.473418) (xy 248.117202 -19.483303) (xy 248.05483 -19.49718)
			(xy 247.99132 -19.504197) (xy 247.959372 -19.50466) (xy 245.520718 -19.50466) (xy 245.487842 -19.504179)
			(xy 245.422506 -19.496782) (xy 245.358407 -19.482123) (xy 245.296351 -19.460386) (xy 245.237115 -19.431844)
			(xy 245.181444 -19.396855) (xy 245.130035 -19.355859) (xy 245.106444 -19.332956) (xy 244.859302 -19.085814)
			(xy 244.851904 -19.078966) (xy 244.833306 -19.071229) (xy 244.823234 -19.070828) (xy 241.123724 -19.070828)
			(xy 241.119152 -19.071082) (xy 241.110188 -19.07226) (xy 241.093871 -19.080023) (xy 241.081243 -19.092947)
			(xy 241.077242 -19.101054) (xy 241.040412 -19.187668) (xy 241.037712 -19.194636) (xy 241.036048 -19.20948)
			(xy 241.03711 -19.216878) (xy 241.03711 -19.217132) (xy 241.038695 -19.224296) (xy 241.045404 -19.237337)
			(xy 241.050318 -19.242786) (xy 241.050572 -19.24304) (xy 241.09401 -19.288699) (xy 241.176046 -19.384386)
			(xy 241.25229 -19.484749) (xy 241.322477 -19.589437) (xy 241.386362 -19.698085) (xy 241.443722 -19.810315)
			(xy 241.494358 -19.925736) (xy 241.538092 -20.043943) (xy 241.574772 -20.164527) (xy 241.604271 -20.287065)
			(xy 241.626485 -20.411131) (xy 241.641337 -20.536291) (xy 241.648775 -20.662111) (xy 241.64925 -20.72513)
			(xy 241.648744 -20.790866) (xy 241.640651 -20.922087) (xy 241.624494 -21.052562) (xy 241.600337 -21.181795)
			(xy 241.568269 -21.309295) (xy 241.528413 -21.434579) (xy 241.48092 -21.557173) (xy 241.425971 -21.67661)
			(xy 241.363772 -21.792437) (xy 241.294562 -21.904216) (xy 241.218601 -22.011523) (xy 241.136179 -22.113949)
			(xy 241.047607 -22.211108) (xy 240.953222 -22.302629) (xy 240.853383 -22.388167) (xy 240.748466 -22.467396)
			(xy 240.638872 -22.540016) (xy 240.612132 -22.555454) (xy 257.53644 -22.555454) (xy 257.540511 -22.499832)
			(xy 257.552637 -22.445395) (xy 257.57256 -22.393304) (xy 257.599856 -22.344669) (xy 257.633942 -22.300526)
			(xy 257.674091 -22.261817) (xy 257.719449 -22.229366) (xy 257.769049 -22.203865) (xy 257.821833 -22.185858)
			(xy 257.876676 -22.175728) (xy 257.93241 -22.173691) (xy 257.987847 -22.179791) (xy 258.041804 -22.193897)
			(xy 258.093133 -22.215709) (xy 258.140739 -22.244763) (xy 258.183607 -22.280438) (xy 258.220824 -22.321975)
			(xy 258.251597 -22.368488) (xy 258.275269 -22.418985) (xy 258.291337 -22.472392) (xy 258.299457 -22.527568)
			(xy 258.299966 -22.555454) (xy 258.299457 -22.58334) (xy 258.291337 -22.638516) (xy 258.275269 -22.691923)
			(xy 258.251597 -22.74242) (xy 258.220824 -22.788933) (xy 258.183607 -22.83047) (xy 258.140739 -22.866145)
			(xy 258.093133 -22.895199) (xy 258.041804 -22.917011) (xy 257.987847 -22.931117) (xy 257.93241 -22.937217)
			(xy 257.876676 -22.93518) (xy 257.821833 -22.92505) (xy 257.769049 -22.907043) (xy 257.719449 -22.881542)
			(xy 257.674091 -22.849091) (xy 257.633942 -22.810382) (xy 257.599856 -22.766239) (xy 257.57256 -22.717604)
			(xy 257.552637 -22.665513) (xy 257.540511 -22.611076) (xy 257.53644 -22.555454) (xy 240.612132 -22.555454)
			(xy 240.525014 -22.605751) (xy 240.407326 -22.664353) (xy 240.286254 -22.715599) (xy 240.162256 -22.759294)
			(xy 240.035804 -22.795273) (xy 239.907376 -22.823399) (xy 239.777461 -22.843565) (xy 239.646551 -22.855696)
			(xy 239.515142 -22.859745) (xy 239.383733 -22.855696) (xy 239.252823 -22.843565) (xy 239.122908 -22.823399)
			(xy 238.99448 -22.795273) (xy 238.868028 -22.759294) (xy 238.74403 -22.715599) (xy 238.622958 -22.664353)
			(xy 238.50527 -22.605751) (xy 238.391412 -22.540016) (xy 238.281818 -22.467396) (xy 238.176901 -22.388167)
			(xy 238.077062 -22.302629) (xy 237.982677 -22.211108) (xy 237.894105 -22.113949) (xy 237.811683 -22.011523)
			(xy 237.735722 -21.904216) (xy 237.666512 -21.792437) (xy 237.604313 -21.67661) (xy 237.549364 -21.557173)
			(xy 237.501871 -21.434579) (xy 237.462015 -21.309295) (xy 237.429947 -21.181795) (xy 237.40579 -21.052562)
			(xy 237.389633 -20.922087) (xy 237.38154 -20.790866) (xy 237.381034 -20.72513) (xy 237.381495 -20.66211)
			(xy 237.388933 -20.53629) (xy 237.403785 -20.411128) (xy 237.425999 -20.287062) (xy 237.455497 -20.164522)
			(xy 237.492178 -20.043938) (xy 237.535912 -19.925729) (xy 237.586548 -19.810308) (xy 237.643908 -19.698077)
			(xy 237.707793 -19.589428) (xy 237.777981 -19.484739) (xy 237.854225 -19.384375) (xy 237.93626 -19.288687)
			(xy 237.979712 -19.24304) (xy 237.979966 -19.242786) (xy 237.98482 -19.237295) (xy 237.991529 -19.224273)
			(xy 237.993174 -19.217132) (xy 237.993174 -19.216878) (xy 237.994266 -19.209481) (xy 237.992597 -19.19463)
			(xy 237.989872 -19.187668) (xy 237.953042 -19.101054) (xy 237.94906 -19.092926) (xy 237.936453 -19.079959)
			(xy 237.920111 -19.072212) (xy 237.911132 -19.071082) (xy 237.90656 -19.070828) (xy 217.151458 -19.070828)
			(xy 217.144854 -19.071336) (xy 217.134081 -19.073286) (xy 217.115528 -19.084869) (xy 217.10904 -19.093688)
			(xy 217.106246 -19.09826) (xy 217.064844 -19.178778) (xy 217.061815 -19.185067) (xy 217.058966 -19.198728)
			(xy 217.059256 -19.205702) (xy 217.060272 -19.219672) (xy 217.068654 -19.231356) (xy 217.085412 -19.255758)
			(xy 217.111984 -19.308653) (xy 217.130061 -19.365019) (xy 217.139209 -19.423501) (xy 217.139774 -19.453098)
			(xy 217.139288 -19.480349) (xy 217.131532 -19.534297) (xy 217.116177 -19.586592) (xy 217.093535 -19.636169)
			(xy 217.064069 -19.682019) (xy 217.028378 -19.72321) (xy 216.987187 -19.758901) (xy 216.941337 -19.788367)
			(xy 216.89176 -19.811009) (xy 216.839465 -19.826364) (xy 216.785517 -19.83412) (xy 216.731015 -19.83412)
			(xy 216.677067 -19.826364) (xy 216.624772 -19.811009) (xy 216.575195 -19.788367) (xy 216.529345 -19.758901)
			(xy 216.488154 -19.72321) (xy 216.452463 -19.682019) (xy 216.422997 -19.636169) (xy 216.400355 -19.586592)
			(xy 216.385 -19.534297) (xy 216.377244 -19.480349) (xy 216.376758 -19.453098) (xy 216.377317 -19.423501)
			(xy 216.386467 -19.365018) (xy 216.404546 -19.308652) (xy 216.431119 -19.255758) (xy 216.447878 -19.231356)
			(xy 216.451791 -19.225557) (xy 216.456548 -19.212407) (xy 216.457276 -19.205448) (xy 216.458292 -19.191478)
			(xy 216.410286 -19.09826) (xy 216.407492 -19.093688) (xy 216.401035 -19.084834) (xy 216.382468 -19.073241)
			(xy 216.371678 -19.071336) (xy 216.365074 -19.070828) (xy 215.347042 -19.070828) (xy 215.336977 -19.071262)
			(xy 215.318391 -19.078995) (xy 215.310974 -19.085814) (xy 215.15197 -19.244818) (xy 215.128407 -19.267717)
			(xy 215.077024 -19.308675) (xy 215.021382 -19.343626) (xy 214.962179 -19.372132) (xy 214.900158 -19.393836)
			(xy 214.836098 -19.408464) (xy 214.770804 -19.415832) (xy 214.73795 -19.416268) (xy 211.167472 -19.416268)
			(xy 211.134089 -19.415764) (xy 211.067762 -19.408123) (xy 211.035138 -19.401028) (xy 211.021422 -19.397726)
			(xy 210.99526 -19.406108) (xy 210.916774 -19.492976) (xy 210.91144 -19.5199) (xy 210.916012 -19.533108)
			(xy 210.925735 -19.563169) (xy 210.936205 -19.625472) (xy 210.93684 -19.65706) (xy 210.93684 -19.657822)
			(xy 210.936317 -19.68656) (xy 210.927691 -19.743385) (xy 210.910636 -19.798273) (xy 210.885539 -19.84998)
			(xy 210.852969 -19.897337) (xy 210.833716 -19.91868) (xy 210.827112 -19.925792) (xy 210.82381 -19.934174)
			(xy 210.822053 -19.938741) (xy 210.820131 -19.948333) (xy 210.82 -19.953224) (xy 210.82 -20.02282)
			(xy 210.820134 -20.027711) (xy 210.822046 -20.037306) (xy 210.82381 -20.04187) (xy 210.827112 -20.050252)
			(xy 210.833716 -20.057364) (xy 210.852983 -20.078692) (xy 210.885542 -20.126055) (xy 210.910628 -20.177766)
			(xy 210.927673 -20.232654) (xy 210.936292 -20.289479) (xy 210.936289 -20.346953) (xy 210.927666 -20.403777)
			(xy 210.910616 -20.458664) (xy 210.906293 -20.467574) (xy 218.38742 -20.467574) (xy 218.391491 -20.411952)
			(xy 218.403617 -20.357515) (xy 218.42354 -20.305424) (xy 218.450836 -20.256789) (xy 218.484922 -20.212646)
			(xy 218.525071 -20.173937) (xy 218.570429 -20.141486) (xy 218.620029 -20.115985) (xy 218.672813 -20.097978)
			(xy 218.727656 -20.087848) (xy 218.78339 -20.085811) (xy 218.838827 -20.091911) (xy 218.892784 -20.106017)
			(xy 218.944113 -20.127829) (xy 218.991719 -20.156883) (xy 219.034587 -20.192558) (xy 219.071804 -20.234095)
			(xy 219.102577 -20.280608) (xy 219.126249 -20.331105) (xy 219.142317 -20.384512) (xy 219.150437 -20.439688)
			(xy 219.150946 -20.467574) (xy 219.150437 -20.49546) (xy 219.142317 -20.550636) (xy 219.126249 -20.604043)
			(xy 219.102577 -20.65454) (xy 219.071804 -20.701053) (xy 219.034587 -20.74259) (xy 218.991719 -20.778265)
			(xy 218.944113 -20.807319) (xy 218.892784 -20.829131) (xy 218.838827 -20.843237) (xy 218.78339 -20.849337)
			(xy 218.727656 -20.8473) (xy 218.672813 -20.83717) (xy 218.620029 -20.819163) (xy 218.570429 -20.793662)
			(xy 218.525071 -20.761211) (xy 218.484922 -20.722502) (xy 218.450836 -20.678359) (xy 218.42354 -20.629724)
			(xy 218.403617 -20.577633) (xy 218.391491 -20.523196) (xy 218.38742 -20.467574) (xy 210.906293 -20.467574)
			(xy 210.885526 -20.510373) (xy 210.852963 -20.557733) (xy 210.833716 -20.57908) (xy 210.827112 -20.586192)
			(xy 210.82381 -20.594574) (xy 210.822053 -20.599141) (xy 210.820131 -20.608733) (xy 210.82 -20.613624)
			(xy 210.82 -20.68322) (xy 210.820134 -20.688111) (xy 210.822046 -20.697706) (xy 210.82381 -20.70227)
			(xy 210.827112 -20.710652) (xy 210.833716 -20.717764) (xy 210.852983 -20.739092) (xy 210.885542 -20.786455)
			(xy 210.910628 -20.838166) (xy 210.927673 -20.893054) (xy 210.936292 -20.949879) (xy 210.936289 -21.007353)
			(xy 210.927666 -21.064177) (xy 210.910616 -21.119064) (xy 210.885526 -21.170773) (xy 210.852963 -21.218133)
			(xy 210.833716 -21.23948) (xy 210.827112 -21.246592) (xy 210.82381 -21.254974) (xy 210.822053 -21.259541)
			(xy 210.820131 -21.269133) (xy 210.82 -21.274024) (xy 210.82 -21.34362) (xy 210.820134 -21.348511)
			(xy 210.822046 -21.358106) (xy 210.82381 -21.36267) (xy 210.827112 -21.371052) (xy 210.833716 -21.378164)
			(xy 210.852984 -21.399492) (xy 210.885543 -21.446856) (xy 210.910629 -21.498568) (xy 210.927674 -21.553458)
			(xy 210.936292 -21.610284) (xy 210.93684 -21.639022) (xy 210.936354 -21.666273) (xy 210.928598 -21.720221)
			(xy 210.913243 -21.772516) (xy 210.911801 -21.775674) (xy 220.03588 -21.775674) (xy 220.039951 -21.720052)
			(xy 220.052077 -21.665615) (xy 220.072 -21.613524) (xy 220.099296 -21.564889) (xy 220.133382 -21.520746)
			(xy 220.173531 -21.482037) (xy 220.218889 -21.449586) (xy 220.268489 -21.424085) (xy 220.321273 -21.406078)
			(xy 220.376116 -21.395948) (xy 220.43185 -21.393911) (xy 220.487287 -21.400011) (xy 220.541244 -21.414117)
			(xy 220.592573 -21.435929) (xy 220.640179 -21.464983) (xy 220.683047 -21.500658) (xy 220.720264 -21.542195)
			(xy 220.751037 -21.588708) (xy 220.774709 -21.639205) (xy 220.790777 -21.692612) (xy 220.798897 -21.747788)
			(xy 220.799406 -21.775674) (xy 220.798897 -21.80356) (xy 220.791226 -21.855684) (xy 220.938596 -21.855684)
			(xy 220.942667 -21.800062) (xy 220.954793 -21.745625) (xy 220.974716 -21.693534) (xy 221.002012 -21.644899)
			(xy 221.036098 -21.600756) (xy 221.076247 -21.562047) (xy 221.121605 -21.529596) (xy 221.171205 -21.504095)
			(xy 221.223989 -21.486088) (xy 221.278832 -21.475958) (xy 221.334566 -21.473921) (xy 221.390003 -21.480021)
			(xy 221.44396 -21.494127) (xy 221.495289 -21.515939) (xy 221.542895 -21.544993) (xy 221.585763 -21.580668)
			(xy 221.62298 -21.622205) (xy 221.653753 -21.668718) (xy 221.677425 -21.719215) (xy 221.693493 -21.772622)
			(xy 221.701613 -21.827798) (xy 221.701964 -21.847048) (xy 222.172782 -21.847048) (xy 222.176853 -21.791426)
			(xy 222.188979 -21.736989) (xy 222.208902 -21.684898) (xy 222.236198 -21.636263) (xy 222.270284 -21.59212)
			(xy 222.310433 -21.553411) (xy 222.355791 -21.52096) (xy 222.405391 -21.495459) (xy 222.458175 -21.477452)
			(xy 222.513018 -21.467322) (xy 222.568752 -21.465285) (xy 222.624189 -21.471385) (xy 222.678146 -21.485491)
			(xy 222.729475 -21.507303) (xy 222.777081 -21.536357) (xy 222.819949 -21.572032) (xy 222.857166 -21.613569)
			(xy 222.887939 -21.660082) (xy 222.911611 -21.710579) (xy 222.927679 -21.763986) (xy 222.935799 -21.819162)
			(xy 222.936308 -21.847048) (xy 222.935799 -21.874934) (xy 222.927679 -21.93011) (xy 222.911611 -21.983517)
			(xy 222.887939 -22.034014) (xy 222.857166 -22.080527) (xy 222.819949 -22.122064) (xy 222.777081 -22.157739)
			(xy 222.729475 -22.186793) (xy 222.678146 -22.208605) (xy 222.624189 -22.222711) (xy 222.568752 -22.228811)
			(xy 222.513018 -22.226774) (xy 222.458175 -22.216644) (xy 222.405391 -22.198637) (xy 222.355791 -22.173136)
			(xy 222.310433 -22.140685) (xy 222.270284 -22.101976) (xy 222.236198 -22.057833) (xy 222.208902 -22.009198)
			(xy 222.188979 -21.957107) (xy 222.176853 -21.90267) (xy 222.172782 -21.847048) (xy 221.701964 -21.847048)
			(xy 221.702122 -21.855684) (xy 221.701613 -21.88357) (xy 221.693493 -21.938746) (xy 221.677425 -21.992153)
			(xy 221.653753 -22.04265) (xy 221.62298 -22.089163) (xy 221.585763 -22.1307) (xy 221.542895 -22.166375)
			(xy 221.495289 -22.195429) (xy 221.44396 -22.217241) (xy 221.390003 -22.231347) (xy 221.334566 -22.237447)
			(xy 221.278832 -22.23541) (xy 221.223989 -22.22528) (xy 221.171205 -22.207273) (xy 221.121605 -22.181772)
			(xy 221.076247 -22.149321) (xy 221.036098 -22.110612) (xy 221.002012 -22.066469) (xy 220.974716 -22.017834)
			(xy 220.954793 -21.965743) (xy 220.942667 -21.911306) (xy 220.938596 -21.855684) (xy 220.791226 -21.855684)
			(xy 220.790777 -21.858736) (xy 220.774709 -21.912143) (xy 220.751037 -21.96264) (xy 220.720264 -22.009153)
			(xy 220.683047 -22.05069) (xy 220.640179 -22.086365) (xy 220.592573 -22.115419) (xy 220.541244 -22.137231)
			(xy 220.487287 -22.151337) (xy 220.43185 -22.157437) (xy 220.376116 -22.1554) (xy 220.321273 -22.14527)
			(xy 220.268489 -22.127263) (xy 220.218889 -22.101762) (xy 220.173531 -22.069311) (xy 220.133382 -22.030602)
			(xy 220.099296 -21.986459) (xy 220.072 -21.937824) (xy 220.052077 -21.885733) (xy 220.039951 -21.831296)
			(xy 220.03588 -21.775674) (xy 210.911801 -21.775674) (xy 210.890601 -21.822093) (xy 210.861135 -21.867943)
			(xy 210.825444 -21.909134) (xy 210.784253 -21.944825) (xy 210.738403 -21.974291) (xy 210.688826 -21.996933)
			(xy 210.636531 -22.012288) (xy 210.582583 -22.020044) (xy 210.528081 -22.020044) (xy 210.474133 -22.012288)
			(xy 210.421838 -21.996933) (xy 210.372261 -21.974291) (xy 210.326411 -21.944825) (xy 210.28522 -21.909134)
			(xy 210.249529 -21.867943) (xy 210.220063 -21.822093) (xy 210.197421 -21.772516) (xy 210.182066 -21.720221)
			(xy 210.17431 -21.666273) (xy 210.173824 -21.639022) (xy 210.174343 -21.610282) (xy 210.182964 -21.553453)
			(xy 210.200012 -21.498561) (xy 210.225103 -21.446847) (xy 210.257669 -21.399484) (xy 210.276948 -21.378164)
			(xy 210.283552 -21.371052) (xy 210.286854 -21.36267) (xy 210.288607 -21.358103) (xy 210.29052 -21.34851)
			(xy 210.290664 -21.34362) (xy 210.290664 -21.274024) (xy 210.290525 -21.269134) (xy 210.288601 -21.259544)
			(xy 210.286854 -21.254974) (xy 210.283552 -21.246592) (xy 210.276948 -21.23948) (xy 210.257674 -21.218154)
			(xy 210.225104 -21.170791) (xy 210.200008 -21.119079) (xy 210.182953 -21.064186) (xy 210.174328 -21.007356)
			(xy 210.174325 -20.949876) (xy 210.182946 -20.893045) (xy 210.199996 -20.838151) (xy 210.225088 -20.786436)
			(xy 210.257654 -20.739071) (xy 210.276948 -20.717764) (xy 210.283552 -20.710652) (xy 210.286854 -20.70227)
			(xy 210.288607 -20.697703) (xy 210.29052 -20.68811) (xy 210.290664 -20.68322) (xy 210.290664 -20.613624)
			(xy 210.290525 -20.608734) (xy 210.288601 -20.599144) (xy 210.286854 -20.594574) (xy 210.283552 -20.586192)
			(xy 210.276948 -20.57908) (xy 210.257674 -20.557754) (xy 210.225104 -20.510391) (xy 210.200008 -20.458679)
			(xy 210.182953 -20.403786) (xy 210.174328 -20.346956) (xy 210.174325 -20.289476) (xy 210.182946 -20.232645)
			(xy 210.199996 -20.177751) (xy 210.225088 -20.126036) (xy 210.257654 -20.078671) (xy 210.276948 -20.057364)
			(xy 210.283552 -20.050252) (xy 210.286854 -20.04187) (xy 210.288607 -20.037303) (xy 210.29052 -20.02771)
			(xy 210.290664 -20.02282) (xy 210.290664 -19.953224) (xy 210.290525 -19.948334) (xy 210.288601 -19.938744)
			(xy 210.286854 -19.934174) (xy 210.283552 -19.925792) (xy 210.276948 -19.91868) (xy 210.257184 -19.896794)
			(xy 210.223959 -19.848076) (xy 210.198635 -19.794822) (xy 210.181814 -19.738304) (xy 210.173898 -19.679869)
			(xy 210.175077 -19.620912) (xy 210.179666 -19.591782) (xy 210.179666 -19.591274) (xy 210.181698 -19.579844)
			(xy 210.17357 -19.555968) (xy 210.103466 -19.488912) (xy 210.093962 -19.48075) (xy 210.069842 -19.474099)
			(xy 210.057492 -19.476212) (xy 210.057238 -19.476212) (xy 210.025951 -19.482664) (xy 209.962435 -19.489533)
			(xy 209.930492 -19.489928) (xy 207.384904 -19.489928) (xy 207.35205 -19.489468) (xy 207.286755 -19.482112)
			(xy 207.222695 -19.467493) (xy 207.160674 -19.445793) (xy 207.101472 -19.417286) (xy 207.045834 -19.382331)
			(xy 206.994458 -19.341366) (xy 206.970884 -19.318478) (xy 206.73822 -19.085814) (xy 206.730818 -19.078979)
			(xy 206.712219 -19.071271) (xy 206.702152 -19.070828) (xy 203.023724 -19.070828) (xy 203.019152 -19.071082)
			(xy 203.010188 -19.07226) (xy 202.993871 -19.080023) (xy 202.981243 -19.092947) (xy 202.977242 -19.101054)
			(xy 202.940412 -19.187668) (xy 202.937712 -19.194636) (xy 202.936048 -19.20948) (xy 202.93711 -19.216878)
			(xy 202.93711 -19.217132) (xy 202.938695 -19.224296) (xy 202.945404 -19.237337) (xy 202.950318 -19.242786)
			(xy 202.950572 -19.24304) (xy 202.99401 -19.288699) (xy 203.076046 -19.384386) (xy 203.15229 -19.484749)
			(xy 203.222477 -19.589437) (xy 203.286362 -19.698085) (xy 203.343722 -19.810315) (xy 203.394358 -19.925736)
			(xy 203.438092 -20.043943) (xy 203.474772 -20.164527) (xy 203.504271 -20.287065) (xy 203.526485 -20.411131)
			(xy 203.541337 -20.536291) (xy 203.548775 -20.662111) (xy 203.54925 -20.72513) (xy 203.548744 -20.790866)
			(xy 203.540651 -20.922087) (xy 203.524494 -21.052562) (xy 203.500337 -21.181795) (xy 203.468269 -21.309295)
			(xy 203.428413 -21.434579) (xy 203.38092 -21.557173) (xy 203.325971 -21.67661) (xy 203.263772 -21.792437)
			(xy 203.194562 -21.904216) (xy 203.118601 -22.011523) (xy 203.036179 -22.113949) (xy 202.947607 -22.211108)
			(xy 202.853222 -22.302629) (xy 202.753383 -22.388167) (xy 202.648466 -22.467396) (xy 202.538872 -22.540016)
			(xy 202.512132 -22.555454) (xy 219.43644 -22.555454) (xy 219.440511 -22.499832) (xy 219.452637 -22.445395)
			(xy 219.47256 -22.393304) (xy 219.499856 -22.344669) (xy 219.533942 -22.300526) (xy 219.574091 -22.261817)
			(xy 219.619449 -22.229366) (xy 219.669049 -22.203865) (xy 219.721833 -22.185858) (xy 219.776676 -22.175728)
			(xy 219.83241 -22.173691) (xy 219.887847 -22.179791) (xy 219.941804 -22.193897) (xy 219.993133 -22.215709)
			(xy 220.040739 -22.244763) (xy 220.083607 -22.280438) (xy 220.120824 -22.321975) (xy 220.151597 -22.368488)
			(xy 220.175269 -22.418985) (xy 220.191337 -22.472392) (xy 220.199457 -22.527568) (xy 220.199966 -22.555454)
			(xy 220.199457 -22.58334) (xy 220.191337 -22.638516) (xy 220.175269 -22.691923) (xy 220.151597 -22.74242)
			(xy 220.120824 -22.788933) (xy 220.083607 -22.83047) (xy 220.040739 -22.866145) (xy 219.993133 -22.895199)
			(xy 219.941804 -22.917011) (xy 219.887847 -22.931117) (xy 219.83241 -22.937217) (xy 219.776676 -22.93518)
			(xy 219.721833 -22.92505) (xy 219.669049 -22.907043) (xy 219.619449 -22.881542) (xy 219.574091 -22.849091)
			(xy 219.533942 -22.810382) (xy 219.499856 -22.766239) (xy 219.47256 -22.717604) (xy 219.452637 -22.665513)
			(xy 219.440511 -22.611076) (xy 219.43644 -22.555454) (xy 202.512132 -22.555454) (xy 202.425014 -22.605751)
			(xy 202.307326 -22.664353) (xy 202.186254 -22.715599) (xy 202.062256 -22.759294) (xy 201.935804 -22.795273)
			(xy 201.807376 -22.823399) (xy 201.677461 -22.843565) (xy 201.546551 -22.855696) (xy 201.415142 -22.859745)
			(xy 201.283733 -22.855696) (xy 201.152823 -22.843565) (xy 201.022908 -22.823399) (xy 200.89448 -22.795273)
			(xy 200.768028 -22.759294) (xy 200.64403 -22.715599) (xy 200.522958 -22.664353) (xy 200.40527 -22.605751)
			(xy 200.291412 -22.540016) (xy 200.181818 -22.467396) (xy 200.076901 -22.388167) (xy 199.977062 -22.302629)
			(xy 199.882677 -22.211108) (xy 199.794105 -22.113949) (xy 199.711683 -22.011523) (xy 199.635722 -21.904216)
			(xy 199.566512 -21.792437) (xy 199.504313 -21.67661) (xy 199.449364 -21.557173) (xy 199.401871 -21.434579)
			(xy 199.362015 -21.309295) (xy 199.329947 -21.181795) (xy 199.30579 -21.052562) (xy 199.289633 -20.922087)
			(xy 199.28154 -20.790866) (xy 199.281034 -20.72513) (xy 199.281495 -20.66211) (xy 199.288933 -20.53629)
			(xy 199.303785 -20.411128) (xy 199.325999 -20.287062) (xy 199.355497 -20.164522) (xy 199.392178 -20.043938)
			(xy 199.435912 -19.925729) (xy 199.486548 -19.810308) (xy 199.543908 -19.698077) (xy 199.607793 -19.589428)
			(xy 199.677981 -19.484739) (xy 199.754225 -19.384375) (xy 199.83626 -19.288687) (xy 199.879712 -19.24304)
			(xy 199.879966 -19.242786) (xy 199.88482 -19.237295) (xy 199.891529 -19.224273) (xy 199.893174 -19.217132)
			(xy 199.893174 -19.216878) (xy 199.894266 -19.209481) (xy 199.892597 -19.19463) (xy 199.889872 -19.187668)
			(xy 199.853042 -19.101054) (xy 199.84906 -19.092926) (xy 199.836453 -19.079959) (xy 199.820111 -19.072212)
			(xy 199.811132 -19.071082) (xy 199.80656 -19.070828) (xy 191.277748 -19.070828) (xy 191.267757 -19.071357)
			(xy 191.249315 -19.079062) (xy 191.241934 -19.085814) (xy 191.182244 -19.145504) (xy 191.171213 -19.156265)
			(xy 191.14742 -19.175853) (xy 191.134746 -19.18462) (xy 191.12738 -19.189446) (xy 191.111632 -19.210782)
			(xy 191.108965 -19.214497) (xy 191.104872 -19.222674) (xy 191.103504 -19.227038) (xy 191.0969 -19.249898)
			(xy 191.095376 -19.26209) (xy 191.09944 -19.279362) (xy 191.102996 -19.289522) (xy 191.11461 -19.315166)
			(xy 191.131009 -19.369019) (xy 191.13931 -19.424697) (xy 191.139826 -19.452844) (xy 191.139826 -19.457924)
			(xy 191.139014 -19.48495) (xy 191.130704 -19.538377) (xy 191.114935 -19.590095) (xy 191.092023 -19.639068)
			(xy 191.062426 -19.684317) (xy 191.026737 -19.724934) (xy 190.985672 -19.760106) (xy 190.940053 -19.789128)
			(xy 190.890793 -19.811419) (xy 190.838879 -19.826533) (xy 190.785352 -19.834166) (xy 190.731284 -19.834166)
			(xy 190.677757 -19.826533) (xy 190.625843 -19.811419) (xy 190.576583 -19.789128) (xy 190.530964 -19.760106)
			(xy 190.489899 -19.724934) (xy 190.45421 -19.684317) (xy 190.424613 -19.639068) (xy 190.401701 -19.590095)
			(xy 190.385932 -19.538377) (xy 190.377622 -19.48495) (xy 190.37681 -19.457924) (xy 190.37681 -19.452844)
			(xy 190.377331 -19.424698) (xy 190.385634 -19.36902) (xy 190.402024 -19.315165) (xy 190.41364 -19.289522)
			(xy 190.417196 -19.279362) (xy 190.42126 -19.26209) (xy 190.419736 -19.249898) (xy 190.413132 -19.227038)
			(xy 190.411755 -19.222678) (xy 190.407659 -19.214505) (xy 190.405004 -19.210782) (xy 190.389256 -19.189446)
			(xy 190.38189 -19.18462) (xy 190.369216 -19.175853) (xy 190.345428 -19.15626) (xy 190.334392 -19.145504)
			(xy 190.274448 -19.08556) (xy 190.267092 -19.078908) (xy 190.248792 -19.071317) (xy 190.238888 -19.070828)
			(xy 189.392306 -19.070828) (xy 189.382236 -19.071251) (xy 189.363632 -19.078967) (xy 189.356238 -19.085814)
			(xy 189.259718 -19.182334) (xy 189.236154 -19.205231) (xy 189.18477 -19.246182) (xy 189.129127 -19.281128)
			(xy 189.069923 -19.309628) (xy 189.007903 -19.331325) (xy 188.943844 -19.345947) (xy 188.878551 -19.35331)
			(xy 188.845698 -19.353784) (xy 185.122058 -19.353784) (xy 185.086688 -19.353263) (xy 185.016465 -19.344718)
			(xy 184.947785 -19.32777) (xy 184.91454 -19.315684) (xy 184.903043 -19.311975) (xy 184.879052 -19.314507)
			(xy 184.868566 -19.32051) (xy 184.832244 -19.34464) (xy 184.820052 -19.366992) (xy 184.820052 -19.372326)
			(xy 184.827164 -19.389852) (xy 184.833768 -19.396964) (xy 184.853038 -19.418291) (xy 184.8856 -19.465652)
			(xy 184.910689 -19.517363) (xy 184.927737 -19.572252) (xy 184.936357 -19.629078) (xy 184.936354 -19.686554)
			(xy 184.927729 -19.743379) (xy 184.910677 -19.798267) (xy 184.885584 -19.849975) (xy 184.853017 -19.897334)
			(xy 184.833768 -19.91868) (xy 184.827164 -19.925792) (xy 184.823862 -19.934174) (xy 184.822107 -19.938741)
			(xy 184.820186 -19.948333) (xy 184.820052 -19.953224) (xy 184.820052 -20.02282) (xy 184.820185 -20.027711)
			(xy 184.822096 -20.037307) (xy 184.823862 -20.04187) (xy 184.827164 -20.050252) (xy 184.833768 -20.057364)
			(xy 184.853038 -20.078691) (xy 184.8856 -20.126052) (xy 184.910689 -20.177763) (xy 184.927737 -20.232652)
			(xy 184.936357 -20.289478) (xy 184.936354 -20.346954) (xy 184.927729 -20.403779) (xy 184.910677 -20.458667)
			(xy 184.906355 -20.467574) (xy 192.387472 -20.467574) (xy 192.391543 -20.411952) (xy 192.403669 -20.357515)
			(xy 192.423592 -20.305424) (xy 192.450888 -20.256789) (xy 192.484974 -20.212646) (xy 192.525123 -20.173937)
			(xy 192.570481 -20.141486) (xy 192.620081 -20.115985) (xy 192.672865 -20.097978) (xy 192.727708 -20.087848)
			(xy 192.783442 -20.085811) (xy 192.838879 -20.091911) (xy 192.892836 -20.106017) (xy 192.944165 -20.127829)
			(xy 192.991771 -20.156883) (xy 193.034639 -20.192558) (xy 193.071856 -20.234095) (xy 193.102629 -20.280608)
			(xy 193.126301 -20.331105) (xy 193.142369 -20.384512) (xy 193.150489 -20.439688) (xy 193.150998 -20.467574)
			(xy 193.150489 -20.49546) (xy 193.142369 -20.550636) (xy 193.126301 -20.604043) (xy 193.102629 -20.65454)
			(xy 193.071856 -20.701053) (xy 193.034639 -20.74259) (xy 192.991771 -20.778265) (xy 192.944165 -20.807319)
			(xy 192.892836 -20.829131) (xy 192.838879 -20.843237) (xy 192.783442 -20.849337) (xy 192.727708 -20.8473)
			(xy 192.672865 -20.83717) (xy 192.620081 -20.819163) (xy 192.570481 -20.793662) (xy 192.525123 -20.761211)
			(xy 192.484974 -20.722502) (xy 192.450888 -20.678359) (xy 192.423592 -20.629724) (xy 192.403669 -20.577633)
			(xy 192.391543 -20.523196) (xy 192.387472 -20.467574) (xy 184.906355 -20.467574) (xy 184.885584 -20.510375)
			(xy 184.853017 -20.557734) (xy 184.833768 -20.57908) (xy 184.827164 -20.586192) (xy 184.823862 -20.594574)
			(xy 184.822107 -20.599141) (xy 184.820186 -20.608733) (xy 184.820052 -20.613624) (xy 184.820052 -20.68322)
			(xy 184.820185 -20.688111) (xy 184.822096 -20.697707) (xy 184.823862 -20.70227) (xy 184.827164 -20.710652)
			(xy 184.833768 -20.717764) (xy 184.853038 -20.739091) (xy 184.8856 -20.786452) (xy 184.910689 -20.838163)
			(xy 184.927737 -20.893052) (xy 184.936357 -20.949878) (xy 184.936354 -21.007354) (xy 184.927729 -21.064179)
			(xy 184.910677 -21.119067) (xy 184.885584 -21.170775) (xy 184.853017 -21.218134) (xy 184.833768 -21.23948)
			(xy 184.827164 -21.246592) (xy 184.823862 -21.254974) (xy 184.822107 -21.259541) (xy 184.820186 -21.269133)
			(xy 184.820052 -21.274024) (xy 184.820052 -21.34362) (xy 184.820185 -21.348511) (xy 184.822096 -21.358107)
			(xy 184.823862 -21.36267) (xy 184.827164 -21.371052) (xy 184.833768 -21.378164) (xy 184.853038 -21.399491)
			(xy 184.885601 -21.446854) (xy 184.91069 -21.498566) (xy 184.927737 -21.553457) (xy 184.936357 -21.610284)
			(xy 184.936892 -21.639022) (xy 184.936406 -21.666273) (xy 184.92865 -21.720221) (xy 184.913295 -21.772516)
			(xy 184.911853 -21.775674) (xy 194.035932 -21.775674) (xy 194.040003 -21.720052) (xy 194.052129 -21.665615)
			(xy 194.072052 -21.613524) (xy 194.099348 -21.564889) (xy 194.133434 -21.520746) (xy 194.173583 -21.482037)
			(xy 194.218941 -21.449586) (xy 194.268541 -21.424085) (xy 194.321325 -21.406078) (xy 194.376168 -21.395948)
			(xy 194.431902 -21.393911) (xy 194.487339 -21.400011) (xy 194.541296 -21.414117) (xy 194.592625 -21.435929)
			(xy 194.640231 -21.464983) (xy 194.683099 -21.500658) (xy 194.720316 -21.542195) (xy 194.751089 -21.588708)
			(xy 194.774761 -21.639205) (xy 194.790829 -21.692612) (xy 194.798949 -21.747788) (xy 194.799458 -21.775674)
			(xy 194.798949 -21.80356) (xy 194.791278 -21.855684) (xy 194.938648 -21.855684) (xy 194.942719 -21.800062)
			(xy 194.954845 -21.745625) (xy 194.974768 -21.693534) (xy 195.002064 -21.644899) (xy 195.03615 -21.600756)
			(xy 195.076299 -21.562047) (xy 195.121657 -21.529596) (xy 195.171257 -21.504095) (xy 195.224041 -21.486088)
			(xy 195.278884 -21.475958) (xy 195.334618 -21.473921) (xy 195.390055 -21.480021) (xy 195.444012 -21.494127)
			(xy 195.495341 -21.515939) (xy 195.542947 -21.544993) (xy 195.585815 -21.580668) (xy 195.623032 -21.622205)
			(xy 195.653805 -21.668718) (xy 195.677477 -21.719215) (xy 195.693545 -21.772622) (xy 195.701665 -21.827798)
			(xy 195.702016 -21.847048) (xy 196.172834 -21.847048) (xy 196.176905 -21.791426) (xy 196.189031 -21.736989)
			(xy 196.208954 -21.684898) (xy 196.23625 -21.636263) (xy 196.270336 -21.59212) (xy 196.310485 -21.553411)
			(xy 196.355843 -21.52096) (xy 196.405443 -21.495459) (xy 196.458227 -21.477452) (xy 196.51307 -21.467322)
			(xy 196.568804 -21.465285) (xy 196.624241 -21.471385) (xy 196.678198 -21.485491) (xy 196.729527 -21.507303)
			(xy 196.777133 -21.536357) (xy 196.820001 -21.572032) (xy 196.857218 -21.613569) (xy 196.887991 -21.660082)
			(xy 196.911663 -21.710579) (xy 196.927731 -21.763986) (xy 196.935851 -21.819162) (xy 196.93636 -21.847048)
			(xy 196.935851 -21.874934) (xy 196.927731 -21.93011) (xy 196.911663 -21.983517) (xy 196.887991 -22.034014)
			(xy 196.857218 -22.080527) (xy 196.820001 -22.122064) (xy 196.777133 -22.157739) (xy 196.729527 -22.186793)
			(xy 196.678198 -22.208605) (xy 196.624241 -22.222711) (xy 196.568804 -22.228811) (xy 196.51307 -22.226774)
			(xy 196.458227 -22.216644) (xy 196.405443 -22.198637) (xy 196.355843 -22.173136) (xy 196.310485 -22.140685)
			(xy 196.270336 -22.101976) (xy 196.23625 -22.057833) (xy 196.208954 -22.009198) (xy 196.189031 -21.957107)
			(xy 196.176905 -21.90267) (xy 196.172834 -21.847048) (xy 195.702016 -21.847048) (xy 195.702174 -21.855684)
			(xy 195.701665 -21.88357) (xy 195.693545 -21.938746) (xy 195.677477 -21.992153) (xy 195.653805 -22.04265)
			(xy 195.623032 -22.089163) (xy 195.585815 -22.1307) (xy 195.542947 -22.166375) (xy 195.495341 -22.195429)
			(xy 195.444012 -22.217241) (xy 195.390055 -22.231347) (xy 195.334618 -22.237447) (xy 195.278884 -22.23541)
			(xy 195.224041 -22.22528) (xy 195.171257 -22.207273) (xy 195.121657 -22.181772) (xy 195.076299 -22.149321)
			(xy 195.03615 -22.110612) (xy 195.002064 -22.066469) (xy 194.974768 -22.017834) (xy 194.954845 -21.965743)
			(xy 194.942719 -21.911306) (xy 194.938648 -21.855684) (xy 194.791278 -21.855684) (xy 194.790829 -21.858736)
			(xy 194.774761 -21.912143) (xy 194.751089 -21.96264) (xy 194.720316 -22.009153) (xy 194.683099 -22.05069)
			(xy 194.640231 -22.086365) (xy 194.592625 -22.115419) (xy 194.541296 -22.137231) (xy 194.487339 -22.151337)
			(xy 194.431902 -22.157437) (xy 194.376168 -22.1554) (xy 194.321325 -22.14527) (xy 194.268541 -22.127263)
			(xy 194.218941 -22.101762) (xy 194.173583 -22.069311) (xy 194.133434 -22.030602) (xy 194.099348 -21.986459)
			(xy 194.072052 -21.937824) (xy 194.052129 -21.885733) (xy 194.040003 -21.831296) (xy 194.035932 -21.775674)
			(xy 184.911853 -21.775674) (xy 184.890653 -21.822093) (xy 184.861187 -21.867943) (xy 184.825496 -21.909134)
			(xy 184.784305 -21.944825) (xy 184.738455 -21.974291) (xy 184.688878 -21.996933) (xy 184.636583 -22.012288)
			(xy 184.582635 -22.020044) (xy 184.528133 -22.020044) (xy 184.474185 -22.012288) (xy 184.42189 -21.996933)
			(xy 184.372313 -21.974291) (xy 184.326463 -21.944825) (xy 184.285272 -21.909134) (xy 184.249581 -21.867943)
			(xy 184.220115 -21.822093) (xy 184.197473 -21.772516) (xy 184.182118 -21.720221) (xy 184.174362 -21.666273)
			(xy 184.173876 -21.639022) (xy 184.174396 -21.610283) (xy 184.183017 -21.553455) (xy 184.200067 -21.498564)
			(xy 184.225161 -21.446852) (xy 184.257729 -21.399491) (xy 184.277 -21.378164) (xy 184.283604 -21.371052)
			(xy 184.286906 -21.36267) (xy 184.288657 -21.358102) (xy 184.290569 -21.34851) (xy 184.290716 -21.34362)
			(xy 184.290716 -21.274024) (xy 184.290577 -21.269134) (xy 184.288655 -21.259543) (xy 184.286906 -21.254974)
			(xy 184.283604 -21.246592) (xy 184.277 -21.23948) (xy 184.257729 -21.218153) (xy 184.225162 -21.170789)
			(xy 184.200069 -21.119076) (xy 184.183017 -21.064184) (xy 184.174392 -21.007356) (xy 184.17439 -20.949876)
			(xy 184.18301 -20.893047) (xy 184.200057 -20.838154) (xy 184.225146 -20.786439) (xy 184.257708 -20.739072)
			(xy 184.277 -20.717764) (xy 184.283604 -20.710652) (xy 184.286906 -20.70227) (xy 184.288657 -20.697702)
			(xy 184.290569 -20.68811) (xy 184.290716 -20.68322) (xy 184.290716 -20.613624) (xy 184.290577 -20.608734)
			(xy 184.288655 -20.599143) (xy 184.286906 -20.594574) (xy 184.283604 -20.586192) (xy 184.277 -20.57908)
			(xy 184.257729 -20.557753) (xy 184.225162 -20.510389) (xy 184.200069 -20.458676) (xy 184.183017 -20.403784)
			(xy 184.174392 -20.346956) (xy 184.17439 -20.289476) (xy 184.18301 -20.232647) (xy 184.200057 -20.177754)
			(xy 184.225146 -20.126039) (xy 184.257708 -20.078672) (xy 184.277 -20.057364) (xy 184.283604 -20.050252)
			(xy 184.286906 -20.04187) (xy 184.288657 -20.037302) (xy 184.290569 -20.02771) (xy 184.290716 -20.02282)
			(xy 184.290716 -19.953224) (xy 184.290577 -19.948334) (xy 184.288655 -19.938743) (xy 184.286906 -19.934174)
			(xy 184.283604 -19.925792) (xy 184.277 -19.91868) (xy 184.257729 -19.897353) (xy 184.225162 -19.849989)
			(xy 184.200069 -19.798276) (xy 184.183017 -19.743384) (xy 184.174392 -19.686556) (xy 184.17439 -19.629076)
			(xy 184.18301 -19.572247) (xy 184.200057 -19.517354) (xy 184.225146 -19.465639) (xy 184.257708 -19.418272)
			(xy 184.277 -19.396964) (xy 184.283604 -19.389852) (xy 184.286906 -19.38147) (xy 184.288657 -19.376902)
			(xy 184.290569 -19.36731) (xy 184.290716 -19.36242) (xy 184.290716 -19.292824) (xy 184.290577 -19.287934)
			(xy 184.288655 -19.278343) (xy 184.286906 -19.273774) (xy 184.283604 -19.265392) (xy 184.277 -19.25828)
			(xy 184.26938 -19.249898) (xy 184.26811 -19.248628) (xy 184.267094 -19.247612) (xy 184.25966 -19.240896)
			(xy 184.24116 -19.23326) (xy 184.221146 -19.23326) (xy 184.202646 -19.240896) (xy 184.195212 -19.247612)
			(xy 184.103518 -19.339306) (xy 184.079954 -19.362204) (xy 184.028571 -19.403157) (xy 183.972928 -19.438104)
			(xy 183.913725 -19.466606) (xy 183.851704 -19.488304) (xy 183.787645 -19.502927) (xy 183.722351 -19.51029)
			(xy 183.689498 -19.510756) (xy 180.800756 -19.510756) (xy 180.767901 -19.510299) (xy 180.702603 -19.502949)
			(xy 180.638539 -19.488334) (xy 180.576513 -19.46664) (xy 180.517306 -19.438137) (xy 180.461663 -19.403186)
			(xy 180.410282 -19.362224) (xy 180.386736 -19.339306) (xy 180.14442 -19.09699) (xy 180.137022 -19.090146)
			(xy 180.118422 -19.082427) (xy 180.108352 -19.082004) (xy 176.992026 -19.082004) (xy 176.987236 -19.086076)
			(xy 176.979647 -19.096095) (xy 176.97704 -19.101816) (xy 176.94783 -19.170142) (xy 176.940464 -19.187922)
			(xy 176.937764 -19.194826) (xy 176.936075 -19.209546) (xy 176.937162 -19.216878) (xy 176.937162 -19.217132)
			(xy 176.938748 -19.224295) (xy 176.945463 -19.237332) (xy 176.95037 -19.242786) (xy 176.950624 -19.24304)
			(xy 176.994063 -19.288699) (xy 177.0761 -19.384385) (xy 177.152345 -19.484747) (xy 177.222534 -19.589435)
			(xy 177.28642 -19.698083) (xy 177.343782 -19.810313) (xy 177.394419 -19.925733) (xy 177.438154 -20.043941)
			(xy 177.474835 -20.164525) (xy 177.504335 -20.287063) (xy 177.526549 -20.41113) (xy 177.541402 -20.536291)
			(xy 177.54884 -20.66211) (xy 177.549302 -20.72513) (xy 177.548796 -20.790866) (xy 177.540703 -20.922087)
			(xy 177.524546 -21.052562) (xy 177.500389 -21.181795) (xy 177.468321 -21.309295) (xy 177.428465 -21.434579)
			(xy 177.380972 -21.557173) (xy 177.326023 -21.67661) (xy 177.263824 -21.792437) (xy 177.194614 -21.904216)
			(xy 177.118653 -22.011523) (xy 177.036231 -22.113949) (xy 176.947659 -22.211108) (xy 176.853274 -22.302629)
			(xy 176.753435 -22.388167) (xy 176.648518 -22.467396) (xy 176.538924 -22.540016) (xy 176.512184 -22.555454)
			(xy 193.436492 -22.555454) (xy 193.440563 -22.499832) (xy 193.452689 -22.445395) (xy 193.472612 -22.393304)
			(xy 193.499908 -22.344669) (xy 193.533994 -22.300526) (xy 193.574143 -22.261817) (xy 193.619501 -22.229366)
			(xy 193.669101 -22.203865) (xy 193.721885 -22.185858) (xy 193.776728 -22.175728) (xy 193.832462 -22.173691)
			(xy 193.887899 -22.179791) (xy 193.941856 -22.193897) (xy 193.993185 -22.215709) (xy 194.040791 -22.244763)
			(xy 194.083659 -22.280438) (xy 194.120876 -22.321975) (xy 194.151649 -22.368488) (xy 194.175321 -22.418985)
			(xy 194.191389 -22.472392) (xy 194.199509 -22.527568) (xy 194.200018 -22.555454) (xy 194.199509 -22.58334)
			(xy 194.191389 -22.638516) (xy 194.175321 -22.691923) (xy 194.151649 -22.74242) (xy 194.120876 -22.788933)
			(xy 194.083659 -22.83047) (xy 194.040791 -22.866145) (xy 193.993185 -22.895199) (xy 193.941856 -22.917011)
			(xy 193.887899 -22.931117) (xy 193.832462 -22.937217) (xy 193.776728 -22.93518) (xy 193.721885 -22.92505)
			(xy 193.669101 -22.907043) (xy 193.619501 -22.881542) (xy 193.574143 -22.849091) (xy 193.533994 -22.810382)
			(xy 193.499908 -22.766239) (xy 193.472612 -22.717604) (xy 193.452689 -22.665513) (xy 193.440563 -22.611076)
			(xy 193.436492 -22.555454) (xy 176.512184 -22.555454) (xy 176.425066 -22.605751) (xy 176.307378 -22.664353)
			(xy 176.186306 -22.715599) (xy 176.062308 -22.759294) (xy 175.935856 -22.795273) (xy 175.807428 -22.823399)
			(xy 175.677513 -22.843565) (xy 175.546603 -22.855696) (xy 175.415194 -22.859745) (xy 175.283785 -22.855696)
			(xy 175.152875 -22.843565) (xy 175.02296 -22.823399) (xy 174.894532 -22.795273) (xy 174.76808 -22.759294)
			(xy 174.644082 -22.715599) (xy 174.52301 -22.664353) (xy 174.405322 -22.605751) (xy 174.291464 -22.540016)
			(xy 174.18187 -22.467396) (xy 174.076953 -22.388167) (xy 173.977114 -22.302629) (xy 173.882729 -22.211108)
			(xy 173.794157 -22.113949) (xy 173.711735 -22.011523) (xy 173.635774 -21.904216) (xy 173.566564 -21.792437)
			(xy 173.504365 -21.67661) (xy 173.449416 -21.557173) (xy 173.401923 -21.434579) (xy 173.362067 -21.309295)
			(xy 173.329999 -21.181795) (xy 173.305842 -21.052562) (xy 173.289685 -20.922087) (xy 173.281592 -20.790866)
			(xy 173.281086 -20.72513) (xy 173.281547 -20.66211) (xy 173.288985 -20.53629) (xy 173.303836 -20.411128)
			(xy 173.32605 -20.287061) (xy 173.355548 -20.164521) (xy 173.392228 -20.043936) (xy 173.435962 -19.925727)
			(xy 173.486596 -19.810305) (xy 173.543956 -19.698073) (xy 173.60784 -19.589423) (xy 173.678026 -19.484733)
			(xy 173.754269 -19.384368) (xy 173.836303 -19.288678) (xy 173.879764 -19.24304) (xy 173.880018 -19.242786)
			(xy 173.884876 -19.237297) (xy 173.891591 -19.224276) (xy 173.893226 -19.217132) (xy 173.893226 -19.216878)
			(xy 173.894266 -19.209545) (xy 173.892582 -19.194836) (xy 173.889924 -19.187922) (xy 173.882558 -19.170142)
			(xy 173.853348 -19.101816) (xy 173.850727 -19.096102) (xy 173.843154 -19.086072) (xy 173.838362 -19.082004)
			(xy 166.120826 -19.082004) (xy 166.09348 -19.081629) (xy 166.039035 -19.076412) (xy 166.012114 -19.07159)
			(xy 166.007542 -19.070828) (xy 165.2778 -19.070828) (xy 165.267813 -19.071366) (xy 165.249384 -19.079083)
			(xy 165.241986 -19.085814) (xy 165.182296 -19.145504) (xy 165.171266 -19.156266) (xy 165.147475 -19.175858)
			(xy 165.134798 -19.18462) (xy 165.127432 -19.189446) (xy 165.111684 -19.210782) (xy 165.109015 -19.214496)
			(xy 165.104918 -19.222672) (xy 165.103556 -19.227038) (xy 165.096952 -19.249898) (xy 165.095428 -19.26209)
			(xy 165.099492 -19.279362) (xy 165.103048 -19.289522) (xy 165.114664 -19.315166) (xy 165.131065 -19.369018)
			(xy 165.139367 -19.424697) (xy 165.139878 -19.452844) (xy 165.139878 -19.457924) (xy 165.139066 -19.48495)
			(xy 165.130756 -19.538377) (xy 165.114987 -19.590095) (xy 165.092075 -19.639068) (xy 165.062478 -19.684317)
			(xy 165.026789 -19.724934) (xy 164.985724 -19.760106) (xy 164.940105 -19.789128) (xy 164.890845 -19.811419)
			(xy 164.838931 -19.826533) (xy 164.785404 -19.834166) (xy 164.731336 -19.834166) (xy 164.677809 -19.826533)
			(xy 164.625895 -19.811419) (xy 164.576635 -19.789128) (xy 164.531016 -19.760106) (xy 164.489951 -19.724934)
			(xy 164.454262 -19.684317) (xy 164.424665 -19.639068) (xy 164.401753 -19.590095) (xy 164.385984 -19.538377)
			(xy 164.377674 -19.48495) (xy 164.376862 -19.457924) (xy 164.376862 -19.452844) (xy 164.377383 -19.424697)
			(xy 164.385685 -19.369019) (xy 164.402073 -19.315163) (xy 164.413692 -19.289522) (xy 164.417248 -19.279362)
			(xy 164.421312 -19.26209) (xy 164.419788 -19.249898) (xy 164.413184 -19.227038) (xy 164.411809 -19.222677)
			(xy 164.407715 -19.214502) (xy 164.405056 -19.210782) (xy 164.389308 -19.189446) (xy 164.381942 -19.18462)
			(xy 164.369267 -19.175855) (xy 164.345476 -19.156264) (xy 164.334444 -19.145504) (xy 164.2745 -19.08556)
			(xy 164.267142 -19.078916) (xy 164.248841 -19.071342) (xy 164.23894 -19.070828) (xy 163.403026 -19.070828)
			(xy 163.392962 -19.071265) (xy 163.37438 -19.079002) (xy 163.366958 -19.085814) (xy 163.22421 -19.228562)
			(xy 163.200645 -19.251457) (xy 163.14926 -19.292407) (xy 163.093617 -19.32735) (xy 163.034413 -19.355848)
			(xy 162.972393 -19.377543) (xy 162.908334 -19.392163) (xy 162.843043 -19.399524) (xy 162.81019 -19.400012)
			(xy 159.093662 -19.400012) (xy 159.075967 -19.399936) (xy 159.040637 -19.397903) (xy 159.02305 -19.395948)
			(xy 159.010096 -19.39417) (xy 158.985712 -19.404076) (xy 158.923482 -19.4818) (xy 158.918305 -19.488732)
			(xy 158.912521 -19.505025) (xy 158.912511 -19.522314) (xy 158.9151 -19.530568) (xy 158.925314 -19.561384)
			(xy 158.9363 -19.625364) (xy 158.936944 -19.657822) (xy 158.936421 -19.68656) (xy 158.927795 -19.743385)
			(xy 158.91074 -19.798273) (xy 158.885644 -19.849981) (xy 158.853073 -19.897338) (xy 158.83382 -19.91868)
			(xy 158.827216 -19.925792) (xy 158.823914 -19.934174) (xy 158.822157 -19.938741) (xy 158.820234 -19.948333)
			(xy 158.820104 -19.953224) (xy 158.820104 -20.02282) (xy 158.820238 -20.027711) (xy 158.82215 -20.037306)
			(xy 158.823914 -20.04187) (xy 158.827216 -20.050252) (xy 158.83382 -20.057364) (xy 158.853087 -20.078692)
			(xy 158.885645 -20.126055) (xy 158.910731 -20.177766) (xy 158.927776 -20.232654) (xy 158.936395 -20.289479)
			(xy 158.936392 -20.346953) (xy 158.927769 -20.403777) (xy 158.910719 -20.458664) (xy 158.906396 -20.467574)
			(xy 166.387524 -20.467574) (xy 166.391595 -20.411952) (xy 166.403721 -20.357515) (xy 166.423644 -20.305424)
			(xy 166.45094 -20.256789) (xy 166.485026 -20.212646) (xy 166.525175 -20.173937) (xy 166.570533 -20.141486)
			(xy 166.620133 -20.115985) (xy 166.672917 -20.097978) (xy 166.72776 -20.087848) (xy 166.783494 -20.085811)
			(xy 166.838931 -20.091911) (xy 166.892888 -20.106017) (xy 166.944217 -20.127829) (xy 166.991823 -20.156883)
			(xy 167.034691 -20.192558) (xy 167.071908 -20.234095) (xy 167.102681 -20.280608) (xy 167.126353 -20.331105)
			(xy 167.142421 -20.384512) (xy 167.150541 -20.439688) (xy 167.15105 -20.467574) (xy 167.150541 -20.49546)
			(xy 167.142421 -20.550636) (xy 167.126353 -20.604043) (xy 167.102681 -20.65454) (xy 167.071908 -20.701053)
			(xy 167.034691 -20.74259) (xy 166.991823 -20.778265) (xy 166.944217 -20.807319) (xy 166.892888 -20.829131)
			(xy 166.838931 -20.843237) (xy 166.783494 -20.849337) (xy 166.72776 -20.8473) (xy 166.672917 -20.83717)
			(xy 166.620133 -20.819163) (xy 166.570533 -20.793662) (xy 166.525175 -20.761211) (xy 166.485026 -20.722502)
			(xy 166.45094 -20.678359) (xy 166.423644 -20.629724) (xy 166.403721 -20.577633) (xy 166.391595 -20.523196)
			(xy 166.387524 -20.467574) (xy 158.906396 -20.467574) (xy 158.885629 -20.510373) (xy 158.853067 -20.557733)
			(xy 158.83382 -20.57908) (xy 158.827216 -20.586192) (xy 158.823914 -20.594574) (xy 158.822157 -20.599141)
			(xy 158.820234 -20.608733) (xy 158.820104 -20.613624) (xy 158.820104 -20.68322) (xy 158.820238 -20.688111)
			(xy 158.82215 -20.697706) (xy 158.823914 -20.70227) (xy 158.827216 -20.710652) (xy 158.83382 -20.717764)
			(xy 158.853087 -20.739092) (xy 158.885645 -20.786455) (xy 158.910731 -20.838166) (xy 158.927776 -20.893054)
			(xy 158.936395 -20.949879) (xy 158.936392 -21.007353) (xy 158.927769 -21.064177) (xy 158.910719 -21.119064)
			(xy 158.885629 -21.170773) (xy 158.853067 -21.218133) (xy 158.83382 -21.23948) (xy 158.827216 -21.246592)
			(xy 158.823914 -21.254974) (xy 158.822157 -21.259541) (xy 158.820234 -21.269133) (xy 158.820104 -21.274024)
			(xy 158.820104 -21.34362) (xy 158.820238 -21.348511) (xy 158.82215 -21.358106) (xy 158.823914 -21.36267)
			(xy 158.827216 -21.371052) (xy 158.83382 -21.378164) (xy 158.853088 -21.399492) (xy 158.885646 -21.446856)
			(xy 158.910732 -21.498568) (xy 158.927777 -21.553458) (xy 158.936395 -21.610284) (xy 158.936944 -21.639022)
			(xy 158.936458 -21.666273) (xy 158.928702 -21.720221) (xy 158.913347 -21.772516) (xy 158.911905 -21.775674)
			(xy 168.035984 -21.775674) (xy 168.040055 -21.720052) (xy 168.052181 -21.665615) (xy 168.072104 -21.613524)
			(xy 168.0994 -21.564889) (xy 168.133486 -21.520746) (xy 168.173635 -21.482037) (xy 168.218993 -21.449586)
			(xy 168.268593 -21.424085) (xy 168.321377 -21.406078) (xy 168.37622 -21.395948) (xy 168.431954 -21.393911)
			(xy 168.487391 -21.400011) (xy 168.541348 -21.414117) (xy 168.592677 -21.435929) (xy 168.640283 -21.464983)
			(xy 168.683151 -21.500658) (xy 168.720368 -21.542195) (xy 168.751141 -21.588708) (xy 168.774813 -21.639205)
			(xy 168.790881 -21.692612) (xy 168.799001 -21.747788) (xy 168.79951 -21.775674) (xy 168.799001 -21.80356)
			(xy 168.79133 -21.855684) (xy 168.9387 -21.855684) (xy 168.942771 -21.800062) (xy 168.954897 -21.745625)
			(xy 168.97482 -21.693534) (xy 169.002116 -21.644899) (xy 169.036202 -21.600756) (xy 169.076351 -21.562047)
			(xy 169.121709 -21.529596) (xy 169.171309 -21.504095) (xy 169.224093 -21.486088) (xy 169.278936 -21.475958)
			(xy 169.33467 -21.473921) (xy 169.390107 -21.480021) (xy 169.444064 -21.494127) (xy 169.495393 -21.515939)
			(xy 169.542999 -21.544993) (xy 169.585867 -21.580668) (xy 169.623084 -21.622205) (xy 169.653857 -21.668718)
			(xy 169.677529 -21.719215) (xy 169.693597 -21.772622) (xy 169.701717 -21.827798) (xy 169.702068 -21.847048)
			(xy 170.172886 -21.847048) (xy 170.176957 -21.791426) (xy 170.189083 -21.736989) (xy 170.209006 -21.684898)
			(xy 170.236302 -21.636263) (xy 170.270388 -21.59212) (xy 170.310537 -21.553411) (xy 170.355895 -21.52096)
			(xy 170.405495 -21.495459) (xy 170.458279 -21.477452) (xy 170.513122 -21.467322) (xy 170.568856 -21.465285)
			(xy 170.624293 -21.471385) (xy 170.67825 -21.485491) (xy 170.729579 -21.507303) (xy 170.777185 -21.536357)
			(xy 170.820053 -21.572032) (xy 170.85727 -21.613569) (xy 170.888043 -21.660082) (xy 170.911715 -21.710579)
			(xy 170.927783 -21.763986) (xy 170.935903 -21.819162) (xy 170.936412 -21.847048) (xy 170.935903 -21.874934)
			(xy 170.927783 -21.93011) (xy 170.911715 -21.983517) (xy 170.888043 -22.034014) (xy 170.85727 -22.080527)
			(xy 170.820053 -22.122064) (xy 170.777185 -22.157739) (xy 170.729579 -22.186793) (xy 170.67825 -22.208605)
			(xy 170.624293 -22.222711) (xy 170.568856 -22.228811) (xy 170.513122 -22.226774) (xy 170.458279 -22.216644)
			(xy 170.405495 -22.198637) (xy 170.355895 -22.173136) (xy 170.310537 -22.140685) (xy 170.270388 -22.101976)
			(xy 170.236302 -22.057833) (xy 170.209006 -22.009198) (xy 170.189083 -21.957107) (xy 170.176957 -21.90267)
			(xy 170.172886 -21.847048) (xy 169.702068 -21.847048) (xy 169.702226 -21.855684) (xy 169.701717 -21.88357)
			(xy 169.693597 -21.938746) (xy 169.677529 -21.992153) (xy 169.653857 -22.04265) (xy 169.623084 -22.089163)
			(xy 169.585867 -22.1307) (xy 169.542999 -22.166375) (xy 169.495393 -22.195429) (xy 169.444064 -22.217241)
			(xy 169.390107 -22.231347) (xy 169.33467 -22.237447) (xy 169.278936 -22.23541) (xy 169.224093 -22.22528)
			(xy 169.171309 -22.207273) (xy 169.121709 -22.181772) (xy 169.076351 -22.149321) (xy 169.036202 -22.110612)
			(xy 169.002116 -22.066469) (xy 168.97482 -22.017834) (xy 168.954897 -21.965743) (xy 168.942771 -21.911306)
			(xy 168.9387 -21.855684) (xy 168.79133 -21.855684) (xy 168.790881 -21.858736) (xy 168.774813 -21.912143)
			(xy 168.751141 -21.96264) (xy 168.720368 -22.009153) (xy 168.683151 -22.05069) (xy 168.640283 -22.086365)
			(xy 168.592677 -22.115419) (xy 168.541348 -22.137231) (xy 168.487391 -22.151337) (xy 168.431954 -22.157437)
			(xy 168.37622 -22.1554) (xy 168.321377 -22.14527) (xy 168.268593 -22.127263) (xy 168.218993 -22.101762)
			(xy 168.173635 -22.069311) (xy 168.133486 -22.030602) (xy 168.0994 -21.986459) (xy 168.072104 -21.937824)
			(xy 168.052181 -21.885733) (xy 168.040055 -21.831296) (xy 168.035984 -21.775674) (xy 158.911905 -21.775674)
			(xy 158.890705 -21.822093) (xy 158.861239 -21.867943) (xy 158.825548 -21.909134) (xy 158.784357 -21.944825)
			(xy 158.738507 -21.974291) (xy 158.68893 -21.996933) (xy 158.636635 -22.012288) (xy 158.582687 -22.020044)
			(xy 158.528185 -22.020044) (xy 158.474237 -22.012288) (xy 158.421942 -21.996933) (xy 158.372365 -21.974291)
			(xy 158.326515 -21.944825) (xy 158.285324 -21.909134) (xy 158.249633 -21.867943) (xy 158.220167 -21.822093)
			(xy 158.197525 -21.772516) (xy 158.18217 -21.720221) (xy 158.174414 -21.666273) (xy 158.173928 -21.639022)
			(xy 158.174447 -21.610282) (xy 158.183068 -21.553454) (xy 158.200116 -21.498561) (xy 158.225207 -21.446848)
			(xy 158.257773 -21.399484) (xy 158.277052 -21.378164) (xy 158.283656 -21.371052) (xy 158.286958 -21.36267)
			(xy 158.288711 -21.358103) (xy 158.290624 -21.34851) (xy 158.290768 -21.34362) (xy 158.290768 -21.274024)
			(xy 158.290629 -21.269134) (xy 158.288705 -21.259544) (xy 158.286958 -21.254974) (xy 158.283656 -21.246592)
			(xy 158.277052 -21.23948) (xy 158.257778 -21.218154) (xy 158.225207 -21.170792) (xy 158.200111 -21.119079)
			(xy 158.183056 -21.064186) (xy 158.17443 -21.007356) (xy 158.174428 -20.949876) (xy 158.183049 -20.893045)
			(xy 158.200099 -20.838151) (xy 158.225191 -20.786436) (xy 158.257758 -20.739071) (xy 158.277052 -20.717764)
			(xy 158.283656 -20.710652) (xy 158.286958 -20.70227) (xy 158.288711 -20.697703) (xy 158.290624 -20.68811)
			(xy 158.290768 -20.68322) (xy 158.290768 -20.613624) (xy 158.290629 -20.608734) (xy 158.288705 -20.599144)
			(xy 158.286958 -20.594574) (xy 158.283656 -20.586192) (xy 158.277052 -20.57908) (xy 158.257778 -20.557754)
			(xy 158.225207 -20.510392) (xy 158.200111 -20.458679) (xy 158.183056 -20.403786) (xy 158.17443 -20.346956)
			(xy 158.174428 -20.289476) (xy 158.183049 -20.232645) (xy 158.200099 -20.177751) (xy 158.225191 -20.126036)
			(xy 158.257758 -20.078671) (xy 158.277052 -20.057364) (xy 158.283656 -20.050252) (xy 158.286958 -20.04187)
			(xy 158.288711 -20.037303) (xy 158.290624 -20.02771) (xy 158.290768 -20.02282) (xy 158.290768 -19.953224)
			(xy 158.290629 -19.948334) (xy 158.288705 -19.938744) (xy 158.286958 -19.934174) (xy 158.283656 -19.925792)
			(xy 158.277052 -19.91868) (xy 158.257778 -19.897354) (xy 158.225207 -19.849992) (xy 158.200111 -19.798279)
			(xy 158.183056 -19.743386) (xy 158.17443 -19.686556) (xy 158.174428 -19.629076) (xy 158.183049 -19.572245)
			(xy 158.200099 -19.517351) (xy 158.225191 -19.465636) (xy 158.257758 -19.418271) (xy 158.277052 -19.396964)
			(xy 158.283656 -19.389852) (xy 158.286958 -19.38147) (xy 158.288711 -19.376903) (xy 158.290624 -19.36731)
			(xy 158.290768 -19.36242) (xy 158.290768 -19.292824) (xy 158.290629 -19.287934) (xy 158.288705 -19.278344)
			(xy 158.286958 -19.273774) (xy 158.283656 -19.265392) (xy 158.277052 -19.25828) (xy 158.255208 -19.23288)
			(xy 158.253938 -19.231356) (xy 158.251906 -19.229324) (xy 158.244472 -19.222608) (xy 158.225972 -19.214972)
			(xy 158.205958 -19.214972) (xy 158.187458 -19.222608) (xy 158.180024 -19.229324) (xy 158.122874 -19.286474)
			(xy 158.09931 -19.309372) (xy 158.047926 -19.350326) (xy 157.992283 -19.385274) (xy 157.93308 -19.413778)
			(xy 157.87106 -19.435479) (xy 157.807001 -19.450106) (xy 157.741708 -19.457474) (xy 157.708854 -19.457924)
			(xy 154.822652 -19.457924) (xy 154.789797 -19.457467) (xy 154.7245 -19.450116) (xy 154.660436 -19.4355)
			(xy 154.598412 -19.413804) (xy 154.539206 -19.385301) (xy 154.483564 -19.350347) (xy 154.432185 -19.309384)
			(xy 154.408632 -19.286474) (xy 154.207972 -19.085814) (xy 154.200573 -19.07897) (xy 154.181974 -19.071244)
			(xy 154.171904 -19.070828) (xy 151.023828 -19.070828) (xy 151.014026 -19.071287) (xy 150.99586 -19.078657)
			(xy 150.981777 -19.092296) (xy 150.977346 -19.101054) (xy 150.940516 -19.187668) (xy 150.937816 -19.194636)
			(xy 150.936151 -19.20948) (xy 150.937214 -19.216878) (xy 150.937214 -19.217132) (xy 150.938799 -19.224296)
			(xy 150.945509 -19.237337) (xy 150.950422 -19.242786) (xy 150.950676 -19.24304) (xy 150.994097 -19.288697)
			(xy 151.076099 -19.384376) (xy 151.152312 -19.484727) (xy 151.22247 -19.589402) (xy 151.286327 -19.698034)
			(xy 151.343663 -19.810246) (xy 151.394276 -19.925646) (xy 151.43799 -20.043832) (xy 151.474653 -20.164391)
			(xy 151.504137 -20.286905) (xy 151.526339 -20.410945) (xy 151.541182 -20.536079) (xy 151.548615 -20.66187)
			(xy 151.5491 -20.724876) (xy 151.548623 -20.789348) (xy 151.540839 -20.918057) (xy 151.525298 -21.04606)
			(xy 151.502057 -21.172892) (xy 151.471199 -21.298089) (xy 151.432839 -21.421195) (xy 151.387116 -21.54176)
			(xy 151.334197 -21.659344) (xy 151.274274 -21.773519) (xy 151.207568 -21.883867) (xy 151.13432 -21.989986)
			(xy 151.054798 -22.091489) (xy 150.969293 -22.188005) (xy 150.878116 -22.279182) (xy 150.781601 -22.364688)
			(xy 150.680099 -22.44421) (xy 150.57398 -22.517459) (xy 150.511129 -22.555454) (xy 167.436544 -22.555454)
			(xy 167.440615 -22.499832) (xy 167.452741 -22.445395) (xy 167.472664 -22.393304) (xy 167.49996 -22.344669)
			(xy 167.534046 -22.300526) (xy 167.574195 -22.261817) (xy 167.619553 -22.229366) (xy 167.669153 -22.203865)
			(xy 167.721937 -22.185858) (xy 167.77678 -22.175728) (xy 167.832514 -22.173691) (xy 167.887951 -22.179791)
			(xy 167.941908 -22.193897) (xy 167.993237 -22.215709) (xy 168.040843 -22.244763) (xy 168.083711 -22.280438)
			(xy 168.120928 -22.321975) (xy 168.151701 -22.368488) (xy 168.175373 -22.418985) (xy 168.191441 -22.472392)
			(xy 168.199561 -22.527568) (xy 168.20007 -22.555454) (xy 168.199561 -22.58334) (xy 168.191441 -22.638516)
			(xy 168.175373 -22.691923) (xy 168.151701 -22.74242) (xy 168.120928 -22.788933) (xy 168.083711 -22.83047)
			(xy 168.040843 -22.866145) (xy 167.993237 -22.895199) (xy 167.941908 -22.917011) (xy 167.887951 -22.931117)
			(xy 167.832514 -22.937217) (xy 167.77678 -22.93518) (xy 167.721937 -22.92505) (xy 167.669153 -22.907043)
			(xy 167.619553 -22.881542) (xy 167.574195 -22.849091) (xy 167.534046 -22.810382) (xy 167.49996 -22.766239)
			(xy 167.472664 -22.717604) (xy 167.452741 -22.665513) (xy 167.440615 -22.611076) (xy 167.436544 -22.555454)
			(xy 150.511129 -22.555454) (xy 150.463633 -22.584167) (xy 150.349459 -22.64409) (xy 150.231875 -22.69701)
			(xy 150.11131 -22.742734) (xy 149.988205 -22.781095) (xy 149.863008 -22.811953) (xy 149.736176 -22.835196)
			(xy 149.608172 -22.850738) (xy 149.479464 -22.858523) (xy 149.414992 -22.858984) (xy 149.350715 -22.858503)
			(xy 149.222395 -22.850764) (xy 149.094774 -22.835315) (xy 148.968314 -22.812213) (xy 148.843474 -22.78154)
			(xy 148.720706 -22.743408) (xy 148.600457 -22.697955) (xy 148.483161 -22.645346) (xy 148.369245 -22.585772)
			(xy 148.259122 -22.519449) (xy 148.15319 -22.446618) (xy 148.051835 -22.367542) (xy 147.955423 -22.282508)
			(xy 147.864305 -22.191826) (xy 147.77881 -22.095823) (xy 147.699249 -21.994847) (xy 147.625911 -21.889266)
			(xy 147.559061 -21.779462) (xy 147.498942 -21.665832) (xy 147.445772 -21.54879) (xy 147.399743 -21.42876)
			(xy 147.361023 -21.306177) (xy 147.329752 -21.181485) (xy 147.306043 -21.055137) (xy 147.289983 -20.927591)
			(xy 147.28163 -20.79931) (xy 147.280884 -20.735036) (xy 147.280884 -20.724622) (xy 147.281366 -20.659894)
			(xy 147.289208 -20.530675) (xy 147.30487 -20.40217) (xy 147.328295 -20.274851) (xy 147.359397 -20.149186)
			(xy 147.39806 -20.025638) (xy 147.444144 -19.904662) (xy 147.497478 -19.786703) (xy 147.557866 -19.672194)
			(xy 147.625086 -19.561558) (xy 147.698891 -19.455201) (xy 147.738592 -19.404076) (xy 147.742924 -19.398252)
			(xy 147.748466 -19.384843) (xy 147.749514 -19.37766) (xy 147.750276 -19.371056) (xy 147.747736 -19.357086)
			(xy 147.726908 -19.313906) (xy 147.70354 -19.2659) (xy 147.700492 -19.261074) (xy 147.698714 -19.258788)
			(xy 147.691137 -19.250073) (xy 147.670372 -19.240022) (xy 147.658836 -19.239484) (xy 139.228576 -19.239484)
			(xy 139.22121 -19.239992) (xy 139.211628 -19.241829) (xy 139.194766 -19.251613) (xy 139.188444 -19.259042)
			(xy 139.138914 -19.322034) (xy 139.135552 -19.326537) (xy 139.130685 -19.336663) (xy 139.129262 -19.3421)
			(xy 139.126722 -19.353022) (xy 139.1285 -19.360134) (xy 139.129516 -19.364706) (xy 139.134393 -19.386478)
			(xy 139.139613 -19.430789) (xy 139.13993 -19.453098) (xy 139.139444 -19.48035) (xy 139.131688 -19.534299)
			(xy 139.116333 -19.586595) (xy 139.093693 -19.636174) (xy 139.064227 -19.682026) (xy 139.028536 -19.723219)
			(xy 138.987346 -19.758912) (xy 138.941495 -19.788381) (xy 138.891918 -19.811025) (xy 138.839623 -19.826383)
			(xy 138.785674 -19.834143) (xy 138.758422 -19.834606) (xy 138.731386 -19.834137) (xy 138.677856 -19.826508)
			(xy 138.625939 -19.811398) (xy 138.576674 -19.789112) (xy 138.531049 -19.760094) (xy 138.489976 -19.724927)
			(xy 138.454279 -19.684313) (xy 138.424672 -19.639068) (xy 138.401749 -19.590096) (xy 138.385968 -19.538379)
			(xy 138.377645 -19.484952) (xy 138.376914 -19.457924) (xy 138.376914 -19.452844) (xy 138.377435 -19.424698)
			(xy 138.385738 -19.36902) (xy 138.402128 -19.315165) (xy 138.413744 -19.289522) (xy 138.4173 -19.279362)
			(xy 138.421364 -19.26209) (xy 138.41984 -19.249898) (xy 138.413236 -19.227038) (xy 138.411859 -19.222678)
			(xy 138.407763 -19.214505) (xy 138.405108 -19.210782) (xy 138.38936 -19.189446) (xy 138.381994 -19.18462)
			(xy 138.36932 -19.175853) (xy 138.345532 -19.15626) (xy 138.334496 -19.145504) (xy 138.274552 -19.08556)
			(xy 138.267197 -19.078908) (xy 138.248897 -19.071315) (xy 138.238992 -19.070828) (xy 137.49401 -19.070828)
			(xy 137.48394 -19.07125) (xy 137.465335 -19.078965) (xy 137.457942 -19.085814) (xy 137.211308 -19.332448)
			(xy 137.187753 -19.355393) (xy 137.136354 -19.396413) (xy 137.080683 -19.431415) (xy 137.02144 -19.459959)
			(xy 136.959373 -19.481686) (xy 136.895262 -19.496322) (xy 136.829914 -19.503683) (xy 136.797034 -19.504152)
			(xy 133.318504 -19.504152) (xy 133.286043 -19.503695) (xy 133.221521 -19.496487) (xy 133.158189 -19.482203)
			(xy 133.09682 -19.461016) (xy 133.067298 -19.44751) (xy 133.05409 -19.44116) (xy 133.02488 -19.444716)
			(xy 132.94233 -19.512534) (xy 132.935201 -19.518948) (xy 132.925913 -19.535709) (xy 132.923383 -19.554704)
			(xy 132.925312 -19.564096) (xy 132.93078 -19.587141) (xy 132.936637 -19.63414) (xy 132.936996 -19.657822)
			(xy 132.936473 -19.68656) (xy 132.927848 -19.743387) (xy 132.910795 -19.798276) (xy 132.885701 -19.849985)
			(xy 132.853134 -19.897345) (xy 132.833872 -19.91868) (xy 132.827268 -19.925792) (xy 132.823966 -19.934174)
			(xy 132.822211 -19.938741) (xy 132.82029 -19.948333) (xy 132.820156 -19.953224) (xy 132.820156 -20.02282)
			(xy 132.820289 -20.027711) (xy 132.8222 -20.037307) (xy 132.823966 -20.04187) (xy 132.827268 -20.050252)
			(xy 132.833872 -20.057364) (xy 132.853141 -20.078691) (xy 132.885704 -20.126053) (xy 132.910792 -20.177763)
			(xy 132.92784 -20.232653) (xy 132.93646 -20.289478) (xy 132.936457 -20.346954) (xy 132.927832 -20.403779)
			(xy 132.910781 -20.458667) (xy 132.906458 -20.467574) (xy 140.387576 -20.467574) (xy 140.391647 -20.411952)
			(xy 140.403773 -20.357515) (xy 140.423696 -20.305424) (xy 140.450992 -20.256789) (xy 140.485078 -20.212646)
			(xy 140.525227 -20.173937) (xy 140.570585 -20.141486) (xy 140.620185 -20.115985) (xy 140.672969 -20.097978)
			(xy 140.727812 -20.087848) (xy 140.783546 -20.085811) (xy 140.838983 -20.091911) (xy 140.89294 -20.106017)
			(xy 140.944269 -20.127829) (xy 140.991875 -20.156883) (xy 141.034743 -20.192558) (xy 141.07196 -20.234095)
			(xy 141.102733 -20.280608) (xy 141.126405 -20.331105) (xy 141.142473 -20.384512) (xy 141.150593 -20.439688)
			(xy 141.151102 -20.467574) (xy 141.150593 -20.49546) (xy 141.142473 -20.550636) (xy 141.126405 -20.604043)
			(xy 141.102733 -20.65454) (xy 141.07196 -20.701053) (xy 141.034743 -20.74259) (xy 140.991875 -20.778265)
			(xy 140.944269 -20.807319) (xy 140.89294 -20.829131) (xy 140.838983 -20.843237) (xy 140.783546 -20.849337)
			(xy 140.727812 -20.8473) (xy 140.672969 -20.83717) (xy 140.620185 -20.819163) (xy 140.570585 -20.793662)
			(xy 140.525227 -20.761211) (xy 140.485078 -20.722502) (xy 140.450992 -20.678359) (xy 140.423696 -20.629724)
			(xy 140.403773 -20.577633) (xy 140.391647 -20.523196) (xy 140.387576 -20.467574) (xy 132.906458 -20.467574)
			(xy 132.885687 -20.510375) (xy 132.853121 -20.557734) (xy 132.833872 -20.57908) (xy 132.827268 -20.586192)
			(xy 132.823966 -20.594574) (xy 132.822211 -20.599141) (xy 132.82029 -20.608733) (xy 132.820156 -20.613624)
			(xy 132.820156 -20.68322) (xy 132.820289 -20.688111) (xy 132.8222 -20.697707) (xy 132.823966 -20.70227)
			(xy 132.827268 -20.710652) (xy 132.833872 -20.717764) (xy 132.853141 -20.739091) (xy 132.885704 -20.786453)
			(xy 132.910792 -20.838163) (xy 132.92784 -20.893053) (xy 132.93646 -20.949878) (xy 132.936457 -21.007354)
			(xy 132.927832 -21.064179) (xy 132.910781 -21.119067) (xy 132.885687 -21.170775) (xy 132.853121 -21.218134)
			(xy 132.833872 -21.23948) (xy 132.827268 -21.246592) (xy 132.823966 -21.254974) (xy 132.822211 -21.259541)
			(xy 132.82029 -21.269133) (xy 132.820156 -21.274024) (xy 132.820156 -21.34362) (xy 132.820289 -21.348511)
			(xy 132.8222 -21.358107) (xy 132.823966 -21.36267) (xy 132.827268 -21.371052) (xy 132.833872 -21.378164)
			(xy 132.853142 -21.399491) (xy 132.885705 -21.446854) (xy 132.910793 -21.498566) (xy 132.927841 -21.553457)
			(xy 132.93646 -21.610284) (xy 132.936996 -21.639022) (xy 132.93651 -21.666273) (xy 132.928754 -21.720221)
			(xy 132.913399 -21.772516) (xy 132.911957 -21.775674) (xy 142.036036 -21.775674) (xy 142.040107 -21.720052)
			(xy 142.052233 -21.665615) (xy 142.072156 -21.613524) (xy 142.099452 -21.564889) (xy 142.133538 -21.520746)
			(xy 142.173687 -21.482037) (xy 142.219045 -21.449586) (xy 142.268645 -21.424085) (xy 142.321429 -21.406078)
			(xy 142.376272 -21.395948) (xy 142.432006 -21.393911) (xy 142.487443 -21.400011) (xy 142.5414 -21.414117)
			(xy 142.592729 -21.435929) (xy 142.640335 -21.464983) (xy 142.683203 -21.500658) (xy 142.72042 -21.542195)
			(xy 142.751193 -21.588708) (xy 142.774865 -21.639205) (xy 142.790933 -21.692612) (xy 142.799053 -21.747788)
			(xy 142.799562 -21.775674) (xy 142.799053 -21.80356) (xy 142.791382 -21.855684) (xy 142.938752 -21.855684)
			(xy 142.942823 -21.800062) (xy 142.954949 -21.745625) (xy 142.974872 -21.693534) (xy 143.002168 -21.644899)
			(xy 143.036254 -21.600756) (xy 143.076403 -21.562047) (xy 143.121761 -21.529596) (xy 143.171361 -21.504095)
			(xy 143.224145 -21.486088) (xy 143.278988 -21.475958) (xy 143.334722 -21.473921) (xy 143.390159 -21.480021)
			(xy 143.444116 -21.494127) (xy 143.495445 -21.515939) (xy 143.543051 -21.544993) (xy 143.585919 -21.580668)
			(xy 143.623136 -21.622205) (xy 143.653909 -21.668718) (xy 143.677581 -21.719215) (xy 143.693649 -21.772622)
			(xy 143.701769 -21.827798) (xy 143.70212 -21.847048) (xy 144.172938 -21.847048) (xy 144.177009 -21.791426)
			(xy 144.189135 -21.736989) (xy 144.209058 -21.684898) (xy 144.236354 -21.636263) (xy 144.27044 -21.59212)
			(xy 144.310589 -21.553411) (xy 144.355947 -21.52096) (xy 144.405547 -21.495459) (xy 144.458331 -21.477452)
			(xy 144.513174 -21.467322) (xy 144.568908 -21.465285) (xy 144.624345 -21.471385) (xy 144.678302 -21.485491)
			(xy 144.729631 -21.507303) (xy 144.777237 -21.536357) (xy 144.820105 -21.572032) (xy 144.857322 -21.613569)
			(xy 144.888095 -21.660082) (xy 144.911767 -21.710579) (xy 144.927835 -21.763986) (xy 144.935955 -21.819162)
			(xy 144.936464 -21.847048) (xy 144.935955 -21.874934) (xy 144.927835 -21.93011) (xy 144.911767 -21.983517)
			(xy 144.888095 -22.034014) (xy 144.857322 -22.080527) (xy 144.820105 -22.122064) (xy 144.777237 -22.157739)
			(xy 144.729631 -22.186793) (xy 144.678302 -22.208605) (xy 144.624345 -22.222711) (xy 144.568908 -22.228811)
			(xy 144.513174 -22.226774) (xy 144.458331 -22.216644) (xy 144.405547 -22.198637) (xy 144.355947 -22.173136)
			(xy 144.310589 -22.140685) (xy 144.27044 -22.101976) (xy 144.236354 -22.057833) (xy 144.209058 -22.009198)
			(xy 144.189135 -21.957107) (xy 144.177009 -21.90267) (xy 144.172938 -21.847048) (xy 143.70212 -21.847048)
			(xy 143.702278 -21.855684) (xy 143.701769 -21.88357) (xy 143.693649 -21.938746) (xy 143.677581 -21.992153)
			(xy 143.653909 -22.04265) (xy 143.623136 -22.089163) (xy 143.585919 -22.1307) (xy 143.543051 -22.166375)
			(xy 143.495445 -22.195429) (xy 143.444116 -22.217241) (xy 143.390159 -22.231347) (xy 143.334722 -22.237447)
			(xy 143.278988 -22.23541) (xy 143.224145 -22.22528) (xy 143.171361 -22.207273) (xy 143.121761 -22.181772)
			(xy 143.076403 -22.149321) (xy 143.036254 -22.110612) (xy 143.002168 -22.066469) (xy 142.974872 -22.017834)
			(xy 142.954949 -21.965743) (xy 142.942823 -21.911306) (xy 142.938752 -21.855684) (xy 142.791382 -21.855684)
			(xy 142.790933 -21.858736) (xy 142.774865 -21.912143) (xy 142.751193 -21.96264) (xy 142.72042 -22.009153)
			(xy 142.683203 -22.05069) (xy 142.640335 -22.086365) (xy 142.592729 -22.115419) (xy 142.5414 -22.137231)
			(xy 142.487443 -22.151337) (xy 142.432006 -22.157437) (xy 142.376272 -22.1554) (xy 142.321429 -22.14527)
			(xy 142.268645 -22.127263) (xy 142.219045 -22.101762) (xy 142.173687 -22.069311) (xy 142.133538 -22.030602)
			(xy 142.099452 -21.986459) (xy 142.072156 -21.937824) (xy 142.052233 -21.885733) (xy 142.040107 -21.831296)
			(xy 142.036036 -21.775674) (xy 132.911957 -21.775674) (xy 132.890757 -21.822093) (xy 132.861291 -21.867943)
			(xy 132.8256 -21.909134) (xy 132.784409 -21.944825) (xy 132.738559 -21.974291) (xy 132.688982 -21.996933)
			(xy 132.636687 -22.012288) (xy 132.582739 -22.020044) (xy 132.528237 -22.020044) (xy 132.474289 -22.012288)
			(xy 132.421994 -21.996933) (xy 132.372417 -21.974291) (xy 132.326567 -21.944825) (xy 132.285376 -21.909134)
			(xy 132.249685 -21.867943) (xy 132.220219 -21.822093) (xy 132.197577 -21.772516) (xy 132.182222 -21.720221)
			(xy 132.174466 -21.666273) (xy 132.17398 -21.639022) (xy 132.1745 -21.610283) (xy 132.183121 -21.553455)
			(xy 132.200172 -21.498564) (xy 132.225265 -21.446853) (xy 132.257834 -21.399492) (xy 132.277104 -21.378164)
			(xy 132.283708 -21.371052) (xy 132.28701 -21.36267) (xy 132.288761 -21.358102) (xy 132.290672 -21.34851)
			(xy 132.29082 -21.34362) (xy 132.29082 -21.274024) (xy 132.290681 -21.269134) (xy 132.28876 -21.259543)
			(xy 132.28701 -21.254974) (xy 132.283708 -21.246592) (xy 132.277104 -21.23948) (xy 132.257832 -21.218153)
			(xy 132.225266 -21.170789) (xy 132.200172 -21.119076) (xy 132.18312 -21.064185) (xy 132.174495 -21.007356)
			(xy 132.174493 -20.949876) (xy 132.183113 -20.893047) (xy 132.20016 -20.838153) (xy 132.225249 -20.786439)
			(xy 132.257812 -20.739072) (xy 132.277104 -20.717764) (xy 132.283708 -20.710652) (xy 132.28701 -20.70227)
			(xy 132.288761 -20.697702) (xy 132.290672 -20.68811) (xy 132.29082 -20.68322) (xy 132.29082 -20.613624)
			(xy 132.290681 -20.608734) (xy 132.28876 -20.599143) (xy 132.28701 -20.594574) (xy 132.283708 -20.586192)
			(xy 132.277104 -20.57908) (xy 132.257832 -20.557753) (xy 132.225266 -20.510389) (xy 132.200172 -20.458676)
			(xy 132.18312 -20.403785) (xy 132.174495 -20.346956) (xy 132.174493 -20.289476) (xy 132.183113 -20.232647)
			(xy 132.20016 -20.177753) (xy 132.225249 -20.126039) (xy 132.257812 -20.078672) (xy 132.277104 -20.057364)
			(xy 132.283708 -20.050252) (xy 132.28701 -20.04187) (xy 132.288761 -20.037302) (xy 132.290672 -20.02771)
			(xy 132.29082 -20.02282) (xy 132.29082 -19.953224) (xy 132.290681 -19.948334) (xy 132.28876 -19.938743)
			(xy 132.28701 -19.934174) (xy 132.283708 -19.925792) (xy 132.277104 -19.91868) (xy 132.257833 -19.897353)
			(xy 132.225267 -19.849991) (xy 132.200173 -19.798279) (xy 132.183121 -19.743389) (xy 132.174496 -19.686561)
			(xy 132.17398 -19.657822) (xy 132.174566 -19.627445) (xy 132.184183 -19.567457) (xy 132.203178 -19.509749)
			(xy 132.231073 -19.455777) (xy 132.248656 -19.431) (xy 132.259832 -19.41576) (xy 132.257038 -19.378422)
			(xy 132.243576 -19.36496) (xy 132.236164 -19.358276) (xy 132.217731 -19.350679) (xy 132.197793 -19.350679)
			(xy 132.17936 -19.358276) (xy 132.171948 -19.36496) (xy 132.14604 -19.390868) (xy 132.122486 -19.413814)
			(xy 132.071087 -19.454835) (xy 132.015416 -19.489839) (xy 131.956173 -19.518386) (xy 131.894106 -19.540115)
			(xy 131.829994 -19.554754) (xy 131.764647 -19.562118) (xy 131.731766 -19.562572) (xy 128.91516 -19.562572)
			(xy 128.882283 -19.562093) (xy 128.816944 -19.5547) (xy 128.752843 -19.540045) (xy 128.690783 -19.518312)
			(xy 128.631544 -19.489774) (xy 128.575868 -19.454788) (xy 128.524456 -19.413794) (xy 128.500886 -19.390868)
			(xy 128.195832 -19.085814) (xy 128.18843 -19.078977) (xy 128.169832 -19.071265) (xy 128.159764 -19.070828)
			(xy 125.023626 -19.070828) (xy 125.019054 -19.071082) (xy 125.010089 -19.07226) (xy 124.993773 -19.080023)
			(xy 124.981144 -19.092946) (xy 124.977144 -19.101054) (xy 124.940314 -19.187668) (xy 124.937614 -19.194636)
			(xy 124.935949 -19.20948) (xy 124.937012 -19.216878) (xy 124.937012 -19.217132) (xy 124.938597 -19.224296)
			(xy 124.945306 -19.237337) (xy 124.95022 -19.242786) (xy 124.950474 -19.24304) (xy 124.993912 -19.288699)
			(xy 125.075947 -19.384386) (xy 125.152191 -19.484749) (xy 125.222378 -19.589437) (xy 125.286263 -19.698085)
			(xy 125.343624 -19.810315) (xy 125.394259 -19.925736) (xy 125.437993 -20.043943) (xy 125.474674 -20.164527)
			(xy 125.504172 -20.287065) (xy 125.526386 -20.411131) (xy 125.541238 -20.536291) (xy 125.548676 -20.662111)
			(xy 125.549152 -20.72513) (xy 125.548646 -20.790866) (xy 125.540553 -20.922087) (xy 125.524396 -21.052562)
			(xy 125.500239 -21.181795) (xy 125.468171 -21.309295) (xy 125.428315 -21.434579) (xy 125.380822 -21.557173)
			(xy 125.325873 -21.67661) (xy 125.263674 -21.792437) (xy 125.194464 -21.904216) (xy 125.118503 -22.011523)
			(xy 125.036081 -22.113949) (xy 124.947509 -22.211108) (xy 124.853124 -22.302629) (xy 124.753285 -22.388167)
			(xy 124.648368 -22.467396) (xy 124.538774 -22.540016) (xy 124.512034 -22.555454) (xy 141.436596 -22.555454)
			(xy 141.440667 -22.499832) (xy 141.452793 -22.445395) (xy 141.472716 -22.393304) (xy 141.500012 -22.344669)
			(xy 141.534098 -22.300526) (xy 141.574247 -22.261817) (xy 141.619605 -22.229366) (xy 141.669205 -22.203865)
			(xy 141.721989 -22.185858) (xy 141.776832 -22.175728) (xy 141.832566 -22.173691) (xy 141.888003 -22.179791)
			(xy 141.94196 -22.193897) (xy 141.993289 -22.215709) (xy 142.040895 -22.244763) (xy 142.083763 -22.280438)
			(xy 142.12098 -22.321975) (xy 142.151753 -22.368488) (xy 142.175425 -22.418985) (xy 142.191493 -22.472392)
			(xy 142.199613 -22.527568) (xy 142.200122 -22.555454) (xy 142.199613 -22.58334) (xy 142.191493 -22.638516)
			(xy 142.175425 -22.691923) (xy 142.151753 -22.74242) (xy 142.12098 -22.788933) (xy 142.083763 -22.83047)
			(xy 142.040895 -22.866145) (xy 141.993289 -22.895199) (xy 141.94196 -22.917011) (xy 141.888003 -22.931117)
			(xy 141.832566 -22.937217) (xy 141.776832 -22.93518) (xy 141.721989 -22.92505) (xy 141.669205 -22.907043)
			(xy 141.619605 -22.881542) (xy 141.574247 -22.849091) (xy 141.534098 -22.810382) (xy 141.500012 -22.766239)
			(xy 141.472716 -22.717604) (xy 141.452793 -22.665513) (xy 141.440667 -22.611076) (xy 141.436596 -22.555454)
			(xy 124.512034 -22.555454) (xy 124.424916 -22.605751) (xy 124.307228 -22.664353) (xy 124.186156 -22.715599)
			(xy 124.062158 -22.759294) (xy 123.935706 -22.795273) (xy 123.807278 -22.823399) (xy 123.677363 -22.843565)
			(xy 123.546453 -22.855696) (xy 123.415044 -22.859745) (xy 123.283635 -22.855696) (xy 123.152725 -22.843565)
			(xy 123.02281 -22.823399) (xy 122.894382 -22.795273) (xy 122.76793 -22.759294) (xy 122.643932 -22.715599)
			(xy 122.52286 -22.664353) (xy 122.405172 -22.605751) (xy 122.291314 -22.540016) (xy 122.18172 -22.467396)
			(xy 122.076803 -22.388167) (xy 121.976964 -22.302629) (xy 121.882579 -22.211108) (xy 121.794007 -22.113949)
			(xy 121.711585 -22.011523) (xy 121.635624 -21.904216) (xy 121.566414 -21.792437) (xy 121.504215 -21.67661)
			(xy 121.449266 -21.557173) (xy 121.401773 -21.434579) (xy 121.361917 -21.309295) (xy 121.329849 -21.181795)
			(xy 121.305692 -21.052562) (xy 121.289535 -20.922087) (xy 121.281442 -20.790866) (xy 121.280936 -20.72513)
			(xy 121.281397 -20.66211) (xy 121.288835 -20.53629) (xy 121.303687 -20.411128) (xy 121.325901 -20.287062)
			(xy 121.3554 -20.164522) (xy 121.39208 -20.043938) (xy 121.435814 -19.925729) (xy 121.48645 -19.810308)
			(xy 121.543811 -19.698077) (xy 121.607696 -19.589428) (xy 121.677883 -19.484739) (xy 121.754127 -19.384375)
			(xy 121.836163 -19.288687) (xy 121.879614 -19.24304) (xy 121.879868 -19.242786) (xy 121.884722 -19.237295)
			(xy 121.891431 -19.224273) (xy 121.893076 -19.217132) (xy 121.893076 -19.216878) (xy 121.894168 -19.209481)
			(xy 121.892499 -19.19463) (xy 121.889774 -19.187668) (xy 121.852944 -19.101054) (xy 121.848962 -19.092926)
			(xy 121.836356 -19.079958) (xy 121.820013 -19.07221) (xy 121.811034 -19.071082) (xy 121.806462 -19.070828)
			(xy 120.126506 -19.070828) (xy 120.120498 -19.071001) (xy 120.108821 -19.073835) (xy 120.103392 -19.076416)
			(xy 120.099918 -19.078256) (xy 120.093539 -19.082849) (xy 120.090692 -19.08556) (xy 116.151152 -23.0251)
			(xy 127.462532 -23.0251) (xy 127.466603 -22.969478) (xy 127.478729 -22.915041) (xy 127.498652 -22.86295)
			(xy 127.525948 -22.814315) (xy 127.560034 -22.770172) (xy 127.600183 -22.731463) (xy 127.645541 -22.699012)
			(xy 127.695141 -22.673511) (xy 127.747925 -22.655504) (xy 127.802768 -22.645374) (xy 127.858502 -22.643337)
			(xy 127.913939 -22.649437) (xy 127.967896 -22.663543) (xy 128.019225 -22.685355) (xy 128.066831 -22.714409)
			(xy 128.109699 -22.750084) (xy 128.146916 -22.791621) (xy 128.177689 -22.838134) (xy 128.201361 -22.888631)
			(xy 128.217429 -22.942038) (xy 128.225549 -22.997214) (xy 128.225896 -23.01621) (xy 128.81178 -23.01621)
			(xy 128.815851 -22.960588) (xy 128.827977 -22.906151) (xy 128.8479 -22.85406) (xy 128.875196 -22.805425)
			(xy 128.909282 -22.761282) (xy 128.949431 -22.722573) (xy 128.994789 -22.690122) (xy 129.044389 -22.664621)
			(xy 129.097173 -22.646614) (xy 129.152016 -22.636484) (xy 129.20775 -22.634447) (xy 129.263187 -22.640547)
			(xy 129.317144 -22.654653) (xy 129.368473 -22.676465) (xy 129.416079 -22.705519) (xy 129.458947 -22.741194)
			(xy 129.496164 -22.782731) (xy 129.526937 -22.829244) (xy 129.550609 -22.879741) (xy 129.566677 -22.933148)
			(xy 129.574797 -22.988324) (xy 129.575306 -23.01621) (xy 129.575144 -23.0251) (xy 153.46248 -23.0251)
			(xy 153.466551 -22.969478) (xy 153.478677 -22.915041) (xy 153.4986 -22.86295) (xy 153.525896 -22.814315)
			(xy 153.559982 -22.770172) (xy 153.600131 -22.731463) (xy 153.645489 -22.699012) (xy 153.695089 -22.673511)
			(xy 153.747873 -22.655504) (xy 153.802716 -22.645374) (xy 153.85845 -22.643337) (xy 153.913887 -22.649437)
			(xy 153.967844 -22.663543) (xy 154.019173 -22.685355) (xy 154.066779 -22.714409) (xy 154.109647 -22.750084)
			(xy 154.146864 -22.791621) (xy 154.177637 -22.838134) (xy 154.201309 -22.888631) (xy 154.217377 -22.942038)
			(xy 154.225497 -22.997214) (xy 154.225844 -23.01621) (xy 154.811728 -23.01621) (xy 154.815799 -22.960588)
			(xy 154.827925 -22.906151) (xy 154.847848 -22.85406) (xy 154.875144 -22.805425) (xy 154.90923 -22.761282)
			(xy 154.949379 -22.722573) (xy 154.994737 -22.690122) (xy 155.044337 -22.664621) (xy 155.097121 -22.646614)
			(xy 155.151964 -22.636484) (xy 155.207698 -22.634447) (xy 155.263135 -22.640547) (xy 155.317092 -22.654653)
			(xy 155.368421 -22.676465) (xy 155.416027 -22.705519) (xy 155.458895 -22.741194) (xy 155.496112 -22.782731)
			(xy 155.526885 -22.829244) (xy 155.550557 -22.879741) (xy 155.566625 -22.933148) (xy 155.574745 -22.988324)
			(xy 155.575254 -23.01621) (xy 155.575092 -23.0251) (xy 179.462428 -23.0251) (xy 179.466499 -22.969478)
			(xy 179.478625 -22.915041) (xy 179.498548 -22.86295) (xy 179.525844 -22.814315) (xy 179.55993 -22.770172)
			(xy 179.600079 -22.731463) (xy 179.645437 -22.699012) (xy 179.695037 -22.673511) (xy 179.747821 -22.655504)
			(xy 179.802664 -22.645374) (xy 179.858398 -22.643337) (xy 179.913835 -22.649437) (xy 179.967792 -22.663543)
			(xy 180.019121 -22.685355) (xy 180.066727 -22.714409) (xy 180.109595 -22.750084) (xy 180.146812 -22.791621)
			(xy 180.177585 -22.838134) (xy 180.201257 -22.888631) (xy 180.217325 -22.942038) (xy 180.225445 -22.997214)
			(xy 180.225792 -23.01621) (xy 180.811676 -23.01621) (xy 180.815747 -22.960588) (xy 180.827873 -22.906151)
			(xy 180.847796 -22.85406) (xy 180.875092 -22.805425) (xy 180.909178 -22.761282) (xy 180.949327 -22.722573)
			(xy 180.994685 -22.690122) (xy 181.044285 -22.664621) (xy 181.097069 -22.646614) (xy 181.151912 -22.636484)
			(xy 181.207646 -22.634447) (xy 181.263083 -22.640547) (xy 181.31704 -22.654653) (xy 181.368369 -22.676465)
			(xy 181.415975 -22.705519) (xy 181.458843 -22.741194) (xy 181.49606 -22.782731) (xy 181.526833 -22.829244)
			(xy 181.550505 -22.879741) (xy 181.566573 -22.933148) (xy 181.574693 -22.988324) (xy 181.575202 -23.01621)
			(xy 181.57504 -23.0251) (xy 205.462376 -23.0251) (xy 205.466447 -22.969478) (xy 205.478573 -22.915041)
			(xy 205.498496 -22.86295) (xy 205.525792 -22.814315) (xy 205.559878 -22.770172) (xy 205.600027 -22.731463)
			(xy 205.645385 -22.699012) (xy 205.694985 -22.673511) (xy 205.747769 -22.655504) (xy 205.802612 -22.645374)
			(xy 205.858346 -22.643337) (xy 205.913783 -22.649437) (xy 205.96774 -22.663543) (xy 206.019069 -22.685355)
			(xy 206.066675 -22.714409) (xy 206.109543 -22.750084) (xy 206.14676 -22.791621) (xy 206.177533 -22.838134)
			(xy 206.201205 -22.888631) (xy 206.217273 -22.942038) (xy 206.225393 -22.997214) (xy 206.22574 -23.01621)
			(xy 206.811624 -23.01621) (xy 206.815695 -22.960588) (xy 206.827821 -22.906151) (xy 206.847744 -22.85406)
			(xy 206.87504 -22.805425) (xy 206.909126 -22.761282) (xy 206.949275 -22.722573) (xy 206.994633 -22.690122)
			(xy 207.044233 -22.664621) (xy 207.097017 -22.646614) (xy 207.15186 -22.636484) (xy 207.207594 -22.634447)
			(xy 207.263031 -22.640547) (xy 207.316988 -22.654653) (xy 207.368317 -22.676465) (xy 207.415923 -22.705519)
			(xy 207.458791 -22.741194) (xy 207.496008 -22.782731) (xy 207.526781 -22.829244) (xy 207.550453 -22.879741)
			(xy 207.566521 -22.933148) (xy 207.574641 -22.988324) (xy 207.57515 -23.01621) (xy 207.574988 -23.0251)
			(xy 243.562376 -23.0251) (xy 243.566447 -22.969478) (xy 243.578573 -22.915041) (xy 243.598496 -22.86295)
			(xy 243.625792 -22.814315) (xy 243.659878 -22.770172) (xy 243.700027 -22.731463) (xy 243.745385 -22.699012)
			(xy 243.794985 -22.673511) (xy 243.847769 -22.655504) (xy 243.902612 -22.645374) (xy 243.958346 -22.643337)
			(xy 244.013783 -22.649437) (xy 244.06774 -22.663543) (xy 244.119069 -22.685355) (xy 244.166675 -22.714409)
			(xy 244.209543 -22.750084) (xy 244.24676 -22.791621) (xy 244.277533 -22.838134) (xy 244.301205 -22.888631)
			(xy 244.317273 -22.942038) (xy 244.325393 -22.997214) (xy 244.32574 -23.01621) (xy 244.911624 -23.01621)
			(xy 244.915695 -22.960588) (xy 244.927821 -22.906151) (xy 244.947744 -22.85406) (xy 244.97504 -22.805425)
			(xy 245.009126 -22.761282) (xy 245.049275 -22.722573) (xy 245.094633 -22.690122) (xy 245.144233 -22.664621)
			(xy 245.197017 -22.646614) (xy 245.25186 -22.636484) (xy 245.307594 -22.634447) (xy 245.363031 -22.640547)
			(xy 245.416988 -22.654653) (xy 245.468317 -22.676465) (xy 245.515923 -22.705519) (xy 245.558791 -22.741194)
			(xy 245.596008 -22.782731) (xy 245.626781 -22.829244) (xy 245.650453 -22.879741) (xy 245.666521 -22.933148)
			(xy 245.674641 -22.988324) (xy 245.67515 -23.01621) (xy 245.674988 -23.0251) (xy 269.562324 -23.0251)
			(xy 269.566395 -22.969478) (xy 269.578521 -22.915041) (xy 269.598444 -22.86295) (xy 269.62574 -22.814315)
			(xy 269.659826 -22.770172) (xy 269.699975 -22.731463) (xy 269.745333 -22.699012) (xy 269.794933 -22.673511)
			(xy 269.847717 -22.655504) (xy 269.90256 -22.645374) (xy 269.958294 -22.643337) (xy 270.013731 -22.649437)
			(xy 270.067688 -22.663543) (xy 270.119017 -22.685355) (xy 270.166623 -22.714409) (xy 270.209491 -22.750084)
			(xy 270.246708 -22.791621) (xy 270.277481 -22.838134) (xy 270.301153 -22.888631) (xy 270.317221 -22.942038)
			(xy 270.325341 -22.997214) (xy 270.325688 -23.01621) (xy 270.911572 -23.01621) (xy 270.915643 -22.960588)
			(xy 270.927769 -22.906151) (xy 270.947692 -22.85406) (xy 270.974988 -22.805425) (xy 271.009074 -22.761282)
			(xy 271.049223 -22.722573) (xy 271.094581 -22.690122) (xy 271.144181 -22.664621) (xy 271.196965 -22.646614)
			(xy 271.251808 -22.636484) (xy 271.307542 -22.634447) (xy 271.362979 -22.640547) (xy 271.416936 -22.654653)
			(xy 271.468265 -22.676465) (xy 271.515871 -22.705519) (xy 271.558739 -22.741194) (xy 271.595956 -22.782731)
			(xy 271.626729 -22.829244) (xy 271.650401 -22.879741) (xy 271.666469 -22.933148) (xy 271.674589 -22.988324)
			(xy 271.675098 -23.01621) (xy 271.674936 -23.0251) (xy 295.562272 -23.0251) (xy 295.566343 -22.969478)
			(xy 295.578469 -22.915041) (xy 295.598392 -22.86295) (xy 295.625688 -22.814315) (xy 295.659774 -22.770172)
			(xy 295.699923 -22.731463) (xy 295.745281 -22.699012) (xy 295.794881 -22.673511) (xy 295.847665 -22.655504)
			(xy 295.902508 -22.645374) (xy 295.958242 -22.643337) (xy 296.013679 -22.649437) (xy 296.067636 -22.663543)
			(xy 296.118965 -22.685355) (xy 296.166571 -22.714409) (xy 296.209439 -22.750084) (xy 296.246656 -22.791621)
			(xy 296.277429 -22.838134) (xy 296.301101 -22.888631) (xy 296.317169 -22.942038) (xy 296.325289 -22.997214)
			(xy 296.325636 -23.01621) (xy 296.91152 -23.01621) (xy 296.915591 -22.960588) (xy 296.927717 -22.906151)
			(xy 296.94764 -22.85406) (xy 296.974936 -22.805425) (xy 297.009022 -22.761282) (xy 297.049171 -22.722573)
			(xy 297.094529 -22.690122) (xy 297.144129 -22.664621) (xy 297.196913 -22.646614) (xy 297.251756 -22.636484)
			(xy 297.30749 -22.634447) (xy 297.362927 -22.640547) (xy 297.416884 -22.654653) (xy 297.468213 -22.676465)
			(xy 297.515819 -22.705519) (xy 297.558687 -22.741194) (xy 297.595904 -22.782731) (xy 297.626677 -22.829244)
			(xy 297.650349 -22.879741) (xy 297.666417 -22.933148) (xy 297.674537 -22.988324) (xy 297.675046 -23.01621)
			(xy 297.674884 -23.0251) (xy 321.56222 -23.0251) (xy 321.566291 -22.969478) (xy 321.578417 -22.915041)
			(xy 321.59834 -22.86295) (xy 321.625636 -22.814315) (xy 321.659722 -22.770172) (xy 321.699871 -22.731463)
			(xy 321.745229 -22.699012) (xy 321.794829 -22.673511) (xy 321.847613 -22.655504) (xy 321.902456 -22.645374)
			(xy 321.95819 -22.643337) (xy 322.013627 -22.649437) (xy 322.067584 -22.663543) (xy 322.118913 -22.685355)
			(xy 322.166519 -22.714409) (xy 322.209387 -22.750084) (xy 322.246604 -22.791621) (xy 322.277377 -22.838134)
			(xy 322.301049 -22.888631) (xy 322.317117 -22.942038) (xy 322.325237 -22.997214) (xy 322.325584 -23.01621)
			(xy 322.911468 -23.01621) (xy 322.915539 -22.960588) (xy 322.927665 -22.906151) (xy 322.947588 -22.85406)
			(xy 322.974884 -22.805425) (xy 323.00897 -22.761282) (xy 323.049119 -22.722573) (xy 323.094477 -22.690122)
			(xy 323.144077 -22.664621) (xy 323.196861 -22.646614) (xy 323.251704 -22.636484) (xy 323.307438 -22.634447)
			(xy 323.362875 -22.640547) (xy 323.416832 -22.654653) (xy 323.468161 -22.676465) (xy 323.515767 -22.705519)
			(xy 323.558635 -22.741194) (xy 323.595852 -22.782731) (xy 323.626625 -22.829244) (xy 323.650297 -22.879741)
			(xy 323.666365 -22.933148) (xy 323.674485 -22.988324) (xy 323.674994 -23.01621) (xy 323.674485 -23.044096)
			(xy 323.666365 -23.099272) (xy 323.650297 -23.152679) (xy 323.626625 -23.203176) (xy 323.595852 -23.249689)
			(xy 323.558635 -23.291226) (xy 323.515767 -23.326901) (xy 323.468161 -23.355955) (xy 323.416832 -23.377767)
			(xy 323.362875 -23.391873) (xy 323.307438 -23.397973) (xy 323.251704 -23.395936) (xy 323.196861 -23.385806)
			(xy 323.144077 -23.367799) (xy 323.094477 -23.342298) (xy 323.049119 -23.309847) (xy 323.00897 -23.271138)
			(xy 322.974884 -23.226995) (xy 322.947588 -23.17836) (xy 322.927665 -23.126269) (xy 322.915539 -23.071832)
			(xy 322.911468 -23.01621) (xy 322.325584 -23.01621) (xy 322.325746 -23.0251) (xy 322.325237 -23.052986)
			(xy 322.317117 -23.108162) (xy 322.301049 -23.161569) (xy 322.277377 -23.212066) (xy 322.246604 -23.258579)
			(xy 322.209387 -23.300116) (xy 322.166519 -23.335791) (xy 322.118913 -23.364845) (xy 322.067584 -23.386657)
			(xy 322.013627 -23.400763) (xy 321.95819 -23.406863) (xy 321.902456 -23.404826) (xy 321.847613 -23.394696)
			(xy 321.794829 -23.376689) (xy 321.745229 -23.351188) (xy 321.699871 -23.318737) (xy 321.659722 -23.280028)
			(xy 321.625636 -23.235885) (xy 321.59834 -23.18725) (xy 321.578417 -23.135159) (xy 321.566291 -23.080722)
			(xy 321.56222 -23.0251) (xy 297.674884 -23.0251) (xy 297.674537 -23.044096) (xy 297.666417 -23.099272)
			(xy 297.650349 -23.152679) (xy 297.626677 -23.203176) (xy 297.595904 -23.249689) (xy 297.558687 -23.291226)
			(xy 297.515819 -23.326901) (xy 297.468213 -23.355955) (xy 297.416884 -23.377767) (xy 297.362927 -23.391873)
			(xy 297.30749 -23.397973) (xy 297.251756 -23.395936) (xy 297.196913 -23.385806) (xy 297.144129 -23.367799)
			(xy 297.094529 -23.342298) (xy 297.049171 -23.309847) (xy 297.009022 -23.271138) (xy 296.974936 -23.226995)
			(xy 296.94764 -23.17836) (xy 296.927717 -23.126269) (xy 296.915591 -23.071832) (xy 296.91152 -23.01621)
			(xy 296.325636 -23.01621) (xy 296.325798 -23.0251) (xy 296.325289 -23.052986) (xy 296.317169 -23.108162)
			(xy 296.301101 -23.161569) (xy 296.277429 -23.212066) (xy 296.246656 -23.258579) (xy 296.209439 -23.300116)
			(xy 296.166571 -23.335791) (xy 296.118965 -23.364845) (xy 296.067636 -23.386657) (xy 296.013679 -23.400763)
			(xy 295.958242 -23.406863) (xy 295.902508 -23.404826) (xy 295.847665 -23.394696) (xy 295.794881 -23.376689)
			(xy 295.745281 -23.351188) (xy 295.699923 -23.318737) (xy 295.659774 -23.280028) (xy 295.625688 -23.235885)
			(xy 295.598392 -23.18725) (xy 295.578469 -23.135159) (xy 295.566343 -23.080722) (xy 295.562272 -23.0251)
			(xy 271.674936 -23.0251) (xy 271.674589 -23.044096) (xy 271.666469 -23.099272) (xy 271.650401 -23.152679)
			(xy 271.626729 -23.203176) (xy 271.595956 -23.249689) (xy 271.558739 -23.291226) (xy 271.515871 -23.326901)
			(xy 271.468265 -23.355955) (xy 271.416936 -23.377767) (xy 271.362979 -23.391873) (xy 271.307542 -23.397973)
			(xy 271.251808 -23.395936) (xy 271.196965 -23.385806) (xy 271.144181 -23.367799) (xy 271.094581 -23.342298)
			(xy 271.049223 -23.309847) (xy 271.009074 -23.271138) (xy 270.974988 -23.226995) (xy 270.947692 -23.17836)
			(xy 270.927769 -23.126269) (xy 270.915643 -23.071832) (xy 270.911572 -23.01621) (xy 270.325688 -23.01621)
			(xy 270.32585 -23.0251) (xy 270.325341 -23.052986) (xy 270.317221 -23.108162) (xy 270.301153 -23.161569)
			(xy 270.277481 -23.212066) (xy 270.246708 -23.258579) (xy 270.209491 -23.300116) (xy 270.166623 -23.335791)
			(xy 270.119017 -23.364845) (xy 270.067688 -23.386657) (xy 270.013731 -23.400763) (xy 269.958294 -23.406863)
			(xy 269.90256 -23.404826) (xy 269.847717 -23.394696) (xy 269.794933 -23.376689) (xy 269.745333 -23.351188)
			(xy 269.699975 -23.318737) (xy 269.659826 -23.280028) (xy 269.62574 -23.235885) (xy 269.598444 -23.18725)
			(xy 269.578521 -23.135159) (xy 269.566395 -23.080722) (xy 269.562324 -23.0251) (xy 245.674988 -23.0251)
			(xy 245.674641 -23.044096) (xy 245.666521 -23.099272) (xy 245.650453 -23.152679) (xy 245.626781 -23.203176)
			(xy 245.596008 -23.249689) (xy 245.558791 -23.291226) (xy 245.515923 -23.326901) (xy 245.468317 -23.355955)
			(xy 245.416988 -23.377767) (xy 245.363031 -23.391873) (xy 245.307594 -23.397973) (xy 245.25186 -23.395936)
			(xy 245.197017 -23.385806) (xy 245.144233 -23.367799) (xy 245.094633 -23.342298) (xy 245.049275 -23.309847)
			(xy 245.009126 -23.271138) (xy 244.97504 -23.226995) (xy 244.947744 -23.17836) (xy 244.927821 -23.126269)
			(xy 244.915695 -23.071832) (xy 244.911624 -23.01621) (xy 244.32574 -23.01621) (xy 244.325902 -23.0251)
			(xy 244.325393 -23.052986) (xy 244.317273 -23.108162) (xy 244.301205 -23.161569) (xy 244.277533 -23.212066)
			(xy 244.24676 -23.258579) (xy 244.209543 -23.300116) (xy 244.166675 -23.335791) (xy 244.119069 -23.364845)
			(xy 244.06774 -23.386657) (xy 244.013783 -23.400763) (xy 243.958346 -23.406863) (xy 243.902612 -23.404826)
			(xy 243.847769 -23.394696) (xy 243.794985 -23.376689) (xy 243.745385 -23.351188) (xy 243.700027 -23.318737)
			(xy 243.659878 -23.280028) (xy 243.625792 -23.235885) (xy 243.598496 -23.18725) (xy 243.578573 -23.135159)
			(xy 243.566447 -23.080722) (xy 243.562376 -23.0251) (xy 207.574988 -23.0251) (xy 207.574641 -23.044096)
			(xy 207.566521 -23.099272) (xy 207.550453 -23.152679) (xy 207.526781 -23.203176) (xy 207.496008 -23.249689)
			(xy 207.458791 -23.291226) (xy 207.415923 -23.326901) (xy 207.368317 -23.355955) (xy 207.316988 -23.377767)
			(xy 207.263031 -23.391873) (xy 207.207594 -23.397973) (xy 207.15186 -23.395936) (xy 207.097017 -23.385806)
			(xy 207.044233 -23.367799) (xy 206.994633 -23.342298) (xy 206.949275 -23.309847) (xy 206.909126 -23.271138)
			(xy 206.87504 -23.226995) (xy 206.847744 -23.17836) (xy 206.827821 -23.126269) (xy 206.815695 -23.071832)
			(xy 206.811624 -23.01621) (xy 206.22574 -23.01621) (xy 206.225902 -23.0251) (xy 206.225393 -23.052986)
			(xy 206.217273 -23.108162) (xy 206.201205 -23.161569) (xy 206.177533 -23.212066) (xy 206.14676 -23.258579)
			(xy 206.109543 -23.300116) (xy 206.066675 -23.335791) (xy 206.019069 -23.364845) (xy 205.96774 -23.386657)
			(xy 205.913783 -23.400763) (xy 205.858346 -23.406863) (xy 205.802612 -23.404826) (xy 205.747769 -23.394696)
			(xy 205.694985 -23.376689) (xy 205.645385 -23.351188) (xy 205.600027 -23.318737) (xy 205.559878 -23.280028)
			(xy 205.525792 -23.235885) (xy 205.498496 -23.18725) (xy 205.478573 -23.135159) (xy 205.466447 -23.080722)
			(xy 205.462376 -23.0251) (xy 181.57504 -23.0251) (xy 181.574693 -23.044096) (xy 181.566573 -23.099272)
			(xy 181.550505 -23.152679) (xy 181.526833 -23.203176) (xy 181.49606 -23.249689) (xy 181.458843 -23.291226)
			(xy 181.415975 -23.326901) (xy 181.368369 -23.355955) (xy 181.31704 -23.377767) (xy 181.263083 -23.391873)
			(xy 181.207646 -23.397973) (xy 181.151912 -23.395936) (xy 181.097069 -23.385806) (xy 181.044285 -23.367799)
			(xy 180.994685 -23.342298) (xy 180.949327 -23.309847) (xy 180.909178 -23.271138) (xy 180.875092 -23.226995)
			(xy 180.847796 -23.17836) (xy 180.827873 -23.126269) (xy 180.815747 -23.071832) (xy 180.811676 -23.01621)
			(xy 180.225792 -23.01621) (xy 180.225954 -23.0251) (xy 180.225445 -23.052986) (xy 180.217325 -23.108162)
			(xy 180.201257 -23.161569) (xy 180.177585 -23.212066) (xy 180.146812 -23.258579) (xy 180.109595 -23.300116)
			(xy 180.066727 -23.335791) (xy 180.019121 -23.364845) (xy 179.967792 -23.386657) (xy 179.913835 -23.400763)
			(xy 179.858398 -23.406863) (xy 179.802664 -23.404826) (xy 179.747821 -23.394696) (xy 179.695037 -23.376689)
			(xy 179.645437 -23.351188) (xy 179.600079 -23.318737) (xy 179.55993 -23.280028) (xy 179.525844 -23.235885)
			(xy 179.498548 -23.18725) (xy 179.478625 -23.135159) (xy 179.466499 -23.080722) (xy 179.462428 -23.0251)
			(xy 155.575092 -23.0251) (xy 155.574745 -23.044096) (xy 155.566625 -23.099272) (xy 155.550557 -23.152679)
			(xy 155.526885 -23.203176) (xy 155.496112 -23.249689) (xy 155.458895 -23.291226) (xy 155.416027 -23.326901)
			(xy 155.368421 -23.355955) (xy 155.317092 -23.377767) (xy 155.263135 -23.391873) (xy 155.207698 -23.397973)
			(xy 155.151964 -23.395936) (xy 155.097121 -23.385806) (xy 155.044337 -23.367799) (xy 154.994737 -23.342298)
			(xy 154.949379 -23.309847) (xy 154.90923 -23.271138) (xy 154.875144 -23.226995) (xy 154.847848 -23.17836)
			(xy 154.827925 -23.126269) (xy 154.815799 -23.071832) (xy 154.811728 -23.01621) (xy 154.225844 -23.01621)
			(xy 154.226006 -23.0251) (xy 154.225497 -23.052986) (xy 154.217377 -23.108162) (xy 154.201309 -23.161569)
			(xy 154.177637 -23.212066) (xy 154.146864 -23.258579) (xy 154.109647 -23.300116) (xy 154.066779 -23.335791)
			(xy 154.019173 -23.364845) (xy 153.967844 -23.386657) (xy 153.913887 -23.400763) (xy 153.85845 -23.406863)
			(xy 153.802716 -23.404826) (xy 153.747873 -23.394696) (xy 153.695089 -23.376689) (xy 153.645489 -23.351188)
			(xy 153.600131 -23.318737) (xy 153.559982 -23.280028) (xy 153.525896 -23.235885) (xy 153.4986 -23.18725)
			(xy 153.478677 -23.135159) (xy 153.466551 -23.080722) (xy 153.46248 -23.0251) (xy 129.575144 -23.0251)
			(xy 129.574797 -23.044096) (xy 129.566677 -23.099272) (xy 129.550609 -23.152679) (xy 129.526937 -23.203176)
			(xy 129.496164 -23.249689) (xy 129.458947 -23.291226) (xy 129.416079 -23.326901) (xy 129.368473 -23.355955)
			(xy 129.317144 -23.377767) (xy 129.263187 -23.391873) (xy 129.20775 -23.397973) (xy 129.152016 -23.395936)
			(xy 129.097173 -23.385806) (xy 129.044389 -23.367799) (xy 128.994789 -23.342298) (xy 128.949431 -23.309847)
			(xy 128.909282 -23.271138) (xy 128.875196 -23.226995) (xy 128.8479 -23.17836) (xy 128.827977 -23.126269)
			(xy 128.815851 -23.071832) (xy 128.81178 -23.01621) (xy 128.225896 -23.01621) (xy 128.226058 -23.0251)
			(xy 128.225549 -23.052986) (xy 128.217429 -23.108162) (xy 128.201361 -23.161569) (xy 128.177689 -23.212066)
			(xy 128.146916 -23.258579) (xy 128.109699 -23.300116) (xy 128.066831 -23.335791) (xy 128.019225 -23.364845)
			(xy 127.967896 -23.386657) (xy 127.913939 -23.400763) (xy 127.858502 -23.406863) (xy 127.802768 -23.404826)
			(xy 127.747925 -23.394696) (xy 127.695141 -23.376689) (xy 127.645541 -23.351188) (xy 127.600183 -23.318737)
			(xy 127.560034 -23.280028) (xy 127.525948 -23.235885) (xy 127.498652 -23.18725) (xy 127.478729 -23.135159)
			(xy 127.466603 -23.080722) (xy 127.462532 -23.0251) (xy 116.151152 -23.0251) (xy 115.586256 -23.589996)
			(xy 132.184646 -23.589996) (xy 132.188717 -23.534374) (xy 132.200843 -23.479937) (xy 132.220766 -23.427846)
			(xy 132.248062 -23.379211) (xy 132.282148 -23.335068) (xy 132.322297 -23.296359) (xy 132.367655 -23.263908)
			(xy 132.417255 -23.238407) (xy 132.470039 -23.2204) (xy 132.524882 -23.21027) (xy 132.580616 -23.208233)
			(xy 132.636053 -23.214333) (xy 132.69001 -23.228439) (xy 132.741339 -23.250251) (xy 132.788945 -23.279305)
			(xy 132.831813 -23.31498) (xy 132.86903 -23.356517) (xy 132.899803 -23.40303) (xy 132.923475 -23.453527)
			(xy 132.939543 -23.506934) (xy 132.947663 -23.56211) (xy 132.948172 -23.589996) (xy 132.947663 -23.617882)
			(xy 132.939543 -23.673058) (xy 132.923475 -23.726465) (xy 132.899803 -23.776962) (xy 132.86903 -23.823475)
			(xy 132.831813 -23.865012) (xy 132.788945 -23.900687) (xy 132.741339 -23.929741) (xy 132.69001 -23.951553)
			(xy 132.637985 -23.965154) (xy 142.177514 -23.965154) (xy 142.181585 -23.909532) (xy 142.193711 -23.855095)
			(xy 142.213634 -23.803004) (xy 142.24093 -23.754369) (xy 142.275016 -23.710226) (xy 142.315165 -23.671517)
			(xy 142.360523 -23.639066) (xy 142.410123 -23.613565) (xy 142.462907 -23.595558) (xy 142.51775 -23.585428)
			(xy 142.573484 -23.583391) (xy 142.628921 -23.589491) (xy 142.682878 -23.603597) (xy 142.734207 -23.625409)
			(xy 142.781813 -23.654463) (xy 142.824681 -23.690138) (xy 142.861898 -23.731675) (xy 142.892671 -23.778188)
			(xy 142.916343 -23.828685) (xy 142.932411 -23.882092) (xy 142.940531 -23.937268) (xy 142.940706 -23.946866)
			(xy 143.18056 -23.946866) (xy 143.184631 -23.891244) (xy 143.196757 -23.836807) (xy 143.21668 -23.784716)
			(xy 143.243976 -23.736081) (xy 143.278062 -23.691938) (xy 143.318211 -23.653229) (xy 143.363569 -23.620778)
			(xy 143.413169 -23.595277) (xy 143.465953 -23.57727) (xy 143.520796 -23.56714) (xy 143.57653 -23.565103)
			(xy 143.631967 -23.571203) (xy 143.685924 -23.585309) (xy 143.737253 -23.607121) (xy 143.784859 -23.636175)
			(xy 143.827727 -23.67185) (xy 143.864944 -23.713387) (xy 143.895717 -23.7599) (xy 143.919389 -23.810397)
			(xy 143.935457 -23.863804) (xy 143.943577 -23.91898) (xy 143.944086 -23.946866) (xy 143.943646 -23.970996)
			(xy 144.172938 -23.970996) (xy 144.177009 -23.915374) (xy 144.189135 -23.860937) (xy 144.209058 -23.808846)
			(xy 144.236354 -23.760211) (xy 144.27044 -23.716068) (xy 144.310589 -23.677359) (xy 144.355947 -23.644908)
			(xy 144.405547 -23.619407) (xy 144.458331 -23.6014) (xy 144.513174 -23.59127) (xy 144.568908 -23.589233)
			(xy 144.575842 -23.589996) (xy 158.184594 -23.589996) (xy 158.188665 -23.534374) (xy 158.200791 -23.479937)
			(xy 158.220714 -23.427846) (xy 158.24801 -23.379211) (xy 158.282096 -23.335068) (xy 158.322245 -23.296359)
			(xy 158.367603 -23.263908) (xy 158.417203 -23.238407) (xy 158.469987 -23.2204) (xy 158.52483 -23.21027)
			(xy 158.580564 -23.208233) (xy 158.636001 -23.214333) (xy 158.689958 -23.228439) (xy 158.741287 -23.250251)
			(xy 158.788893 -23.279305) (xy 158.831761 -23.31498) (xy 158.868978 -23.356517) (xy 158.899751 -23.40303)
			(xy 158.923423 -23.453527) (xy 158.939491 -23.506934) (xy 158.947611 -23.56211) (xy 158.94812 -23.589996)
			(xy 158.947611 -23.617882) (xy 158.939491 -23.673058) (xy 158.923423 -23.726465) (xy 158.899751 -23.776962)
			(xy 158.868978 -23.823475) (xy 158.831761 -23.865012) (xy 158.788893 -23.900687) (xy 158.741287 -23.929741)
			(xy 158.689958 -23.951553) (xy 158.637933 -23.965154) (xy 168.177462 -23.965154) (xy 168.181533 -23.909532)
			(xy 168.193659 -23.855095) (xy 168.213582 -23.803004) (xy 168.240878 -23.754369) (xy 168.274964 -23.710226)
			(xy 168.315113 -23.671517) (xy 168.360471 -23.639066) (xy 168.410071 -23.613565) (xy 168.462855 -23.595558)
			(xy 168.517698 -23.585428) (xy 168.573432 -23.583391) (xy 168.628869 -23.589491) (xy 168.682826 -23.603597)
			(xy 168.734155 -23.625409) (xy 168.781761 -23.654463) (xy 168.824629 -23.690138) (xy 168.861846 -23.731675)
			(xy 168.892619 -23.778188) (xy 168.916291 -23.828685) (xy 168.932359 -23.882092) (xy 168.940479 -23.937268)
			(xy 168.940654 -23.946866) (xy 169.180508 -23.946866) (xy 169.184579 -23.891244) (xy 169.196705 -23.836807)
			(xy 169.216628 -23.784716) (xy 169.243924 -23.736081) (xy 169.27801 -23.691938) (xy 169.318159 -23.653229)
			(xy 169.363517 -23.620778) (xy 169.413117 -23.595277) (xy 169.465901 -23.57727) (xy 169.520744 -23.56714)
			(xy 169.576478 -23.565103) (xy 169.631915 -23.571203) (xy 169.685872 -23.585309) (xy 169.737201 -23.607121)
			(xy 169.784807 -23.636175) (xy 169.827675 -23.67185) (xy 169.864892 -23.713387) (xy 169.895665 -23.7599)
			(xy 169.919337 -23.810397) (xy 169.935405 -23.863804) (xy 169.943525 -23.91898) (xy 169.944034 -23.946866)
			(xy 169.943594 -23.970996) (xy 170.172886 -23.970996) (xy 170.176957 -23.915374) (xy 170.189083 -23.860937)
			(xy 170.209006 -23.808846) (xy 170.236302 -23.760211) (xy 170.270388 -23.716068) (xy 170.310537 -23.677359)
			(xy 170.355895 -23.644908) (xy 170.405495 -23.619407) (xy 170.458279 -23.6014) (xy 170.513122 -23.59127)
			(xy 170.568856 -23.589233) (xy 170.57579 -23.589996) (xy 184.184542 -23.589996) (xy 184.188613 -23.534374)
			(xy 184.200739 -23.479937) (xy 184.220662 -23.427846) (xy 184.247958 -23.379211) (xy 184.282044 -23.335068)
			(xy 184.322193 -23.296359) (xy 184.367551 -23.263908) (xy 184.417151 -23.238407) (xy 184.469935 -23.2204)
			(xy 184.524778 -23.21027) (xy 184.580512 -23.208233) (xy 184.635949 -23.214333) (xy 184.689906 -23.228439)
			(xy 184.741235 -23.250251) (xy 184.788841 -23.279305) (xy 184.831709 -23.31498) (xy 184.868926 -23.356517)
			(xy 184.899699 -23.40303) (xy 184.923371 -23.453527) (xy 184.939439 -23.506934) (xy 184.947559 -23.56211)
			(xy 184.948068 -23.589996) (xy 184.947559 -23.617882) (xy 184.939439 -23.673058) (xy 184.923371 -23.726465)
			(xy 184.899699 -23.776962) (xy 184.868926 -23.823475) (xy 184.831709 -23.865012) (xy 184.788841 -23.900687)
			(xy 184.741235 -23.929741) (xy 184.689906 -23.951553) (xy 184.637881 -23.965154) (xy 194.17741 -23.965154)
			(xy 194.181481 -23.909532) (xy 194.193607 -23.855095) (xy 194.21353 -23.803004) (xy 194.240826 -23.754369)
			(xy 194.274912 -23.710226) (xy 194.315061 -23.671517) (xy 194.360419 -23.639066) (xy 194.410019 -23.613565)
			(xy 194.462803 -23.595558) (xy 194.517646 -23.585428) (xy 194.57338 -23.583391) (xy 194.628817 -23.589491)
			(xy 194.682774 -23.603597) (xy 194.734103 -23.625409) (xy 194.781709 -23.654463) (xy 194.824577 -23.690138)
			(xy 194.861794 -23.731675) (xy 194.892567 -23.778188) (xy 194.916239 -23.828685) (xy 194.932307 -23.882092)
			(xy 194.940427 -23.937268) (xy 194.940602 -23.946866) (xy 195.180456 -23.946866) (xy 195.184527 -23.891244)
			(xy 195.196653 -23.836807) (xy 195.216576 -23.784716) (xy 195.243872 -23.736081) (xy 195.277958 -23.691938)
			(xy 195.318107 -23.653229) (xy 195.363465 -23.620778) (xy 195.413065 -23.595277) (xy 195.465849 -23.57727)
			(xy 195.520692 -23.56714) (xy 195.576426 -23.565103) (xy 195.631863 -23.571203) (xy 195.68582 -23.585309)
			(xy 195.737149 -23.607121) (xy 195.784755 -23.636175) (xy 195.827623 -23.67185) (xy 195.86484 -23.713387)
			(xy 195.895613 -23.7599) (xy 195.919285 -23.810397) (xy 195.935353 -23.863804) (xy 195.943473 -23.91898)
			(xy 195.943982 -23.946866) (xy 195.943542 -23.970996) (xy 196.172834 -23.970996) (xy 196.176905 -23.915374)
			(xy 196.189031 -23.860937) (xy 196.208954 -23.808846) (xy 196.23625 -23.760211) (xy 196.270336 -23.716068)
			(xy 196.310485 -23.677359) (xy 196.355843 -23.644908) (xy 196.405443 -23.619407) (xy 196.458227 -23.6014)
			(xy 196.51307 -23.59127) (xy 196.568804 -23.589233) (xy 196.575738 -23.589996) (xy 210.18449 -23.589996)
			(xy 210.188561 -23.534374) (xy 210.200687 -23.479937) (xy 210.22061 -23.427846) (xy 210.247906 -23.379211)
			(xy 210.281992 -23.335068) (xy 210.322141 -23.296359) (xy 210.367499 -23.263908) (xy 210.417099 -23.238407)
			(xy 210.469883 -23.2204) (xy 210.524726 -23.21027) (xy 210.58046 -23.208233) (xy 210.635897 -23.214333)
			(xy 210.689854 -23.228439) (xy 210.741183 -23.250251) (xy 210.788789 -23.279305) (xy 210.831657 -23.31498)
			(xy 210.868874 -23.356517) (xy 210.899647 -23.40303) (xy 210.923319 -23.453527) (xy 210.939387 -23.506934)
			(xy 210.947507 -23.56211) (xy 210.948016 -23.589996) (xy 210.947507 -23.617882) (xy 210.939387 -23.673058)
			(xy 210.923319 -23.726465) (xy 210.899647 -23.776962) (xy 210.868874 -23.823475) (xy 210.831657 -23.865012)
			(xy 210.788789 -23.900687) (xy 210.741183 -23.929741) (xy 210.689854 -23.951553) (xy 210.637829 -23.965154)
			(xy 220.177358 -23.965154) (xy 220.181429 -23.909532) (xy 220.193555 -23.855095) (xy 220.213478 -23.803004)
			(xy 220.240774 -23.754369) (xy 220.27486 -23.710226) (xy 220.315009 -23.671517) (xy 220.360367 -23.639066)
			(xy 220.409967 -23.613565) (xy 220.462751 -23.595558) (xy 220.517594 -23.585428) (xy 220.573328 -23.583391)
			(xy 220.628765 -23.589491) (xy 220.682722 -23.603597) (xy 220.734051 -23.625409) (xy 220.781657 -23.654463)
			(xy 220.824525 -23.690138) (xy 220.861742 -23.731675) (xy 220.892515 -23.778188) (xy 220.916187 -23.828685)
			(xy 220.932255 -23.882092) (xy 220.940375 -23.937268) (xy 220.94055 -23.946866) (xy 221.180404 -23.946866)
			(xy 221.184475 -23.891244) (xy 221.196601 -23.836807) (xy 221.216524 -23.784716) (xy 221.24382 -23.736081)
			(xy 221.277906 -23.691938) (xy 221.318055 -23.653229) (xy 221.363413 -23.620778) (xy 221.413013 -23.595277)
			(xy 221.465797 -23.57727) (xy 221.52064 -23.56714) (xy 221.576374 -23.565103) (xy 221.631811 -23.571203)
			(xy 221.685768 -23.585309) (xy 221.737097 -23.607121) (xy 221.784703 -23.636175) (xy 221.827571 -23.67185)
			(xy 221.864788 -23.713387) (xy 221.895561 -23.7599) (xy 221.919233 -23.810397) (xy 221.935301 -23.863804)
			(xy 221.943421 -23.91898) (xy 221.94393 -23.946866) (xy 221.94349 -23.970996) (xy 222.172782 -23.970996)
			(xy 222.176853 -23.915374) (xy 222.188979 -23.860937) (xy 222.208902 -23.808846) (xy 222.236198 -23.760211)
			(xy 222.270284 -23.716068) (xy 222.310433 -23.677359) (xy 222.355791 -23.644908) (xy 222.405391 -23.619407)
			(xy 222.458175 -23.6014) (xy 222.513018 -23.59127) (xy 222.568752 -23.589233) (xy 222.575686 -23.589996)
			(xy 248.28449 -23.589996) (xy 248.288561 -23.534374) (xy 248.300687 -23.479937) (xy 248.32061 -23.427846)
			(xy 248.347906 -23.379211) (xy 248.381992 -23.335068) (xy 248.422141 -23.296359) (xy 248.467499 -23.263908)
			(xy 248.517099 -23.238407) (xy 248.569883 -23.2204) (xy 248.624726 -23.21027) (xy 248.68046 -23.208233)
			(xy 248.735897 -23.214333) (xy 248.789854 -23.228439) (xy 248.841183 -23.250251) (xy 248.888789 -23.279305)
			(xy 248.931657 -23.31498) (xy 248.968874 -23.356517) (xy 248.999647 -23.40303) (xy 249.023319 -23.453527)
			(xy 249.039387 -23.506934) (xy 249.047507 -23.56211) (xy 249.048016 -23.589996) (xy 249.047507 -23.617882)
			(xy 249.039387 -23.673058) (xy 249.023319 -23.726465) (xy 248.999647 -23.776962) (xy 248.968874 -23.823475)
			(xy 248.931657 -23.865012) (xy 248.888789 -23.900687) (xy 248.841183 -23.929741) (xy 248.789854 -23.951553)
			(xy 248.737829 -23.965154) (xy 258.277358 -23.965154) (xy 258.281429 -23.909532) (xy 258.293555 -23.855095)
			(xy 258.313478 -23.803004) (xy 258.340774 -23.754369) (xy 258.37486 -23.710226) (xy 258.415009 -23.671517)
			(xy 258.460367 -23.639066) (xy 258.509967 -23.613565) (xy 258.562751 -23.595558) (xy 258.617594 -23.585428)
			(xy 258.673328 -23.583391) (xy 258.728765 -23.589491) (xy 258.782722 -23.603597) (xy 258.834051 -23.625409)
			(xy 258.881657 -23.654463) (xy 258.924525 -23.690138) (xy 258.961742 -23.731675) (xy 258.992515 -23.778188)
			(xy 259.016187 -23.828685) (xy 259.032255 -23.882092) (xy 259.040375 -23.937268) (xy 259.04055 -23.946866)
			(xy 259.280404 -23.946866) (xy 259.284475 -23.891244) (xy 259.296601 -23.836807) (xy 259.316524 -23.784716)
			(xy 259.34382 -23.736081) (xy 259.377906 -23.691938) (xy 259.418055 -23.653229) (xy 259.463413 -23.620778)
			(xy 259.513013 -23.595277) (xy 259.565797 -23.57727) (xy 259.62064 -23.56714) (xy 259.676374 -23.565103)
			(xy 259.731811 -23.571203) (xy 259.785768 -23.585309) (xy 259.837097 -23.607121) (xy 259.884703 -23.636175)
			(xy 259.927571 -23.67185) (xy 259.964788 -23.713387) (xy 259.995561 -23.7599) (xy 260.019233 -23.810397)
			(xy 260.035301 -23.863804) (xy 260.043421 -23.91898) (xy 260.04393 -23.946866) (xy 260.04349 -23.970996)
			(xy 260.272782 -23.970996) (xy 260.276853 -23.915374) (xy 260.288979 -23.860937) (xy 260.308902 -23.808846)
			(xy 260.336198 -23.760211) (xy 260.370284 -23.716068) (xy 260.410433 -23.677359) (xy 260.455791 -23.644908)
			(xy 260.505391 -23.619407) (xy 260.558175 -23.6014) (xy 260.613018 -23.59127) (xy 260.668752 -23.589233)
			(xy 260.675686 -23.589996) (xy 274.284438 -23.589996) (xy 274.288509 -23.534374) (xy 274.300635 -23.479937)
			(xy 274.320558 -23.427846) (xy 274.347854 -23.379211) (xy 274.38194 -23.335068) (xy 274.422089 -23.296359)
			(xy 274.467447 -23.263908) (xy 274.517047 -23.238407) (xy 274.569831 -23.2204) (xy 274.624674 -23.21027)
			(xy 274.680408 -23.208233) (xy 274.735845 -23.214333) (xy 274.789802 -23.228439) (xy 274.841131 -23.250251)
			(xy 274.888737 -23.279305) (xy 274.931605 -23.31498) (xy 274.968822 -23.356517) (xy 274.999595 -23.40303)
			(xy 275.023267 -23.453527) (xy 275.039335 -23.506934) (xy 275.047455 -23.56211) (xy 275.047964 -23.589996)
			(xy 275.047455 -23.617882) (xy 275.039335 -23.673058) (xy 275.023267 -23.726465) (xy 274.999595 -23.776962)
			(xy 274.968822 -23.823475) (xy 274.931605 -23.865012) (xy 274.888737 -23.900687) (xy 274.841131 -23.929741)
			(xy 274.789802 -23.951553) (xy 274.737777 -23.965154) (xy 284.277306 -23.965154) (xy 284.281377 -23.909532)
			(xy 284.293503 -23.855095) (xy 284.313426 -23.803004) (xy 284.340722 -23.754369) (xy 284.374808 -23.710226)
			(xy 284.414957 -23.671517) (xy 284.460315 -23.639066) (xy 284.509915 -23.613565) (xy 284.562699 -23.595558)
			(xy 284.617542 -23.585428) (xy 284.673276 -23.583391) (xy 284.728713 -23.589491) (xy 284.78267 -23.603597)
			(xy 284.833999 -23.625409) (xy 284.881605 -23.654463) (xy 284.924473 -23.690138) (xy 284.96169 -23.731675)
			(xy 284.992463 -23.778188) (xy 285.016135 -23.828685) (xy 285.032203 -23.882092) (xy 285.040323 -23.937268)
			(xy 285.040498 -23.946866) (xy 285.280352 -23.946866) (xy 285.284423 -23.891244) (xy 285.296549 -23.836807)
			(xy 285.316472 -23.784716) (xy 285.343768 -23.736081) (xy 285.377854 -23.691938) (xy 285.418003 -23.653229)
			(xy 285.463361 -23.620778) (xy 285.512961 -23.595277) (xy 285.565745 -23.57727) (xy 285.620588 -23.56714)
			(xy 285.676322 -23.565103) (xy 285.731759 -23.571203) (xy 285.785716 -23.585309) (xy 285.837045 -23.607121)
			(xy 285.884651 -23.636175) (xy 285.927519 -23.67185) (xy 285.964736 -23.713387) (xy 285.995509 -23.7599)
			(xy 286.019181 -23.810397) (xy 286.035249 -23.863804) (xy 286.043369 -23.91898) (xy 286.043878 -23.946866)
			(xy 286.043438 -23.970996) (xy 286.27273 -23.970996) (xy 286.276801 -23.915374) (xy 286.288927 -23.860937)
			(xy 286.30885 -23.808846) (xy 286.336146 -23.760211) (xy 286.370232 -23.716068) (xy 286.410381 -23.677359)
			(xy 286.455739 -23.644908) (xy 286.505339 -23.619407) (xy 286.558123 -23.6014) (xy 286.612966 -23.59127)
			(xy 286.6687 -23.589233) (xy 286.675634 -23.589996) (xy 300.284386 -23.589996) (xy 300.288457 -23.534374)
			(xy 300.300583 -23.479937) (xy 300.320506 -23.427846) (xy 300.347802 -23.379211) (xy 300.381888 -23.335068)
			(xy 300.422037 -23.296359) (xy 300.467395 -23.263908) (xy 300.516995 -23.238407) (xy 300.569779 -23.2204)
			(xy 300.624622 -23.21027) (xy 300.680356 -23.208233) (xy 300.735793 -23.214333) (xy 300.78975 -23.228439)
			(xy 300.841079 -23.250251) (xy 300.888685 -23.279305) (xy 300.931553 -23.31498) (xy 300.96877 -23.356517)
			(xy 300.999543 -23.40303) (xy 301.023215 -23.453527) (xy 301.039283 -23.506934) (xy 301.047403 -23.56211)
			(xy 301.047912 -23.589996) (xy 301.047403 -23.617882) (xy 301.039283 -23.673058) (xy 301.023215 -23.726465)
			(xy 300.999543 -23.776962) (xy 300.96877 -23.823475) (xy 300.931553 -23.865012) (xy 300.888685 -23.900687)
			(xy 300.841079 -23.929741) (xy 300.78975 -23.951553) (xy 300.737725 -23.965154) (xy 310.277254 -23.965154)
			(xy 310.281325 -23.909532) (xy 310.293451 -23.855095) (xy 310.313374 -23.803004) (xy 310.34067 -23.754369)
			(xy 310.374756 -23.710226) (xy 310.414905 -23.671517) (xy 310.460263 -23.639066) (xy 310.509863 -23.613565)
			(xy 310.562647 -23.595558) (xy 310.61749 -23.585428) (xy 310.673224 -23.583391) (xy 310.728661 -23.589491)
			(xy 310.782618 -23.603597) (xy 310.833947 -23.625409) (xy 310.881553 -23.654463) (xy 310.924421 -23.690138)
			(xy 310.961638 -23.731675) (xy 310.992411 -23.778188) (xy 311.016083 -23.828685) (xy 311.032151 -23.882092)
			(xy 311.040271 -23.937268) (xy 311.040446 -23.946866) (xy 311.2803 -23.946866) (xy 311.284371 -23.891244)
			(xy 311.296497 -23.836807) (xy 311.31642 -23.784716) (xy 311.343716 -23.736081) (xy 311.377802 -23.691938)
			(xy 311.417951 -23.653229) (xy 311.463309 -23.620778) (xy 311.512909 -23.595277) (xy 311.565693 -23.57727)
			(xy 311.620536 -23.56714) (xy 311.67627 -23.565103) (xy 311.731707 -23.571203) (xy 311.785664 -23.585309)
			(xy 311.836993 -23.607121) (xy 311.884599 -23.636175) (xy 311.927467 -23.67185) (xy 311.964684 -23.713387)
			(xy 311.995457 -23.7599) (xy 312.019129 -23.810397) (xy 312.035197 -23.863804) (xy 312.043317 -23.91898)
			(xy 312.043826 -23.946866) (xy 312.043386 -23.970996) (xy 312.272678 -23.970996) (xy 312.276749 -23.915374)
			(xy 312.288875 -23.860937) (xy 312.308798 -23.808846) (xy 312.336094 -23.760211) (xy 312.37018 -23.716068)
			(xy 312.410329 -23.677359) (xy 312.455687 -23.644908) (xy 312.505287 -23.619407) (xy 312.558071 -23.6014)
			(xy 312.612914 -23.59127) (xy 312.668648 -23.589233) (xy 312.675582 -23.589996) (xy 326.284334 -23.589996)
			(xy 326.288405 -23.534374) (xy 326.300531 -23.479937) (xy 326.320454 -23.427846) (xy 326.34775 -23.379211)
			(xy 326.381836 -23.335068) (xy 326.421985 -23.296359) (xy 326.467343 -23.263908) (xy 326.516943 -23.238407)
			(xy 326.569727 -23.2204) (xy 326.62457 -23.21027) (xy 326.680304 -23.208233) (xy 326.735741 -23.214333)
			(xy 326.789698 -23.228439) (xy 326.841027 -23.250251) (xy 326.888633 -23.279305) (xy 326.931501 -23.31498)
			(xy 326.968718 -23.356517) (xy 326.999491 -23.40303) (xy 327.023163 -23.453527) (xy 327.039231 -23.506934)
			(xy 327.047351 -23.56211) (xy 327.04786 -23.589996) (xy 327.047351 -23.617882) (xy 327.039231 -23.673058)
			(xy 327.023163 -23.726465) (xy 326.999491 -23.776962) (xy 326.968718 -23.823475) (xy 326.931501 -23.865012)
			(xy 326.888633 -23.900687) (xy 326.841027 -23.929741) (xy 326.789698 -23.951553) (xy 326.735741 -23.965659)
			(xy 326.680304 -23.971759) (xy 326.62457 -23.969722) (xy 326.569727 -23.959592) (xy 326.516943 -23.941585)
			(xy 326.467343 -23.916084) (xy 326.421985 -23.883633) (xy 326.381836 -23.844924) (xy 326.34775 -23.800781)
			(xy 326.320454 -23.752146) (xy 326.300531 -23.700055) (xy 326.288405 -23.645618) (xy 326.284334 -23.589996)
			(xy 312.675582 -23.589996) (xy 312.724085 -23.595333) (xy 312.778042 -23.609439) (xy 312.829371 -23.631251)
			(xy 312.876977 -23.660305) (xy 312.919845 -23.69598) (xy 312.957062 -23.737517) (xy 312.987835 -23.78403)
			(xy 313.011507 -23.834527) (xy 313.027575 -23.887934) (xy 313.035695 -23.94311) (xy 313.036204 -23.970996)
			(xy 313.035695 -23.998882) (xy 313.027575 -24.054058) (xy 313.011507 -24.107465) (xy 312.987835 -24.157962)
			(xy 312.987682 -24.158194) (xy 317.65062 -24.158194) (xy 317.654691 -24.102572) (xy 317.666817 -24.048135)
			(xy 317.68674 -23.996044) (xy 317.714036 -23.947409) (xy 317.748122 -23.903266) (xy 317.788271 -23.864557)
			(xy 317.833629 -23.832106) (xy 317.883229 -23.806605) (xy 317.936013 -23.788598) (xy 317.990856 -23.778468)
			(xy 318.04659 -23.776431) (xy 318.102027 -23.782531) (xy 318.155984 -23.796637) (xy 318.207313 -23.818449)
			(xy 318.254919 -23.847503) (xy 318.297787 -23.883178) (xy 318.335004 -23.924715) (xy 318.365777 -23.971228)
			(xy 318.389449 -24.021725) (xy 318.405517 -24.075132) (xy 318.413637 -24.130308) (xy 318.414146 -24.158194)
			(xy 318.413637 -24.18608) (xy 318.413068 -24.189944) (xy 321.49872 -24.189944) (xy 321.502791 -24.134322)
			(xy 321.514917 -24.079885) (xy 321.53484 -24.027794) (xy 321.562136 -23.979159) (xy 321.596222 -23.935016)
			(xy 321.636371 -23.896307) (xy 321.681729 -23.863856) (xy 321.731329 -23.838355) (xy 321.784113 -23.820348)
			(xy 321.838956 -23.810218) (xy 321.89469 -23.808181) (xy 321.950127 -23.814281) (xy 322.004084 -23.828387)
			(xy 322.055413 -23.850199) (xy 322.103019 -23.879253) (xy 322.145887 -23.914928) (xy 322.183104 -23.956465)
			(xy 322.213877 -24.002978) (xy 322.237549 -24.053475) (xy 322.253617 -24.106882) (xy 322.261737 -24.162058)
			(xy 322.262246 -24.189944) (xy 324.021702 -24.189944) (xy 324.025773 -24.134322) (xy 324.037899 -24.079885)
			(xy 324.057822 -24.027794) (xy 324.085118 -23.979159) (xy 324.119204 -23.935016) (xy 324.159353 -23.896307)
			(xy 324.204711 -23.863856) (xy 324.254311 -23.838355) (xy 324.307095 -23.820348) (xy 324.361938 -23.810218)
			(xy 324.417672 -23.808181) (xy 324.473109 -23.814281) (xy 324.527066 -23.828387) (xy 324.578395 -23.850199)
			(xy 324.626001 -23.879253) (xy 324.668869 -23.914928) (xy 324.706086 -23.956465) (xy 324.736859 -24.002978)
			(xy 324.760531 -24.053475) (xy 324.776599 -24.106882) (xy 324.784719 -24.162058) (xy 324.785228 -24.189944)
			(xy 324.784719 -24.21783) (xy 324.776599 -24.273006) (xy 324.760531 -24.326413) (xy 324.736859 -24.37691)
			(xy 324.706086 -24.423423) (xy 324.668869 -24.46496) (xy 324.626001 -24.500635) (xy 324.578395 -24.529689)
			(xy 324.527066 -24.551501) (xy 324.473109 -24.565607) (xy 324.417672 -24.571707) (xy 324.361938 -24.56967)
			(xy 324.307095 -24.55954) (xy 324.254311 -24.541533) (xy 324.204711 -24.516032) (xy 324.159353 -24.483581)
			(xy 324.119204 -24.444872) (xy 324.085118 -24.400729) (xy 324.057822 -24.352094) (xy 324.037899 -24.300003)
			(xy 324.025773 -24.245566) (xy 324.021702 -24.189944) (xy 322.262246 -24.189944) (xy 322.261737 -24.21783)
			(xy 322.253617 -24.273006) (xy 322.237549 -24.326413) (xy 322.213877 -24.37691) (xy 322.183104 -24.423423)
			(xy 322.145887 -24.46496) (xy 322.103019 -24.500635) (xy 322.055413 -24.529689) (xy 322.004084 -24.551501)
			(xy 321.950127 -24.565607) (xy 321.89469 -24.571707) (xy 321.838956 -24.56967) (xy 321.784113 -24.55954)
			(xy 321.731329 -24.541533) (xy 321.681729 -24.516032) (xy 321.636371 -24.483581) (xy 321.596222 -24.444872)
			(xy 321.562136 -24.400729) (xy 321.53484 -24.352094) (xy 321.514917 -24.300003) (xy 321.502791 -24.245566)
			(xy 321.49872 -24.189944) (xy 318.413068 -24.189944) (xy 318.405517 -24.241256) (xy 318.389449 -24.294663)
			(xy 318.365777 -24.34516) (xy 318.335004 -24.391673) (xy 318.297787 -24.43321) (xy 318.254919 -24.468885)
			(xy 318.207313 -24.497939) (xy 318.155984 -24.519751) (xy 318.102027 -24.533857) (xy 318.04659 -24.539957)
			(xy 317.990856 -24.53792) (xy 317.936013 -24.52779) (xy 317.883229 -24.509783) (xy 317.833629 -24.484282)
			(xy 317.788271 -24.451831) (xy 317.748122 -24.413122) (xy 317.714036 -24.368979) (xy 317.68674 -24.320344)
			(xy 317.666817 -24.268253) (xy 317.654691 -24.213816) (xy 317.65062 -24.158194) (xy 312.987682 -24.158194)
			(xy 312.957062 -24.204475) (xy 312.919845 -24.246012) (xy 312.876977 -24.281687) (xy 312.829371 -24.310741)
			(xy 312.778042 -24.332553) (xy 312.724085 -24.346659) (xy 312.668648 -24.352759) (xy 312.612914 -24.350722)
			(xy 312.558071 -24.340592) (xy 312.505287 -24.322585) (xy 312.455687 -24.297084) (xy 312.410329 -24.264633)
			(xy 312.37018 -24.225924) (xy 312.336094 -24.181781) (xy 312.308798 -24.133146) (xy 312.288875 -24.081055)
			(xy 312.276749 -24.026618) (xy 312.272678 -23.970996) (xy 312.043386 -23.970996) (xy 312.043317 -23.974752)
			(xy 312.035197 -24.029928) (xy 312.019129 -24.083335) (xy 311.995457 -24.133832) (xy 311.964684 -24.180345)
			(xy 311.927467 -24.221882) (xy 311.884599 -24.257557) (xy 311.836993 -24.286611) (xy 311.785664 -24.308423)
			(xy 311.731707 -24.322529) (xy 311.67627 -24.328629) (xy 311.620536 -24.326592) (xy 311.565693 -24.316462)
			(xy 311.512909 -24.298455) (xy 311.463309 -24.272954) (xy 311.417951 -24.240503) (xy 311.377802 -24.201794)
			(xy 311.343716 -24.157651) (xy 311.31642 -24.109016) (xy 311.296497 -24.056925) (xy 311.284371 -24.002488)
			(xy 311.2803 -23.946866) (xy 311.040446 -23.946866) (xy 311.04078 -23.965154) (xy 311.040271 -23.99304)
			(xy 311.032151 -24.048216) (xy 311.016083 -24.101623) (xy 310.992411 -24.15212) (xy 310.961638 -24.198633)
			(xy 310.924421 -24.24017) (xy 310.881553 -24.275845) (xy 310.833947 -24.304899) (xy 310.782618 -24.326711)
			(xy 310.728661 -24.340817) (xy 310.673224 -24.346917) (xy 310.61749 -24.34488) (xy 310.562647 -24.33475)
			(xy 310.509863 -24.316743) (xy 310.460263 -24.291242) (xy 310.414905 -24.258791) (xy 310.374756 -24.220082)
			(xy 310.34067 -24.175939) (xy 310.313374 -24.127304) (xy 310.293451 -24.075213) (xy 310.281325 -24.020776)
			(xy 310.277254 -23.965154) (xy 300.737725 -23.965154) (xy 300.735793 -23.965659) (xy 300.680356 -23.971759)
			(xy 300.624622 -23.969722) (xy 300.569779 -23.959592) (xy 300.516995 -23.941585) (xy 300.467395 -23.916084)
			(xy 300.422037 -23.883633) (xy 300.381888 -23.844924) (xy 300.347802 -23.800781) (xy 300.320506 -23.752146)
			(xy 300.300583 -23.700055) (xy 300.288457 -23.645618) (xy 300.284386 -23.589996) (xy 286.675634 -23.589996)
			(xy 286.724137 -23.595333) (xy 286.778094 -23.609439) (xy 286.829423 -23.631251) (xy 286.877029 -23.660305)
			(xy 286.919897 -23.69598) (xy 286.957114 -23.737517) (xy 286.987887 -23.78403) (xy 287.011559 -23.834527)
			(xy 287.027627 -23.887934) (xy 287.035747 -23.94311) (xy 287.036256 -23.970996) (xy 287.035747 -23.998882)
			(xy 287.027627 -24.054058) (xy 287.011559 -24.107465) (xy 286.987887 -24.157962) (xy 286.987734 -24.158194)
			(xy 291.650672 -24.158194) (xy 291.654743 -24.102572) (xy 291.666869 -24.048135) (xy 291.686792 -23.996044)
			(xy 291.714088 -23.947409) (xy 291.748174 -23.903266) (xy 291.788323 -23.864557) (xy 291.833681 -23.832106)
			(xy 291.883281 -23.806605) (xy 291.936065 -23.788598) (xy 291.990908 -23.778468) (xy 292.046642 -23.776431)
			(xy 292.102079 -23.782531) (xy 292.156036 -23.796637) (xy 292.207365 -23.818449) (xy 292.254971 -23.847503)
			(xy 292.297839 -23.883178) (xy 292.335056 -23.924715) (xy 292.365829 -23.971228) (xy 292.389501 -24.021725)
			(xy 292.405569 -24.075132) (xy 292.413689 -24.130308) (xy 292.414198 -24.158194) (xy 292.413689 -24.18608)
			(xy 292.41312 -24.189944) (xy 295.498772 -24.189944) (xy 295.502843 -24.134322) (xy 295.514969 -24.079885)
			(xy 295.534892 -24.027794) (xy 295.562188 -23.979159) (xy 295.596274 -23.935016) (xy 295.636423 -23.896307)
			(xy 295.681781 -23.863856) (xy 295.731381 -23.838355) (xy 295.784165 -23.820348) (xy 295.839008 -23.810218)
			(xy 295.894742 -23.808181) (xy 295.950179 -23.814281) (xy 296.004136 -23.828387) (xy 296.055465 -23.850199)
			(xy 296.103071 -23.879253) (xy 296.145939 -23.914928) (xy 296.183156 -23.956465) (xy 296.213929 -24.002978)
			(xy 296.237601 -24.053475) (xy 296.253669 -24.106882) (xy 296.261789 -24.162058) (xy 296.262298 -24.189944)
			(xy 298.021754 -24.189944) (xy 298.025825 -24.134322) (xy 298.037951 -24.079885) (xy 298.057874 -24.027794)
			(xy 298.08517 -23.979159) (xy 298.119256 -23.935016) (xy 298.159405 -23.896307) (xy 298.204763 -23.863856)
			(xy 298.254363 -23.838355) (xy 298.307147 -23.820348) (xy 298.36199 -23.810218) (xy 298.417724 -23.808181)
			(xy 298.473161 -23.814281) (xy 298.527118 -23.828387) (xy 298.578447 -23.850199) (xy 298.626053 -23.879253)
			(xy 298.668921 -23.914928) (xy 298.706138 -23.956465) (xy 298.736911 -24.002978) (xy 298.760583 -24.053475)
			(xy 298.776651 -24.106882) (xy 298.784771 -24.162058) (xy 298.78528 -24.189944) (xy 298.784771 -24.21783)
			(xy 298.776651 -24.273006) (xy 298.760583 -24.326413) (xy 298.736911 -24.37691) (xy 298.706138 -24.423423)
			(xy 298.668921 -24.46496) (xy 298.626053 -24.500635) (xy 298.578447 -24.529689) (xy 298.527118 -24.551501)
			(xy 298.473161 -24.565607) (xy 298.417724 -24.571707) (xy 298.36199 -24.56967) (xy 298.307147 -24.55954)
			(xy 298.254363 -24.541533) (xy 298.204763 -24.516032) (xy 298.159405 -24.483581) (xy 298.119256 -24.444872)
			(xy 298.08517 -24.400729) (xy 298.057874 -24.352094) (xy 298.037951 -24.300003) (xy 298.025825 -24.245566)
			(xy 298.021754 -24.189944) (xy 296.262298 -24.189944) (xy 296.261789 -24.21783) (xy 296.253669 -24.273006)
			(xy 296.237601 -24.326413) (xy 296.213929 -24.37691) (xy 296.183156 -24.423423) (xy 296.145939 -24.46496)
			(xy 296.103071 -24.500635) (xy 296.055465 -24.529689) (xy 296.004136 -24.551501) (xy 295.950179 -24.565607)
			(xy 295.894742 -24.571707) (xy 295.839008 -24.56967) (xy 295.784165 -24.55954) (xy 295.731381 -24.541533)
			(xy 295.681781 -24.516032) (xy 295.636423 -24.483581) (xy 295.596274 -24.444872) (xy 295.562188 -24.400729)
			(xy 295.534892 -24.352094) (xy 295.514969 -24.300003) (xy 295.502843 -24.245566) (xy 295.498772 -24.189944)
			(xy 292.41312 -24.189944) (xy 292.405569 -24.241256) (xy 292.389501 -24.294663) (xy 292.365829 -24.34516)
			(xy 292.335056 -24.391673) (xy 292.297839 -24.43321) (xy 292.254971 -24.468885) (xy 292.207365 -24.497939)
			(xy 292.156036 -24.519751) (xy 292.102079 -24.533857) (xy 292.046642 -24.539957) (xy 291.990908 -24.53792)
			(xy 291.936065 -24.52779) (xy 291.883281 -24.509783) (xy 291.833681 -24.484282) (xy 291.788323 -24.451831)
			(xy 291.748174 -24.413122) (xy 291.714088 -24.368979) (xy 291.686792 -24.320344) (xy 291.666869 -24.268253)
			(xy 291.654743 -24.213816) (xy 291.650672 -24.158194) (xy 286.987734 -24.158194) (xy 286.957114 -24.204475)
			(xy 286.919897 -24.246012) (xy 286.877029 -24.281687) (xy 286.829423 -24.310741) (xy 286.778094 -24.332553)
			(xy 286.724137 -24.346659) (xy 286.6687 -24.352759) (xy 286.612966 -24.350722) (xy 286.558123 -24.340592)
			(xy 286.505339 -24.322585) (xy 286.455739 -24.297084) (xy 286.410381 -24.264633) (xy 286.370232 -24.225924)
			(xy 286.336146 -24.181781) (xy 286.30885 -24.133146) (xy 286.288927 -24.081055) (xy 286.276801 -24.026618)
			(xy 286.27273 -23.970996) (xy 286.043438 -23.970996) (xy 286.043369 -23.974752) (xy 286.035249 -24.029928)
			(xy 286.019181 -24.083335) (xy 285.995509 -24.133832) (xy 285.964736 -24.180345) (xy 285.927519 -24.221882)
			(xy 285.884651 -24.257557) (xy 285.837045 -24.286611) (xy 285.785716 -24.308423) (xy 285.731759 -24.322529)
			(xy 285.676322 -24.328629) (xy 285.620588 -24.326592) (xy 285.565745 -24.316462) (xy 285.512961 -24.298455)
			(xy 285.463361 -24.272954) (xy 285.418003 -24.240503) (xy 285.377854 -24.201794) (xy 285.343768 -24.157651)
			(xy 285.316472 -24.109016) (xy 285.296549 -24.056925) (xy 285.284423 -24.002488) (xy 285.280352 -23.946866)
			(xy 285.040498 -23.946866) (xy 285.040832 -23.965154) (xy 285.040323 -23.99304) (xy 285.032203 -24.048216)
			(xy 285.016135 -24.101623) (xy 284.992463 -24.15212) (xy 284.96169 -24.198633) (xy 284.924473 -24.24017)
			(xy 284.881605 -24.275845) (xy 284.833999 -24.304899) (xy 284.78267 -24.326711) (xy 284.728713 -24.340817)
			(xy 284.673276 -24.346917) (xy 284.617542 -24.34488) (xy 284.562699 -24.33475) (xy 284.509915 -24.316743)
			(xy 284.460315 -24.291242) (xy 284.414957 -24.258791) (xy 284.374808 -24.220082) (xy 284.340722 -24.175939)
			(xy 284.313426 -24.127304) (xy 284.293503 -24.075213) (xy 284.281377 -24.020776) (xy 284.277306 -23.965154)
			(xy 274.737777 -23.965154) (xy 274.735845 -23.965659) (xy 274.680408 -23.971759) (xy 274.624674 -23.969722)
			(xy 274.569831 -23.959592) (xy 274.517047 -23.941585) (xy 274.467447 -23.916084) (xy 274.422089 -23.883633)
			(xy 274.38194 -23.844924) (xy 274.347854 -23.800781) (xy 274.320558 -23.752146) (xy 274.300635 -23.700055)
			(xy 274.288509 -23.645618) (xy 274.284438 -23.589996) (xy 260.675686 -23.589996) (xy 260.724189 -23.595333)
			(xy 260.778146 -23.609439) (xy 260.829475 -23.631251) (xy 260.877081 -23.660305) (xy 260.919949 -23.69598)
			(xy 260.957166 -23.737517) (xy 260.987939 -23.78403) (xy 261.011611 -23.834527) (xy 261.027679 -23.887934)
			(xy 261.035799 -23.94311) (xy 261.036308 -23.970996) (xy 261.035799 -23.998882) (xy 261.027679 -24.054058)
			(xy 261.011611 -24.107465) (xy 260.987939 -24.157962) (xy 260.987786 -24.158194) (xy 265.650724 -24.158194)
			(xy 265.654795 -24.102572) (xy 265.666921 -24.048135) (xy 265.686844 -23.996044) (xy 265.71414 -23.947409)
			(xy 265.748226 -23.903266) (xy 265.788375 -23.864557) (xy 265.833733 -23.832106) (xy 265.883333 -23.806605)
			(xy 265.936117 -23.788598) (xy 265.99096 -23.778468) (xy 266.046694 -23.776431) (xy 266.102131 -23.782531)
			(xy 266.156088 -23.796637) (xy 266.207417 -23.818449) (xy 266.255023 -23.847503) (xy 266.297891 -23.883178)
			(xy 266.335108 -23.924715) (xy 266.365881 -23.971228) (xy 266.389553 -24.021725) (xy 266.405621 -24.075132)
			(xy 266.413741 -24.130308) (xy 266.41425 -24.158194) (xy 266.413741 -24.18608) (xy 266.413172 -24.189944)
			(xy 269.498824 -24.189944) (xy 269.502895 -24.134322) (xy 269.515021 -24.079885) (xy 269.534944 -24.027794)
			(xy 269.56224 -23.979159) (xy 269.596326 -23.935016) (xy 269.636475 -23.896307) (xy 269.681833 -23.863856)
			(xy 269.731433 -23.838355) (xy 269.784217 -23.820348) (xy 269.83906 -23.810218) (xy 269.894794 -23.808181)
			(xy 269.950231 -23.814281) (xy 270.004188 -23.828387) (xy 270.055517 -23.850199) (xy 270.103123 -23.879253)
			(xy 270.145991 -23.914928) (xy 270.183208 -23.956465) (xy 270.213981 -24.002978) (xy 270.237653 -24.053475)
			(xy 270.253721 -24.106882) (xy 270.261841 -24.162058) (xy 270.26235 -24.189944) (xy 272.021806 -24.189944)
			(xy 272.025877 -24.134322) (xy 272.038003 -24.079885) (xy 272.057926 -24.027794) (xy 272.085222 -23.979159)
			(xy 272.119308 -23.935016) (xy 272.159457 -23.896307) (xy 272.204815 -23.863856) (xy 272.254415 -23.838355)
			(xy 272.307199 -23.820348) (xy 272.362042 -23.810218) (xy 272.417776 -23.808181) (xy 272.473213 -23.814281)
			(xy 272.52717 -23.828387) (xy 272.578499 -23.850199) (xy 272.626105 -23.879253) (xy 272.668973 -23.914928)
			(xy 272.70619 -23.956465) (xy 272.736963 -24.002978) (xy 272.760635 -24.053475) (xy 272.776703 -24.106882)
			(xy 272.784823 -24.162058) (xy 272.785332 -24.189944) (xy 272.784823 -24.21783) (xy 272.776703 -24.273006)
			(xy 272.760635 -24.326413) (xy 272.736963 -24.37691) (xy 272.70619 -24.423423) (xy 272.668973 -24.46496)
			(xy 272.626105 -24.500635) (xy 272.578499 -24.529689) (xy 272.52717 -24.551501) (xy 272.473213 -24.565607)
			(xy 272.417776 -24.571707) (xy 272.362042 -24.56967) (xy 272.307199 -24.55954) (xy 272.254415 -24.541533)
			(xy 272.204815 -24.516032) (xy 272.159457 -24.483581) (xy 272.119308 -24.444872) (xy 272.085222 -24.400729)
			(xy 272.057926 -24.352094) (xy 272.038003 -24.300003) (xy 272.025877 -24.245566) (xy 272.021806 -24.189944)
			(xy 270.26235 -24.189944) (xy 270.261841 -24.21783) (xy 270.253721 -24.273006) (xy 270.237653 -24.326413)
			(xy 270.213981 -24.37691) (xy 270.183208 -24.423423) (xy 270.145991 -24.46496) (xy 270.103123 -24.500635)
			(xy 270.055517 -24.529689) (xy 270.004188 -24.551501) (xy 269.950231 -24.565607) (xy 269.894794 -24.571707)
			(xy 269.83906 -24.56967) (xy 269.784217 -24.55954) (xy 269.731433 -24.541533) (xy 269.681833 -24.516032)
			(xy 269.636475 -24.483581) (xy 269.596326 -24.444872) (xy 269.56224 -24.400729) (xy 269.534944 -24.352094)
			(xy 269.515021 -24.300003) (xy 269.502895 -24.245566) (xy 269.498824 -24.189944) (xy 266.413172 -24.189944)
			(xy 266.405621 -24.241256) (xy 266.389553 -24.294663) (xy 266.365881 -24.34516) (xy 266.335108 -24.391673)
			(xy 266.297891 -24.43321) (xy 266.255023 -24.468885) (xy 266.207417 -24.497939) (xy 266.156088 -24.519751)
			(xy 266.102131 -24.533857) (xy 266.046694 -24.539957) (xy 265.99096 -24.53792) (xy 265.936117 -24.52779)
			(xy 265.883333 -24.509783) (xy 265.833733 -24.484282) (xy 265.788375 -24.451831) (xy 265.748226 -24.413122)
			(xy 265.71414 -24.368979) (xy 265.686844 -24.320344) (xy 265.666921 -24.268253) (xy 265.654795 -24.213816)
			(xy 265.650724 -24.158194) (xy 260.987786 -24.158194) (xy 260.957166 -24.204475) (xy 260.919949 -24.246012)
			(xy 260.877081 -24.281687) (xy 260.829475 -24.310741) (xy 260.778146 -24.332553) (xy 260.724189 -24.346659)
			(xy 260.668752 -24.352759) (xy 260.613018 -24.350722) (xy 260.558175 -24.340592) (xy 260.505391 -24.322585)
			(xy 260.455791 -24.297084) (xy 260.410433 -24.264633) (xy 260.370284 -24.225924) (xy 260.336198 -24.181781)
			(xy 260.308902 -24.133146) (xy 260.288979 -24.081055) (xy 260.276853 -24.026618) (xy 260.272782 -23.970996)
			(xy 260.04349 -23.970996) (xy 260.043421 -23.974752) (xy 260.035301 -24.029928) (xy 260.019233 -24.083335)
			(xy 259.995561 -24.133832) (xy 259.964788 -24.180345) (xy 259.927571 -24.221882) (xy 259.884703 -24.257557)
			(xy 259.837097 -24.286611) (xy 259.785768 -24.308423) (xy 259.731811 -24.322529) (xy 259.676374 -24.328629)
			(xy 259.62064 -24.326592) (xy 259.565797 -24.316462) (xy 259.513013 -24.298455) (xy 259.463413 -24.272954)
			(xy 259.418055 -24.240503) (xy 259.377906 -24.201794) (xy 259.34382 -24.157651) (xy 259.316524 -24.109016)
			(xy 259.296601 -24.056925) (xy 259.284475 -24.002488) (xy 259.280404 -23.946866) (xy 259.04055 -23.946866)
			(xy 259.040884 -23.965154) (xy 259.040375 -23.99304) (xy 259.032255 -24.048216) (xy 259.016187 -24.101623)
			(xy 258.992515 -24.15212) (xy 258.961742 -24.198633) (xy 258.924525 -24.24017) (xy 258.881657 -24.275845)
			(xy 258.834051 -24.304899) (xy 258.782722 -24.326711) (xy 258.728765 -24.340817) (xy 258.673328 -24.346917)
			(xy 258.617594 -24.34488) (xy 258.562751 -24.33475) (xy 258.509967 -24.316743) (xy 258.460367 -24.291242)
			(xy 258.415009 -24.258791) (xy 258.37486 -24.220082) (xy 258.340774 -24.175939) (xy 258.313478 -24.127304)
			(xy 258.293555 -24.075213) (xy 258.281429 -24.020776) (xy 258.277358 -23.965154) (xy 248.737829 -23.965154)
			(xy 248.735897 -23.965659) (xy 248.68046 -23.971759) (xy 248.624726 -23.969722) (xy 248.569883 -23.959592)
			(xy 248.517099 -23.941585) (xy 248.467499 -23.916084) (xy 248.422141 -23.883633) (xy 248.381992 -23.844924)
			(xy 248.347906 -23.800781) (xy 248.32061 -23.752146) (xy 248.300687 -23.700055) (xy 248.288561 -23.645618)
			(xy 248.28449 -23.589996) (xy 222.575686 -23.589996) (xy 222.624189 -23.595333) (xy 222.678146 -23.609439)
			(xy 222.729475 -23.631251) (xy 222.777081 -23.660305) (xy 222.819949 -23.69598) (xy 222.857166 -23.737517)
			(xy 222.887939 -23.78403) (xy 222.911611 -23.834527) (xy 222.927679 -23.887934) (xy 222.935799 -23.94311)
			(xy 222.936308 -23.970996) (xy 222.935799 -23.998882) (xy 222.927679 -24.054058) (xy 222.911611 -24.107465)
			(xy 222.887939 -24.157962) (xy 222.887786 -24.158194) (xy 239.650776 -24.158194) (xy 239.654847 -24.102572)
			(xy 239.666973 -24.048135) (xy 239.686896 -23.996044) (xy 239.714192 -23.947409) (xy 239.748278 -23.903266)
			(xy 239.788427 -23.864557) (xy 239.833785 -23.832106) (xy 239.883385 -23.806605) (xy 239.936169 -23.788598)
			(xy 239.991012 -23.778468) (xy 240.046746 -23.776431) (xy 240.102183 -23.782531) (xy 240.15614 -23.796637)
			(xy 240.207469 -23.818449) (xy 240.255075 -23.847503) (xy 240.297943 -23.883178) (xy 240.33516 -23.924715)
			(xy 240.365933 -23.971228) (xy 240.389605 -24.021725) (xy 240.405673 -24.075132) (xy 240.413793 -24.130308)
			(xy 240.414302 -24.158194) (xy 240.413793 -24.18608) (xy 240.413224 -24.189944) (xy 243.498876 -24.189944)
			(xy 243.502947 -24.134322) (xy 243.515073 -24.079885) (xy 243.534996 -24.027794) (xy 243.562292 -23.979159)
			(xy 243.596378 -23.935016) (xy 243.636527 -23.896307) (xy 243.681885 -23.863856) (xy 243.731485 -23.838355)
			(xy 243.784269 -23.820348) (xy 243.839112 -23.810218) (xy 243.894846 -23.808181) (xy 243.950283 -23.814281)
			(xy 244.00424 -23.828387) (xy 244.055569 -23.850199) (xy 244.103175 -23.879253) (xy 244.146043 -23.914928)
			(xy 244.18326 -23.956465) (xy 244.214033 -24.002978) (xy 244.237705 -24.053475) (xy 244.253773 -24.106882)
			(xy 244.261893 -24.162058) (xy 244.262402 -24.189944) (xy 246.021858 -24.189944) (xy 246.025929 -24.134322)
			(xy 246.038055 -24.079885) (xy 246.057978 -24.027794) (xy 246.085274 -23.979159) (xy 246.11936 -23.935016)
			(xy 246.159509 -23.896307) (xy 246.204867 -23.863856) (xy 246.254467 -23.838355) (xy 246.307251 -23.820348)
			(xy 246.362094 -23.810218) (xy 246.417828 -23.808181) (xy 246.473265 -23.814281) (xy 246.527222 -23.828387)
			(xy 246.578551 -23.850199) (xy 246.626157 -23.879253) (xy 246.669025 -23.914928) (xy 246.706242 -23.956465)
			(xy 246.737015 -24.002978) (xy 246.760687 -24.053475) (xy 246.776755 -24.106882) (xy 246.784875 -24.162058)
			(xy 246.785384 -24.189944) (xy 246.784875 -24.21783) (xy 246.776755 -24.273006) (xy 246.760687 -24.326413)
			(xy 246.737015 -24.37691) (xy 246.706242 -24.423423) (xy 246.669025 -24.46496) (xy 246.626157 -24.500635)
			(xy 246.578551 -24.529689) (xy 246.527222 -24.551501) (xy 246.473265 -24.565607) (xy 246.417828 -24.571707)
			(xy 246.362094 -24.56967) (xy 246.307251 -24.55954) (xy 246.254467 -24.541533) (xy 246.204867 -24.516032)
			(xy 246.159509 -24.483581) (xy 246.11936 -24.444872) (xy 246.085274 -24.400729) (xy 246.057978 -24.352094)
			(xy 246.038055 -24.300003) (xy 246.025929 -24.245566) (xy 246.021858 -24.189944) (xy 244.262402 -24.189944)
			(xy 244.261893 -24.21783) (xy 244.253773 -24.273006) (xy 244.237705 -24.326413) (xy 244.214033 -24.37691)
			(xy 244.18326 -24.423423) (xy 244.146043 -24.46496) (xy 244.103175 -24.500635) (xy 244.055569 -24.529689)
			(xy 244.00424 -24.551501) (xy 243.950283 -24.565607) (xy 243.894846 -24.571707) (xy 243.839112 -24.56967)
			(xy 243.784269 -24.55954) (xy 243.731485 -24.541533) (xy 243.681885 -24.516032) (xy 243.636527 -24.483581)
			(xy 243.596378 -24.444872) (xy 243.562292 -24.400729) (xy 243.534996 -24.352094) (xy 243.515073 -24.300003)
			(xy 243.502947 -24.245566) (xy 243.498876 -24.189944) (xy 240.413224 -24.189944) (xy 240.405673 -24.241256)
			(xy 240.389605 -24.294663) (xy 240.365933 -24.34516) (xy 240.33516 -24.391673) (xy 240.297943 -24.43321)
			(xy 240.255075 -24.468885) (xy 240.207469 -24.497939) (xy 240.15614 -24.519751) (xy 240.102183 -24.533857)
			(xy 240.046746 -24.539957) (xy 239.991012 -24.53792) (xy 239.936169 -24.52779) (xy 239.883385 -24.509783)
			(xy 239.833785 -24.484282) (xy 239.788427 -24.451831) (xy 239.748278 -24.413122) (xy 239.714192 -24.368979)
			(xy 239.686896 -24.320344) (xy 239.666973 -24.268253) (xy 239.654847 -24.213816) (xy 239.650776 -24.158194)
			(xy 222.887786 -24.158194) (xy 222.857166 -24.204475) (xy 222.819949 -24.246012) (xy 222.777081 -24.281687)
			(xy 222.729475 -24.310741) (xy 222.678146 -24.332553) (xy 222.624189 -24.346659) (xy 222.568752 -24.352759)
			(xy 222.513018 -24.350722) (xy 222.458175 -24.340592) (xy 222.405391 -24.322585) (xy 222.355791 -24.297084)
			(xy 222.310433 -24.264633) (xy 222.270284 -24.225924) (xy 222.236198 -24.181781) (xy 222.208902 -24.133146)
			(xy 222.188979 -24.081055) (xy 222.176853 -24.026618) (xy 222.172782 -23.970996) (xy 221.94349 -23.970996)
			(xy 221.943421 -23.974752) (xy 221.935301 -24.029928) (xy 221.919233 -24.083335) (xy 221.895561 -24.133832)
			(xy 221.864788 -24.180345) (xy 221.827571 -24.221882) (xy 221.784703 -24.257557) (xy 221.737097 -24.286611)
			(xy 221.685768 -24.308423) (xy 221.631811 -24.322529) (xy 221.576374 -24.328629) (xy 221.52064 -24.326592)
			(xy 221.465797 -24.316462) (xy 221.413013 -24.298455) (xy 221.363413 -24.272954) (xy 221.318055 -24.240503)
			(xy 221.277906 -24.201794) (xy 221.24382 -24.157651) (xy 221.216524 -24.109016) (xy 221.196601 -24.056925)
			(xy 221.184475 -24.002488) (xy 221.180404 -23.946866) (xy 220.94055 -23.946866) (xy 220.940884 -23.965154)
			(xy 220.940375 -23.99304) (xy 220.932255 -24.048216) (xy 220.916187 -24.101623) (xy 220.892515 -24.15212)
			(xy 220.861742 -24.198633) (xy 220.824525 -24.24017) (xy 220.781657 -24.275845) (xy 220.734051 -24.304899)
			(xy 220.682722 -24.326711) (xy 220.628765 -24.340817) (xy 220.573328 -24.346917) (xy 220.517594 -24.34488)
			(xy 220.462751 -24.33475) (xy 220.409967 -24.316743) (xy 220.360367 -24.291242) (xy 220.315009 -24.258791)
			(xy 220.27486 -24.220082) (xy 220.240774 -24.175939) (xy 220.213478 -24.127304) (xy 220.193555 -24.075213)
			(xy 220.181429 -24.020776) (xy 220.177358 -23.965154) (xy 210.637829 -23.965154) (xy 210.635897 -23.965659)
			(xy 210.58046 -23.971759) (xy 210.524726 -23.969722) (xy 210.469883 -23.959592) (xy 210.417099 -23.941585)
			(xy 210.367499 -23.916084) (xy 210.322141 -23.883633) (xy 210.281992 -23.844924) (xy 210.247906 -23.800781)
			(xy 210.22061 -23.752146) (xy 210.200687 -23.700055) (xy 210.188561 -23.645618) (xy 210.18449 -23.589996)
			(xy 196.575738 -23.589996) (xy 196.624241 -23.595333) (xy 196.678198 -23.609439) (xy 196.729527 -23.631251)
			(xy 196.777133 -23.660305) (xy 196.820001 -23.69598) (xy 196.857218 -23.737517) (xy 196.887991 -23.78403)
			(xy 196.911663 -23.834527) (xy 196.927731 -23.887934) (xy 196.935851 -23.94311) (xy 196.93636 -23.970996)
			(xy 196.935851 -23.998882) (xy 196.927731 -24.054058) (xy 196.911663 -24.107465) (xy 196.887991 -24.157962)
			(xy 196.887838 -24.158194) (xy 201.550776 -24.158194) (xy 201.554847 -24.102572) (xy 201.566973 -24.048135)
			(xy 201.586896 -23.996044) (xy 201.614192 -23.947409) (xy 201.648278 -23.903266) (xy 201.688427 -23.864557)
			(xy 201.733785 -23.832106) (xy 201.783385 -23.806605) (xy 201.836169 -23.788598) (xy 201.891012 -23.778468)
			(xy 201.946746 -23.776431) (xy 202.002183 -23.782531) (xy 202.05614 -23.796637) (xy 202.107469 -23.818449)
			(xy 202.155075 -23.847503) (xy 202.197943 -23.883178) (xy 202.23516 -23.924715) (xy 202.265933 -23.971228)
			(xy 202.289605 -24.021725) (xy 202.305673 -24.075132) (xy 202.313793 -24.130308) (xy 202.314302 -24.158194)
			(xy 202.313793 -24.18608) (xy 202.313224 -24.189944) (xy 205.398876 -24.189944) (xy 205.402947 -24.134322)
			(xy 205.415073 -24.079885) (xy 205.434996 -24.027794) (xy 205.462292 -23.979159) (xy 205.496378 -23.935016)
			(xy 205.536527 -23.896307) (xy 205.581885 -23.863856) (xy 205.631485 -23.838355) (xy 205.684269 -23.820348)
			(xy 205.739112 -23.810218) (xy 205.794846 -23.808181) (xy 205.850283 -23.814281) (xy 205.90424 -23.828387)
			(xy 205.955569 -23.850199) (xy 206.003175 -23.879253) (xy 206.046043 -23.914928) (xy 206.08326 -23.956465)
			(xy 206.114033 -24.002978) (xy 206.137705 -24.053475) (xy 206.153773 -24.106882) (xy 206.161893 -24.162058)
			(xy 206.162402 -24.189944) (xy 207.921858 -24.189944) (xy 207.925929 -24.134322) (xy 207.938055 -24.079885)
			(xy 207.957978 -24.027794) (xy 207.985274 -23.979159) (xy 208.01936 -23.935016) (xy 208.059509 -23.896307)
			(xy 208.104867 -23.863856) (xy 208.154467 -23.838355) (xy 208.207251 -23.820348) (xy 208.262094 -23.810218)
			(xy 208.317828 -23.808181) (xy 208.373265 -23.814281) (xy 208.427222 -23.828387) (xy 208.478551 -23.850199)
			(xy 208.526157 -23.879253) (xy 208.569025 -23.914928) (xy 208.606242 -23.956465) (xy 208.637015 -24.002978)
			(xy 208.660687 -24.053475) (xy 208.676755 -24.106882) (xy 208.684875 -24.162058) (xy 208.685384 -24.189944)
			(xy 208.684875 -24.21783) (xy 208.676755 -24.273006) (xy 208.660687 -24.326413) (xy 208.637015 -24.37691)
			(xy 208.606242 -24.423423) (xy 208.569025 -24.46496) (xy 208.526157 -24.500635) (xy 208.478551 -24.529689)
			(xy 208.427222 -24.551501) (xy 208.373265 -24.565607) (xy 208.317828 -24.571707) (xy 208.262094 -24.56967)
			(xy 208.207251 -24.55954) (xy 208.154467 -24.541533) (xy 208.104867 -24.516032) (xy 208.059509 -24.483581)
			(xy 208.01936 -24.444872) (xy 207.985274 -24.400729) (xy 207.957978 -24.352094) (xy 207.938055 -24.300003)
			(xy 207.925929 -24.245566) (xy 207.921858 -24.189944) (xy 206.162402 -24.189944) (xy 206.161893 -24.21783)
			(xy 206.153773 -24.273006) (xy 206.137705 -24.326413) (xy 206.114033 -24.37691) (xy 206.08326 -24.423423)
			(xy 206.046043 -24.46496) (xy 206.003175 -24.500635) (xy 205.955569 -24.529689) (xy 205.90424 -24.551501)
			(xy 205.850283 -24.565607) (xy 205.794846 -24.571707) (xy 205.739112 -24.56967) (xy 205.684269 -24.55954)
			(xy 205.631485 -24.541533) (xy 205.581885 -24.516032) (xy 205.536527 -24.483581) (xy 205.496378 -24.444872)
			(xy 205.462292 -24.400729) (xy 205.434996 -24.352094) (xy 205.415073 -24.300003) (xy 205.402947 -24.245566)
			(xy 205.398876 -24.189944) (xy 202.313224 -24.189944) (xy 202.305673 -24.241256) (xy 202.289605 -24.294663)
			(xy 202.265933 -24.34516) (xy 202.23516 -24.391673) (xy 202.197943 -24.43321) (xy 202.155075 -24.468885)
			(xy 202.107469 -24.497939) (xy 202.05614 -24.519751) (xy 202.002183 -24.533857) (xy 201.946746 -24.539957)
			(xy 201.891012 -24.53792) (xy 201.836169 -24.52779) (xy 201.783385 -24.509783) (xy 201.733785 -24.484282)
			(xy 201.688427 -24.451831) (xy 201.648278 -24.413122) (xy 201.614192 -24.368979) (xy 201.586896 -24.320344)
			(xy 201.566973 -24.268253) (xy 201.554847 -24.213816) (xy 201.550776 -24.158194) (xy 196.887838 -24.158194)
			(xy 196.857218 -24.204475) (xy 196.820001 -24.246012) (xy 196.777133 -24.281687) (xy 196.729527 -24.310741)
			(xy 196.678198 -24.332553) (xy 196.624241 -24.346659) (xy 196.568804 -24.352759) (xy 196.51307 -24.350722)
			(xy 196.458227 -24.340592) (xy 196.405443 -24.322585) (xy 196.355843 -24.297084) (xy 196.310485 -24.264633)
			(xy 196.270336 -24.225924) (xy 196.23625 -24.181781) (xy 196.208954 -24.133146) (xy 196.189031 -24.081055)
			(xy 196.176905 -24.026618) (xy 196.172834 -23.970996) (xy 195.943542 -23.970996) (xy 195.943473 -23.974752)
			(xy 195.935353 -24.029928) (xy 195.919285 -24.083335) (xy 195.895613 -24.133832) (xy 195.86484 -24.180345)
			(xy 195.827623 -24.221882) (xy 195.784755 -24.257557) (xy 195.737149 -24.286611) (xy 195.68582 -24.308423)
			(xy 195.631863 -24.322529) (xy 195.576426 -24.328629) (xy 195.520692 -24.326592) (xy 195.465849 -24.316462)
			(xy 195.413065 -24.298455) (xy 195.363465 -24.272954) (xy 195.318107 -24.240503) (xy 195.277958 -24.201794)
			(xy 195.243872 -24.157651) (xy 195.216576 -24.109016) (xy 195.196653 -24.056925) (xy 195.184527 -24.002488)
			(xy 195.180456 -23.946866) (xy 194.940602 -23.946866) (xy 194.940936 -23.965154) (xy 194.940427 -23.99304)
			(xy 194.932307 -24.048216) (xy 194.916239 -24.101623) (xy 194.892567 -24.15212) (xy 194.861794 -24.198633)
			(xy 194.824577 -24.24017) (xy 194.781709 -24.275845) (xy 194.734103 -24.304899) (xy 194.682774 -24.326711)
			(xy 194.628817 -24.340817) (xy 194.57338 -24.346917) (xy 194.517646 -24.34488) (xy 194.462803 -24.33475)
			(xy 194.410019 -24.316743) (xy 194.360419 -24.291242) (xy 194.315061 -24.258791) (xy 194.274912 -24.220082)
			(xy 194.240826 -24.175939) (xy 194.21353 -24.127304) (xy 194.193607 -24.075213) (xy 194.181481 -24.020776)
			(xy 194.17741 -23.965154) (xy 184.637881 -23.965154) (xy 184.635949 -23.965659) (xy 184.580512 -23.971759)
			(xy 184.524778 -23.969722) (xy 184.469935 -23.959592) (xy 184.417151 -23.941585) (xy 184.367551 -23.916084)
			(xy 184.322193 -23.883633) (xy 184.282044 -23.844924) (xy 184.247958 -23.800781) (xy 184.220662 -23.752146)
			(xy 184.200739 -23.700055) (xy 184.188613 -23.645618) (xy 184.184542 -23.589996) (xy 170.57579 -23.589996)
			(xy 170.624293 -23.595333) (xy 170.67825 -23.609439) (xy 170.729579 -23.631251) (xy 170.777185 -23.660305)
			(xy 170.820053 -23.69598) (xy 170.85727 -23.737517) (xy 170.888043 -23.78403) (xy 170.911715 -23.834527)
			(xy 170.927783 -23.887934) (xy 170.935903 -23.94311) (xy 170.936412 -23.970996) (xy 170.935903 -23.998882)
			(xy 170.927783 -24.054058) (xy 170.911715 -24.107465) (xy 170.888043 -24.157962) (xy 170.88789 -24.158194)
			(xy 175.550828 -24.158194) (xy 175.554899 -24.102572) (xy 175.567025 -24.048135) (xy 175.586948 -23.996044)
			(xy 175.614244 -23.947409) (xy 175.64833 -23.903266) (xy 175.688479 -23.864557) (xy 175.733837 -23.832106)
			(xy 175.783437 -23.806605) (xy 175.836221 -23.788598) (xy 175.891064 -23.778468) (xy 175.946798 -23.776431)
			(xy 176.002235 -23.782531) (xy 176.056192 -23.796637) (xy 176.107521 -23.818449) (xy 176.155127 -23.847503)
			(xy 176.197995 -23.883178) (xy 176.235212 -23.924715) (xy 176.265985 -23.971228) (xy 176.289657 -24.021725)
			(xy 176.305725 -24.075132) (xy 176.313845 -24.130308) (xy 176.314354 -24.158194) (xy 176.313845 -24.18608)
			(xy 176.313276 -24.189944) (xy 179.398928 -24.189944) (xy 179.402999 -24.134322) (xy 179.415125 -24.079885)
			(xy 179.435048 -24.027794) (xy 179.462344 -23.979159) (xy 179.49643 -23.935016) (xy 179.536579 -23.896307)
			(xy 179.581937 -23.863856) (xy 179.631537 -23.838355) (xy 179.684321 -23.820348) (xy 179.739164 -23.810218)
			(xy 179.794898 -23.808181) (xy 179.850335 -23.814281) (xy 179.904292 -23.828387) (xy 179.955621 -23.850199)
			(xy 180.003227 -23.879253) (xy 180.046095 -23.914928) (xy 180.083312 -23.956465) (xy 180.114085 -24.002978)
			(xy 180.137757 -24.053475) (xy 180.153825 -24.106882) (xy 180.161945 -24.162058) (xy 180.162454 -24.189944)
			(xy 181.92191 -24.189944) (xy 181.925981 -24.134322) (xy 181.938107 -24.079885) (xy 181.95803 -24.027794)
			(xy 181.985326 -23.979159) (xy 182.019412 -23.935016) (xy 182.059561 -23.896307) (xy 182.104919 -23.863856)
			(xy 182.154519 -23.838355) (xy 182.207303 -23.820348) (xy 182.262146 -23.810218) (xy 182.31788 -23.808181)
			(xy 182.373317 -23.814281) (xy 182.427274 -23.828387) (xy 182.478603 -23.850199) (xy 182.526209 -23.879253)
			(xy 182.569077 -23.914928) (xy 182.606294 -23.956465) (xy 182.637067 -24.002978) (xy 182.660739 -24.053475)
			(xy 182.676807 -24.106882) (xy 182.684927 -24.162058) (xy 182.685436 -24.189944) (xy 182.684927 -24.21783)
			(xy 182.676807 -24.273006) (xy 182.660739 -24.326413) (xy 182.637067 -24.37691) (xy 182.606294 -24.423423)
			(xy 182.569077 -24.46496) (xy 182.526209 -24.500635) (xy 182.478603 -24.529689) (xy 182.427274 -24.551501)
			(xy 182.373317 -24.565607) (xy 182.31788 -24.571707) (xy 182.262146 -24.56967) (xy 182.207303 -24.55954)
			(xy 182.154519 -24.541533) (xy 182.104919 -24.516032) (xy 182.059561 -24.483581) (xy 182.019412 -24.444872)
			(xy 181.985326 -24.400729) (xy 181.95803 -24.352094) (xy 181.938107 -24.300003) (xy 181.925981 -24.245566)
			(xy 181.92191 -24.189944) (xy 180.162454 -24.189944) (xy 180.161945 -24.21783) (xy 180.153825 -24.273006)
			(xy 180.137757 -24.326413) (xy 180.114085 -24.37691) (xy 180.083312 -24.423423) (xy 180.046095 -24.46496)
			(xy 180.003227 -24.500635) (xy 179.955621 -24.529689) (xy 179.904292 -24.551501) (xy 179.850335 -24.565607)
			(xy 179.794898 -24.571707) (xy 179.739164 -24.56967) (xy 179.684321 -24.55954) (xy 179.631537 -24.541533)
			(xy 179.581937 -24.516032) (xy 179.536579 -24.483581) (xy 179.49643 -24.444872) (xy 179.462344 -24.400729)
			(xy 179.435048 -24.352094) (xy 179.415125 -24.300003) (xy 179.402999 -24.245566) (xy 179.398928 -24.189944)
			(xy 176.313276 -24.189944) (xy 176.305725 -24.241256) (xy 176.289657 -24.294663) (xy 176.265985 -24.34516)
			(xy 176.235212 -24.391673) (xy 176.197995 -24.43321) (xy 176.155127 -24.468885) (xy 176.107521 -24.497939)
			(xy 176.056192 -24.519751) (xy 176.002235 -24.533857) (xy 175.946798 -24.539957) (xy 175.891064 -24.53792)
			(xy 175.836221 -24.52779) (xy 175.783437 -24.509783) (xy 175.733837 -24.484282) (xy 175.688479 -24.451831)
			(xy 175.64833 -24.413122) (xy 175.614244 -24.368979) (xy 175.586948 -24.320344) (xy 175.567025 -24.268253)
			(xy 175.554899 -24.213816) (xy 175.550828 -24.158194) (xy 170.88789 -24.158194) (xy 170.85727 -24.204475)
			(xy 170.820053 -24.246012) (xy 170.777185 -24.281687) (xy 170.729579 -24.310741) (xy 170.67825 -24.332553)
			(xy 170.624293 -24.346659) (xy 170.568856 -24.352759) (xy 170.513122 -24.350722) (xy 170.458279 -24.340592)
			(xy 170.405495 -24.322585) (xy 170.355895 -24.297084) (xy 170.310537 -24.264633) (xy 170.270388 -24.225924)
			(xy 170.236302 -24.181781) (xy 170.209006 -24.133146) (xy 170.189083 -24.081055) (xy 170.176957 -24.026618)
			(xy 170.172886 -23.970996) (xy 169.943594 -23.970996) (xy 169.943525 -23.974752) (xy 169.935405 -24.029928)
			(xy 169.919337 -24.083335) (xy 169.895665 -24.133832) (xy 169.864892 -24.180345) (xy 169.827675 -24.221882)
			(xy 169.784807 -24.257557) (xy 169.737201 -24.286611) (xy 169.685872 -24.308423) (xy 169.631915 -24.322529)
			(xy 169.576478 -24.328629) (xy 169.520744 -24.326592) (xy 169.465901 -24.316462) (xy 169.413117 -24.298455)
			(xy 169.363517 -24.272954) (xy 169.318159 -24.240503) (xy 169.27801 -24.201794) (xy 169.243924 -24.157651)
			(xy 169.216628 -24.109016) (xy 169.196705 -24.056925) (xy 169.184579 -24.002488) (xy 169.180508 -23.946866)
			(xy 168.940654 -23.946866) (xy 168.940988 -23.965154) (xy 168.940479 -23.99304) (xy 168.932359 -24.048216)
			(xy 168.916291 -24.101623) (xy 168.892619 -24.15212) (xy 168.861846 -24.198633) (xy 168.824629 -24.24017)
			(xy 168.781761 -24.275845) (xy 168.734155 -24.304899) (xy 168.682826 -24.326711) (xy 168.628869 -24.340817)
			(xy 168.573432 -24.346917) (xy 168.517698 -24.34488) (xy 168.462855 -24.33475) (xy 168.410071 -24.316743)
			(xy 168.360471 -24.291242) (xy 168.315113 -24.258791) (xy 168.274964 -24.220082) (xy 168.240878 -24.175939)
			(xy 168.213582 -24.127304) (xy 168.193659 -24.075213) (xy 168.181533 -24.020776) (xy 168.177462 -23.965154)
			(xy 158.637933 -23.965154) (xy 158.636001 -23.965659) (xy 158.580564 -23.971759) (xy 158.52483 -23.969722)
			(xy 158.469987 -23.959592) (xy 158.417203 -23.941585) (xy 158.367603 -23.916084) (xy 158.322245 -23.883633)
			(xy 158.282096 -23.844924) (xy 158.24801 -23.800781) (xy 158.220714 -23.752146) (xy 158.200791 -23.700055)
			(xy 158.188665 -23.645618) (xy 158.184594 -23.589996) (xy 144.575842 -23.589996) (xy 144.624345 -23.595333)
			(xy 144.678302 -23.609439) (xy 144.729631 -23.631251) (xy 144.777237 -23.660305) (xy 144.820105 -23.69598)
			(xy 144.857322 -23.737517) (xy 144.888095 -23.78403) (xy 144.911767 -23.834527) (xy 144.927835 -23.887934)
			(xy 144.935955 -23.94311) (xy 144.936464 -23.970996) (xy 144.935955 -23.998882) (xy 144.927835 -24.054058)
			(xy 144.911767 -24.107465) (xy 144.888095 -24.157962) (xy 144.887942 -24.158194) (xy 149.55088 -24.158194)
			(xy 149.554951 -24.102572) (xy 149.567077 -24.048135) (xy 149.587 -23.996044) (xy 149.614296 -23.947409)
			(xy 149.648382 -23.903266) (xy 149.688531 -23.864557) (xy 149.733889 -23.832106) (xy 149.783489 -23.806605)
			(xy 149.836273 -23.788598) (xy 149.891116 -23.778468) (xy 149.94685 -23.776431) (xy 150.002287 -23.782531)
			(xy 150.056244 -23.796637) (xy 150.107573 -23.818449) (xy 150.155179 -23.847503) (xy 150.198047 -23.883178)
			(xy 150.235264 -23.924715) (xy 150.266037 -23.971228) (xy 150.289709 -24.021725) (xy 150.305777 -24.075132)
			(xy 150.313897 -24.130308) (xy 150.314406 -24.158194) (xy 150.313897 -24.18608) (xy 150.313328 -24.189944)
			(xy 153.39898 -24.189944) (xy 153.403051 -24.134322) (xy 153.415177 -24.079885) (xy 153.4351 -24.027794)
			(xy 153.462396 -23.979159) (xy 153.496482 -23.935016) (xy 153.536631 -23.896307) (xy 153.581989 -23.863856)
			(xy 153.631589 -23.838355) (xy 153.684373 -23.820348) (xy 153.739216 -23.810218) (xy 153.79495 -23.808181)
			(xy 153.850387 -23.814281) (xy 153.904344 -23.828387) (xy 153.955673 -23.850199) (xy 154.003279 -23.879253)
			(xy 154.046147 -23.914928) (xy 154.083364 -23.956465) (xy 154.114137 -24.002978) (xy 154.137809 -24.053475)
			(xy 154.153877 -24.106882) (xy 154.161997 -24.162058) (xy 154.162506 -24.189944) (xy 155.921962 -24.189944)
			(xy 155.926033 -24.134322) (xy 155.938159 -24.079885) (xy 155.958082 -24.027794) (xy 155.985378 -23.979159)
			(xy 156.019464 -23.935016) (xy 156.059613 -23.896307) (xy 156.104971 -23.863856) (xy 156.154571 -23.838355)
			(xy 156.207355 -23.820348) (xy 156.262198 -23.810218) (xy 156.317932 -23.808181) (xy 156.373369 -23.814281)
			(xy 156.427326 -23.828387) (xy 156.478655 -23.850199) (xy 156.526261 -23.879253) (xy 156.569129 -23.914928)
			(xy 156.606346 -23.956465) (xy 156.637119 -24.002978) (xy 156.660791 -24.053475) (xy 156.676859 -24.106882)
			(xy 156.684979 -24.162058) (xy 156.685488 -24.189944) (xy 156.684979 -24.21783) (xy 156.676859 -24.273006)
			(xy 156.660791 -24.326413) (xy 156.637119 -24.37691) (xy 156.606346 -24.423423) (xy 156.569129 -24.46496)
			(xy 156.526261 -24.500635) (xy 156.478655 -24.529689) (xy 156.427326 -24.551501) (xy 156.373369 -24.565607)
			(xy 156.317932 -24.571707) (xy 156.262198 -24.56967) (xy 156.207355 -24.55954) (xy 156.154571 -24.541533)
			(xy 156.104971 -24.516032) (xy 156.059613 -24.483581) (xy 156.019464 -24.444872) (xy 155.985378 -24.400729)
			(xy 155.958082 -24.352094) (xy 155.938159 -24.300003) (xy 155.926033 -24.245566) (xy 155.921962 -24.189944)
			(xy 154.162506 -24.189944) (xy 154.161997 -24.21783) (xy 154.153877 -24.273006) (xy 154.137809 -24.326413)
			(xy 154.114137 -24.37691) (xy 154.083364 -24.423423) (xy 154.046147 -24.46496) (xy 154.003279 -24.500635)
			(xy 153.955673 -24.529689) (xy 153.904344 -24.551501) (xy 153.850387 -24.565607) (xy 153.79495 -24.571707)
			(xy 153.739216 -24.56967) (xy 153.684373 -24.55954) (xy 153.631589 -24.541533) (xy 153.581989 -24.516032)
			(xy 153.536631 -24.483581) (xy 153.496482 -24.444872) (xy 153.462396 -24.400729) (xy 153.4351 -24.352094)
			(xy 153.415177 -24.300003) (xy 153.403051 -24.245566) (xy 153.39898 -24.189944) (xy 150.313328 -24.189944)
			(xy 150.305777 -24.241256) (xy 150.289709 -24.294663) (xy 150.266037 -24.34516) (xy 150.235264 -24.391673)
			(xy 150.198047 -24.43321) (xy 150.155179 -24.468885) (xy 150.107573 -24.497939) (xy 150.056244 -24.519751)
			(xy 150.002287 -24.533857) (xy 149.94685 -24.539957) (xy 149.891116 -24.53792) (xy 149.836273 -24.52779)
			(xy 149.783489 -24.509783) (xy 149.733889 -24.484282) (xy 149.688531 -24.451831) (xy 149.648382 -24.413122)
			(xy 149.614296 -24.368979) (xy 149.587 -24.320344) (xy 149.567077 -24.268253) (xy 149.554951 -24.213816)
			(xy 149.55088 -24.158194) (xy 144.887942 -24.158194) (xy 144.857322 -24.204475) (xy 144.820105 -24.246012)
			(xy 144.777237 -24.281687) (xy 144.729631 -24.310741) (xy 144.678302 -24.332553) (xy 144.624345 -24.346659)
			(xy 144.568908 -24.352759) (xy 144.513174 -24.350722) (xy 144.458331 -24.340592) (xy 144.405547 -24.322585)
			(xy 144.355947 -24.297084) (xy 144.310589 -24.264633) (xy 144.27044 -24.225924) (xy 144.236354 -24.181781)
			(xy 144.209058 -24.133146) (xy 144.189135 -24.081055) (xy 144.177009 -24.026618) (xy 144.172938 -23.970996)
			(xy 143.943646 -23.970996) (xy 143.943577 -23.974752) (xy 143.935457 -24.029928) (xy 143.919389 -24.083335)
			(xy 143.895717 -24.133832) (xy 143.864944 -24.180345) (xy 143.827727 -24.221882) (xy 143.784859 -24.257557)
			(xy 143.737253 -24.286611) (xy 143.685924 -24.308423) (xy 143.631967 -24.322529) (xy 143.57653 -24.328629)
			(xy 143.520796 -24.326592) (xy 143.465953 -24.316462) (xy 143.413169 -24.298455) (xy 143.363569 -24.272954)
			(xy 143.318211 -24.240503) (xy 143.278062 -24.201794) (xy 143.243976 -24.157651) (xy 143.21668 -24.109016)
			(xy 143.196757 -24.056925) (xy 143.184631 -24.002488) (xy 143.18056 -23.946866) (xy 142.940706 -23.946866)
			(xy 142.94104 -23.965154) (xy 142.940531 -23.99304) (xy 142.932411 -24.048216) (xy 142.916343 -24.101623)
			(xy 142.892671 -24.15212) (xy 142.861898 -24.198633) (xy 142.824681 -24.24017) (xy 142.781813 -24.275845)
			(xy 142.734207 -24.304899) (xy 142.682878 -24.326711) (xy 142.628921 -24.340817) (xy 142.573484 -24.346917)
			(xy 142.51775 -24.34488) (xy 142.462907 -24.33475) (xy 142.410123 -24.316743) (xy 142.360523 -24.291242)
			(xy 142.315165 -24.258791) (xy 142.275016 -24.220082) (xy 142.24093 -24.175939) (xy 142.213634 -24.127304)
			(xy 142.193711 -24.075213) (xy 142.181585 -24.020776) (xy 142.177514 -23.965154) (xy 132.637985 -23.965154)
			(xy 132.636053 -23.965659) (xy 132.580616 -23.971759) (xy 132.524882 -23.969722) (xy 132.470039 -23.959592)
			(xy 132.417255 -23.941585) (xy 132.367655 -23.916084) (xy 132.322297 -23.883633) (xy 132.282148 -23.844924)
			(xy 132.248062 -23.800781) (xy 132.220766 -23.752146) (xy 132.200843 -23.700055) (xy 132.188717 -23.645618)
			(xy 132.184646 -23.589996) (xy 115.586256 -23.589996) (xy 115.018058 -24.158194) (xy 123.550932 -24.158194)
			(xy 123.555003 -24.102572) (xy 123.567129 -24.048135) (xy 123.587052 -23.996044) (xy 123.614348 -23.947409)
			(xy 123.648434 -23.903266) (xy 123.688583 -23.864557) (xy 123.733941 -23.832106) (xy 123.783541 -23.806605)
			(xy 123.836325 -23.788598) (xy 123.891168 -23.778468) (xy 123.946902 -23.776431) (xy 124.002339 -23.782531)
			(xy 124.056296 -23.796637) (xy 124.107625 -23.818449) (xy 124.155231 -23.847503) (xy 124.198099 -23.883178)
			(xy 124.235316 -23.924715) (xy 124.266089 -23.971228) (xy 124.289761 -24.021725) (xy 124.305829 -24.075132)
			(xy 124.313949 -24.130308) (xy 124.314458 -24.158194) (xy 124.313949 -24.18608) (xy 124.31338 -24.189944)
			(xy 127.399032 -24.189944) (xy 127.403103 -24.134322) (xy 127.415229 -24.079885) (xy 127.435152 -24.027794)
			(xy 127.462448 -23.979159) (xy 127.496534 -23.935016) (xy 127.536683 -23.896307) (xy 127.582041 -23.863856)
			(xy 127.631641 -23.838355) (xy 127.684425 -23.820348) (xy 127.739268 -23.810218) (xy 127.795002 -23.808181)
			(xy 127.850439 -23.814281) (xy 127.904396 -23.828387) (xy 127.955725 -23.850199) (xy 128.003331 -23.879253)
			(xy 128.046199 -23.914928) (xy 128.083416 -23.956465) (xy 128.114189 -24.002978) (xy 128.137861 -24.053475)
			(xy 128.153929 -24.106882) (xy 128.162049 -24.162058) (xy 128.162558 -24.189944) (xy 129.922014 -24.189944)
			(xy 129.926085 -24.134322) (xy 129.938211 -24.079885) (xy 129.958134 -24.027794) (xy 129.98543 -23.979159)
			(xy 130.019516 -23.935016) (xy 130.059665 -23.896307) (xy 130.105023 -23.863856) (xy 130.154623 -23.838355)
			(xy 130.207407 -23.820348) (xy 130.26225 -23.810218) (xy 130.317984 -23.808181) (xy 130.373421 -23.814281)
			(xy 130.427378 -23.828387) (xy 130.478707 -23.850199) (xy 130.526313 -23.879253) (xy 130.569181 -23.914928)
			(xy 130.606398 -23.956465) (xy 130.637171 -24.002978) (xy 130.660843 -24.053475) (xy 130.676911 -24.106882)
			(xy 130.685031 -24.162058) (xy 130.68554 -24.189944) (xy 130.685031 -24.21783) (xy 130.676911 -24.273006)
			(xy 130.660843 -24.326413) (xy 130.637171 -24.37691) (xy 130.606398 -24.423423) (xy 130.569181 -24.46496)
			(xy 130.526313 -24.500635) (xy 130.478707 -24.529689) (xy 130.427378 -24.551501) (xy 130.373421 -24.565607)
			(xy 130.317984 -24.571707) (xy 130.26225 -24.56967) (xy 130.207407 -24.55954) (xy 130.154623 -24.541533)
			(xy 130.105023 -24.516032) (xy 130.059665 -24.483581) (xy 130.019516 -24.444872) (xy 129.98543 -24.400729)
			(xy 129.958134 -24.352094) (xy 129.938211 -24.300003) (xy 129.926085 -24.245566) (xy 129.922014 -24.189944)
			(xy 128.162558 -24.189944) (xy 128.162049 -24.21783) (xy 128.153929 -24.273006) (xy 128.137861 -24.326413)
			(xy 128.114189 -24.37691) (xy 128.083416 -24.423423) (xy 128.046199 -24.46496) (xy 128.003331 -24.500635)
			(xy 127.955725 -24.529689) (xy 127.904396 -24.551501) (xy 127.850439 -24.565607) (xy 127.795002 -24.571707)
			(xy 127.739268 -24.56967) (xy 127.684425 -24.55954) (xy 127.631641 -24.541533) (xy 127.582041 -24.516032)
			(xy 127.536683 -24.483581) (xy 127.496534 -24.444872) (xy 127.462448 -24.400729) (xy 127.435152 -24.352094)
			(xy 127.415229 -24.300003) (xy 127.403103 -24.245566) (xy 127.399032 -24.189944) (xy 124.31338 -24.189944)
			(xy 124.305829 -24.241256) (xy 124.289761 -24.294663) (xy 124.266089 -24.34516) (xy 124.235316 -24.391673)
			(xy 124.198099 -24.43321) (xy 124.155231 -24.468885) (xy 124.107625 -24.497939) (xy 124.056296 -24.519751)
			(xy 124.002339 -24.533857) (xy 123.946902 -24.539957) (xy 123.891168 -24.53792) (xy 123.836325 -24.52779)
			(xy 123.783541 -24.509783) (xy 123.733941 -24.484282) (xy 123.688583 -24.451831) (xy 123.648434 -24.413122)
			(xy 123.614348 -24.368979) (xy 123.587052 -24.320344) (xy 123.567129 -24.268253) (xy 123.555003 -24.213816)
			(xy 123.550932 -24.158194) (xy 115.018058 -24.158194) (xy 114.606832 -24.56942) (xy 114.599434 -24.576264)
			(xy 114.580834 -24.583987) (xy 114.570764 -24.584406) (xy 114.283744 -24.584406) (xy 114.273678 -24.58484)
			(xy 114.255089 -24.592569) (xy 114.247676 -24.599392) (xy 114.157252 -24.689816) (xy 114.133699 -24.712765)
			(xy 114.082302 -24.75379) (xy 114.026631 -24.788798) (xy 113.987995 -24.807418) (xy 122.471432 -24.807418)
			(xy 122.475503 -24.751796) (xy 122.487629 -24.697359) (xy 122.507552 -24.645268) (xy 122.534848 -24.596633)
			(xy 122.568934 -24.55249) (xy 122.609083 -24.513781) (xy 122.654441 -24.48133) (xy 122.704041 -24.455829)
			(xy 122.756825 -24.437822) (xy 122.811668 -24.427692) (xy 122.867402 -24.425655) (xy 122.922839 -24.431755)
			(xy 122.976796 -24.445861) (xy 123.028125 -24.467673) (xy 123.075731 -24.496727) (xy 123.118599 -24.532402)
			(xy 123.155816 -24.573939) (xy 123.186589 -24.620452) (xy 123.210261 -24.670949) (xy 123.226329 -24.724356)
			(xy 123.234449 -24.779532) (xy 123.234958 -24.807418) (xy 124.720348 -24.807418) (xy 124.724419 -24.751796)
			(xy 124.736545 -24.697359) (xy 124.756468 -24.645268) (xy 124.783764 -24.596633) (xy 124.81785 -24.55249)
			(xy 124.857999 -24.513781) (xy 124.903357 -24.48133) (xy 124.952957 -24.455829) (xy 125.005741 -24.437822)
			(xy 125.060584 -24.427692) (xy 125.116318 -24.425655) (xy 125.171755 -24.431755) (xy 125.225712 -24.445861)
			(xy 125.277041 -24.467673) (xy 125.324647 -24.496727) (xy 125.367515 -24.532402) (xy 125.404732 -24.573939)
			(xy 125.435505 -24.620452) (xy 125.459177 -24.670949) (xy 125.475245 -24.724356) (xy 125.483365 -24.779532)
			(xy 125.483874 -24.807418) (xy 125.483365 -24.835304) (xy 125.475245 -24.89048) (xy 125.459177 -24.943887)
			(xy 125.435505 -24.994384) (xy 125.404732 -25.040897) (xy 125.367515 -25.082434) (xy 125.324647 -25.118109)
			(xy 125.277041 -25.147163) (xy 125.225712 -25.168975) (xy 125.171755 -25.183081) (xy 125.116318 -25.189181)
			(xy 125.060584 -25.187144) (xy 125.005741 -25.177014) (xy 124.952957 -25.159007) (xy 124.903357 -25.133506)
			(xy 124.857999 -25.101055) (xy 124.81785 -25.062346) (xy 124.783764 -25.018203) (xy 124.756468 -24.969568)
			(xy 124.736545 -24.917477) (xy 124.724419 -24.86304) (xy 124.720348 -24.807418) (xy 123.234958 -24.807418)
			(xy 123.234449 -24.835304) (xy 123.226329 -24.89048) (xy 123.210261 -24.943887) (xy 123.186589 -24.994384)
			(xy 123.155816 -25.040897) (xy 123.118599 -25.082434) (xy 123.075731 -25.118109) (xy 123.028125 -25.147163)
			(xy 122.976796 -25.168975) (xy 122.922839 -25.183081) (xy 122.867402 -25.189181) (xy 122.811668 -25.187144)
			(xy 122.756825 -25.177014) (xy 122.704041 -25.159007) (xy 122.654441 -25.133506) (xy 122.609083 -25.101055)
			(xy 122.568934 -25.062346) (xy 122.534848 -25.018203) (xy 122.507552 -24.969568) (xy 122.487629 -24.917477)
			(xy 122.475503 -24.86304) (xy 122.471432 -24.807418) (xy 113.987995 -24.807418) (xy 113.967389 -24.817349)
			(xy 113.905321 -24.839082) (xy 113.841209 -24.853723) (xy 113.775859 -24.861089) (xy 113.742978 -24.86152)
			(xy 100.653088 -24.86152) (xy 100.62021 -24.861043) (xy 100.554871 -24.853652) (xy 100.490769 -24.838999)
			(xy 100.428708 -24.817266) (xy 100.369468 -24.788728) (xy 100.313793 -24.753741) (xy 100.26238 -24.712746)
			(xy 100.238814 -24.689816) (xy 100.14839 -24.599392) (xy 100.140991 -24.592548) (xy 100.122393 -24.584818)
			(xy 100.112322 -24.584406) (xy 100.090478 -24.584406) (xy 100.080409 -24.583979) (xy 100.06181 -24.57626)
			(xy 100.05441 -24.56942) (xy 94.880938 -19.395948) (xy 94.877636 -19.3929) (xy 94.874234 -19.390191)
			(xy 94.866698 -19.385854) (xy 94.86265 -19.384264) (xy 94.825566 -19.389344) (xy 94.816168 -19.394932)
			(xy 94.81566 -19.395694) (xy 94.793054 -19.436588) (xy 94.790757 -19.441691) (xy 94.788202 -19.452586)
			(xy 94.787974 -19.458178) (xy 94.792292 -19.476212) (xy 94.796356 -19.486626) (xy 94.807243 -19.509289)
			(xy 94.823629 -19.556822) (xy 94.833621 -19.606098) (xy 94.835726 -19.631152) (xy 94.835726 -19.63166)
			(xy 94.836742 -19.655282) (xy 94.836742 -19.661378) (xy 94.835961 -19.689756) (xy 94.827034 -19.745818)
			(xy 94.809896 -19.799938) (xy 94.784923 -19.850918) (xy 94.75267 -19.897634) (xy 94.733618 -19.91868)
			(xy 94.727014 -19.925792) (xy 94.723712 -19.934174) (xy 94.721955 -19.938741) (xy 94.720033 -19.948333)
			(xy 94.719902 -19.953224) (xy 94.719902 -20.02282) (xy 94.720036 -20.027711) (xy 94.721948 -20.037306)
			(xy 94.723712 -20.04187) (xy 94.727014 -20.050252) (xy 94.733618 -20.057364) (xy 94.752885 -20.078692)
			(xy 94.785444 -20.126055) (xy 94.810529 -20.177766) (xy 94.827574 -20.232654) (xy 94.836193 -20.289479)
			(xy 94.836191 -20.346953) (xy 94.827567 -20.403777) (xy 94.810518 -20.458664) (xy 94.785428 -20.510373)
			(xy 94.752865 -20.557733) (xy 94.733618 -20.57908) (xy 94.727014 -20.586192) (xy 94.723712 -20.594574)
			(xy 94.721955 -20.599141) (xy 94.720033 -20.608733) (xy 94.719902 -20.613624) (xy 94.719902 -20.68322)
			(xy 94.720036 -20.688111) (xy 94.721948 -20.697706) (xy 94.723712 -20.70227) (xy 94.727014 -20.710652)
			(xy 94.733618 -20.717764) (xy 94.752885 -20.739092) (xy 94.785444 -20.786455) (xy 94.810529 -20.838166)
			(xy 94.827574 -20.893054) (xy 94.836193 -20.949879) (xy 94.836191 -21.007353) (xy 94.827567 -21.064177)
			(xy 94.810518 -21.119064) (xy 94.785428 -21.170773) (xy 94.752865 -21.218133) (xy 94.733618 -21.23948)
			(xy 94.727014 -21.246592) (xy 94.723712 -21.254974) (xy 94.721955 -21.259541) (xy 94.720033 -21.269133)
			(xy 94.719902 -21.274024) (xy 94.719902 -21.34362) (xy 94.720036 -21.348511) (xy 94.721948 -21.358106)
			(xy 94.723712 -21.36267) (xy 94.727014 -21.371052) (xy 94.733618 -21.378164) (xy 94.752886 -21.399492)
			(xy 94.785445 -21.446856) (xy 94.81053 -21.498568) (xy 94.827575 -21.553458) (xy 94.836194 -21.610284)
			(xy 94.836742 -21.639022) (xy 94.836256 -21.666273) (xy 94.8285 -21.720221) (xy 94.813145 -21.772516)
			(xy 94.790503 -21.822093) (xy 94.761037 -21.867943) (xy 94.725346 -21.909134) (xy 94.684155 -21.944825)
			(xy 94.638305 -21.974291) (xy 94.588728 -21.996933) (xy 94.536433 -22.012288) (xy 94.482485 -22.020044)
			(xy 94.427983 -22.020044) (xy 94.374035 -22.012288) (xy 94.32174 -21.996933) (xy 94.272163 -21.974291)
			(xy 94.226313 -21.944825) (xy 94.185122 -21.909134) (xy 94.149431 -21.867943) (xy 94.119965 -21.822093)
			(xy 94.097323 -21.772516) (xy 94.081968 -21.720221) (xy 94.074212 -21.666273) (xy 94.073726 -21.639022)
			(xy 94.074245 -21.610282) (xy 94.082866 -21.553453) (xy 94.099914 -21.498561) (xy 94.125005 -21.446848)
			(xy 94.157571 -21.399484) (xy 94.17685 -21.378164) (xy 94.183454 -21.371052) (xy 94.186756 -21.36267)
			(xy 94.188509 -21.358103) (xy 94.190422 -21.34851) (xy 94.190566 -21.34362) (xy 94.190566 -21.274024)
			(xy 94.190427 -21.269134) (xy 94.188503 -21.259544) (xy 94.186756 -21.254974) (xy 94.183454 -21.246592)
			(xy 94.17685 -21.23948) (xy 94.157576 -21.218154) (xy 94.125006 -21.170791) (xy 94.099909 -21.119079)
			(xy 94.082855 -21.064186) (xy 94.074229 -21.007356) (xy 94.074227 -20.949876) (xy 94.082848 -20.893045)
			(xy 94.099897 -20.838151) (xy 94.12499 -20.786436) (xy 94.157556 -20.739071) (xy 94.17685 -20.717764)
			(xy 94.183454 -20.710652) (xy 94.186756 -20.70227) (xy 94.188509 -20.697703) (xy 94.190422 -20.68811)
			(xy 94.190566 -20.68322) (xy 94.190566 -20.613624) (xy 94.190427 -20.608734) (xy 94.188503 -20.599144)
			(xy 94.186756 -20.594574) (xy 94.183454 -20.586192) (xy 94.17685 -20.57908) (xy 94.157576 -20.557754)
			(xy 94.125006 -20.510391) (xy 94.099909 -20.458679) (xy 94.082855 -20.403786) (xy 94.074229 -20.346956)
			(xy 94.074227 -20.289476) (xy 94.082848 -20.232645) (xy 94.099897 -20.177751) (xy 94.12499 -20.126036)
			(xy 94.157556 -20.078671) (xy 94.17685 -20.057364) (xy 94.183454 -20.050252) (xy 94.186756 -20.04187)
			(xy 94.188509 -20.037303) (xy 94.190422 -20.02771) (xy 94.190566 -20.02282) (xy 94.190566 -19.953224)
			(xy 94.190427 -19.948334) (xy 94.188503 -19.938744) (xy 94.186756 -19.934174) (xy 94.183454 -19.925792)
			(xy 94.17685 -19.91868) (xy 94.157581 -19.897352) (xy 94.125019 -19.849988) (xy 94.09993 -19.798277)
			(xy 94.08288 -19.743387) (xy 94.074256 -19.68656) (xy 94.073726 -19.657822) (xy 94.074076 -19.634248)
			(xy 94.079885 -19.58746) (xy 94.091418 -19.541744) (xy 94.099634 -19.519646) (xy 94.099888 -19.519392)
			(xy 94.101854 -19.513574) (xy 94.103256 -19.501377) (xy 94.102682 -19.495262) (xy 94.101412 -19.483324)
			(xy 94.045024 -19.400774) (xy 94.038824 -19.393519) (xy 94.022375 -19.383871) (xy 94.01302 -19.381978)
			(xy 94.004892 -19.381216) (xy 93.979238 -19.381216) (xy 93.962728 -19.387312) (xy 93.95587 -19.3929)
			(xy 93.929573 -19.414068) (xy 93.872979 -19.450873) (xy 93.812528 -19.480926) (xy 93.749022 -19.503828)
			(xy 93.683303 -19.519274) (xy 93.616245 -19.527059) (xy 93.58249 -19.52752) (xy 91.132152 -19.52752)
			(xy 91.098378 -19.52704) (xy 91.031279 -19.519267) (xy 90.965519 -19.503829) (xy 90.90197 -19.480932)
			(xy 90.841477 -19.450878) (xy 90.78484 -19.414067) (xy 90.758518 -19.3929) (xy 90.751507 -19.387494)
			(xy 90.734855 -19.381512) (xy 90.726006 -19.381216) (xy 90.07094 -19.381216) (xy 90.070686 -19.381216)
			(xy 90.062555 -19.38155) (xy 90.047135 -19.386722) (xy 90.04046 -19.391376) (xy 90.01989 -19.407712)
			(xy 89.975114 -19.435181) (xy 89.926995 -19.45625) (xy 89.876442 -19.470521) (xy 89.824409 -19.477724)
			(xy 89.771879 -19.477724) (xy 89.719846 -19.470521) (xy 89.669293 -19.45625) (xy 89.621174 -19.435181)
			(xy 89.576398 -19.407712) (xy 89.555828 -19.391376) (xy 89.549147 -19.386729) (xy 89.533733 -19.381532)
			(xy 89.525602 -19.381216) (xy 87.182198 -19.381216) (xy 87.18169 -19.381216) (xy 87.169976 -19.381924)
			(xy 87.149064 -19.392515) (xy 87.141558 -19.401536) (xy 87.137494 -19.40814) (xy 87.095076 -19.48688)
			(xy 87.092048 -19.49304) (xy 87.089075 -19.506435) (xy 87.089234 -19.513296) (xy 87.089742 -19.527012)
			(xy 87.097616 -19.53895) (xy 87.131874 -19.59133) (xy 87.194921 -19.699465) (xy 87.251521 -19.811109)
			(xy 87.301479 -19.92588) (xy 87.344623 -20.043382) (xy 87.380805 -20.163211) (xy 87.4099 -20.284954)
			(xy 87.431809 -20.408194) (xy 87.446456 -20.532507) (xy 87.453791 -20.657464) (xy 87.454232 -20.72005)
			(xy 87.453726 -20.785786) (xy 87.445633 -20.917007) (xy 87.429476 -21.047482) (xy 87.405319 -21.176715)
			(xy 87.373251 -21.304215) (xy 87.333395 -21.429499) (xy 87.285902 -21.552093) (xy 87.230953 -21.67153)
			(xy 87.168754 -21.787357) (xy 87.099544 -21.899136) (xy 87.023583 -22.006443) (xy 86.941161 -22.108869)
			(xy 86.852589 -22.206028) (xy 86.758204 -22.297549) (xy 86.658365 -22.383087) (xy 86.553448 -22.462316)
			(xy 86.443854 -22.534936) (xy 86.329996 -22.600671) (xy 86.212308 -22.659273) (xy 86.091236 -22.710519)
			(xy 85.967238 -22.754214) (xy 85.840786 -22.790193) (xy 85.712358 -22.818319) (xy 85.582443 -22.838485)
			(xy 85.451533 -22.850616) (xy 85.320124 -22.854665) (xy 85.188715 -22.850616) (xy 85.057805 -22.838485)
			(xy 84.92789 -22.818319) (xy 84.799462 -22.790193) (xy 84.67301 -22.754214) (xy 84.549012 -22.710519)
			(xy 84.42794 -22.659273) (xy 84.310252 -22.600671) (xy 84.196394 -22.534936) (xy 84.0868 -22.462316)
			(xy 83.981883 -22.383087) (xy 83.882044 -22.297549) (xy 83.787659 -22.206028) (xy 83.699087 -22.108869)
			(xy 83.616665 -22.006443) (xy 83.540704 -21.899136) (xy 83.471494 -21.787357) (xy 83.409295 -21.67153)
			(xy 83.354346 -21.552093) (xy 83.306853 -21.429499) (xy 83.266997 -21.304215) (xy 83.234929 -21.176715)
			(xy 83.210772 -21.047482) (xy 83.194615 -20.917007) (xy 83.186522 -20.785786) (xy 83.186016 -20.72005)
			(xy 83.186475 -20.657465) (xy 83.193814 -20.532509) (xy 83.208464 -20.408199) (xy 83.230375 -20.28496)
			(xy 83.259471 -20.163218) (xy 83.295653 -20.043391) (xy 83.338795 -19.92589) (xy 83.38875 -19.811119)
			(xy 83.445346 -19.699474) (xy 83.508387 -19.591338) (xy 83.542632 -19.53895) (xy 83.542886 -19.538696)
			(xy 83.546458 -19.532861) (xy 83.550703 -19.51986) (xy 83.551268 -19.513042) (xy 83.551776 -19.499326)
			(xy 83.502754 -19.40814) (xy 83.49869 -19.401536) (xy 83.49119 -19.392503) (xy 83.470277 -19.381891)
			(xy 83.458558 -19.381216) (xy 75.140312 -19.381216) (xy 75.138026 -19.381216) (xy 75.130673 -19.381755)
			(xy 75.116733 -19.386532) (xy 75.110594 -19.390614) (xy 75.10526 -19.395186) (xy 75.054968 -19.442684)
			(xy 75.051552 -19.446069) (xy 75.045927 -19.453868) (xy 75.043792 -19.458178) (xy 75.039728 -19.466814)
			(xy 75.038966 -19.475958) (xy 75.038966 -19.47672) (xy 75.036659 -19.505427) (xy 75.024494 -19.561718)
			(xy 75.004007 -19.615541) (xy 74.975662 -19.665673) (xy 74.940105 -19.710974) (xy 74.898142 -19.750417)
			(xy 74.850727 -19.783104) (xy 74.798937 -19.808293) (xy 74.74395 -19.825412) (xy 74.687015 -19.834071)
			(xy 74.65822 -19.834606) (xy 74.631448 -19.834155) (xy 74.57843 -19.826667) (xy 74.52698 -19.811835)
			(xy 74.478112 -19.789951) (xy 74.432786 -19.761446) (xy 74.391893 -19.726881) (xy 74.356238 -19.686934)
			(xy 74.340974 -19.664934) (xy 74.334878 -19.656044) (xy 74.326496 -19.650456) (xy 74.321931 -19.647663)
			(xy 74.311945 -19.643819) (xy 74.306684 -19.642836) (xy 74.233278 -19.631152) (xy 74.228141 -19.630433)
			(xy 74.217777 -19.630827) (xy 74.212704 -19.631914) (xy 74.202544 -19.634454) (xy 74.194162 -19.641058)
			(xy 74.174026 -19.656152) (xy 74.130542 -19.681485) (xy 74.084108 -19.700888) (xy 74.035528 -19.714026)
			(xy 73.985644 -19.720671) (xy 73.960482 -19.721068) (xy 73.949814 -19.721068) (xy 73.94956 -19.720814)
			(xy 73.921447 -19.719519) (xy 73.866035 -19.709687) (xy 73.812669 -19.69182) (xy 73.762508 -19.666306)
			(xy 73.716639 -19.6337) (xy 73.676059 -19.594708) (xy 73.641647 -19.550177) (xy 73.614152 -19.501073)
			(xy 73.59417 -19.448463) (xy 73.58761 -19.421094) (xy 73.585832 -19.412458) (xy 73.576688 -19.39798)
			(xy 73.56983 -19.392392) (xy 73.562906 -19.387281) (xy 73.546679 -19.381577) (xy 73.53808 -19.381216)
			(xy 68.905628 -19.381216) (xy 68.8975 -19.381978) (xy 68.888145 -19.383861) (xy 68.871709 -19.393529)
			(xy 68.865496 -19.400774) (xy 68.81622 -19.47291) (xy 68.812852 -19.478093) (xy 68.808493 -19.489656)
			(xy 68.807584 -19.49577) (xy 68.806314 -19.507708) (xy 68.810886 -19.519646) (xy 68.819098 -19.541746)
			(xy 68.830632 -19.587461) (xy 68.836449 -19.634248) (xy 68.836794 -19.657822) (xy 68.836271 -19.68656)
			(xy 68.827646 -19.743386) (xy 68.810593 -19.798275) (xy 68.785499 -19.849985) (xy 68.752932 -19.897345)
			(xy 68.73367 -19.91868) (xy 68.727066 -19.925792) (xy 68.723764 -19.934174) (xy 68.722009 -19.938741)
			(xy 68.720088 -19.948333) (xy 68.719954 -19.953224) (xy 68.719954 -20.02282) (xy 68.720087 -20.027711)
			(xy 68.721998 -20.037307) (xy 68.723764 -20.04187) (xy 68.727066 -20.050252) (xy 68.73367 -20.057364)
			(xy 68.752939 -20.078691) (xy 68.785502 -20.126052) (xy 68.810591 -20.177763) (xy 68.827638 -20.232653)
			(xy 68.836258 -20.289478) (xy 68.836256 -20.346954) (xy 68.827631 -20.403779) (xy 68.810579 -20.458667)
			(xy 68.806257 -20.467574) (xy 76.287374 -20.467574) (xy 76.291445 -20.411952) (xy 76.303571 -20.357515)
			(xy 76.323494 -20.305424) (xy 76.35079 -20.256789) (xy 76.384876 -20.212646) (xy 76.425025 -20.173937)
			(xy 76.470383 -20.141486) (xy 76.519983 -20.115985) (xy 76.572767 -20.097978) (xy 76.62761 -20.087848)
			(xy 76.683344 -20.085811) (xy 76.738781 -20.091911) (xy 76.792738 -20.106017) (xy 76.844067 -20.127829)
			(xy 76.891673 -20.156883) (xy 76.934541 -20.192558) (xy 76.971758 -20.234095) (xy 77.002531 -20.280608)
			(xy 77.026203 -20.331105) (xy 77.042271 -20.384512) (xy 77.050391 -20.439688) (xy 77.0509 -20.467574)
			(xy 77.050391 -20.49546) (xy 77.042271 -20.550636) (xy 77.026203 -20.604043) (xy 77.002531 -20.65454)
			(xy 76.971758 -20.701053) (xy 76.934541 -20.74259) (xy 76.891673 -20.778265) (xy 76.844067 -20.807319)
			(xy 76.792738 -20.829131) (xy 76.738781 -20.843237) (xy 76.683344 -20.849337) (xy 76.62761 -20.8473)
			(xy 76.572767 -20.83717) (xy 76.519983 -20.819163) (xy 76.470383 -20.793662) (xy 76.425025 -20.761211)
			(xy 76.384876 -20.722502) (xy 76.35079 -20.678359) (xy 76.323494 -20.629724) (xy 76.303571 -20.577633)
			(xy 76.291445 -20.523196) (xy 76.287374 -20.467574) (xy 68.806257 -20.467574) (xy 68.785486 -20.510375)
			(xy 68.752919 -20.557734) (xy 68.73367 -20.57908) (xy 68.727066 -20.586192) (xy 68.723764 -20.594574)
			(xy 68.722009 -20.599141) (xy 68.720088 -20.608733) (xy 68.719954 -20.613624) (xy 68.719954 -20.68322)
			(xy 68.720087 -20.688111) (xy 68.721998 -20.697707) (xy 68.723764 -20.70227) (xy 68.727066 -20.710652)
			(xy 68.73367 -20.717764) (xy 68.752939 -20.739091) (xy 68.785502 -20.786452) (xy 68.810591 -20.838163)
			(xy 68.827638 -20.893053) (xy 68.836258 -20.949878) (xy 68.836256 -21.007354) (xy 68.827631 -21.064179)
			(xy 68.810579 -21.119067) (xy 68.785486 -21.170775) (xy 68.752919 -21.218134) (xy 68.73367 -21.23948)
			(xy 68.727066 -21.246592) (xy 68.723764 -21.254974) (xy 68.722009 -21.259541) (xy 68.720088 -21.269133)
			(xy 68.719954 -21.274024) (xy 68.719954 -21.34362) (xy 68.720087 -21.348511) (xy 68.721998 -21.358107)
			(xy 68.723764 -21.36267) (xy 68.727066 -21.371052) (xy 68.73367 -21.378164) (xy 68.75294 -21.399491)
			(xy 68.785503 -21.446854) (xy 68.810592 -21.498566) (xy 68.827639 -21.553457) (xy 68.836258 -21.610284)
			(xy 68.836794 -21.639022) (xy 68.836308 -21.666273) (xy 68.828552 -21.720221) (xy 68.813197 -21.772516)
			(xy 68.811755 -21.775674) (xy 77.935834 -21.775674) (xy 77.939905 -21.720052) (xy 77.952031 -21.665615)
			(xy 77.971954 -21.613524) (xy 77.99925 -21.564889) (xy 78.033336 -21.520746) (xy 78.073485 -21.482037)
			(xy 78.118843 -21.449586) (xy 78.168443 -21.424085) (xy 78.221227 -21.406078) (xy 78.27607 -21.395948)
			(xy 78.331804 -21.393911) (xy 78.387241 -21.400011) (xy 78.441198 -21.414117) (xy 78.492527 -21.435929)
			(xy 78.540133 -21.464983) (xy 78.583001 -21.500658) (xy 78.620218 -21.542195) (xy 78.650991 -21.588708)
			(xy 78.674663 -21.639205) (xy 78.690731 -21.692612) (xy 78.698851 -21.747788) (xy 78.69936 -21.775674)
			(xy 78.698851 -21.80356) (xy 78.69118 -21.855684) (xy 78.83855 -21.855684) (xy 78.842621 -21.800062)
			(xy 78.854747 -21.745625) (xy 78.87467 -21.693534) (xy 78.901966 -21.644899) (xy 78.936052 -21.600756)
			(xy 78.976201 -21.562047) (xy 79.021559 -21.529596) (xy 79.071159 -21.504095) (xy 79.123943 -21.486088)
			(xy 79.178786 -21.475958) (xy 79.23452 -21.473921) (xy 79.289957 -21.480021) (xy 79.343914 -21.494127)
			(xy 79.395243 -21.515939) (xy 79.442849 -21.544993) (xy 79.485717 -21.580668) (xy 79.522934 -21.622205)
			(xy 79.553707 -21.668718) (xy 79.577379 -21.719215) (xy 79.593447 -21.772622) (xy 79.601567 -21.827798)
			(xy 79.601918 -21.847048) (xy 80.072736 -21.847048) (xy 80.076807 -21.791426) (xy 80.088933 -21.736989)
			(xy 80.108856 -21.684898) (xy 80.136152 -21.636263) (xy 80.170238 -21.59212) (xy 80.210387 -21.553411)
			(xy 80.255745 -21.52096) (xy 80.305345 -21.495459) (xy 80.358129 -21.477452) (xy 80.412972 -21.467322)
			(xy 80.468706 -21.465285) (xy 80.524143 -21.471385) (xy 80.5781 -21.485491) (xy 80.629429 -21.507303)
			(xy 80.677035 -21.536357) (xy 80.719903 -21.572032) (xy 80.75712 -21.613569) (xy 80.787893 -21.660082)
			(xy 80.811565 -21.710579) (xy 80.827633 -21.763986) (xy 80.835753 -21.819162) (xy 80.836262 -21.847048)
			(xy 80.835753 -21.874934) (xy 80.827633 -21.93011) (xy 80.811565 -21.983517) (xy 80.787893 -22.034014)
			(xy 80.75712 -22.080527) (xy 80.719903 -22.122064) (xy 80.677035 -22.157739) (xy 80.629429 -22.186793)
			(xy 80.5781 -22.208605) (xy 80.524143 -22.222711) (xy 80.468706 -22.228811) (xy 80.412972 -22.226774)
			(xy 80.358129 -22.216644) (xy 80.305345 -22.198637) (xy 80.255745 -22.173136) (xy 80.210387 -22.140685)
			(xy 80.170238 -22.101976) (xy 80.136152 -22.057833) (xy 80.108856 -22.009198) (xy 80.088933 -21.957107)
			(xy 80.076807 -21.90267) (xy 80.072736 -21.847048) (xy 79.601918 -21.847048) (xy 79.602076 -21.855684)
			(xy 79.601567 -21.88357) (xy 79.593447 -21.938746) (xy 79.577379 -21.992153) (xy 79.553707 -22.04265)
			(xy 79.522934 -22.089163) (xy 79.485717 -22.1307) (xy 79.442849 -22.166375) (xy 79.395243 -22.195429)
			(xy 79.343914 -22.217241) (xy 79.289957 -22.231347) (xy 79.23452 -22.237447) (xy 79.178786 -22.23541)
			(xy 79.123943 -22.22528) (xy 79.071159 -22.207273) (xy 79.021559 -22.181772) (xy 78.976201 -22.149321)
			(xy 78.936052 -22.110612) (xy 78.901966 -22.066469) (xy 78.87467 -22.017834) (xy 78.854747 -21.965743)
			(xy 78.842621 -21.911306) (xy 78.83855 -21.855684) (xy 78.69118 -21.855684) (xy 78.690731 -21.858736)
			(xy 78.674663 -21.912143) (xy 78.650991 -21.96264) (xy 78.620218 -22.009153) (xy 78.583001 -22.05069)
			(xy 78.540133 -22.086365) (xy 78.492527 -22.115419) (xy 78.441198 -22.137231) (xy 78.387241 -22.151337)
			(xy 78.331804 -22.157437) (xy 78.27607 -22.1554) (xy 78.221227 -22.14527) (xy 78.168443 -22.127263)
			(xy 78.118843 -22.101762) (xy 78.073485 -22.069311) (xy 78.033336 -22.030602) (xy 77.99925 -21.986459)
			(xy 77.971954 -21.937824) (xy 77.952031 -21.885733) (xy 77.939905 -21.831296) (xy 77.935834 -21.775674)
			(xy 68.811755 -21.775674) (xy 68.790555 -21.822093) (xy 68.761089 -21.867943) (xy 68.725398 -21.909134)
			(xy 68.684207 -21.944825) (xy 68.638357 -21.974291) (xy 68.58878 -21.996933) (xy 68.536485 -22.012288)
			(xy 68.482537 -22.020044) (xy 68.428035 -22.020044) (xy 68.374087 -22.012288) (xy 68.321792 -21.996933)
			(xy 68.272215 -21.974291) (xy 68.226365 -21.944825) (xy 68.185174 -21.909134) (xy 68.149483 -21.867943)
			(xy 68.120017 -21.822093) (xy 68.097375 -21.772516) (xy 68.08202 -21.720221) (xy 68.074264 -21.666273)
			(xy 68.073778 -21.639022) (xy 68.074298 -21.610283) (xy 68.082919 -21.553455) (xy 68.09997 -21.498564)
			(xy 68.125063 -21.446852) (xy 68.157632 -21.399492) (xy 68.176902 -21.378164) (xy 68.183506 -21.371052)
			(xy 68.186808 -21.36267) (xy 68.188559 -21.358102) (xy 68.19047 -21.34851) (xy 68.190618 -21.34362)
			(xy 68.190618 -21.274024) (xy 68.190479 -21.269134) (xy 68.188557 -21.259543) (xy 68.186808 -21.254974)
			(xy 68.183506 -21.246592) (xy 68.176902 -21.23948) (xy 68.157631 -21.218153) (xy 68.125064 -21.170789)
			(xy 68.099971 -21.119076) (xy 68.082919 -21.064184) (xy 68.074294 -21.007356) (xy 68.074291 -20.949876)
			(xy 68.082911 -20.893047) (xy 68.099959 -20.838154) (xy 68.125048 -20.786439) (xy 68.15761 -20.739072)
			(xy 68.176902 -20.717764) (xy 68.183506 -20.710652) (xy 68.186808 -20.70227) (xy 68.188559 -20.697702)
			(xy 68.19047 -20.68811) (xy 68.190618 -20.68322) (xy 68.190618 -20.613624) (xy 68.190479 -20.608734)
			(xy 68.188557 -20.599143) (xy 68.186808 -20.594574) (xy 68.183506 -20.586192) (xy 68.176902 -20.57908)
			(xy 68.157631 -20.557753) (xy 68.125064 -20.510389) (xy 68.099971 -20.458676) (xy 68.082919 -20.403784)
			(xy 68.074294 -20.346956) (xy 68.074291 -20.289476) (xy 68.082911 -20.232647) (xy 68.099959 -20.177754)
			(xy 68.125048 -20.126039) (xy 68.15761 -20.078672) (xy 68.176902 -20.057364) (xy 68.183506 -20.050252)
			(xy 68.186808 -20.04187) (xy 68.188559 -20.037302) (xy 68.19047 -20.02771) (xy 68.190618 -20.02282)
			(xy 68.190618 -19.953224) (xy 68.190479 -19.948334) (xy 68.188557 -19.938743) (xy 68.186808 -19.934174)
			(xy 68.183506 -19.925792) (xy 68.176902 -19.91868) (xy 68.157631 -19.897353) (xy 68.125065 -19.849991)
			(xy 68.099972 -19.798279) (xy 68.08292 -19.743389) (xy 68.074294 -19.686561) (xy 68.073778 -19.657822)
			(xy 68.074128 -19.634248) (xy 68.079938 -19.58746) (xy 68.091472 -19.541745) (xy 68.099686 -19.519646)
			(xy 68.09994 -19.519392) (xy 68.101922 -19.513578) (xy 68.103326 -19.501377) (xy 68.102734 -19.495262)
			(xy 68.101464 -19.483324) (xy 68.045076 -19.400774) (xy 68.03888 -19.393512) (xy 68.022433 -19.383847)
			(xy 68.013072 -19.381978) (xy 68.004944 -19.381216) (xy 64.070992 -19.381216) (xy 64.070738 -19.381216)
			(xy 64.06261 -19.381557) (xy 64.047198 -19.386741) (xy 64.040512 -19.391376) (xy 64.019942 -19.407712)
			(xy 63.975166 -19.435181) (xy 63.927047 -19.45625) (xy 63.876494 -19.470521) (xy 63.824461 -19.477724)
			(xy 63.771931 -19.477724) (xy 63.719898 -19.470521) (xy 63.669345 -19.45625) (xy 63.621226 -19.435181)
			(xy 63.57645 -19.407712) (xy 63.55588 -19.391376) (xy 63.549197 -19.386736) (xy 63.533783 -19.381554)
			(xy 63.525654 -19.381216) (xy 61.181996 -19.381216) (xy 61.181488 -19.381216) (xy 61.169774 -19.381924)
			(xy 61.148863 -19.392516) (xy 61.141356 -19.401536) (xy 61.137292 -19.40814) (xy 61.094874 -19.48688)
			(xy 61.091846 -19.49304) (xy 61.088873 -19.506435) (xy 61.089032 -19.513296) (xy 61.08954 -19.527012)
			(xy 61.097414 -19.53895) (xy 61.131672 -19.59133) (xy 61.194719 -19.699465) (xy 61.251319 -19.811109)
			(xy 61.301277 -19.92588) (xy 61.344421 -20.043382) (xy 61.380603 -20.163211) (xy 61.409699 -20.284954)
			(xy 61.431608 -20.408194) (xy 61.446255 -20.532507) (xy 61.453589 -20.657464) (xy 61.45403 -20.72005)
			(xy 61.453524 -20.785786) (xy 61.445431 -20.917007) (xy 61.429274 -21.047482) (xy 61.405117 -21.176715)
			(xy 61.373049 -21.304215) (xy 61.333193 -21.429499) (xy 61.2857 -21.552093) (xy 61.230751 -21.67153)
			(xy 61.168552 -21.787357) (xy 61.099342 -21.899136) (xy 61.023381 -22.006443) (xy 60.940959 -22.108869)
			(xy 60.852387 -22.206028) (xy 60.758002 -22.297549) (xy 60.658163 -22.383087) (xy 60.553246 -22.462316)
			(xy 60.443652 -22.534936) (xy 60.408113 -22.555454) (xy 77.336394 -22.555454) (xy 77.340465 -22.499832)
			(xy 77.352591 -22.445395) (xy 77.372514 -22.393304) (xy 77.39981 -22.344669) (xy 77.433896 -22.300526)
			(xy 77.474045 -22.261817) (xy 77.519403 -22.229366) (xy 77.569003 -22.203865) (xy 77.621787 -22.185858)
			(xy 77.67663 -22.175728) (xy 77.732364 -22.173691) (xy 77.787801 -22.179791) (xy 77.841758 -22.193897)
			(xy 77.893087 -22.215709) (xy 77.940693 -22.244763) (xy 77.983561 -22.280438) (xy 78.020778 -22.321975)
			(xy 78.051551 -22.368488) (xy 78.075223 -22.418985) (xy 78.091291 -22.472392) (xy 78.099411 -22.527568)
			(xy 78.09992 -22.555454) (xy 78.099411 -22.58334) (xy 78.091291 -22.638516) (xy 78.075223 -22.691923)
			(xy 78.051551 -22.74242) (xy 78.020778 -22.788933) (xy 77.983561 -22.83047) (xy 77.940693 -22.866145)
			(xy 77.893087 -22.895199) (xy 77.841758 -22.917011) (xy 77.787801 -22.931117) (xy 77.732364 -22.937217)
			(xy 77.67663 -22.93518) (xy 77.621787 -22.92505) (xy 77.569003 -22.907043) (xy 77.519403 -22.881542)
			(xy 77.474045 -22.849091) (xy 77.433896 -22.810382) (xy 77.39981 -22.766239) (xy 77.372514 -22.717604)
			(xy 77.352591 -22.665513) (xy 77.340465 -22.611076) (xy 77.336394 -22.555454) (xy 60.408113 -22.555454)
			(xy 60.329794 -22.600671) (xy 60.212106 -22.659273) (xy 60.091034 -22.710519) (xy 59.967036 -22.754214)
			(xy 59.840584 -22.790193) (xy 59.712156 -22.818319) (xy 59.582241 -22.838485) (xy 59.451331 -22.850616)
			(xy 59.319922 -22.854665) (xy 59.188513 -22.850616) (xy 59.057603 -22.838485) (xy 58.927688 -22.818319)
			(xy 58.79926 -22.790193) (xy 58.672808 -22.754214) (xy 58.54881 -22.710519) (xy 58.427738 -22.659273)
			(xy 58.31005 -22.600671) (xy 58.196192 -22.534936) (xy 58.086598 -22.462316) (xy 57.981681 -22.383087)
			(xy 57.881842 -22.297549) (xy 57.787457 -22.206028) (xy 57.698885 -22.108869) (xy 57.616463 -22.006443)
			(xy 57.540502 -21.899136) (xy 57.471292 -21.787357) (xy 57.409093 -21.67153) (xy 57.354144 -21.552093)
			(xy 57.306651 -21.429499) (xy 57.266795 -21.304215) (xy 57.234727 -21.176715) (xy 57.21057 -21.047482)
			(xy 57.194413 -20.917007) (xy 57.18632 -20.785786) (xy 57.185814 -20.72005) (xy 57.186273 -20.657465)
			(xy 57.193612 -20.532509) (xy 57.208262 -20.408199) (xy 57.230173 -20.28496) (xy 57.259269 -20.163218)
			(xy 57.295451 -20.043391) (xy 57.338593 -19.92589) (xy 57.388548 -19.811119) (xy 57.445143 -19.699474)
			(xy 57.508185 -19.591337) (xy 57.54243 -19.53895) (xy 57.542684 -19.538696) (xy 57.546256 -19.532861)
			(xy 57.550501 -19.51986) (xy 57.551066 -19.513042) (xy 57.551574 -19.499326) (xy 57.502552 -19.40814)
			(xy 57.498488 -19.401536) (xy 57.490988 -19.392503) (xy 57.470075 -19.381892) (xy 57.458356 -19.381216)
			(xy 49.140364 -19.381216) (xy 49.138078 -19.381216) (xy 49.130728 -19.381762) (xy 49.116796 -19.38655)
			(xy 49.110646 -19.390614) (xy 49.105312 -19.395186) (xy 49.05502 -19.442684) (xy 49.051601 -19.446067)
			(xy 49.045971 -19.453864) (xy 49.043844 -19.458178) (xy 49.03978 -19.466814) (xy 49.039018 -19.475958)
			(xy 49.039018 -19.47672) (xy 49.036711 -19.505429) (xy 49.024547 -19.561723) (xy 49.00406 -19.615549)
			(xy 48.975717 -19.665685) (xy 48.94016 -19.710991) (xy 48.898198 -19.750439) (xy 48.850783 -19.783132)
			(xy 48.798994 -19.808327) (xy 48.744006 -19.825453) (xy 48.687068 -19.834119) (xy 48.658272 -19.834606)
			(xy 48.631498 -19.834158) (xy 48.578476 -19.826676) (xy 48.527021 -19.81185) (xy 48.478148 -19.78997)
			(xy 48.432816 -19.761468) (xy 48.391917 -19.726904) (xy 48.356257 -19.686958) (xy 48.341026 -19.664934)
			(xy 48.33493 -19.656044) (xy 48.326548 -19.650456) (xy 48.321981 -19.647667) (xy 48.311994 -19.643833)
			(xy 48.306736 -19.642836) (xy 48.23333 -19.631152) (xy 48.228192 -19.630428) (xy 48.217826 -19.630811)
			(xy 48.212756 -19.631914) (xy 48.202596 -19.634454) (xy 48.194214 -19.641058) (xy 48.174077 -19.65615)
			(xy 48.130592 -19.681477) (xy 48.084158 -19.700874) (xy 48.035578 -19.714006) (xy 47.985695 -19.720645)
			(xy 47.960534 -19.721068) (xy 47.949866 -19.721068) (xy 47.949612 -19.720814) (xy 47.921496 -19.719523)
			(xy 47.866079 -19.709697) (xy 47.812707 -19.691834) (xy 47.762539 -19.666324) (xy 47.716664 -19.633719)
			(xy 47.676078 -19.594727) (xy 47.641661 -19.550195) (xy 47.614161 -19.501089) (xy 47.594175 -19.448475)
			(xy 47.587662 -19.421094) (xy 47.585884 -19.412458) (xy 47.57674 -19.39798) (xy 47.569882 -19.392392)
			(xy 47.56296 -19.387273) (xy 47.546734 -19.381553) (xy 47.538132 -19.381216) (xy 42.90568 -19.381216)
			(xy 42.897552 -19.381978) (xy 42.888192 -19.383853) (xy 42.871742 -19.393511) (xy 42.865548 -19.400774)
			(xy 42.816272 -19.47291) (xy 42.812906 -19.478094) (xy 42.808552 -19.489657) (xy 42.807636 -19.49577)
			(xy 42.806366 -19.507708) (xy 42.810938 -19.519646) (xy 42.819151 -19.541746) (xy 42.830687 -19.587461)
			(xy 42.836504 -19.634248) (xy 42.836846 -19.657822) (xy 42.836323 -19.68656) (xy 42.827697 -19.743385)
			(xy 42.810642 -19.798273) (xy 42.785546 -19.849981) (xy 42.752976 -19.897338) (xy 42.733722 -19.91868)
			(xy 42.727118 -19.925792) (xy 42.723816 -19.934174) (xy 42.722059 -19.938741) (xy 42.720136 -19.948333)
			(xy 42.720006 -19.953224) (xy 42.720006 -20.02282) (xy 42.72014 -20.027711) (xy 42.722052 -20.037306)
			(xy 42.723816 -20.04187) (xy 42.727118 -20.050252) (xy 42.733722 -20.057364) (xy 42.752989 -20.078692)
			(xy 42.785547 -20.126055) (xy 42.810633 -20.177766) (xy 42.827677 -20.232654) (xy 42.836296 -20.289479)
			(xy 42.836294 -20.346953) (xy 42.82767 -20.403777) (xy 42.810621 -20.458664) (xy 42.806298 -20.467574)
			(xy 50.287426 -20.467574) (xy 50.291497 -20.411952) (xy 50.303623 -20.357515) (xy 50.323546 -20.305424)
			(xy 50.350842 -20.256789) (xy 50.384928 -20.212646) (xy 50.425077 -20.173937) (xy 50.470435 -20.141486)
			(xy 50.520035 -20.115985) (xy 50.572819 -20.097978) (xy 50.627662 -20.087848) (xy 50.683396 -20.085811)
			(xy 50.738833 -20.091911) (xy 50.79279 -20.106017) (xy 50.844119 -20.127829) (xy 50.891725 -20.156883)
			(xy 50.934593 -20.192558) (xy 50.97181 -20.234095) (xy 51.002583 -20.280608) (xy 51.026255 -20.331105)
			(xy 51.042323 -20.384512) (xy 51.050443 -20.439688) (xy 51.050952 -20.467574) (xy 51.050443 -20.49546)
			(xy 51.042323 -20.550636) (xy 51.026255 -20.604043) (xy 51.002583 -20.65454) (xy 50.97181 -20.701053)
			(xy 50.934593 -20.74259) (xy 50.891725 -20.778265) (xy 50.844119 -20.807319) (xy 50.79279 -20.829131)
			(xy 50.738833 -20.843237) (xy 50.683396 -20.849337) (xy 50.627662 -20.8473) (xy 50.572819 -20.83717)
			(xy 50.520035 -20.819163) (xy 50.470435 -20.793662) (xy 50.425077 -20.761211) (xy 50.384928 -20.722502)
			(xy 50.350842 -20.678359) (xy 50.323546 -20.629724) (xy 50.303623 -20.577633) (xy 50.291497 -20.523196)
			(xy 50.287426 -20.467574) (xy 42.806298 -20.467574) (xy 42.785531 -20.510373) (xy 42.752969 -20.557733)
			(xy 42.733722 -20.57908) (xy 42.727118 -20.586192) (xy 42.723816 -20.594574) (xy 42.722059 -20.599141)
			(xy 42.720136 -20.608733) (xy 42.720006 -20.613624) (xy 42.720006 -20.68322) (xy 42.72014 -20.688111)
			(xy 42.722052 -20.697706) (xy 42.723816 -20.70227) (xy 42.727118 -20.710652) (xy 42.733722 -20.717764)
			(xy 42.752989 -20.739092) (xy 42.785547 -20.786455) (xy 42.810633 -20.838166) (xy 42.827677 -20.893054)
			(xy 42.836296 -20.949879) (xy 42.836294 -21.007353) (xy 42.82767 -21.064177) (xy 42.810621 -21.119064)
			(xy 42.785531 -21.170773) (xy 42.752969 -21.218133) (xy 42.733722 -21.23948) (xy 42.727118 -21.246592)
			(xy 42.723816 -21.254974) (xy 42.722059 -21.259541) (xy 42.720136 -21.269133) (xy 42.720006 -21.274024)
			(xy 42.720006 -21.34362) (xy 42.72014 -21.348511) (xy 42.722052 -21.358106) (xy 42.723816 -21.36267)
			(xy 42.727118 -21.371052) (xy 42.733722 -21.378164) (xy 42.752989 -21.399492) (xy 42.785548 -21.446856)
			(xy 42.810634 -21.498569) (xy 42.827678 -21.553459) (xy 42.836297 -21.610284) (xy 42.836846 -21.639022)
			(xy 42.83636 -21.666273) (xy 42.828604 -21.720221) (xy 42.813249 -21.772516) (xy 42.811807 -21.775674)
			(xy 51.935886 -21.775674) (xy 51.939957 -21.720052) (xy 51.952083 -21.665615) (xy 51.972006 -21.613524)
			(xy 51.999302 -21.564889) (xy 52.033388 -21.520746) (xy 52.073537 -21.482037) (xy 52.118895 -21.449586)
			(xy 52.168495 -21.424085) (xy 52.221279 -21.406078) (xy 52.276122 -21.395948) (xy 52.331856 -21.393911)
			(xy 52.387293 -21.400011) (xy 52.44125 -21.414117) (xy 52.492579 -21.435929) (xy 52.540185 -21.464983)
			(xy 52.583053 -21.500658) (xy 52.62027 -21.542195) (xy 52.651043 -21.588708) (xy 52.674715 -21.639205)
			(xy 52.690783 -21.692612) (xy 52.698903 -21.747788) (xy 52.699412 -21.775674) (xy 52.698903 -21.80356)
			(xy 52.691232 -21.855684) (xy 52.838602 -21.855684) (xy 52.842673 -21.800062) (xy 52.854799 -21.745625)
			(xy 52.874722 -21.693534) (xy 52.902018 -21.644899) (xy 52.936104 -21.600756) (xy 52.976253 -21.562047)
			(xy 53.021611 -21.529596) (xy 53.071211 -21.504095) (xy 53.123995 -21.486088) (xy 53.178838 -21.475958)
			(xy 53.234572 -21.473921) (xy 53.290009 -21.480021) (xy 53.343966 -21.494127) (xy 53.395295 -21.515939)
			(xy 53.442901 -21.544993) (xy 53.485769 -21.580668) (xy 53.522986 -21.622205) (xy 53.553759 -21.668718)
			(xy 53.577431 -21.719215) (xy 53.593499 -21.772622) (xy 53.601619 -21.827798) (xy 53.60197 -21.847048)
			(xy 54.072788 -21.847048) (xy 54.076859 -21.791426) (xy 54.088985 -21.736989) (xy 54.108908 -21.684898)
			(xy 54.136204 -21.636263) (xy 54.17029 -21.59212) (xy 54.210439 -21.553411) (xy 54.255797 -21.52096)
			(xy 54.305397 -21.495459) (xy 54.358181 -21.477452) (xy 54.413024 -21.467322) (xy 54.468758 -21.465285)
			(xy 54.524195 -21.471385) (xy 54.578152 -21.485491) (xy 54.629481 -21.507303) (xy 54.677087 -21.536357)
			(xy 54.719955 -21.572032) (xy 54.757172 -21.613569) (xy 54.787945 -21.660082) (xy 54.811617 -21.710579)
			(xy 54.827685 -21.763986) (xy 54.835805 -21.819162) (xy 54.836314 -21.847048) (xy 54.835805 -21.874934)
			(xy 54.827685 -21.93011) (xy 54.811617 -21.983517) (xy 54.787945 -22.034014) (xy 54.757172 -22.080527)
			(xy 54.719955 -22.122064) (xy 54.677087 -22.157739) (xy 54.629481 -22.186793) (xy 54.578152 -22.208605)
			(xy 54.524195 -22.222711) (xy 54.468758 -22.228811) (xy 54.413024 -22.226774) (xy 54.358181 -22.216644)
			(xy 54.305397 -22.198637) (xy 54.255797 -22.173136) (xy 54.210439 -22.140685) (xy 54.17029 -22.101976)
			(xy 54.136204 -22.057833) (xy 54.108908 -22.009198) (xy 54.088985 -21.957107) (xy 54.076859 -21.90267)
			(xy 54.072788 -21.847048) (xy 53.60197 -21.847048) (xy 53.602128 -21.855684) (xy 53.601619 -21.88357)
			(xy 53.593499 -21.938746) (xy 53.577431 -21.992153) (xy 53.553759 -22.04265) (xy 53.522986 -22.089163)
			(xy 53.485769 -22.1307) (xy 53.442901 -22.166375) (xy 53.395295 -22.195429) (xy 53.343966 -22.217241)
			(xy 53.290009 -22.231347) (xy 53.234572 -22.237447) (xy 53.178838 -22.23541) (xy 53.123995 -22.22528)
			(xy 53.071211 -22.207273) (xy 53.021611 -22.181772) (xy 52.976253 -22.149321) (xy 52.936104 -22.110612)
			(xy 52.902018 -22.066469) (xy 52.874722 -22.017834) (xy 52.854799 -21.965743) (xy 52.842673 -21.911306)
			(xy 52.838602 -21.855684) (xy 52.691232 -21.855684) (xy 52.690783 -21.858736) (xy 52.674715 -21.912143)
			(xy 52.651043 -21.96264) (xy 52.62027 -22.009153) (xy 52.583053 -22.05069) (xy 52.540185 -22.086365)
			(xy 52.492579 -22.115419) (xy 52.44125 -22.137231) (xy 52.387293 -22.151337) (xy 52.331856 -22.157437)
			(xy 52.276122 -22.1554) (xy 52.221279 -22.14527) (xy 52.168495 -22.127263) (xy 52.118895 -22.101762)
			(xy 52.073537 -22.069311) (xy 52.033388 -22.030602) (xy 51.999302 -21.986459) (xy 51.972006 -21.937824)
			(xy 51.952083 -21.885733) (xy 51.939957 -21.831296) (xy 51.935886 -21.775674) (xy 42.811807 -21.775674)
			(xy 42.790607 -21.822093) (xy 42.761141 -21.867943) (xy 42.72545 -21.909134) (xy 42.684259 -21.944825)
			(xy 42.638409 -21.974291) (xy 42.588832 -21.996933) (xy 42.536537 -22.012288) (xy 42.482589 -22.020044)
			(xy 42.428087 -22.020044) (xy 42.374139 -22.012288) (xy 42.321844 -21.996933) (xy 42.272267 -21.974291)
			(xy 42.226417 -21.944825) (xy 42.185226 -21.909134) (xy 42.149535 -21.867943) (xy 42.120069 -21.822093)
			(xy 42.097427 -21.772516) (xy 42.082072 -21.720221) (xy 42.074316 -21.666273) (xy 42.07383 -21.639022)
			(xy 42.074349 -21.610282) (xy 42.08297 -21.553454) (xy 42.100018 -21.498561) (xy 42.12511 -21.446848)
			(xy 42.157675 -21.399484) (xy 42.176954 -21.378164) (xy 42.183558 -21.371052) (xy 42.18686 -21.36267)
			(xy 42.188613 -21.358103) (xy 42.190526 -21.34851) (xy 42.19067 -21.34362) (xy 42.19067 -21.274024)
			(xy 42.190531 -21.269134) (xy 42.188607 -21.259544) (xy 42.18686 -21.254974) (xy 42.183558 -21.246592)
			(xy 42.176954 -21.23948) (xy 42.15768 -21.218154) (xy 42.125109 -21.170792) (xy 42.100012 -21.119079)
			(xy 42.082958 -21.064186) (xy 42.074332 -21.007356) (xy 42.07433 -20.949876) (xy 42.082951 -20.893045)
			(xy 42.100001 -20.838151) (xy 42.125093 -20.786436) (xy 42.15766 -20.739071) (xy 42.176954 -20.717764)
			(xy 42.183558 -20.710652) (xy 42.18686 -20.70227) (xy 42.188613 -20.697703) (xy 42.190526 -20.68811)
			(xy 42.19067 -20.68322) (xy 42.19067 -20.613624) (xy 42.190531 -20.608734) (xy 42.188607 -20.599144)
			(xy 42.18686 -20.594574) (xy 42.183558 -20.586192) (xy 42.176954 -20.57908) (xy 42.15768 -20.557754)
			(xy 42.125109 -20.510392) (xy 42.100012 -20.458679) (xy 42.082958 -20.403786) (xy 42.074332 -20.346956)
			(xy 42.07433 -20.289476) (xy 42.082951 -20.232645) (xy 42.100001 -20.177751) (xy 42.125093 -20.126036)
			(xy 42.15766 -20.078671) (xy 42.176954 -20.057364) (xy 42.183558 -20.050252) (xy 42.18686 -20.04187)
			(xy 42.188613 -20.037303) (xy 42.190526 -20.02771) (xy 42.19067 -20.02282) (xy 42.19067 -19.953224)
			(xy 42.190531 -19.948334) (xy 42.188607 -19.938744) (xy 42.18686 -19.934174) (xy 42.183558 -19.925792)
			(xy 42.176954 -19.91868) (xy 42.157685 -19.897352) (xy 42.125123 -19.849988) (xy 42.100033 -19.798277)
			(xy 42.082983 -19.743387) (xy 42.074359 -19.68656) (xy 42.07383 -19.657822) (xy 42.07418 -19.634248)
			(xy 42.079989 -19.58746) (xy 42.091522 -19.541744) (xy 42.099738 -19.519646) (xy 42.099992 -19.519392)
			(xy 42.101958 -19.513574) (xy 42.10336 -19.501377) (xy 42.102786 -19.495262) (xy 42.101516 -19.483324)
			(xy 42.045128 -19.400774) (xy 42.038929 -19.393518) (xy 42.022479 -19.383869) (xy 42.013124 -19.381978)
			(xy 42.004996 -19.381216) (xy 38.071044 -19.381216) (xy 38.07079 -19.381216) (xy 38.062659 -19.381549)
			(xy 38.047238 -19.386721) (xy 38.040564 -19.391376) (xy 38.019994 -19.407712) (xy 37.975218 -19.435181)
			(xy 37.927099 -19.45625) (xy 37.876546 -19.470521) (xy 37.824513 -19.477724) (xy 37.771983 -19.477724)
			(xy 37.71995 -19.470521) (xy 37.669397 -19.45625) (xy 37.621278 -19.435181) (xy 37.576502 -19.407712)
			(xy 37.555932 -19.391376) (xy 37.549247 -19.386742) (xy 37.533833 -19.381575) (xy 37.525706 -19.381216)
			(xy 35.182048 -19.381216) (xy 35.18154 -19.381216) (xy 35.169821 -19.381913) (xy 35.148892 -19.392492)
			(xy 35.141408 -19.401536) (xy 35.137344 -19.40814) (xy 35.094926 -19.48688) (xy 35.091896 -19.49304)
			(xy 35.08892 -19.506434) (xy 35.089084 -19.513296) (xy 35.089592 -19.527012) (xy 35.097466 -19.53895)
			(xy 35.131723 -19.59133) (xy 35.194768 -19.699466) (xy 35.251367 -19.811111) (xy 35.301324 -19.925881)
			(xy 35.344467 -20.043383) (xy 35.380648 -20.163212) (xy 35.409743 -20.284955) (xy 35.431652 -20.408195)
			(xy 35.446298 -20.532507) (xy 35.453633 -20.657464) (xy 35.454082 -20.72005) (xy 35.453576 -20.785786)
			(xy 35.445483 -20.917007) (xy 35.429326 -21.047482) (xy 35.405169 -21.176715) (xy 35.373101 -21.304215)
			(xy 35.333245 -21.429499) (xy 35.285752 -21.552093) (xy 35.230803 -21.67153) (xy 35.168604 -21.787357)
			(xy 35.099394 -21.899136) (xy 35.023433 -22.006443) (xy 34.941011 -22.108869) (xy 34.852439 -22.206028)
			(xy 34.758054 -22.297549) (xy 34.658215 -22.383087) (xy 34.553298 -22.462316) (xy 34.443704 -22.534936)
			(xy 34.408165 -22.555454) (xy 51.336446 -22.555454) (xy 51.340517 -22.499832) (xy 51.352643 -22.445395)
			(xy 51.372566 -22.393304) (xy 51.399862 -22.344669) (xy 51.433948 -22.300526) (xy 51.474097 -22.261817)
			(xy 51.519455 -22.229366) (xy 51.569055 -22.203865) (xy 51.621839 -22.185858) (xy 51.676682 -22.175728)
			(xy 51.732416 -22.173691) (xy 51.787853 -22.179791) (xy 51.84181 -22.193897) (xy 51.893139 -22.215709)
			(xy 51.940745 -22.244763) (xy 51.983613 -22.280438) (xy 52.02083 -22.321975) (xy 52.051603 -22.368488)
			(xy 52.075275 -22.418985) (xy 52.091343 -22.472392) (xy 52.099463 -22.527568) (xy 52.099972 -22.555454)
			(xy 52.099463 -22.58334) (xy 52.091343 -22.638516) (xy 52.075275 -22.691923) (xy 52.051603 -22.74242)
			(xy 52.02083 -22.788933) (xy 51.983613 -22.83047) (xy 51.940745 -22.866145) (xy 51.893139 -22.895199)
			(xy 51.84181 -22.917011) (xy 51.787853 -22.931117) (xy 51.732416 -22.937217) (xy 51.676682 -22.93518)
			(xy 51.621839 -22.92505) (xy 51.569055 -22.907043) (xy 51.519455 -22.881542) (xy 51.474097 -22.849091)
			(xy 51.433948 -22.810382) (xy 51.399862 -22.766239) (xy 51.372566 -22.717604) (xy 51.352643 -22.665513)
			(xy 51.340517 -22.611076) (xy 51.336446 -22.555454) (xy 34.408165 -22.555454) (xy 34.329846 -22.600671)
			(xy 34.212158 -22.659273) (xy 34.091086 -22.710519) (xy 33.967088 -22.754214) (xy 33.840636 -22.790193)
			(xy 33.712208 -22.818319) (xy 33.582293 -22.838485) (xy 33.451383 -22.850616) (xy 33.319974 -22.854665)
			(xy 33.188565 -22.850616) (xy 33.057655 -22.838485) (xy 32.92774 -22.818319) (xy 32.799312 -22.790193)
			(xy 32.67286 -22.754214) (xy 32.548862 -22.710519) (xy 32.42779 -22.659273) (xy 32.310102 -22.600671)
			(xy 32.196244 -22.534936) (xy 32.08665 -22.462316) (xy 31.981733 -22.383087) (xy 31.881894 -22.297549)
			(xy 31.787509 -22.206028) (xy 31.698937 -22.108869) (xy 31.616515 -22.006443) (xy 31.540554 -21.899136)
			(xy 31.471344 -21.787357) (xy 31.409145 -21.67153) (xy 31.354196 -21.552093) (xy 31.306703 -21.429499)
			(xy 31.266847 -21.304215) (xy 31.234779 -21.176715) (xy 31.210622 -21.047482) (xy 31.194465 -20.917007)
			(xy 31.186372 -20.785786) (xy 31.185866 -20.72005) (xy 31.186325 -20.657465) (xy 31.193664 -20.532509)
			(xy 31.208315 -20.408199) (xy 31.230226 -20.284961) (xy 31.259323 -20.163219) (xy 31.295505 -20.043392)
			(xy 31.338648 -19.925892) (xy 31.388604 -19.811122) (xy 31.445201 -19.699477) (xy 31.508244 -19.591342)
			(xy 31.542482 -19.53895) (xy 31.542736 -19.538696) (xy 31.546311 -19.532862) (xy 31.55056 -19.519861)
			(xy 31.551118 -19.513042) (xy 31.551626 -19.499326) (xy 31.502604 -19.40814) (xy 31.49854 -19.401536)
			(xy 31.491037 -19.392511) (xy 31.470123 -19.38192) (xy 31.458408 -19.381216) (xy 31.077408 -19.381216)
			(xy 31.072796 -19.381315) (xy 31.063721 -19.382972) (xy 31.059374 -19.384518) (xy 31.04934 -19.388891)
			(xy 31.033946 -19.40442) (xy 31.029656 -19.41449) (xy 31.001763 -19.512511) (xy 30.939362 -19.706546)
			(xy 30.869488 -19.898018) (xy 30.792248 -20.086638) (xy 30.707757 -20.272124) (xy 30.616143 -20.454196)
			(xy 30.517542 -20.632582) (xy 30.412103 -20.807013) (xy 30.299984 -20.977227) (xy 30.181354 -21.14297)
			(xy 30.05639 -21.303991) (xy 29.925282 -21.460049) (xy 29.788224 -21.610909) (xy 29.645424 -21.756346)
			(xy 29.497096 -21.896139) (xy 29.343462 -22.030081) (xy 29.184754 -22.157968) (xy 29.021209 -22.27961)
			(xy 28.853074 -22.394824) (xy 28.6806 -22.503436) (xy 28.504048 -22.605283) (xy 28.323682 -22.700213)
			(xy 28.139773 -22.788082) (xy 27.952597 -22.868759) (xy 27.762435 -22.942123) (xy 27.569574 -23.008064)
			(xy 27.512628 -23.0251) (xy 37.362382 -23.0251) (xy 37.366453 -22.969478) (xy 37.378579 -22.915041)
			(xy 37.398502 -22.86295) (xy 37.425798 -22.814315) (xy 37.459884 -22.770172) (xy 37.500033 -22.731463)
			(xy 37.545391 -22.699012) (xy 37.594991 -22.673511) (xy 37.647775 -22.655504) (xy 37.702618 -22.645374)
			(xy 37.758352 -22.643337) (xy 37.813789 -22.649437) (xy 37.867746 -22.663543) (xy 37.919075 -22.685355)
			(xy 37.966681 -22.714409) (xy 38.009549 -22.750084) (xy 38.046766 -22.791621) (xy 38.077539 -22.838134)
			(xy 38.101211 -22.888631) (xy 38.117279 -22.942038) (xy 38.125399 -22.997214) (xy 38.125746 -23.01621)
			(xy 38.71163 -23.01621) (xy 38.715701 -22.960588) (xy 38.727827 -22.906151) (xy 38.74775 -22.85406)
			(xy 38.775046 -22.805425) (xy 38.809132 -22.761282) (xy 38.849281 -22.722573) (xy 38.894639 -22.690122)
			(xy 38.944239 -22.664621) (xy 38.997023 -22.646614) (xy 39.051866 -22.636484) (xy 39.1076 -22.634447)
			(xy 39.163037 -22.640547) (xy 39.216994 -22.654653) (xy 39.268323 -22.676465) (xy 39.315929 -22.705519)
			(xy 39.358797 -22.741194) (xy 39.396014 -22.782731) (xy 39.426787 -22.829244) (xy 39.450459 -22.879741)
			(xy 39.466527 -22.933148) (xy 39.474647 -22.988324) (xy 39.475156 -23.01621) (xy 39.474994 -23.0251)
			(xy 63.36233 -23.0251) (xy 63.366401 -22.969478) (xy 63.378527 -22.915041) (xy 63.39845 -22.86295)
			(xy 63.425746 -22.814315) (xy 63.459832 -22.770172) (xy 63.499981 -22.731463) (xy 63.545339 -22.699012)
			(xy 63.594939 -22.673511) (xy 63.647723 -22.655504) (xy 63.702566 -22.645374) (xy 63.7583 -22.643337)
			(xy 63.813737 -22.649437) (xy 63.867694 -22.663543) (xy 63.919023 -22.685355) (xy 63.966629 -22.714409)
			(xy 64.009497 -22.750084) (xy 64.046714 -22.791621) (xy 64.077487 -22.838134) (xy 64.101159 -22.888631)
			(xy 64.117227 -22.942038) (xy 64.125347 -22.997214) (xy 64.125694 -23.01621) (xy 64.711578 -23.01621)
			(xy 64.715649 -22.960588) (xy 64.727775 -22.906151) (xy 64.747698 -22.85406) (xy 64.774994 -22.805425)
			(xy 64.80908 -22.761282) (xy 64.849229 -22.722573) (xy 64.894587 -22.690122) (xy 64.944187 -22.664621)
			(xy 64.996971 -22.646614) (xy 65.051814 -22.636484) (xy 65.107548 -22.634447) (xy 65.162985 -22.640547)
			(xy 65.216942 -22.654653) (xy 65.268271 -22.676465) (xy 65.315877 -22.705519) (xy 65.358745 -22.741194)
			(xy 65.395962 -22.782731) (xy 65.426735 -22.829244) (xy 65.450407 -22.879741) (xy 65.466475 -22.933148)
			(xy 65.474595 -22.988324) (xy 65.475104 -23.01621) (xy 65.474942 -23.0251) (xy 89.362278 -23.0251)
			(xy 89.366349 -22.969478) (xy 89.378475 -22.915041) (xy 89.398398 -22.86295) (xy 89.425694 -22.814315)
			(xy 89.45978 -22.770172) (xy 89.499929 -22.731463) (xy 89.545287 -22.699012) (xy 89.594887 -22.673511)
			(xy 89.647671 -22.655504) (xy 89.702514 -22.645374) (xy 89.758248 -22.643337) (xy 89.813685 -22.649437)
			(xy 89.867642 -22.663543) (xy 89.918971 -22.685355) (xy 89.966577 -22.714409) (xy 90.009445 -22.750084)
			(xy 90.046662 -22.791621) (xy 90.077435 -22.838134) (xy 90.101107 -22.888631) (xy 90.117175 -22.942038)
			(xy 90.125295 -22.997214) (xy 90.125642 -23.01621) (xy 90.711526 -23.01621) (xy 90.715597 -22.960588)
			(xy 90.727723 -22.906151) (xy 90.747646 -22.85406) (xy 90.774942 -22.805425) (xy 90.809028 -22.761282)
			(xy 90.849177 -22.722573) (xy 90.894535 -22.690122) (xy 90.944135 -22.664621) (xy 90.996919 -22.646614)
			(xy 91.051762 -22.636484) (xy 91.107496 -22.634447) (xy 91.162933 -22.640547) (xy 91.21689 -22.654653)
			(xy 91.268219 -22.676465) (xy 91.315825 -22.705519) (xy 91.358693 -22.741194) (xy 91.39591 -22.782731)
			(xy 91.426683 -22.829244) (xy 91.450355 -22.879741) (xy 91.466423 -22.933148) (xy 91.474543 -22.988324)
			(xy 91.475052 -23.01621) (xy 91.474543 -23.044096) (xy 91.466423 -23.099272) (xy 91.450355 -23.152679)
			(xy 91.426683 -23.203176) (xy 91.39591 -23.249689) (xy 91.358693 -23.291226) (xy 91.315825 -23.326901)
			(xy 91.268219 -23.355955) (xy 91.21689 -23.377767) (xy 91.162933 -23.391873) (xy 91.107496 -23.397973)
			(xy 91.051762 -23.395936) (xy 90.996919 -23.385806) (xy 90.944135 -23.367799) (xy 90.894535 -23.342298)
			(xy 90.849177 -23.309847) (xy 90.809028 -23.271138) (xy 90.774942 -23.226995) (xy 90.747646 -23.17836)
			(xy 90.727723 -23.126269) (xy 90.715597 -23.071832) (xy 90.711526 -23.01621) (xy 90.125642 -23.01621)
			(xy 90.125804 -23.0251) (xy 90.125295 -23.052986) (xy 90.117175 -23.108162) (xy 90.101107 -23.161569)
			(xy 90.077435 -23.212066) (xy 90.046662 -23.258579) (xy 90.009445 -23.300116) (xy 89.966577 -23.335791)
			(xy 89.918971 -23.364845) (xy 89.867642 -23.386657) (xy 89.813685 -23.400763) (xy 89.758248 -23.406863)
			(xy 89.702514 -23.404826) (xy 89.647671 -23.394696) (xy 89.594887 -23.376689) (xy 89.545287 -23.351188)
			(xy 89.499929 -23.318737) (xy 89.45978 -23.280028) (xy 89.425694 -23.235885) (xy 89.398398 -23.18725)
			(xy 89.378475 -23.135159) (xy 89.366349 -23.080722) (xy 89.362278 -23.0251) (xy 65.474942 -23.0251)
			(xy 65.474595 -23.044096) (xy 65.466475 -23.099272) (xy 65.450407 -23.152679) (xy 65.426735 -23.203176)
			(xy 65.395962 -23.249689) (xy 65.358745 -23.291226) (xy 65.315877 -23.326901) (xy 65.268271 -23.355955)
			(xy 65.216942 -23.377767) (xy 65.162985 -23.391873) (xy 65.107548 -23.397973) (xy 65.051814 -23.395936)
			(xy 64.996971 -23.385806) (xy 64.944187 -23.367799) (xy 64.894587 -23.342298) (xy 64.849229 -23.309847)
			(xy 64.80908 -23.271138) (xy 64.774994 -23.226995) (xy 64.747698 -23.17836) (xy 64.727775 -23.126269)
			(xy 64.715649 -23.071832) (xy 64.711578 -23.01621) (xy 64.125694 -23.01621) (xy 64.125856 -23.0251)
			(xy 64.125347 -23.052986) (xy 64.117227 -23.108162) (xy 64.101159 -23.161569) (xy 64.077487 -23.212066)
			(xy 64.046714 -23.258579) (xy 64.009497 -23.300116) (xy 63.966629 -23.335791) (xy 63.919023 -23.364845)
			(xy 63.867694 -23.386657) (xy 63.813737 -23.400763) (xy 63.7583 -23.406863) (xy 63.702566 -23.404826)
			(xy 63.647723 -23.394696) (xy 63.594939 -23.376689) (xy 63.545339 -23.351188) (xy 63.499981 -23.318737)
			(xy 63.459832 -23.280028) (xy 63.425746 -23.235885) (xy 63.39845 -23.18725) (xy 63.378527 -23.135159)
			(xy 63.366401 -23.080722) (xy 63.36233 -23.0251) (xy 39.474994 -23.0251) (xy 39.474647 -23.044096)
			(xy 39.466527 -23.099272) (xy 39.450459 -23.152679) (xy 39.426787 -23.203176) (xy 39.396014 -23.249689)
			(xy 39.358797 -23.291226) (xy 39.315929 -23.326901) (xy 39.268323 -23.355955) (xy 39.216994 -23.377767)
			(xy 39.163037 -23.391873) (xy 39.1076 -23.397973) (xy 39.051866 -23.395936) (xy 38.997023 -23.385806)
			(xy 38.944239 -23.367799) (xy 38.894639 -23.342298) (xy 38.849281 -23.309847) (xy 38.809132 -23.271138)
			(xy 38.775046 -23.226995) (xy 38.74775 -23.17836) (xy 38.727827 -23.126269) (xy 38.715701 -23.071832)
			(xy 38.71163 -23.01621) (xy 38.125746 -23.01621) (xy 38.125908 -23.0251) (xy 38.125399 -23.052986)
			(xy 38.117279 -23.108162) (xy 38.101211 -23.161569) (xy 38.077539 -23.212066) (xy 38.046766 -23.258579)
			(xy 38.009549 -23.300116) (xy 37.966681 -23.335791) (xy 37.919075 -23.364845) (xy 37.867746 -23.386657)
			(xy 37.813789 -23.400763) (xy 37.758352 -23.406863) (xy 37.702618 -23.404826) (xy 37.647775 -23.394696)
			(xy 37.594991 -23.376689) (xy 37.545391 -23.351188) (xy 37.500033 -23.318737) (xy 37.459884 -23.280028)
			(xy 37.425798 -23.235885) (xy 37.398502 -23.18725) (xy 37.378579 -23.135159) (xy 37.366453 -23.080722)
			(xy 37.362382 -23.0251) (xy 27.512628 -23.0251) (xy 27.374303 -23.066481) (xy 27.176914 -23.117288)
			(xy 26.977705 -23.160409) (xy 26.776975 -23.195778) (xy 26.575025 -23.223343) (xy 26.372158 -23.243061)
			(xy 26.16868 -23.254905) (xy 25.964896 -23.258854) (xy 25.761112 -23.254905) (xy 25.557634 -23.243061)
			(xy 25.354767 -23.223343) (xy 25.152817 -23.195778) (xy 24.952087 -23.160409) (xy 24.752878 -23.117288)
			(xy 24.555489 -23.066481) (xy 24.360218 -23.008064) (xy 24.167357 -22.942123) (xy 23.977195 -22.868759)
			(xy 23.790019 -22.788082) (xy 23.60611 -22.700213) (xy 23.425744 -22.605283) (xy 23.249192 -22.503436)
			(xy 23.076718 -22.394824) (xy 22.908583 -22.27961) (xy 22.745038 -22.157968) (xy 22.58633 -22.030081)
			(xy 22.432696 -21.896139) (xy 22.284368 -21.756346) (xy 22.141568 -21.610909) (xy 22.00451 -21.460049)
			(xy 21.873402 -21.303991) (xy 21.748438 -21.14297) (xy 21.629808 -20.977227) (xy 21.517689 -20.807013)
			(xy 21.41225 -20.632582) (xy 21.313649 -20.454196) (xy 21.222035 -20.272124) (xy 21.137544 -20.086638)
			(xy 21.060304 -19.898018) (xy 20.99043 -19.706546) (xy 20.928029 -19.512511) (xy 20.900136 -19.41449)
			(xy 20.895883 -19.404395) (xy 20.880477 -19.388855) (xy 20.870418 -19.384518) (xy 20.866071 -19.382973)
			(xy 20.856997 -19.381308) (xy 20.852384 -19.381216) (xy 16.905732 -19.381216) (xy 16.897604 -19.381978)
			(xy 16.888248 -19.38386) (xy 16.871811 -19.393528) (xy 16.8656 -19.400774) (xy 16.816324 -19.47291)
			(xy 16.812955 -19.478093) (xy 16.808597 -19.489655) (xy 16.807688 -19.49577) (xy 16.806418 -19.507708)
			(xy 16.81099 -19.519646) (xy 16.819202 -19.541746) (xy 16.830736 -19.587461) (xy 16.836552 -19.634248)
			(xy 16.836898 -19.657822) (xy 16.836375 -19.68656) (xy 16.82775 -19.743387) (xy 16.810697 -19.798276)
			(xy 16.785603 -19.849985) (xy 16.753036 -19.897346) (xy 16.733774 -19.91868) (xy 16.72717 -19.925792)
			(xy 16.723868 -19.934174) (xy 16.722113 -19.938741) (xy 16.720192 -19.948333) (xy 16.720058 -19.953224)
			(xy 16.720058 -20.02282) (xy 16.720191 -20.027711) (xy 16.722103 -20.037307) (xy 16.723868 -20.04187)
			(xy 16.72717 -20.050252) (xy 16.733774 -20.057364) (xy 16.753043 -20.078691) (xy 16.785605 -20.126053)
			(xy 16.810694 -20.177763) (xy 16.827741 -20.232653) (xy 16.836361 -20.289478) (xy 16.836359 -20.346954)
			(xy 16.827734 -20.403779) (xy 16.810682 -20.458667) (xy 16.785589 -20.510375) (xy 16.753023 -20.557734)
			(xy 16.733774 -20.57908) (xy 16.72717 -20.586192) (xy 16.723868 -20.594574) (xy 16.722113 -20.599141)
			(xy 16.720192 -20.608733) (xy 16.720058 -20.613624) (xy 16.720058 -20.68322) (xy 16.720191 -20.688111)
			(xy 16.722103 -20.697707) (xy 16.723868 -20.70227) (xy 16.72717 -20.710652) (xy 16.733774 -20.717764)
			(xy 16.753043 -20.739091) (xy 16.785605 -20.786453) (xy 16.810694 -20.838163) (xy 16.827741 -20.893053)
			(xy 16.836361 -20.949878) (xy 16.836359 -21.007354) (xy 16.827734 -21.064179) (xy 16.810682 -21.119067)
			(xy 16.785589 -21.170775) (xy 16.753023 -21.218134) (xy 16.733774 -21.23948) (xy 16.72717 -21.246592)
			(xy 16.723868 -21.254974) (xy 16.722113 -21.259541) (xy 16.720192 -21.269133) (xy 16.720058 -21.274024)
			(xy 16.720058 -21.34362) (xy 16.720191 -21.348511) (xy 16.722103 -21.358107) (xy 16.723868 -21.36267)
			(xy 16.72717 -21.371052) (xy 16.733774 -21.378164) (xy 16.753044 -21.399491) (xy 16.785606 -21.446854)
			(xy 16.810695 -21.498566) (xy 16.827742 -21.553457) (xy 16.836361 -21.610284) (xy 16.836898 -21.639022)
			(xy 16.836412 -21.666273) (xy 16.828656 -21.720221) (xy 16.813301 -21.772516) (xy 16.790659 -21.822093)
			(xy 16.761193 -21.867943) (xy 16.725502 -21.909134) (xy 16.684311 -21.944825) (xy 16.638461 -21.974291)
			(xy 16.588884 -21.996933) (xy 16.536589 -22.012288) (xy 16.482641 -22.020044) (xy 16.428139 -22.020044)
			(xy 16.374191 -22.012288) (xy 16.321896 -21.996933) (xy 16.272319 -21.974291) (xy 16.226469 -21.944825)
			(xy 16.185278 -21.909134) (xy 16.149587 -21.867943) (xy 16.120121 -21.822093) (xy 16.097479 -21.772516)
			(xy 16.082124 -21.720221) (xy 16.074368 -21.666273) (xy 16.073882 -21.639022) (xy 16.074402 -21.610283)
			(xy 16.083023 -21.553455) (xy 16.100074 -21.498564) (xy 16.125168 -21.446853) (xy 16.157736 -21.399492)
			(xy 16.177006 -21.378164) (xy 16.18361 -21.371052) (xy 16.186912 -21.36267) (xy 16.188663 -21.358102)
			(xy 16.190574 -21.34851) (xy 16.190722 -21.34362) (xy 16.190722 -21.274024) (xy 16.190583 -21.269134)
			(xy 16.188662 -21.259543) (xy 16.186912 -21.254974) (xy 16.18361 -21.246592) (xy 16.177006 -21.23948)
			(xy 16.157734 -21.218153) (xy 16.125167 -21.170789) (xy 16.100074 -21.119077) (xy 16.083022 -21.064185)
			(xy 16.074397 -21.007356) (xy 16.074394 -20.949876) (xy 16.083014 -20.893047) (xy 16.100062 -20.838153)
			(xy 16.125151 -20.786438) (xy 16.157714 -20.739072) (xy 16.177006 -20.717764) (xy 16.18361 -20.710652)
			(xy 16.186912 -20.70227) (xy 16.188663 -20.697702) (xy 16.190574 -20.68811) (xy 16.190722 -20.68322)
			(xy 16.190722 -20.613624) (xy 16.190583 -20.608734) (xy 16.188662 -20.599143) (xy 16.186912 -20.594574)
			(xy 16.18361 -20.586192) (xy 16.177006 -20.57908) (xy 16.157734 -20.557753) (xy 16.125167 -20.510389)
			(xy 16.100074 -20.458677) (xy 16.083022 -20.403785) (xy 16.074397 -20.346956) (xy 16.074394 -20.289476)
			(xy 16.083014 -20.232647) (xy 16.100062 -20.177753) (xy 16.125151 -20.126038) (xy 16.157714 -20.078672)
			(xy 16.177006 -20.057364) (xy 16.18361 -20.050252) (xy 16.186912 -20.04187) (xy 16.188663 -20.037302)
			(xy 16.190574 -20.02771) (xy 16.190722 -20.02282) (xy 16.190722 -19.953224) (xy 16.190583 -19.948334)
			(xy 16.188662 -19.938743) (xy 16.186912 -19.934174) (xy 16.18361 -19.925792) (xy 16.177006 -19.91868)
			(xy 16.157735 -19.897353) (xy 16.125168 -19.849991) (xy 16.100075 -19.798279) (xy 16.083023 -19.743389)
			(xy 16.074397 -19.686561) (xy 16.073882 -19.657822) (xy 16.074232 -19.634248) (xy 16.080041 -19.58746)
			(xy 16.091572 -19.541744) (xy 16.09979 -19.519646) (xy 16.100044 -19.519392) (xy 16.102026 -19.513578)
			(xy 16.10343 -19.501377) (xy 16.102838 -19.495262) (xy 16.101568 -19.483324) (xy 16.04518 -19.400774)
			(xy 16.038984 -19.393511) (xy 16.022538 -19.383846) (xy 16.013176 -19.381978) (xy 16.005048 -19.381216)
			(xy 12.071096 -19.381216) (xy 12.070842 -19.381216) (xy 12.062714 -19.381557) (xy 12.047302 -19.38674)
			(xy 12.040616 -19.391376) (xy 12.020046 -19.407712) (xy 11.97527 -19.435181) (xy 11.927151 -19.45625)
			(xy 11.876598 -19.470521) (xy 11.824565 -19.477724) (xy 11.772035 -19.477724) (xy 11.720002 -19.470521)
			(xy 11.669449 -19.45625) (xy 11.62133 -19.435181) (xy 11.576554 -19.407712) (xy 11.555984 -19.391376)
			(xy 11.549301 -19.386735) (xy 11.533887 -19.381552) (xy 11.525758 -19.381216) (xy 9.1821 -19.381216)
			(xy 9.181592 -19.381216) (xy 9.169878 -19.381923) (xy 9.148965 -19.392514) (xy 9.14146 -19.401536)
			(xy 9.137396 -19.40814) (xy 9.094978 -19.48688) (xy 9.09195 -19.49304) (xy 9.088977 -19.506434) (xy 9.089136 -19.513296)
			(xy 9.089644 -19.527012) (xy 9.097518 -19.53895) (xy 9.131775 -19.59133) (xy 9.194823 -19.699465)
			(xy 9.251422 -19.81111) (xy 9.30138 -19.92588) (xy 9.344525 -20.043382) (xy 9.380707 -20.163211)
			(xy 9.409802 -20.284954) (xy 9.431711 -20.408194) (xy 9.446358 -20.532507) (xy 9.453693 -20.657464)
			(xy 9.454134 -20.72005) (xy 9.453628 -20.785786) (xy 9.445535 -20.917007) (xy 9.429378 -21.047482)
			(xy 9.405221 -21.176715) (xy 9.373153 -21.304215) (xy 9.333297 -21.429499) (xy 9.285804 -21.552093)
			(xy 9.230855 -21.67153) (xy 9.168656 -21.787357) (xy 9.099446 -21.899136) (xy 9.023485 -22.006443)
			(xy 8.941063 -22.108869) (xy 8.852491 -22.206028) (xy 8.758106 -22.297549) (xy 8.658267 -22.383087)
			(xy 8.55335 -22.462316) (xy 8.443756 -22.534936) (xy 8.329898 -22.600671) (xy 8.21221 -22.659273)
			(xy 8.091138 -22.710519) (xy 7.96714 -22.754214) (xy 7.840688 -22.790193) (xy 7.71226 -22.818319)
			(xy 7.582345 -22.838485) (xy 7.451435 -22.850616) (xy 7.320026 -22.854665) (xy 7.188617 -22.850616)
			(xy 7.057707 -22.838485) (xy 6.927792 -22.818319) (xy 6.799364 -22.790193) (xy 6.672912 -22.754214)
			(xy 6.548914 -22.710519) (xy 6.427842 -22.659273) (xy 6.310154 -22.600671) (xy 6.196296 -22.534936)
			(xy 6.086702 -22.462316) (xy 5.981785 -22.383087) (xy 5.881946 -22.297549) (xy 5.787561 -22.206028)
			(xy 5.698989 -22.108869) (xy 5.616567 -22.006443) (xy 5.540606 -21.899136) (xy 5.471396 -21.787357)
			(xy 5.409197 -21.67153) (xy 5.354248 -21.552093) (xy 5.306755 -21.429499) (xy 5.266899 -21.304215)
			(xy 5.234831 -21.176715) (xy 5.210674 -21.047482) (xy 5.194517 -20.917007) (xy 5.186424 -20.785786)
			(xy 5.185918 -20.72005) (xy 5.186376 -20.657464) (xy 5.193714 -20.532508) (xy 5.208362 -20.408197)
			(xy 5.230272 -20.284958) (xy 5.259367 -20.163215) (xy 5.295547 -20.043387) (xy 5.338688 -19.925885)
			(xy 5.388642 -19.811114) (xy 5.445237 -19.699468) (xy 5.508279 -19.591331) (xy 5.542534 -19.53895)
			(xy 5.542788 -19.538696) (xy 5.54636 -19.532861) (xy 5.550605 -19.51986) (xy 5.55117 -19.513042)
			(xy 5.551678 -19.499326) (xy 5.502656 -19.40814) (xy 5.498592 -19.401536) (xy 5.491092 -19.392503)
			(xy 5.470179 -19.38189) (xy 5.45846 -19.381216) (xy 3.948176 -19.381216) (xy 3.942166 -19.38138)
			(xy 3.930481 -19.3842) (xy 3.925062 -19.386804) (xy 3.921589 -19.388645) (xy 3.915212 -19.39324)
			(xy 3.912362 -19.395948) (xy 3.18389 -20.12442) (xy 3.179557 -20.12905) (xy 3.173122 -20.139971)
			(xy 3.17119 -20.14601) (xy 3.169412 -20.152106) (xy 3.168904 -20.164044) (xy 3.170174 -20.170648)
			(xy 3.173963 -20.189984) (xy 3.178037 -20.229178) (xy 3.178302 -20.24888) (xy 3.177816 -20.276131)
			(xy 3.17006 -20.330079) (xy 3.154705 -20.382374) (xy 3.132064 -20.431952) (xy 3.102597 -20.477802)
			(xy 3.066906 -20.518993) (xy 3.025716 -20.554685) (xy 2.979865 -20.584152) (xy 2.930288 -20.606793)
			(xy 2.877993 -20.622149) (xy 2.824045 -20.629906) (xy 2.796794 -20.630388) (xy 2.777154 -20.630135)
			(xy 2.738085 -20.626066) (xy 2.718816 -20.62226) (xy 2.718308 -20.62226) (xy 2.705862 -20.61972)
			(xy 2.693924 -20.623276) (xy 2.687894 -20.625232) (xy 2.676966 -20.631649) (xy 2.672334 -20.635976)
			(xy 2.039112 -21.269198) (xy 2.036407 -21.27205) (xy 2.031816 -21.278429) (xy 2.029968 -21.281898)
			(xy 2.027382 -21.287324) (xy 2.024549 -21.299004) (xy 2.02438 -21.305012) (xy 2.02438 -21.988526)
			(xy 2.024955 -21.999728) (xy 2.03443 -22.020031) (xy 2.042668 -22.027642) (xy 2.105406 -22.07768)
			(xy 2.109999 -22.081171) (xy 2.120384 -22.086186) (xy 2.12598 -22.087586) (xy 2.136902 -22.090126)
			(xy 2.148078 -22.087586) (xy 2.168699 -22.083276) (xy 2.210579 -22.078699) (xy 2.231644 -22.078442)
			(xy 2.258895 -22.078928) (xy 2.312842 -22.086685) (xy 2.365137 -22.102041) (xy 2.414713 -22.124682)
			(xy 2.460563 -22.154148) (xy 2.501753 -22.18984) (xy 2.537444 -22.23103) (xy 2.56691 -22.27688) (xy 2.589551 -22.326457)
			(xy 2.589817 -22.327362) (xy 2.865626 -22.327362) (xy 2.869697 -22.27174) (xy 2.881823 -22.217303)
			(xy 2.901746 -22.165212) (xy 2.929042 -22.116577) (xy 2.963128 -22.072434) (xy 3.003277 -22.033725)
			(xy 3.048635 -22.001274) (xy 3.098235 -21.975773) (xy 3.151019 -21.957766) (xy 3.205862 -21.947636)
			(xy 3.261596 -21.945599) (xy 3.317033 -21.951699) (xy 3.37099 -21.965805) (xy 3.422319 -21.987617)
			(xy 3.469925 -22.016671) (xy 3.512793 -22.052346) (xy 3.55001 -22.093883) (xy 3.580783 -22.140396)
			(xy 3.604455 -22.190893) (xy 3.620523 -22.2443) (xy 3.628643 -22.299476) (xy 3.629152 -22.327362)
			(xy 3.628643 -22.355248) (xy 3.620523 -22.410424) (xy 3.604455 -22.463831) (xy 3.580783 -22.514328)
			(xy 3.55001 -22.560841) (xy 3.512793 -22.602378) (xy 3.469925 -22.638053) (xy 3.422319 -22.667107)
			(xy 3.37099 -22.688919) (xy 3.317033 -22.703025) (xy 3.261596 -22.709125) (xy 3.205862 -22.707088)
			(xy 3.151019 -22.696958) (xy 3.098235 -22.678951) (xy 3.048635 -22.65345) (xy 3.003277 -22.620999)
			(xy 2.963128 -22.58229) (xy 2.929042 -22.538147) (xy 2.901746 -22.489512) (xy 2.881823 -22.437421)
			(xy 2.869697 -22.382984) (xy 2.865626 -22.327362) (xy 2.589817 -22.327362) (xy 2.604906 -22.378752)
			(xy 2.612662 -22.432699) (xy 2.612662 -22.487201) (xy 2.604906 -22.541148) (xy 2.589551 -22.593443)
			(xy 2.56691 -22.64302) (xy 2.537444 -22.68887) (xy 2.501753 -22.73006) (xy 2.460563 -22.765752) (xy 2.414713 -22.795218)
			(xy 2.365137 -22.817859) (xy 2.312842 -22.833215) (xy 2.258895 -22.840972) (xy 2.231644 -22.841458)
			(xy 2.21058 -22.841192) (xy 2.168702 -22.836608) (xy 2.148078 -22.832314) (xy 2.136902 -22.829774)
			(xy 2.12598 -22.832314) (xy 2.120393 -22.833739) (xy 2.110013 -22.838752) (xy 2.105406 -22.84222)
			(xy 2.083113 -22.86) (xy 4.189982 -22.86) (xy 4.194053 -22.804378) (xy 4.206179 -22.749941) (xy 4.226102 -22.69785)
			(xy 4.253398 -22.649215) (xy 4.287484 -22.605072) (xy 4.327633 -22.566363) (xy 4.372991 -22.533912)
			(xy 4.422591 -22.508411) (xy 4.475375 -22.490404) (xy 4.530218 -22.480274) (xy 4.585952 -22.478237)
			(xy 4.641389 -22.484337) (xy 4.695346 -22.498443) (xy 4.746675 -22.520255) (xy 4.794281 -22.549309)
			(xy 4.837149 -22.584984) (xy 4.874366 -22.626521) (xy 4.905139 -22.673034) (xy 4.928811 -22.723531)
			(xy 4.944879 -22.776938) (xy 4.952999 -22.832114) (xy 4.953508 -22.86) (xy 4.952999 -22.887886) (xy 4.944879 -22.943062)
			(xy 4.930743 -22.990048) (xy 11.298934 -22.990048) (xy 11.303005 -22.934426) (xy 11.315131 -22.879989)
			(xy 11.335054 -22.827898) (xy 11.36235 -22.779263) (xy 11.396436 -22.73512) (xy 11.436585 -22.696411)
			(xy 11.481943 -22.66396) (xy 11.531543 -22.638459) (xy 11.584327 -22.620452) (xy 11.63917 -22.610322)
			(xy 11.694904 -22.608285) (xy 11.750341 -22.614385) (xy 11.804298 -22.628491) (xy 11.855627 -22.650303)
			(xy 11.903233 -22.679357) (xy 11.946101 -22.715032) (xy 11.983318 -22.756569) (xy 12.014091 -22.803082)
			(xy 12.037763 -22.853579) (xy 12.053831 -22.906986) (xy 12.061951 -22.962162) (xy 12.06246 -22.990048)
			(xy 12.061982 -23.01621) (xy 12.711682 -23.01621) (xy 12.715753 -22.960588) (xy 12.727879 -22.906151)
			(xy 12.747802 -22.85406) (xy 12.775098 -22.805425) (xy 12.809184 -22.761282) (xy 12.849333 -22.722573)
			(xy 12.894691 -22.690122) (xy 12.944291 -22.664621) (xy 12.997075 -22.646614) (xy 13.051918 -22.636484)
			(xy 13.107652 -22.634447) (xy 13.163089 -22.640547) (xy 13.217046 -22.654653) (xy 13.268375 -22.676465)
			(xy 13.315981 -22.705519) (xy 13.358849 -22.741194) (xy 13.396066 -22.782731) (xy 13.426839 -22.829244)
			(xy 13.450511 -22.879741) (xy 13.466579 -22.933148) (xy 13.474699 -22.988324) (xy 13.475208 -23.01621)
			(xy 13.474699 -23.044096) (xy 13.466579 -23.099272) (xy 13.450511 -23.152679) (xy 13.426839 -23.203176)
			(xy 13.396066 -23.249689) (xy 13.358849 -23.291226) (xy 13.315981 -23.326901) (xy 13.268375 -23.355955)
			(xy 13.217046 -23.377767) (xy 13.163089 -23.391873) (xy 13.107652 -23.397973) (xy 13.051918 -23.395936)
			(xy 12.997075 -23.385806) (xy 12.944291 -23.367799) (xy 12.894691 -23.342298) (xy 12.849333 -23.309847)
			(xy 12.809184 -23.271138) (xy 12.775098 -23.226995) (xy 12.747802 -23.17836) (xy 12.727879 -23.126269)
			(xy 12.715753 -23.071832) (xy 12.711682 -23.01621) (xy 12.061982 -23.01621) (xy 12.061951 -23.017934)
			(xy 12.053831 -23.07311) (xy 12.037763 -23.126517) (xy 12.014091 -23.177014) (xy 11.983318 -23.223527)
			(xy 11.946101 -23.265064) (xy 11.903233 -23.300739) (xy 11.855627 -23.329793) (xy 11.804298 -23.351605)
			(xy 11.750341 -23.365711) (xy 11.694904 -23.371811) (xy 11.63917 -23.369774) (xy 11.584327 -23.359644)
			(xy 11.531543 -23.341637) (xy 11.481943 -23.316136) (xy 11.436585 -23.283685) (xy 11.396436 -23.244976)
			(xy 11.36235 -23.200833) (xy 11.335054 -23.152198) (xy 11.315131 -23.100107) (xy 11.303005 -23.04567)
			(xy 11.298934 -22.990048) (xy 4.930743 -22.990048) (xy 4.928811 -22.996469) (xy 4.905139 -23.046966)
			(xy 4.874366 -23.093479) (xy 4.837149 -23.135016) (xy 4.794281 -23.170691) (xy 4.746675 -23.199745)
			(xy 4.695346 -23.221557) (xy 4.641389 -23.235663) (xy 4.585952 -23.241763) (xy 4.530218 -23.239726)
			(xy 4.475375 -23.229596) (xy 4.422591 -23.211589) (xy 4.372991 -23.186088) (xy 4.327633 -23.153637)
			(xy 4.287484 -23.114928) (xy 4.253398 -23.070785) (xy 4.226102 -23.02215) (xy 4.206179 -22.970059)
			(xy 4.194053 -22.915622) (xy 4.189982 -22.86) (xy 2.083113 -22.86) (xy 2.042668 -22.892258) (xy 2.034411 -22.899861)
			(xy 2.024903 -22.920163) (xy 2.02438 -22.931374) (xy 2.02438 -23.935944) (xy 2.23215 -23.935944)
			(xy 2.236221 -23.880322) (xy 2.248347 -23.825885) (xy 2.26827 -23.773794) (xy 2.295566 -23.725159)
			(xy 2.329652 -23.681016) (xy 2.369801 -23.642307) (xy 2.415159 -23.609856) (xy 2.464759 -23.584355)
			(xy 2.517543 -23.566348) (xy 2.572386 -23.556218) (xy 2.62812 -23.554181) (xy 2.683557 -23.560281)
			(xy 2.737514 -23.574387) (xy 2.788843 -23.596199) (xy 2.836449 -23.625253) (xy 2.879317 -23.660928)
			(xy 2.916534 -23.702465) (xy 2.947307 -23.748978) (xy 2.970979 -23.799475) (xy 2.987047 -23.852882)
			(xy 2.995167 -23.908058) (xy 2.995676 -23.935944) (xy 3.241038 -23.935944) (xy 3.245109 -23.880322)
			(xy 3.257235 -23.825885) (xy 3.277158 -23.773794) (xy 3.304454 -23.725159) (xy 3.33854 -23.681016)
			(xy 3.378689 -23.642307) (xy 3.424047 -23.609856) (xy 3.473647 -23.584355) (xy 3.526431 -23.566348)
			(xy 3.581274 -23.556218) (xy 3.637008 -23.554181) (xy 3.692445 -23.560281) (xy 3.746402 -23.574387)
			(xy 3.783134 -23.589996) (xy 16.084548 -23.589996) (xy 16.088619 -23.534374) (xy 16.100745 -23.479937)
			(xy 16.120668 -23.427846) (xy 16.147964 -23.379211) (xy 16.18205 -23.335068) (xy 16.222199 -23.296359)
			(xy 16.267557 -23.263908) (xy 16.317157 -23.238407) (xy 16.369941 -23.2204) (xy 16.424784 -23.21027)
			(xy 16.480518 -23.208233) (xy 16.535955 -23.214333) (xy 16.589912 -23.228439) (xy 16.641241 -23.250251)
			(xy 16.688847 -23.279305) (xy 16.731715 -23.31498) (xy 16.768932 -23.356517) (xy 16.799705 -23.40303)
			(xy 16.823377 -23.453527) (xy 16.839445 -23.506934) (xy 16.847565 -23.56211) (xy 16.848074 -23.589996)
			(xy 42.084496 -23.589996) (xy 42.088567 -23.534374) (xy 42.100693 -23.479937) (xy 42.120616 -23.427846)
			(xy 42.147912 -23.379211) (xy 42.181998 -23.335068) (xy 42.222147 -23.296359) (xy 42.267505 -23.263908)
			(xy 42.317105 -23.238407) (xy 42.369889 -23.2204) (xy 42.424732 -23.21027) (xy 42.480466 -23.208233)
			(xy 42.535903 -23.214333) (xy 42.58986 -23.228439) (xy 42.641189 -23.250251) (xy 42.688795 -23.279305)
			(xy 42.731663 -23.31498) (xy 42.76888 -23.356517) (xy 42.799653 -23.40303) (xy 42.823325 -23.453527)
			(xy 42.839393 -23.506934) (xy 42.847513 -23.56211) (xy 42.848022 -23.589996) (xy 42.847513 -23.617882)
			(xy 42.839393 -23.673058) (xy 42.823325 -23.726465) (xy 42.799653 -23.776962) (xy 42.76888 -23.823475)
			(xy 42.731663 -23.865012) (xy 42.688795 -23.900687) (xy 42.641189 -23.929741) (xy 42.58986 -23.951553)
			(xy 42.537835 -23.965154) (xy 52.077364 -23.965154) (xy 52.081435 -23.909532) (xy 52.093561 -23.855095)
			(xy 52.113484 -23.803004) (xy 52.14078 -23.754369) (xy 52.174866 -23.710226) (xy 52.215015 -23.671517)
			(xy 52.260373 -23.639066) (xy 52.309973 -23.613565) (xy 52.362757 -23.595558) (xy 52.4176 -23.585428)
			(xy 52.473334 -23.583391) (xy 52.528771 -23.589491) (xy 52.582728 -23.603597) (xy 52.634057 -23.625409)
			(xy 52.681663 -23.654463) (xy 52.724531 -23.690138) (xy 52.761748 -23.731675) (xy 52.792521 -23.778188)
			(xy 52.816193 -23.828685) (xy 52.832261 -23.882092) (xy 52.840381 -23.937268) (xy 52.840556 -23.946866)
			(xy 53.08041 -23.946866) (xy 53.084481 -23.891244) (xy 53.096607 -23.836807) (xy 53.11653 -23.784716)
			(xy 53.143826 -23.736081) (xy 53.177912 -23.691938) (xy 53.218061 -23.653229) (xy 53.263419 -23.620778)
			(xy 53.313019 -23.595277) (xy 53.365803 -23.57727) (xy 53.420646 -23.56714) (xy 53.47638 -23.565103)
			(xy 53.531817 -23.571203) (xy 53.585774 -23.585309) (xy 53.637103 -23.607121) (xy 53.684709 -23.636175)
			(xy 53.727577 -23.67185) (xy 53.764794 -23.713387) (xy 53.795567 -23.7599) (xy 53.819239 -23.810397)
			(xy 53.835307 -23.863804) (xy 53.843427 -23.91898) (xy 53.843936 -23.946866) (xy 53.843496 -23.970996)
			(xy 54.072788 -23.970996) (xy 54.076859 -23.915374) (xy 54.088985 -23.860937) (xy 54.108908 -23.808846)
			(xy 54.136204 -23.760211) (xy 54.17029 -23.716068) (xy 54.210439 -23.677359) (xy 54.255797 -23.644908)
			(xy 54.305397 -23.619407) (xy 54.358181 -23.6014) (xy 54.413024 -23.59127) (xy 54.468758 -23.589233)
			(xy 54.475692 -23.589996) (xy 68.084444 -23.589996) (xy 68.088515 -23.534374) (xy 68.100641 -23.479937)
			(xy 68.120564 -23.427846) (xy 68.14786 -23.379211) (xy 68.181946 -23.335068) (xy 68.222095 -23.296359)
			(xy 68.267453 -23.263908) (xy 68.317053 -23.238407) (xy 68.369837 -23.2204) (xy 68.42468 -23.21027)
			(xy 68.480414 -23.208233) (xy 68.535851 -23.214333) (xy 68.589808 -23.228439) (xy 68.641137 -23.250251)
			(xy 68.688743 -23.279305) (xy 68.731611 -23.31498) (xy 68.768828 -23.356517) (xy 68.799601 -23.40303)
			(xy 68.823273 -23.453527) (xy 68.839341 -23.506934) (xy 68.847461 -23.56211) (xy 68.84797 -23.589996)
			(xy 68.847461 -23.617882) (xy 68.839341 -23.673058) (xy 68.823273 -23.726465) (xy 68.799601 -23.776962)
			(xy 68.768828 -23.823475) (xy 68.731611 -23.865012) (xy 68.688743 -23.900687) (xy 68.641137 -23.929741)
			(xy 68.589808 -23.951553) (xy 68.537783 -23.965154) (xy 78.077312 -23.965154) (xy 78.081383 -23.909532)
			(xy 78.093509 -23.855095) (xy 78.113432 -23.803004) (xy 78.140728 -23.754369) (xy 78.174814 -23.710226)
			(xy 78.214963 -23.671517) (xy 78.260321 -23.639066) (xy 78.309921 -23.613565) (xy 78.362705 -23.595558)
			(xy 78.417548 -23.585428) (xy 78.473282 -23.583391) (xy 78.528719 -23.589491) (xy 78.582676 -23.603597)
			(xy 78.634005 -23.625409) (xy 78.681611 -23.654463) (xy 78.724479 -23.690138) (xy 78.761696 -23.731675)
			(xy 78.792469 -23.778188) (xy 78.816141 -23.828685) (xy 78.832209 -23.882092) (xy 78.840329 -23.937268)
			(xy 78.840504 -23.946866) (xy 79.080358 -23.946866) (xy 79.084429 -23.891244) (xy 79.096555 -23.836807)
			(xy 79.116478 -23.784716) (xy 79.143774 -23.736081) (xy 79.17786 -23.691938) (xy 79.218009 -23.653229)
			(xy 79.263367 -23.620778) (xy 79.312967 -23.595277) (xy 79.365751 -23.57727) (xy 79.420594 -23.56714)
			(xy 79.476328 -23.565103) (xy 79.531765 -23.571203) (xy 79.585722 -23.585309) (xy 79.637051 -23.607121)
			(xy 79.684657 -23.636175) (xy 79.727525 -23.67185) (xy 79.764742 -23.713387) (xy 79.795515 -23.7599)
			(xy 79.819187 -23.810397) (xy 79.835255 -23.863804) (xy 79.843375 -23.91898) (xy 79.843884 -23.946866)
			(xy 79.843444 -23.970996) (xy 80.072736 -23.970996) (xy 80.076807 -23.915374) (xy 80.088933 -23.860937)
			(xy 80.108856 -23.808846) (xy 80.136152 -23.760211) (xy 80.170238 -23.716068) (xy 80.210387 -23.677359)
			(xy 80.255745 -23.644908) (xy 80.305345 -23.619407) (xy 80.358129 -23.6014) (xy 80.412972 -23.59127)
			(xy 80.468706 -23.589233) (xy 80.47564 -23.589996) (xy 94.084392 -23.589996) (xy 94.088463 -23.534374)
			(xy 94.100589 -23.479937) (xy 94.120512 -23.427846) (xy 94.147808 -23.379211) (xy 94.181894 -23.335068)
			(xy 94.222043 -23.296359) (xy 94.267401 -23.263908) (xy 94.317001 -23.238407) (xy 94.369785 -23.2204)
			(xy 94.424628 -23.21027) (xy 94.480362 -23.208233) (xy 94.535799 -23.214333) (xy 94.589756 -23.228439)
			(xy 94.641085 -23.250251) (xy 94.688691 -23.279305) (xy 94.731559 -23.31498) (xy 94.768776 -23.356517)
			(xy 94.799549 -23.40303) (xy 94.823221 -23.453527) (xy 94.839289 -23.506934) (xy 94.847409 -23.56211)
			(xy 94.847918 -23.589996) (xy 94.847409 -23.617882) (xy 94.839289 -23.673058) (xy 94.823221 -23.726465)
			(xy 94.799549 -23.776962) (xy 94.768776 -23.823475) (xy 94.731559 -23.865012) (xy 94.688691 -23.900687)
			(xy 94.641085 -23.929741) (xy 94.589756 -23.951553) (xy 94.535799 -23.965659) (xy 94.480362 -23.971759)
			(xy 94.424628 -23.969722) (xy 94.369785 -23.959592) (xy 94.317001 -23.941585) (xy 94.267401 -23.916084)
			(xy 94.222043 -23.883633) (xy 94.181894 -23.844924) (xy 94.147808 -23.800781) (xy 94.120512 -23.752146)
			(xy 94.100589 -23.700055) (xy 94.088463 -23.645618) (xy 94.084392 -23.589996) (xy 80.47564 -23.589996)
			(xy 80.524143 -23.595333) (xy 80.5781 -23.609439) (xy 80.629429 -23.631251) (xy 80.677035 -23.660305)
			(xy 80.719903 -23.69598) (xy 80.75712 -23.737517) (xy 80.787893 -23.78403) (xy 80.811565 -23.834527)
			(xy 80.827633 -23.887934) (xy 80.835753 -23.94311) (xy 80.836262 -23.970996) (xy 80.835753 -23.998882)
			(xy 80.827633 -24.054058) (xy 80.811565 -24.107465) (xy 80.787893 -24.157962) (xy 80.78774 -24.158194)
			(xy 85.450678 -24.158194) (xy 85.454749 -24.102572) (xy 85.466875 -24.048135) (xy 85.486798 -23.996044)
			(xy 85.514094 -23.947409) (xy 85.54818 -23.903266) (xy 85.588329 -23.864557) (xy 85.633687 -23.832106)
			(xy 85.683287 -23.806605) (xy 85.736071 -23.788598) (xy 85.790914 -23.778468) (xy 85.846648 -23.776431)
			(xy 85.902085 -23.782531) (xy 85.956042 -23.796637) (xy 86.007371 -23.818449) (xy 86.054977 -23.847503)
			(xy 86.097845 -23.883178) (xy 86.135062 -23.924715) (xy 86.165835 -23.971228) (xy 86.189507 -24.021725)
			(xy 86.205575 -24.075132) (xy 86.213695 -24.130308) (xy 86.214204 -24.158194) (xy 86.213695 -24.18608)
			(xy 86.213126 -24.189944) (xy 89.298778 -24.189944) (xy 89.302849 -24.134322) (xy 89.314975 -24.079885)
			(xy 89.334898 -24.027794) (xy 89.362194 -23.979159) (xy 89.39628 -23.935016) (xy 89.436429 -23.896307)
			(xy 89.481787 -23.863856) (xy 89.531387 -23.838355) (xy 89.584171 -23.820348) (xy 89.639014 -23.810218)
			(xy 89.694748 -23.808181) (xy 89.750185 -23.814281) (xy 89.804142 -23.828387) (xy 89.855471 -23.850199)
			(xy 89.903077 -23.879253) (xy 89.945945 -23.914928) (xy 89.983162 -23.956465) (xy 90.013935 -24.002978)
			(xy 90.037607 -24.053475) (xy 90.053675 -24.106882) (xy 90.061795 -24.162058) (xy 90.062304 -24.189944)
			(xy 91.82176 -24.189944) (xy 91.825831 -24.134322) (xy 91.837957 -24.079885) (xy 91.85788 -24.027794)
			(xy 91.885176 -23.979159) (xy 91.919262 -23.935016) (xy 91.959411 -23.896307) (xy 92.004769 -23.863856)
			(xy 92.054369 -23.838355) (xy 92.107153 -23.820348) (xy 92.161996 -23.810218) (xy 92.21773 -23.808181)
			(xy 92.273167 -23.814281) (xy 92.327124 -23.828387) (xy 92.378453 -23.850199) (xy 92.426059 -23.879253)
			(xy 92.468927 -23.914928) (xy 92.506144 -23.956465) (xy 92.536917 -24.002978) (xy 92.560589 -24.053475)
			(xy 92.576657 -24.106882) (xy 92.584777 -24.162058) (xy 92.585286 -24.189944) (xy 92.584777 -24.21783)
			(xy 92.576657 -24.273006) (xy 92.560589 -24.326413) (xy 92.536917 -24.37691) (xy 92.506144 -24.423423)
			(xy 92.468927 -24.46496) (xy 92.426059 -24.500635) (xy 92.378453 -24.529689) (xy 92.327124 -24.551501)
			(xy 92.273167 -24.565607) (xy 92.21773 -24.571707) (xy 92.161996 -24.56967) (xy 92.107153 -24.55954)
			(xy 92.054369 -24.541533) (xy 92.004769 -24.516032) (xy 91.959411 -24.483581) (xy 91.919262 -24.444872)
			(xy 91.885176 -24.400729) (xy 91.85788 -24.352094) (xy 91.837957 -24.300003) (xy 91.825831 -24.245566)
			(xy 91.82176 -24.189944) (xy 90.062304 -24.189944) (xy 90.061795 -24.21783) (xy 90.053675 -24.273006)
			(xy 90.037607 -24.326413) (xy 90.013935 -24.37691) (xy 89.983162 -24.423423) (xy 89.945945 -24.46496)
			(xy 89.903077 -24.500635) (xy 89.855471 -24.529689) (xy 89.804142 -24.551501) (xy 89.750185 -24.565607)
			(xy 89.694748 -24.571707) (xy 89.639014 -24.56967) (xy 89.584171 -24.55954) (xy 89.531387 -24.541533)
			(xy 89.481787 -24.516032) (xy 89.436429 -24.483581) (xy 89.39628 -24.444872) (xy 89.362194 -24.400729)
			(xy 89.334898 -24.352094) (xy 89.314975 -24.300003) (xy 89.302849 -24.245566) (xy 89.298778 -24.189944)
			(xy 86.213126 -24.189944) (xy 86.205575 -24.241256) (xy 86.189507 -24.294663) (xy 86.165835 -24.34516)
			(xy 86.135062 -24.391673) (xy 86.097845 -24.43321) (xy 86.054977 -24.468885) (xy 86.007371 -24.497939)
			(xy 85.956042 -24.519751) (xy 85.902085 -24.533857) (xy 85.846648 -24.539957) (xy 85.790914 -24.53792)
			(xy 85.736071 -24.52779) (xy 85.683287 -24.509783) (xy 85.633687 -24.484282) (xy 85.588329 -24.451831)
			(xy 85.54818 -24.413122) (xy 85.514094 -24.368979) (xy 85.486798 -24.320344) (xy 85.466875 -24.268253)
			(xy 85.454749 -24.213816) (xy 85.450678 -24.158194) (xy 80.78774 -24.158194) (xy 80.75712 -24.204475)
			(xy 80.719903 -24.246012) (xy 80.677035 -24.281687) (xy 80.629429 -24.310741) (xy 80.5781 -24.332553)
			(xy 80.524143 -24.346659) (xy 80.468706 -24.352759) (xy 80.412972 -24.350722) (xy 80.358129 -24.340592)
			(xy 80.305345 -24.322585) (xy 80.255745 -24.297084) (xy 80.210387 -24.264633) (xy 80.170238 -24.225924)
			(xy 80.136152 -24.181781) (xy 80.108856 -24.133146) (xy 80.088933 -24.081055) (xy 80.076807 -24.026618)
			(xy 80.072736 -23.970996) (xy 79.843444 -23.970996) (xy 79.843375 -23.974752) (xy 79.835255 -24.029928)
			(xy 79.819187 -24.083335) (xy 79.795515 -24.133832) (xy 79.764742 -24.180345) (xy 79.727525 -24.221882)
			(xy 79.684657 -24.257557) (xy 79.637051 -24.286611) (xy 79.585722 -24.308423) (xy 79.531765 -24.322529)
			(xy 79.476328 -24.328629) (xy 79.420594 -24.326592) (xy 79.365751 -24.316462) (xy 79.312967 -24.298455)
			(xy 79.263367 -24.272954) (xy 79.218009 -24.240503) (xy 79.17786 -24.201794) (xy 79.143774 -24.157651)
			(xy 79.116478 -24.109016) (xy 79.096555 -24.056925) (xy 79.084429 -24.002488) (xy 79.080358 -23.946866)
			(xy 78.840504 -23.946866) (xy 78.840838 -23.965154) (xy 78.840329 -23.99304) (xy 78.832209 -24.048216)
			(xy 78.816141 -24.101623) (xy 78.792469 -24.15212) (xy 78.761696 -24.198633) (xy 78.724479 -24.24017)
			(xy 78.681611 -24.275845) (xy 78.634005 -24.304899) (xy 78.582676 -24.326711) (xy 78.528719 -24.340817)
			(xy 78.473282 -24.346917) (xy 78.417548 -24.34488) (xy 78.362705 -24.33475) (xy 78.309921 -24.316743)
			(xy 78.260321 -24.291242) (xy 78.214963 -24.258791) (xy 78.174814 -24.220082) (xy 78.140728 -24.175939)
			(xy 78.113432 -24.127304) (xy 78.093509 -24.075213) (xy 78.081383 -24.020776) (xy 78.077312 -23.965154)
			(xy 68.537783 -23.965154) (xy 68.535851 -23.965659) (xy 68.480414 -23.971759) (xy 68.42468 -23.969722)
			(xy 68.369837 -23.959592) (xy 68.317053 -23.941585) (xy 68.267453 -23.916084) (xy 68.222095 -23.883633)
			(xy 68.181946 -23.844924) (xy 68.14786 -23.800781) (xy 68.120564 -23.752146) (xy 68.100641 -23.700055)
			(xy 68.088515 -23.645618) (xy 68.084444 -23.589996) (xy 54.475692 -23.589996) (xy 54.524195 -23.595333)
			(xy 54.578152 -23.609439) (xy 54.629481 -23.631251) (xy 54.677087 -23.660305) (xy 54.719955 -23.69598)
			(xy 54.757172 -23.737517) (xy 54.787945 -23.78403) (xy 54.811617 -23.834527) (xy 54.827685 -23.887934)
			(xy 54.835805 -23.94311) (xy 54.836314 -23.970996) (xy 54.835805 -23.998882) (xy 54.827685 -24.054058)
			(xy 54.811617 -24.107465) (xy 54.787945 -24.157962) (xy 54.787792 -24.158194) (xy 59.45073 -24.158194)
			(xy 59.454801 -24.102572) (xy 59.466927 -24.048135) (xy 59.48685 -23.996044) (xy 59.514146 -23.947409)
			(xy 59.548232 -23.903266) (xy 59.588381 -23.864557) (xy 59.633739 -23.832106) (xy 59.683339 -23.806605)
			(xy 59.736123 -23.788598) (xy 59.790966 -23.778468) (xy 59.8467 -23.776431) (xy 59.902137 -23.782531)
			(xy 59.956094 -23.796637) (xy 60.007423 -23.818449) (xy 60.055029 -23.847503) (xy 60.097897 -23.883178)
			(xy 60.135114 -23.924715) (xy 60.165887 -23.971228) (xy 60.189559 -24.021725) (xy 60.205627 -24.075132)
			(xy 60.213747 -24.130308) (xy 60.214256 -24.158194) (xy 60.213747 -24.18608) (xy 60.213178 -24.189944)
			(xy 63.29883 -24.189944) (xy 63.302901 -24.134322) (xy 63.315027 -24.079885) (xy 63.33495 -24.027794)
			(xy 63.362246 -23.979159) (xy 63.396332 -23.935016) (xy 63.436481 -23.896307) (xy 63.481839 -23.863856)
			(xy 63.531439 -23.838355) (xy 63.584223 -23.820348) (xy 63.639066 -23.810218) (xy 63.6948 -23.808181)
			(xy 63.750237 -23.814281) (xy 63.804194 -23.828387) (xy 63.855523 -23.850199) (xy 63.903129 -23.879253)
			(xy 63.945997 -23.914928) (xy 63.983214 -23.956465) (xy 64.013987 -24.002978) (xy 64.037659 -24.053475)
			(xy 64.053727 -24.106882) (xy 64.061847 -24.162058) (xy 64.062356 -24.189944) (xy 65.821812 -24.189944)
			(xy 65.825883 -24.134322) (xy 65.838009 -24.079885) (xy 65.857932 -24.027794) (xy 65.885228 -23.979159)
			(xy 65.919314 -23.935016) (xy 65.959463 -23.896307) (xy 66.004821 -23.863856) (xy 66.054421 -23.838355)
			(xy 66.107205 -23.820348) (xy 66.162048 -23.810218) (xy 66.217782 -23.808181) (xy 66.273219 -23.814281)
			(xy 66.327176 -23.828387) (xy 66.378505 -23.850199) (xy 66.426111 -23.879253) (xy 66.468979 -23.914928)
			(xy 66.506196 -23.956465) (xy 66.536969 -24.002978) (xy 66.560641 -24.053475) (xy 66.576709 -24.106882)
			(xy 66.584829 -24.162058) (xy 66.585338 -24.189944) (xy 66.584829 -24.21783) (xy 66.576709 -24.273006)
			(xy 66.560641 -24.326413) (xy 66.536969 -24.37691) (xy 66.506196 -24.423423) (xy 66.468979 -24.46496)
			(xy 66.426111 -24.500635) (xy 66.378505 -24.529689) (xy 66.327176 -24.551501) (xy 66.273219 -24.565607)
			(xy 66.217782 -24.571707) (xy 66.162048 -24.56967) (xy 66.107205 -24.55954) (xy 66.054421 -24.541533)
			(xy 66.004821 -24.516032) (xy 65.959463 -24.483581) (xy 65.919314 -24.444872) (xy 65.885228 -24.400729)
			(xy 65.857932 -24.352094) (xy 65.838009 -24.300003) (xy 65.825883 -24.245566) (xy 65.821812 -24.189944)
			(xy 64.062356 -24.189944) (xy 64.061847 -24.21783) (xy 64.053727 -24.273006) (xy 64.037659 -24.326413)
			(xy 64.013987 -24.37691) (xy 63.983214 -24.423423) (xy 63.945997 -24.46496) (xy 63.903129 -24.500635)
			(xy 63.855523 -24.529689) (xy 63.804194 -24.551501) (xy 63.750237 -24.565607) (xy 63.6948 -24.571707)
			(xy 63.639066 -24.56967) (xy 63.584223 -24.55954) (xy 63.531439 -24.541533) (xy 63.481839 -24.516032)
			(xy 63.436481 -24.483581) (xy 63.396332 -24.444872) (xy 63.362246 -24.400729) (xy 63.33495 -24.352094)
			(xy 63.315027 -24.300003) (xy 63.302901 -24.245566) (xy 63.29883 -24.189944) (xy 60.213178 -24.189944)
			(xy 60.205627 -24.241256) (xy 60.189559 -24.294663) (xy 60.165887 -24.34516) (xy 60.135114 -24.391673)
			(xy 60.097897 -24.43321) (xy 60.055029 -24.468885) (xy 60.007423 -24.497939) (xy 59.956094 -24.519751)
			(xy 59.902137 -24.533857) (xy 59.8467 -24.539957) (xy 59.790966 -24.53792) (xy 59.736123 -24.52779)
			(xy 59.683339 -24.509783) (xy 59.633739 -24.484282) (xy 59.588381 -24.451831) (xy 59.548232 -24.413122)
			(xy 59.514146 -24.368979) (xy 59.48685 -24.320344) (xy 59.466927 -24.268253) (xy 59.454801 -24.213816)
			(xy 59.45073 -24.158194) (xy 54.787792 -24.158194) (xy 54.757172 -24.204475) (xy 54.719955 -24.246012)
			(xy 54.677087 -24.281687) (xy 54.629481 -24.310741) (xy 54.578152 -24.332553) (xy 54.524195 -24.346659)
			(xy 54.468758 -24.352759) (xy 54.413024 -24.350722) (xy 54.358181 -24.340592) (xy 54.305397 -24.322585)
			(xy 54.255797 -24.297084) (xy 54.210439 -24.264633) (xy 54.17029 -24.225924) (xy 54.136204 -24.181781)
			(xy 54.108908 -24.133146) (xy 54.088985 -24.081055) (xy 54.076859 -24.026618) (xy 54.072788 -23.970996)
			(xy 53.843496 -23.970996) (xy 53.843427 -23.974752) (xy 53.835307 -24.029928) (xy 53.819239 -24.083335)
			(xy 53.795567 -24.133832) (xy 53.764794 -24.180345) (xy 53.727577 -24.221882) (xy 53.684709 -24.257557)
			(xy 53.637103 -24.286611) (xy 53.585774 -24.308423) (xy 53.531817 -24.322529) (xy 53.47638 -24.328629)
			(xy 53.420646 -24.326592) (xy 53.365803 -24.316462) (xy 53.313019 -24.298455) (xy 53.263419 -24.272954)
			(xy 53.218061 -24.240503) (xy 53.177912 -24.201794) (xy 53.143826 -24.157651) (xy 53.11653 -24.109016)
			(xy 53.096607 -24.056925) (xy 53.084481 -24.002488) (xy 53.08041 -23.946866) (xy 52.840556 -23.946866)
			(xy 52.84089 -23.965154) (xy 52.840381 -23.99304) (xy 52.832261 -24.048216) (xy 52.816193 -24.101623)
			(xy 52.792521 -24.15212) (xy 52.761748 -24.198633) (xy 52.724531 -24.24017) (xy 52.681663 -24.275845)
			(xy 52.634057 -24.304899) (xy 52.582728 -24.326711) (xy 52.528771 -24.340817) (xy 52.473334 -24.346917)
			(xy 52.4176 -24.34488) (xy 52.362757 -24.33475) (xy 52.309973 -24.316743) (xy 52.260373 -24.291242)
			(xy 52.215015 -24.258791) (xy 52.174866 -24.220082) (xy 52.14078 -24.175939) (xy 52.113484 -24.127304)
			(xy 52.093561 -24.075213) (xy 52.081435 -24.020776) (xy 52.077364 -23.965154) (xy 42.537835 -23.965154)
			(xy 42.535903 -23.965659) (xy 42.480466 -23.971759) (xy 42.424732 -23.969722) (xy 42.369889 -23.959592)
			(xy 42.317105 -23.941585) (xy 42.267505 -23.916084) (xy 42.222147 -23.883633) (xy 42.181998 -23.844924)
			(xy 42.147912 -23.800781) (xy 42.120616 -23.752146) (xy 42.100693 -23.700055) (xy 42.088567 -23.645618)
			(xy 42.084496 -23.589996) (xy 16.848074 -23.589996) (xy 16.847565 -23.617882) (xy 16.839445 -23.673058)
			(xy 16.823377 -23.726465) (xy 16.799705 -23.776962) (xy 16.768932 -23.823475) (xy 16.731715 -23.865012)
			(xy 16.688847 -23.900687) (xy 16.641241 -23.929741) (xy 16.589912 -23.951553) (xy 16.535955 -23.965659)
			(xy 16.480518 -23.971759) (xy 16.424784 -23.969722) (xy 16.369941 -23.959592) (xy 16.317157 -23.941585)
			(xy 16.267557 -23.916084) (xy 16.222199 -23.883633) (xy 16.18205 -23.844924) (xy 16.147964 -23.800781)
			(xy 16.120668 -23.752146) (xy 16.100745 -23.700055) (xy 16.088619 -23.645618) (xy 16.084548 -23.589996)
			(xy 3.783134 -23.589996) (xy 3.797731 -23.596199) (xy 3.845337 -23.625253) (xy 3.888205 -23.660928)
			(xy 3.925422 -23.702465) (xy 3.956195 -23.748978) (xy 3.979867 -23.799475) (xy 3.995935 -23.852882)
			(xy 4.004055 -23.908058) (xy 4.004564 -23.935944) (xy 4.004055 -23.96383) (xy 3.995935 -24.019006)
			(xy 3.979867 -24.072413) (xy 3.956195 -24.12291) (xy 3.925422 -24.169423) (xy 3.907035 -24.189944)
			(xy 13.821916 -24.189944) (xy 13.825987 -24.134322) (xy 13.838113 -24.079885) (xy 13.858036 -24.027794)
			(xy 13.885332 -23.979159) (xy 13.919418 -23.935016) (xy 13.959567 -23.896307) (xy 14.004925 -23.863856)
			(xy 14.054525 -23.838355) (xy 14.107309 -23.820348) (xy 14.162152 -23.810218) (xy 14.217886 -23.808181)
			(xy 14.273323 -23.814281) (xy 14.32728 -23.828387) (xy 14.378609 -23.850199) (xy 14.426215 -23.879253)
			(xy 14.469083 -23.914928) (xy 14.5063 -23.956465) (xy 14.537073 -24.002978) (xy 14.560745 -24.053475)
			(xy 14.576813 -24.106882) (xy 14.584933 -24.162058) (xy 14.585442 -24.189944) (xy 14.584933 -24.21783)
			(xy 14.576813 -24.273006) (xy 14.560745 -24.326413) (xy 14.548157 -24.353266) (xy 19.380198 -24.353266)
			(xy 19.384269 -24.297644) (xy 19.396395 -24.243207) (xy 19.416318 -24.191116) (xy 19.443614 -24.142481)
			(xy 19.4777 -24.098338) (xy 19.517849 -24.059629) (xy 19.563207 -24.027178) (xy 19.612807 -24.001677)
			(xy 19.665591 -23.98367) (xy 19.720434 -23.97354) (xy 19.776168 -23.971503) (xy 19.831605 -23.977603)
			(xy 19.885562 -23.991709) (xy 19.936891 -24.013521) (xy 19.984497 -24.042575) (xy 20.027365 -24.07825)
			(xy 20.064582 -24.119787) (xy 20.089992 -24.158194) (xy 33.450782 -24.158194) (xy 33.454853 -24.102572)
			(xy 33.466979 -24.048135) (xy 33.486902 -23.996044) (xy 33.514198 -23.947409) (xy 33.548284 -23.903266)
			(xy 33.588433 -23.864557) (xy 33.633791 -23.832106) (xy 33.683391 -23.806605) (xy 33.736175 -23.788598)
			(xy 33.791018 -23.778468) (xy 33.846752 -23.776431) (xy 33.902189 -23.782531) (xy 33.956146 -23.796637)
			(xy 34.007475 -23.818449) (xy 34.055081 -23.847503) (xy 34.097949 -23.883178) (xy 34.135166 -23.924715)
			(xy 34.165939 -23.971228) (xy 34.189611 -24.021725) (xy 34.205679 -24.075132) (xy 34.213799 -24.130308)
			(xy 34.214308 -24.158194) (xy 34.213799 -24.18608) (xy 34.21323 -24.189944) (xy 37.298882 -24.189944)
			(xy 37.302953 -24.134322) (xy 37.315079 -24.079885) (xy 37.335002 -24.027794) (xy 37.362298 -23.979159)
			(xy 37.396384 -23.935016) (xy 37.436533 -23.896307) (xy 37.481891 -23.863856) (xy 37.531491 -23.838355)
			(xy 37.584275 -23.820348) (xy 37.639118 -23.810218) (xy 37.694852 -23.808181) (xy 37.750289 -23.814281)
			(xy 37.804246 -23.828387) (xy 37.855575 -23.850199) (xy 37.903181 -23.879253) (xy 37.946049 -23.914928)
			(xy 37.983266 -23.956465) (xy 38.014039 -24.002978) (xy 38.037711 -24.053475) (xy 38.053779 -24.106882)
			(xy 38.061899 -24.162058) (xy 38.062408 -24.189944) (xy 39.821864 -24.189944) (xy 39.825935 -24.134322)
			(xy 39.838061 -24.079885) (xy 39.857984 -24.027794) (xy 39.88528 -23.979159) (xy 39.919366 -23.935016)
			(xy 39.959515 -23.896307) (xy 40.004873 -23.863856) (xy 40.054473 -23.838355) (xy 40.107257 -23.820348)
			(xy 40.1621 -23.810218) (xy 40.217834 -23.808181) (xy 40.273271 -23.814281) (xy 40.327228 -23.828387)
			(xy 40.378557 -23.850199) (xy 40.426163 -23.879253) (xy 40.469031 -23.914928) (xy 40.506248 -23.956465)
			(xy 40.537021 -24.002978) (xy 40.560693 -24.053475) (xy 40.576761 -24.106882) (xy 40.584881 -24.162058)
			(xy 40.58539 -24.189944) (xy 40.584881 -24.21783) (xy 40.576761 -24.273006) (xy 40.560693 -24.326413)
			(xy 40.537021 -24.37691) (xy 40.506248 -24.423423) (xy 40.469031 -24.46496) (xy 40.426163 -24.500635)
			(xy 40.378557 -24.529689) (xy 40.327228 -24.551501) (xy 40.273271 -24.565607) (xy 40.217834 -24.571707)
			(xy 40.1621 -24.56967) (xy 40.107257 -24.55954) (xy 40.054473 -24.541533) (xy 40.004873 -24.516032)
			(xy 39.959515 -24.483581) (xy 39.919366 -24.444872) (xy 39.88528 -24.400729) (xy 39.857984 -24.352094)
			(xy 39.838061 -24.300003) (xy 39.825935 -24.245566) (xy 39.821864 -24.189944) (xy 38.062408 -24.189944)
			(xy 38.061899 -24.21783) (xy 38.053779 -24.273006) (xy 38.037711 -24.326413) (xy 38.014039 -24.37691)
			(xy 37.983266 -24.423423) (xy 37.946049 -24.46496) (xy 37.903181 -24.500635) (xy 37.855575 -24.529689)
			(xy 37.804246 -24.551501) (xy 37.750289 -24.565607) (xy 37.694852 -24.571707) (xy 37.639118 -24.56967)
			(xy 37.584275 -24.55954) (xy 37.531491 -24.541533) (xy 37.481891 -24.516032) (xy 37.436533 -24.483581)
			(xy 37.396384 -24.444872) (xy 37.362298 -24.400729) (xy 37.335002 -24.352094) (xy 37.315079 -24.300003)
			(xy 37.302953 -24.245566) (xy 37.298882 -24.189944) (xy 34.21323 -24.189944) (xy 34.205679 -24.241256)
			(xy 34.189611 -24.294663) (xy 34.165939 -24.34516) (xy 34.135166 -24.391673) (xy 34.097949 -24.43321)
			(xy 34.055081 -24.468885) (xy 34.007475 -24.497939) (xy 33.956146 -24.519751) (xy 33.902189 -24.533857)
			(xy 33.846752 -24.539957) (xy 33.791018 -24.53792) (xy 33.736175 -24.52779) (xy 33.683391 -24.509783)
			(xy 33.633791 -24.484282) (xy 33.588433 -24.451831) (xy 33.548284 -24.413122) (xy 33.514198 -24.368979)
			(xy 33.486902 -24.320344) (xy 33.466979 -24.268253) (xy 33.454853 -24.213816) (xy 33.450782 -24.158194)
			(xy 20.089992 -24.158194) (xy 20.095355 -24.1663) (xy 20.119027 -24.216797) (xy 20.135095 -24.270204)
			(xy 20.143215 -24.32538) (xy 20.143724 -24.353266) (xy 20.143215 -24.381152) (xy 20.135095 -24.436328)
			(xy 20.119027 -24.489735) (xy 20.095355 -24.540232) (xy 20.064582 -24.586745) (xy 20.027365 -24.628282)
			(xy 19.984497 -24.663957) (xy 19.936891 -24.693011) (xy 19.885562 -24.714823) (xy 19.831605 -24.728929)
			(xy 19.776168 -24.735029) (xy 19.720434 -24.732992) (xy 19.665591 -24.722862) (xy 19.612807 -24.704855)
			(xy 19.563207 -24.679354) (xy 19.517849 -24.646903) (xy 19.4777 -24.608194) (xy 19.443614 -24.564051)
			(xy 19.416318 -24.515416) (xy 19.396395 -24.463325) (xy 19.384269 -24.408888) (xy 19.380198 -24.353266)
			(xy 14.548157 -24.353266) (xy 14.537073 -24.37691) (xy 14.5063 -24.423423) (xy 14.469083 -24.46496)
			(xy 14.426215 -24.500635) (xy 14.378609 -24.529689) (xy 14.32728 -24.551501) (xy 14.273323 -24.565607)
			(xy 14.217886 -24.571707) (xy 14.162152 -24.56967) (xy 14.107309 -24.55954) (xy 14.054525 -24.541533)
			(xy 14.004925 -24.516032) (xy 13.959567 -24.483581) (xy 13.919418 -24.444872) (xy 13.885332 -24.400729)
			(xy 13.858036 -24.352094) (xy 13.838113 -24.300003) (xy 13.825987 -24.245566) (xy 13.821916 -24.189944)
			(xy 3.907035 -24.189944) (xy 3.888205 -24.21096) (xy 3.845337 -24.246635) (xy 3.797731 -24.275689)
			(xy 3.746402 -24.297501) (xy 3.692445 -24.311607) (xy 3.637008 -24.317707) (xy 3.581274 -24.31567)
			(xy 3.526431 -24.30554) (xy 3.473647 -24.287533) (xy 3.424047 -24.262032) (xy 3.378689 -24.229581)
			(xy 3.33854 -24.190872) (xy 3.304454 -24.146729) (xy 3.277158 -24.098094) (xy 3.257235 -24.046003)
			(xy 3.245109 -23.991566) (xy 3.241038 -23.935944) (xy 2.995676 -23.935944) (xy 2.995167 -23.96383)
			(xy 2.987047 -24.019006) (xy 2.970979 -24.072413) (xy 2.947307 -24.12291) (xy 2.916534 -24.169423)
			(xy 2.879317 -24.21096) (xy 2.836449 -24.246635) (xy 2.788843 -24.275689) (xy 2.737514 -24.297501)
			(xy 2.683557 -24.311607) (xy 2.62812 -24.317707) (xy 2.572386 -24.31567) (xy 2.517543 -24.30554)
			(xy 2.464759 -24.287533) (xy 2.415159 -24.262032) (xy 2.369801 -24.229581) (xy 2.329652 -24.190872)
			(xy 2.295566 -24.146729) (xy 2.26827 -24.098094) (xy 2.248347 -24.046003) (xy 2.236221 -23.991566)
			(xy 2.23215 -23.935944) (xy 2.02438 -23.935944) (xy 2.02438 -24.807418) (xy 6.371334 -24.807418)
			(xy 6.375405 -24.751796) (xy 6.387531 -24.697359) (xy 6.407454 -24.645268) (xy 6.43475 -24.596633)
			(xy 6.468836 -24.55249) (xy 6.508985 -24.513781) (xy 6.554343 -24.48133) (xy 6.603943 -24.455829)
			(xy 6.656727 -24.437822) (xy 6.71157 -24.427692) (xy 6.767304 -24.425655) (xy 6.822741 -24.431755)
			(xy 6.876698 -24.445861) (xy 6.928027 -24.467673) (xy 6.975633 -24.496727) (xy 7.018501 -24.532402)
			(xy 7.055718 -24.573939) (xy 7.086491 -24.620452) (xy 7.110163 -24.670949) (xy 7.126231 -24.724356)
			(xy 7.134351 -24.779532) (xy 7.13486 -24.807418) (xy 8.62025 -24.807418) (xy 8.624321 -24.751796)
			(xy 8.636447 -24.697359) (xy 8.65637 -24.645268) (xy 8.683666 -24.596633) (xy 8.717752 -24.55249)
			(xy 8.757901 -24.513781) (xy 8.803259 -24.48133) (xy 8.852859 -24.455829) (xy 8.905643 -24.437822)
			(xy 8.960486 -24.427692) (xy 9.01622 -24.425655) (xy 9.071657 -24.431755) (xy 9.125614 -24.445861)
			(xy 9.176943 -24.467673) (xy 9.224549 -24.496727) (xy 9.267417 -24.532402) (xy 9.304634 -24.573939)
			(xy 9.335407 -24.620452) (xy 9.359079 -24.670949) (xy 9.375147 -24.724356) (xy 9.383267 -24.779532)
			(xy 9.383776 -24.807418) (xy 9.383267 -24.835304) (xy 9.375147 -24.89048) (xy 9.359079 -24.943887)
			(xy 9.335407 -24.994384) (xy 9.304634 -25.040897) (xy 9.267417 -25.082434) (xy 9.224549 -25.118109)
			(xy 9.176943 -25.147163) (xy 9.125614 -25.168975) (xy 9.071657 -25.183081) (xy 9.01622 -25.189181)
			(xy 8.960486 -25.187144) (xy 8.905643 -25.177014) (xy 8.852859 -25.159007) (xy 8.803259 -25.133506)
			(xy 8.757901 -25.101055) (xy 8.717752 -25.062346) (xy 8.683666 -25.018203) (xy 8.65637 -24.969568)
			(xy 8.636447 -24.917477) (xy 8.624321 -24.86304) (xy 8.62025 -24.807418) (xy 7.13486 -24.807418)
			(xy 7.134351 -24.835304) (xy 7.126231 -24.89048) (xy 7.110163 -24.943887) (xy 7.086491 -24.994384)
			(xy 7.055718 -25.040897) (xy 7.018501 -25.082434) (xy 6.975633 -25.118109) (xy 6.928027 -25.147163)
			(xy 6.876698 -25.168975) (xy 6.822741 -25.183081) (xy 6.767304 -25.189181) (xy 6.71157 -25.187144)
			(xy 6.656727 -25.177014) (xy 6.603943 -25.159007) (xy 6.554343 -25.133506) (xy 6.508985 -25.101055)
			(xy 6.468836 -25.062346) (xy 6.43475 -25.018203) (xy 6.407454 -24.969568) (xy 6.387531 -24.917477)
			(xy 6.375405 -24.86304) (xy 6.371334 -24.807418) (xy 2.02438 -24.807418) (xy 2.02438 -25.390094)
			(xy 13.809216 -25.390094) (xy 13.813287 -25.334472) (xy 13.825413 -25.280035) (xy 13.845336 -25.227944)
			(xy 13.872632 -25.179309) (xy 13.906718 -25.135166) (xy 13.946867 -25.096457) (xy 13.992225 -25.064006)
			(xy 14.041825 -25.038505) (xy 14.094609 -25.020498) (xy 14.149452 -25.010368) (xy 14.205186 -25.008331)
			(xy 14.260623 -25.014431) (xy 14.31458 -25.028537) (xy 14.322621 -25.031954) (xy 18.187922 -25.031954)
			(xy 18.191993 -24.976332) (xy 18.204119 -24.921895) (xy 18.224042 -24.869804) (xy 18.251338 -24.821169)
			(xy 18.285424 -24.777026) (xy 18.325573 -24.738317) (xy 18.370931 -24.705866) (xy 18.420531 -24.680365)
			(xy 18.473315 -24.662358) (xy 18.528158 -24.652228) (xy 18.583892 -24.650191) (xy 18.639329 -24.656291)
			(xy 18.693286 -24.670397) (xy 18.744615 -24.692209) (xy 18.792221 -24.721263) (xy 18.835089 -24.756938)
			(xy 18.872306 -24.798475) (xy 18.878223 -24.807418) (xy 32.371282 -24.807418) (xy 32.375353 -24.751796)
			(xy 32.387479 -24.697359) (xy 32.407402 -24.645268) (xy 32.434698 -24.596633) (xy 32.468784 -24.55249)
			(xy 32.508933 -24.513781) (xy 32.554291 -24.48133) (xy 32.603891 -24.455829) (xy 32.656675 -24.437822)
			(xy 32.711518 -24.427692) (xy 32.767252 -24.425655) (xy 32.822689 -24.431755) (xy 32.876646 -24.445861)
			(xy 32.927975 -24.467673) (xy 32.975581 -24.496727) (xy 33.018449 -24.532402) (xy 33.055666 -24.573939)
			(xy 33.086439 -24.620452) (xy 33.110111 -24.670949) (xy 33.126179 -24.724356) (xy 33.134299 -24.779532)
			(xy 33.134808 -24.807418) (xy 34.620198 -24.807418) (xy 34.624269 -24.751796) (xy 34.636395 -24.697359)
			(xy 34.656318 -24.645268) (xy 34.683614 -24.596633) (xy 34.7177 -24.55249) (xy 34.757849 -24.513781)
			(xy 34.803207 -24.48133) (xy 34.852807 -24.455829) (xy 34.905591 -24.437822) (xy 34.960434 -24.427692)
			(xy 35.016168 -24.425655) (xy 35.071605 -24.431755) (xy 35.125562 -24.445861) (xy 35.176891 -24.467673)
			(xy 35.224497 -24.496727) (xy 35.267365 -24.532402) (xy 35.304582 -24.573939) (xy 35.335355 -24.620452)
			(xy 35.359027 -24.670949) (xy 35.375095 -24.724356) (xy 35.383215 -24.779532) (xy 35.383724 -24.807418)
			(xy 35.383215 -24.835304) (xy 35.375095 -24.89048) (xy 35.359027 -24.943887) (xy 35.335355 -24.994384)
			(xy 35.304582 -25.040897) (xy 35.267365 -25.082434) (xy 35.224497 -25.118109) (xy 35.176891 -25.147163)
			(xy 35.125562 -25.168975) (xy 35.071605 -25.183081) (xy 35.016168 -25.189181) (xy 34.960434 -25.187144)
			(xy 34.905591 -25.177014) (xy 34.852807 -25.159007) (xy 34.803207 -25.133506) (xy 34.757849 -25.101055)
			(xy 34.7177 -25.062346) (xy 34.683614 -25.018203) (xy 34.656318 -24.969568) (xy 34.636395 -24.917477)
			(xy 34.624269 -24.86304) (xy 34.620198 -24.807418) (xy 33.134808 -24.807418) (xy 33.134299 -24.835304)
			(xy 33.126179 -24.89048) (xy 33.110111 -24.943887) (xy 33.086439 -24.994384) (xy 33.055666 -25.040897)
			(xy 33.018449 -25.082434) (xy 32.975581 -25.118109) (xy 32.927975 -25.147163) (xy 32.876646 -25.168975)
			(xy 32.822689 -25.183081) (xy 32.767252 -25.189181) (xy 32.711518 -25.187144) (xy 32.656675 -25.177014)
			(xy 32.603891 -25.159007) (xy 32.554291 -25.133506) (xy 32.508933 -25.101055) (xy 32.468784 -25.062346)
			(xy 32.434698 -25.018203) (xy 32.407402 -24.969568) (xy 32.387479 -24.917477) (xy 32.375353 -24.86304)
			(xy 32.371282 -24.807418) (xy 18.878223 -24.807418) (xy 18.903079 -24.844988) (xy 18.926751 -24.895485)
			(xy 18.942819 -24.948892) (xy 18.950939 -25.004068) (xy 18.951448 -25.031954) (xy 18.950939 -25.05984)
			(xy 18.942819 -25.115016) (xy 18.926751 -25.168423) (xy 18.903079 -25.21892) (xy 18.872306 -25.265433)
			(xy 18.835089 -25.30697) (xy 18.792221 -25.342645) (xy 18.744615 -25.371699) (xy 18.701327 -25.390094)
			(xy 39.809164 -25.390094) (xy 39.813235 -25.334472) (xy 39.825361 -25.280035) (xy 39.845284 -25.227944)
			(xy 39.87258 -25.179309) (xy 39.906666 -25.135166) (xy 39.946815 -25.096457) (xy 39.992173 -25.064006)
			(xy 40.041773 -25.038505) (xy 40.094557 -25.020498) (xy 40.1494 -25.010368) (xy 40.205134 -25.008331)
			(xy 40.260571 -25.014431) (xy 40.314528 -25.028537) (xy 40.322569 -25.031954) (xy 44.18787 -25.031954)
			(xy 44.191941 -24.976332) (xy 44.204067 -24.921895) (xy 44.22399 -24.869804) (xy 44.251286 -24.821169)
			(xy 44.285372 -24.777026) (xy 44.325521 -24.738317) (xy 44.370879 -24.705866) (xy 44.420479 -24.680365)
			(xy 44.473263 -24.662358) (xy 44.528106 -24.652228) (xy 44.58384 -24.650191) (xy 44.639277 -24.656291)
			(xy 44.693234 -24.670397) (xy 44.744563 -24.692209) (xy 44.792169 -24.721263) (xy 44.835037 -24.756938)
			(xy 44.836571 -24.75865) (xy 46.868586 -24.75865) (xy 46.872657 -24.703028) (xy 46.884783 -24.648591)
			(xy 46.904706 -24.5965) (xy 46.932002 -24.547865) (xy 46.966088 -24.503722) (xy 47.006237 -24.465013)
			(xy 47.051595 -24.432562) (xy 47.101195 -24.407061) (xy 47.153979 -24.389054) (xy 47.208822 -24.378924)
			(xy 47.264556 -24.376887) (xy 47.319993 -24.382987) (xy 47.37395 -24.397093) (xy 47.425279 -24.418905)
			(xy 47.472885 -24.447959) (xy 47.515753 -24.483634) (xy 47.55297 -24.525171) (xy 47.583743 -24.571684)
			(xy 47.607415 -24.622181) (xy 47.623483 -24.675588) (xy 47.631603 -24.730764) (xy 47.632112 -24.75865)
			(xy 47.631603 -24.786536) (xy 47.62853 -24.807418) (xy 58.37123 -24.807418) (xy 58.375301 -24.751796)
			(xy 58.387427 -24.697359) (xy 58.40735 -24.645268) (xy 58.434646 -24.596633) (xy 58.468732 -24.55249)
			(xy 58.508881 -24.513781) (xy 58.554239 -24.48133) (xy 58.603839 -24.455829) (xy 58.656623 -24.437822)
			(xy 58.711466 -24.427692) (xy 58.7672 -24.425655) (xy 58.822637 -24.431755) (xy 58.876594 -24.445861)
			(xy 58.927923 -24.467673) (xy 58.975529 -24.496727) (xy 59.018397 -24.532402) (xy 59.055614 -24.573939)
			(xy 59.086387 -24.620452) (xy 59.110059 -24.670949) (xy 59.126127 -24.724356) (xy 59.134247 -24.779532)
			(xy 59.134756 -24.807418) (xy 60.620146 -24.807418) (xy 60.624217 -24.751796) (xy 60.636343 -24.697359)
			(xy 60.656266 -24.645268) (xy 60.683562 -24.596633) (xy 60.717648 -24.55249) (xy 60.757797 -24.513781)
			(xy 60.803155 -24.48133) (xy 60.852755 -24.455829) (xy 60.905539 -24.437822) (xy 60.960382 -24.427692)
			(xy 61.016116 -24.425655) (xy 61.071553 -24.431755) (xy 61.12551 -24.445861) (xy 61.176839 -24.467673)
			(xy 61.224445 -24.496727) (xy 61.267313 -24.532402) (xy 61.30453 -24.573939) (xy 61.335303 -24.620452)
			(xy 61.358975 -24.670949) (xy 61.375043 -24.724356) (xy 61.383163 -24.779532) (xy 61.383672 -24.807418)
			(xy 61.383163 -24.835304) (xy 61.375043 -24.89048) (xy 61.358975 -24.943887) (xy 61.335303 -24.994384)
			(xy 61.30453 -25.040897) (xy 61.267313 -25.082434) (xy 61.224445 -25.118109) (xy 61.176839 -25.147163)
			(xy 61.12551 -25.168975) (xy 61.071553 -25.183081) (xy 61.016116 -25.189181) (xy 60.960382 -25.187144)
			(xy 60.905539 -25.177014) (xy 60.852755 -25.159007) (xy 60.803155 -25.133506) (xy 60.757797 -25.101055)
			(xy 60.717648 -25.062346) (xy 60.683562 -25.018203) (xy 60.656266 -24.969568) (xy 60.636343 -24.917477)
			(xy 60.624217 -24.86304) (xy 60.620146 -24.807418) (xy 59.134756 -24.807418) (xy 59.134247 -24.835304)
			(xy 59.126127 -24.89048) (xy 59.110059 -24.943887) (xy 59.086387 -24.994384) (xy 59.055614 -25.040897)
			(xy 59.018397 -25.082434) (xy 58.975529 -25.118109) (xy 58.927923 -25.147163) (xy 58.876594 -25.168975)
			(xy 58.822637 -25.183081) (xy 58.7672 -25.189181) (xy 58.711466 -25.187144) (xy 58.656623 -25.177014)
			(xy 58.603839 -25.159007) (xy 58.554239 -25.133506) (xy 58.508881 -25.101055) (xy 58.468732 -25.062346)
			(xy 58.434646 -25.018203) (xy 58.40735 -24.969568) (xy 58.387427 -24.917477) (xy 58.375301 -24.86304)
			(xy 58.37123 -24.807418) (xy 47.62853 -24.807418) (xy 47.623483 -24.841712) (xy 47.607415 -24.895119)
			(xy 47.583743 -24.945616) (xy 47.55297 -24.992129) (xy 47.515753 -25.033666) (xy 47.472885 -25.069341)
			(xy 47.425279 -25.098395) (xy 47.37395 -25.120207) (xy 47.319993 -25.134313) (xy 47.264556 -25.140413)
			(xy 47.208822 -25.138376) (xy 47.153979 -25.128246) (xy 47.101195 -25.110239) (xy 47.051595 -25.084738)
			(xy 47.006237 -25.052287) (xy 46.966088 -25.013578) (xy 46.932002 -24.969435) (xy 46.904706 -24.9208)
			(xy 46.884783 -24.868709) (xy 46.872657 -24.814272) (xy 46.868586 -24.75865) (xy 44.836571 -24.75865)
			(xy 44.872254 -24.798475) (xy 44.903027 -24.844988) (xy 44.926699 -24.895485) (xy 44.942767 -24.948892)
			(xy 44.950887 -25.004068) (xy 44.951396 -25.031954) (xy 44.950887 -25.05984) (xy 44.942767 -25.115016)
			(xy 44.926699 -25.168423) (xy 44.903027 -25.21892) (xy 44.872254 -25.265433) (xy 44.835037 -25.30697)
			(xy 44.792169 -25.342645) (xy 44.744563 -25.371699) (xy 44.693234 -25.393511) (xy 44.639277 -25.407617)
			(xy 44.58384 -25.413717) (xy 44.528106 -25.41168) (xy 44.473263 -25.40155) (xy 44.420479 -25.383543)
			(xy 44.370879 -25.358042) (xy 44.325521 -25.325591) (xy 44.285372 -25.286882) (xy 44.251286 -25.242739)
			(xy 44.22399 -25.194104) (xy 44.204067 -25.142013) (xy 44.191941 -25.087576) (xy 44.18787 -25.031954)
			(xy 40.322569 -25.031954) (xy 40.365857 -25.050349) (xy 40.413463 -25.079403) (xy 40.456331 -25.115078)
			(xy 40.493548 -25.156615) (xy 40.524321 -25.203128) (xy 40.547993 -25.253625) (xy 40.564061 -25.307032)
			(xy 40.572181 -25.362208) (xy 40.57269 -25.390094) (xy 40.572181 -25.41798) (xy 40.564061 -25.473156)
			(xy 40.547993 -25.526563) (xy 40.532904 -25.55875) (xy 48.64176 -25.55875) (xy 48.645831 -25.503128)
			(xy 48.657957 -25.448691) (xy 48.67788 -25.3966) (xy 48.705176 -25.347965) (xy 48.739262 -25.303822)
			(xy 48.779411 -25.265113) (xy 48.824769 -25.232662) (xy 48.874369 -25.207161) (xy 48.927153 -25.189154)
			(xy 48.981996 -25.179024) (xy 49.03773 -25.176987) (xy 49.093167 -25.183087) (xy 49.147124 -25.197193)
			(xy 49.198453 -25.219005) (xy 49.246059 -25.248059) (xy 49.288927 -25.283734) (xy 49.326144 -25.325271)
			(xy 49.356917 -25.371784) (xy 49.3655 -25.390094) (xy 65.809112 -25.390094) (xy 65.813183 -25.334472)
			(xy 65.825309 -25.280035) (xy 65.845232 -25.227944) (xy 65.872528 -25.179309) (xy 65.906614 -25.135166)
			(xy 65.946763 -25.096457) (xy 65.992121 -25.064006) (xy 66.041721 -25.038505) (xy 66.094505 -25.020498)
			(xy 66.149348 -25.010368) (xy 66.205082 -25.008331) (xy 66.260519 -25.014431) (xy 66.314476 -25.028537)
			(xy 66.322517 -25.031954) (xy 70.187818 -25.031954) (xy 70.191889 -24.976332) (xy 70.204015 -24.921895)
			(xy 70.223938 -24.869804) (xy 70.251234 -24.821169) (xy 70.28532 -24.777026) (xy 70.325469 -24.738317)
			(xy 70.370827 -24.705866) (xy 70.420427 -24.680365) (xy 70.473211 -24.662358) (xy 70.528054 -24.652228)
			(xy 70.583788 -24.650191) (xy 70.639225 -24.656291) (xy 70.693182 -24.670397) (xy 70.744511 -24.692209)
			(xy 70.792117 -24.721263) (xy 70.834985 -24.756938) (xy 70.836519 -24.75865) (xy 72.868534 -24.75865)
			(xy 72.872605 -24.703028) (xy 72.884731 -24.648591) (xy 72.904654 -24.5965) (xy 72.93195 -24.547865)
			(xy 72.966036 -24.503722) (xy 73.006185 -24.465013) (xy 73.051543 -24.432562) (xy 73.101143 -24.407061)
			(xy 73.153927 -24.389054) (xy 73.20877 -24.378924) (xy 73.264504 -24.376887) (xy 73.319941 -24.382987)
			(xy 73.373898 -24.397093) (xy 73.425227 -24.418905) (xy 73.472833 -24.447959) (xy 73.515701 -24.483634)
			(xy 73.552918 -24.525171) (xy 73.583691 -24.571684) (xy 73.607363 -24.622181) (xy 73.623431 -24.675588)
			(xy 73.631551 -24.730764) (xy 73.63206 -24.75865) (xy 73.631551 -24.786536) (xy 73.628478 -24.807418)
			(xy 84.371178 -24.807418) (xy 84.375249 -24.751796) (xy 84.387375 -24.697359) (xy 84.407298 -24.645268)
			(xy 84.434594 -24.596633) (xy 84.46868 -24.55249) (xy 84.508829 -24.513781) (xy 84.554187 -24.48133)
			(xy 84.603787 -24.455829) (xy 84.656571 -24.437822) (xy 84.711414 -24.427692) (xy 84.767148 -24.425655)
			(xy 84.822585 -24.431755) (xy 84.876542 -24.445861) (xy 84.927871 -24.467673) (xy 84.975477 -24.496727)
			(xy 85.018345 -24.532402) (xy 85.055562 -24.573939) (xy 85.086335 -24.620452) (xy 85.110007 -24.670949)
			(xy 85.126075 -24.724356) (xy 85.134195 -24.779532) (xy 85.134704 -24.807418) (xy 86.620094 -24.807418)
			(xy 86.624165 -24.751796) (xy 86.636291 -24.697359) (xy 86.656214 -24.645268) (xy 86.68351 -24.596633)
			(xy 86.717596 -24.55249) (xy 86.757745 -24.513781) (xy 86.803103 -24.48133) (xy 86.852703 -24.455829)
			(xy 86.905487 -24.437822) (xy 86.96033 -24.427692) (xy 87.016064 -24.425655) (xy 87.071501 -24.431755)
			(xy 87.125458 -24.445861) (xy 87.176787 -24.467673) (xy 87.224393 -24.496727) (xy 87.267261 -24.532402)
			(xy 87.304478 -24.573939) (xy 87.335251 -24.620452) (xy 87.358923 -24.670949) (xy 87.374991 -24.724356)
			(xy 87.383111 -24.779532) (xy 87.38362 -24.807418) (xy 87.383111 -24.835304) (xy 87.374991 -24.89048)
			(xy 87.358923 -24.943887) (xy 87.335251 -24.994384) (xy 87.304478 -25.040897) (xy 87.267261 -25.082434)
			(xy 87.224393 -25.118109) (xy 87.176787 -25.147163) (xy 87.125458 -25.168975) (xy 87.071501 -25.183081)
			(xy 87.016064 -25.189181) (xy 86.96033 -25.187144) (xy 86.905487 -25.177014) (xy 86.852703 -25.159007)
			(xy 86.803103 -25.133506) (xy 86.757745 -25.101055) (xy 86.717596 -25.062346) (xy 86.68351 -25.018203)
			(xy 86.656214 -24.969568) (xy 86.636291 -24.917477) (xy 86.624165 -24.86304) (xy 86.620094 -24.807418)
			(xy 85.134704 -24.807418) (xy 85.134195 -24.835304) (xy 85.126075 -24.89048) (xy 85.110007 -24.943887)
			(xy 85.086335 -24.994384) (xy 85.055562 -25.040897) (xy 85.018345 -25.082434) (xy 84.975477 -25.118109)
			(xy 84.927871 -25.147163) (xy 84.876542 -25.168975) (xy 84.822585 -25.183081) (xy 84.767148 -25.189181)
			(xy 84.711414 -25.187144) (xy 84.656571 -25.177014) (xy 84.603787 -25.159007) (xy 84.554187 -25.133506)
			(xy 84.508829 -25.101055) (xy 84.46868 -25.062346) (xy 84.434594 -25.018203) (xy 84.407298 -24.969568)
			(xy 84.387375 -24.917477) (xy 84.375249 -24.86304) (xy 84.371178 -24.807418) (xy 73.628478 -24.807418)
			(xy 73.623431 -24.841712) (xy 73.607363 -24.895119) (xy 73.583691 -24.945616) (xy 73.552918 -24.992129)
			(xy 73.515701 -25.033666) (xy 73.472833 -25.069341) (xy 73.425227 -25.098395) (xy 73.373898 -25.120207)
			(xy 73.319941 -25.134313) (xy 73.264504 -25.140413) (xy 73.20877 -25.138376) (xy 73.153927 -25.128246)
			(xy 73.101143 -25.110239) (xy 73.051543 -25.084738) (xy 73.006185 -25.052287) (xy 72.966036 -25.013578)
			(xy 72.93195 -24.969435) (xy 72.904654 -24.9208) (xy 72.884731 -24.868709) (xy 72.872605 -24.814272)
			(xy 72.868534 -24.75865) (xy 70.836519 -24.75865) (xy 70.872202 -24.798475) (xy 70.902975 -24.844988)
			(xy 70.926647 -24.895485) (xy 70.942715 -24.948892) (xy 70.950835 -25.004068) (xy 70.951344 -25.031954)
			(xy 70.950835 -25.05984) (xy 70.942715 -25.115016) (xy 70.926647 -25.168423) (xy 70.902975 -25.21892)
			(xy 70.872202 -25.265433) (xy 70.834985 -25.30697) (xy 70.792117 -25.342645) (xy 70.744511 -25.371699)
			(xy 70.693182 -25.393511) (xy 70.639225 -25.407617) (xy 70.583788 -25.413717) (xy 70.528054 -25.41168)
			(xy 70.473211 -25.40155) (xy 70.420427 -25.383543) (xy 70.370827 -25.358042) (xy 70.325469 -25.325591)
			(xy 70.28532 -25.286882) (xy 70.251234 -25.242739) (xy 70.223938 -25.194104) (xy 70.204015 -25.142013)
			(xy 70.191889 -25.087576) (xy 70.187818 -25.031954) (xy 66.322517 -25.031954) (xy 66.365805 -25.050349)
			(xy 66.413411 -25.079403) (xy 66.456279 -25.115078) (xy 66.493496 -25.156615) (xy 66.524269 -25.203128)
			(xy 66.547941 -25.253625) (xy 66.564009 -25.307032) (xy 66.572129 -25.362208) (xy 66.572638 -25.390094)
			(xy 66.572129 -25.41798) (xy 66.564009 -25.473156) (xy 66.547941 -25.526563) (xy 66.532852 -25.55875)
			(xy 74.641708 -25.55875) (xy 74.645779 -25.503128) (xy 74.657905 -25.448691) (xy 74.677828 -25.3966)
			(xy 74.705124 -25.347965) (xy 74.73921 -25.303822) (xy 74.779359 -25.265113) (xy 74.824717 -25.232662)
			(xy 74.874317 -25.207161) (xy 74.927101 -25.189154) (xy 74.981944 -25.179024) (xy 75.037678 -25.176987)
			(xy 75.093115 -25.183087) (xy 75.147072 -25.197193) (xy 75.198401 -25.219005) (xy 75.246007 -25.248059)
			(xy 75.288875 -25.283734) (xy 75.326092 -25.325271) (xy 75.356865 -25.371784) (xy 75.365448 -25.390094)
			(xy 91.80906 -25.390094) (xy 91.813131 -25.334472) (xy 91.825257 -25.280035) (xy 91.84518 -25.227944)
			(xy 91.872476 -25.179309) (xy 91.906562 -25.135166) (xy 91.946711 -25.096457) (xy 91.992069 -25.064006)
			(xy 92.041669 -25.038505) (xy 92.094453 -25.020498) (xy 92.149296 -25.010368) (xy 92.20503 -25.008331)
			(xy 92.260467 -25.014431) (xy 92.314424 -25.028537) (xy 92.322465 -25.031954) (xy 96.187766 -25.031954)
			(xy 96.191837 -24.976332) (xy 96.203963 -24.921895) (xy 96.223886 -24.869804) (xy 96.251182 -24.821169)
			(xy 96.285268 -24.777026) (xy 96.325417 -24.738317) (xy 96.370775 -24.705866) (xy 96.420375 -24.680365)
			(xy 96.473159 -24.662358) (xy 96.528002 -24.652228) (xy 96.583736 -24.650191) (xy 96.639173 -24.656291)
			(xy 96.69313 -24.670397) (xy 96.744459 -24.692209) (xy 96.792065 -24.721263) (xy 96.834933 -24.756938)
			(xy 96.836467 -24.75865) (xy 98.868482 -24.75865) (xy 98.872553 -24.703028) (xy 98.884679 -24.648591)
			(xy 98.904602 -24.5965) (xy 98.931898 -24.547865) (xy 98.965984 -24.503722) (xy 99.006133 -24.465013)
			(xy 99.051491 -24.432562) (xy 99.101091 -24.407061) (xy 99.153875 -24.389054) (xy 99.208718 -24.378924)
			(xy 99.264452 -24.376887) (xy 99.319889 -24.382987) (xy 99.373846 -24.397093) (xy 99.425175 -24.418905)
			(xy 99.472781 -24.447959) (xy 99.515649 -24.483634) (xy 99.552866 -24.525171) (xy 99.583639 -24.571684)
			(xy 99.607311 -24.622181) (xy 99.623379 -24.675588) (xy 99.631499 -24.730764) (xy 99.632008 -24.75865)
			(xy 99.631499 -24.786536) (xy 99.623379 -24.841712) (xy 99.607311 -24.895119) (xy 99.583639 -24.945616)
			(xy 99.552866 -24.992129) (xy 99.515649 -25.033666) (xy 99.472781 -25.069341) (xy 99.425175 -25.098395)
			(xy 99.373846 -25.120207) (xy 99.319889 -25.134313) (xy 99.264452 -25.140413) (xy 99.208718 -25.138376)
			(xy 99.153875 -25.128246) (xy 99.101091 -25.110239) (xy 99.051491 -25.084738) (xy 99.006133 -25.052287)
			(xy 98.965984 -25.013578) (xy 98.931898 -24.969435) (xy 98.904602 -24.9208) (xy 98.884679 -24.868709)
			(xy 98.872553 -24.814272) (xy 98.868482 -24.75865) (xy 96.836467 -24.75865) (xy 96.87215 -24.798475)
			(xy 96.902923 -24.844988) (xy 96.926595 -24.895485) (xy 96.942663 -24.948892) (xy 96.950783 -25.004068)
			(xy 96.951292 -25.031954) (xy 96.950783 -25.05984) (xy 96.942663 -25.115016) (xy 96.926595 -25.168423)
			(xy 96.902923 -25.21892) (xy 96.87215 -25.265433) (xy 96.834933 -25.30697) (xy 96.792065 -25.342645)
			(xy 96.744459 -25.371699) (xy 96.69313 -25.393511) (xy 96.639173 -25.407617) (xy 96.583736 -25.413717)
			(xy 96.528002 -25.41168) (xy 96.473159 -25.40155) (xy 96.420375 -25.383543) (xy 96.370775 -25.358042)
			(xy 96.325417 -25.325591) (xy 96.285268 -25.286882) (xy 96.251182 -25.242739) (xy 96.223886 -25.194104)
			(xy 96.203963 -25.142013) (xy 96.191837 -25.087576) (xy 96.187766 -25.031954) (xy 92.322465 -25.031954)
			(xy 92.365753 -25.050349) (xy 92.413359 -25.079403) (xy 92.456227 -25.115078) (xy 92.493444 -25.156615)
			(xy 92.524217 -25.203128) (xy 92.547889 -25.253625) (xy 92.563957 -25.307032) (xy 92.572077 -25.362208)
			(xy 92.572586 -25.390094) (xy 92.572077 -25.41798) (xy 92.563957 -25.473156) (xy 92.547889 -25.526563)
			(xy 92.5328 -25.55875) (xy 100.641656 -25.55875) (xy 100.645727 -25.503128) (xy 100.657853 -25.448691)
			(xy 100.677776 -25.3966) (xy 100.705072 -25.347965) (xy 100.739158 -25.303822) (xy 100.779307 -25.265113)
			(xy 100.824665 -25.232662) (xy 100.874265 -25.207161) (xy 100.927049 -25.189154) (xy 100.981892 -25.179024)
			(xy 101.037626 -25.176987) (xy 101.093063 -25.183087) (xy 101.14702 -25.197193) (xy 101.198349 -25.219005)
			(xy 101.245955 -25.248059) (xy 101.288823 -25.283734) (xy 101.32604 -25.325271) (xy 101.356813 -25.371784)
			(xy 101.365396 -25.390094) (xy 129.909314 -25.390094) (xy 129.913385 -25.334472) (xy 129.925511 -25.280035)
			(xy 129.945434 -25.227944) (xy 129.97273 -25.179309) (xy 130.006816 -25.135166) (xy 130.046965 -25.096457)
			(xy 130.092323 -25.064006) (xy 130.141923 -25.038505) (xy 130.194707 -25.020498) (xy 130.24955 -25.010368)
			(xy 130.305284 -25.008331) (xy 130.360721 -25.014431) (xy 130.414678 -25.028537) (xy 130.422719 -25.031954)
			(xy 134.28802 -25.031954) (xy 134.292091 -24.976332) (xy 134.304217 -24.921895) (xy 134.32414 -24.869804)
			(xy 134.351436 -24.821169) (xy 134.385522 -24.777026) (xy 134.425671 -24.738317) (xy 134.471029 -24.705866)
			(xy 134.520629 -24.680365) (xy 134.573413 -24.662358) (xy 134.628256 -24.652228) (xy 134.68399 -24.650191)
			(xy 134.739427 -24.656291) (xy 134.793384 -24.670397) (xy 134.844713 -24.692209) (xy 134.892319 -24.721263)
			(xy 134.935187 -24.756938) (xy 134.936721 -24.75865) (xy 136.968736 -24.75865) (xy 136.972807 -24.703028)
			(xy 136.984933 -24.648591) (xy 137.004856 -24.5965) (xy 137.032152 -24.547865) (xy 137.066238 -24.503722)
			(xy 137.106387 -24.465013) (xy 137.151745 -24.432562) (xy 137.201345 -24.407061) (xy 137.254129 -24.389054)
			(xy 137.308972 -24.378924) (xy 137.364706 -24.376887) (xy 137.420143 -24.382987) (xy 137.4741 -24.397093)
			(xy 137.525429 -24.418905) (xy 137.573035 -24.447959) (xy 137.615903 -24.483634) (xy 137.65312 -24.525171)
			(xy 137.683893 -24.571684) (xy 137.707565 -24.622181) (xy 137.723633 -24.675588) (xy 137.731753 -24.730764)
			(xy 137.732262 -24.75865) (xy 137.731753 -24.786536) (xy 137.72868 -24.807418) (xy 148.47138 -24.807418)
			(xy 148.475451 -24.751796) (xy 148.487577 -24.697359) (xy 148.5075 -24.645268) (xy 148.534796 -24.596633)
			(xy 148.568882 -24.55249) (xy 148.609031 -24.513781) (xy 148.654389 -24.48133) (xy 148.703989 -24.455829)
			(xy 148.756773 -24.437822) (xy 148.811616 -24.427692) (xy 148.86735 -24.425655) (xy 148.922787 -24.431755)
			(xy 148.976744 -24.445861) (xy 149.028073 -24.467673) (xy 149.075679 -24.496727) (xy 149.118547 -24.532402)
			(xy 149.155764 -24.573939) (xy 149.186537 -24.620452) (xy 149.210209 -24.670949) (xy 149.226277 -24.724356)
			(xy 149.234397 -24.779532) (xy 149.234906 -24.807418) (xy 150.720296 -24.807418) (xy 150.724367 -24.751796)
			(xy 150.736493 -24.697359) (xy 150.756416 -24.645268) (xy 150.783712 -24.596633) (xy 150.817798 -24.55249)
			(xy 150.857947 -24.513781) (xy 150.903305 -24.48133) (xy 150.952905 -24.455829) (xy 151.005689 -24.437822)
			(xy 151.060532 -24.427692) (xy 151.116266 -24.425655) (xy 151.171703 -24.431755) (xy 151.22566 -24.445861)
			(xy 151.276989 -24.467673) (xy 151.324595 -24.496727) (xy 151.367463 -24.532402) (xy 151.40468 -24.573939)
			(xy 151.435453 -24.620452) (xy 151.459125 -24.670949) (xy 151.475193 -24.724356) (xy 151.483313 -24.779532)
			(xy 151.483822 -24.807418) (xy 151.483313 -24.835304) (xy 151.475193 -24.89048) (xy 151.459125 -24.943887)
			(xy 151.435453 -24.994384) (xy 151.40468 -25.040897) (xy 151.367463 -25.082434) (xy 151.324595 -25.118109)
			(xy 151.276989 -25.147163) (xy 151.22566 -25.168975) (xy 151.171703 -25.183081) (xy 151.116266 -25.189181)
			(xy 151.060532 -25.187144) (xy 151.005689 -25.177014) (xy 150.952905 -25.159007) (xy 150.903305 -25.133506)
			(xy 150.857947 -25.101055) (xy 150.817798 -25.062346) (xy 150.783712 -25.018203) (xy 150.756416 -24.969568)
			(xy 150.736493 -24.917477) (xy 150.724367 -24.86304) (xy 150.720296 -24.807418) (xy 149.234906 -24.807418)
			(xy 149.234397 -24.835304) (xy 149.226277 -24.89048) (xy 149.210209 -24.943887) (xy 149.186537 -24.994384)
			(xy 149.155764 -25.040897) (xy 149.118547 -25.082434) (xy 149.075679 -25.118109) (xy 149.028073 -25.147163)
			(xy 148.976744 -25.168975) (xy 148.922787 -25.183081) (xy 148.86735 -25.189181) (xy 148.811616 -25.187144)
			(xy 148.756773 -25.177014) (xy 148.703989 -25.159007) (xy 148.654389 -25.133506) (xy 148.609031 -25.101055)
			(xy 148.568882 -25.062346) (xy 148.534796 -25.018203) (xy 148.5075 -24.969568) (xy 148.487577 -24.917477)
			(xy 148.475451 -24.86304) (xy 148.47138 -24.807418) (xy 137.72868 -24.807418) (xy 137.723633 -24.841712)
			(xy 137.707565 -24.895119) (xy 137.683893 -24.945616) (xy 137.65312 -24.992129) (xy 137.615903 -25.033666)
			(xy 137.573035 -25.069341) (xy 137.525429 -25.098395) (xy 137.4741 -25.120207) (xy 137.420143 -25.134313)
			(xy 137.364706 -25.140413) (xy 137.308972 -25.138376) (xy 137.254129 -25.128246) (xy 137.201345 -25.110239)
			(xy 137.151745 -25.084738) (xy 137.106387 -25.052287) (xy 137.066238 -25.013578) (xy 137.032152 -24.969435)
			(xy 137.004856 -24.9208) (xy 136.984933 -24.868709) (xy 136.972807 -24.814272) (xy 136.968736 -24.75865)
			(xy 134.936721 -24.75865) (xy 134.972404 -24.798475) (xy 135.003177 -24.844988) (xy 135.026849 -24.895485)
			(xy 135.042917 -24.948892) (xy 135.051037 -25.004068) (xy 135.051546 -25.031954) (xy 135.051037 -25.05984)
			(xy 135.042917 -25.115016) (xy 135.026849 -25.168423) (xy 135.003177 -25.21892) (xy 134.972404 -25.265433)
			(xy 134.935187 -25.30697) (xy 134.892319 -25.342645) (xy 134.844713 -25.371699) (xy 134.793384 -25.393511)
			(xy 134.739427 -25.407617) (xy 134.68399 -25.413717) (xy 134.628256 -25.41168) (xy 134.573413 -25.40155)
			(xy 134.520629 -25.383543) (xy 134.471029 -25.358042) (xy 134.425671 -25.325591) (xy 134.385522 -25.286882)
			(xy 134.351436 -25.242739) (xy 134.32414 -25.194104) (xy 134.304217 -25.142013) (xy 134.292091 -25.087576)
			(xy 134.28802 -25.031954) (xy 130.422719 -25.031954) (xy 130.466007 -25.050349) (xy 130.513613 -25.079403)
			(xy 130.556481 -25.115078) (xy 130.593698 -25.156615) (xy 130.624471 -25.203128) (xy 130.648143 -25.253625)
			(xy 130.664211 -25.307032) (xy 130.672331 -25.362208) (xy 130.67284 -25.390094) (xy 130.672331 -25.41798)
			(xy 130.664211 -25.473156) (xy 130.648143 -25.526563) (xy 130.633054 -25.55875) (xy 138.74191 -25.55875)
			(xy 138.745981 -25.503128) (xy 138.758107 -25.448691) (xy 138.77803 -25.3966) (xy 138.805326 -25.347965)
			(xy 138.839412 -25.303822) (xy 138.879561 -25.265113) (xy 138.924919 -25.232662) (xy 138.974519 -25.207161)
			(xy 139.027303 -25.189154) (xy 139.082146 -25.179024) (xy 139.13788 -25.176987) (xy 139.193317 -25.183087)
			(xy 139.247274 -25.197193) (xy 139.298603 -25.219005) (xy 139.346209 -25.248059) (xy 139.389077 -25.283734)
			(xy 139.426294 -25.325271) (xy 139.457067 -25.371784) (xy 139.46565 -25.390094) (xy 155.909262 -25.390094)
			(xy 155.913333 -25.334472) (xy 155.925459 -25.280035) (xy 155.945382 -25.227944) (xy 155.972678 -25.179309)
			(xy 156.006764 -25.135166) (xy 156.046913 -25.096457) (xy 156.092271 -25.064006) (xy 156.141871 -25.038505)
			(xy 156.194655 -25.020498) (xy 156.249498 -25.010368) (xy 156.305232 -25.008331) (xy 156.360669 -25.014431)
			(xy 156.414626 -25.028537) (xy 156.422667 -25.031954) (xy 160.287968 -25.031954) (xy 160.292039 -24.976332)
			(xy 160.304165 -24.921895) (xy 160.324088 -24.869804) (xy 160.351384 -24.821169) (xy 160.38547 -24.777026)
			(xy 160.425619 -24.738317) (xy 160.470977 -24.705866) (xy 160.520577 -24.680365) (xy 160.573361 -24.662358)
			(xy 160.628204 -24.652228) (xy 160.683938 -24.650191) (xy 160.739375 -24.656291) (xy 160.793332 -24.670397)
			(xy 160.844661 -24.692209) (xy 160.892267 -24.721263) (xy 160.935135 -24.756938) (xy 160.936669 -24.75865)
			(xy 162.968684 -24.75865) (xy 162.972755 -24.703028) (xy 162.984881 -24.648591) (xy 163.004804 -24.5965)
			(xy 163.0321 -24.547865) (xy 163.066186 -24.503722) (xy 163.106335 -24.465013) (xy 163.151693 -24.432562)
			(xy 163.201293 -24.407061) (xy 163.254077 -24.389054) (xy 163.30892 -24.378924) (xy 163.364654 -24.376887)
			(xy 163.420091 -24.382987) (xy 163.474048 -24.397093) (xy 163.525377 -24.418905) (xy 163.572983 -24.447959)
			(xy 163.615851 -24.483634) (xy 163.653068 -24.525171) (xy 163.683841 -24.571684) (xy 163.707513 -24.622181)
			(xy 163.723581 -24.675588) (xy 163.731701 -24.730764) (xy 163.73221 -24.75865) (xy 163.731701 -24.786536)
			(xy 163.728628 -24.807418) (xy 174.471328 -24.807418) (xy 174.475399 -24.751796) (xy 174.487525 -24.697359)
			(xy 174.507448 -24.645268) (xy 174.534744 -24.596633) (xy 174.56883 -24.55249) (xy 174.608979 -24.513781)
			(xy 174.654337 -24.48133) (xy 174.703937 -24.455829) (xy 174.756721 -24.437822) (xy 174.811564 -24.427692)
			(xy 174.867298 -24.425655) (xy 174.922735 -24.431755) (xy 174.976692 -24.445861) (xy 175.028021 -24.467673)
			(xy 175.075627 -24.496727) (xy 175.118495 -24.532402) (xy 175.155712 -24.573939) (xy 175.186485 -24.620452)
			(xy 175.210157 -24.670949) (xy 175.226225 -24.724356) (xy 175.234345 -24.779532) (xy 175.234854 -24.807418)
			(xy 176.720244 -24.807418) (xy 176.724315 -24.751796) (xy 176.736441 -24.697359) (xy 176.756364 -24.645268)
			(xy 176.78366 -24.596633) (xy 176.817746 -24.55249) (xy 176.857895 -24.513781) (xy 176.903253 -24.48133)
			(xy 176.952853 -24.455829) (xy 177.005637 -24.437822) (xy 177.06048 -24.427692) (xy 177.116214 -24.425655)
			(xy 177.171651 -24.431755) (xy 177.225608 -24.445861) (xy 177.276937 -24.467673) (xy 177.324543 -24.496727)
			(xy 177.367411 -24.532402) (xy 177.404628 -24.573939) (xy 177.435401 -24.620452) (xy 177.459073 -24.670949)
			(xy 177.475141 -24.724356) (xy 177.483261 -24.779532) (xy 177.48377 -24.807418) (xy 177.483261 -24.835304)
			(xy 177.475141 -24.89048) (xy 177.459073 -24.943887) (xy 177.435401 -24.994384) (xy 177.404628 -25.040897)
			(xy 177.367411 -25.082434) (xy 177.324543 -25.118109) (xy 177.276937 -25.147163) (xy 177.225608 -25.168975)
			(xy 177.171651 -25.183081) (xy 177.116214 -25.189181) (xy 177.06048 -25.187144) (xy 177.005637 -25.177014)
			(xy 176.952853 -25.159007) (xy 176.903253 -25.133506) (xy 176.857895 -25.101055) (xy 176.817746 -25.062346)
			(xy 176.78366 -25.018203) (xy 176.756364 -24.969568) (xy 176.736441 -24.917477) (xy 176.724315 -24.86304)
			(xy 176.720244 -24.807418) (xy 175.234854 -24.807418) (xy 175.234345 -24.835304) (xy 175.226225 -24.89048)
			(xy 175.210157 -24.943887) (xy 175.186485 -24.994384) (xy 175.155712 -25.040897) (xy 175.118495 -25.082434)
			(xy 175.075627 -25.118109) (xy 175.028021 -25.147163) (xy 174.976692 -25.168975) (xy 174.922735 -25.183081)
			(xy 174.867298 -25.189181) (xy 174.811564 -25.187144) (xy 174.756721 -25.177014) (xy 174.703937 -25.159007)
			(xy 174.654337 -25.133506) (xy 174.608979 -25.101055) (xy 174.56883 -25.062346) (xy 174.534744 -25.018203)
			(xy 174.507448 -24.969568) (xy 174.487525 -24.917477) (xy 174.475399 -24.86304) (xy 174.471328 -24.807418)
			(xy 163.728628 -24.807418) (xy 163.723581 -24.841712) (xy 163.707513 -24.895119) (xy 163.683841 -24.945616)
			(xy 163.653068 -24.992129) (xy 163.615851 -25.033666) (xy 163.572983 -25.069341) (xy 163.525377 -25.098395)
			(xy 163.474048 -25.120207) (xy 163.420091 -25.134313) (xy 163.364654 -25.140413) (xy 163.30892 -25.138376)
			(xy 163.254077 -25.128246) (xy 163.201293 -25.110239) (xy 163.151693 -25.084738) (xy 163.106335 -25.052287)
			(xy 163.066186 -25.013578) (xy 163.0321 -24.969435) (xy 163.004804 -24.9208) (xy 162.984881 -24.868709)
			(xy 162.972755 -24.814272) (xy 162.968684 -24.75865) (xy 160.936669 -24.75865) (xy 160.972352 -24.798475)
			(xy 161.003125 -24.844988) (xy 161.026797 -24.895485) (xy 161.042865 -24.948892) (xy 161.050985 -25.004068)
			(xy 161.051494 -25.031954) (xy 161.050985 -25.05984) (xy 161.042865 -25.115016) (xy 161.026797 -25.168423)
			(xy 161.003125 -25.21892) (xy 160.972352 -25.265433) (xy 160.935135 -25.30697) (xy 160.892267 -25.342645)
			(xy 160.844661 -25.371699) (xy 160.793332 -25.393511) (xy 160.739375 -25.407617) (xy 160.683938 -25.413717)
			(xy 160.628204 -25.41168) (xy 160.573361 -25.40155) (xy 160.520577 -25.383543) (xy 160.470977 -25.358042)
			(xy 160.425619 -25.325591) (xy 160.38547 -25.286882) (xy 160.351384 -25.242739) (xy 160.324088 -25.194104)
			(xy 160.304165 -25.142013) (xy 160.292039 -25.087576) (xy 160.287968 -25.031954) (xy 156.422667 -25.031954)
			(xy 156.465955 -25.050349) (xy 156.513561 -25.079403) (xy 156.556429 -25.115078) (xy 156.593646 -25.156615)
			(xy 156.624419 -25.203128) (xy 156.648091 -25.253625) (xy 156.664159 -25.307032) (xy 156.672279 -25.362208)
			(xy 156.672788 -25.390094) (xy 156.672279 -25.41798) (xy 156.664159 -25.473156) (xy 156.648091 -25.526563)
			(xy 156.633002 -25.55875) (xy 164.741858 -25.55875) (xy 164.745929 -25.503128) (xy 164.758055 -25.448691)
			(xy 164.777978 -25.3966) (xy 164.805274 -25.347965) (xy 164.83936 -25.303822) (xy 164.879509 -25.265113)
			(xy 164.924867 -25.232662) (xy 164.974467 -25.207161) (xy 165.027251 -25.189154) (xy 165.082094 -25.179024)
			(xy 165.137828 -25.176987) (xy 165.193265 -25.183087) (xy 165.247222 -25.197193) (xy 165.298551 -25.219005)
			(xy 165.346157 -25.248059) (xy 165.389025 -25.283734) (xy 165.426242 -25.325271) (xy 165.457015 -25.371784)
			(xy 165.465598 -25.390094) (xy 181.90921 -25.390094) (xy 181.913281 -25.334472) (xy 181.925407 -25.280035)
			(xy 181.94533 -25.227944) (xy 181.972626 -25.179309) (xy 182.006712 -25.135166) (xy 182.046861 -25.096457)
			(xy 182.092219 -25.064006) (xy 182.141819 -25.038505) (xy 182.194603 -25.020498) (xy 182.249446 -25.010368)
			(xy 182.30518 -25.008331) (xy 182.360617 -25.014431) (xy 182.414574 -25.028537) (xy 182.422615 -25.031954)
			(xy 186.287916 -25.031954) (xy 186.291987 -24.976332) (xy 186.304113 -24.921895) (xy 186.324036 -24.869804)
			(xy 186.351332 -24.821169) (xy 186.385418 -24.777026) (xy 186.425567 -24.738317) (xy 186.470925 -24.705866)
			(xy 186.520525 -24.680365) (xy 186.573309 -24.662358) (xy 186.628152 -24.652228) (xy 186.683886 -24.650191)
			(xy 186.739323 -24.656291) (xy 186.79328 -24.670397) (xy 186.844609 -24.692209) (xy 186.892215 -24.721263)
			(xy 186.935083 -24.756938) (xy 186.936617 -24.75865) (xy 188.968632 -24.75865) (xy 188.972703 -24.703028)
			(xy 188.984829 -24.648591) (xy 189.004752 -24.5965) (xy 189.032048 -24.547865) (xy 189.066134 -24.503722)
			(xy 189.106283 -24.465013) (xy 189.151641 -24.432562) (xy 189.201241 -24.407061) (xy 189.254025 -24.389054)
			(xy 189.308868 -24.378924) (xy 189.364602 -24.376887) (xy 189.420039 -24.382987) (xy 189.473996 -24.397093)
			(xy 189.525325 -24.418905) (xy 189.572931 -24.447959) (xy 189.615799 -24.483634) (xy 189.653016 -24.525171)
			(xy 189.683789 -24.571684) (xy 189.707461 -24.622181) (xy 189.723529 -24.675588) (xy 189.731649 -24.730764)
			(xy 189.732158 -24.75865) (xy 189.731649 -24.786536) (xy 189.728576 -24.807418) (xy 200.471276 -24.807418)
			(xy 200.475347 -24.751796) (xy 200.487473 -24.697359) (xy 200.507396 -24.645268) (xy 200.534692 -24.596633)
			(xy 200.568778 -24.55249) (xy 200.608927 -24.513781) (xy 200.654285 -24.48133) (xy 200.703885 -24.455829)
			(xy 200.756669 -24.437822) (xy 200.811512 -24.427692) (xy 200.867246 -24.425655) (xy 200.922683 -24.431755)
			(xy 200.97664 -24.445861) (xy 201.027969 -24.467673) (xy 201.075575 -24.496727) (xy 201.118443 -24.532402)
			(xy 201.15566 -24.573939) (xy 201.186433 -24.620452) (xy 201.210105 -24.670949) (xy 201.226173 -24.724356)
			(xy 201.234293 -24.779532) (xy 201.234802 -24.807418) (xy 202.720192 -24.807418) (xy 202.724263 -24.751796)
			(xy 202.736389 -24.697359) (xy 202.756312 -24.645268) (xy 202.783608 -24.596633) (xy 202.817694 -24.55249)
			(xy 202.857843 -24.513781) (xy 202.903201 -24.48133) (xy 202.952801 -24.455829) (xy 203.005585 -24.437822)
			(xy 203.060428 -24.427692) (xy 203.116162 -24.425655) (xy 203.171599 -24.431755) (xy 203.225556 -24.445861)
			(xy 203.276885 -24.467673) (xy 203.324491 -24.496727) (xy 203.367359 -24.532402) (xy 203.404576 -24.573939)
			(xy 203.435349 -24.620452) (xy 203.459021 -24.670949) (xy 203.475089 -24.724356) (xy 203.483209 -24.779532)
			(xy 203.483718 -24.807418) (xy 203.483209 -24.835304) (xy 203.475089 -24.89048) (xy 203.459021 -24.943887)
			(xy 203.435349 -24.994384) (xy 203.404576 -25.040897) (xy 203.367359 -25.082434) (xy 203.324491 -25.118109)
			(xy 203.276885 -25.147163) (xy 203.225556 -25.168975) (xy 203.171599 -25.183081) (xy 203.116162 -25.189181)
			(xy 203.060428 -25.187144) (xy 203.005585 -25.177014) (xy 202.952801 -25.159007) (xy 202.903201 -25.133506)
			(xy 202.857843 -25.101055) (xy 202.817694 -25.062346) (xy 202.783608 -25.018203) (xy 202.756312 -24.969568)
			(xy 202.736389 -24.917477) (xy 202.724263 -24.86304) (xy 202.720192 -24.807418) (xy 201.234802 -24.807418)
			(xy 201.234293 -24.835304) (xy 201.226173 -24.89048) (xy 201.210105 -24.943887) (xy 201.186433 -24.994384)
			(xy 201.15566 -25.040897) (xy 201.118443 -25.082434) (xy 201.075575 -25.118109) (xy 201.027969 -25.147163)
			(xy 200.97664 -25.168975) (xy 200.922683 -25.183081) (xy 200.867246 -25.189181) (xy 200.811512 -25.187144)
			(xy 200.756669 -25.177014) (xy 200.703885 -25.159007) (xy 200.654285 -25.133506) (xy 200.608927 -25.101055)
			(xy 200.568778 -25.062346) (xy 200.534692 -25.018203) (xy 200.507396 -24.969568) (xy 200.487473 -24.917477)
			(xy 200.475347 -24.86304) (xy 200.471276 -24.807418) (xy 189.728576 -24.807418) (xy 189.723529 -24.841712)
			(xy 189.707461 -24.895119) (xy 189.683789 -24.945616) (xy 189.653016 -24.992129) (xy 189.615799 -25.033666)
			(xy 189.572931 -25.069341) (xy 189.525325 -25.098395) (xy 189.473996 -25.120207) (xy 189.420039 -25.134313)
			(xy 189.364602 -25.140413) (xy 189.308868 -25.138376) (xy 189.254025 -25.128246) (xy 189.201241 -25.110239)
			(xy 189.151641 -25.084738) (xy 189.106283 -25.052287) (xy 189.066134 -25.013578) (xy 189.032048 -24.969435)
			(xy 189.004752 -24.9208) (xy 188.984829 -24.868709) (xy 188.972703 -24.814272) (xy 188.968632 -24.75865)
			(xy 186.936617 -24.75865) (xy 186.9723 -24.798475) (xy 187.003073 -24.844988) (xy 187.026745 -24.895485)
			(xy 187.042813 -24.948892) (xy 187.050933 -25.004068) (xy 187.051442 -25.031954) (xy 187.050933 -25.05984)
			(xy 187.042813 -25.115016) (xy 187.026745 -25.168423) (xy 187.003073 -25.21892) (xy 186.9723 -25.265433)
			(xy 186.935083 -25.30697) (xy 186.892215 -25.342645) (xy 186.844609 -25.371699) (xy 186.79328 -25.393511)
			(xy 186.739323 -25.407617) (xy 186.683886 -25.413717) (xy 186.628152 -25.41168) (xy 186.573309 -25.40155)
			(xy 186.520525 -25.383543) (xy 186.470925 -25.358042) (xy 186.425567 -25.325591) (xy 186.385418 -25.286882)
			(xy 186.351332 -25.242739) (xy 186.324036 -25.194104) (xy 186.304113 -25.142013) (xy 186.291987 -25.087576)
			(xy 186.287916 -25.031954) (xy 182.422615 -25.031954) (xy 182.465903 -25.050349) (xy 182.513509 -25.079403)
			(xy 182.556377 -25.115078) (xy 182.593594 -25.156615) (xy 182.624367 -25.203128) (xy 182.648039 -25.253625)
			(xy 182.664107 -25.307032) (xy 182.672227 -25.362208) (xy 182.672736 -25.390094) (xy 182.672227 -25.41798)
			(xy 182.664107 -25.473156) (xy 182.648039 -25.526563) (xy 182.63295 -25.55875) (xy 190.741806 -25.55875)
			(xy 190.745877 -25.503128) (xy 190.758003 -25.448691) (xy 190.777926 -25.3966) (xy 190.805222 -25.347965)
			(xy 190.839308 -25.303822) (xy 190.879457 -25.265113) (xy 190.924815 -25.232662) (xy 190.974415 -25.207161)
			(xy 191.027199 -25.189154) (xy 191.082042 -25.179024) (xy 191.137776 -25.176987) (xy 191.193213 -25.183087)
			(xy 191.24717 -25.197193) (xy 191.298499 -25.219005) (xy 191.346105 -25.248059) (xy 191.388973 -25.283734)
			(xy 191.42619 -25.325271) (xy 191.456963 -25.371784) (xy 191.465546 -25.390094) (xy 207.909158 -25.390094)
			(xy 207.913229 -25.334472) (xy 207.925355 -25.280035) (xy 207.945278 -25.227944) (xy 207.972574 -25.179309)
			(xy 208.00666 -25.135166) (xy 208.046809 -25.096457) (xy 208.092167 -25.064006) (xy 208.141767 -25.038505)
			(xy 208.194551 -25.020498) (xy 208.249394 -25.010368) (xy 208.305128 -25.008331) (xy 208.360565 -25.014431)
			(xy 208.414522 -25.028537) (xy 208.422563 -25.031954) (xy 212.287864 -25.031954) (xy 212.291935 -24.976332)
			(xy 212.304061 -24.921895) (xy 212.323984 -24.869804) (xy 212.35128 -24.821169) (xy 212.385366 -24.777026)
			(xy 212.425515 -24.738317) (xy 212.470873 -24.705866) (xy 212.520473 -24.680365) (xy 212.573257 -24.662358)
			(xy 212.6281 -24.652228) (xy 212.683834 -24.650191) (xy 212.739271 -24.656291) (xy 212.793228 -24.670397)
			(xy 212.844557 -24.692209) (xy 212.892163 -24.721263) (xy 212.935031 -24.756938) (xy 212.936565 -24.75865)
			(xy 214.96858 -24.75865) (xy 214.972651 -24.703028) (xy 214.984777 -24.648591) (xy 215.0047 -24.5965)
			(xy 215.031996 -24.547865) (xy 215.066082 -24.503722) (xy 215.106231 -24.465013) (xy 215.151589 -24.432562)
			(xy 215.201189 -24.407061) (xy 215.253973 -24.389054) (xy 215.308816 -24.378924) (xy 215.36455 -24.376887)
			(xy 215.419987 -24.382987) (xy 215.473944 -24.397093) (xy 215.525273 -24.418905) (xy 215.572879 -24.447959)
			(xy 215.615747 -24.483634) (xy 215.652964 -24.525171) (xy 215.683737 -24.571684) (xy 215.707409 -24.622181)
			(xy 215.723477 -24.675588) (xy 215.731597 -24.730764) (xy 215.732106 -24.75865) (xy 215.731597 -24.786536)
			(xy 215.728524 -24.807418) (xy 238.571276 -24.807418) (xy 238.575347 -24.751796) (xy 238.587473 -24.697359)
			(xy 238.607396 -24.645268) (xy 238.634692 -24.596633) (xy 238.668778 -24.55249) (xy 238.708927 -24.513781)
			(xy 238.754285 -24.48133) (xy 238.803885 -24.455829) (xy 238.856669 -24.437822) (xy 238.911512 -24.427692)
			(xy 238.967246 -24.425655) (xy 239.022683 -24.431755) (xy 239.07664 -24.445861) (xy 239.127969 -24.467673)
			(xy 239.175575 -24.496727) (xy 239.218443 -24.532402) (xy 239.25566 -24.573939) (xy 239.286433 -24.620452)
			(xy 239.310105 -24.670949) (xy 239.326173 -24.724356) (xy 239.334293 -24.779532) (xy 239.334802 -24.807418)
			(xy 240.820192 -24.807418) (xy 240.824263 -24.751796) (xy 240.836389 -24.697359) (xy 240.856312 -24.645268)
			(xy 240.883608 -24.596633) (xy 240.917694 -24.55249) (xy 240.957843 -24.513781) (xy 241.003201 -24.48133)
			(xy 241.052801 -24.455829) (xy 241.105585 -24.437822) (xy 241.160428 -24.427692) (xy 241.216162 -24.425655)
			(xy 241.271599 -24.431755) (xy 241.325556 -24.445861) (xy 241.376885 -24.467673) (xy 241.424491 -24.496727)
			(xy 241.467359 -24.532402) (xy 241.504576 -24.573939) (xy 241.535349 -24.620452) (xy 241.559021 -24.670949)
			(xy 241.575089 -24.724356) (xy 241.583209 -24.779532) (xy 241.583718 -24.807418) (xy 241.583209 -24.835304)
			(xy 241.575089 -24.89048) (xy 241.559021 -24.943887) (xy 241.535349 -24.994384) (xy 241.504576 -25.040897)
			(xy 241.467359 -25.082434) (xy 241.424491 -25.118109) (xy 241.376885 -25.147163) (xy 241.325556 -25.168975)
			(xy 241.271599 -25.183081) (xy 241.216162 -25.189181) (xy 241.160428 -25.187144) (xy 241.105585 -25.177014)
			(xy 241.052801 -25.159007) (xy 241.003201 -25.133506) (xy 240.957843 -25.101055) (xy 240.917694 -25.062346)
			(xy 240.883608 -25.018203) (xy 240.856312 -24.969568) (xy 240.836389 -24.917477) (xy 240.824263 -24.86304)
			(xy 240.820192 -24.807418) (xy 239.334802 -24.807418) (xy 239.334293 -24.835304) (xy 239.326173 -24.89048)
			(xy 239.310105 -24.943887) (xy 239.286433 -24.994384) (xy 239.25566 -25.040897) (xy 239.218443 -25.082434)
			(xy 239.175575 -25.118109) (xy 239.127969 -25.147163) (xy 239.07664 -25.168975) (xy 239.022683 -25.183081)
			(xy 238.967246 -25.189181) (xy 238.911512 -25.187144) (xy 238.856669 -25.177014) (xy 238.803885 -25.159007)
			(xy 238.754285 -25.133506) (xy 238.708927 -25.101055) (xy 238.668778 -25.062346) (xy 238.634692 -25.018203)
			(xy 238.607396 -24.969568) (xy 238.587473 -24.917477) (xy 238.575347 -24.86304) (xy 238.571276 -24.807418)
			(xy 215.728524 -24.807418) (xy 215.723477 -24.841712) (xy 215.707409 -24.895119) (xy 215.683737 -24.945616)
			(xy 215.652964 -24.992129) (xy 215.615747 -25.033666) (xy 215.572879 -25.069341) (xy 215.525273 -25.098395)
			(xy 215.473944 -25.120207) (xy 215.419987 -25.134313) (xy 215.36455 -25.140413) (xy 215.308816 -25.138376)
			(xy 215.253973 -25.128246) (xy 215.201189 -25.110239) (xy 215.151589 -25.084738) (xy 215.106231 -25.052287)
			(xy 215.066082 -25.013578) (xy 215.031996 -24.969435) (xy 215.0047 -24.9208) (xy 214.984777 -24.868709)
			(xy 214.972651 -24.814272) (xy 214.96858 -24.75865) (xy 212.936565 -24.75865) (xy 212.972248 -24.798475)
			(xy 213.003021 -24.844988) (xy 213.026693 -24.895485) (xy 213.042761 -24.948892) (xy 213.050881 -25.004068)
			(xy 213.05139 -25.031954) (xy 213.050881 -25.05984) (xy 213.042761 -25.115016) (xy 213.026693 -25.168423)
			(xy 213.003021 -25.21892) (xy 212.972248 -25.265433) (xy 212.935031 -25.30697) (xy 212.892163 -25.342645)
			(xy 212.844557 -25.371699) (xy 212.793228 -25.393511) (xy 212.739271 -25.407617) (xy 212.683834 -25.413717)
			(xy 212.6281 -25.41168) (xy 212.573257 -25.40155) (xy 212.520473 -25.383543) (xy 212.470873 -25.358042)
			(xy 212.425515 -25.325591) (xy 212.385366 -25.286882) (xy 212.35128 -25.242739) (xy 212.323984 -25.194104)
			(xy 212.304061 -25.142013) (xy 212.291935 -25.087576) (xy 212.287864 -25.031954) (xy 208.422563 -25.031954)
			(xy 208.465851 -25.050349) (xy 208.513457 -25.079403) (xy 208.556325 -25.115078) (xy 208.593542 -25.156615)
			(xy 208.624315 -25.203128) (xy 208.647987 -25.253625) (xy 208.664055 -25.307032) (xy 208.672175 -25.362208)
			(xy 208.672684 -25.390094) (xy 208.672175 -25.41798) (xy 208.664055 -25.473156) (xy 208.647987 -25.526563)
			(xy 208.632898 -25.55875) (xy 216.741754 -25.55875) (xy 216.745825 -25.503128) (xy 216.757951 -25.448691)
			(xy 216.777874 -25.3966) (xy 216.80517 -25.347965) (xy 216.839256 -25.303822) (xy 216.879405 -25.265113)
			(xy 216.924763 -25.232662) (xy 216.974363 -25.207161) (xy 217.027147 -25.189154) (xy 217.08199 -25.179024)
			(xy 217.137724 -25.176987) (xy 217.193161 -25.183087) (xy 217.247118 -25.197193) (xy 217.298447 -25.219005)
			(xy 217.346053 -25.248059) (xy 217.388921 -25.283734) (xy 217.426138 -25.325271) (xy 217.456911 -25.371784)
			(xy 217.465494 -25.390094) (xy 246.009158 -25.390094) (xy 246.013229 -25.334472) (xy 246.025355 -25.280035)
			(xy 246.045278 -25.227944) (xy 246.072574 -25.179309) (xy 246.10666 -25.135166) (xy 246.146809 -25.096457)
			(xy 246.192167 -25.064006) (xy 246.241767 -25.038505) (xy 246.294551 -25.020498) (xy 246.349394 -25.010368)
			(xy 246.405128 -25.008331) (xy 246.460565 -25.014431) (xy 246.514522 -25.028537) (xy 246.522563 -25.031954)
			(xy 250.387864 -25.031954) (xy 250.391935 -24.976332) (xy 250.404061 -24.921895) (xy 250.423984 -24.869804)
			(xy 250.45128 -24.821169) (xy 250.485366 -24.777026) (xy 250.525515 -24.738317) (xy 250.570873 -24.705866)
			(xy 250.620473 -24.680365) (xy 250.673257 -24.662358) (xy 250.7281 -24.652228) (xy 250.783834 -24.650191)
			(xy 250.839271 -24.656291) (xy 250.893228 -24.670397) (xy 250.944557 -24.692209) (xy 250.992163 -24.721263)
			(xy 251.035031 -24.756938) (xy 251.036565 -24.75865) (xy 253.06858 -24.75865) (xy 253.072651 -24.703028)
			(xy 253.084777 -24.648591) (xy 253.1047 -24.5965) (xy 253.131996 -24.547865) (xy 253.166082 -24.503722)
			(xy 253.206231 -24.465013) (xy 253.251589 -24.432562) (xy 253.301189 -24.407061) (xy 253.353973 -24.389054)
			(xy 253.408816 -24.378924) (xy 253.46455 -24.376887) (xy 253.519987 -24.382987) (xy 253.573944 -24.397093)
			(xy 253.625273 -24.418905) (xy 253.672879 -24.447959) (xy 253.715747 -24.483634) (xy 253.752964 -24.525171)
			(xy 253.783737 -24.571684) (xy 253.807409 -24.622181) (xy 253.823477 -24.675588) (xy 253.831597 -24.730764)
			(xy 253.832106 -24.75865) (xy 253.831597 -24.786536) (xy 253.828524 -24.807418) (xy 264.571224 -24.807418)
			(xy 264.575295 -24.751796) (xy 264.587421 -24.697359) (xy 264.607344 -24.645268) (xy 264.63464 -24.596633)
			(xy 264.668726 -24.55249) (xy 264.708875 -24.513781) (xy 264.754233 -24.48133) (xy 264.803833 -24.455829)
			(xy 264.856617 -24.437822) (xy 264.91146 -24.427692) (xy 264.967194 -24.425655) (xy 265.022631 -24.431755)
			(xy 265.076588 -24.445861) (xy 265.127917 -24.467673) (xy 265.175523 -24.496727) (xy 265.218391 -24.532402)
			(xy 265.255608 -24.573939) (xy 265.286381 -24.620452) (xy 265.310053 -24.670949) (xy 265.326121 -24.724356)
			(xy 265.334241 -24.779532) (xy 265.33475 -24.807418) (xy 266.82014 -24.807418) (xy 266.824211 -24.751796)
			(xy 266.836337 -24.697359) (xy 266.85626 -24.645268) (xy 266.883556 -24.596633) (xy 266.917642 -24.55249)
			(xy 266.957791 -24.513781) (xy 267.003149 -24.48133) (xy 267.052749 -24.455829) (xy 267.105533 -24.437822)
			(xy 267.160376 -24.427692) (xy 267.21611 -24.425655) (xy 267.271547 -24.431755) (xy 267.325504 -24.445861)
			(xy 267.376833 -24.467673) (xy 267.424439 -24.496727) (xy 267.467307 -24.532402) (xy 267.504524 -24.573939)
			(xy 267.535297 -24.620452) (xy 267.558969 -24.670949) (xy 267.575037 -24.724356) (xy 267.583157 -24.779532)
			(xy 267.583666 -24.807418) (xy 267.583157 -24.835304) (xy 267.575037 -24.89048) (xy 267.558969 -24.943887)
			(xy 267.535297 -24.994384) (xy 267.504524 -25.040897) (xy 267.467307 -25.082434) (xy 267.424439 -25.118109)
			(xy 267.376833 -25.147163) (xy 267.325504 -25.168975) (xy 267.271547 -25.183081) (xy 267.21611 -25.189181)
			(xy 267.160376 -25.187144) (xy 267.105533 -25.177014) (xy 267.052749 -25.159007) (xy 267.003149 -25.133506)
			(xy 266.957791 -25.101055) (xy 266.917642 -25.062346) (xy 266.883556 -25.018203) (xy 266.85626 -24.969568)
			(xy 266.836337 -24.917477) (xy 266.824211 -24.86304) (xy 266.82014 -24.807418) (xy 265.33475 -24.807418)
			(xy 265.334241 -24.835304) (xy 265.326121 -24.89048) (xy 265.310053 -24.943887) (xy 265.286381 -24.994384)
			(xy 265.255608 -25.040897) (xy 265.218391 -25.082434) (xy 265.175523 -25.118109) (xy 265.127917 -25.147163)
			(xy 265.076588 -25.168975) (xy 265.022631 -25.183081) (xy 264.967194 -25.189181) (xy 264.91146 -25.187144)
			(xy 264.856617 -25.177014) (xy 264.803833 -25.159007) (xy 264.754233 -25.133506) (xy 264.708875 -25.101055)
			(xy 264.668726 -25.062346) (xy 264.63464 -25.018203) (xy 264.607344 -24.969568) (xy 264.587421 -24.917477)
			(xy 264.575295 -24.86304) (xy 264.571224 -24.807418) (xy 253.828524 -24.807418) (xy 253.823477 -24.841712)
			(xy 253.807409 -24.895119) (xy 253.783737 -24.945616) (xy 253.752964 -24.992129) (xy 253.715747 -25.033666)
			(xy 253.672879 -25.069341) (xy 253.625273 -25.098395) (xy 253.573944 -25.120207) (xy 253.519987 -25.134313)
			(xy 253.46455 -25.140413) (xy 253.408816 -25.138376) (xy 253.353973 -25.128246) (xy 253.301189 -25.110239)
			(xy 253.251589 -25.084738) (xy 253.206231 -25.052287) (xy 253.166082 -25.013578) (xy 253.131996 -24.969435)
			(xy 253.1047 -24.9208) (xy 253.084777 -24.868709) (xy 253.072651 -24.814272) (xy 253.06858 -24.75865)
			(xy 251.036565 -24.75865) (xy 251.072248 -24.798475) (xy 251.103021 -24.844988) (xy 251.126693 -24.895485)
			(xy 251.142761 -24.948892) (xy 251.150881 -25.004068) (xy 251.15139 -25.031954) (xy 251.150881 -25.05984)
			(xy 251.142761 -25.115016) (xy 251.126693 -25.168423) (xy 251.103021 -25.21892) (xy 251.072248 -25.265433)
			(xy 251.035031 -25.30697) (xy 250.992163 -25.342645) (xy 250.944557 -25.371699) (xy 250.893228 -25.393511)
			(xy 250.839271 -25.407617) (xy 250.783834 -25.413717) (xy 250.7281 -25.41168) (xy 250.673257 -25.40155)
			(xy 250.620473 -25.383543) (xy 250.570873 -25.358042) (xy 250.525515 -25.325591) (xy 250.485366 -25.286882)
			(xy 250.45128 -25.242739) (xy 250.423984 -25.194104) (xy 250.404061 -25.142013) (xy 250.391935 -25.087576)
			(xy 250.387864 -25.031954) (xy 246.522563 -25.031954) (xy 246.565851 -25.050349) (xy 246.613457 -25.079403)
			(xy 246.656325 -25.115078) (xy 246.693542 -25.156615) (xy 246.724315 -25.203128) (xy 246.747987 -25.253625)
			(xy 246.764055 -25.307032) (xy 246.772175 -25.362208) (xy 246.772684 -25.390094) (xy 246.772175 -25.41798)
			(xy 246.764055 -25.473156) (xy 246.747987 -25.526563) (xy 246.732898 -25.55875) (xy 254.841754 -25.55875)
			(xy 254.845825 -25.503128) (xy 254.857951 -25.448691) (xy 254.877874 -25.3966) (xy 254.90517 -25.347965)
			(xy 254.939256 -25.303822) (xy 254.979405 -25.265113) (xy 255.024763 -25.232662) (xy 255.074363 -25.207161)
			(xy 255.127147 -25.189154) (xy 255.18199 -25.179024) (xy 255.237724 -25.176987) (xy 255.293161 -25.183087)
			(xy 255.347118 -25.197193) (xy 255.398447 -25.219005) (xy 255.446053 -25.248059) (xy 255.488921 -25.283734)
			(xy 255.526138 -25.325271) (xy 255.556911 -25.371784) (xy 255.565494 -25.390094) (xy 272.009106 -25.390094)
			(xy 272.013177 -25.334472) (xy 272.025303 -25.280035) (xy 272.045226 -25.227944) (xy 272.072522 -25.179309)
			(xy 272.106608 -25.135166) (xy 272.146757 -25.096457) (xy 272.192115 -25.064006) (xy 272.241715 -25.038505)
			(xy 272.294499 -25.020498) (xy 272.349342 -25.010368) (xy 272.405076 -25.008331) (xy 272.460513 -25.014431)
			(xy 272.51447 -25.028537) (xy 272.522511 -25.031954) (xy 276.387812 -25.031954) (xy 276.391883 -24.976332)
			(xy 276.404009 -24.921895) (xy 276.423932 -24.869804) (xy 276.451228 -24.821169) (xy 276.485314 -24.777026)
			(xy 276.525463 -24.738317) (xy 276.570821 -24.705866) (xy 276.620421 -24.680365) (xy 276.673205 -24.662358)
			(xy 276.728048 -24.652228) (xy 276.783782 -24.650191) (xy 276.839219 -24.656291) (xy 276.893176 -24.670397)
			(xy 276.944505 -24.692209) (xy 276.992111 -24.721263) (xy 277.034979 -24.756938) (xy 277.036513 -24.75865)
			(xy 279.068528 -24.75865) (xy 279.072599 -24.703028) (xy 279.084725 -24.648591) (xy 279.104648 -24.5965)
			(xy 279.131944 -24.547865) (xy 279.16603 -24.503722) (xy 279.206179 -24.465013) (xy 279.251537 -24.432562)
			(xy 279.301137 -24.407061) (xy 279.353921 -24.389054) (xy 279.408764 -24.378924) (xy 279.464498 -24.376887)
			(xy 279.519935 -24.382987) (xy 279.573892 -24.397093) (xy 279.625221 -24.418905) (xy 279.672827 -24.447959)
			(xy 279.715695 -24.483634) (xy 279.752912 -24.525171) (xy 279.783685 -24.571684) (xy 279.807357 -24.622181)
			(xy 279.823425 -24.675588) (xy 279.831545 -24.730764) (xy 279.832054 -24.75865) (xy 279.831545 -24.786536)
			(xy 279.828472 -24.807418) (xy 290.571172 -24.807418) (xy 290.575243 -24.751796) (xy 290.587369 -24.697359)
			(xy 290.607292 -24.645268) (xy 290.634588 -24.596633) (xy 290.668674 -24.55249) (xy 290.708823 -24.513781)
			(xy 290.754181 -24.48133) (xy 290.803781 -24.455829) (xy 290.856565 -24.437822) (xy 290.911408 -24.427692)
			(xy 290.967142 -24.425655) (xy 291.022579 -24.431755) (xy 291.076536 -24.445861) (xy 291.127865 -24.467673)
			(xy 291.175471 -24.496727) (xy 291.218339 -24.532402) (xy 291.255556 -24.573939) (xy 291.286329 -24.620452)
			(xy 291.310001 -24.670949) (xy 291.326069 -24.724356) (xy 291.334189 -24.779532) (xy 291.334698 -24.807418)
			(xy 292.820088 -24.807418) (xy 292.824159 -24.751796) (xy 292.836285 -24.697359) (xy 292.856208 -24.645268)
			(xy 292.883504 -24.596633) (xy 292.91759 -24.55249) (xy 292.957739 -24.513781) (xy 293.003097 -24.48133)
			(xy 293.052697 -24.455829) (xy 293.105481 -24.437822) (xy 293.160324 -24.427692) (xy 293.216058 -24.425655)
			(xy 293.271495 -24.431755) (xy 293.325452 -24.445861) (xy 293.376781 -24.467673) (xy 293.424387 -24.496727)
			(xy 293.467255 -24.532402) (xy 293.504472 -24.573939) (xy 293.535245 -24.620452) (xy 293.558917 -24.670949)
			(xy 293.574985 -24.724356) (xy 293.583105 -24.779532) (xy 293.583614 -24.807418) (xy 293.583105 -24.835304)
			(xy 293.574985 -24.89048) (xy 293.558917 -24.943887) (xy 293.535245 -24.994384) (xy 293.504472 -25.040897)
			(xy 293.467255 -25.082434) (xy 293.424387 -25.118109) (xy 293.376781 -25.147163) (xy 293.325452 -25.168975)
			(xy 293.271495 -25.183081) (xy 293.216058 -25.189181) (xy 293.160324 -25.187144) (xy 293.105481 -25.177014)
			(xy 293.052697 -25.159007) (xy 293.003097 -25.133506) (xy 292.957739 -25.101055) (xy 292.91759 -25.062346)
			(xy 292.883504 -25.018203) (xy 292.856208 -24.969568) (xy 292.836285 -24.917477) (xy 292.824159 -24.86304)
			(xy 292.820088 -24.807418) (xy 291.334698 -24.807418) (xy 291.334189 -24.835304) (xy 291.326069 -24.89048)
			(xy 291.310001 -24.943887) (xy 291.286329 -24.994384) (xy 291.255556 -25.040897) (xy 291.218339 -25.082434)
			(xy 291.175471 -25.118109) (xy 291.127865 -25.147163) (xy 291.076536 -25.168975) (xy 291.022579 -25.183081)
			(xy 290.967142 -25.189181) (xy 290.911408 -25.187144) (xy 290.856565 -25.177014) (xy 290.803781 -25.159007)
			(xy 290.754181 -25.133506) (xy 290.708823 -25.101055) (xy 290.668674 -25.062346) (xy 290.634588 -25.018203)
			(xy 290.607292 -24.969568) (xy 290.587369 -24.917477) (xy 290.575243 -24.86304) (xy 290.571172 -24.807418)
			(xy 279.828472 -24.807418) (xy 279.823425 -24.841712) (xy 279.807357 -24.895119) (xy 279.783685 -24.945616)
			(xy 279.752912 -24.992129) (xy 279.715695 -25.033666) (xy 279.672827 -25.069341) (xy 279.625221 -25.098395)
			(xy 279.573892 -25.120207) (xy 279.519935 -25.134313) (xy 279.464498 -25.140413) (xy 279.408764 -25.138376)
			(xy 279.353921 -25.128246) (xy 279.301137 -25.110239) (xy 279.251537 -25.084738) (xy 279.206179 -25.052287)
			(xy 279.16603 -25.013578) (xy 279.131944 -24.969435) (xy 279.104648 -24.9208) (xy 279.084725 -24.868709)
			(xy 279.072599 -24.814272) (xy 279.068528 -24.75865) (xy 277.036513 -24.75865) (xy 277.072196 -24.798475)
			(xy 277.102969 -24.844988) (xy 277.126641 -24.895485) (xy 277.142709 -24.948892) (xy 277.150829 -25.004068)
			(xy 277.151338 -25.031954) (xy 277.150829 -25.05984) (xy 277.142709 -25.115016) (xy 277.126641 -25.168423)
			(xy 277.102969 -25.21892) (xy 277.072196 -25.265433) (xy 277.034979 -25.30697) (xy 276.992111 -25.342645)
			(xy 276.944505 -25.371699) (xy 276.893176 -25.393511) (xy 276.839219 -25.407617) (xy 276.783782 -25.413717)
			(xy 276.728048 -25.41168) (xy 276.673205 -25.40155) (xy 276.620421 -25.383543) (xy 276.570821 -25.358042)
			(xy 276.525463 -25.325591) (xy 276.485314 -25.286882) (xy 276.451228 -25.242739) (xy 276.423932 -25.194104)
			(xy 276.404009 -25.142013) (xy 276.391883 -25.087576) (xy 276.387812 -25.031954) (xy 272.522511 -25.031954)
			(xy 272.565799 -25.050349) (xy 272.613405 -25.079403) (xy 272.656273 -25.115078) (xy 272.69349 -25.156615)
			(xy 272.724263 -25.203128) (xy 272.747935 -25.253625) (xy 272.764003 -25.307032) (xy 272.772123 -25.362208)
			(xy 272.772632 -25.390094) (xy 272.772123 -25.41798) (xy 272.764003 -25.473156) (xy 272.747935 -25.526563)
			(xy 272.732846 -25.55875) (xy 280.841702 -25.55875) (xy 280.845773 -25.503128) (xy 280.857899 -25.448691)
			(xy 280.877822 -25.3966) (xy 280.905118 -25.347965) (xy 280.939204 -25.303822) (xy 280.979353 -25.265113)
			(xy 281.024711 -25.232662) (xy 281.074311 -25.207161) (xy 281.127095 -25.189154) (xy 281.181938 -25.179024)
			(xy 281.237672 -25.176987) (xy 281.293109 -25.183087) (xy 281.347066 -25.197193) (xy 281.398395 -25.219005)
			(xy 281.446001 -25.248059) (xy 281.488869 -25.283734) (xy 281.526086 -25.325271) (xy 281.556859 -25.371784)
			(xy 281.565442 -25.390094) (xy 298.009054 -25.390094) (xy 298.013125 -25.334472) (xy 298.025251 -25.280035)
			(xy 298.045174 -25.227944) (xy 298.07247 -25.179309) (xy 298.106556 -25.135166) (xy 298.146705 -25.096457)
			(xy 298.192063 -25.064006) (xy 298.241663 -25.038505) (xy 298.294447 -25.020498) (xy 298.34929 -25.010368)
			(xy 298.405024 -25.008331) (xy 298.460461 -25.014431) (xy 298.514418 -25.028537) (xy 298.522459 -25.031954)
			(xy 302.38776 -25.031954) (xy 302.391831 -24.976332) (xy 302.403957 -24.921895) (xy 302.42388 -24.869804)
			(xy 302.451176 -24.821169) (xy 302.485262 -24.777026) (xy 302.525411 -24.738317) (xy 302.570769 -24.705866)
			(xy 302.620369 -24.680365) (xy 302.673153 -24.662358) (xy 302.727996 -24.652228) (xy 302.78373 -24.650191)
			(xy 302.839167 -24.656291) (xy 302.893124 -24.670397) (xy 302.944453 -24.692209) (xy 302.992059 -24.721263)
			(xy 303.034927 -24.756938) (xy 303.036461 -24.75865) (xy 305.068476 -24.75865) (xy 305.072547 -24.703028)
			(xy 305.084673 -24.648591) (xy 305.104596 -24.5965) (xy 305.131892 -24.547865) (xy 305.165978 -24.503722)
			(xy 305.206127 -24.465013) (xy 305.251485 -24.432562) (xy 305.301085 -24.407061) (xy 305.353869 -24.389054)
			(xy 305.408712 -24.378924) (xy 305.464446 -24.376887) (xy 305.519883 -24.382987) (xy 305.57384 -24.397093)
			(xy 305.625169 -24.418905) (xy 305.672775 -24.447959) (xy 305.715643 -24.483634) (xy 305.75286 -24.525171)
			(xy 305.783633 -24.571684) (xy 305.807305 -24.622181) (xy 305.823373 -24.675588) (xy 305.831493 -24.730764)
			(xy 305.832002 -24.75865) (xy 305.831493 -24.786536) (xy 305.82842 -24.807418) (xy 316.57112 -24.807418)
			(xy 316.575191 -24.751796) (xy 316.587317 -24.697359) (xy 316.60724 -24.645268) (xy 316.634536 -24.596633)
			(xy 316.668622 -24.55249) (xy 316.708771 -24.513781) (xy 316.754129 -24.48133) (xy 316.803729 -24.455829)
			(xy 316.856513 -24.437822) (xy 316.911356 -24.427692) (xy 316.96709 -24.425655) (xy 317.022527 -24.431755)
			(xy 317.076484 -24.445861) (xy 317.127813 -24.467673) (xy 317.175419 -24.496727) (xy 317.218287 -24.532402)
			(xy 317.255504 -24.573939) (xy 317.286277 -24.620452) (xy 317.309949 -24.670949) (xy 317.326017 -24.724356)
			(xy 317.334137 -24.779532) (xy 317.334646 -24.807418) (xy 318.820036 -24.807418) (xy 318.824107 -24.751796)
			(xy 318.836233 -24.697359) (xy 318.856156 -24.645268) (xy 318.883452 -24.596633) (xy 318.917538 -24.55249)
			(xy 318.957687 -24.513781) (xy 319.003045 -24.48133) (xy 319.052645 -24.455829) (xy 319.105429 -24.437822)
			(xy 319.160272 -24.427692) (xy 319.216006 -24.425655) (xy 319.271443 -24.431755) (xy 319.3254 -24.445861)
			(xy 319.376729 -24.467673) (xy 319.424335 -24.496727) (xy 319.467203 -24.532402) (xy 319.50442 -24.573939)
			(xy 319.535193 -24.620452) (xy 319.558865 -24.670949) (xy 319.574933 -24.724356) (xy 319.583053 -24.779532)
			(xy 319.583562 -24.807418) (xy 319.583053 -24.835304) (xy 319.574933 -24.89048) (xy 319.558865 -24.943887)
			(xy 319.535193 -24.994384) (xy 319.50442 -25.040897) (xy 319.467203 -25.082434) (xy 319.424335 -25.118109)
			(xy 319.376729 -25.147163) (xy 319.3254 -25.168975) (xy 319.271443 -25.183081) (xy 319.216006 -25.189181)
			(xy 319.160272 -25.187144) (xy 319.105429 -25.177014) (xy 319.052645 -25.159007) (xy 319.003045 -25.133506)
			(xy 318.957687 -25.101055) (xy 318.917538 -25.062346) (xy 318.883452 -25.018203) (xy 318.856156 -24.969568)
			(xy 318.836233 -24.917477) (xy 318.824107 -24.86304) (xy 318.820036 -24.807418) (xy 317.334646 -24.807418)
			(xy 317.334137 -24.835304) (xy 317.326017 -24.89048) (xy 317.309949 -24.943887) (xy 317.286277 -24.994384)
			(xy 317.255504 -25.040897) (xy 317.218287 -25.082434) (xy 317.175419 -25.118109) (xy 317.127813 -25.147163)
			(xy 317.076484 -25.168975) (xy 317.022527 -25.183081) (xy 316.96709 -25.189181) (xy 316.911356 -25.187144)
			(xy 316.856513 -25.177014) (xy 316.803729 -25.159007) (xy 316.754129 -25.133506) (xy 316.708771 -25.101055)
			(xy 316.668622 -25.062346) (xy 316.634536 -25.018203) (xy 316.60724 -24.969568) (xy 316.587317 -24.917477)
			(xy 316.575191 -24.86304) (xy 316.57112 -24.807418) (xy 305.82842 -24.807418) (xy 305.823373 -24.841712)
			(xy 305.807305 -24.895119) (xy 305.783633 -24.945616) (xy 305.75286 -24.992129) (xy 305.715643 -25.033666)
			(xy 305.672775 -25.069341) (xy 305.625169 -25.098395) (xy 305.57384 -25.120207) (xy 305.519883 -25.134313)
			(xy 305.464446 -25.140413) (xy 305.408712 -25.138376) (xy 305.353869 -25.128246) (xy 305.301085 -25.110239)
			(xy 305.251485 -25.084738) (xy 305.206127 -25.052287) (xy 305.165978 -25.013578) (xy 305.131892 -24.969435)
			(xy 305.104596 -24.9208) (xy 305.084673 -24.868709) (xy 305.072547 -24.814272) (xy 305.068476 -24.75865)
			(xy 303.036461 -24.75865) (xy 303.072144 -24.798475) (xy 303.102917 -24.844988) (xy 303.126589 -24.895485)
			(xy 303.142657 -24.948892) (xy 303.150777 -25.004068) (xy 303.151286 -25.031954) (xy 303.150777 -25.05984)
			(xy 303.142657 -25.115016) (xy 303.126589 -25.168423) (xy 303.102917 -25.21892) (xy 303.072144 -25.265433)
			(xy 303.034927 -25.30697) (xy 302.992059 -25.342645) (xy 302.944453 -25.371699) (xy 302.893124 -25.393511)
			(xy 302.839167 -25.407617) (xy 302.78373 -25.413717) (xy 302.727996 -25.41168) (xy 302.673153 -25.40155)
			(xy 302.620369 -25.383543) (xy 302.570769 -25.358042) (xy 302.525411 -25.325591) (xy 302.485262 -25.286882)
			(xy 302.451176 -25.242739) (xy 302.42388 -25.194104) (xy 302.403957 -25.142013) (xy 302.391831 -25.087576)
			(xy 302.38776 -25.031954) (xy 298.522459 -25.031954) (xy 298.565747 -25.050349) (xy 298.613353 -25.079403)
			(xy 298.656221 -25.115078) (xy 298.693438 -25.156615) (xy 298.724211 -25.203128) (xy 298.747883 -25.253625)
			(xy 298.763951 -25.307032) (xy 298.772071 -25.362208) (xy 298.77258 -25.390094) (xy 298.772071 -25.41798)
			(xy 298.763951 -25.473156) (xy 298.747883 -25.526563) (xy 298.732794 -25.55875) (xy 306.84165 -25.55875)
			(xy 306.845721 -25.503128) (xy 306.857847 -25.448691) (xy 306.87777 -25.3966) (xy 306.905066 -25.347965)
			(xy 306.939152 -25.303822) (xy 306.979301 -25.265113) (xy 307.024659 -25.232662) (xy 307.074259 -25.207161)
			(xy 307.127043 -25.189154) (xy 307.181886 -25.179024) (xy 307.23762 -25.176987) (xy 307.293057 -25.183087)
			(xy 307.347014 -25.197193) (xy 307.398343 -25.219005) (xy 307.445949 -25.248059) (xy 307.488817 -25.283734)
			(xy 307.526034 -25.325271) (xy 307.556807 -25.371784) (xy 307.56539 -25.390094) (xy 324.009002 -25.390094)
			(xy 324.013073 -25.334472) (xy 324.025199 -25.280035) (xy 324.045122 -25.227944) (xy 324.072418 -25.179309)
			(xy 324.106504 -25.135166) (xy 324.146653 -25.096457) (xy 324.192011 -25.064006) (xy 324.241611 -25.038505)
			(xy 324.294395 -25.020498) (xy 324.349238 -25.010368) (xy 324.404972 -25.008331) (xy 324.460409 -25.014431)
			(xy 324.514366 -25.028537) (xy 324.522407 -25.031954) (xy 328.387708 -25.031954) (xy 328.391779 -24.976332)
			(xy 328.403905 -24.921895) (xy 328.423828 -24.869804) (xy 328.451124 -24.821169) (xy 328.48521 -24.777026)
			(xy 328.525359 -24.738317) (xy 328.570717 -24.705866) (xy 328.620317 -24.680365) (xy 328.673101 -24.662358)
			(xy 328.727944 -24.652228) (xy 328.783678 -24.650191) (xy 328.839115 -24.656291) (xy 328.893072 -24.670397)
			(xy 328.944401 -24.692209) (xy 328.992007 -24.721263) (xy 329.034875 -24.756938) (xy 329.072092 -24.798475)
			(xy 329.102865 -24.844988) (xy 329.126537 -24.895485) (xy 329.142605 -24.948892) (xy 329.150725 -25.004068)
			(xy 329.151234 -25.031954) (xy 329.150725 -25.05984) (xy 329.142605 -25.115016) (xy 329.126537 -25.168423)
			(xy 329.102865 -25.21892) (xy 329.072092 -25.265433) (xy 329.034875 -25.30697) (xy 328.992007 -25.342645)
			(xy 328.944401 -25.371699) (xy 328.893072 -25.393511) (xy 328.839115 -25.407617) (xy 328.783678 -25.413717)
			(xy 328.727944 -25.41168) (xy 328.673101 -25.40155) (xy 328.620317 -25.383543) (xy 328.570717 -25.358042)
			(xy 328.525359 -25.325591) (xy 328.48521 -25.286882) (xy 328.451124 -25.242739) (xy 328.423828 -25.194104)
			(xy 328.403905 -25.142013) (xy 328.391779 -25.087576) (xy 328.387708 -25.031954) (xy 324.522407 -25.031954)
			(xy 324.565695 -25.050349) (xy 324.613301 -25.079403) (xy 324.656169 -25.115078) (xy 324.693386 -25.156615)
			(xy 324.724159 -25.203128) (xy 324.747831 -25.253625) (xy 324.763899 -25.307032) (xy 324.772019 -25.362208)
			(xy 324.772528 -25.390094) (xy 324.772019 -25.41798) (xy 324.763899 -25.473156) (xy 324.747831 -25.526563)
			(xy 324.732742 -25.55875) (xy 332.841598 -25.55875) (xy 332.845669 -25.503128) (xy 332.857795 -25.448691)
			(xy 332.877718 -25.3966) (xy 332.905014 -25.347965) (xy 332.9391 -25.303822) (xy 332.979249 -25.265113)
			(xy 333.024607 -25.232662) (xy 333.074207 -25.207161) (xy 333.126991 -25.189154) (xy 333.181834 -25.179024)
			(xy 333.237568 -25.176987) (xy 333.293005 -25.183087) (xy 333.346962 -25.197193) (xy 333.398291 -25.219005)
			(xy 333.445897 -25.248059) (xy 333.488765 -25.283734) (xy 333.525982 -25.325271) (xy 333.556755 -25.371784)
			(xy 333.565338 -25.390094) (xy 362.109256 -25.390094) (xy 362.113327 -25.334472) (xy 362.125453 -25.280035)
			(xy 362.145376 -25.227944) (xy 362.172672 -25.179309) (xy 362.206758 -25.135166) (xy 362.246907 -25.096457)
			(xy 362.292265 -25.064006) (xy 362.341865 -25.038505) (xy 362.394649 -25.020498) (xy 362.449492 -25.010368)
			(xy 362.505226 -25.008331) (xy 362.560663 -25.014431) (xy 362.61462 -25.028537) (xy 362.622661 -25.031954)
			(xy 366.487962 -25.031954) (xy 366.492033 -24.976332) (xy 366.504159 -24.921895) (xy 366.524082 -24.869804)
			(xy 366.551378 -24.821169) (xy 366.585464 -24.777026) (xy 366.625613 -24.738317) (xy 366.670971 -24.705866)
			(xy 366.720571 -24.680365) (xy 366.773355 -24.662358) (xy 366.828198 -24.652228) (xy 366.883932 -24.650191)
			(xy 366.939369 -24.656291) (xy 366.993326 -24.670397) (xy 367.044655 -24.692209) (xy 367.092261 -24.721263)
			(xy 367.135129 -24.756938) (xy 367.136663 -24.75865) (xy 369.168678 -24.75865) (xy 369.172749 -24.703028)
			(xy 369.184875 -24.648591) (xy 369.204798 -24.5965) (xy 369.232094 -24.547865) (xy 369.26618 -24.503722)
			(xy 369.306329 -24.465013) (xy 369.351687 -24.432562) (xy 369.401287 -24.407061) (xy 369.454071 -24.389054)
			(xy 369.508914 -24.378924) (xy 369.564648 -24.376887) (xy 369.620085 -24.382987) (xy 369.674042 -24.397093)
			(xy 369.725371 -24.418905) (xy 369.772977 -24.447959) (xy 369.815845 -24.483634) (xy 369.853062 -24.525171)
			(xy 369.883835 -24.571684) (xy 369.907507 -24.622181) (xy 369.923575 -24.675588) (xy 369.931695 -24.730764)
			(xy 369.932204 -24.75865) (xy 369.931695 -24.786536) (xy 369.928622 -24.807418) (xy 380.671322 -24.807418)
			(xy 380.675393 -24.751796) (xy 380.687519 -24.697359) (xy 380.707442 -24.645268) (xy 380.734738 -24.596633)
			(xy 380.768824 -24.55249) (xy 380.808973 -24.513781) (xy 380.854331 -24.48133) (xy 380.903931 -24.455829)
			(xy 380.956715 -24.437822) (xy 381.011558 -24.427692) (xy 381.067292 -24.425655) (xy 381.122729 -24.431755)
			(xy 381.176686 -24.445861) (xy 381.228015 -24.467673) (xy 381.275621 -24.496727) (xy 381.318489 -24.532402)
			(xy 381.355706 -24.573939) (xy 381.386479 -24.620452) (xy 381.410151 -24.670949) (xy 381.426219 -24.724356)
			(xy 381.434339 -24.779532) (xy 381.434848 -24.807418) (xy 382.920238 -24.807418) (xy 382.924309 -24.751796)
			(xy 382.936435 -24.697359) (xy 382.956358 -24.645268) (xy 382.983654 -24.596633) (xy 383.01774 -24.55249)
			(xy 383.057889 -24.513781) (xy 383.103247 -24.48133) (xy 383.152847 -24.455829) (xy 383.205631 -24.437822)
			(xy 383.260474 -24.427692) (xy 383.316208 -24.425655) (xy 383.371645 -24.431755) (xy 383.425602 -24.445861)
			(xy 383.476931 -24.467673) (xy 383.524537 -24.496727) (xy 383.567405 -24.532402) (xy 383.604622 -24.573939)
			(xy 383.635395 -24.620452) (xy 383.659067 -24.670949) (xy 383.675135 -24.724356) (xy 383.683255 -24.779532)
			(xy 383.683764 -24.807418) (xy 383.683255 -24.835304) (xy 383.675135 -24.89048) (xy 383.659067 -24.943887)
			(xy 383.635395 -24.994384) (xy 383.604622 -25.040897) (xy 383.567405 -25.082434) (xy 383.524537 -25.118109)
			(xy 383.476931 -25.147163) (xy 383.425602 -25.168975) (xy 383.371645 -25.183081) (xy 383.316208 -25.189181)
			(xy 383.260474 -25.187144) (xy 383.205631 -25.177014) (xy 383.152847 -25.159007) (xy 383.103247 -25.133506)
			(xy 383.057889 -25.101055) (xy 383.01774 -25.062346) (xy 382.983654 -25.018203) (xy 382.956358 -24.969568)
			(xy 382.936435 -24.917477) (xy 382.924309 -24.86304) (xy 382.920238 -24.807418) (xy 381.434848 -24.807418)
			(xy 381.434339 -24.835304) (xy 381.426219 -24.89048) (xy 381.410151 -24.943887) (xy 381.386479 -24.994384)
			(xy 381.355706 -25.040897) (xy 381.318489 -25.082434) (xy 381.275621 -25.118109) (xy 381.228015 -25.147163)
			(xy 381.176686 -25.168975) (xy 381.122729 -25.183081) (xy 381.067292 -25.189181) (xy 381.011558 -25.187144)
			(xy 380.956715 -25.177014) (xy 380.903931 -25.159007) (xy 380.854331 -25.133506) (xy 380.808973 -25.101055)
			(xy 380.768824 -25.062346) (xy 380.734738 -25.018203) (xy 380.707442 -24.969568) (xy 380.687519 -24.917477)
			(xy 380.675393 -24.86304) (xy 380.671322 -24.807418) (xy 369.928622 -24.807418) (xy 369.923575 -24.841712)
			(xy 369.907507 -24.895119) (xy 369.883835 -24.945616) (xy 369.853062 -24.992129) (xy 369.815845 -25.033666)
			(xy 369.772977 -25.069341) (xy 369.725371 -25.098395) (xy 369.674042 -25.120207) (xy 369.620085 -25.134313)
			(xy 369.564648 -25.140413) (xy 369.508914 -25.138376) (xy 369.454071 -25.128246) (xy 369.401287 -25.110239)
			(xy 369.351687 -25.084738) (xy 369.306329 -25.052287) (xy 369.26618 -25.013578) (xy 369.232094 -24.969435)
			(xy 369.204798 -24.9208) (xy 369.184875 -24.868709) (xy 369.172749 -24.814272) (xy 369.168678 -24.75865)
			(xy 367.136663 -24.75865) (xy 367.172346 -24.798475) (xy 367.203119 -24.844988) (xy 367.226791 -24.895485)
			(xy 367.242859 -24.948892) (xy 367.250979 -25.004068) (xy 367.251488 -25.031954) (xy 367.250979 -25.05984)
			(xy 367.242859 -25.115016) (xy 367.226791 -25.168423) (xy 367.203119 -25.21892) (xy 367.172346 -25.265433)
			(xy 367.135129 -25.30697) (xy 367.092261 -25.342645) (xy 367.044655 -25.371699) (xy 366.993326 -25.393511)
			(xy 366.939369 -25.407617) (xy 366.883932 -25.413717) (xy 366.828198 -25.41168) (xy 366.773355 -25.40155)
			(xy 366.720571 -25.383543) (xy 366.670971 -25.358042) (xy 366.625613 -25.325591) (xy 366.585464 -25.286882)
			(xy 366.551378 -25.242739) (xy 366.524082 -25.194104) (xy 366.504159 -25.142013) (xy 366.492033 -25.087576)
			(xy 366.487962 -25.031954) (xy 362.622661 -25.031954) (xy 362.665949 -25.050349) (xy 362.713555 -25.079403)
			(xy 362.756423 -25.115078) (xy 362.79364 -25.156615) (xy 362.824413 -25.203128) (xy 362.848085 -25.253625)
			(xy 362.864153 -25.307032) (xy 362.872273 -25.362208) (xy 362.872782 -25.390094) (xy 362.872273 -25.41798)
			(xy 362.864153 -25.473156) (xy 362.848085 -25.526563) (xy 362.832996 -25.55875) (xy 370.941852 -25.55875)
			(xy 370.945923 -25.503128) (xy 370.958049 -25.448691) (xy 370.977972 -25.3966) (xy 371.005268 -25.347965)
			(xy 371.039354 -25.303822) (xy 371.079503 -25.265113) (xy 371.124861 -25.232662) (xy 371.174461 -25.207161)
			(xy 371.227245 -25.189154) (xy 371.282088 -25.179024) (xy 371.337822 -25.176987) (xy 371.393259 -25.183087)
			(xy 371.447216 -25.197193) (xy 371.498545 -25.219005) (xy 371.546151 -25.248059) (xy 371.589019 -25.283734)
			(xy 371.626236 -25.325271) (xy 371.657009 -25.371784) (xy 371.665592 -25.390094) (xy 388.109204 -25.390094)
			(xy 388.113275 -25.334472) (xy 388.125401 -25.280035) (xy 388.145324 -25.227944) (xy 388.17262 -25.179309)
			(xy 388.206706 -25.135166) (xy 388.246855 -25.096457) (xy 388.292213 -25.064006) (xy 388.341813 -25.038505)
			(xy 388.394597 -25.020498) (xy 388.44944 -25.010368) (xy 388.505174 -25.008331) (xy 388.560611 -25.014431)
			(xy 388.614568 -25.028537) (xy 388.622609 -25.031954) (xy 392.48791 -25.031954) (xy 392.491981 -24.976332)
			(xy 392.504107 -24.921895) (xy 392.52403 -24.869804) (xy 392.551326 -24.821169) (xy 392.585412 -24.777026)
			(xy 392.625561 -24.738317) (xy 392.670919 -24.705866) (xy 392.720519 -24.680365) (xy 392.773303 -24.662358)
			(xy 392.828146 -24.652228) (xy 392.88388 -24.650191) (xy 392.939317 -24.656291) (xy 392.993274 -24.670397)
			(xy 393.044603 -24.692209) (xy 393.092209 -24.721263) (xy 393.135077 -24.756938) (xy 393.136611 -24.75865)
			(xy 395.168626 -24.75865) (xy 395.172697 -24.703028) (xy 395.184823 -24.648591) (xy 395.204746 -24.5965)
			(xy 395.232042 -24.547865) (xy 395.266128 -24.503722) (xy 395.306277 -24.465013) (xy 395.351635 -24.432562)
			(xy 395.401235 -24.407061) (xy 395.454019 -24.389054) (xy 395.508862 -24.378924) (xy 395.564596 -24.376887)
			(xy 395.620033 -24.382987) (xy 395.67399 -24.397093) (xy 395.725319 -24.418905) (xy 395.772925 -24.447959)
			(xy 395.815793 -24.483634) (xy 395.85301 -24.525171) (xy 395.883783 -24.571684) (xy 395.907455 -24.622181)
			(xy 395.923523 -24.675588) (xy 395.931643 -24.730764) (xy 395.932152 -24.75865) (xy 395.931643 -24.786536)
			(xy 395.92857 -24.807418) (xy 406.67127 -24.807418) (xy 406.675341 -24.751796) (xy 406.687467 -24.697359)
			(xy 406.70739 -24.645268) (xy 406.734686 -24.596633) (xy 406.768772 -24.55249) (xy 406.808921 -24.513781)
			(xy 406.854279 -24.48133) (xy 406.903879 -24.455829) (xy 406.956663 -24.437822) (xy 407.011506 -24.427692)
			(xy 407.06724 -24.425655) (xy 407.122677 -24.431755) (xy 407.176634 -24.445861) (xy 407.227963 -24.467673)
			(xy 407.275569 -24.496727) (xy 407.318437 -24.532402) (xy 407.355654 -24.573939) (xy 407.386427 -24.620452)
			(xy 407.410099 -24.670949) (xy 407.426167 -24.724356) (xy 407.434287 -24.779532) (xy 407.434796 -24.807418)
			(xy 408.920186 -24.807418) (xy 408.924257 -24.751796) (xy 408.936383 -24.697359) (xy 408.956306 -24.645268)
			(xy 408.983602 -24.596633) (xy 409.017688 -24.55249) (xy 409.057837 -24.513781) (xy 409.103195 -24.48133)
			(xy 409.152795 -24.455829) (xy 409.205579 -24.437822) (xy 409.260422 -24.427692) (xy 409.316156 -24.425655)
			(xy 409.371593 -24.431755) (xy 409.42555 -24.445861) (xy 409.476879 -24.467673) (xy 409.524485 -24.496727)
			(xy 409.567353 -24.532402) (xy 409.60457 -24.573939) (xy 409.635343 -24.620452) (xy 409.659015 -24.670949)
			(xy 409.675083 -24.724356) (xy 409.683203 -24.779532) (xy 409.683712 -24.807418) (xy 409.683203 -24.835304)
			(xy 409.675083 -24.89048) (xy 409.659015 -24.943887) (xy 409.635343 -24.994384) (xy 409.60457 -25.040897)
			(xy 409.567353 -25.082434) (xy 409.524485 -25.118109) (xy 409.476879 -25.147163) (xy 409.42555 -25.168975)
			(xy 409.371593 -25.183081) (xy 409.316156 -25.189181) (xy 409.260422 -25.187144) (xy 409.205579 -25.177014)
			(xy 409.152795 -25.159007) (xy 409.103195 -25.133506) (xy 409.057837 -25.101055) (xy 409.017688 -25.062346)
			(xy 408.983602 -25.018203) (xy 408.956306 -24.969568) (xy 408.936383 -24.917477) (xy 408.924257 -24.86304)
			(xy 408.920186 -24.807418) (xy 407.434796 -24.807418) (xy 407.434287 -24.835304) (xy 407.426167 -24.89048)
			(xy 407.410099 -24.943887) (xy 407.386427 -24.994384) (xy 407.355654 -25.040897) (xy 407.318437 -25.082434)
			(xy 407.275569 -25.118109) (xy 407.227963 -25.147163) (xy 407.176634 -25.168975) (xy 407.122677 -25.183081)
			(xy 407.06724 -25.189181) (xy 407.011506 -25.187144) (xy 406.956663 -25.177014) (xy 406.903879 -25.159007)
			(xy 406.854279 -25.133506) (xy 406.808921 -25.101055) (xy 406.768772 -25.062346) (xy 406.734686 -25.018203)
			(xy 406.70739 -24.969568) (xy 406.687467 -24.917477) (xy 406.675341 -24.86304) (xy 406.67127 -24.807418)
			(xy 395.92857 -24.807418) (xy 395.923523 -24.841712) (xy 395.907455 -24.895119) (xy 395.883783 -24.945616)
			(xy 395.85301 -24.992129) (xy 395.815793 -25.033666) (xy 395.772925 -25.069341) (xy 395.725319 -25.098395)
			(xy 395.67399 -25.120207) (xy 395.620033 -25.134313) (xy 395.564596 -25.140413) (xy 395.508862 -25.138376)
			(xy 395.454019 -25.128246) (xy 395.401235 -25.110239) (xy 395.351635 -25.084738) (xy 395.306277 -25.052287)
			(xy 395.266128 -25.013578) (xy 395.232042 -24.969435) (xy 395.204746 -24.9208) (xy 395.184823 -24.868709)
			(xy 395.172697 -24.814272) (xy 395.168626 -24.75865) (xy 393.136611 -24.75865) (xy 393.172294 -24.798475)
			(xy 393.203067 -24.844988) (xy 393.226739 -24.895485) (xy 393.242807 -24.948892) (xy 393.250927 -25.004068)
			(xy 393.251436 -25.031954) (xy 393.250927 -25.05984) (xy 393.242807 -25.115016) (xy 393.226739 -25.168423)
			(xy 393.203067 -25.21892) (xy 393.172294 -25.265433) (xy 393.135077 -25.30697) (xy 393.092209 -25.342645)
			(xy 393.044603 -25.371699) (xy 392.993274 -25.393511) (xy 392.939317 -25.407617) (xy 392.88388 -25.413717)
			(xy 392.828146 -25.41168) (xy 392.773303 -25.40155) (xy 392.720519 -25.383543) (xy 392.670919 -25.358042)
			(xy 392.625561 -25.325591) (xy 392.585412 -25.286882) (xy 392.551326 -25.242739) (xy 392.52403 -25.194104)
			(xy 392.504107 -25.142013) (xy 392.491981 -25.087576) (xy 392.48791 -25.031954) (xy 388.622609 -25.031954)
			(xy 388.665897 -25.050349) (xy 388.713503 -25.079403) (xy 388.756371 -25.115078) (xy 388.793588 -25.156615)
			(xy 388.824361 -25.203128) (xy 388.848033 -25.253625) (xy 388.864101 -25.307032) (xy 388.872221 -25.362208)
			(xy 388.87273 -25.390094) (xy 388.872221 -25.41798) (xy 388.864101 -25.473156) (xy 388.848033 -25.526563)
			(xy 388.832944 -25.55875) (xy 396.9418 -25.55875) (xy 396.945871 -25.503128) (xy 396.957997 -25.448691)
			(xy 396.97792 -25.3966) (xy 397.005216 -25.347965) (xy 397.039302 -25.303822) (xy 397.079451 -25.265113)
			(xy 397.124809 -25.232662) (xy 397.174409 -25.207161) (xy 397.227193 -25.189154) (xy 397.282036 -25.179024)
			(xy 397.33777 -25.176987) (xy 397.393207 -25.183087) (xy 397.447164 -25.197193) (xy 397.498493 -25.219005)
			(xy 397.546099 -25.248059) (xy 397.588967 -25.283734) (xy 397.626184 -25.325271) (xy 397.656957 -25.371784)
			(xy 397.66554 -25.390094) (xy 414.109152 -25.390094) (xy 414.113223 -25.334472) (xy 414.125349 -25.280035)
			(xy 414.145272 -25.227944) (xy 414.172568 -25.179309) (xy 414.206654 -25.135166) (xy 414.246803 -25.096457)
			(xy 414.292161 -25.064006) (xy 414.341761 -25.038505) (xy 414.394545 -25.020498) (xy 414.449388 -25.010368)
			(xy 414.505122 -25.008331) (xy 414.560559 -25.014431) (xy 414.614516 -25.028537) (xy 414.622557 -25.031954)
			(xy 418.487858 -25.031954) (xy 418.491929 -24.976332) (xy 418.504055 -24.921895) (xy 418.523978 -24.869804)
			(xy 418.551274 -24.821169) (xy 418.58536 -24.777026) (xy 418.625509 -24.738317) (xy 418.670867 -24.705866)
			(xy 418.720467 -24.680365) (xy 418.773251 -24.662358) (xy 418.828094 -24.652228) (xy 418.883828 -24.650191)
			(xy 418.939265 -24.656291) (xy 418.993222 -24.670397) (xy 419.044551 -24.692209) (xy 419.092157 -24.721263)
			(xy 419.135025 -24.756938) (xy 419.136559 -24.75865) (xy 421.168574 -24.75865) (xy 421.172645 -24.703028)
			(xy 421.184771 -24.648591) (xy 421.204694 -24.5965) (xy 421.23199 -24.547865) (xy 421.266076 -24.503722)
			(xy 421.306225 -24.465013) (xy 421.351583 -24.432562) (xy 421.401183 -24.407061) (xy 421.453967 -24.389054)
			(xy 421.50881 -24.378924) (xy 421.564544 -24.376887) (xy 421.619981 -24.382987) (xy 421.673938 -24.397093)
			(xy 421.725267 -24.418905) (xy 421.772873 -24.447959) (xy 421.815741 -24.483634) (xy 421.852958 -24.525171)
			(xy 421.883731 -24.571684) (xy 421.907403 -24.622181) (xy 421.923471 -24.675588) (xy 421.931591 -24.730764)
			(xy 421.9321 -24.75865) (xy 421.931591 -24.786536) (xy 421.928518 -24.807418) (xy 432.671218 -24.807418)
			(xy 432.675289 -24.751796) (xy 432.687415 -24.697359) (xy 432.707338 -24.645268) (xy 432.734634 -24.596633)
			(xy 432.76872 -24.55249) (xy 432.808869 -24.513781) (xy 432.854227 -24.48133) (xy 432.903827 -24.455829)
			(xy 432.956611 -24.437822) (xy 433.011454 -24.427692) (xy 433.067188 -24.425655) (xy 433.122625 -24.431755)
			(xy 433.176582 -24.445861) (xy 433.227911 -24.467673) (xy 433.275517 -24.496727) (xy 433.318385 -24.532402)
			(xy 433.355602 -24.573939) (xy 433.386375 -24.620452) (xy 433.410047 -24.670949) (xy 433.426115 -24.724356)
			(xy 433.434235 -24.779532) (xy 433.434744 -24.807418) (xy 434.920134 -24.807418) (xy 434.924205 -24.751796)
			(xy 434.936331 -24.697359) (xy 434.956254 -24.645268) (xy 434.98355 -24.596633) (xy 435.017636 -24.55249)
			(xy 435.057785 -24.513781) (xy 435.103143 -24.48133) (xy 435.152743 -24.455829) (xy 435.205527 -24.437822)
			(xy 435.26037 -24.427692) (xy 435.316104 -24.425655) (xy 435.371541 -24.431755) (xy 435.425498 -24.445861)
			(xy 435.476827 -24.467673) (xy 435.524433 -24.496727) (xy 435.567301 -24.532402) (xy 435.604518 -24.573939)
			(xy 435.635291 -24.620452) (xy 435.658963 -24.670949) (xy 435.675031 -24.724356) (xy 435.683151 -24.779532)
			(xy 435.68366 -24.807418) (xy 435.683151 -24.835304) (xy 435.675031 -24.89048) (xy 435.658963 -24.943887)
			(xy 435.635291 -24.994384) (xy 435.604518 -25.040897) (xy 435.567301 -25.082434) (xy 435.524433 -25.118109)
			(xy 435.476827 -25.147163) (xy 435.425498 -25.168975) (xy 435.371541 -25.183081) (xy 435.316104 -25.189181)
			(xy 435.26037 -25.187144) (xy 435.205527 -25.177014) (xy 435.152743 -25.159007) (xy 435.103143 -25.133506)
			(xy 435.057785 -25.101055) (xy 435.017636 -25.062346) (xy 434.98355 -25.018203) (xy 434.956254 -24.969568)
			(xy 434.936331 -24.917477) (xy 434.924205 -24.86304) (xy 434.920134 -24.807418) (xy 433.434744 -24.807418)
			(xy 433.434235 -24.835304) (xy 433.426115 -24.89048) (xy 433.410047 -24.943887) (xy 433.386375 -24.994384)
			(xy 433.355602 -25.040897) (xy 433.318385 -25.082434) (xy 433.275517 -25.118109) (xy 433.227911 -25.147163)
			(xy 433.176582 -25.168975) (xy 433.122625 -25.183081) (xy 433.067188 -25.189181) (xy 433.011454 -25.187144)
			(xy 432.956611 -25.177014) (xy 432.903827 -25.159007) (xy 432.854227 -25.133506) (xy 432.808869 -25.101055)
			(xy 432.76872 -25.062346) (xy 432.734634 -25.018203) (xy 432.707338 -24.969568) (xy 432.687415 -24.917477)
			(xy 432.675289 -24.86304) (xy 432.671218 -24.807418) (xy 421.928518 -24.807418) (xy 421.923471 -24.841712)
			(xy 421.907403 -24.895119) (xy 421.883731 -24.945616) (xy 421.852958 -24.992129) (xy 421.815741 -25.033666)
			(xy 421.772873 -25.069341) (xy 421.725267 -25.098395) (xy 421.673938 -25.120207) (xy 421.619981 -25.134313)
			(xy 421.564544 -25.140413) (xy 421.50881 -25.138376) (xy 421.453967 -25.128246) (xy 421.401183 -25.110239)
			(xy 421.351583 -25.084738) (xy 421.306225 -25.052287) (xy 421.266076 -25.013578) (xy 421.23199 -24.969435)
			(xy 421.204694 -24.9208) (xy 421.184771 -24.868709) (xy 421.172645 -24.814272) (xy 421.168574 -24.75865)
			(xy 419.136559 -24.75865) (xy 419.172242 -24.798475) (xy 419.203015 -24.844988) (xy 419.226687 -24.895485)
			(xy 419.242755 -24.948892) (xy 419.250875 -25.004068) (xy 419.251384 -25.031954) (xy 419.250875 -25.05984)
			(xy 419.242755 -25.115016) (xy 419.226687 -25.168423) (xy 419.203015 -25.21892) (xy 419.172242 -25.265433)
			(xy 419.135025 -25.30697) (xy 419.092157 -25.342645) (xy 419.044551 -25.371699) (xy 418.993222 -25.393511)
			(xy 418.939265 -25.407617) (xy 418.883828 -25.413717) (xy 418.828094 -25.41168) (xy 418.773251 -25.40155)
			(xy 418.720467 -25.383543) (xy 418.670867 -25.358042) (xy 418.625509 -25.325591) (xy 418.58536 -25.286882)
			(xy 418.551274 -25.242739) (xy 418.523978 -25.194104) (xy 418.504055 -25.142013) (xy 418.491929 -25.087576)
			(xy 418.487858 -25.031954) (xy 414.622557 -25.031954) (xy 414.665845 -25.050349) (xy 414.713451 -25.079403)
			(xy 414.756319 -25.115078) (xy 414.793536 -25.156615) (xy 414.824309 -25.203128) (xy 414.847981 -25.253625)
			(xy 414.864049 -25.307032) (xy 414.872169 -25.362208) (xy 414.872678 -25.390094) (xy 414.872169 -25.41798)
			(xy 414.864049 -25.473156) (xy 414.847981 -25.526563) (xy 414.832892 -25.55875) (xy 422.941748 -25.55875)
			(xy 422.945819 -25.503128) (xy 422.957945 -25.448691) (xy 422.977868 -25.3966) (xy 423.005164 -25.347965)
			(xy 423.03925 -25.303822) (xy 423.079399 -25.265113) (xy 423.124757 -25.232662) (xy 423.174357 -25.207161)
			(xy 423.227141 -25.189154) (xy 423.281984 -25.179024) (xy 423.337718 -25.176987) (xy 423.393155 -25.183087)
			(xy 423.447112 -25.197193) (xy 423.498441 -25.219005) (xy 423.546047 -25.248059) (xy 423.588915 -25.283734)
			(xy 423.626132 -25.325271) (xy 423.656905 -25.371784) (xy 423.665488 -25.390094) (xy 440.1091 -25.390094)
			(xy 440.113171 -25.334472) (xy 440.125297 -25.280035) (xy 440.14522 -25.227944) (xy 440.172516 -25.179309)
			(xy 440.206602 -25.135166) (xy 440.246751 -25.096457) (xy 440.292109 -25.064006) (xy 440.341709 -25.038505)
			(xy 440.394493 -25.020498) (xy 440.449336 -25.010368) (xy 440.50507 -25.008331) (xy 440.560507 -25.014431)
			(xy 440.614464 -25.028537) (xy 440.622505 -25.031954) (xy 444.487806 -25.031954) (xy 444.491877 -24.976332)
			(xy 444.504003 -24.921895) (xy 444.523926 -24.869804) (xy 444.551222 -24.821169) (xy 444.585308 -24.777026)
			(xy 444.625457 -24.738317) (xy 444.670815 -24.705866) (xy 444.720415 -24.680365) (xy 444.773199 -24.662358)
			(xy 444.828042 -24.652228) (xy 444.883776 -24.650191) (xy 444.939213 -24.656291) (xy 444.99317 -24.670397)
			(xy 445.044499 -24.692209) (xy 445.092105 -24.721263) (xy 445.134973 -24.756938) (xy 445.136507 -24.75865)
			(xy 447.168522 -24.75865) (xy 447.172593 -24.703028) (xy 447.184719 -24.648591) (xy 447.204642 -24.5965)
			(xy 447.231938 -24.547865) (xy 447.266024 -24.503722) (xy 447.306173 -24.465013) (xy 447.351531 -24.432562)
			(xy 447.401131 -24.407061) (xy 447.453915 -24.389054) (xy 447.508758 -24.378924) (xy 447.564492 -24.376887)
			(xy 447.619929 -24.382987) (xy 447.673886 -24.397093) (xy 447.725215 -24.418905) (xy 447.772821 -24.447959)
			(xy 447.815689 -24.483634) (xy 447.852906 -24.525171) (xy 447.883679 -24.571684) (xy 447.907351 -24.622181)
			(xy 447.923419 -24.675588) (xy 447.931539 -24.730764) (xy 447.932048 -24.75865) (xy 447.931539 -24.786536)
			(xy 447.923419 -24.841712) (xy 447.907351 -24.895119) (xy 447.883679 -24.945616) (xy 447.852906 -24.992129)
			(xy 447.815689 -25.033666) (xy 447.772821 -25.069341) (xy 447.725215 -25.098395) (xy 447.673886 -25.120207)
			(xy 447.619929 -25.134313) (xy 447.564492 -25.140413) (xy 447.508758 -25.138376) (xy 447.453915 -25.128246)
			(xy 447.401131 -25.110239) (xy 447.351531 -25.084738) (xy 447.306173 -25.052287) (xy 447.266024 -25.013578)
			(xy 447.231938 -24.969435) (xy 447.204642 -24.9208) (xy 447.184719 -24.868709) (xy 447.172593 -24.814272)
			(xy 447.168522 -24.75865) (xy 445.136507 -24.75865) (xy 445.17219 -24.798475) (xy 445.202963 -24.844988)
			(xy 445.226635 -24.895485) (xy 445.242703 -24.948892) (xy 445.250823 -25.004068) (xy 445.251332 -25.031954)
			(xy 445.250823 -25.05984) (xy 445.242703 -25.115016) (xy 445.226635 -25.168423) (xy 445.202963 -25.21892)
			(xy 445.17219 -25.265433) (xy 445.134973 -25.30697) (xy 445.092105 -25.342645) (xy 445.044499 -25.371699)
			(xy 444.99317 -25.393511) (xy 444.939213 -25.407617) (xy 444.883776 -25.413717) (xy 444.828042 -25.41168)
			(xy 444.773199 -25.40155) (xy 444.720415 -25.383543) (xy 444.670815 -25.358042) (xy 444.625457 -25.325591)
			(xy 444.585308 -25.286882) (xy 444.551222 -25.242739) (xy 444.523926 -25.194104) (xy 444.504003 -25.142013)
			(xy 444.491877 -25.087576) (xy 444.487806 -25.031954) (xy 440.622505 -25.031954) (xy 440.665793 -25.050349)
			(xy 440.713399 -25.079403) (xy 440.756267 -25.115078) (xy 440.793484 -25.156615) (xy 440.824257 -25.203128)
			(xy 440.847929 -25.253625) (xy 440.863997 -25.307032) (xy 440.872117 -25.362208) (xy 440.872626 -25.390094)
			(xy 440.872117 -25.41798) (xy 440.863997 -25.473156) (xy 440.847929 -25.526563) (xy 440.83284 -25.55875)
			(xy 448.941696 -25.55875) (xy 448.945767 -25.503128) (xy 448.957893 -25.448691) (xy 448.977816 -25.3966)
			(xy 449.005112 -25.347965) (xy 449.039198 -25.303822) (xy 449.079347 -25.265113) (xy 449.124705 -25.232662)
			(xy 449.174305 -25.207161) (xy 449.227089 -25.189154) (xy 449.281932 -25.179024) (xy 449.337666 -25.176987)
			(xy 449.393103 -25.183087) (xy 449.44706 -25.197193) (xy 449.498389 -25.219005) (xy 449.545995 -25.248059)
			(xy 449.588863 -25.283734) (xy 449.62608 -25.325271) (xy 449.656853 -25.371784) (xy 449.680525 -25.422281)
			(xy 449.696593 -25.475688) (xy 449.704713 -25.530864) (xy 449.705222 -25.55875) (xy 449.704713 -25.586636)
			(xy 449.696593 -25.641812) (xy 449.680525 -25.695219) (xy 449.656853 -25.745716) (xy 449.62608 -25.792229)
			(xy 449.588863 -25.833766) (xy 449.545995 -25.869441) (xy 449.498389 -25.898495) (xy 449.44706 -25.920307)
			(xy 449.393103 -25.934413) (xy 449.337666 -25.940513) (xy 449.281932 -25.938476) (xy 449.227089 -25.928346)
			(xy 449.174305 -25.910339) (xy 449.124705 -25.884838) (xy 449.079347 -25.852387) (xy 449.039198 -25.813678)
			(xy 449.005112 -25.769535) (xy 448.977816 -25.7209) (xy 448.957893 -25.668809) (xy 448.945767 -25.614372)
			(xy 448.941696 -25.55875) (xy 440.83284 -25.55875) (xy 440.824257 -25.57706) (xy 440.793484 -25.623573)
			(xy 440.756267 -25.66511) (xy 440.713399 -25.700785) (xy 440.665793 -25.729839) (xy 440.614464 -25.751651)
			(xy 440.560507 -25.765757) (xy 440.50507 -25.771857) (xy 440.449336 -25.76982) (xy 440.394493 -25.75969)
			(xy 440.341709 -25.741683) (xy 440.292109 -25.716182) (xy 440.246751 -25.683731) (xy 440.206602 -25.645022)
			(xy 440.172516 -25.600879) (xy 440.14522 -25.552244) (xy 440.125297 -25.500153) (xy 440.113171 -25.445716)
			(xy 440.1091 -25.390094) (xy 423.665488 -25.390094) (xy 423.680577 -25.422281) (xy 423.696645 -25.475688)
			(xy 423.704765 -25.530864) (xy 423.705274 -25.55875) (xy 423.704765 -25.586636) (xy 423.696645 -25.641812)
			(xy 423.680577 -25.695219) (xy 423.656905 -25.745716) (xy 423.626132 -25.792229) (xy 423.588915 -25.833766)
			(xy 423.546047 -25.869441) (xy 423.498441 -25.898495) (xy 423.447112 -25.920307) (xy 423.393155 -25.934413)
			(xy 423.337718 -25.940513) (xy 423.281984 -25.938476) (xy 423.227141 -25.928346) (xy 423.174357 -25.910339)
			(xy 423.124757 -25.884838) (xy 423.079399 -25.852387) (xy 423.03925 -25.813678) (xy 423.005164 -25.769535)
			(xy 422.977868 -25.7209) (xy 422.957945 -25.668809) (xy 422.945819 -25.614372) (xy 422.941748 -25.55875)
			(xy 414.832892 -25.55875) (xy 414.824309 -25.57706) (xy 414.793536 -25.623573) (xy 414.756319 -25.66511)
			(xy 414.713451 -25.700785) (xy 414.665845 -25.729839) (xy 414.614516 -25.751651) (xy 414.560559 -25.765757)
			(xy 414.505122 -25.771857) (xy 414.449388 -25.76982) (xy 414.394545 -25.75969) (xy 414.341761 -25.741683)
			(xy 414.292161 -25.716182) (xy 414.246803 -25.683731) (xy 414.206654 -25.645022) (xy 414.172568 -25.600879)
			(xy 414.145272 -25.552244) (xy 414.125349 -25.500153) (xy 414.113223 -25.445716) (xy 414.109152 -25.390094)
			(xy 397.66554 -25.390094) (xy 397.680629 -25.422281) (xy 397.696697 -25.475688) (xy 397.704817 -25.530864)
			(xy 397.705326 -25.55875) (xy 397.704817 -25.586636) (xy 397.696697 -25.641812) (xy 397.680629 -25.695219)
			(xy 397.656957 -25.745716) (xy 397.626184 -25.792229) (xy 397.588967 -25.833766) (xy 397.546099 -25.869441)
			(xy 397.498493 -25.898495) (xy 397.447164 -25.920307) (xy 397.393207 -25.934413) (xy 397.33777 -25.940513)
			(xy 397.282036 -25.938476) (xy 397.227193 -25.928346) (xy 397.174409 -25.910339) (xy 397.124809 -25.884838)
			(xy 397.079451 -25.852387) (xy 397.039302 -25.813678) (xy 397.005216 -25.769535) (xy 396.97792 -25.7209)
			(xy 396.957997 -25.668809) (xy 396.945871 -25.614372) (xy 396.9418 -25.55875) (xy 388.832944 -25.55875)
			(xy 388.824361 -25.57706) (xy 388.793588 -25.623573) (xy 388.756371 -25.66511) (xy 388.713503 -25.700785)
			(xy 388.665897 -25.729839) (xy 388.614568 -25.751651) (xy 388.560611 -25.765757) (xy 388.505174 -25.771857)
			(xy 388.44944 -25.76982) (xy 388.394597 -25.75969) (xy 388.341813 -25.741683) (xy 388.292213 -25.716182)
			(xy 388.246855 -25.683731) (xy 388.206706 -25.645022) (xy 388.17262 -25.600879) (xy 388.145324 -25.552244)
			(xy 388.125401 -25.500153) (xy 388.113275 -25.445716) (xy 388.109204 -25.390094) (xy 371.665592 -25.390094)
			(xy 371.680681 -25.422281) (xy 371.696749 -25.475688) (xy 371.704869 -25.530864) (xy 371.705378 -25.55875)
			(xy 371.704869 -25.586636) (xy 371.696749 -25.641812) (xy 371.680681 -25.695219) (xy 371.657009 -25.745716)
			(xy 371.626236 -25.792229) (xy 371.589019 -25.833766) (xy 371.546151 -25.869441) (xy 371.498545 -25.898495)
			(xy 371.447216 -25.920307) (xy 371.393259 -25.934413) (xy 371.337822 -25.940513) (xy 371.282088 -25.938476)
			(xy 371.227245 -25.928346) (xy 371.174461 -25.910339) (xy 371.124861 -25.884838) (xy 371.079503 -25.852387)
			(xy 371.039354 -25.813678) (xy 371.005268 -25.769535) (xy 370.977972 -25.7209) (xy 370.958049 -25.668809)
			(xy 370.945923 -25.614372) (xy 370.941852 -25.55875) (xy 362.832996 -25.55875) (xy 362.824413 -25.57706)
			(xy 362.79364 -25.623573) (xy 362.756423 -25.66511) (xy 362.713555 -25.700785) (xy 362.665949 -25.729839)
			(xy 362.61462 -25.751651) (xy 362.560663 -25.765757) (xy 362.505226 -25.771857) (xy 362.449492 -25.76982)
			(xy 362.394649 -25.75969) (xy 362.341865 -25.741683) (xy 362.292265 -25.716182) (xy 362.246907 -25.683731)
			(xy 362.206758 -25.645022) (xy 362.172672 -25.600879) (xy 362.145376 -25.552244) (xy 362.125453 -25.500153)
			(xy 362.113327 -25.445716) (xy 362.109256 -25.390094) (xy 333.565338 -25.390094) (xy 333.580427 -25.422281)
			(xy 333.596495 -25.475688) (xy 333.604615 -25.530864) (xy 333.605124 -25.55875) (xy 333.604615 -25.586636)
			(xy 333.596495 -25.641812) (xy 333.580427 -25.695219) (xy 333.556755 -25.745716) (xy 333.525982 -25.792229)
			(xy 333.488765 -25.833766) (xy 333.445897 -25.869441) (xy 333.398291 -25.898495) (xy 333.346962 -25.920307)
			(xy 333.293005 -25.934413) (xy 333.237568 -25.940513) (xy 333.181834 -25.938476) (xy 333.126991 -25.928346)
			(xy 333.074207 -25.910339) (xy 333.024607 -25.884838) (xy 332.979249 -25.852387) (xy 332.9391 -25.813678)
			(xy 332.905014 -25.769535) (xy 332.877718 -25.7209) (xy 332.857795 -25.668809) (xy 332.845669 -25.614372)
			(xy 332.841598 -25.55875) (xy 324.732742 -25.55875) (xy 324.724159 -25.57706) (xy 324.693386 -25.623573)
			(xy 324.656169 -25.66511) (xy 324.613301 -25.700785) (xy 324.565695 -25.729839) (xy 324.514366 -25.751651)
			(xy 324.460409 -25.765757) (xy 324.404972 -25.771857) (xy 324.349238 -25.76982) (xy 324.294395 -25.75969)
			(xy 324.241611 -25.741683) (xy 324.192011 -25.716182) (xy 324.146653 -25.683731) (xy 324.106504 -25.645022)
			(xy 324.072418 -25.600879) (xy 324.045122 -25.552244) (xy 324.025199 -25.500153) (xy 324.013073 -25.445716)
			(xy 324.009002 -25.390094) (xy 307.56539 -25.390094) (xy 307.580479 -25.422281) (xy 307.596547 -25.475688)
			(xy 307.604667 -25.530864) (xy 307.605176 -25.55875) (xy 307.604667 -25.586636) (xy 307.596547 -25.641812)
			(xy 307.580479 -25.695219) (xy 307.556807 -25.745716) (xy 307.526034 -25.792229) (xy 307.488817 -25.833766)
			(xy 307.445949 -25.869441) (xy 307.398343 -25.898495) (xy 307.347014 -25.920307) (xy 307.293057 -25.934413)
			(xy 307.23762 -25.940513) (xy 307.181886 -25.938476) (xy 307.127043 -25.928346) (xy 307.074259 -25.910339)
			(xy 307.024659 -25.884838) (xy 306.979301 -25.852387) (xy 306.939152 -25.813678) (xy 306.905066 -25.769535)
			(xy 306.87777 -25.7209) (xy 306.857847 -25.668809) (xy 306.845721 -25.614372) (xy 306.84165 -25.55875)
			(xy 298.732794 -25.55875) (xy 298.724211 -25.57706) (xy 298.693438 -25.623573) (xy 298.656221 -25.66511)
			(xy 298.613353 -25.700785) (xy 298.565747 -25.729839) (xy 298.514418 -25.751651) (xy 298.460461 -25.765757)
			(xy 298.405024 -25.771857) (xy 298.34929 -25.76982) (xy 298.294447 -25.75969) (xy 298.241663 -25.741683)
			(xy 298.192063 -25.716182) (xy 298.146705 -25.683731) (xy 298.106556 -25.645022) (xy 298.07247 -25.600879)
			(xy 298.045174 -25.552244) (xy 298.025251 -25.500153) (xy 298.013125 -25.445716) (xy 298.009054 -25.390094)
			(xy 281.565442 -25.390094) (xy 281.580531 -25.422281) (xy 281.596599 -25.475688) (xy 281.604719 -25.530864)
			(xy 281.605228 -25.55875) (xy 281.604719 -25.586636) (xy 281.596599 -25.641812) (xy 281.580531 -25.695219)
			(xy 281.556859 -25.745716) (xy 281.526086 -25.792229) (xy 281.488869 -25.833766) (xy 281.446001 -25.869441)
			(xy 281.398395 -25.898495) (xy 281.347066 -25.920307) (xy 281.293109 -25.934413) (xy 281.237672 -25.940513)
			(xy 281.181938 -25.938476) (xy 281.127095 -25.928346) (xy 281.074311 -25.910339) (xy 281.024711 -25.884838)
			(xy 280.979353 -25.852387) (xy 280.939204 -25.813678) (xy 280.905118 -25.769535) (xy 280.877822 -25.7209)
			(xy 280.857899 -25.668809) (xy 280.845773 -25.614372) (xy 280.841702 -25.55875) (xy 272.732846 -25.55875)
			(xy 272.724263 -25.57706) (xy 272.69349 -25.623573) (xy 272.656273 -25.66511) (xy 272.613405 -25.700785)
			(xy 272.565799 -25.729839) (xy 272.51447 -25.751651) (xy 272.460513 -25.765757) (xy 272.405076 -25.771857)
			(xy 272.349342 -25.76982) (xy 272.294499 -25.75969) (xy 272.241715 -25.741683) (xy 272.192115 -25.716182)
			(xy 272.146757 -25.683731) (xy 272.106608 -25.645022) (xy 272.072522 -25.600879) (xy 272.045226 -25.552244)
			(xy 272.025303 -25.500153) (xy 272.013177 -25.445716) (xy 272.009106 -25.390094) (xy 255.565494 -25.390094)
			(xy 255.580583 -25.422281) (xy 255.596651 -25.475688) (xy 255.604771 -25.530864) (xy 255.60528 -25.55875)
			(xy 255.604771 -25.586636) (xy 255.596651 -25.641812) (xy 255.580583 -25.695219) (xy 255.556911 -25.745716)
			(xy 255.526138 -25.792229) (xy 255.488921 -25.833766) (xy 255.446053 -25.869441) (xy 255.398447 -25.898495)
			(xy 255.347118 -25.920307) (xy 255.293161 -25.934413) (xy 255.237724 -25.940513) (xy 255.18199 -25.938476)
			(xy 255.127147 -25.928346) (xy 255.074363 -25.910339) (xy 255.024763 -25.884838) (xy 254.979405 -25.852387)
			(xy 254.939256 -25.813678) (xy 254.90517 -25.769535) (xy 254.877874 -25.7209) (xy 254.857951 -25.668809)
			(xy 254.845825 -25.614372) (xy 254.841754 -25.55875) (xy 246.732898 -25.55875) (xy 246.724315 -25.57706)
			(xy 246.693542 -25.623573) (xy 246.656325 -25.66511) (xy 246.613457 -25.700785) (xy 246.565851 -25.729839)
			(xy 246.514522 -25.751651) (xy 246.460565 -25.765757) (xy 246.405128 -25.771857) (xy 246.349394 -25.76982)
			(xy 246.294551 -25.75969) (xy 246.241767 -25.741683) (xy 246.192167 -25.716182) (xy 246.146809 -25.683731)
			(xy 246.10666 -25.645022) (xy 246.072574 -25.600879) (xy 246.045278 -25.552244) (xy 246.025355 -25.500153)
			(xy 246.013229 -25.445716) (xy 246.009158 -25.390094) (xy 217.465494 -25.390094) (xy 217.480583 -25.422281)
			(xy 217.496651 -25.475688) (xy 217.504771 -25.530864) (xy 217.50528 -25.55875) (xy 217.504771 -25.586636)
			(xy 217.496651 -25.641812) (xy 217.480583 -25.695219) (xy 217.456911 -25.745716) (xy 217.426138 -25.792229)
			(xy 217.388921 -25.833766) (xy 217.346053 -25.869441) (xy 217.298447 -25.898495) (xy 217.247118 -25.920307)
			(xy 217.193161 -25.934413) (xy 217.137724 -25.940513) (xy 217.08199 -25.938476) (xy 217.027147 -25.928346)
			(xy 216.974363 -25.910339) (xy 216.924763 -25.884838) (xy 216.879405 -25.852387) (xy 216.839256 -25.813678)
			(xy 216.80517 -25.769535) (xy 216.777874 -25.7209) (xy 216.757951 -25.668809) (xy 216.745825 -25.614372)
			(xy 216.741754 -25.55875) (xy 208.632898 -25.55875) (xy 208.624315 -25.57706) (xy 208.593542 -25.623573)
			(xy 208.556325 -25.66511) (xy 208.513457 -25.700785) (xy 208.465851 -25.729839) (xy 208.414522 -25.751651)
			(xy 208.360565 -25.765757) (xy 208.305128 -25.771857) (xy 208.249394 -25.76982) (xy 208.194551 -25.75969)
			(xy 208.141767 -25.741683) (xy 208.092167 -25.716182) (xy 208.046809 -25.683731) (xy 208.00666 -25.645022)
			(xy 207.972574 -25.600879) (xy 207.945278 -25.552244) (xy 207.925355 -25.500153) (xy 207.913229 -25.445716)
			(xy 207.909158 -25.390094) (xy 191.465546 -25.390094) (xy 191.480635 -25.422281) (xy 191.496703 -25.475688)
			(xy 191.504823 -25.530864) (xy 191.505332 -25.55875) (xy 191.504823 -25.586636) (xy 191.496703 -25.641812)
			(xy 191.480635 -25.695219) (xy 191.456963 -25.745716) (xy 191.42619 -25.792229) (xy 191.388973 -25.833766)
			(xy 191.346105 -25.869441) (xy 191.298499 -25.898495) (xy 191.24717 -25.920307) (xy 191.193213 -25.934413)
			(xy 191.137776 -25.940513) (xy 191.082042 -25.938476) (xy 191.027199 -25.928346) (xy 190.974415 -25.910339)
			(xy 190.924815 -25.884838) (xy 190.879457 -25.852387) (xy 190.839308 -25.813678) (xy 190.805222 -25.769535)
			(xy 190.777926 -25.7209) (xy 190.758003 -25.668809) (xy 190.745877 -25.614372) (xy 190.741806 -25.55875)
			(xy 182.63295 -25.55875) (xy 182.624367 -25.57706) (xy 182.593594 -25.623573) (xy 182.556377 -25.66511)
			(xy 182.513509 -25.700785) (xy 182.465903 -25.729839) (xy 182.414574 -25.751651) (xy 182.360617 -25.765757)
			(xy 182.30518 -25.771857) (xy 182.249446 -25.76982) (xy 182.194603 -25.75969) (xy 182.141819 -25.741683)
			(xy 182.092219 -25.716182) (xy 182.046861 -25.683731) (xy 182.006712 -25.645022) (xy 181.972626 -25.600879)
			(xy 181.94533 -25.552244) (xy 181.925407 -25.500153) (xy 181.913281 -25.445716) (xy 181.90921 -25.390094)
			(xy 165.465598 -25.390094) (xy 165.480687 -25.422281) (xy 165.496755 -25.475688) (xy 165.504875 -25.530864)
			(xy 165.505384 -25.55875) (xy 165.504875 -25.586636) (xy 165.496755 -25.641812) (xy 165.480687 -25.695219)
			(xy 165.457015 -25.745716) (xy 165.426242 -25.792229) (xy 165.389025 -25.833766) (xy 165.346157 -25.869441)
			(xy 165.298551 -25.898495) (xy 165.247222 -25.920307) (xy 165.193265 -25.934413) (xy 165.137828 -25.940513)
			(xy 165.082094 -25.938476) (xy 165.027251 -25.928346) (xy 164.974467 -25.910339) (xy 164.924867 -25.884838)
			(xy 164.879509 -25.852387) (xy 164.83936 -25.813678) (xy 164.805274 -25.769535) (xy 164.777978 -25.7209)
			(xy 164.758055 -25.668809) (xy 164.745929 -25.614372) (xy 164.741858 -25.55875) (xy 156.633002 -25.55875)
			(xy 156.624419 -25.57706) (xy 156.593646 -25.623573) (xy 156.556429 -25.66511) (xy 156.513561 -25.700785)
			(xy 156.465955 -25.729839) (xy 156.414626 -25.751651) (xy 156.360669 -25.765757) (xy 156.305232 -25.771857)
			(xy 156.249498 -25.76982) (xy 156.194655 -25.75969) (xy 156.141871 -25.741683) (xy 156.092271 -25.716182)
			(xy 156.046913 -25.683731) (xy 156.006764 -25.645022) (xy 155.972678 -25.600879) (xy 155.945382 -25.552244)
			(xy 155.925459 -25.500153) (xy 155.913333 -25.445716) (xy 155.909262 -25.390094) (xy 139.46565 -25.390094)
			(xy 139.480739 -25.422281) (xy 139.496807 -25.475688) (xy 139.504927 -25.530864) (xy 139.505436 -25.55875)
			(xy 139.504927 -25.586636) (xy 139.496807 -25.641812) (xy 139.480739 -25.695219) (xy 139.457067 -25.745716)
			(xy 139.426294 -25.792229) (xy 139.389077 -25.833766) (xy 139.346209 -25.869441) (xy 139.298603 -25.898495)
			(xy 139.247274 -25.920307) (xy 139.193317 -25.934413) (xy 139.13788 -25.940513) (xy 139.082146 -25.938476)
			(xy 139.027303 -25.928346) (xy 138.974519 -25.910339) (xy 138.924919 -25.884838) (xy 138.879561 -25.852387)
			(xy 138.839412 -25.813678) (xy 138.805326 -25.769535) (xy 138.77803 -25.7209) (xy 138.758107 -25.668809)
			(xy 138.745981 -25.614372) (xy 138.74191 -25.55875) (xy 130.633054 -25.55875) (xy 130.624471 -25.57706)
			(xy 130.593698 -25.623573) (xy 130.556481 -25.66511) (xy 130.513613 -25.700785) (xy 130.466007 -25.729839)
			(xy 130.414678 -25.751651) (xy 130.360721 -25.765757) (xy 130.305284 -25.771857) (xy 130.24955 -25.76982)
			(xy 130.194707 -25.75969) (xy 130.141923 -25.741683) (xy 130.092323 -25.716182) (xy 130.046965 -25.683731)
			(xy 130.006816 -25.645022) (xy 129.97273 -25.600879) (xy 129.945434 -25.552244) (xy 129.925511 -25.500153)
			(xy 129.913385 -25.445716) (xy 129.909314 -25.390094) (xy 101.365396 -25.390094) (xy 101.380485 -25.422281)
			(xy 101.396553 -25.475688) (xy 101.404673 -25.530864) (xy 101.405182 -25.55875) (xy 101.404673 -25.586636)
			(xy 101.396553 -25.641812) (xy 101.380485 -25.695219) (xy 101.356813 -25.745716) (xy 101.32604 -25.792229)
			(xy 101.288823 -25.833766) (xy 101.245955 -25.869441) (xy 101.198349 -25.898495) (xy 101.14702 -25.920307)
			(xy 101.093063 -25.934413) (xy 101.037626 -25.940513) (xy 100.981892 -25.938476) (xy 100.927049 -25.928346)
			(xy 100.874265 -25.910339) (xy 100.824665 -25.884838) (xy 100.779307 -25.852387) (xy 100.739158 -25.813678)
			(xy 100.705072 -25.769535) (xy 100.677776 -25.7209) (xy 100.657853 -25.668809) (xy 100.645727 -25.614372)
			(xy 100.641656 -25.55875) (xy 92.5328 -25.55875) (xy 92.524217 -25.57706) (xy 92.493444 -25.623573)
			(xy 92.456227 -25.66511) (xy 92.413359 -25.700785) (xy 92.365753 -25.729839) (xy 92.314424 -25.751651)
			(xy 92.260467 -25.765757) (xy 92.20503 -25.771857) (xy 92.149296 -25.76982) (xy 92.094453 -25.75969)
			(xy 92.041669 -25.741683) (xy 91.992069 -25.716182) (xy 91.946711 -25.683731) (xy 91.906562 -25.645022)
			(xy 91.872476 -25.600879) (xy 91.84518 -25.552244) (xy 91.825257 -25.500153) (xy 91.813131 -25.445716)
			(xy 91.80906 -25.390094) (xy 75.365448 -25.390094) (xy 75.380537 -25.422281) (xy 75.396605 -25.475688)
			(xy 75.404725 -25.530864) (xy 75.405234 -25.55875) (xy 75.404725 -25.586636) (xy 75.396605 -25.641812)
			(xy 75.380537 -25.695219) (xy 75.356865 -25.745716) (xy 75.326092 -25.792229) (xy 75.288875 -25.833766)
			(xy 75.246007 -25.869441) (xy 75.198401 -25.898495) (xy 75.147072 -25.920307) (xy 75.093115 -25.934413)
			(xy 75.037678 -25.940513) (xy 74.981944 -25.938476) (xy 74.927101 -25.928346) (xy 74.874317 -25.910339)
			(xy 74.824717 -25.884838) (xy 74.779359 -25.852387) (xy 74.73921 -25.813678) (xy 74.705124 -25.769535)
			(xy 74.677828 -25.7209) (xy 74.657905 -25.668809) (xy 74.645779 -25.614372) (xy 74.641708 -25.55875)
			(xy 66.532852 -25.55875) (xy 66.524269 -25.57706) (xy 66.493496 -25.623573) (xy 66.456279 -25.66511)
			(xy 66.413411 -25.700785) (xy 66.365805 -25.729839) (xy 66.314476 -25.751651) (xy 66.260519 -25.765757)
			(xy 66.205082 -25.771857) (xy 66.149348 -25.76982) (xy 66.094505 -25.75969) (xy 66.041721 -25.741683)
			(xy 65.992121 -25.716182) (xy 65.946763 -25.683731) (xy 65.906614 -25.645022) (xy 65.872528 -25.600879)
			(xy 65.845232 -25.552244) (xy 65.825309 -25.500153) (xy 65.813183 -25.445716) (xy 65.809112 -25.390094)
			(xy 49.3655 -25.390094) (xy 49.380589 -25.422281) (xy 49.396657 -25.475688) (xy 49.404777 -25.530864)
			(xy 49.405286 -25.55875) (xy 49.404777 -25.586636) (xy 49.396657 -25.641812) (xy 49.380589 -25.695219)
			(xy 49.356917 -25.745716) (xy 49.326144 -25.792229) (xy 49.288927 -25.833766) (xy 49.246059 -25.869441)
			(xy 49.198453 -25.898495) (xy 49.147124 -25.920307) (xy 49.093167 -25.934413) (xy 49.03773 -25.940513)
			(xy 48.981996 -25.938476) (xy 48.927153 -25.928346) (xy 48.874369 -25.910339) (xy 48.824769 -25.884838)
			(xy 48.779411 -25.852387) (xy 48.739262 -25.813678) (xy 48.705176 -25.769535) (xy 48.67788 -25.7209)
			(xy 48.657957 -25.668809) (xy 48.645831 -25.614372) (xy 48.64176 -25.55875) (xy 40.532904 -25.55875)
			(xy 40.524321 -25.57706) (xy 40.493548 -25.623573) (xy 40.456331 -25.66511) (xy 40.413463 -25.700785)
			(xy 40.365857 -25.729839) (xy 40.314528 -25.751651) (xy 40.260571 -25.765757) (xy 40.205134 -25.771857)
			(xy 40.1494 -25.76982) (xy 40.094557 -25.75969) (xy 40.041773 -25.741683) (xy 39.992173 -25.716182)
			(xy 39.946815 -25.683731) (xy 39.906666 -25.645022) (xy 39.87258 -25.600879) (xy 39.845284 -25.552244)
			(xy 39.825361 -25.500153) (xy 39.813235 -25.445716) (xy 39.809164 -25.390094) (xy 18.701327 -25.390094)
			(xy 18.693286 -25.393511) (xy 18.639329 -25.407617) (xy 18.583892 -25.413717) (xy 18.528158 -25.41168)
			(xy 18.473315 -25.40155) (xy 18.420531 -25.383543) (xy 18.370931 -25.358042) (xy 18.325573 -25.325591)
			(xy 18.285424 -25.286882) (xy 18.251338 -25.242739) (xy 18.224042 -25.194104) (xy 18.204119 -25.142013)
			(xy 18.191993 -25.087576) (xy 18.187922 -25.031954) (xy 14.322621 -25.031954) (xy 14.365909 -25.050349)
			(xy 14.413515 -25.079403) (xy 14.456383 -25.115078) (xy 14.4936 -25.156615) (xy 14.524373 -25.203128)
			(xy 14.548045 -25.253625) (xy 14.564113 -25.307032) (xy 14.572233 -25.362208) (xy 14.572742 -25.390094)
			(xy 14.572233 -25.41798) (xy 14.564113 -25.473156) (xy 14.548045 -25.526563) (xy 14.524373 -25.57706)
			(xy 14.4936 -25.623573) (xy 14.456383 -25.66511) (xy 14.413515 -25.700785) (xy 14.365909 -25.729839)
			(xy 14.31458 -25.751651) (xy 14.260623 -25.765757) (xy 14.205186 -25.771857) (xy 14.149452 -25.76982)
			(xy 14.094609 -25.75969) (xy 14.041825 -25.741683) (xy 13.992225 -25.716182) (xy 13.946867 -25.683731)
			(xy 13.906718 -25.645022) (xy 13.872632 -25.600879) (xy 13.845336 -25.552244) (xy 13.825413 -25.500153)
			(xy 13.813287 -25.445716) (xy 13.809216 -25.390094) (xy 2.02438 -25.390094) (xy 2.02438 -25.605232)
			(xy 2.024787 -25.614512) (xy 2.031435 -25.631839) (xy 2.037334 -25.639014) (xy 2.04343 -25.645872)
			(xy 2.060448 -25.654508) (xy 2.0701 -25.655524) (xy 2.097982 -25.658806) (xy 2.152426 -25.672507)
			(xy 2.204272 -25.694042) (xy 2.2524 -25.722946) (xy 2.295772 -25.758593) (xy 2.333448 -25.800214)
			(xy 2.364615 -25.846909) (xy 2.3886 -25.897668) (xy 2.402585 -25.943814) (xy 4.265674 -25.943814)
			(xy 4.269745 -25.888192) (xy 4.281871 -25.833755) (xy 4.301794 -25.781664) (xy 4.32909 -25.733029)
			(xy 4.363176 -25.688886) (xy 4.403325 -25.650177) (xy 4.448683 -25.617726) (xy 4.498283 -25.592225)
			(xy 4.551067 -25.574218) (xy 4.60591 -25.564088) (xy 4.661644 -25.562051) (xy 4.717081 -25.568151)
			(xy 4.771038 -25.582257) (xy 4.822367 -25.604069) (xy 4.869973 -25.633123) (xy 4.912841 -25.668798)
			(xy 4.950058 -25.710335) (xy 4.980831 -25.756848) (xy 5.004503 -25.807345) (xy 5.020571 -25.860752)
			(xy 5.028691 -25.915928) (xy 5.0292 -25.943814) (xy 5.028691 -25.9717) (xy 5.020571 -26.026876) (xy 5.018509 -26.03373)
			(xy 5.317488 -26.03373) (xy 5.321559 -25.978108) (xy 5.333685 -25.923671) (xy 5.353608 -25.87158)
			(xy 5.380904 -25.822945) (xy 5.41499 -25.778802) (xy 5.455139 -25.740093) (xy 5.500497 -25.707642)
			(xy 5.550097 -25.682141) (xy 5.602881 -25.664134) (xy 5.657724 -25.654004) (xy 5.713458 -25.651967)
			(xy 5.768895 -25.658067) (xy 5.822852 -25.672173) (xy 5.874181 -25.693985) (xy 5.921787 -25.723039)
			(xy 5.964655 -25.758714) (xy 6.001872 -25.800251) (xy 6.032645 -25.846764) (xy 6.056317 -25.897261)
			(xy 6.072385 -25.950668) (xy 6.080505 -26.005844) (xy 6.081014 -26.03373) (xy 6.080505 -26.061616)
			(xy 6.072385 -26.116792) (xy 6.056317 -26.170199) (xy 6.032645 -26.220696) (xy 6.002411 -26.266394)
			(xy 8.520684 -26.266394) (xy 8.52117 -26.239143) (xy 8.528926 -26.185195) (xy 8.544281 -26.1329)
			(xy 8.566923 -26.083323) (xy 8.596389 -26.037473) (xy 8.63208 -25.996282) (xy 8.673271 -25.960591)
			(xy 8.719121 -25.931125) (xy 8.768698 -25.908483) (xy 8.820993 -25.893128) (xy 8.874941 -25.885372)
			(xy 8.929443 -25.885372) (xy 8.983391 -25.893128) (xy 9.035686 -25.908483) (xy 9.085263 -25.931125)
			(xy 9.131113 -25.960591) (xy 9.172304 -25.996282) (xy 9.207995 -26.037473) (xy 9.237461 -26.083323)
			(xy 9.260103 -26.1329) (xy 9.275458 -26.185195) (xy 9.283214 -26.239143) (xy 9.2837 -26.266394) (xy 9.283148 -26.295882)
			(xy 9.274053 -26.354152) (xy 9.256095 -26.410328) (xy 9.229702 -26.463068) (xy 9.195503 -26.511116)
			(xy 9.154314 -26.553325) (xy 9.131046 -26.571448) (xy 9.119897 -26.580312) (xy 9.102719 -26.603023)
			(xy 9.092477 -26.629593) (xy 9.089965 -26.657958) (xy 9.095379 -26.685914) (xy 9.108298 -26.71129)
			(xy 9.127719 -26.732115) (xy 9.139682 -26.73985) (xy 9.163414 -26.754761) (xy 9.206651 -26.790425)
			(xy 9.244203 -26.832031) (xy 9.275264 -26.878684) (xy 9.299164 -26.92938) (xy 9.31539 -26.983027)
			(xy 9.323591 -27.03847) (xy 9.324086 -27.066494) (xy 9.3236 -27.093745) (xy 9.315844 -27.147693)
			(xy 9.300489 -27.199988) (xy 9.277847 -27.249565) (xy 9.248381 -27.295415) (xy 9.21269 -27.336606)
			(xy 9.205488 -27.342846) (xy 16.523716 -27.342846) (xy 16.523716 -26.479246) (xy 16.524206 -26.449278)
			(xy 16.532029 -26.389856) (xy 16.547542 -26.331963) (xy 16.570478 -26.27659) (xy 16.600445 -26.224684)
			(xy 16.636932 -26.177134) (xy 16.679312 -26.134754) (xy 16.726862 -26.098267) (xy 16.778768 -26.0683)
			(xy 16.834141 -26.045364) (xy 16.892034 -26.029851) (xy 16.951456 -26.022028) (xy 17.011392 -26.022028)
			(xy 17.070814 -26.029851) (xy 17.128707 -26.045364) (xy 17.18408 -26.0683) (xy 17.235986 -26.098267)
			(xy 17.283536 -26.134754) (xy 17.325916 -26.177134) (xy 17.362403 -26.224684) (xy 17.39237 -26.27659)
			(xy 17.415306 -26.331963) (xy 17.423055 -26.360882) (xy 19.089622 -26.360882) (xy 19.093693 -26.30526)
			(xy 19.105819 -26.250823) (xy 19.125742 -26.198732) (xy 19.153038 -26.150097) (xy 19.187124 -26.105954)
			(xy 19.227273 -26.067245) (xy 19.272631 -26.034794) (xy 19.322231 -26.009293) (xy 19.375015 -25.991286)
			(xy 19.429858 -25.981156) (xy 19.485592 -25.979119) (xy 19.541029 -25.985219) (xy 19.594986 -25.999325)
			(xy 19.646315 -26.021137) (xy 19.666949 -26.03373) (xy 31.267906 -26.03373) (xy 31.271977 -25.978108)
			(xy 31.284103 -25.923671) (xy 31.304026 -25.87158) (xy 31.331322 -25.822945) (xy 31.365408 -25.778802)
			(xy 31.405557 -25.740093) (xy 31.450915 -25.707642) (xy 31.500515 -25.682141) (xy 31.553299 -25.664134)
			(xy 31.608142 -25.654004) (xy 31.663876 -25.651967) (xy 31.719313 -25.658067) (xy 31.77327 -25.672173)
			(xy 31.824599 -25.693985) (xy 31.872205 -25.723039) (xy 31.915073 -25.758714) (xy 31.95229 -25.800251)
			(xy 31.983063 -25.846764) (xy 32.006735 -25.897261) (xy 32.022803 -25.950668) (xy 32.030923 -26.005844)
			(xy 32.031432 -26.03373) (xy 32.030923 -26.061616) (xy 32.022803 -26.116792) (xy 32.006735 -26.170199)
			(xy 31.983063 -26.220696) (xy 31.952829 -26.266394) (xy 34.520632 -26.266394) (xy 34.521118 -26.239143)
			(xy 34.528874 -26.185195) (xy 34.544229 -26.1329) (xy 34.566871 -26.083323) (xy 34.596337 -26.037473)
			(xy 34.632028 -25.996282) (xy 34.673219 -25.960591) (xy 34.719069 -25.931125) (xy 34.768646 -25.908483)
			(xy 34.820941 -25.893128) (xy 34.874889 -25.885372) (xy 34.929391 -25.885372) (xy 34.983339 -25.893128)
			(xy 35.035634 -25.908483) (xy 35.085211 -25.931125) (xy 35.131061 -25.960591) (xy 35.172252 -25.996282)
			(xy 35.207943 -26.037473) (xy 35.237409 -26.083323) (xy 35.260051 -26.1329) (xy 35.275406 -26.185195)
			(xy 35.283162 -26.239143) (xy 35.283648 -26.266394) (xy 35.283077 -26.295881) (xy 35.273984 -26.354149)
			(xy 35.256028 -26.410324) (xy 35.229638 -26.463064) (xy 35.195444 -26.511112) (xy 35.15426 -26.553324)
			(xy 35.130994 -26.571448) (xy 35.119838 -26.580307) (xy 35.102651 -26.603017) (xy 35.092403 -26.629589)
			(xy 35.08989 -26.657958) (xy 35.095306 -26.685918) (xy 35.108232 -26.711296) (xy 35.127662 -26.732118)
			(xy 35.13963 -26.73985) (xy 35.163373 -26.754744) (xy 35.206607 -26.790413) (xy 35.244157 -26.832023)
			(xy 35.275216 -26.878679) (xy 35.299114 -26.929376) (xy 35.315339 -26.983025) (xy 35.323539 -27.03847)
			(xy 35.324034 -27.066494) (xy 35.323548 -27.093745) (xy 35.315792 -27.147693) (xy 35.300437 -27.199988)
			(xy 35.277795 -27.249565) (xy 35.248329 -27.295415) (xy 35.212638 -27.336606) (xy 35.205436 -27.342846)
			(xy 42.523664 -27.342846) (xy 42.523664 -26.479246) (xy 42.524154 -26.449278) (xy 42.531977 -26.389856)
			(xy 42.54749 -26.331963) (xy 42.570426 -26.27659) (xy 42.600393 -26.224684) (xy 42.63688 -26.177134)
			(xy 42.67926 -26.134754) (xy 42.72681 -26.098267) (xy 42.778716 -26.0683) (xy 42.834089 -26.045364)
			(xy 42.891982 -26.029851) (xy 42.951404 -26.022028) (xy 43.01134 -26.022028) (xy 43.070762 -26.029851)
			(xy 43.128655 -26.045364) (xy 43.184028 -26.0683) (xy 43.235934 -26.098267) (xy 43.283484 -26.134754)
			(xy 43.325864 -26.177134) (xy 43.362351 -26.224684) (xy 43.392318 -26.27659) (xy 43.415254 -26.331963)
			(xy 43.423003 -26.360882) (xy 45.08957 -26.360882) (xy 45.093641 -26.30526) (xy 45.105767 -26.250823)
			(xy 45.12569 -26.198732) (xy 45.152986 -26.150097) (xy 45.187072 -26.105954) (xy 45.227221 -26.067245)
			(xy 45.272579 -26.034794) (xy 45.322179 -26.009293) (xy 45.374963 -25.991286) (xy 45.429806 -25.981156)
			(xy 45.48554 -25.979119) (xy 45.540977 -25.985219) (xy 45.594934 -25.999325) (xy 45.646263 -26.021137)
			(xy 45.693869 -26.050191) (xy 45.736737 -26.085866) (xy 45.773954 -26.127403) (xy 45.804727 -26.173916)
			(xy 45.828399 -26.224413) (xy 45.844467 -26.27782) (xy 45.850635 -26.319734) (xy 50.841908 -26.319734)
			(xy 50.845979 -26.264112) (xy 50.858105 -26.209675) (xy 50.878028 -26.157584) (xy 50.905324 -26.108949)
			(xy 50.93941 -26.064806) (xy 50.979559 -26.026097) (xy 51.024917 -25.993646) (xy 51.074517 -25.968145)
			(xy 51.127301 -25.950138) (xy 51.182144 -25.940008) (xy 51.237878 -25.937971) (xy 51.293315 -25.944071)
			(xy 51.347272 -25.958177) (xy 51.398601 -25.979989) (xy 51.446207 -26.009043) (xy 51.475872 -26.03373)
			(xy 57.267854 -26.03373) (xy 57.271925 -25.978108) (xy 57.284051 -25.923671) (xy 57.303974 -25.87158)
			(xy 57.33127 -25.822945) (xy 57.365356 -25.778802) (xy 57.405505 -25.740093) (xy 57.450863 -25.707642)
			(xy 57.500463 -25.682141) (xy 57.553247 -25.664134) (xy 57.60809 -25.654004) (xy 57.663824 -25.651967)
			(xy 57.719261 -25.658067) (xy 57.773218 -25.672173) (xy 57.824547 -25.693985) (xy 57.872153 -25.723039)
			(xy 57.915021 -25.758714) (xy 57.952238 -25.800251) (xy 57.983011 -25.846764) (xy 58.006683 -25.897261)
			(xy 58.022751 -25.950668) (xy 58.030871 -26.005844) (xy 58.03138 -26.03373) (xy 58.030871 -26.061616)
			(xy 58.022751 -26.116792) (xy 58.006683 -26.170199) (xy 57.983011 -26.220696) (xy 57.952777 -26.266394)
			(xy 60.52058 -26.266394) (xy 60.521066 -26.239143) (xy 60.528822 -26.185195) (xy 60.544177 -26.1329)
			(xy 60.566819 -26.083323) (xy 60.596285 -26.037473) (xy 60.631976 -25.996282) (xy 60.673167 -25.960591)
			(xy 60.719017 -25.931125) (xy 60.768594 -25.908483) (xy 60.820889 -25.893128) (xy 60.874837 -25.885372)
			(xy 60.929339 -25.885372) (xy 60.983287 -25.893128) (xy 61.035582 -25.908483) (xy 61.085159 -25.931125)
			(xy 61.131009 -25.960591) (xy 61.1722 -25.996282) (xy 61.207891 -26.037473) (xy 61.237357 -26.083323)
			(xy 61.259999 -26.1329) (xy 61.275354 -26.185195) (xy 61.28311 -26.239143) (xy 61.283596 -26.266394)
			(xy 61.283046 -26.295882) (xy 61.273951 -26.354152) (xy 61.255992 -26.410328) (xy 61.229599 -26.463068)
			(xy 61.1954 -26.511116) (xy 61.15421 -26.553325) (xy 61.130942 -26.571448) (xy 61.119794 -26.580313)
			(xy 61.102617 -26.603024) (xy 61.092375 -26.629593) (xy 61.089863 -26.657958) (xy 61.095277 -26.685913)
			(xy 61.108195 -26.71129) (xy 61.127615 -26.732115) (xy 61.139578 -26.73985) (xy 61.16331 -26.754763)
			(xy 61.206546 -26.790426) (xy 61.244099 -26.832032) (xy 61.27516 -26.878685) (xy 61.29906 -26.92938)
			(xy 61.315286 -26.983027) (xy 61.323487 -27.038471) (xy 61.323982 -27.066494) (xy 61.323496 -27.093745)
			(xy 61.31574 -27.147693) (xy 61.300385 -27.199988) (xy 61.277743 -27.249565) (xy 61.248277 -27.295415)
			(xy 61.212586 -27.336606) (xy 61.205384 -27.342846) (xy 68.523612 -27.342846) (xy 68.523612 -26.479246)
			(xy 68.524102 -26.449278) (xy 68.531925 -26.389856) (xy 68.547438 -26.331963) (xy 68.570374 -26.27659)
			(xy 68.600341 -26.224684) (xy 68.636828 -26.177134) (xy 68.679208 -26.134754) (xy 68.726758 -26.098267)
			(xy 68.778664 -26.0683) (xy 68.834037 -26.045364) (xy 68.89193 -26.029851) (xy 68.951352 -26.022028)
			(xy 69.011288 -26.022028) (xy 69.07071 -26.029851) (xy 69.128603 -26.045364) (xy 69.183976 -26.0683)
			(xy 69.235882 -26.098267) (xy 69.283432 -26.134754) (xy 69.325812 -26.177134) (xy 69.362299 -26.224684)
			(xy 69.392266 -26.27659) (xy 69.415202 -26.331963) (xy 69.422951 -26.360882) (xy 71.089518 -26.360882)
			(xy 71.093589 -26.30526) (xy 71.105715 -26.250823) (xy 71.125638 -26.198732) (xy 71.152934 -26.150097)
			(xy 71.18702 -26.105954) (xy 71.227169 -26.067245) (xy 71.272527 -26.034794) (xy 71.322127 -26.009293)
			(xy 71.374911 -25.991286) (xy 71.429754 -25.981156) (xy 71.485488 -25.979119) (xy 71.540925 -25.985219)
			(xy 71.594882 -25.999325) (xy 71.646211 -26.021137) (xy 71.693817 -26.050191) (xy 71.736685 -26.085866)
			(xy 71.773902 -26.127403) (xy 71.804675 -26.173916) (xy 71.828347 -26.224413) (xy 71.844415 -26.27782)
			(xy 71.850583 -26.319734) (xy 76.841856 -26.319734) (xy 76.845927 -26.264112) (xy 76.858053 -26.209675)
			(xy 76.877976 -26.157584) (xy 76.905272 -26.108949) (xy 76.939358 -26.064806) (xy 76.979507 -26.026097)
			(xy 77.024865 -25.993646) (xy 77.074465 -25.968145) (xy 77.127249 -25.950138) (xy 77.182092 -25.940008)
			(xy 77.237826 -25.937971) (xy 77.293263 -25.944071) (xy 77.34722 -25.958177) (xy 77.398549 -25.979989)
			(xy 77.446155 -26.009043) (xy 77.47582 -26.03373) (xy 83.267802 -26.03373) (xy 83.271873 -25.978108)
			(xy 83.283999 -25.923671) (xy 83.303922 -25.87158) (xy 83.331218 -25.822945) (xy 83.365304 -25.778802)
			(xy 83.405453 -25.740093) (xy 83.450811 -25.707642) (xy 83.500411 -25.682141) (xy 83.553195 -25.664134)
			(xy 83.608038 -25.654004) (xy 83.663772 -25.651967) (xy 83.719209 -25.658067) (xy 83.773166 -25.672173)
			(xy 83.824495 -25.693985) (xy 83.872101 -25.723039) (xy 83.914969 -25.758714) (xy 83.952186 -25.800251)
			(xy 83.982959 -25.846764) (xy 84.006631 -25.897261) (xy 84.022699 -25.950668) (xy 84.030819 -26.005844)
			(xy 84.031328 -26.03373) (xy 84.030819 -26.061616) (xy 84.022699 -26.116792) (xy 84.006631 -26.170199)
			(xy 83.982959 -26.220696) (xy 83.952725 -26.266394) (xy 86.520528 -26.266394) (xy 86.521014 -26.239143)
			(xy 86.52877 -26.185195) (xy 86.544125 -26.1329) (xy 86.566767 -26.083323) (xy 86.596233 -26.037473)
			(xy 86.631924 -25.996282) (xy 86.673115 -25.960591) (xy 86.718965 -25.931125) (xy 86.768542 -25.908483)
			(xy 86.820837 -25.893128) (xy 86.874785 -25.885372) (xy 86.929287 -25.885372) (xy 86.983235 -25.893128)
			(xy 87.03553 -25.908483) (xy 87.085107 -25.931125) (xy 87.130957 -25.960591) (xy 87.172148 -25.996282)
			(xy 87.207839 -26.037473) (xy 87.237305 -26.083323) (xy 87.259947 -26.1329) (xy 87.275302 -26.185195)
			(xy 87.283058 -26.239143) (xy 87.283544 -26.266394) (xy 87.282975 -26.295881) (xy 87.273881 -26.35415)
			(xy 87.255925 -26.410324) (xy 87.229535 -26.463064) (xy 87.19534 -26.511112) (xy 87.154156 -26.553324)
			(xy 87.13089 -26.571448) (xy 87.119734 -26.580307) (xy 87.102549 -26.603017) (xy 87.092301 -26.629589)
			(xy 87.089788 -26.657958) (xy 87.095204 -26.685918) (xy 87.108129 -26.711295) (xy 87.127559 -26.732118)
			(xy 87.139526 -26.73985) (xy 87.163268 -26.754746) (xy 87.206502 -26.790414) (xy 87.244053 -26.832023)
			(xy 87.275111 -26.878679) (xy 87.29901 -26.929377) (xy 87.315235 -26.983025) (xy 87.323435 -27.03847)
			(xy 87.32393 -27.066494) (xy 87.323444 -27.093745) (xy 87.315688 -27.147693) (xy 87.300333 -27.199988)
			(xy 87.277691 -27.249565) (xy 87.248225 -27.295415) (xy 87.212534 -27.336606) (xy 87.205332 -27.342846)
			(xy 94.52356 -27.342846) (xy 94.52356 -26.479246) (xy 94.52405 -26.449278) (xy 94.531873 -26.389856)
			(xy 94.547386 -26.331963) (xy 94.570322 -26.27659) (xy 94.600289 -26.224684) (xy 94.636776 -26.177134)
			(xy 94.679156 -26.134754) (xy 94.726706 -26.098267) (xy 94.778612 -26.0683) (xy 94.833985 -26.045364)
			(xy 94.891878 -26.029851) (xy 94.9513 -26.022028) (xy 95.011236 -26.022028) (xy 95.070658 -26.029851)
			(xy 95.128551 -26.045364) (xy 95.183924 -26.0683) (xy 95.23583 -26.098267) (xy 95.28338 -26.134754)
			(xy 95.32576 -26.177134) (xy 95.362247 -26.224684) (xy 95.392214 -26.27659) (xy 95.41515 -26.331963)
			(xy 95.422899 -26.360882) (xy 97.089466 -26.360882) (xy 97.093537 -26.30526) (xy 97.105663 -26.250823)
			(xy 97.125586 -26.198732) (xy 97.152882 -26.150097) (xy 97.186968 -26.105954) (xy 97.227117 -26.067245)
			(xy 97.272475 -26.034794) (xy 97.322075 -26.009293) (xy 97.374859 -25.991286) (xy 97.429702 -25.981156)
			(xy 97.485436 -25.979119) (xy 97.540873 -25.985219) (xy 97.59483 -25.999325) (xy 97.646159 -26.021137)
			(xy 97.693765 -26.050191) (xy 97.736633 -26.085866) (xy 97.77385 -26.127403) (xy 97.804623 -26.173916)
			(xy 97.828295 -26.224413) (xy 97.844363 -26.27782) (xy 97.850531 -26.319734) (xy 102.841804 -26.319734)
			(xy 102.845875 -26.264112) (xy 102.858001 -26.209675) (xy 102.877924 -26.157584) (xy 102.90522 -26.108949)
			(xy 102.939306 -26.064806) (xy 102.979455 -26.026097) (xy 103.024813 -25.993646) (xy 103.074413 -25.968145)
			(xy 103.127197 -25.950138) (xy 103.18204 -25.940008) (xy 103.237774 -25.937971) (xy 103.293211 -25.944071)
			(xy 103.347168 -25.958177) (xy 103.398497 -25.979989) (xy 103.446103 -26.009043) (xy 103.475768 -26.03373)
			(xy 121.368056 -26.03373) (xy 121.372127 -25.978108) (xy 121.384253 -25.923671) (xy 121.404176 -25.87158)
			(xy 121.431472 -25.822945) (xy 121.465558 -25.778802) (xy 121.505707 -25.740093) (xy 121.551065 -25.707642)
			(xy 121.600665 -25.682141) (xy 121.653449 -25.664134) (xy 121.708292 -25.654004) (xy 121.764026 -25.651967)
			(xy 121.819463 -25.658067) (xy 121.87342 -25.672173) (xy 121.924749 -25.693985) (xy 121.972355 -25.723039)
			(xy 122.015223 -25.758714) (xy 122.05244 -25.800251) (xy 122.083213 -25.846764) (xy 122.106885 -25.897261)
			(xy 122.122953 -25.950668) (xy 122.131073 -26.005844) (xy 122.131582 -26.03373) (xy 122.131073 -26.061616)
			(xy 122.122953 -26.116792) (xy 122.106885 -26.170199) (xy 122.083213 -26.220696) (xy 122.052979 -26.266394)
			(xy 124.620782 -26.266394) (xy 124.621268 -26.239143) (xy 124.629024 -26.185195) (xy 124.644379 -26.1329)
			(xy 124.667021 -26.083323) (xy 124.696487 -26.037473) (xy 124.732178 -25.996282) (xy 124.773369 -25.960591)
			(xy 124.819219 -25.931125) (xy 124.868796 -25.908483) (xy 124.921091 -25.893128) (xy 124.975039 -25.885372)
			(xy 125.029541 -25.885372) (xy 125.083489 -25.893128) (xy 125.135784 -25.908483) (xy 125.185361 -25.931125)
			(xy 125.231211 -25.960591) (xy 125.272402 -25.996282) (xy 125.308093 -26.037473) (xy 125.337559 -26.083323)
			(xy 125.360201 -26.1329) (xy 125.375556 -26.185195) (xy 125.383312 -26.239143) (xy 125.383798 -26.266394)
			(xy 125.383247 -26.295882) (xy 125.374152 -26.354152) (xy 125.356194 -26.410328) (xy 125.3298 -26.463068)
			(xy 125.295601 -26.511116) (xy 125.254412 -26.553325) (xy 125.231144 -26.571448) (xy 125.219995 -26.580313)
			(xy 125.202818 -26.603024) (xy 125.192576 -26.629593) (xy 125.190064 -26.657958) (xy 125.195478 -26.685914)
			(xy 125.208397 -26.71129) (xy 125.227817 -26.732115) (xy 125.23978 -26.73985) (xy 125.263512 -26.754762)
			(xy 125.306748 -26.790426) (xy 125.344301 -26.832032) (xy 125.375362 -26.878684) (xy 125.399262 -26.92938)
			(xy 125.415488 -26.983027) (xy 125.423689 -27.038471) (xy 125.424184 -27.066494) (xy 125.423698 -27.093745)
			(xy 125.415942 -27.147693) (xy 125.400587 -27.199988) (xy 125.377945 -27.249565) (xy 125.348479 -27.295415)
			(xy 125.312788 -27.336606) (xy 125.305586 -27.342846) (xy 132.62356 -27.342846) (xy 132.62356 -26.479246)
			(xy 132.62405 -26.449262) (xy 132.631878 -26.389806) (xy 132.647399 -26.331881) (xy 132.670348 -26.276477)
			(xy 132.700332 -26.224543) (xy 132.736838 -26.176967) (xy 132.779243 -26.134562) (xy 132.826819 -26.098056)
			(xy 132.878753 -26.068072) (xy 132.934157 -26.045123) (xy 132.992082 -26.029602) (xy 133.051538 -26.021774)
			(xy 133.111506 -26.021774) (xy 133.170962 -26.029602) (xy 133.228887 -26.045123) (xy 133.284291 -26.068072)
			(xy 133.336225 -26.098056) (xy 133.383801 -26.134562) (xy 133.426206 -26.176967) (xy 133.462712 -26.224543)
			(xy 133.492696 -26.276477) (xy 133.515645 -26.331881) (xy 133.523416 -26.360882) (xy 135.18972 -26.360882)
			(xy 135.193791 -26.30526) (xy 135.205917 -26.250823) (xy 135.22584 -26.198732) (xy 135.253136 -26.150097)
			(xy 135.287222 -26.105954) (xy 135.327371 -26.067245) (xy 135.372729 -26.034794) (xy 135.422329 -26.009293)
			(xy 135.475113 -25.991286) (xy 135.529956 -25.981156) (xy 135.58569 -25.979119) (xy 135.641127 -25.985219)
			(xy 135.695084 -25.999325) (xy 135.746413 -26.021137) (xy 135.794019 -26.050191) (xy 135.836887 -26.085866)
			(xy 135.874104 -26.127403) (xy 135.904877 -26.173916) (xy 135.928549 -26.224413) (xy 135.944617 -26.27782)
			(xy 135.950785 -26.319734) (xy 140.942058 -26.319734) (xy 140.946129 -26.264112) (xy 140.958255 -26.209675)
			(xy 140.978178 -26.157584) (xy 141.005474 -26.108949) (xy 141.03956 -26.064806) (xy 141.079709 -26.026097)
			(xy 141.125067 -25.993646) (xy 141.174667 -25.968145) (xy 141.227451 -25.950138) (xy 141.282294 -25.940008)
			(xy 141.338028 -25.937971) (xy 141.393465 -25.944071) (xy 141.447422 -25.958177) (xy 141.498751 -25.979989)
			(xy 141.546357 -26.009043) (xy 141.576022 -26.03373) (xy 147.368004 -26.03373) (xy 147.372075 -25.978108)
			(xy 147.384201 -25.923671) (xy 147.404124 -25.87158) (xy 147.43142 -25.822945) (xy 147.465506 -25.778802)
			(xy 147.505655 -25.740093) (xy 147.551013 -25.707642) (xy 147.600613 -25.682141) (xy 147.653397 -25.664134)
			(xy 147.70824 -25.654004) (xy 147.763974 -25.651967) (xy 147.819411 -25.658067) (xy 147.873368 -25.672173)
			(xy 147.924697 -25.693985) (xy 147.972303 -25.723039) (xy 148.015171 -25.758714) (xy 148.052388 -25.800251)
			(xy 148.083161 -25.846764) (xy 148.106833 -25.897261) (xy 148.122901 -25.950668) (xy 148.131021 -26.005844)
			(xy 148.13153 -26.03373) (xy 148.131021 -26.061616) (xy 148.122901 -26.116792) (xy 148.106833 -26.170199)
			(xy 148.083161 -26.220696) (xy 148.052927 -26.266394) (xy 150.62073 -26.266394) (xy 150.621216 -26.239143)
			(xy 150.628972 -26.185195) (xy 150.644327 -26.1329) (xy 150.666969 -26.083323) (xy 150.696435 -26.037473)
			(xy 150.732126 -25.996282) (xy 150.773317 -25.960591) (xy 150.819167 -25.931125) (xy 150.868744 -25.908483)
			(xy 150.921039 -25.893128) (xy 150.974987 -25.885372) (xy 151.029489 -25.885372) (xy 151.083437 -25.893128)
			(xy 151.135732 -25.908483) (xy 151.185309 -25.931125) (xy 151.231159 -25.960591) (xy 151.27235 -25.996282)
			(xy 151.308041 -26.037473) (xy 151.337507 -26.083323) (xy 151.360149 -26.1329) (xy 151.375504 -26.185195)
			(xy 151.38326 -26.239143) (xy 151.383746 -26.266394) (xy 151.383176 -26.295881) (xy 151.374082 -26.35415)
			(xy 151.356127 -26.410324) (xy 151.329737 -26.463064) (xy 151.295542 -26.511112) (xy 151.254358 -26.553324)
			(xy 151.231092 -26.571448) (xy 151.219936 -26.580307) (xy 151.20275 -26.603017) (xy 151.192502 -26.629589)
			(xy 151.189989 -26.657958) (xy 151.195405 -26.685918) (xy 151.208331 -26.711295) (xy 151.227761 -26.732118)
			(xy 151.239728 -26.73985) (xy 151.263471 -26.754745) (xy 151.306705 -26.790413) (xy 151.344255 -26.832023)
			(xy 151.375314 -26.878679) (xy 151.399212 -26.929376) (xy 151.415437 -26.983025) (xy 151.423637 -27.03847)
			(xy 151.424132 -27.066494) (xy 151.423646 -27.093745) (xy 151.41589 -27.147693) (xy 151.400535 -27.199988)
			(xy 151.377893 -27.249565) (xy 151.348427 -27.295415) (xy 151.312736 -27.336606) (xy 151.305534 -27.342846)
			(xy 158.623508 -27.342846) (xy 158.623508 -26.479246) (xy 158.623998 -26.449262) (xy 158.631826 -26.389806)
			(xy 158.647347 -26.331881) (xy 158.670296 -26.276477) (xy 158.70028 -26.224543) (xy 158.736786 -26.176967)
			(xy 158.779191 -26.134562) (xy 158.826767 -26.098056) (xy 158.878701 -26.068072) (xy 158.934105 -26.045123)
			(xy 158.99203 -26.029602) (xy 159.051486 -26.021774) (xy 159.111454 -26.021774) (xy 159.17091 -26.029602)
			(xy 159.228835 -26.045123) (xy 159.284239 -26.068072) (xy 159.336173 -26.098056) (xy 159.383749 -26.134562)
			(xy 159.426154 -26.176967) (xy 159.46266 -26.224543) (xy 159.492644 -26.276477) (xy 159.515593 -26.331881)
			(xy 159.523364 -26.360882) (xy 161.189668 -26.360882) (xy 161.193739 -26.30526) (xy 161.205865 -26.250823)
			(xy 161.225788 -26.198732) (xy 161.253084 -26.150097) (xy 161.28717 -26.105954) (xy 161.327319 -26.067245)
			(xy 161.372677 -26.034794) (xy 161.422277 -26.009293) (xy 161.475061 -25.991286) (xy 161.529904 -25.981156)
			(xy 161.585638 -25.979119) (xy 161.641075 -25.985219) (xy 161.695032 -25.999325) (xy 161.746361 -26.021137)
			(xy 161.793967 -26.050191) (xy 161.836835 -26.085866) (xy 161.874052 -26.127403) (xy 161.904825 -26.173916)
			(xy 161.928497 -26.224413) (xy 161.944565 -26.27782) (xy 161.950733 -26.319734) (xy 166.942006 -26.319734)
			(xy 166.946077 -26.264112) (xy 166.958203 -26.209675) (xy 166.978126 -26.157584) (xy 167.005422 -26.108949)
			(xy 167.039508 -26.064806) (xy 167.079657 -26.026097) (xy 167.125015 -25.993646) (xy 167.174615 -25.968145)
			(xy 167.227399 -25.950138) (xy 167.282242 -25.940008) (xy 167.337976 -25.937971) (xy 167.393413 -25.944071)
			(xy 167.44737 -25.958177) (xy 167.498699 -25.979989) (xy 167.546305 -26.009043) (xy 167.57597 -26.03373)
			(xy 173.367952 -26.03373) (xy 173.372023 -25.978108) (xy 173.384149 -25.923671) (xy 173.404072 -25.87158)
			(xy 173.431368 -25.822945) (xy 173.465454 -25.778802) (xy 173.505603 -25.740093) (xy 173.550961 -25.707642)
			(xy 173.600561 -25.682141) (xy 173.653345 -25.664134) (xy 173.708188 -25.654004) (xy 173.763922 -25.651967)
			(xy 173.819359 -25.658067) (xy 173.873316 -25.672173) (xy 173.924645 -25.693985) (xy 173.972251 -25.723039)
			(xy 174.015119 -25.758714) (xy 174.052336 -25.800251) (xy 174.083109 -25.846764) (xy 174.106781 -25.897261)
			(xy 174.122849 -25.950668) (xy 174.130969 -26.005844) (xy 174.131478 -26.03373) (xy 174.130969 -26.061616)
			(xy 174.122849 -26.116792) (xy 174.106781 -26.170199) (xy 174.083109 -26.220696) (xy 174.052875 -26.266394)
			(xy 176.620678 -26.266394) (xy 176.621164 -26.239143) (xy 176.62892 -26.185195) (xy 176.644275 -26.1329)
			(xy 176.666917 -26.083323) (xy 176.696383 -26.037473) (xy 176.732074 -25.996282) (xy 176.773265 -25.960591)
			(xy 176.819115 -25.931125) (xy 176.868692 -25.908483) (xy 176.920987 -25.893128) (xy 176.974935 -25.885372)
			(xy 177.029437 -25.885372) (xy 177.083385 -25.893128) (xy 177.13568 -25.908483) (xy 177.185257 -25.931125)
			(xy 177.231107 -25.960591) (xy 177.272298 -25.996282) (xy 177.307989 -26.037473) (xy 177.337455 -26.083323)
			(xy 177.360097 -26.1329) (xy 177.375452 -26.185195) (xy 177.383208 -26.239143) (xy 177.383694 -26.266394)
			(xy 177.383144 -26.295882) (xy 177.37405 -26.354153) (xy 177.356091 -26.410328) (xy 177.329697 -26.463069)
			(xy 177.295498 -26.511116) (xy 177.254308 -26.553325) (xy 177.23104 -26.571448) (xy 177.219892 -26.580313)
			(xy 177.202715 -26.603024) (xy 177.192474 -26.629594) (xy 177.189962 -26.657958) (xy 177.195375 -26.685913)
			(xy 177.208294 -26.711289) (xy 177.227714 -26.732115) (xy 177.239676 -26.73985) (xy 177.263407 -26.754763)
			(xy 177.306643 -26.790427) (xy 177.344196 -26.832032) (xy 177.375257 -26.878685) (xy 177.399158 -26.92938)
			(xy 177.415384 -26.983027) (xy 177.423585 -27.038471) (xy 177.42408 -27.066494) (xy 177.423594 -27.093745)
			(xy 177.415838 -27.147693) (xy 177.400483 -27.199988) (xy 177.377841 -27.249565) (xy 177.348375 -27.295415)
			(xy 177.312684 -27.336606) (xy 177.305482 -27.342846) (xy 184.623456 -27.342846) (xy 184.623456 -26.479246)
			(xy 184.623946 -26.449262) (xy 184.631774 -26.389806) (xy 184.647295 -26.331881) (xy 184.670244 -26.276477)
			(xy 184.700228 -26.224543) (xy 184.736734 -26.176967) (xy 184.779139 -26.134562) (xy 184.826715 -26.098056)
			(xy 184.878649 -26.068072) (xy 184.934053 -26.045123) (xy 184.991978 -26.029602) (xy 185.051434 -26.021774)
			(xy 185.111402 -26.021774) (xy 185.170858 -26.029602) (xy 185.228783 -26.045123) (xy 185.284187 -26.068072)
			(xy 185.336121 -26.098056) (xy 185.383697 -26.134562) (xy 185.426102 -26.176967) (xy 185.462608 -26.224543)
			(xy 185.492592 -26.276477) (xy 185.515541 -26.331881) (xy 185.523312 -26.360882) (xy 187.189616 -26.360882)
			(xy 187.193687 -26.30526) (xy 187.205813 -26.250823) (xy 187.225736 -26.198732) (xy 187.253032 -26.150097)
			(xy 187.287118 -26.105954) (xy 187.327267 -26.067245) (xy 187.372625 -26.034794) (xy 187.422225 -26.009293)
			(xy 187.475009 -25.991286) (xy 187.529852 -25.981156) (xy 187.585586 -25.979119) (xy 187.641023 -25.985219)
			(xy 187.69498 -25.999325) (xy 187.746309 -26.021137) (xy 187.793915 -26.050191) (xy 187.836783 -26.085866)
			(xy 187.874 -26.127403) (xy 187.904773 -26.173916) (xy 187.928445 -26.224413) (xy 187.944513 -26.27782)
			(xy 187.950681 -26.319734) (xy 192.941954 -26.319734) (xy 192.946025 -26.264112) (xy 192.958151 -26.209675)
			(xy 192.978074 -26.157584) (xy 193.00537 -26.108949) (xy 193.039456 -26.064806) (xy 193.079605 -26.026097)
			(xy 193.124963 -25.993646) (xy 193.174563 -25.968145) (xy 193.227347 -25.950138) (xy 193.28219 -25.940008)
			(xy 193.337924 -25.937971) (xy 193.393361 -25.944071) (xy 193.447318 -25.958177) (xy 193.498647 -25.979989)
			(xy 193.546253 -26.009043) (xy 193.575918 -26.03373) (xy 199.3679 -26.03373) (xy 199.371971 -25.978108)
			(xy 199.384097 -25.923671) (xy 199.40402 -25.87158) (xy 199.431316 -25.822945) (xy 199.465402 -25.778802)
			(xy 199.505551 -25.740093) (xy 199.550909 -25.707642) (xy 199.600509 -25.682141) (xy 199.653293 -25.664134)
			(xy 199.708136 -25.654004) (xy 199.76387 -25.651967) (xy 199.819307 -25.658067) (xy 199.873264 -25.672173)
			(xy 199.924593 -25.693985) (xy 199.972199 -25.723039) (xy 200.015067 -25.758714) (xy 200.052284 -25.800251)
			(xy 200.083057 -25.846764) (xy 200.106729 -25.897261) (xy 200.122797 -25.950668) (xy 200.130917 -26.005844)
			(xy 200.131426 -26.03373) (xy 200.130917 -26.061616) (xy 200.122797 -26.116792) (xy 200.106729 -26.170199)
			(xy 200.083057 -26.220696) (xy 200.052823 -26.266394) (xy 202.620626 -26.266394) (xy 202.621112 -26.239143)
			(xy 202.628868 -26.185195) (xy 202.644223 -26.1329) (xy 202.666865 -26.083323) (xy 202.696331 -26.037473)
			(xy 202.732022 -25.996282) (xy 202.773213 -25.960591) (xy 202.819063 -25.931125) (xy 202.86864 -25.908483)
			(xy 202.920935 -25.893128) (xy 202.974883 -25.885372) (xy 203.029385 -25.885372) (xy 203.083333 -25.893128)
			(xy 203.135628 -25.908483) (xy 203.185205 -25.931125) (xy 203.231055 -25.960591) (xy 203.272246 -25.996282)
			(xy 203.307937 -26.037473) (xy 203.337403 -26.083323) (xy 203.360045 -26.1329) (xy 203.3754 -26.185195)
			(xy 203.383156 -26.239143) (xy 203.383642 -26.266394) (xy 203.383073 -26.295881) (xy 203.37398 -26.35415)
			(xy 203.356024 -26.410324) (xy 203.329634 -26.463064) (xy 203.295439 -26.511113) (xy 203.254254 -26.553324)
			(xy 203.230988 -26.571448) (xy 203.219833 -26.580307) (xy 203.202647 -26.603017) (xy 203.1924 -26.629589)
			(xy 203.189887 -26.657958) (xy 203.195303 -26.685917) (xy 203.208228 -26.711295) (xy 203.227657 -26.732118)
			(xy 203.239624 -26.73985) (xy 203.263366 -26.754746) (xy 203.3066 -26.790414) (xy 203.344151 -26.832024)
			(xy 203.375209 -26.878679) (xy 203.399108 -26.929377) (xy 203.415333 -26.983025) (xy 203.423533 -27.03847)
			(xy 203.424028 -27.066494) (xy 203.423542 -27.093745) (xy 203.415786 -27.147693) (xy 203.400431 -27.199988)
			(xy 203.377789 -27.249565) (xy 203.348323 -27.295415) (xy 203.312632 -27.336606) (xy 203.30543 -27.342846)
			(xy 210.623404 -27.342846) (xy 210.623404 -26.479246) (xy 210.623894 -26.449262) (xy 210.631722 -26.389806)
			(xy 210.647243 -26.331881) (xy 210.670192 -26.276477) (xy 210.700176 -26.224543) (xy 210.736682 -26.176967)
			(xy 210.779087 -26.134562) (xy 210.826663 -26.098056) (xy 210.878597 -26.068072) (xy 210.934001 -26.045123)
			(xy 210.991926 -26.029602) (xy 211.051382 -26.021774) (xy 211.11135 -26.021774) (xy 211.170806 -26.029602)
			(xy 211.228731 -26.045123) (xy 211.284135 -26.068072) (xy 211.336069 -26.098056) (xy 211.383645 -26.134562)
			(xy 211.42605 -26.176967) (xy 211.462556 -26.224543) (xy 211.49254 -26.276477) (xy 211.515489 -26.331881)
			(xy 211.52326 -26.360882) (xy 213.189564 -26.360882) (xy 213.193635 -26.30526) (xy 213.205761 -26.250823)
			(xy 213.225684 -26.198732) (xy 213.25298 -26.150097) (xy 213.287066 -26.105954) (xy 213.327215 -26.067245)
			(xy 213.372573 -26.034794) (xy 213.422173 -26.009293) (xy 213.474957 -25.991286) (xy 213.5298 -25.981156)
			(xy 213.585534 -25.979119) (xy 213.640971 -25.985219) (xy 213.694928 -25.999325) (xy 213.746257 -26.021137)
			(xy 213.793863 -26.050191) (xy 213.836731 -26.085866) (xy 213.873948 -26.127403) (xy 213.904721 -26.173916)
			(xy 213.928393 -26.224413) (xy 213.944461 -26.27782) (xy 213.950629 -26.319734) (xy 218.941902 -26.319734)
			(xy 218.945973 -26.264112) (xy 218.958099 -26.209675) (xy 218.978022 -26.157584) (xy 219.005318 -26.108949)
			(xy 219.039404 -26.064806) (xy 219.079553 -26.026097) (xy 219.124911 -25.993646) (xy 219.174511 -25.968145)
			(xy 219.227295 -25.950138) (xy 219.282138 -25.940008) (xy 219.337872 -25.937971) (xy 219.393309 -25.944071)
			(xy 219.447266 -25.958177) (xy 219.498595 -25.979989) (xy 219.546201 -26.009043) (xy 219.575866 -26.03373)
			(xy 237.4679 -26.03373) (xy 237.471971 -25.978108) (xy 237.484097 -25.923671) (xy 237.50402 -25.87158)
			(xy 237.531316 -25.822945) (xy 237.565402 -25.778802) (xy 237.605551 -25.740093) (xy 237.650909 -25.707642)
			(xy 237.700509 -25.682141) (xy 237.753293 -25.664134) (xy 237.808136 -25.654004) (xy 237.86387 -25.651967)
			(xy 237.919307 -25.658067) (xy 237.973264 -25.672173) (xy 238.024593 -25.693985) (xy 238.072199 -25.723039)
			(xy 238.115067 -25.758714) (xy 238.152284 -25.800251) (xy 238.183057 -25.846764) (xy 238.206729 -25.897261)
			(xy 238.222797 -25.950668) (xy 238.230917 -26.005844) (xy 238.231426 -26.03373) (xy 238.230917 -26.061616)
			(xy 238.222797 -26.116792) (xy 238.206729 -26.170199) (xy 238.183057 -26.220696) (xy 238.152823 -26.266394)
			(xy 240.720626 -26.266394) (xy 240.721112 -26.239143) (xy 240.728868 -26.185195) (xy 240.744223 -26.1329)
			(xy 240.766865 -26.083323) (xy 240.796331 -26.037473) (xy 240.832022 -25.996282) (xy 240.873213 -25.960591)
			(xy 240.919063 -25.931125) (xy 240.96864 -25.908483) (xy 241.020935 -25.893128) (xy 241.074883 -25.885372)
			(xy 241.129385 -25.885372) (xy 241.183333 -25.893128) (xy 241.235628 -25.908483) (xy 241.285205 -25.931125)
			(xy 241.331055 -25.960591) (xy 241.372246 -25.996282) (xy 241.407937 -26.037473) (xy 241.437403 -26.083323)
			(xy 241.460045 -26.1329) (xy 241.4754 -26.185195) (xy 241.483156 -26.239143) (xy 241.483642 -26.266394)
			(xy 241.483073 -26.295881) (xy 241.47398 -26.35415) (xy 241.456024 -26.410324) (xy 241.429634 -26.463064)
			(xy 241.395439 -26.511113) (xy 241.354254 -26.553324) (xy 241.330988 -26.571448) (xy 241.319833 -26.580307)
			(xy 241.302647 -26.603017) (xy 241.2924 -26.629589) (xy 241.289887 -26.657958) (xy 241.295303 -26.685917)
			(xy 241.308228 -26.711295) (xy 241.327657 -26.732118) (xy 241.339624 -26.73985) (xy 241.363366 -26.754746)
			(xy 241.4066 -26.790414) (xy 241.444151 -26.832024) (xy 241.475209 -26.878679) (xy 241.499108 -26.929377)
			(xy 241.515333 -26.983025) (xy 241.523533 -27.03847) (xy 241.524028 -27.066494) (xy 241.523542 -27.093745)
			(xy 241.515786 -27.147693) (xy 241.500431 -27.199988) (xy 241.477789 -27.249565) (xy 241.448323 -27.295415)
			(xy 241.412632 -27.336606) (xy 241.40543 -27.342846) (xy 248.723404 -27.342846) (xy 248.723404 -26.479246)
			(xy 248.723894 -26.449262) (xy 248.731722 -26.389806) (xy 248.747243 -26.331881) (xy 248.770192 -26.276477)
			(xy 248.800176 -26.224543) (xy 248.836682 -26.176967) (xy 248.879087 -26.134562) (xy 248.926663 -26.098056)
			(xy 248.978597 -26.068072) (xy 249.034001 -26.045123) (xy 249.091926 -26.029602) (xy 249.151382 -26.021774)
			(xy 249.21135 -26.021774) (xy 249.270806 -26.029602) (xy 249.328731 -26.045123) (xy 249.384135 -26.068072)
			(xy 249.436069 -26.098056) (xy 249.483645 -26.134562) (xy 249.52605 -26.176967) (xy 249.562556 -26.224543)
			(xy 249.59254 -26.276477) (xy 249.615489 -26.331881) (xy 249.62326 -26.360882) (xy 251.289564 -26.360882)
			(xy 251.293635 -26.30526) (xy 251.305761 -26.250823) (xy 251.325684 -26.198732) (xy 251.35298 -26.150097)
			(xy 251.387066 -26.105954) (xy 251.427215 -26.067245) (xy 251.472573 -26.034794) (xy 251.522173 -26.009293)
			(xy 251.574957 -25.991286) (xy 251.6298 -25.981156) (xy 251.685534 -25.979119) (xy 251.740971 -25.985219)
			(xy 251.794928 -25.999325) (xy 251.846257 -26.021137) (xy 251.893863 -26.050191) (xy 251.936731 -26.085866)
			(xy 251.973948 -26.127403) (xy 252.004721 -26.173916) (xy 252.028393 -26.224413) (xy 252.044461 -26.27782)
			(xy 252.050629 -26.319734) (xy 257.041902 -26.319734) (xy 257.045973 -26.264112) (xy 257.058099 -26.209675)
			(xy 257.078022 -26.157584) (xy 257.105318 -26.108949) (xy 257.139404 -26.064806) (xy 257.179553 -26.026097)
			(xy 257.224911 -25.993646) (xy 257.274511 -25.968145) (xy 257.327295 -25.950138) (xy 257.382138 -25.940008)
			(xy 257.437872 -25.937971) (xy 257.493309 -25.944071) (xy 257.547266 -25.958177) (xy 257.598595 -25.979989)
			(xy 257.646201 -26.009043) (xy 257.675866 -26.03373) (xy 263.467848 -26.03373) (xy 263.471919 -25.978108)
			(xy 263.484045 -25.923671) (xy 263.503968 -25.87158) (xy 263.531264 -25.822945) (xy 263.56535 -25.778802)
			(xy 263.605499 -25.740093) (xy 263.650857 -25.707642) (xy 263.700457 -25.682141) (xy 263.753241 -25.664134)
			(xy 263.808084 -25.654004) (xy 263.863818 -25.651967) (xy 263.919255 -25.658067) (xy 263.973212 -25.672173)
			(xy 264.024541 -25.693985) (xy 264.072147 -25.723039) (xy 264.115015 -25.758714) (xy 264.152232 -25.800251)
			(xy 264.183005 -25.846764) (xy 264.206677 -25.897261) (xy 264.222745 -25.950668) (xy 264.230865 -26.005844)
			(xy 264.231374 -26.03373) (xy 264.230865 -26.061616) (xy 264.222745 -26.116792) (xy 264.206677 -26.170199)
			(xy 264.183005 -26.220696) (xy 264.152771 -26.266394) (xy 266.720574 -26.266394) (xy 266.72106 -26.239143)
			(xy 266.728816 -26.185195) (xy 266.744171 -26.1329) (xy 266.766813 -26.083323) (xy 266.796279 -26.037473)
			(xy 266.83197 -25.996282) (xy 266.873161 -25.960591) (xy 266.919011 -25.931125) (xy 266.968588 -25.908483)
			(xy 267.020883 -25.893128) (xy 267.074831 -25.885372) (xy 267.129333 -25.885372) (xy 267.183281 -25.893128)
			(xy 267.235576 -25.908483) (xy 267.285153 -25.931125) (xy 267.331003 -25.960591) (xy 267.372194 -25.996282)
			(xy 267.407885 -26.037473) (xy 267.437351 -26.083323) (xy 267.459993 -26.1329) (xy 267.475348 -26.185195)
			(xy 267.483104 -26.239143) (xy 267.48359 -26.266394) (xy 267.483042 -26.295882) (xy 267.473947 -26.354153)
			(xy 267.455988 -26.410328) (xy 267.429594 -26.463069) (xy 267.395395 -26.511117) (xy 267.354205 -26.553326)
			(xy 267.330936 -26.571448) (xy 267.319789 -26.580314) (xy 267.302613 -26.603025) (xy 267.292371 -26.629594)
			(xy 267.28986 -26.657958) (xy 267.295273 -26.685913) (xy 267.308191 -26.711289) (xy 267.32761 -26.732114)
			(xy 267.339572 -26.73985) (xy 267.363302 -26.754765) (xy 267.406539 -26.790428) (xy 267.444092 -26.832033)
			(xy 267.475153 -26.878685) (xy 267.499054 -26.929381) (xy 267.51528 -26.983027) (xy 267.523481 -27.038471)
			(xy 267.523976 -27.066494) (xy 267.52349 -27.093745) (xy 267.515734 -27.147693) (xy 267.500379 -27.199988)
			(xy 267.477737 -27.249565) (xy 267.448271 -27.295415) (xy 267.41258 -27.336606) (xy 267.405378 -27.342846)
			(xy 274.723352 -27.342846) (xy 274.723352 -26.479246) (xy 274.723842 -26.449262) (xy 274.73167 -26.389806)
			(xy 274.747191 -26.331881) (xy 274.77014 -26.276477) (xy 274.800124 -26.224543) (xy 274.83663 -26.176967)
			(xy 274.879035 -26.134562) (xy 274.926611 -26.098056) (xy 274.978545 -26.068072) (xy 275.033949 -26.045123)
			(xy 275.091874 -26.029602) (xy 275.15133 -26.021774) (xy 275.211298 -26.021774) (xy 275.270754 -26.029602)
			(xy 275.328679 -26.045123) (xy 275.384083 -26.068072) (xy 275.436017 -26.098056) (xy 275.483593 -26.134562)
			(xy 275.525998 -26.176967) (xy 275.562504 -26.224543) (xy 275.592488 -26.276477) (xy 275.615437 -26.331881)
			(xy 275.623208 -26.360882) (xy 277.289512 -26.360882) (xy 277.293583 -26.30526) (xy 277.305709 -26.250823)
			(xy 277.325632 -26.198732) (xy 277.352928 -26.150097) (xy 277.387014 -26.105954) (xy 277.427163 -26.067245)
			(xy 277.472521 -26.034794) (xy 277.522121 -26.009293) (xy 277.574905 -25.991286) (xy 277.629748 -25.981156)
			(xy 277.685482 -25.979119) (xy 277.740919 -25.985219) (xy 277.794876 -25.999325) (xy 277.846205 -26.021137)
			(xy 277.893811 -26.050191) (xy 277.936679 -26.085866) (xy 277.973896 -26.127403) (xy 278.004669 -26.173916)
			(xy 278.028341 -26.224413) (xy 278.044409 -26.27782) (xy 278.050577 -26.319734) (xy 283.04185 -26.319734)
			(xy 283.045921 -26.264112) (xy 283.058047 -26.209675) (xy 283.07797 -26.157584) (xy 283.105266 -26.108949)
			(xy 283.139352 -26.064806) (xy 283.179501 -26.026097) (xy 283.224859 -25.993646) (xy 283.274459 -25.968145)
			(xy 283.327243 -25.950138) (xy 283.382086 -25.940008) (xy 283.43782 -25.937971) (xy 283.493257 -25.944071)
			(xy 283.547214 -25.958177) (xy 283.598543 -25.979989) (xy 283.646149 -26.009043) (xy 283.675814 -26.03373)
			(xy 289.467796 -26.03373) (xy 289.471867 -25.978108) (xy 289.483993 -25.923671) (xy 289.503916 -25.87158)
			(xy 289.531212 -25.822945) (xy 289.565298 -25.778802) (xy 289.605447 -25.740093) (xy 289.650805 -25.707642)
			(xy 289.700405 -25.682141) (xy 289.753189 -25.664134) (xy 289.808032 -25.654004) (xy 289.863766 -25.651967)
			(xy 289.919203 -25.658067) (xy 289.97316 -25.672173) (xy 290.024489 -25.693985) (xy 290.072095 -25.723039)
			(xy 290.114963 -25.758714) (xy 290.15218 -25.800251) (xy 290.182953 -25.846764) (xy 290.206625 -25.897261)
			(xy 290.222693 -25.950668) (xy 290.230813 -26.005844) (xy 290.231322 -26.03373) (xy 290.230813 -26.061616)
			(xy 290.222693 -26.116792) (xy 290.206625 -26.170199) (xy 290.182953 -26.220696) (xy 290.152719 -26.266394)
			(xy 292.720522 -26.266394) (xy 292.721008 -26.239143) (xy 292.728764 -26.185195) (xy 292.744119 -26.1329)
			(xy 292.766761 -26.083323) (xy 292.796227 -26.037473) (xy 292.831918 -25.996282) (xy 292.873109 -25.960591)
			(xy 292.918959 -25.931125) (xy 292.968536 -25.908483) (xy 293.020831 -25.893128) (xy 293.074779 -25.885372)
			(xy 293.129281 -25.885372) (xy 293.183229 -25.893128) (xy 293.235524 -25.908483) (xy 293.285101 -25.931125)
			(xy 293.330951 -25.960591) (xy 293.372142 -25.996282) (xy 293.407833 -26.037473) (xy 293.437299 -26.083323)
			(xy 293.459941 -26.1329) (xy 293.475296 -26.185195) (xy 293.483052 -26.239143) (xy 293.483538 -26.266394)
			(xy 293.482971 -26.295881) (xy 293.473877 -26.35415) (xy 293.455921 -26.410324) (xy 293.429531 -26.463064)
			(xy 293.395335 -26.511113) (xy 293.35415 -26.553324) (xy 293.330884 -26.571448) (xy 293.319729 -26.580308)
			(xy 293.302545 -26.603018) (xy 293.292298 -26.62959) (xy 293.289785 -26.657958) (xy 293.295201 -26.685917)
			(xy 293.308125 -26.711294) (xy 293.327553 -26.732118) (xy 293.33952 -26.73985) (xy 293.363261 -26.754748)
			(xy 293.406495 -26.790415) (xy 293.444046 -26.832024) (xy 293.475105 -26.87868) (xy 293.499004 -26.929377)
			(xy 293.515228 -26.983025) (xy 293.523429 -27.03847) (xy 293.523924 -27.066494) (xy 293.523438 -27.093745)
			(xy 293.515682 -27.147693) (xy 293.500327 -27.199988) (xy 293.477685 -27.249565) (xy 293.448219 -27.295415)
			(xy 293.412528 -27.336606) (xy 293.405326 -27.342846) (xy 300.7233 -27.342846) (xy 300.7233 -26.479246)
			(xy 300.72379 -26.449262) (xy 300.731618 -26.389806) (xy 300.747139 -26.331881) (xy 300.770088 -26.276477)
			(xy 300.800072 -26.224543) (xy 300.836578 -26.176967) (xy 300.878983 -26.134562) (xy 300.926559 -26.098056)
			(xy 300.978493 -26.068072) (xy 301.033897 -26.045123) (xy 301.091822 -26.029602) (xy 301.151278 -26.021774)
			(xy 301.211246 -26.021774) (xy 301.270702 -26.029602) (xy 301.328627 -26.045123) (xy 301.384031 -26.068072)
			(xy 301.435965 -26.098056) (xy 301.483541 -26.134562) (xy 301.525946 -26.176967) (xy 301.562452 -26.224543)
			(xy 301.592436 -26.276477) (xy 301.615385 -26.331881) (xy 301.623156 -26.360882) (xy 303.28946 -26.360882)
			(xy 303.293531 -26.30526) (xy 303.305657 -26.250823) (xy 303.32558 -26.198732) (xy 303.352876 -26.150097)
			(xy 303.386962 -26.105954) (xy 303.427111 -26.067245) (xy 303.472469 -26.034794) (xy 303.522069 -26.009293)
			(xy 303.574853 -25.991286) (xy 303.629696 -25.981156) (xy 303.68543 -25.979119) (xy 303.740867 -25.985219)
			(xy 303.794824 -25.999325) (xy 303.846153 -26.021137) (xy 303.893759 -26.050191) (xy 303.936627 -26.085866)
			(xy 303.973844 -26.127403) (xy 304.004617 -26.173916) (xy 304.028289 -26.224413) (xy 304.044357 -26.27782)
			(xy 304.050525 -26.319734) (xy 309.041798 -26.319734) (xy 309.045869 -26.264112) (xy 309.057995 -26.209675)
			(xy 309.077918 -26.157584) (xy 309.105214 -26.108949) (xy 309.1393 -26.064806) (xy 309.179449 -26.026097)
			(xy 309.224807 -25.993646) (xy 309.274407 -25.968145) (xy 309.327191 -25.950138) (xy 309.382034 -25.940008)
			(xy 309.437768 -25.937971) (xy 309.493205 -25.944071) (xy 309.547162 -25.958177) (xy 309.598491 -25.979989)
			(xy 309.646097 -26.009043) (xy 309.675762 -26.03373) (xy 315.467744 -26.03373) (xy 315.471815 -25.978108)
			(xy 315.483941 -25.923671) (xy 315.503864 -25.87158) (xy 315.53116 -25.822945) (xy 315.565246 -25.778802)
			(xy 315.605395 -25.740093) (xy 315.650753 -25.707642) (xy 315.700353 -25.682141) (xy 315.753137 -25.664134)
			(xy 315.80798 -25.654004) (xy 315.863714 -25.651967) (xy 315.919151 -25.658067) (xy 315.973108 -25.672173)
			(xy 316.024437 -25.693985) (xy 316.072043 -25.723039) (xy 316.114911 -25.758714) (xy 316.152128 -25.800251)
			(xy 316.182901 -25.846764) (xy 316.206573 -25.897261) (xy 316.222641 -25.950668) (xy 316.230761 -26.005844)
			(xy 316.23127 -26.03373) (xy 316.230761 -26.061616) (xy 316.222641 -26.116792) (xy 316.206573 -26.170199)
			(xy 316.182901 -26.220696) (xy 316.152667 -26.266394) (xy 318.72047 -26.266394) (xy 318.720956 -26.239143)
			(xy 318.728712 -26.185195) (xy 318.744067 -26.1329) (xy 318.766709 -26.083323) (xy 318.796175 -26.037473)
			(xy 318.831866 -25.996282) (xy 318.873057 -25.960591) (xy 318.918907 -25.931125) (xy 318.968484 -25.908483)
			(xy 319.020779 -25.893128) (xy 319.074727 -25.885372) (xy 319.129229 -25.885372) (xy 319.183177 -25.893128)
			(xy 319.235472 -25.908483) (xy 319.285049 -25.931125) (xy 319.330899 -25.960591) (xy 319.37209 -25.996282)
			(xy 319.407781 -26.037473) (xy 319.437247 -26.083323) (xy 319.459889 -26.1329) (xy 319.475244 -26.185195)
			(xy 319.483 -26.239143) (xy 319.483486 -26.266394) (xy 319.48294 -26.295882) (xy 319.473844 -26.354153)
			(xy 319.455886 -26.410329) (xy 319.429491 -26.463069) (xy 319.395291 -26.511117) (xy 319.354101 -26.553326)
			(xy 319.330832 -26.571448) (xy 319.319685 -26.580314) (xy 319.30251 -26.603025) (xy 319.292269 -26.629594)
			(xy 319.289758 -26.657958) (xy 319.295171 -26.685913) (xy 319.308088 -26.711288) (xy 319.327506 -26.732114)
			(xy 319.339468 -26.73985) (xy 319.363197 -26.754766) (xy 319.406434 -26.790429) (xy 319.443987 -26.832034)
			(xy 319.475049 -26.878686) (xy 319.49895 -26.929381) (xy 319.515176 -26.983027) (xy 319.523377 -27.038471)
			(xy 319.523872 -27.066494) (xy 319.523386 -27.093745) (xy 319.51563 -27.147693) (xy 319.500275 -27.199988)
			(xy 319.477633 -27.249565) (xy 319.448167 -27.295415) (xy 319.412476 -27.336606) (xy 319.405274 -27.342846)
			(xy 326.723248 -27.342846) (xy 326.723248 -26.479246) (xy 326.723738 -26.449262) (xy 326.731566 -26.389806)
			(xy 326.747087 -26.331881) (xy 326.770036 -26.276477) (xy 326.80002 -26.224543) (xy 326.836526 -26.176967)
			(xy 326.878931 -26.134562) (xy 326.926507 -26.098056) (xy 326.978441 -26.068072) (xy 327.033845 -26.045123)
			(xy 327.09177 -26.029602) (xy 327.151226 -26.021774) (xy 327.211194 -26.021774) (xy 327.27065 -26.029602)
			(xy 327.328575 -26.045123) (xy 327.383979 -26.068072) (xy 327.435913 -26.098056) (xy 327.483489 -26.134562)
			(xy 327.525894 -26.176967) (xy 327.5624 -26.224543) (xy 327.592384 -26.276477) (xy 327.615333 -26.331881)
			(xy 327.623104 -26.360882) (xy 329.289408 -26.360882) (xy 329.293479 -26.30526) (xy 329.305605 -26.250823)
			(xy 329.325528 -26.198732) (xy 329.352824 -26.150097) (xy 329.38691 -26.105954) (xy 329.427059 -26.067245)
			(xy 329.472417 -26.034794) (xy 329.522017 -26.009293) (xy 329.574801 -25.991286) (xy 329.629644 -25.981156)
			(xy 329.685378 -25.979119) (xy 329.740815 -25.985219) (xy 329.794772 -25.999325) (xy 329.846101 -26.021137)
			(xy 329.893707 -26.050191) (xy 329.936575 -26.085866) (xy 329.973792 -26.127403) (xy 330.004565 -26.173916)
			(xy 330.028237 -26.224413) (xy 330.044305 -26.27782) (xy 330.050473 -26.319734) (xy 335.041746 -26.319734)
			(xy 335.045817 -26.264112) (xy 335.057943 -26.209675) (xy 335.077866 -26.157584) (xy 335.105162 -26.108949)
			(xy 335.139248 -26.064806) (xy 335.179397 -26.026097) (xy 335.224755 -25.993646) (xy 335.274355 -25.968145)
			(xy 335.327139 -25.950138) (xy 335.381982 -25.940008) (xy 335.437716 -25.937971) (xy 335.493153 -25.944071)
			(xy 335.54711 -25.958177) (xy 335.598439 -25.979989) (xy 335.646045 -26.009043) (xy 335.67571 -26.03373)
			(xy 353.567998 -26.03373) (xy 353.572069 -25.978108) (xy 353.584195 -25.923671) (xy 353.604118 -25.87158)
			(xy 353.631414 -25.822945) (xy 353.6655 -25.778802) (xy 353.705649 -25.740093) (xy 353.751007 -25.707642)
			(xy 353.800607 -25.682141) (xy 353.853391 -25.664134) (xy 353.908234 -25.654004) (xy 353.963968 -25.651967)
			(xy 354.019405 -25.658067) (xy 354.073362 -25.672173) (xy 354.124691 -25.693985) (xy 354.172297 -25.723039)
			(xy 354.215165 -25.758714) (xy 354.252382 -25.800251) (xy 354.283155 -25.846764) (xy 354.306827 -25.897261)
			(xy 354.322895 -25.950668) (xy 354.331015 -26.005844) (xy 354.331524 -26.03373) (xy 354.331015 -26.061616)
			(xy 354.322895 -26.116792) (xy 354.306827 -26.170199) (xy 354.283155 -26.220696) (xy 354.252921 -26.266394)
			(xy 356.820724 -26.266394) (xy 356.82121 -26.239143) (xy 356.828966 -26.185195) (xy 356.844321 -26.1329)
			(xy 356.866963 -26.083323) (xy 356.896429 -26.037473) (xy 356.93212 -25.996282) (xy 356.973311 -25.960591)
			(xy 357.019161 -25.931125) (xy 357.068738 -25.908483) (xy 357.121033 -25.893128) (xy 357.174981 -25.885372)
			(xy 357.229483 -25.885372) (xy 357.283431 -25.893128) (xy 357.335726 -25.908483) (xy 357.385303 -25.931125)
			(xy 357.431153 -25.960591) (xy 357.472344 -25.996282) (xy 357.508035 -26.037473) (xy 357.537501 -26.083323)
			(xy 357.560143 -26.1329) (xy 357.575498 -26.185195) (xy 357.583254 -26.239143) (xy 357.58374 -26.266394)
			(xy 357.583172 -26.295881) (xy 357.574079 -26.35415) (xy 357.556122 -26.410324) (xy 357.529732 -26.463064)
			(xy 357.495537 -26.511113) (xy 357.454352 -26.553324) (xy 357.431086 -26.571448) (xy 357.419931 -26.580308)
			(xy 357.402746 -26.603018) (xy 357.392499 -26.62959) (xy 357.389986 -26.657958) (xy 357.395402 -26.685917)
			(xy 357.408327 -26.711295) (xy 357.427755 -26.732118) (xy 357.439722 -26.73985) (xy 357.463464 -26.754747)
			(xy 357.506698 -26.790415) (xy 357.544248 -26.832024) (xy 357.575307 -26.878679) (xy 357.599206 -26.929377)
			(xy 357.61543 -26.983025) (xy 357.623631 -27.03847) (xy 357.624126 -27.066494) (xy 357.62364 -27.093745)
			(xy 357.615884 -27.147693) (xy 357.600529 -27.199988) (xy 357.577887 -27.249565) (xy 357.548421 -27.295415)
			(xy 357.51273 -27.336606) (xy 357.505528 -27.342846) (xy 364.823756 -27.342846) (xy 364.823756 -26.479246)
			(xy 364.824246 -26.449278) (xy 364.832069 -26.389856) (xy 364.847582 -26.331963) (xy 364.870518 -26.27659)
			(xy 364.900485 -26.224684) (xy 364.936972 -26.177134) (xy 364.979352 -26.134754) (xy 365.026902 -26.098267)
			(xy 365.078808 -26.0683) (xy 365.134181 -26.045364) (xy 365.192074 -26.029851) (xy 365.251496 -26.022028)
			(xy 365.311432 -26.022028) (xy 365.370854 -26.029851) (xy 365.428747 -26.045364) (xy 365.48412 -26.0683)
			(xy 365.536026 -26.098267) (xy 365.583576 -26.134754) (xy 365.625956 -26.177134) (xy 365.662443 -26.224684)
			(xy 365.69241 -26.27659) (xy 365.715346 -26.331963) (xy 365.723095 -26.360882) (xy 367.389662 -26.360882)
			(xy 367.393733 -26.30526) (xy 367.405859 -26.250823) (xy 367.425782 -26.198732) (xy 367.453078 -26.150097)
			(xy 367.487164 -26.105954) (xy 367.527313 -26.067245) (xy 367.572671 -26.034794) (xy 367.622271 -26.009293)
			(xy 367.675055 -25.991286) (xy 367.729898 -25.981156) (xy 367.785632 -25.979119) (xy 367.841069 -25.985219)
			(xy 367.895026 -25.999325) (xy 367.946355 -26.021137) (xy 367.993961 -26.050191) (xy 368.036829 -26.085866)
			(xy 368.074046 -26.127403) (xy 368.104819 -26.173916) (xy 368.128491 -26.224413) (xy 368.144559 -26.27782)
			(xy 368.150727 -26.319734) (xy 373.142 -26.319734) (xy 373.146071 -26.264112) (xy 373.158197 -26.209675)
			(xy 373.17812 -26.157584) (xy 373.205416 -26.108949) (xy 373.239502 -26.064806) (xy 373.279651 -26.026097)
			(xy 373.325009 -25.993646) (xy 373.374609 -25.968145) (xy 373.427393 -25.950138) (xy 373.482236 -25.940008)
			(xy 373.53797 -25.937971) (xy 373.593407 -25.944071) (xy 373.647364 -25.958177) (xy 373.698693 -25.979989)
			(xy 373.746299 -26.009043) (xy 373.775964 -26.03373) (xy 379.567946 -26.03373) (xy 379.572017 -25.978108)
			(xy 379.584143 -25.923671) (xy 379.604066 -25.87158) (xy 379.631362 -25.822945) (xy 379.665448 -25.778802)
			(xy 379.705597 -25.740093) (xy 379.750955 -25.707642) (xy 379.800555 -25.682141) (xy 379.853339 -25.664134)
			(xy 379.908182 -25.654004) (xy 379.963916 -25.651967) (xy 380.019353 -25.658067) (xy 380.07331 -25.672173)
			(xy 380.124639 -25.693985) (xy 380.172245 -25.723039) (xy 380.215113 -25.758714) (xy 380.25233 -25.800251)
			(xy 380.283103 -25.846764) (xy 380.306775 -25.897261) (xy 380.322843 -25.950668) (xy 380.330963 -26.005844)
			(xy 380.331472 -26.03373) (xy 380.330963 -26.061616) (xy 380.322843 -26.116792) (xy 380.306775 -26.170199)
			(xy 380.283103 -26.220696) (xy 380.252869 -26.266394) (xy 382.820672 -26.266394) (xy 382.821158 -26.239143)
			(xy 382.828914 -26.185195) (xy 382.844269 -26.1329) (xy 382.866911 -26.083323) (xy 382.896377 -26.037473)
			(xy 382.932068 -25.996282) (xy 382.973259 -25.960591) (xy 383.019109 -25.931125) (xy 383.068686 -25.908483)
			(xy 383.120981 -25.893128) (xy 383.174929 -25.885372) (xy 383.229431 -25.885372) (xy 383.283379 -25.893128)
			(xy 383.335674 -25.908483) (xy 383.385251 -25.931125) (xy 383.431101 -25.960591) (xy 383.472292 -25.996282)
			(xy 383.507983 -26.037473) (xy 383.537449 -26.083323) (xy 383.560091 -26.1329) (xy 383.575446 -26.185195)
			(xy 383.583202 -26.239143) (xy 383.583688 -26.266394) (xy 383.583141 -26.295882) (xy 383.574046 -26.354153)
			(xy 383.556087 -26.410329) (xy 383.529693 -26.463069) (xy 383.495493 -26.511117) (xy 383.454303 -26.553326)
			(xy 383.431034 -26.571448) (xy 383.419887 -26.580314) (xy 383.402711 -26.603025) (xy 383.39247 -26.629594)
			(xy 383.389959 -26.657958) (xy 383.395372 -26.685913) (xy 383.40829 -26.711289) (xy 383.427708 -26.732114)
			(xy 383.43967 -26.73985) (xy 383.4634 -26.754766) (xy 383.506636 -26.790428) (xy 383.54419 -26.832033)
			(xy 383.575251 -26.878686) (xy 383.599152 -26.929381) (xy 383.615378 -26.983027) (xy 383.623579 -27.038471)
			(xy 383.624074 -27.066494) (xy 383.623588 -27.093745) (xy 383.615832 -27.147693) (xy 383.600477 -27.199988)
			(xy 383.577835 -27.249565) (xy 383.548369 -27.295415) (xy 383.512678 -27.336606) (xy 383.505476 -27.342846)
			(xy 390.823704 -27.342846) (xy 390.823704 -26.479246) (xy 390.824194 -26.449278) (xy 390.832017 -26.389856)
			(xy 390.84753 -26.331963) (xy 390.870466 -26.27659) (xy 390.900433 -26.224684) (xy 390.93692 -26.177134)
			(xy 390.9793 -26.134754) (xy 391.02685 -26.098267) (xy 391.078756 -26.0683) (xy 391.134129 -26.045364)
			(xy 391.192022 -26.029851) (xy 391.251444 -26.022028) (xy 391.31138 -26.022028) (xy 391.370802 -26.029851)
			(xy 391.428695 -26.045364) (xy 391.484068 -26.0683) (xy 391.535974 -26.098267) (xy 391.583524 -26.134754)
			(xy 391.625904 -26.177134) (xy 391.662391 -26.224684) (xy 391.692358 -26.27659) (xy 391.715294 -26.331963)
			(xy 391.723043 -26.360882) (xy 393.38961 -26.360882) (xy 393.393681 -26.30526) (xy 393.405807 -26.250823)
			(xy 393.42573 -26.198732) (xy 393.453026 -26.150097) (xy 393.487112 -26.105954) (xy 393.527261 -26.067245)
			(xy 393.572619 -26.034794) (xy 393.622219 -26.009293) (xy 393.675003 -25.991286) (xy 393.729846 -25.981156)
			(xy 393.78558 -25.979119) (xy 393.841017 -25.985219) (xy 393.894974 -25.999325) (xy 393.946303 -26.021137)
			(xy 393.993909 -26.050191) (xy 394.036777 -26.085866) (xy 394.073994 -26.127403) (xy 394.104767 -26.173916)
			(xy 394.128439 -26.224413) (xy 394.144507 -26.27782) (xy 394.150675 -26.319734) (xy 399.141948 -26.319734)
			(xy 399.146019 -26.264112) (xy 399.158145 -26.209675) (xy 399.178068 -26.157584) (xy 399.205364 -26.108949)
			(xy 399.23945 -26.064806) (xy 399.279599 -26.026097) (xy 399.324957 -25.993646) (xy 399.374557 -25.968145)
			(xy 399.427341 -25.950138) (xy 399.482184 -25.940008) (xy 399.537918 -25.937971) (xy 399.593355 -25.944071)
			(xy 399.647312 -25.958177) (xy 399.698641 -25.979989) (xy 399.746247 -26.009043) (xy 399.775912 -26.03373)
			(xy 405.567894 -26.03373) (xy 405.571965 -25.978108) (xy 405.584091 -25.923671) (xy 405.604014 -25.87158)
			(xy 405.63131 -25.822945) (xy 405.665396 -25.778802) (xy 405.705545 -25.740093) (xy 405.750903 -25.707642)
			(xy 405.800503 -25.682141) (xy 405.853287 -25.664134) (xy 405.90813 -25.654004) (xy 405.963864 -25.651967)
			(xy 406.019301 -25.658067) (xy 406.073258 -25.672173) (xy 406.124587 -25.693985) (xy 406.172193 -25.723039)
			(xy 406.215061 -25.758714) (xy 406.252278 -25.800251) (xy 406.283051 -25.846764) (xy 406.306723 -25.897261)
			(xy 406.322791 -25.950668) (xy 406.330911 -26.005844) (xy 406.33142 -26.03373) (xy 406.330911 -26.061616)
			(xy 406.322791 -26.116792) (xy 406.306723 -26.170199) (xy 406.283051 -26.220696) (xy 406.252817 -26.266394)
			(xy 408.82062 -26.266394) (xy 408.821106 -26.239143) (xy 408.828862 -26.185195) (xy 408.844217 -26.1329)
			(xy 408.866859 -26.083323) (xy 408.896325 -26.037473) (xy 408.932016 -25.996282) (xy 408.973207 -25.960591)
			(xy 409.019057 -25.931125) (xy 409.068634 -25.908483) (xy 409.120929 -25.893128) (xy 409.174877 -25.885372)
			(xy 409.229379 -25.885372) (xy 409.283327 -25.893128) (xy 409.335622 -25.908483) (xy 409.385199 -25.931125)
			(xy 409.431049 -25.960591) (xy 409.47224 -25.996282) (xy 409.507931 -26.037473) (xy 409.537397 -26.083323)
			(xy 409.560039 -26.1329) (xy 409.575394 -26.185195) (xy 409.58315 -26.239143) (xy 409.583636 -26.266394)
			(xy 409.58307 -26.295881) (xy 409.573976 -26.35415) (xy 409.55602 -26.410325) (xy 409.529629 -26.463065)
			(xy 409.495434 -26.511113) (xy 409.454248 -26.553324) (xy 409.430982 -26.571448) (xy 409.419828 -26.580308)
			(xy 409.402643 -26.603018) (xy 409.392397 -26.62959) (xy 409.389884 -26.657958) (xy 409.3953 -26.685917)
			(xy 409.408224 -26.711294) (xy 409.427652 -26.732118) (xy 409.439618 -26.73985) (xy 409.463359 -26.754748)
			(xy 409.506593 -26.790416) (xy 409.544144 -26.832025) (xy 409.575203 -26.87868) (xy 409.599102 -26.929377)
			(xy 409.615326 -26.983025) (xy 409.623527 -27.03847) (xy 409.624022 -27.066494) (xy 409.623536 -27.093745)
			(xy 409.61578 -27.147693) (xy 409.600425 -27.199988) (xy 409.577783 -27.249565) (xy 409.548317 -27.295415)
			(xy 409.512626 -27.336606) (xy 409.505424 -27.342846) (xy 416.823652 -27.342846) (xy 416.823652 -26.479246)
			(xy 416.824142 -26.449278) (xy 416.831965 -26.389856) (xy 416.847478 -26.331963) (xy 416.870414 -26.27659)
			(xy 416.900381 -26.224684) (xy 416.936868 -26.177134) (xy 416.979248 -26.134754) (xy 417.026798 -26.098267)
			(xy 417.078704 -26.0683) (xy 417.134077 -26.045364) (xy 417.19197 -26.029851) (xy 417.251392 -26.022028)
			(xy 417.311328 -26.022028) (xy 417.37075 -26.029851) (xy 417.428643 -26.045364) (xy 417.484016 -26.0683)
			(xy 417.535922 -26.098267) (xy 417.583472 -26.134754) (xy 417.625852 -26.177134) (xy 417.662339 -26.224684)
			(xy 417.692306 -26.27659) (xy 417.715242 -26.331963) (xy 417.722991 -26.360882) (xy 419.389558 -26.360882)
			(xy 419.393629 -26.30526) (xy 419.405755 -26.250823) (xy 419.425678 -26.198732) (xy 419.452974 -26.150097)
			(xy 419.48706 -26.105954) (xy 419.527209 -26.067245) (xy 419.572567 -26.034794) (xy 419.622167 -26.009293)
			(xy 419.674951 -25.991286) (xy 419.729794 -25.981156) (xy 419.785528 -25.979119) (xy 419.840965 -25.985219)
			(xy 419.894922 -25.999325) (xy 419.946251 -26.021137) (xy 419.993857 -26.050191) (xy 420.036725 -26.085866)
			(xy 420.073942 -26.127403) (xy 420.104715 -26.173916) (xy 420.128387 -26.224413) (xy 420.144455 -26.27782)
			(xy 420.150623 -26.319734) (xy 425.141896 -26.319734) (xy 425.145967 -26.264112) (xy 425.158093 -26.209675)
			(xy 425.178016 -26.157584) (xy 425.205312 -26.108949) (xy 425.239398 -26.064806) (xy 425.279547 -26.026097)
			(xy 425.324905 -25.993646) (xy 425.374505 -25.968145) (xy 425.427289 -25.950138) (xy 425.482132 -25.940008)
			(xy 425.537866 -25.937971) (xy 425.593303 -25.944071) (xy 425.64726 -25.958177) (xy 425.698589 -25.979989)
			(xy 425.746195 -26.009043) (xy 425.77586 -26.03373) (xy 431.567842 -26.03373) (xy 431.571913 -25.978108)
			(xy 431.584039 -25.923671) (xy 431.603962 -25.87158) (xy 431.631258 -25.822945) (xy 431.665344 -25.778802)
			(xy 431.705493 -25.740093) (xy 431.750851 -25.707642) (xy 431.800451 -25.682141) (xy 431.853235 -25.664134)
			(xy 431.908078 -25.654004) (xy 431.963812 -25.651967) (xy 432.019249 -25.658067) (xy 432.073206 -25.672173)
			(xy 432.124535 -25.693985) (xy 432.172141 -25.723039) (xy 432.215009 -25.758714) (xy 432.252226 -25.800251)
			(xy 432.282999 -25.846764) (xy 432.306671 -25.897261) (xy 432.322739 -25.950668) (xy 432.330859 -26.005844)
			(xy 432.331368 -26.03373) (xy 432.330859 -26.061616) (xy 432.322739 -26.116792) (xy 432.306671 -26.170199)
			(xy 432.282999 -26.220696) (xy 432.252765 -26.266394) (xy 434.820568 -26.266394) (xy 434.821054 -26.239143)
			(xy 434.82881 -26.185195) (xy 434.844165 -26.1329) (xy 434.866807 -26.083323) (xy 434.896273 -26.037473)
			(xy 434.931964 -25.996282) (xy 434.973155 -25.960591) (xy 435.019005 -25.931125) (xy 435.068582 -25.908483)
			(xy 435.120877 -25.893128) (xy 435.174825 -25.885372) (xy 435.229327 -25.885372) (xy 435.283275 -25.893128)
			(xy 435.33557 -25.908483) (xy 435.385147 -25.931125) (xy 435.430997 -25.960591) (xy 435.472188 -25.996282)
			(xy 435.507879 -26.037473) (xy 435.537345 -26.083323) (xy 435.559987 -26.1329) (xy 435.575342 -26.185195)
			(xy 435.583098 -26.239143) (xy 435.583584 -26.266394) (xy 435.583038 -26.295882) (xy 435.573943 -26.354153)
			(xy 435.555984 -26.410329) (xy 435.52959 -26.463069) (xy 435.49539 -26.511117) (xy 435.454199 -26.553326)
			(xy 435.43093 -26.571448) (xy 435.419784 -26.580314) (xy 435.402609 -26.603026) (xy 435.392368 -26.629594)
			(xy 435.389857 -26.657958) (xy 435.39527 -26.685912) (xy 435.408187 -26.711288) (xy 435.427605 -26.732114)
			(xy 435.439566 -26.73985) (xy 435.463295 -26.754767) (xy 435.506532 -26.790429) (xy 435.544085 -26.832034)
			(xy 435.575147 -26.878686) (xy 435.599048 -26.929381) (xy 435.615274 -26.983027) (xy 435.623475 -27.038471)
			(xy 435.62397 -27.066494) (xy 435.623484 -27.093745) (xy 435.615728 -27.147693) (xy 435.600373 -27.199988)
			(xy 435.577731 -27.249565) (xy 435.548265 -27.295415) (xy 435.512574 -27.336606) (xy 435.505372 -27.342846)
			(xy 442.8236 -27.342846) (xy 442.8236 -26.479246) (xy 442.82409 -26.449278) (xy 442.831913 -26.389856)
			(xy 442.847426 -26.331963) (xy 442.870362 -26.27659) (xy 442.900329 -26.224684) (xy 442.936816 -26.177134)
			(xy 442.979196 -26.134754) (xy 443.026746 -26.098267) (xy 443.078652 -26.0683) (xy 443.134025 -26.045364)
			(xy 443.191918 -26.029851) (xy 443.25134 -26.022028) (xy 443.311276 -26.022028) (xy 443.370698 -26.029851)
			(xy 443.428591 -26.045364) (xy 443.483964 -26.0683) (xy 443.53587 -26.098267) (xy 443.58342 -26.134754)
			(xy 443.6258 -26.177134) (xy 443.662287 -26.224684) (xy 443.692254 -26.27659) (xy 443.71519 -26.331963)
			(xy 443.722939 -26.360882) (xy 445.389506 -26.360882) (xy 445.393577 -26.30526) (xy 445.405703 -26.250823)
			(xy 445.425626 -26.198732) (xy 445.452922 -26.150097) (xy 445.487008 -26.105954) (xy 445.527157 -26.067245)
			(xy 445.572515 -26.034794) (xy 445.622115 -26.009293) (xy 445.674899 -25.991286) (xy 445.729742 -25.981156)
			(xy 445.785476 -25.979119) (xy 445.840913 -25.985219) (xy 445.89487 -25.999325) (xy 445.946199 -26.021137)
			(xy 445.993805 -26.050191) (xy 446.036673 -26.085866) (xy 446.07389 -26.127403) (xy 446.104663 -26.173916)
			(xy 446.128335 -26.224413) (xy 446.144403 -26.27782) (xy 446.152523 -26.332996) (xy 446.153032 -26.360882)
			(xy 446.152523 -26.388768) (xy 446.144403 -26.443944) (xy 446.128335 -26.497351) (xy 446.104663 -26.547848)
			(xy 446.07389 -26.594361) (xy 446.036673 -26.635898) (xy 445.993805 -26.671573) (xy 445.946199 -26.700627)
			(xy 445.89487 -26.722439) (xy 445.840913 -26.736545) (xy 445.785476 -26.742645) (xy 445.729742 -26.740608)
			(xy 445.674899 -26.730478) (xy 445.622115 -26.712471) (xy 445.572515 -26.68697) (xy 445.527157 -26.654519)
			(xy 445.487008 -26.61581) (xy 445.452922 -26.571667) (xy 445.425626 -26.523032) (xy 445.405703 -26.470941)
			(xy 445.393577 -26.416504) (xy 445.389506 -26.360882) (xy 443.722939 -26.360882) (xy 443.730703 -26.389856)
			(xy 443.738526 -26.449278) (xy 443.739016 -26.479246) (xy 443.739016 -26.971244) (xy 447.150996 -26.971244)
			(xy 447.155067 -26.915622) (xy 447.167193 -26.861185) (xy 447.187116 -26.809094) (xy 447.214412 -26.760459)
			(xy 447.248498 -26.716316) (xy 447.288647 -26.677607) (xy 447.334005 -26.645156) (xy 447.383605 -26.619655)
			(xy 447.436389 -26.601648) (xy 447.491232 -26.591518) (xy 447.546966 -26.589481) (xy 447.602403 -26.595581)
			(xy 447.65636 -26.609687) (xy 447.707689 -26.631499) (xy 447.755295 -26.660553) (xy 447.798163 -26.696228)
			(xy 447.83538 -26.737765) (xy 447.866153 -26.784278) (xy 447.889825 -26.834775) (xy 447.905893 -26.888182)
			(xy 447.914013 -26.943358) (xy 447.914522 -26.971244) (xy 447.914013 -26.99913) (xy 447.905893 -27.054306)
			(xy 447.889825 -27.107713) (xy 447.866153 -27.15821) (xy 447.83538 -27.204723) (xy 447.798163 -27.24626)
			(xy 447.755295 -27.281935) (xy 447.707689 -27.310989) (xy 447.65636 -27.332801) (xy 447.602403 -27.346907)
			(xy 447.546966 -27.353007) (xy 447.491232 -27.35097) (xy 447.436389 -27.34084) (xy 447.383605 -27.322833)
			(xy 447.334005 -27.297332) (xy 447.288647 -27.264881) (xy 447.248498 -27.226172) (xy 447.214412 -27.182029)
			(xy 447.187116 -27.133394) (xy 447.167193 -27.081303) (xy 447.155067 -27.026866) (xy 447.150996 -26.971244)
			(xy 443.739016 -26.971244) (xy 443.739016 -27.342846) (xy 443.738526 -27.372814) (xy 443.730703 -27.432236)
			(xy 443.71519 -27.490129) (xy 443.692254 -27.545502) (xy 443.662287 -27.597408) (xy 443.6258 -27.644958)
			(xy 443.58342 -27.687338) (xy 443.53587 -27.723825) (xy 443.483964 -27.753792) (xy 443.428591 -27.776728)
			(xy 443.370698 -27.792241) (xy 443.311276 -27.800064) (xy 443.25134 -27.800064) (xy 443.191918 -27.792241)
			(xy 443.134025 -27.776728) (xy 443.078652 -27.753792) (xy 443.026746 -27.723825) (xy 442.979196 -27.687338)
			(xy 442.936816 -27.644958) (xy 442.900329 -27.597408) (xy 442.870362 -27.545502) (xy 442.847426 -27.490129)
			(xy 442.831913 -27.432236) (xy 442.82409 -27.372814) (xy 442.8236 -27.342846) (xy 435.505372 -27.342846)
			(xy 435.471383 -27.372297) (xy 435.425533 -27.401763) (xy 435.375956 -27.424405) (xy 435.323661 -27.43976)
			(xy 435.269713 -27.447516) (xy 435.215211 -27.447516) (xy 435.161263 -27.43976) (xy 435.108968 -27.424405)
			(xy 435.059391 -27.401763) (xy 435.013541 -27.372297) (xy 434.97235 -27.336606) (xy 434.936659 -27.295415)
			(xy 434.907193 -27.249565) (xy 434.884551 -27.199988) (xy 434.869196 -27.147693) (xy 434.86144 -27.093745)
			(xy 434.860954 -27.066494) (xy 434.861515 -27.037007) (xy 434.870611 -26.978738) (xy 434.888568 -26.922563)
			(xy 434.91496 -26.869823) (xy 434.949156 -26.821775) (xy 434.990342 -26.779564) (xy 435.013608 -26.76144)
			(xy 435.024673 -26.752476) (xy 435.041858 -26.729791) (xy 435.052113 -26.703243) (xy 435.054638 -26.674895)
			(xy 435.049239 -26.646953) (xy 435.036334 -26.621587) (xy 435.016927 -26.60077) (xy 435.004972 -26.593038)
			(xy 434.981224 -26.578151) (xy 434.93799 -26.542482) (xy 434.90044 -26.50087) (xy 434.869382 -26.454213)
			(xy 434.845484 -26.403514) (xy 434.829261 -26.349865) (xy 434.821062 -26.294419) (xy 434.820568 -26.266394)
			(xy 432.252765 -26.266394) (xy 432.252226 -26.267209) (xy 432.215009 -26.308746) (xy 432.172141 -26.344421)
			(xy 432.124535 -26.373475) (xy 432.073206 -26.395287) (xy 432.019249 -26.409393) (xy 431.963812 -26.415493)
			(xy 431.908078 -26.413456) (xy 431.853235 -26.403326) (xy 431.800451 -26.385319) (xy 431.750851 -26.359818)
			(xy 431.705493 -26.327367) (xy 431.665344 -26.288658) (xy 431.631258 -26.244515) (xy 431.603962 -26.19588)
			(xy 431.584039 -26.143789) (xy 431.571913 -26.089352) (xy 431.567842 -26.03373) (xy 425.77586 -26.03373)
			(xy 425.789063 -26.044718) (xy 425.82628 -26.086255) (xy 425.857053 -26.132768) (xy 425.880725 -26.183265)
			(xy 425.896793 -26.236672) (xy 425.904913 -26.291848) (xy 425.905422 -26.319734) (xy 425.904913 -26.34762)
			(xy 425.896793 -26.402796) (xy 425.880725 -26.456203) (xy 425.857053 -26.5067) (xy 425.82628 -26.553213)
			(xy 425.789063 -26.59475) (xy 425.746195 -26.630425) (xy 425.698589 -26.659479) (xy 425.64726 -26.681291)
			(xy 425.593303 -26.695397) (xy 425.537866 -26.701497) (xy 425.482132 -26.69946) (xy 425.427289 -26.68933)
			(xy 425.374505 -26.671323) (xy 425.324905 -26.645822) (xy 425.279547 -26.613371) (xy 425.239398 -26.574662)
			(xy 425.205312 -26.530519) (xy 425.178016 -26.481884) (xy 425.158093 -26.429793) (xy 425.145967 -26.375356)
			(xy 425.141896 -26.319734) (xy 420.150623 -26.319734) (xy 420.152575 -26.332996) (xy 420.153084 -26.360882)
			(xy 420.152575 -26.388768) (xy 420.144455 -26.443944) (xy 420.128387 -26.497351) (xy 420.104715 -26.547848)
			(xy 420.073942 -26.594361) (xy 420.036725 -26.635898) (xy 419.993857 -26.671573) (xy 419.946251 -26.700627)
			(xy 419.894922 -26.722439) (xy 419.840965 -26.736545) (xy 419.785528 -26.742645) (xy 419.729794 -26.740608)
			(xy 419.674951 -26.730478) (xy 419.622167 -26.712471) (xy 419.572567 -26.68697) (xy 419.527209 -26.654519)
			(xy 419.48706 -26.61581) (xy 419.452974 -26.571667) (xy 419.425678 -26.523032) (xy 419.405755 -26.470941)
			(xy 419.393629 -26.416504) (xy 419.389558 -26.360882) (xy 417.722991 -26.360882) (xy 417.730755 -26.389856)
			(xy 417.738578 -26.449278) (xy 417.739068 -26.479246) (xy 417.739068 -26.971244) (xy 421.151048 -26.971244)
			(xy 421.155119 -26.915622) (xy 421.167245 -26.861185) (xy 421.187168 -26.809094) (xy 421.214464 -26.760459)
			(xy 421.24855 -26.716316) (xy 421.288699 -26.677607) (xy 421.334057 -26.645156) (xy 421.383657 -26.619655)
			(xy 421.436441 -26.601648) (xy 421.491284 -26.591518) (xy 421.547018 -26.589481) (xy 421.602455 -26.595581)
			(xy 421.656412 -26.609687) (xy 421.707741 -26.631499) (xy 421.755347 -26.660553) (xy 421.798215 -26.696228)
			(xy 421.835432 -26.737765) (xy 421.866205 -26.784278) (xy 421.889877 -26.834775) (xy 421.905945 -26.888182)
			(xy 421.914065 -26.943358) (xy 421.914574 -26.971244) (xy 421.914065 -26.99913) (xy 421.905945 -27.054306)
			(xy 421.889877 -27.107713) (xy 421.866205 -27.15821) (xy 421.835432 -27.204723) (xy 421.798215 -27.24626)
			(xy 421.755347 -27.281935) (xy 421.707741 -27.310989) (xy 421.656412 -27.332801) (xy 421.602455 -27.346907)
			(xy 421.547018 -27.353007) (xy 421.491284 -27.35097) (xy 421.436441 -27.34084) (xy 421.383657 -27.322833)
			(xy 421.334057 -27.297332) (xy 421.288699 -27.264881) (xy 421.24855 -27.226172) (xy 421.214464 -27.182029)
			(xy 421.187168 -27.133394) (xy 421.167245 -27.081303) (xy 421.155119 -27.026866) (xy 421.151048 -26.971244)
			(xy 417.739068 -26.971244) (xy 417.739068 -27.342846) (xy 417.738578 -27.372814) (xy 417.730755 -27.432236)
			(xy 417.715242 -27.490129) (xy 417.692306 -27.545502) (xy 417.662339 -27.597408) (xy 417.625852 -27.644958)
			(xy 417.583472 -27.687338) (xy 417.535922 -27.723825) (xy 417.484016 -27.753792) (xy 417.428643 -27.776728)
			(xy 417.37075 -27.792241) (xy 417.311328 -27.800064) (xy 417.251392 -27.800064) (xy 417.19197 -27.792241)
			(xy 417.134077 -27.776728) (xy 417.078704 -27.753792) (xy 417.026798 -27.723825) (xy 416.979248 -27.687338)
			(xy 416.936868 -27.644958) (xy 416.900381 -27.597408) (xy 416.870414 -27.545502) (xy 416.847478 -27.490129)
			(xy 416.831965 -27.432236) (xy 416.824142 -27.372814) (xy 416.823652 -27.342846) (xy 409.505424 -27.342846)
			(xy 409.471435 -27.372297) (xy 409.425585 -27.401763) (xy 409.376008 -27.424405) (xy 409.323713 -27.43976)
			(xy 409.269765 -27.447516) (xy 409.215263 -27.447516) (xy 409.161315 -27.43976) (xy 409.10902 -27.424405)
			(xy 409.059443 -27.401763) (xy 409.013593 -27.372297) (xy 408.972402 -27.336606) (xy 408.936711 -27.295415)
			(xy 408.907245 -27.249565) (xy 408.884603 -27.199988) (xy 408.869248 -27.147693) (xy 408.861492 -27.093745)
			(xy 408.861006 -27.066494) (xy 408.861547 -27.037006) (xy 408.870644 -26.978735) (xy 408.888604 -26.922559)
			(xy 408.914999 -26.869819) (xy 408.9492 -26.821771) (xy 408.990391 -26.779562) (xy 409.01366 -26.76144)
			(xy 409.024718 -26.75247) (xy 409.041894 -26.729784) (xy 409.052142 -26.703238) (xy 409.054665 -26.674896)
			(xy 409.049269 -26.646957) (xy 409.036371 -26.621593) (xy 409.016975 -26.600773) (xy 409.005024 -26.593038)
			(xy 408.981288 -26.578133) (xy 408.938051 -26.542468) (xy 408.900499 -26.500861) (xy 408.869438 -26.454207)
			(xy 408.845538 -26.40351) (xy 408.829314 -26.349862) (xy 408.821114 -26.294418) (xy 408.82062 -26.266394)
			(xy 406.252817 -26.266394) (xy 406.252278 -26.267209) (xy 406.215061 -26.308746) (xy 406.172193 -26.344421)
			(xy 406.124587 -26.373475) (xy 406.073258 -26.395287) (xy 406.019301 -26.409393) (xy 405.963864 -26.415493)
			(xy 405.90813 -26.413456) (xy 405.853287 -26.403326) (xy 405.800503 -26.385319) (xy 405.750903 -26.359818)
			(xy 405.705545 -26.327367) (xy 405.665396 -26.288658) (xy 405.63131 -26.244515) (xy 405.604014 -26.19588)
			(xy 405.584091 -26.143789) (xy 405.571965 -26.089352) (xy 405.567894 -26.03373) (xy 399.775912 -26.03373)
			(xy 399.789115 -26.044718) (xy 399.826332 -26.086255) (xy 399.857105 -26.132768) (xy 399.880777 -26.183265)
			(xy 399.896845 -26.236672) (xy 399.904965 -26.291848) (xy 399.905474 -26.319734) (xy 399.904965 -26.34762)
			(xy 399.896845 -26.402796) (xy 399.880777 -26.456203) (xy 399.857105 -26.5067) (xy 399.826332 -26.553213)
			(xy 399.789115 -26.59475) (xy 399.746247 -26.630425) (xy 399.698641 -26.659479) (xy 399.647312 -26.681291)
			(xy 399.593355 -26.695397) (xy 399.537918 -26.701497) (xy 399.482184 -26.69946) (xy 399.427341 -26.68933)
			(xy 399.374557 -26.671323) (xy 399.324957 -26.645822) (xy 399.279599 -26.613371) (xy 399.23945 -26.574662)
			(xy 399.205364 -26.530519) (xy 399.178068 -26.481884) (xy 399.158145 -26.429793) (xy 399.146019 -26.375356)
			(xy 399.141948 -26.319734) (xy 394.150675 -26.319734) (xy 394.152627 -26.332996) (xy 394.153136 -26.360882)
			(xy 394.152627 -26.388768) (xy 394.144507 -26.443944) (xy 394.128439 -26.497351) (xy 394.104767 -26.547848)
			(xy 394.073994 -26.594361) (xy 394.036777 -26.635898) (xy 393.993909 -26.671573) (xy 393.946303 -26.700627)
			(xy 393.894974 -26.722439) (xy 393.841017 -26.736545) (xy 393.78558 -26.742645) (xy 393.729846 -26.740608)
			(xy 393.675003 -26.730478) (xy 393.622219 -26.712471) (xy 393.572619 -26.68697) (xy 393.527261 -26.654519)
			(xy 393.487112 -26.61581) (xy 393.453026 -26.571667) (xy 393.42573 -26.523032) (xy 393.405807 -26.470941)
			(xy 393.393681 -26.416504) (xy 393.38961 -26.360882) (xy 391.723043 -26.360882) (xy 391.730807 -26.389856)
			(xy 391.73863 -26.449278) (xy 391.73912 -26.479246) (xy 391.73912 -26.971244) (xy 395.1511 -26.971244)
			(xy 395.155171 -26.915622) (xy 395.167297 -26.861185) (xy 395.18722 -26.809094) (xy 395.214516 -26.760459)
			(xy 395.248602 -26.716316) (xy 395.288751 -26.677607) (xy 395.334109 -26.645156) (xy 395.383709 -26.619655)
			(xy 395.436493 -26.601648) (xy 395.491336 -26.591518) (xy 395.54707 -26.589481) (xy 395.602507 -26.595581)
			(xy 395.656464 -26.609687) (xy 395.707793 -26.631499) (xy 395.755399 -26.660553) (xy 395.798267 -26.696228)
			(xy 395.835484 -26.737765) (xy 395.866257 -26.784278) (xy 395.889929 -26.834775) (xy 395.905997 -26.888182)
			(xy 395.914117 -26.943358) (xy 395.914626 -26.971244) (xy 395.914117 -26.99913) (xy 395.905997 -27.054306)
			(xy 395.889929 -27.107713) (xy 395.866257 -27.15821) (xy 395.835484 -27.204723) (xy 395.798267 -27.24626)
			(xy 395.755399 -27.281935) (xy 395.707793 -27.310989) (xy 395.656464 -27.332801) (xy 395.602507 -27.346907)
			(xy 395.54707 -27.353007) (xy 395.491336 -27.35097) (xy 395.436493 -27.34084) (xy 395.383709 -27.322833)
			(xy 395.334109 -27.297332) (xy 395.288751 -27.264881) (xy 395.248602 -27.226172) (xy 395.214516 -27.182029)
			(xy 395.18722 -27.133394) (xy 395.167297 -27.081303) (xy 395.155171 -27.026866) (xy 395.1511 -26.971244)
			(xy 391.73912 -26.971244) (xy 391.73912 -27.342846) (xy 391.73863 -27.372814) (xy 391.730807 -27.432236)
			(xy 391.715294 -27.490129) (xy 391.692358 -27.545502) (xy 391.662391 -27.597408) (xy 391.625904 -27.644958)
			(xy 391.583524 -27.687338) (xy 391.535974 -27.723825) (xy 391.484068 -27.753792) (xy 391.428695 -27.776728)
			(xy 391.370802 -27.792241) (xy 391.31138 -27.800064) (xy 391.251444 -27.800064) (xy 391.192022 -27.792241)
			(xy 391.134129 -27.776728) (xy 391.078756 -27.753792) (xy 391.02685 -27.723825) (xy 390.9793 -27.687338)
			(xy 390.93692 -27.644958) (xy 390.900433 -27.597408) (xy 390.870466 -27.545502) (xy 390.84753 -27.490129)
			(xy 390.832017 -27.432236) (xy 390.824194 -27.372814) (xy 390.823704 -27.342846) (xy 383.505476 -27.342846)
			(xy 383.471487 -27.372297) (xy 383.425637 -27.401763) (xy 383.37606 -27.424405) (xy 383.323765 -27.43976)
			(xy 383.269817 -27.447516) (xy 383.215315 -27.447516) (xy 383.161367 -27.43976) (xy 383.109072 -27.424405)
			(xy 383.059495 -27.401763) (xy 383.013645 -27.372297) (xy 382.972454 -27.336606) (xy 382.936763 -27.295415)
			(xy 382.907297 -27.249565) (xy 382.884655 -27.199988) (xy 382.8693 -27.147693) (xy 382.861544 -27.093745)
			(xy 382.861058 -27.066494) (xy 382.861618 -27.037007) (xy 382.870713 -26.978737) (xy 382.888671 -26.922563)
			(xy 382.915063 -26.869823) (xy 382.949259 -26.821775) (xy 382.990445 -26.779564) (xy 383.013712 -26.76144)
			(xy 383.024776 -26.752476) (xy 383.041961 -26.729791) (xy 383.052215 -26.703243) (xy 383.05474 -26.674895)
			(xy 383.049341 -26.646953) (xy 383.036437 -26.621587) (xy 383.017031 -26.60077) (xy 383.005076 -26.593038)
			(xy 382.981329 -26.57815) (xy 382.938095 -26.542481) (xy 382.900544 -26.50087) (xy 382.869486 -26.454213)
			(xy 382.845588 -26.403514) (xy 382.829365 -26.349864) (xy 382.821166 -26.294418) (xy 382.820672 -26.266394)
			(xy 380.252869 -26.266394) (xy 380.25233 -26.267209) (xy 380.215113 -26.308746) (xy 380.172245 -26.344421)
			(xy 380.124639 -26.373475) (xy 380.07331 -26.395287) (xy 380.019353 -26.409393) (xy 379.963916 -26.415493)
			(xy 379.908182 -26.413456) (xy 379.853339 -26.403326) (xy 379.800555 -26.385319) (xy 379.750955 -26.359818)
			(xy 379.705597 -26.327367) (xy 379.665448 -26.288658) (xy 379.631362 -26.244515) (xy 379.604066 -26.19588)
			(xy 379.584143 -26.143789) (xy 379.572017 -26.089352) (xy 379.567946 -26.03373) (xy 373.775964 -26.03373)
			(xy 373.789167 -26.044718) (xy 373.826384 -26.086255) (xy 373.857157 -26.132768) (xy 373.880829 -26.183265)
			(xy 373.896897 -26.236672) (xy 373.905017 -26.291848) (xy 373.905526 -26.319734) (xy 373.905017 -26.34762)
			(xy 373.896897 -26.402796) (xy 373.880829 -26.456203) (xy 373.857157 -26.5067) (xy 373.826384 -26.553213)
			(xy 373.789167 -26.59475) (xy 373.746299 -26.630425) (xy 373.698693 -26.659479) (xy 373.647364 -26.681291)
			(xy 373.593407 -26.695397) (xy 373.53797 -26.701497) (xy 373.482236 -26.69946) (xy 373.427393 -26.68933)
			(xy 373.374609 -26.671323) (xy 373.325009 -26.645822) (xy 373.279651 -26.613371) (xy 373.239502 -26.574662)
			(xy 373.205416 -26.530519) (xy 373.17812 -26.481884) (xy 373.158197 -26.429793) (xy 373.146071 -26.375356)
			(xy 373.142 -26.319734) (xy 368.150727 -26.319734) (xy 368.152679 -26.332996) (xy 368.153188 -26.360882)
			(xy 368.152679 -26.388768) (xy 368.144559 -26.443944) (xy 368.128491 -26.497351) (xy 368.104819 -26.547848)
			(xy 368.074046 -26.594361) (xy 368.036829 -26.635898) (xy 367.993961 -26.671573) (xy 367.946355 -26.700627)
			(xy 367.895026 -26.722439) (xy 367.841069 -26.736545) (xy 367.785632 -26.742645) (xy 367.729898 -26.740608)
			(xy 367.675055 -26.730478) (xy 367.622271 -26.712471) (xy 367.572671 -26.68697) (xy 367.527313 -26.654519)
			(xy 367.487164 -26.61581) (xy 367.453078 -26.571667) (xy 367.425782 -26.523032) (xy 367.405859 -26.470941)
			(xy 367.393733 -26.416504) (xy 367.389662 -26.360882) (xy 365.723095 -26.360882) (xy 365.730859 -26.389856)
			(xy 365.738682 -26.449278) (xy 365.739172 -26.479246) (xy 365.739172 -26.971244) (xy 369.151152 -26.971244)
			(xy 369.155223 -26.915622) (xy 369.167349 -26.861185) (xy 369.187272 -26.809094) (xy 369.214568 -26.760459)
			(xy 369.248654 -26.716316) (xy 369.288803 -26.677607) (xy 369.334161 -26.645156) (xy 369.383761 -26.619655)
			(xy 369.436545 -26.601648) (xy 369.491388 -26.591518) (xy 369.547122 -26.589481) (xy 369.602559 -26.595581)
			(xy 369.656516 -26.609687) (xy 369.707845 -26.631499) (xy 369.755451 -26.660553) (xy 369.798319 -26.696228)
			(xy 369.835536 -26.737765) (xy 369.866309 -26.784278) (xy 369.889981 -26.834775) (xy 369.906049 -26.888182)
			(xy 369.914169 -26.943358) (xy 369.914678 -26.971244) (xy 369.914169 -26.99913) (xy 369.906049 -27.054306)
			(xy 369.889981 -27.107713) (xy 369.866309 -27.15821) (xy 369.835536 -27.204723) (xy 369.798319 -27.24626)
			(xy 369.755451 -27.281935) (xy 369.707845 -27.310989) (xy 369.656516 -27.332801) (xy 369.602559 -27.346907)
			(xy 369.547122 -27.353007) (xy 369.491388 -27.35097) (xy 369.436545 -27.34084) (xy 369.383761 -27.322833)
			(xy 369.334161 -27.297332) (xy 369.288803 -27.264881) (xy 369.248654 -27.226172) (xy 369.214568 -27.182029)
			(xy 369.187272 -27.133394) (xy 369.167349 -27.081303) (xy 369.155223 -27.026866) (xy 369.151152 -26.971244)
			(xy 365.739172 -26.971244) (xy 365.739172 -27.342846) (xy 365.738682 -27.372814) (xy 365.730859 -27.432236)
			(xy 365.715346 -27.490129) (xy 365.69241 -27.545502) (xy 365.662443 -27.597408) (xy 365.625956 -27.644958)
			(xy 365.583576 -27.687338) (xy 365.536026 -27.723825) (xy 365.48412 -27.753792) (xy 365.428747 -27.776728)
			(xy 365.370854 -27.792241) (xy 365.311432 -27.800064) (xy 365.251496 -27.800064) (xy 365.192074 -27.792241)
			(xy 365.134181 -27.776728) (xy 365.078808 -27.753792) (xy 365.026902 -27.723825) (xy 364.979352 -27.687338)
			(xy 364.936972 -27.644958) (xy 364.900485 -27.597408) (xy 364.870518 -27.545502) (xy 364.847582 -27.490129)
			(xy 364.832069 -27.432236) (xy 364.824246 -27.372814) (xy 364.823756 -27.342846) (xy 357.505528 -27.342846)
			(xy 357.471539 -27.372297) (xy 357.425689 -27.401763) (xy 357.376112 -27.424405) (xy 357.323817 -27.43976)
			(xy 357.269869 -27.447516) (xy 357.215367 -27.447516) (xy 357.161419 -27.43976) (xy 357.109124 -27.424405)
			(xy 357.059547 -27.401763) (xy 357.013697 -27.372297) (xy 356.972506 -27.336606) (xy 356.936815 -27.295415)
			(xy 356.907349 -27.249565) (xy 356.884707 -27.199988) (xy 356.869352 -27.147693) (xy 356.861596 -27.093745)
			(xy 356.86111 -27.066494) (xy 356.861649 -27.037006) (xy 356.870746 -26.978734) (xy 356.888707 -26.922559)
			(xy 356.915102 -26.869818) (xy 356.949303 -26.821771) (xy 356.990495 -26.779562) (xy 357.013764 -26.76144)
			(xy 357.024821 -26.75247) (xy 357.041996 -26.729784) (xy 357.052244 -26.703238) (xy 357.054767 -26.674896)
			(xy 357.049371 -26.646957) (xy 357.036474 -26.621593) (xy 357.017078 -26.600773) (xy 357.005128 -26.593038)
			(xy 356.981392 -26.578131) (xy 356.938156 -26.542467) (xy 356.900603 -26.50086) (xy 356.869542 -26.454207)
			(xy 356.845643 -26.40351) (xy 356.829418 -26.349862) (xy 356.821218 -26.294418) (xy 356.820724 -26.266394)
			(xy 354.252921 -26.266394) (xy 354.252382 -26.267209) (xy 354.215165 -26.308746) (xy 354.172297 -26.344421)
			(xy 354.124691 -26.373475) (xy 354.073362 -26.395287) (xy 354.019405 -26.409393) (xy 353.963968 -26.415493)
			(xy 353.908234 -26.413456) (xy 353.853391 -26.403326) (xy 353.800607 -26.385319) (xy 353.751007 -26.359818)
			(xy 353.705649 -26.327367) (xy 353.6655 -26.288658) (xy 353.631414 -26.244515) (xy 353.604118 -26.19588)
			(xy 353.584195 -26.143789) (xy 353.572069 -26.089352) (xy 353.567998 -26.03373) (xy 335.67571 -26.03373)
			(xy 335.688913 -26.044718) (xy 335.72613 -26.086255) (xy 335.756903 -26.132768) (xy 335.780575 -26.183265)
			(xy 335.796643 -26.236672) (xy 335.804763 -26.291848) (xy 335.805272 -26.319734) (xy 335.804763 -26.34762)
			(xy 335.796643 -26.402796) (xy 335.780575 -26.456203) (xy 335.756903 -26.5067) (xy 335.72613 -26.553213)
			(xy 335.688913 -26.59475) (xy 335.646045 -26.630425) (xy 335.598439 -26.659479) (xy 335.54711 -26.681291)
			(xy 335.493153 -26.695397) (xy 335.437716 -26.701497) (xy 335.381982 -26.69946) (xy 335.327139 -26.68933)
			(xy 335.274355 -26.671323) (xy 335.224755 -26.645822) (xy 335.179397 -26.613371) (xy 335.139248 -26.574662)
			(xy 335.105162 -26.530519) (xy 335.077866 -26.481884) (xy 335.057943 -26.429793) (xy 335.045817 -26.375356)
			(xy 335.041746 -26.319734) (xy 330.050473 -26.319734) (xy 330.052425 -26.332996) (xy 330.052934 -26.360882)
			(xy 330.052425 -26.388768) (xy 330.044305 -26.443944) (xy 330.028237 -26.497351) (xy 330.004565 -26.547848)
			(xy 329.973792 -26.594361) (xy 329.936575 -26.635898) (xy 329.893707 -26.671573) (xy 329.846101 -26.700627)
			(xy 329.794772 -26.722439) (xy 329.740815 -26.736545) (xy 329.685378 -26.742645) (xy 329.629644 -26.740608)
			(xy 329.574801 -26.730478) (xy 329.522017 -26.712471) (xy 329.472417 -26.68697) (xy 329.427059 -26.654519)
			(xy 329.38691 -26.61581) (xy 329.352824 -26.571667) (xy 329.325528 -26.523032) (xy 329.305605 -26.470941)
			(xy 329.293479 -26.416504) (xy 329.289408 -26.360882) (xy 327.623104 -26.360882) (xy 327.630854 -26.389806)
			(xy 327.638682 -26.449262) (xy 327.639172 -26.479246) (xy 327.639172 -26.971244) (xy 331.050898 -26.971244)
			(xy 331.054969 -26.915622) (xy 331.067095 -26.861185) (xy 331.087018 -26.809094) (xy 331.114314 -26.760459)
			(xy 331.1484 -26.716316) (xy 331.188549 -26.677607) (xy 331.233907 -26.645156) (xy 331.283507 -26.619655)
			(xy 331.336291 -26.601648) (xy 331.391134 -26.591518) (xy 331.446868 -26.589481) (xy 331.502305 -26.595581)
			(xy 331.556262 -26.609687) (xy 331.607591 -26.631499) (xy 331.655197 -26.660553) (xy 331.698065 -26.696228)
			(xy 331.735282 -26.737765) (xy 331.766055 -26.784278) (xy 331.789727 -26.834775) (xy 331.805795 -26.888182)
			(xy 331.813915 -26.943358) (xy 331.814424 -26.971244) (xy 331.813915 -26.99913) (xy 331.805795 -27.054306)
			(xy 331.789727 -27.107713) (xy 331.766055 -27.15821) (xy 331.735282 -27.204723) (xy 331.698065 -27.24626)
			(xy 331.655197 -27.281935) (xy 331.607591 -27.310989) (xy 331.556262 -27.332801) (xy 331.502305 -27.346907)
			(xy 331.446868 -27.353007) (xy 331.391134 -27.35097) (xy 331.336291 -27.34084) (xy 331.283507 -27.322833)
			(xy 331.233907 -27.297332) (xy 331.188549 -27.264881) (xy 331.1484 -27.226172) (xy 331.114314 -27.182029)
			(xy 331.087018 -27.133394) (xy 331.067095 -27.081303) (xy 331.054969 -27.026866) (xy 331.050898 -26.971244)
			(xy 327.639172 -26.971244) (xy 327.639172 -27.342846) (xy 327.638682 -27.37283) (xy 327.630854 -27.432286)
			(xy 327.615333 -27.490211) (xy 327.592384 -27.545615) (xy 327.5624 -27.597549) (xy 327.525894 -27.645125)
			(xy 327.483489 -27.68753) (xy 327.435913 -27.724036) (xy 327.383979 -27.75402) (xy 327.328575 -27.776969)
			(xy 327.27065 -27.79249) (xy 327.211194 -27.800318) (xy 327.151226 -27.800318) (xy 327.09177 -27.79249)
			(xy 327.033845 -27.776969) (xy 326.978441 -27.75402) (xy 326.926507 -27.724036) (xy 326.878931 -27.68753)
			(xy 326.836526 -27.645125) (xy 326.80002 -27.597549) (xy 326.770036 -27.545615) (xy 326.747087 -27.490211)
			(xy 326.731566 -27.432286) (xy 326.723738 -27.37283) (xy 326.723248 -27.342846) (xy 319.405274 -27.342846)
			(xy 319.371285 -27.372297) (xy 319.325435 -27.401763) (xy 319.275858 -27.424405) (xy 319.223563 -27.43976)
			(xy 319.169615 -27.447516) (xy 319.115113 -27.447516) (xy 319.061165 -27.43976) (xy 319.00887 -27.424405)
			(xy 318.959293 -27.401763) (xy 318.913443 -27.372297) (xy 318.872252 -27.336606) (xy 318.836561 -27.295415)
			(xy 318.807095 -27.249565) (xy 318.784453 -27.199988) (xy 318.769098 -27.147693) (xy 318.761342 -27.093745)
			(xy 318.760856 -27.066494) (xy 318.761417 -27.037007) (xy 318.770512 -26.978738) (xy 318.78847 -26.922563)
			(xy 318.814861 -26.869823) (xy 318.849058 -26.821775) (xy 318.890244 -26.779564) (xy 318.91351 -26.76144)
			(xy 318.924575 -26.752476) (xy 318.94176 -26.729791) (xy 318.952014 -26.703243) (xy 318.954539 -26.674895)
			(xy 318.94914 -26.646953) (xy 318.936235 -26.621587) (xy 318.916829 -26.60077) (xy 318.904874 -26.593038)
			(xy 318.881126 -26.578151) (xy 318.837892 -26.542481) (xy 318.800342 -26.50087) (xy 318.769284 -26.454213)
			(xy 318.745386 -26.403514) (xy 318.729163 -26.349864) (xy 318.720964 -26.294418) (xy 318.72047 -26.266394)
			(xy 316.152667 -26.266394) (xy 316.152128 -26.267209) (xy 316.114911 -26.308746) (xy 316.072043 -26.344421)
			(xy 316.024437 -26.373475) (xy 315.973108 -26.395287) (xy 315.919151 -26.409393) (xy 315.863714 -26.415493)
			(xy 315.80798 -26.413456) (xy 315.753137 -26.403326) (xy 315.700353 -26.385319) (xy 315.650753 -26.359818)
			(xy 315.605395 -26.327367) (xy 315.565246 -26.288658) (xy 315.53116 -26.244515) (xy 315.503864 -26.19588)
			(xy 315.483941 -26.143789) (xy 315.471815 -26.089352) (xy 315.467744 -26.03373) (xy 309.675762 -26.03373)
			(xy 309.688965 -26.044718) (xy 309.726182 -26.086255) (xy 309.756955 -26.132768) (xy 309.780627 -26.183265)
			(xy 309.796695 -26.236672) (xy 309.804815 -26.291848) (xy 309.805324 -26.319734) (xy 309.804815 -26.34762)
			(xy 309.796695 -26.402796) (xy 309.780627 -26.456203) (xy 309.756955 -26.5067) (xy 309.726182 -26.553213)
			(xy 309.688965 -26.59475) (xy 309.646097 -26.630425) (xy 309.598491 -26.659479) (xy 309.547162 -26.681291)
			(xy 309.493205 -26.695397) (xy 309.437768 -26.701497) (xy 309.382034 -26.69946) (xy 309.327191 -26.68933)
			(xy 309.274407 -26.671323) (xy 309.224807 -26.645822) (xy 309.179449 -26.613371) (xy 309.1393 -26.574662)
			(xy 309.105214 -26.530519) (xy 309.077918 -26.481884) (xy 309.057995 -26.429793) (xy 309.045869 -26.375356)
			(xy 309.041798 -26.319734) (xy 304.050525 -26.319734) (xy 304.052477 -26.332996) (xy 304.052986 -26.360882)
			(xy 304.052477 -26.388768) (xy 304.044357 -26.443944) (xy 304.028289 -26.497351) (xy 304.004617 -26.547848)
			(xy 303.973844 -26.594361) (xy 303.936627 -26.635898) (xy 303.893759 -26.671573) (xy 303.846153 -26.700627)
			(xy 303.794824 -26.722439) (xy 303.740867 -26.736545) (xy 303.68543 -26.742645) (xy 303.629696 -26.740608)
			(xy 303.574853 -26.730478) (xy 303.522069 -26.712471) (xy 303.472469 -26.68697) (xy 303.427111 -26.654519)
			(xy 303.386962 -26.61581) (xy 303.352876 -26.571667) (xy 303.32558 -26.523032) (xy 303.305657 -26.470941)
			(xy 303.293531 -26.416504) (xy 303.28946 -26.360882) (xy 301.623156 -26.360882) (xy 301.630906 -26.389806)
			(xy 301.638734 -26.449262) (xy 301.639224 -26.479246) (xy 301.639224 -26.971244) (xy 305.05095 -26.971244)
			(xy 305.055021 -26.915622) (xy 305.067147 -26.861185) (xy 305.08707 -26.809094) (xy 305.114366 -26.760459)
			(xy 305.148452 -26.716316) (xy 305.188601 -26.677607) (xy 305.233959 -26.645156) (xy 305.283559 -26.619655)
			(xy 305.336343 -26.601648) (xy 305.391186 -26.591518) (xy 305.44692 -26.589481) (xy 305.502357 -26.595581)
			(xy 305.556314 -26.609687) (xy 305.607643 -26.631499) (xy 305.655249 -26.660553) (xy 305.698117 -26.696228)
			(xy 305.735334 -26.737765) (xy 305.766107 -26.784278) (xy 305.789779 -26.834775) (xy 305.805847 -26.888182)
			(xy 305.813967 -26.943358) (xy 305.814476 -26.971244) (xy 305.813967 -26.99913) (xy 305.805847 -27.054306)
			(xy 305.789779 -27.107713) (xy 305.766107 -27.15821) (xy 305.735334 -27.204723) (xy 305.698117 -27.24626)
			(xy 305.655249 -27.281935) (xy 305.607643 -27.310989) (xy 305.556314 -27.332801) (xy 305.502357 -27.346907)
			(xy 305.44692 -27.353007) (xy 305.391186 -27.35097) (xy 305.336343 -27.34084) (xy 305.283559 -27.322833)
			(xy 305.233959 -27.297332) (xy 305.188601 -27.264881) (xy 305.148452 -27.226172) (xy 305.114366 -27.182029)
			(xy 305.08707 -27.133394) (xy 305.067147 -27.081303) (xy 305.055021 -27.026866) (xy 305.05095 -26.971244)
			(xy 301.639224 -26.971244) (xy 301.639224 -27.342846) (xy 301.638734 -27.37283) (xy 301.630906 -27.432286)
			(xy 301.615385 -27.490211) (xy 301.592436 -27.545615) (xy 301.562452 -27.597549) (xy 301.525946 -27.645125)
			(xy 301.483541 -27.68753) (xy 301.435965 -27.724036) (xy 301.384031 -27.75402) (xy 301.328627 -27.776969)
			(xy 301.270702 -27.79249) (xy 301.211246 -27.800318) (xy 301.151278 -27.800318) (xy 301.091822 -27.79249)
			(xy 301.033897 -27.776969) (xy 300.978493 -27.75402) (xy 300.926559 -27.724036) (xy 300.878983 -27.68753)
			(xy 300.836578 -27.645125) (xy 300.800072 -27.597549) (xy 300.770088 -27.545615) (xy 300.747139 -27.490211)
			(xy 300.731618 -27.432286) (xy 300.72379 -27.37283) (xy 300.7233 -27.342846) (xy 293.405326 -27.342846)
			(xy 293.371337 -27.372297) (xy 293.325487 -27.401763) (xy 293.27591 -27.424405) (xy 293.223615 -27.43976)
			(xy 293.169667 -27.447516) (xy 293.115165 -27.447516) (xy 293.061217 -27.43976) (xy 293.008922 -27.424405)
			(xy 292.959345 -27.401763) (xy 292.913495 -27.372297) (xy 292.872304 -27.336606) (xy 292.836613 -27.295415)
			(xy 292.807147 -27.249565) (xy 292.784505 -27.199988) (xy 292.76915 -27.147693) (xy 292.761394 -27.093745)
			(xy 292.760908 -27.066494) (xy 292.761448 -27.037006) (xy 292.770545 -26.978735) (xy 292.788505 -26.922559)
			(xy 292.814901 -26.869818) (xy 292.849102 -26.821771) (xy 292.890293 -26.779562) (xy 292.913562 -26.76144)
			(xy 292.924619 -26.75247) (xy 292.941795 -26.729784) (xy 292.952043 -26.703238) (xy 292.954566 -26.674896)
			(xy 292.94917 -26.646957) (xy 292.936273 -26.621593) (xy 292.916876 -26.600773) (xy 292.904926 -26.593038)
			(xy 292.88119 -26.578132) (xy 292.837953 -26.542468) (xy 292.800401 -26.500861) (xy 292.76934 -26.454207)
			(xy 292.74544 -26.40351) (xy 292.729216 -26.349862) (xy 292.721016 -26.294418) (xy 292.720522 -26.266394)
			(xy 290.152719 -26.266394) (xy 290.15218 -26.267209) (xy 290.114963 -26.308746) (xy 290.072095 -26.344421)
			(xy 290.024489 -26.373475) (xy 289.97316 -26.395287) (xy 289.919203 -26.409393) (xy 289.863766 -26.415493)
			(xy 289.808032 -26.413456) (xy 289.753189 -26.403326) (xy 289.700405 -26.385319) (xy 289.650805 -26.359818)
			(xy 289.605447 -26.327367) (xy 289.565298 -26.288658) (xy 289.531212 -26.244515) (xy 289.503916 -26.19588)
			(xy 289.483993 -26.143789) (xy 289.471867 -26.089352) (xy 289.467796 -26.03373) (xy 283.675814 -26.03373)
			(xy 283.689017 -26.044718) (xy 283.726234 -26.086255) (xy 283.757007 -26.132768) (xy 283.780679 -26.183265)
			(xy 283.796747 -26.236672) (xy 283.804867 -26.291848) (xy 283.805376 -26.319734) (xy 283.804867 -26.34762)
			(xy 283.796747 -26.402796) (xy 283.780679 -26.456203) (xy 283.757007 -26.5067) (xy 283.726234 -26.553213)
			(xy 283.689017 -26.59475) (xy 283.646149 -26.630425) (xy 283.598543 -26.659479) (xy 283.547214 -26.681291)
			(xy 283.493257 -26.695397) (xy 283.43782 -26.701497) (xy 283.382086 -26.69946) (xy 283.327243 -26.68933)
			(xy 283.274459 -26.671323) (xy 283.224859 -26.645822) (xy 283.179501 -26.613371) (xy 283.139352 -26.574662)
			(xy 283.105266 -26.530519) (xy 283.07797 -26.481884) (xy 283.058047 -26.429793) (xy 283.045921 -26.375356)
			(xy 283.04185 -26.319734) (xy 278.050577 -26.319734) (xy 278.052529 -26.332996) (xy 278.053038 -26.360882)
			(xy 278.052529 -26.388768) (xy 278.044409 -26.443944) (xy 278.028341 -26.497351) (xy 278.004669 -26.547848)
			(xy 277.973896 -26.594361) (xy 277.936679 -26.635898) (xy 277.893811 -26.671573) (xy 277.846205 -26.700627)
			(xy 277.794876 -26.722439) (xy 277.740919 -26.736545) (xy 277.685482 -26.742645) (xy 277.629748 -26.740608)
			(xy 277.574905 -26.730478) (xy 277.522121 -26.712471) (xy 277.472521 -26.68697) (xy 277.427163 -26.654519)
			(xy 277.387014 -26.61581) (xy 277.352928 -26.571667) (xy 277.325632 -26.523032) (xy 277.305709 -26.470941)
			(xy 277.293583 -26.416504) (xy 277.289512 -26.360882) (xy 275.623208 -26.360882) (xy 275.630958 -26.389806)
			(xy 275.638786 -26.449262) (xy 275.639276 -26.479246) (xy 275.639276 -26.971244) (xy 279.051002 -26.971244)
			(xy 279.055073 -26.915622) (xy 279.067199 -26.861185) (xy 279.087122 -26.809094) (xy 279.114418 -26.760459)
			(xy 279.148504 -26.716316) (xy 279.188653 -26.677607) (xy 279.234011 -26.645156) (xy 279.283611 -26.619655)
			(xy 279.336395 -26.601648) (xy 279.391238 -26.591518) (xy 279.446972 -26.589481) (xy 279.502409 -26.595581)
			(xy 279.556366 -26.609687) (xy 279.607695 -26.631499) (xy 279.655301 -26.660553) (xy 279.698169 -26.696228)
			(xy 279.735386 -26.737765) (xy 279.766159 -26.784278) (xy 279.789831 -26.834775) (xy 279.805899 -26.888182)
			(xy 279.814019 -26.943358) (xy 279.814528 -26.971244) (xy 279.814019 -26.99913) (xy 279.805899 -27.054306)
			(xy 279.789831 -27.107713) (xy 279.766159 -27.15821) (xy 279.735386 -27.204723) (xy 279.698169 -27.24626)
			(xy 279.655301 -27.281935) (xy 279.607695 -27.310989) (xy 279.556366 -27.332801) (xy 279.502409 -27.346907)
			(xy 279.446972 -27.353007) (xy 279.391238 -27.35097) (xy 279.336395 -27.34084) (xy 279.283611 -27.322833)
			(xy 279.234011 -27.297332) (xy 279.188653 -27.264881) (xy 279.148504 -27.226172) (xy 279.114418 -27.182029)
			(xy 279.087122 -27.133394) (xy 279.067199 -27.081303) (xy 279.055073 -27.026866) (xy 279.051002 -26.971244)
			(xy 275.639276 -26.971244) (xy 275.639276 -27.342846) (xy 275.638786 -27.37283) (xy 275.630958 -27.432286)
			(xy 275.615437 -27.490211) (xy 275.592488 -27.545615) (xy 275.562504 -27.597549) (xy 275.525998 -27.645125)
			(xy 275.483593 -27.68753) (xy 275.436017 -27.724036) (xy 275.384083 -27.75402) (xy 275.328679 -27.776969)
			(xy 275.270754 -27.79249) (xy 275.211298 -27.800318) (xy 275.15133 -27.800318) (xy 275.091874 -27.79249)
			(xy 275.033949 -27.776969) (xy 274.978545 -27.75402) (xy 274.926611 -27.724036) (xy 274.879035 -27.68753)
			(xy 274.83663 -27.645125) (xy 274.800124 -27.597549) (xy 274.77014 -27.545615) (xy 274.747191 -27.490211)
			(xy 274.73167 -27.432286) (xy 274.723842 -27.37283) (xy 274.723352 -27.342846) (xy 267.405378 -27.342846)
			(xy 267.371389 -27.372297) (xy 267.325539 -27.401763) (xy 267.275962 -27.424405) (xy 267.223667 -27.43976)
			(xy 267.169719 -27.447516) (xy 267.115217 -27.447516) (xy 267.061269 -27.43976) (xy 267.008974 -27.424405)
			(xy 266.959397 -27.401763) (xy 266.913547 -27.372297) (xy 266.872356 -27.336606) (xy 266.836665 -27.295415)
			(xy 266.807199 -27.249565) (xy 266.784557 -27.199988) (xy 266.769202 -27.147693) (xy 266.761446 -27.093745)
			(xy 266.76096 -27.066494) (xy 266.761519 -27.037007) (xy 266.770615 -26.978737) (xy 266.788572 -26.922563)
			(xy 266.814964 -26.869823) (xy 266.849161 -26.821775) (xy 266.890347 -26.779564) (xy 266.913614 -26.76144)
			(xy 266.924678 -26.752476) (xy 266.941862 -26.72979) (xy 266.952116 -26.703242) (xy 266.954641 -26.674895)
			(xy 266.949242 -26.646953) (xy 266.936338 -26.621587) (xy 266.916933 -26.60077) (xy 266.904978 -26.593038)
			(xy 266.881231 -26.578149) (xy 266.837997 -26.54248) (xy 266.800447 -26.500869) (xy 266.769388 -26.454213)
			(xy 266.74549 -26.403514) (xy 266.729267 -26.349864) (xy 266.721068 -26.294418) (xy 266.720574 -26.266394)
			(xy 264.152771 -26.266394) (xy 264.152232 -26.267209) (xy 264.115015 -26.308746) (xy 264.072147 -26.344421)
			(xy 264.024541 -26.373475) (xy 263.973212 -26.395287) (xy 263.919255 -26.409393) (xy 263.863818 -26.415493)
			(xy 263.808084 -26.413456) (xy 263.753241 -26.403326) (xy 263.700457 -26.385319) (xy 263.650857 -26.359818)
			(xy 263.605499 -26.327367) (xy 263.56535 -26.288658) (xy 263.531264 -26.244515) (xy 263.503968 -26.19588)
			(xy 263.484045 -26.143789) (xy 263.471919 -26.089352) (xy 263.467848 -26.03373) (xy 257.675866 -26.03373)
			(xy 257.689069 -26.044718) (xy 257.726286 -26.086255) (xy 257.757059 -26.132768) (xy 257.780731 -26.183265)
			(xy 257.796799 -26.236672) (xy 257.804919 -26.291848) (xy 257.805428 -26.319734) (xy 257.804919 -26.34762)
			(xy 257.796799 -26.402796) (xy 257.780731 -26.456203) (xy 257.757059 -26.5067) (xy 257.726286 -26.553213)
			(xy 257.689069 -26.59475) (xy 257.646201 -26.630425) (xy 257.598595 -26.659479) (xy 257.547266 -26.681291)
			(xy 257.493309 -26.695397) (xy 257.437872 -26.701497) (xy 257.382138 -26.69946) (xy 257.327295 -26.68933)
			(xy 257.274511 -26.671323) (xy 257.224911 -26.645822) (xy 257.179553 -26.613371) (xy 257.139404 -26.574662)
			(xy 257.105318 -26.530519) (xy 257.078022 -26.481884) (xy 257.058099 -26.429793) (xy 257.045973 -26.375356)
			(xy 257.041902 -26.319734) (xy 252.050629 -26.319734) (xy 252.052581 -26.332996) (xy 252.05309 -26.360882)
			(xy 252.052581 -26.388768) (xy 252.044461 -26.443944) (xy 252.028393 -26.497351) (xy 252.004721 -26.547848)
			(xy 251.973948 -26.594361) (xy 251.936731 -26.635898) (xy 251.893863 -26.671573) (xy 251.846257 -26.700627)
			(xy 251.794928 -26.722439) (xy 251.740971 -26.736545) (xy 251.685534 -26.742645) (xy 251.6298 -26.740608)
			(xy 251.574957 -26.730478) (xy 251.522173 -26.712471) (xy 251.472573 -26.68697) (xy 251.427215 -26.654519)
			(xy 251.387066 -26.61581) (xy 251.35298 -26.571667) (xy 251.325684 -26.523032) (xy 251.305761 -26.470941)
			(xy 251.293635 -26.416504) (xy 251.289564 -26.360882) (xy 249.62326 -26.360882) (xy 249.63101 -26.389806)
			(xy 249.638838 -26.449262) (xy 249.639328 -26.479246) (xy 249.639328 -26.971244) (xy 253.051054 -26.971244)
			(xy 253.055125 -26.915622) (xy 253.067251 -26.861185) (xy 253.087174 -26.809094) (xy 253.11447 -26.760459)
			(xy 253.148556 -26.716316) (xy 253.188705 -26.677607) (xy 253.234063 -26.645156) (xy 253.283663 -26.619655)
			(xy 253.336447 -26.601648) (xy 253.39129 -26.591518) (xy 253.447024 -26.589481) (xy 253.502461 -26.595581)
			(xy 253.556418 -26.609687) (xy 253.607747 -26.631499) (xy 253.655353 -26.660553) (xy 253.698221 -26.696228)
			(xy 253.735438 -26.737765) (xy 253.766211 -26.784278) (xy 253.789883 -26.834775) (xy 253.805951 -26.888182)
			(xy 253.814071 -26.943358) (xy 253.81458 -26.971244) (xy 253.814071 -26.99913) (xy 253.805951 -27.054306)
			(xy 253.789883 -27.107713) (xy 253.766211 -27.15821) (xy 253.735438 -27.204723) (xy 253.698221 -27.24626)
			(xy 253.655353 -27.281935) (xy 253.607747 -27.310989) (xy 253.556418 -27.332801) (xy 253.502461 -27.346907)
			(xy 253.447024 -27.353007) (xy 253.39129 -27.35097) (xy 253.336447 -27.34084) (xy 253.283663 -27.322833)
			(xy 253.234063 -27.297332) (xy 253.188705 -27.264881) (xy 253.148556 -27.226172) (xy 253.11447 -27.182029)
			(xy 253.087174 -27.133394) (xy 253.067251 -27.081303) (xy 253.055125 -27.026866) (xy 253.051054 -26.971244)
			(xy 249.639328 -26.971244) (xy 249.639328 -27.342846) (xy 249.638838 -27.37283) (xy 249.63101 -27.432286)
			(xy 249.615489 -27.490211) (xy 249.59254 -27.545615) (xy 249.562556 -27.597549) (xy 249.52605 -27.645125)
			(xy 249.483645 -27.68753) (xy 249.436069 -27.724036) (xy 249.384135 -27.75402) (xy 249.328731 -27.776969)
			(xy 249.270806 -27.79249) (xy 249.21135 -27.800318) (xy 249.151382 -27.800318) (xy 249.091926 -27.79249)
			(xy 249.034001 -27.776969) (xy 248.978597 -27.75402) (xy 248.926663 -27.724036) (xy 248.879087 -27.68753)
			(xy 248.836682 -27.645125) (xy 248.800176 -27.597549) (xy 248.770192 -27.545615) (xy 248.747243 -27.490211)
			(xy 248.731722 -27.432286) (xy 248.723894 -27.37283) (xy 248.723404 -27.342846) (xy 241.40543 -27.342846)
			(xy 241.371441 -27.372297) (xy 241.325591 -27.401763) (xy 241.276014 -27.424405) (xy 241.223719 -27.43976)
			(xy 241.169771 -27.447516) (xy 241.115269 -27.447516) (xy 241.061321 -27.43976) (xy 241.009026 -27.424405)
			(xy 240.959449 -27.401763) (xy 240.913599 -27.372297) (xy 240.872408 -27.336606) (xy 240.836717 -27.295415)
			(xy 240.807251 -27.249565) (xy 240.784609 -27.199988) (xy 240.769254 -27.147693) (xy 240.761498 -27.093745)
			(xy 240.761012 -27.066494) (xy 240.76155 -27.037006) (xy 240.770647 -26.978734) (xy 240.788608 -26.922559)
			(xy 240.815004 -26.869818) (xy 240.849205 -26.821771) (xy 240.890397 -26.779562) (xy 240.913666 -26.76144)
			(xy 240.924723 -26.75247) (xy 240.941898 -26.729783) (xy 240.952145 -26.703238) (xy 240.954668 -26.674896)
			(xy 240.949272 -26.646957) (xy 240.936376 -26.621593) (xy 240.91698 -26.600773) (xy 240.90503 -26.593038)
			(xy 240.881295 -26.578131) (xy 240.838058 -26.542467) (xy 240.800505 -26.50086) (xy 240.769445 -26.454206)
			(xy 240.745545 -26.40351) (xy 240.72932 -26.349862) (xy 240.72112 -26.294418) (xy 240.720626 -26.266394)
			(xy 238.152823 -26.266394) (xy 238.152284 -26.267209) (xy 238.115067 -26.308746) (xy 238.072199 -26.344421)
			(xy 238.024593 -26.373475) (xy 237.973264 -26.395287) (xy 237.919307 -26.409393) (xy 237.86387 -26.415493)
			(xy 237.808136 -26.413456) (xy 237.753293 -26.403326) (xy 237.700509 -26.385319) (xy 237.650909 -26.359818)
			(xy 237.605551 -26.327367) (xy 237.565402 -26.288658) (xy 237.531316 -26.244515) (xy 237.50402 -26.19588)
			(xy 237.484097 -26.143789) (xy 237.471971 -26.089352) (xy 237.4679 -26.03373) (xy 219.575866 -26.03373)
			(xy 219.589069 -26.044718) (xy 219.626286 -26.086255) (xy 219.657059 -26.132768) (xy 219.680731 -26.183265)
			(xy 219.696799 -26.236672) (xy 219.704919 -26.291848) (xy 219.705428 -26.319734) (xy 219.704919 -26.34762)
			(xy 219.696799 -26.402796) (xy 219.680731 -26.456203) (xy 219.657059 -26.5067) (xy 219.626286 -26.553213)
			(xy 219.589069 -26.59475) (xy 219.546201 -26.630425) (xy 219.498595 -26.659479) (xy 219.447266 -26.681291)
			(xy 219.393309 -26.695397) (xy 219.337872 -26.701497) (xy 219.282138 -26.69946) (xy 219.227295 -26.68933)
			(xy 219.174511 -26.671323) (xy 219.124911 -26.645822) (xy 219.079553 -26.613371) (xy 219.039404 -26.574662)
			(xy 219.005318 -26.530519) (xy 218.978022 -26.481884) (xy 218.958099 -26.429793) (xy 218.945973 -26.375356)
			(xy 218.941902 -26.319734) (xy 213.950629 -26.319734) (xy 213.952581 -26.332996) (xy 213.95309 -26.360882)
			(xy 213.952581 -26.388768) (xy 213.944461 -26.443944) (xy 213.928393 -26.497351) (xy 213.904721 -26.547848)
			(xy 213.873948 -26.594361) (xy 213.836731 -26.635898) (xy 213.793863 -26.671573) (xy 213.746257 -26.700627)
			(xy 213.694928 -26.722439) (xy 213.640971 -26.736545) (xy 213.585534 -26.742645) (xy 213.5298 -26.740608)
			(xy 213.474957 -26.730478) (xy 213.422173 -26.712471) (xy 213.372573 -26.68697) (xy 213.327215 -26.654519)
			(xy 213.287066 -26.61581) (xy 213.25298 -26.571667) (xy 213.225684 -26.523032) (xy 213.205761 -26.470941)
			(xy 213.193635 -26.416504) (xy 213.189564 -26.360882) (xy 211.52326 -26.360882) (xy 211.53101 -26.389806)
			(xy 211.538838 -26.449262) (xy 211.539328 -26.479246) (xy 211.539328 -26.971244) (xy 214.951054 -26.971244)
			(xy 214.955125 -26.915622) (xy 214.967251 -26.861185) (xy 214.987174 -26.809094) (xy 215.01447 -26.760459)
			(xy 215.048556 -26.716316) (xy 215.088705 -26.677607) (xy 215.134063 -26.645156) (xy 215.183663 -26.619655)
			(xy 215.236447 -26.601648) (xy 215.29129 -26.591518) (xy 215.347024 -26.589481) (xy 215.402461 -26.595581)
			(xy 215.456418 -26.609687) (xy 215.507747 -26.631499) (xy 215.555353 -26.660553) (xy 215.598221 -26.696228)
			(xy 215.635438 -26.737765) (xy 215.666211 -26.784278) (xy 215.689883 -26.834775) (xy 215.705951 -26.888182)
			(xy 215.714071 -26.943358) (xy 215.71458 -26.971244) (xy 215.714071 -26.99913) (xy 215.705951 -27.054306)
			(xy 215.689883 -27.107713) (xy 215.666211 -27.15821) (xy 215.635438 -27.204723) (xy 215.598221 -27.24626)
			(xy 215.555353 -27.281935) (xy 215.507747 -27.310989) (xy 215.456418 -27.332801) (xy 215.402461 -27.346907)
			(xy 215.347024 -27.353007) (xy 215.29129 -27.35097) (xy 215.236447 -27.34084) (xy 215.183663 -27.322833)
			(xy 215.134063 -27.297332) (xy 215.088705 -27.264881) (xy 215.048556 -27.226172) (xy 215.01447 -27.182029)
			(xy 214.987174 -27.133394) (xy 214.967251 -27.081303) (xy 214.955125 -27.026866) (xy 214.951054 -26.971244)
			(xy 211.539328 -26.971244) (xy 211.539328 -27.342846) (xy 211.538838 -27.37283) (xy 211.53101 -27.432286)
			(xy 211.515489 -27.490211) (xy 211.49254 -27.545615) (xy 211.462556 -27.597549) (xy 211.42605 -27.645125)
			(xy 211.383645 -27.68753) (xy 211.336069 -27.724036) (xy 211.284135 -27.75402) (xy 211.228731 -27.776969)
			(xy 211.170806 -27.79249) (xy 211.11135 -27.800318) (xy 211.051382 -27.800318) (xy 210.991926 -27.79249)
			(xy 210.934001 -27.776969) (xy 210.878597 -27.75402) (xy 210.826663 -27.724036) (xy 210.779087 -27.68753)
			(xy 210.736682 -27.645125) (xy 210.700176 -27.597549) (xy 210.670192 -27.545615) (xy 210.647243 -27.490211)
			(xy 210.631722 -27.432286) (xy 210.623894 -27.37283) (xy 210.623404 -27.342846) (xy 203.30543 -27.342846)
			(xy 203.271441 -27.372297) (xy 203.225591 -27.401763) (xy 203.176014 -27.424405) (xy 203.123719 -27.43976)
			(xy 203.069771 -27.447516) (xy 203.015269 -27.447516) (xy 202.961321 -27.43976) (xy 202.909026 -27.424405)
			(xy 202.859449 -27.401763) (xy 202.813599 -27.372297) (xy 202.772408 -27.336606) (xy 202.736717 -27.295415)
			(xy 202.707251 -27.249565) (xy 202.684609 -27.199988) (xy 202.669254 -27.147693) (xy 202.661498 -27.093745)
			(xy 202.661012 -27.066494) (xy 202.66155 -27.037006) (xy 202.670647 -26.978734) (xy 202.688608 -26.922559)
			(xy 202.715004 -26.869818) (xy 202.749205 -26.821771) (xy 202.790397 -26.779562) (xy 202.813666 -26.76144)
			(xy 202.824723 -26.75247) (xy 202.841898 -26.729783) (xy 202.852145 -26.703238) (xy 202.854668 -26.674896)
			(xy 202.849272 -26.646957) (xy 202.836376 -26.621593) (xy 202.81698 -26.600773) (xy 202.80503 -26.593038)
			(xy 202.781295 -26.578131) (xy 202.738058 -26.542467) (xy 202.700505 -26.50086) (xy 202.669445 -26.454206)
			(xy 202.645545 -26.40351) (xy 202.62932 -26.349862) (xy 202.62112 -26.294418) (xy 202.620626 -26.266394)
			(xy 200.052823 -26.266394) (xy 200.052284 -26.267209) (xy 200.015067 -26.308746) (xy 199.972199 -26.344421)
			(xy 199.924593 -26.373475) (xy 199.873264 -26.395287) (xy 199.819307 -26.409393) (xy 199.76387 -26.415493)
			(xy 199.708136 -26.413456) (xy 199.653293 -26.403326) (xy 199.600509 -26.385319) (xy 199.550909 -26.359818)
			(xy 199.505551 -26.327367) (xy 199.465402 -26.288658) (xy 199.431316 -26.244515) (xy 199.40402 -26.19588)
			(xy 199.384097 -26.143789) (xy 199.371971 -26.089352) (xy 199.3679 -26.03373) (xy 193.575918 -26.03373)
			(xy 193.589121 -26.044718) (xy 193.626338 -26.086255) (xy 193.657111 -26.132768) (xy 193.680783 -26.183265)
			(xy 193.696851 -26.236672) (xy 193.704971 -26.291848) (xy 193.70548 -26.319734) (xy 193.704971 -26.34762)
			(xy 193.696851 -26.402796) (xy 193.680783 -26.456203) (xy 193.657111 -26.5067) (xy 193.626338 -26.553213)
			(xy 193.589121 -26.59475) (xy 193.546253 -26.630425) (xy 193.498647 -26.659479) (xy 193.447318 -26.681291)
			(xy 193.393361 -26.695397) (xy 193.337924 -26.701497) (xy 193.28219 -26.69946) (xy 193.227347 -26.68933)
			(xy 193.174563 -26.671323) (xy 193.124963 -26.645822) (xy 193.079605 -26.613371) (xy 193.039456 -26.574662)
			(xy 193.00537 -26.530519) (xy 192.978074 -26.481884) (xy 192.958151 -26.429793) (xy 192.946025 -26.375356)
			(xy 192.941954 -26.319734) (xy 187.950681 -26.319734) (xy 187.952633 -26.332996) (xy 187.953142 -26.360882)
			(xy 187.952633 -26.388768) (xy 187.944513 -26.443944) (xy 187.928445 -26.497351) (xy 187.904773 -26.547848)
			(xy 187.874 -26.594361) (xy 187.836783 -26.635898) (xy 187.793915 -26.671573) (xy 187.746309 -26.700627)
			(xy 187.69498 -26.722439) (xy 187.641023 -26.736545) (xy 187.585586 -26.742645) (xy 187.529852 -26.740608)
			(xy 187.475009 -26.730478) (xy 187.422225 -26.712471) (xy 187.372625 -26.68697) (xy 187.327267 -26.654519)
			(xy 187.287118 -26.61581) (xy 187.253032 -26.571667) (xy 187.225736 -26.523032) (xy 187.205813 -26.470941)
			(xy 187.193687 -26.416504) (xy 187.189616 -26.360882) (xy 185.523312 -26.360882) (xy 185.531062 -26.389806)
			(xy 185.53889 -26.449262) (xy 185.53938 -26.479246) (xy 185.53938 -26.971244) (xy 188.951106 -26.971244)
			(xy 188.955177 -26.915622) (xy 188.967303 -26.861185) (xy 188.987226 -26.809094) (xy 189.014522 -26.760459)
			(xy 189.048608 -26.716316) (xy 189.088757 -26.677607) (xy 189.134115 -26.645156) (xy 189.183715 -26.619655)
			(xy 189.236499 -26.601648) (xy 189.291342 -26.591518) (xy 189.347076 -26.589481) (xy 189.402513 -26.595581)
			(xy 189.45647 -26.609687) (xy 189.507799 -26.631499) (xy 189.555405 -26.660553) (xy 189.598273 -26.696228)
			(xy 189.63549 -26.737765) (xy 189.666263 -26.784278) (xy 189.689935 -26.834775) (xy 189.706003 -26.888182)
			(xy 189.714123 -26.943358) (xy 189.714632 -26.971244) (xy 189.714123 -26.99913) (xy 189.706003 -27.054306)
			(xy 189.689935 -27.107713) (xy 189.666263 -27.15821) (xy 189.63549 -27.204723) (xy 189.598273 -27.24626)
			(xy 189.555405 -27.281935) (xy 189.507799 -27.310989) (xy 189.45647 -27.332801) (xy 189.402513 -27.346907)
			(xy 189.347076 -27.353007) (xy 189.291342 -27.35097) (xy 189.236499 -27.34084) (xy 189.183715 -27.322833)
			(xy 189.134115 -27.297332) (xy 189.088757 -27.264881) (xy 189.048608 -27.226172) (xy 189.014522 -27.182029)
			(xy 188.987226 -27.133394) (xy 188.967303 -27.081303) (xy 188.955177 -27.026866) (xy 188.951106 -26.971244)
			(xy 185.53938 -26.971244) (xy 185.53938 -27.342846) (xy 185.53889 -27.37283) (xy 185.531062 -27.432286)
			(xy 185.515541 -27.490211) (xy 185.492592 -27.545615) (xy 185.462608 -27.597549) (xy 185.426102 -27.645125)
			(xy 185.383697 -27.68753) (xy 185.336121 -27.724036) (xy 185.284187 -27.75402) (xy 185.228783 -27.776969)
			(xy 185.170858 -27.79249) (xy 185.111402 -27.800318) (xy 185.051434 -27.800318) (xy 184.991978 -27.79249)
			(xy 184.934053 -27.776969) (xy 184.878649 -27.75402) (xy 184.826715 -27.724036) (xy 184.779139 -27.68753)
			(xy 184.736734 -27.645125) (xy 184.700228 -27.597549) (xy 184.670244 -27.545615) (xy 184.647295 -27.490211)
			(xy 184.631774 -27.432286) (xy 184.623946 -27.37283) (xy 184.623456 -27.342846) (xy 177.305482 -27.342846)
			(xy 177.271493 -27.372297) (xy 177.225643 -27.401763) (xy 177.176066 -27.424405) (xy 177.123771 -27.43976)
			(xy 177.069823 -27.447516) (xy 177.015321 -27.447516) (xy 176.961373 -27.43976) (xy 176.909078 -27.424405)
			(xy 176.859501 -27.401763) (xy 176.813651 -27.372297) (xy 176.77246 -27.336606) (xy 176.736769 -27.295415)
			(xy 176.707303 -27.249565) (xy 176.684661 -27.199988) (xy 176.669306 -27.147693) (xy 176.66155 -27.093745)
			(xy 176.661064 -27.066494) (xy 176.661622 -27.037007) (xy 176.670717 -26.978737) (xy 176.688675 -26.922563)
			(xy 176.715067 -26.869822) (xy 176.749265 -26.821774) (xy 176.790451 -26.779564) (xy 176.813718 -26.76144)
			(xy 176.824782 -26.752475) (xy 176.841965 -26.72979) (xy 176.852218 -26.703242) (xy 176.854743 -26.674895)
			(xy 176.849344 -26.646953) (xy 176.836441 -26.621588) (xy 176.817036 -26.600771) (xy 176.805082 -26.593038)
			(xy 176.781336 -26.578148) (xy 176.738102 -26.542479) (xy 176.700551 -26.500869) (xy 176.669493 -26.454212)
			(xy 176.645595 -26.403514) (xy 176.629371 -26.349864) (xy 176.621172 -26.294418) (xy 176.620678 -26.266394)
			(xy 174.052875 -26.266394) (xy 174.052336 -26.267209) (xy 174.015119 -26.308746) (xy 173.972251 -26.344421)
			(xy 173.924645 -26.373475) (xy 173.873316 -26.395287) (xy 173.819359 -26.409393) (xy 173.763922 -26.415493)
			(xy 173.708188 -26.413456) (xy 173.653345 -26.403326) (xy 173.600561 -26.385319) (xy 173.550961 -26.359818)
			(xy 173.505603 -26.327367) (xy 173.465454 -26.288658) (xy 173.431368 -26.244515) (xy 173.404072 -26.19588)
			(xy 173.384149 -26.143789) (xy 173.372023 -26.089352) (xy 173.367952 -26.03373) (xy 167.57597 -26.03373)
			(xy 167.589173 -26.044718) (xy 167.62639 -26.086255) (xy 167.657163 -26.132768) (xy 167.680835 -26.183265)
			(xy 167.696903 -26.236672) (xy 167.705023 -26.291848) (xy 167.705532 -26.319734) (xy 167.705023 -26.34762)
			(xy 167.696903 -26.402796) (xy 167.680835 -26.456203) (xy 167.657163 -26.5067) (xy 167.62639 -26.553213)
			(xy 167.589173 -26.59475) (xy 167.546305 -26.630425) (xy 167.498699 -26.659479) (xy 167.44737 -26.681291)
			(xy 167.393413 -26.695397) (xy 167.337976 -26.701497) (xy 167.282242 -26.69946) (xy 167.227399 -26.68933)
			(xy 167.174615 -26.671323) (xy 167.125015 -26.645822) (xy 167.079657 -26.613371) (xy 167.039508 -26.574662)
			(xy 167.005422 -26.530519) (xy 166.978126 -26.481884) (xy 166.958203 -26.429793) (xy 166.946077 -26.375356)
			(xy 166.942006 -26.319734) (xy 161.950733 -26.319734) (xy 161.952685 -26.332996) (xy 161.953194 -26.360882)
			(xy 161.952685 -26.388768) (xy 161.944565 -26.443944) (xy 161.928497 -26.497351) (xy 161.904825 -26.547848)
			(xy 161.874052 -26.594361) (xy 161.836835 -26.635898) (xy 161.793967 -26.671573) (xy 161.746361 -26.700627)
			(xy 161.695032 -26.722439) (xy 161.641075 -26.736545) (xy 161.585638 -26.742645) (xy 161.529904 -26.740608)
			(xy 161.475061 -26.730478) (xy 161.422277 -26.712471) (xy 161.372677 -26.68697) (xy 161.327319 -26.654519)
			(xy 161.28717 -26.61581) (xy 161.253084 -26.571667) (xy 161.225788 -26.523032) (xy 161.205865 -26.470941)
			(xy 161.193739 -26.416504) (xy 161.189668 -26.360882) (xy 159.523364 -26.360882) (xy 159.531114 -26.389806)
			(xy 159.538942 -26.449262) (xy 159.539432 -26.479246) (xy 159.539432 -26.971244) (xy 162.951158 -26.971244)
			(xy 162.955229 -26.915622) (xy 162.967355 -26.861185) (xy 162.987278 -26.809094) (xy 163.014574 -26.760459)
			(xy 163.04866 -26.716316) (xy 163.088809 -26.677607) (xy 163.134167 -26.645156) (xy 163.183767 -26.619655)
			(xy 163.236551 -26.601648) (xy 163.291394 -26.591518) (xy 163.347128 -26.589481) (xy 163.402565 -26.595581)
			(xy 163.456522 -26.609687) (xy 163.507851 -26.631499) (xy 163.555457 -26.660553) (xy 163.598325 -26.696228)
			(xy 163.635542 -26.737765) (xy 163.666315 -26.784278) (xy 163.689987 -26.834775) (xy 163.706055 -26.888182)
			(xy 163.714175 -26.943358) (xy 163.714684 -26.971244) (xy 163.714175 -26.99913) (xy 163.706055 -27.054306)
			(xy 163.689987 -27.107713) (xy 163.666315 -27.15821) (xy 163.635542 -27.204723) (xy 163.598325 -27.24626)
			(xy 163.555457 -27.281935) (xy 163.507851 -27.310989) (xy 163.456522 -27.332801) (xy 163.402565 -27.346907)
			(xy 163.347128 -27.353007) (xy 163.291394 -27.35097) (xy 163.236551 -27.34084) (xy 163.183767 -27.322833)
			(xy 163.134167 -27.297332) (xy 163.088809 -27.264881) (xy 163.04866 -27.226172) (xy 163.014574 -27.182029)
			(xy 162.987278 -27.133394) (xy 162.967355 -27.081303) (xy 162.955229 -27.026866) (xy 162.951158 -26.971244)
			(xy 159.539432 -26.971244) (xy 159.539432 -27.342846) (xy 159.538942 -27.37283) (xy 159.531114 -27.432286)
			(xy 159.515593 -27.490211) (xy 159.492644 -27.545615) (xy 159.46266 -27.597549) (xy 159.426154 -27.645125)
			(xy 159.383749 -27.68753) (xy 159.336173 -27.724036) (xy 159.284239 -27.75402) (xy 159.228835 -27.776969)
			(xy 159.17091 -27.79249) (xy 159.111454 -27.800318) (xy 159.051486 -27.800318) (xy 158.99203 -27.79249)
			(xy 158.934105 -27.776969) (xy 158.878701 -27.75402) (xy 158.826767 -27.724036) (xy 158.779191 -27.68753)
			(xy 158.736786 -27.645125) (xy 158.70028 -27.597549) (xy 158.670296 -27.545615) (xy 158.647347 -27.490211)
			(xy 158.631826 -27.432286) (xy 158.623998 -27.37283) (xy 158.623508 -27.342846) (xy 151.305534 -27.342846)
			(xy 151.271545 -27.372297) (xy 151.225695 -27.401763) (xy 151.176118 -27.424405) (xy 151.123823 -27.43976)
			(xy 151.069875 -27.447516) (xy 151.015373 -27.447516) (xy 150.961425 -27.43976) (xy 150.90913 -27.424405)
			(xy 150.859553 -27.401763) (xy 150.813703 -27.372297) (xy 150.772512 -27.336606) (xy 150.736821 -27.295415)
			(xy 150.707355 -27.249565) (xy 150.684713 -27.199988) (xy 150.669358 -27.147693) (xy 150.661602 -27.093745)
			(xy 150.661116 -27.066494) (xy 150.661653 -27.037006) (xy 150.67075 -26.978734) (xy 150.688711 -26.922558)
			(xy 150.715107 -26.869818) (xy 150.749308 -26.82177) (xy 150.7905 -26.779562) (xy 150.81377 -26.76144)
			(xy 150.824826 -26.752469) (xy 150.842 -26.729783) (xy 150.852247 -26.703238) (xy 150.85477 -26.674896)
			(xy 150.849375 -26.646958) (xy 150.836478 -26.621594) (xy 150.817084 -26.600774) (xy 150.805134 -26.593038)
			(xy 150.7814 -26.578129) (xy 150.738163 -26.542466) (xy 150.70061 -26.500859) (xy 150.669549 -26.454206)
			(xy 150.645649 -26.40351) (xy 150.629424 -26.349862) (xy 150.621224 -26.294418) (xy 150.62073 -26.266394)
			(xy 148.052927 -26.266394) (xy 148.052388 -26.267209) (xy 148.015171 -26.308746) (xy 147.972303 -26.344421)
			(xy 147.924697 -26.373475) (xy 147.873368 -26.395287) (xy 147.819411 -26.409393) (xy 147.763974 -26.415493)
			(xy 147.70824 -26.413456) (xy 147.653397 -26.403326) (xy 147.600613 -26.385319) (xy 147.551013 -26.359818)
			(xy 147.505655 -26.327367) (xy 147.465506 -26.288658) (xy 147.43142 -26.244515) (xy 147.404124 -26.19588)
			(xy 147.384201 -26.143789) (xy 147.372075 -26.089352) (xy 147.368004 -26.03373) (xy 141.576022 -26.03373)
			(xy 141.589225 -26.044718) (xy 141.626442 -26.086255) (xy 141.657215 -26.132768) (xy 141.680887 -26.183265)
			(xy 141.696955 -26.236672) (xy 141.705075 -26.291848) (xy 141.705584 -26.319734) (xy 141.705075 -26.34762)
			(xy 141.696955 -26.402796) (xy 141.680887 -26.456203) (xy 141.657215 -26.5067) (xy 141.626442 -26.553213)
			(xy 141.589225 -26.59475) (xy 141.546357 -26.630425) (xy 141.498751 -26.659479) (xy 141.447422 -26.681291)
			(xy 141.393465 -26.695397) (xy 141.338028 -26.701497) (xy 141.282294 -26.69946) (xy 141.227451 -26.68933)
			(xy 141.174667 -26.671323) (xy 141.125067 -26.645822) (xy 141.079709 -26.613371) (xy 141.03956 -26.574662)
			(xy 141.005474 -26.530519) (xy 140.978178 -26.481884) (xy 140.958255 -26.429793) (xy 140.946129 -26.375356)
			(xy 140.942058 -26.319734) (xy 135.950785 -26.319734) (xy 135.952737 -26.332996) (xy 135.953246 -26.360882)
			(xy 135.952737 -26.388768) (xy 135.944617 -26.443944) (xy 135.928549 -26.497351) (xy 135.904877 -26.547848)
			(xy 135.874104 -26.594361) (xy 135.836887 -26.635898) (xy 135.794019 -26.671573) (xy 135.746413 -26.700627)
			(xy 135.695084 -26.722439) (xy 135.641127 -26.736545) (xy 135.58569 -26.742645) (xy 135.529956 -26.740608)
			(xy 135.475113 -26.730478) (xy 135.422329 -26.712471) (xy 135.372729 -26.68697) (xy 135.327371 -26.654519)
			(xy 135.287222 -26.61581) (xy 135.253136 -26.571667) (xy 135.22584 -26.523032) (xy 135.205917 -26.470941)
			(xy 135.193791 -26.416504) (xy 135.18972 -26.360882) (xy 133.523416 -26.360882) (xy 133.531166 -26.389806)
			(xy 133.538994 -26.449262) (xy 133.539484 -26.479246) (xy 133.539484 -26.971244) (xy 136.95121 -26.971244)
			(xy 136.955281 -26.915622) (xy 136.967407 -26.861185) (xy 136.98733 -26.809094) (xy 137.014626 -26.760459)
			(xy 137.048712 -26.716316) (xy 137.088861 -26.677607) (xy 137.134219 -26.645156) (xy 137.183819 -26.619655)
			(xy 137.236603 -26.601648) (xy 137.291446 -26.591518) (xy 137.34718 -26.589481) (xy 137.402617 -26.595581)
			(xy 137.456574 -26.609687) (xy 137.507903 -26.631499) (xy 137.555509 -26.660553) (xy 137.598377 -26.696228)
			(xy 137.635594 -26.737765) (xy 137.666367 -26.784278) (xy 137.690039 -26.834775) (xy 137.706107 -26.888182)
			(xy 137.714227 -26.943358) (xy 137.714736 -26.971244) (xy 137.714227 -26.99913) (xy 137.706107 -27.054306)
			(xy 137.690039 -27.107713) (xy 137.666367 -27.15821) (xy 137.635594 -27.204723) (xy 137.598377 -27.24626)
			(xy 137.555509 -27.281935) (xy 137.507903 -27.310989) (xy 137.456574 -27.332801) (xy 137.402617 -27.346907)
			(xy 137.34718 -27.353007) (xy 137.291446 -27.35097) (xy 137.236603 -27.34084) (xy 137.183819 -27.322833)
			(xy 137.134219 -27.297332) (xy 137.088861 -27.264881) (xy 137.048712 -27.226172) (xy 137.014626 -27.182029)
			(xy 136.98733 -27.133394) (xy 136.967407 -27.081303) (xy 136.955281 -27.026866) (xy 136.95121 -26.971244)
			(xy 133.539484 -26.971244) (xy 133.539484 -27.342846) (xy 133.538994 -27.37283) (xy 133.531166 -27.432286)
			(xy 133.515645 -27.490211) (xy 133.492696 -27.545615) (xy 133.462712 -27.597549) (xy 133.426206 -27.645125)
			(xy 133.383801 -27.68753) (xy 133.336225 -27.724036) (xy 133.284291 -27.75402) (xy 133.228887 -27.776969)
			(xy 133.170962 -27.79249) (xy 133.111506 -27.800318) (xy 133.051538 -27.800318) (xy 132.992082 -27.79249)
			(xy 132.934157 -27.776969) (xy 132.878753 -27.75402) (xy 132.826819 -27.724036) (xy 132.779243 -27.68753)
			(xy 132.736838 -27.645125) (xy 132.700332 -27.597549) (xy 132.670348 -27.545615) (xy 132.647399 -27.490211)
			(xy 132.631878 -27.432286) (xy 132.62405 -27.37283) (xy 132.62356 -27.342846) (xy 125.305586 -27.342846)
			(xy 125.271597 -27.372297) (xy 125.225747 -27.401763) (xy 125.17617 -27.424405) (xy 125.123875 -27.43976)
			(xy 125.069927 -27.447516) (xy 125.015425 -27.447516) (xy 124.961477 -27.43976) (xy 124.909182 -27.424405)
			(xy 124.859605 -27.401763) (xy 124.813755 -27.372297) (xy 124.772564 -27.336606) (xy 124.736873 -27.295415)
			(xy 124.707407 -27.249565) (xy 124.684765 -27.199988) (xy 124.66941 -27.147693) (xy 124.661654 -27.093745)
			(xy 124.661168 -27.066494) (xy 124.661724 -27.037007) (xy 124.67082 -26.978737) (xy 124.688778 -26.922562)
			(xy 124.71517 -26.869822) (xy 124.749368 -26.821774) (xy 124.790555 -26.779564) (xy 124.813822 -26.76144)
			(xy 124.824885 -26.752475) (xy 124.842068 -26.729789) (xy 124.85232 -26.703242) (xy 124.854845 -26.674895)
			(xy 124.849447 -26.646954) (xy 124.836544 -26.621588) (xy 124.81714 -26.600771) (xy 124.805186 -26.593038)
			(xy 124.781441 -26.578146) (xy 124.738206 -26.542478) (xy 124.700656 -26.500868) (xy 124.669597 -26.454212)
			(xy 124.645699 -26.403513) (xy 124.629475 -26.349864) (xy 124.621276 -26.294418) (xy 124.620782 -26.266394)
			(xy 122.052979 -26.266394) (xy 122.05244 -26.267209) (xy 122.015223 -26.308746) (xy 121.972355 -26.344421)
			(xy 121.924749 -26.373475) (xy 121.87342 -26.395287) (xy 121.819463 -26.409393) (xy 121.764026 -26.415493)
			(xy 121.708292 -26.413456) (xy 121.653449 -26.403326) (xy 121.600665 -26.385319) (xy 121.551065 -26.359818)
			(xy 121.505707 -26.327367) (xy 121.465558 -26.288658) (xy 121.431472 -26.244515) (xy 121.404176 -26.19588)
			(xy 121.384253 -26.143789) (xy 121.372127 -26.089352) (xy 121.368056 -26.03373) (xy 103.475768 -26.03373)
			(xy 103.488971 -26.044718) (xy 103.526188 -26.086255) (xy 103.556961 -26.132768) (xy 103.580633 -26.183265)
			(xy 103.596701 -26.236672) (xy 103.604821 -26.291848) (xy 103.60533 -26.319734) (xy 103.604821 -26.34762)
			(xy 103.596701 -26.402796) (xy 103.580633 -26.456203) (xy 103.556961 -26.5067) (xy 103.526188 -26.553213)
			(xy 103.488971 -26.59475) (xy 103.446103 -26.630425) (xy 103.398497 -26.659479) (xy 103.347168 -26.681291)
			(xy 103.293211 -26.695397) (xy 103.237774 -26.701497) (xy 103.18204 -26.69946) (xy 103.127197 -26.68933)
			(xy 103.074413 -26.671323) (xy 103.024813 -26.645822) (xy 102.979455 -26.613371) (xy 102.939306 -26.574662)
			(xy 102.90522 -26.530519) (xy 102.877924 -26.481884) (xy 102.858001 -26.429793) (xy 102.845875 -26.375356)
			(xy 102.841804 -26.319734) (xy 97.850531 -26.319734) (xy 97.852483 -26.332996) (xy 97.852992 -26.360882)
			(xy 97.852483 -26.388768) (xy 97.844363 -26.443944) (xy 97.828295 -26.497351) (xy 97.804623 -26.547848)
			(xy 97.77385 -26.594361) (xy 97.736633 -26.635898) (xy 97.693765 -26.671573) (xy 97.646159 -26.700627)
			(xy 97.59483 -26.722439) (xy 97.540873 -26.736545) (xy 97.485436 -26.742645) (xy 97.429702 -26.740608)
			(xy 97.374859 -26.730478) (xy 97.322075 -26.712471) (xy 97.272475 -26.68697) (xy 97.227117 -26.654519)
			(xy 97.186968 -26.61581) (xy 97.152882 -26.571667) (xy 97.125586 -26.523032) (xy 97.105663 -26.470941)
			(xy 97.093537 -26.416504) (xy 97.089466 -26.360882) (xy 95.422899 -26.360882) (xy 95.430663 -26.389856)
			(xy 95.438486 -26.449278) (xy 95.438976 -26.479246) (xy 95.438976 -26.971244) (xy 98.850956 -26.971244)
			(xy 98.855027 -26.915622) (xy 98.867153 -26.861185) (xy 98.887076 -26.809094) (xy 98.914372 -26.760459)
			(xy 98.948458 -26.716316) (xy 98.988607 -26.677607) (xy 99.033965 -26.645156) (xy 99.083565 -26.619655)
			(xy 99.136349 -26.601648) (xy 99.191192 -26.591518) (xy 99.246926 -26.589481) (xy 99.302363 -26.595581)
			(xy 99.35632 -26.609687) (xy 99.407649 -26.631499) (xy 99.455255 -26.660553) (xy 99.498123 -26.696228)
			(xy 99.53534 -26.737765) (xy 99.566113 -26.784278) (xy 99.589785 -26.834775) (xy 99.605853 -26.888182)
			(xy 99.613973 -26.943358) (xy 99.614482 -26.971244) (xy 99.613973 -26.99913) (xy 99.605853 -27.054306)
			(xy 99.589785 -27.107713) (xy 99.566113 -27.15821) (xy 99.53534 -27.204723) (xy 99.498123 -27.24626)
			(xy 99.455255 -27.281935) (xy 99.407649 -27.310989) (xy 99.35632 -27.332801) (xy 99.302363 -27.346907)
			(xy 99.246926 -27.353007) (xy 99.191192 -27.35097) (xy 99.136349 -27.34084) (xy 99.083565 -27.322833)
			(xy 99.033965 -27.297332) (xy 98.988607 -27.264881) (xy 98.948458 -27.226172) (xy 98.914372 -27.182029)
			(xy 98.887076 -27.133394) (xy 98.867153 -27.081303) (xy 98.855027 -27.026866) (xy 98.850956 -26.971244)
			(xy 95.438976 -26.971244) (xy 95.438976 -27.342846) (xy 95.438486 -27.372814) (xy 95.430663 -27.432236)
			(xy 95.41515 -27.490129) (xy 95.392214 -27.545502) (xy 95.362247 -27.597408) (xy 95.32576 -27.644958)
			(xy 95.28338 -27.687338) (xy 95.23583 -27.723825) (xy 95.183924 -27.753792) (xy 95.128551 -27.776728)
			(xy 95.070658 -27.792241) (xy 95.011236 -27.800064) (xy 94.9513 -27.800064) (xy 94.891878 -27.792241)
			(xy 94.833985 -27.776728) (xy 94.778612 -27.753792) (xy 94.726706 -27.723825) (xy 94.679156 -27.687338)
			(xy 94.636776 -27.644958) (xy 94.600289 -27.597408) (xy 94.570322 -27.545502) (xy 94.547386 -27.490129)
			(xy 94.531873 -27.432236) (xy 94.52405 -27.372814) (xy 94.52356 -27.342846) (xy 87.205332 -27.342846)
			(xy 87.171343 -27.372297) (xy 87.125493 -27.401763) (xy 87.075916 -27.424405) (xy 87.023621 -27.43976)
			(xy 86.969673 -27.447516) (xy 86.915171 -27.447516) (xy 86.861223 -27.43976) (xy 86.808928 -27.424405)
			(xy 86.759351 -27.401763) (xy 86.713501 -27.372297) (xy 86.67231 -27.336606) (xy 86.636619 -27.295415)
			(xy 86.607153 -27.249565) (xy 86.584511 -27.199988) (xy 86.569156 -27.147693) (xy 86.5614 -27.093745)
			(xy 86.560914 -27.066494) (xy 86.561452 -27.037006) (xy 86.570549 -26.978734) (xy 86.588509 -26.922558)
			(xy 86.614905 -26.869818) (xy 86.649107 -26.82177) (xy 86.690299 -26.779562) (xy 86.713568 -26.76144)
			(xy 86.724624 -26.75247) (xy 86.741799 -26.729783) (xy 86.752046 -26.703238) (xy 86.754569 -26.674896)
			(xy 86.749173 -26.646958) (xy 86.736277 -26.621594) (xy 86.716882 -26.600773) (xy 86.704932 -26.593038)
			(xy 86.681197 -26.57813) (xy 86.637961 -26.542466) (xy 86.600408 -26.50086) (xy 86.569347 -26.454206)
			(xy 86.545447 -26.40351) (xy 86.529222 -26.349862) (xy 86.521022 -26.294418) (xy 86.520528 -26.266394)
			(xy 83.952725 -26.266394) (xy 83.952186 -26.267209) (xy 83.914969 -26.308746) (xy 83.872101 -26.344421)
			(xy 83.824495 -26.373475) (xy 83.773166 -26.395287) (xy 83.719209 -26.409393) (xy 83.663772 -26.415493)
			(xy 83.608038 -26.413456) (xy 83.553195 -26.403326) (xy 83.500411 -26.385319) (xy 83.450811 -26.359818)
			(xy 83.405453 -26.327367) (xy 83.365304 -26.288658) (xy 83.331218 -26.244515) (xy 83.303922 -26.19588)
			(xy 83.283999 -26.143789) (xy 83.271873 -26.089352) (xy 83.267802 -26.03373) (xy 77.47582 -26.03373)
			(xy 77.489023 -26.044718) (xy 77.52624 -26.086255) (xy 77.557013 -26.132768) (xy 77.580685 -26.183265)
			(xy 77.596753 -26.236672) (xy 77.604873 -26.291848) (xy 77.605382 -26.319734) (xy 77.604873 -26.34762)
			(xy 77.596753 -26.402796) (xy 77.580685 -26.456203) (xy 77.557013 -26.5067) (xy 77.52624 -26.553213)
			(xy 77.489023 -26.59475) (xy 77.446155 -26.630425) (xy 77.398549 -26.659479) (xy 77.34722 -26.681291)
			(xy 77.293263 -26.695397) (xy 77.237826 -26.701497) (xy 77.182092 -26.69946) (xy 77.127249 -26.68933)
			(xy 77.074465 -26.671323) (xy 77.024865 -26.645822) (xy 76.979507 -26.613371) (xy 76.939358 -26.574662)
			(xy 76.905272 -26.530519) (xy 76.877976 -26.481884) (xy 76.858053 -26.429793) (xy 76.845927 -26.375356)
			(xy 76.841856 -26.319734) (xy 71.850583 -26.319734) (xy 71.852535 -26.332996) (xy 71.853044 -26.360882)
			(xy 71.852535 -26.388768) (xy 71.844415 -26.443944) (xy 71.828347 -26.497351) (xy 71.804675 -26.547848)
			(xy 71.773902 -26.594361) (xy 71.736685 -26.635898) (xy 71.693817 -26.671573) (xy 71.646211 -26.700627)
			(xy 71.594882 -26.722439) (xy 71.540925 -26.736545) (xy 71.485488 -26.742645) (xy 71.429754 -26.740608)
			(xy 71.374911 -26.730478) (xy 71.322127 -26.712471) (xy 71.272527 -26.68697) (xy 71.227169 -26.654519)
			(xy 71.18702 -26.61581) (xy 71.152934 -26.571667) (xy 71.125638 -26.523032) (xy 71.105715 -26.470941)
			(xy 71.093589 -26.416504) (xy 71.089518 -26.360882) (xy 69.422951 -26.360882) (xy 69.430715 -26.389856)
			(xy 69.438538 -26.449278) (xy 69.439028 -26.479246) (xy 69.439028 -26.971244) (xy 72.851008 -26.971244)
			(xy 72.855079 -26.915622) (xy 72.867205 -26.861185) (xy 72.887128 -26.809094) (xy 72.914424 -26.760459)
			(xy 72.94851 -26.716316) (xy 72.988659 -26.677607) (xy 73.034017 -26.645156) (xy 73.083617 -26.619655)
			(xy 73.136401 -26.601648) (xy 73.191244 -26.591518) (xy 73.246978 -26.589481) (xy 73.302415 -26.595581)
			(xy 73.356372 -26.609687) (xy 73.407701 -26.631499) (xy 73.455307 -26.660553) (xy 73.498175 -26.696228)
			(xy 73.535392 -26.737765) (xy 73.566165 -26.784278) (xy 73.589837 -26.834775) (xy 73.605905 -26.888182)
			(xy 73.614025 -26.943358) (xy 73.614534 -26.971244) (xy 73.614025 -26.99913) (xy 73.605905 -27.054306)
			(xy 73.589837 -27.107713) (xy 73.566165 -27.15821) (xy 73.535392 -27.204723) (xy 73.498175 -27.24626)
			(xy 73.455307 -27.281935) (xy 73.407701 -27.310989) (xy 73.356372 -27.332801) (xy 73.302415 -27.346907)
			(xy 73.246978 -27.353007) (xy 73.191244 -27.35097) (xy 73.136401 -27.34084) (xy 73.083617 -27.322833)
			(xy 73.034017 -27.297332) (xy 72.988659 -27.264881) (xy 72.94851 -27.226172) (xy 72.914424 -27.182029)
			(xy 72.887128 -27.133394) (xy 72.867205 -27.081303) (xy 72.855079 -27.026866) (xy 72.851008 -26.971244)
			(xy 69.439028 -26.971244) (xy 69.439028 -27.342846) (xy 69.438538 -27.372814) (xy 69.430715 -27.432236)
			(xy 69.415202 -27.490129) (xy 69.392266 -27.545502) (xy 69.362299 -27.597408) (xy 69.325812 -27.644958)
			(xy 69.283432 -27.687338) (xy 69.235882 -27.723825) (xy 69.183976 -27.753792) (xy 69.128603 -27.776728)
			(xy 69.07071 -27.792241) (xy 69.011288 -27.800064) (xy 68.951352 -27.800064) (xy 68.89193 -27.792241)
			(xy 68.834037 -27.776728) (xy 68.778664 -27.753792) (xy 68.726758 -27.723825) (xy 68.679208 -27.687338)
			(xy 68.636828 -27.644958) (xy 68.600341 -27.597408) (xy 68.570374 -27.545502) (xy 68.547438 -27.490129)
			(xy 68.531925 -27.432236) (xy 68.524102 -27.372814) (xy 68.523612 -27.342846) (xy 61.205384 -27.342846)
			(xy 61.171395 -27.372297) (xy 61.125545 -27.401763) (xy 61.075968 -27.424405) (xy 61.023673 -27.43976)
			(xy 60.969725 -27.447516) (xy 60.915223 -27.447516) (xy 60.861275 -27.43976) (xy 60.80898 -27.424405)
			(xy 60.759403 -27.401763) (xy 60.713553 -27.372297) (xy 60.672362 -27.336606) (xy 60.636671 -27.295415)
			(xy 60.607205 -27.249565) (xy 60.584563 -27.199988) (xy 60.569208 -27.147693) (xy 60.561452 -27.093745)
			(xy 60.560966 -27.066494) (xy 60.561523 -27.037007) (xy 60.570618 -26.978737) (xy 60.588577 -26.922562)
			(xy 60.614969 -26.869822) (xy 60.649166 -26.821774) (xy 60.690353 -26.779564) (xy 60.71362 -26.76144)
			(xy 60.724683 -26.752475) (xy 60.741866 -26.729789) (xy 60.752119 -26.703242) (xy 60.754644 -26.674895)
			(xy 60.749245 -26.646954) (xy 60.736342 -26.621588) (xy 60.716938 -26.600771) (xy 60.704984 -26.593038)
			(xy 60.681238 -26.578147) (xy 60.638004 -26.542478) (xy 60.600453 -26.500868) (xy 60.569395 -26.454212)
			(xy 60.545497 -26.403513) (xy 60.529273 -26.349864) (xy 60.521074 -26.294418) (xy 60.52058 -26.266394)
			(xy 57.952777 -26.266394) (xy 57.952238 -26.267209) (xy 57.915021 -26.308746) (xy 57.872153 -26.344421)
			(xy 57.824547 -26.373475) (xy 57.773218 -26.395287) (xy 57.719261 -26.409393) (xy 57.663824 -26.415493)
			(xy 57.60809 -26.413456) (xy 57.553247 -26.403326) (xy 57.500463 -26.385319) (xy 57.450863 -26.359818)
			(xy 57.405505 -26.327367) (xy 57.365356 -26.288658) (xy 57.33127 -26.244515) (xy 57.303974 -26.19588)
			(xy 57.284051 -26.143789) (xy 57.271925 -26.089352) (xy 57.267854 -26.03373) (xy 51.475872 -26.03373)
			(xy 51.489075 -26.044718) (xy 51.526292 -26.086255) (xy 51.557065 -26.132768) (xy 51.580737 -26.183265)
			(xy 51.596805 -26.236672) (xy 51.604925 -26.291848) (xy 51.605434 -26.319734) (xy 51.604925 -26.34762)
			(xy 51.596805 -26.402796) (xy 51.580737 -26.456203) (xy 51.557065 -26.5067) (xy 51.526292 -26.553213)
			(xy 51.489075 -26.59475) (xy 51.446207 -26.630425) (xy 51.398601 -26.659479) (xy 51.347272 -26.681291)
			(xy 51.293315 -26.695397) (xy 51.237878 -26.701497) (xy 51.182144 -26.69946) (xy 51.127301 -26.68933)
			(xy 51.074517 -26.671323) (xy 51.024917 -26.645822) (xy 50.979559 -26.613371) (xy 50.93941 -26.574662)
			(xy 50.905324 -26.530519) (xy 50.878028 -26.481884) (xy 50.858105 -26.429793) (xy 50.845979 -26.375356)
			(xy 50.841908 -26.319734) (xy 45.850635 -26.319734) (xy 45.852587 -26.332996) (xy 45.853096 -26.360882)
			(xy 45.852587 -26.388768) (xy 45.844467 -26.443944) (xy 45.828399 -26.497351) (xy 45.804727 -26.547848)
			(xy 45.773954 -26.594361) (xy 45.736737 -26.635898) (xy 45.693869 -26.671573) (xy 45.646263 -26.700627)
			(xy 45.594934 -26.722439) (xy 45.540977 -26.736545) (xy 45.48554 -26.742645) (xy 45.429806 -26.740608)
			(xy 45.374963 -26.730478) (xy 45.322179 -26.712471) (xy 45.272579 -26.68697) (xy 45.227221 -26.654519)
			(xy 45.187072 -26.61581) (xy 45.152986 -26.571667) (xy 45.12569 -26.523032) (xy 45.105767 -26.470941)
			(xy 45.093641 -26.416504) (xy 45.08957 -26.360882) (xy 43.423003 -26.360882) (xy 43.430767 -26.389856)
			(xy 43.43859 -26.449278) (xy 43.43908 -26.479246) (xy 43.43908 -26.971244) (xy 46.85106 -26.971244)
			(xy 46.855131 -26.915622) (xy 46.867257 -26.861185) (xy 46.88718 -26.809094) (xy 46.914476 -26.760459)
			(xy 46.948562 -26.716316) (xy 46.988711 -26.677607) (xy 47.034069 -26.645156) (xy 47.083669 -26.619655)
			(xy 47.136453 -26.601648) (xy 47.191296 -26.591518) (xy 47.24703 -26.589481) (xy 47.302467 -26.595581)
			(xy 47.356424 -26.609687) (xy 47.407753 -26.631499) (xy 47.455359 -26.660553) (xy 47.498227 -26.696228)
			(xy 47.535444 -26.737765) (xy 47.566217 -26.784278) (xy 47.589889 -26.834775) (xy 47.605957 -26.888182)
			(xy 47.614077 -26.943358) (xy 47.614586 -26.971244) (xy 47.614077 -26.99913) (xy 47.605957 -27.054306)
			(xy 47.589889 -27.107713) (xy 47.566217 -27.15821) (xy 47.535444 -27.204723) (xy 47.498227 -27.24626)
			(xy 47.455359 -27.281935) (xy 47.407753 -27.310989) (xy 47.356424 -27.332801) (xy 47.302467 -27.346907)
			(xy 47.24703 -27.353007) (xy 47.191296 -27.35097) (xy 47.136453 -27.34084) (xy 47.083669 -27.322833)
			(xy 47.034069 -27.297332) (xy 46.988711 -27.264881) (xy 46.948562 -27.226172) (xy 46.914476 -27.182029)
			(xy 46.88718 -27.133394) (xy 46.867257 -27.081303) (xy 46.855131 -27.026866) (xy 46.85106 -26.971244)
			(xy 43.43908 -26.971244) (xy 43.43908 -27.342846) (xy 43.43859 -27.372814) (xy 43.430767 -27.432236)
			(xy 43.415254 -27.490129) (xy 43.392318 -27.545502) (xy 43.362351 -27.597408) (xy 43.325864 -27.644958)
			(xy 43.283484 -27.687338) (xy 43.235934 -27.723825) (xy 43.184028 -27.753792) (xy 43.128655 -27.776728)
			(xy 43.070762 -27.792241) (xy 43.01134 -27.800064) (xy 42.951404 -27.800064) (xy 42.891982 -27.792241)
			(xy 42.834089 -27.776728) (xy 42.778716 -27.753792) (xy 42.72681 -27.723825) (xy 42.67926 -27.687338)
			(xy 42.63688 -27.644958) (xy 42.600393 -27.597408) (xy 42.570426 -27.545502) (xy 42.54749 -27.490129)
			(xy 42.531977 -27.432236) (xy 42.524154 -27.372814) (xy 42.523664 -27.342846) (xy 35.205436 -27.342846)
			(xy 35.171447 -27.372297) (xy 35.125597 -27.401763) (xy 35.07602 -27.424405) (xy 35.023725 -27.43976)
			(xy 34.969777 -27.447516) (xy 34.915275 -27.447516) (xy 34.861327 -27.43976) (xy 34.809032 -27.424405)
			(xy 34.759455 -27.401763) (xy 34.713605 -27.372297) (xy 34.672414 -27.336606) (xy 34.636723 -27.295415)
			(xy 34.607257 -27.249565) (xy 34.584615 -27.199988) (xy 34.56926 -27.147693) (xy 34.561504 -27.093745)
			(xy 34.561018 -27.066494) (xy 34.561554 -27.037005) (xy 34.570651 -26.978734) (xy 34.588612 -26.922558)
			(xy 34.615008 -26.869818) (xy 34.64921 -26.82177) (xy 34.690402 -26.779562) (xy 34.713672 -26.76144)
			(xy 34.724728 -26.752469) (xy 34.741902 -26.729782) (xy 34.752148 -26.703237) (xy 34.754672 -26.674896)
			(xy 34.749276 -26.646958) (xy 34.73638 -26.621594) (xy 34.716985 -26.600774) (xy 34.705036 -26.593038)
			(xy 34.681302 -26.578128) (xy 34.638065 -26.542465) (xy 34.600512 -26.500859) (xy 34.569451 -26.454206)
			(xy 34.545551 -26.40351) (xy 34.529326 -26.349862) (xy 34.521126 -26.294418) (xy 34.520632 -26.266394)
			(xy 31.952829 -26.266394) (xy 31.95229 -26.267209) (xy 31.915073 -26.308746) (xy 31.872205 -26.344421)
			(xy 31.824599 -26.373475) (xy 31.77327 -26.395287) (xy 31.719313 -26.409393) (xy 31.663876 -26.415493)
			(xy 31.608142 -26.413456) (xy 31.553299 -26.403326) (xy 31.500515 -26.385319) (xy 31.450915 -26.359818)
			(xy 31.405557 -26.327367) (xy 31.365408 -26.288658) (xy 31.331322 -26.244515) (xy 31.304026 -26.19588)
			(xy 31.284103 -26.143789) (xy 31.271977 -26.089352) (xy 31.267906 -26.03373) (xy 19.666949 -26.03373)
			(xy 19.693921 -26.050191) (xy 19.736789 -26.085866) (xy 19.774006 -26.127403) (xy 19.804779 -26.173916)
			(xy 19.828451 -26.224413) (xy 19.844519 -26.27782) (xy 19.852639 -26.332996) (xy 19.853148 -26.360882)
			(xy 19.852639 -26.388768) (xy 19.844519 -26.443944) (xy 19.828451 -26.497351) (xy 19.804779 -26.547848)
			(xy 19.774006 -26.594361) (xy 19.736789 -26.635898) (xy 19.693921 -26.671573) (xy 19.646315 -26.700627)
			(xy 19.594986 -26.722439) (xy 19.541029 -26.736545) (xy 19.485592 -26.742645) (xy 19.429858 -26.740608)
			(xy 19.375015 -26.730478) (xy 19.322231 -26.712471) (xy 19.272631 -26.68697) (xy 19.227273 -26.654519)
			(xy 19.187124 -26.61581) (xy 19.153038 -26.571667) (xy 19.125742 -26.523032) (xy 19.105819 -26.470941)
			(xy 19.093693 -26.416504) (xy 19.089622 -26.360882) (xy 17.423055 -26.360882) (xy 17.430819 -26.389856)
			(xy 17.438642 -26.449278) (xy 17.439132 -26.479246) (xy 17.439132 -27.342846) (xy 17.438642 -27.372814)
			(xy 17.430819 -27.432236) (xy 17.415306 -27.490129) (xy 17.39237 -27.545502) (xy 17.362403 -27.597408)
			(xy 17.325916 -27.644958) (xy 17.283536 -27.687338) (xy 17.235986 -27.723825) (xy 17.18408 -27.753792)
			(xy 17.128707 -27.776728) (xy 17.070814 -27.792241) (xy 17.011392 -27.800064) (xy 16.951456 -27.800064)
			(xy 16.892034 -27.792241) (xy 16.834141 -27.776728) (xy 16.778768 -27.753792) (xy 16.726862 -27.723825)
			(xy 16.679312 -27.687338) (xy 16.636932 -27.644958) (xy 16.600445 -27.597408) (xy 16.570478 -27.545502)
			(xy 16.547542 -27.490129) (xy 16.532029 -27.432236) (xy 16.524206 -27.372814) (xy 16.523716 -27.342846)
			(xy 9.205488 -27.342846) (xy 9.171499 -27.372297) (xy 9.125649 -27.401763) (xy 9.076072 -27.424405)
			(xy 9.023777 -27.43976) (xy 8.969829 -27.447516) (xy 8.915327 -27.447516) (xy 8.861379 -27.43976)
			(xy 8.809084 -27.424405) (xy 8.759507 -27.401763) (xy 8.713657 -27.372297) (xy 8.672466 -27.336606)
			(xy 8.636775 -27.295415) (xy 8.607309 -27.249565) (xy 8.584667 -27.199988) (xy 8.569312 -27.147693)
			(xy 8.561556 -27.093745) (xy 8.56107 -27.066494) (xy 8.561625 -27.037006) (xy 8.570721 -26.978737)
			(xy 8.588679 -26.922562) (xy 8.615072 -26.869822) (xy 8.64927 -26.821774) (xy 8.690457 -26.779564)
			(xy 8.713724 -26.76144) (xy 8.724787 -26.752474) (xy 8.741969 -26.729789) (xy 8.752221 -26.703241)
			(xy 8.754746 -26.674895) (xy 8.749348 -26.646954) (xy 8.736445 -26.621589) (xy 8.717042 -26.600771)
			(xy 8.705088 -26.593038) (xy 8.681343 -26.578146) (xy 8.638109 -26.542477) (xy 8.600558 -26.500868)
			(xy 8.569499 -26.454211) (xy 8.545601 -26.403513) (xy 8.529377 -26.349864) (xy 8.521178 -26.294418)
			(xy 8.520684 -26.266394) (xy 6.002411 -26.266394) (xy 6.001872 -26.267209) (xy 5.964655 -26.308746)
			(xy 5.921787 -26.344421) (xy 5.874181 -26.373475) (xy 5.822852 -26.395287) (xy 5.768895 -26.409393)
			(xy 5.713458 -26.415493) (xy 5.657724 -26.413456) (xy 5.602881 -26.403326) (xy 5.550097 -26.385319)
			(xy 5.500497 -26.359818) (xy 5.455139 -26.327367) (xy 5.41499 -26.288658) (xy 5.380904 -26.244515)
			(xy 5.353608 -26.19588) (xy 5.333685 -26.143789) (xy 5.321559 -26.089352) (xy 5.317488 -26.03373)
			(xy 5.018509 -26.03373) (xy 5.004503 -26.080283) (xy 4.980831 -26.13078) (xy 4.950058 -26.177293)
			(xy 4.912841 -26.21883) (xy 4.869973 -26.254505) (xy 4.822367 -26.283559) (xy 4.771038 -26.305371)
			(xy 4.717081 -26.319477) (xy 4.661644 -26.325577) (xy 4.60591 -26.32354) (xy 4.551067 -26.31341)
			(xy 4.498283 -26.295403) (xy 4.448683 -26.269902) (xy 4.403325 -26.237451) (xy 4.363176 -26.198742)
			(xy 4.32909 -26.154599) (xy 4.301794 -26.105964) (xy 4.281871 -26.053873) (xy 4.269745 -25.999436)
			(xy 4.265674 -25.943814) (xy 2.402585 -25.943814) (xy 2.404883 -25.951395) (xy 2.413114 -26.00693)
			(xy 2.413114 -26.06307) (xy 2.404883 -26.118605) (xy 2.3886 -26.172332) (xy 2.364615 -26.223091)
			(xy 2.333448 -26.269786) (xy 2.295772 -26.311407) (xy 2.2524 -26.347054) (xy 2.204272 -26.375958)
			(xy 2.152426 -26.397493) (xy 2.097982 -26.411194) (xy 2.0701 -26.414476) (xy 2.069846 -26.414476)
			(xy 2.060476 -26.415802) (xy 2.043646 -26.424424) (xy 2.03708 -26.43124) (xy 2.030984 -26.438098)
			(xy 2.02438 -26.45537) (xy 2.02438 -29.330142) (xy 2.191256 -29.330142) (xy 2.195327 -29.27452) (xy 2.207453 -29.220083)
			(xy 2.227376 -29.167992) (xy 2.254672 -29.119357) (xy 2.288758 -29.075214) (xy 2.328907 -29.036505)
			(xy 2.374265 -29.004054) (xy 2.423865 -28.978553) (xy 2.476649 -28.960546) (xy 2.531492 -28.950416)
			(xy 2.587226 -28.948379) (xy 2.642663 -28.954479) (xy 2.69662 -28.968585) (xy 2.747949 -28.990397)
			(xy 2.795555 -29.019451) (xy 2.838423 -29.055126) (xy 2.87564 -29.096663) (xy 2.906413 -29.143176)
			(xy 2.930085 -29.193673) (xy 2.946153 -29.24708) (xy 2.954273 -29.302256) (xy 2.954782 -29.330142)
			(xy 2.954281 -29.357574) (xy 3.464304 -29.357574) (xy 3.468375 -29.301952) (xy 3.480501 -29.247515)
			(xy 3.500424 -29.195424) (xy 3.52772 -29.146789) (xy 3.561806 -29.102646) (xy 3.601955 -29.063937)
			(xy 3.647313 -29.031486) (xy 3.696913 -29.005985) (xy 3.749697 -28.987978) (xy 3.80454 -28.977848)
			(xy 3.860274 -28.975811) (xy 3.915711 -28.981911) (xy 3.969668 -28.996017) (xy 4.020997 -29.017829)
			(xy 4.068603 -29.046883) (xy 4.111471 -29.082558) (xy 4.147142 -29.12237) (xy 8.607044 -29.12237)
			(xy 8.607044 -28.25877) (xy 8.607534 -28.228802) (xy 8.615357 -28.16938) (xy 8.63087 -28.111487)
			(xy 8.653806 -28.056114) (xy 8.683773 -28.004208) (xy 8.72026 -27.956658) (xy 8.76264 -27.914278)
			(xy 8.81019 -27.877791) (xy 8.862096 -27.847824) (xy 8.917469 -27.824888) (xy 8.975362 -27.809375)
			(xy 9.034784 -27.801552) (xy 9.09472 -27.801552) (xy 9.154142 -27.809375) (xy 9.212035 -27.824888)
			(xy 9.267408 -27.847824) (xy 9.319314 -27.877791) (xy 9.366864 -27.914278) (xy 9.409244 -27.956658)
			(xy 9.445731 -28.004208) (xy 9.475698 -28.056114) (xy 9.498634 -28.111487) (xy 9.514147 -28.16938)
			(xy 9.52197 -28.228802) (xy 9.52246 -28.25877) (xy 9.52246 -29.114242) (xy 18.847308 -29.114242)
			(xy 18.847308 -28.250642) (xy 18.847798 -28.220658) (xy 18.855626 -28.161202) (xy 18.871147 -28.103277)
			(xy 18.894096 -28.047873) (xy 18.92408 -27.995939) (xy 18.960586 -27.948363) (xy 19.002991 -27.905958)
			(xy 19.050567 -27.869452) (xy 19.102501 -27.839468) (xy 19.157905 -27.816519) (xy 19.21583 -27.800998)
			(xy 19.275286 -27.79317) (xy 19.335254 -27.79317) (xy 19.39471 -27.800998) (xy 19.452635 -27.816519)
			(xy 19.508039 -27.839468) (xy 19.559973 -27.869452) (xy 19.607549 -27.905958) (xy 19.649954 -27.948363)
			(xy 19.68646 -27.995939) (xy 19.716444 -28.047873) (xy 19.739393 -28.103277) (xy 19.749001 -28.139136)
			(xy 28.39796 -28.139136) (xy 28.402031 -28.083514) (xy 28.414157 -28.029077) (xy 28.43408 -27.976986)
			(xy 28.461376 -27.928351) (xy 28.495462 -27.884208) (xy 28.535611 -27.845499) (xy 28.580969 -27.813048)
			(xy 28.630569 -27.787547) (xy 28.683353 -27.76954) (xy 28.738196 -27.75941) (xy 28.79393 -27.757373)
			(xy 28.849367 -27.763473) (xy 28.903324 -27.777579) (xy 28.954653 -27.799391) (xy 29.002259 -27.828445)
			(xy 29.045127 -27.86412) (xy 29.082344 -27.905657) (xy 29.113117 -27.95217) (xy 29.136789 -28.002667)
			(xy 29.152857 -28.056074) (xy 29.160977 -28.11125) (xy 29.161486 -28.139136) (xy 29.66796 -28.139136)
			(xy 29.672031 -28.083514) (xy 29.684157 -28.029077) (xy 29.70408 -27.976986) (xy 29.731376 -27.928351)
			(xy 29.765462 -27.884208) (xy 29.805611 -27.845499) (xy 29.850969 -27.813048) (xy 29.900569 -27.787547)
			(xy 29.953353 -27.76954) (xy 30.008196 -27.75941) (xy 30.06393 -27.757373) (xy 30.119367 -27.763473)
			(xy 30.173324 -27.777579) (xy 30.224653 -27.799391) (xy 30.272259 -27.828445) (xy 30.315127 -27.86412)
			(xy 30.352344 -27.905657) (xy 30.383117 -27.95217) (xy 30.406789 -28.002667) (xy 30.422857 -28.056074)
			(xy 30.430977 -28.11125) (xy 30.431486 -28.139136) (xy 30.430977 -28.167022) (xy 30.422857 -28.222198)
			(xy 30.406789 -28.275605) (xy 30.383117 -28.326102) (xy 30.352344 -28.372615) (xy 30.315127 -28.414152)
			(xy 30.272259 -28.449827) (xy 30.224653 -28.478881) (xy 30.173324 -28.500693) (xy 30.119367 -28.514799)
			(xy 30.06393 -28.520899) (xy 30.008196 -28.518862) (xy 29.953353 -28.508732) (xy 29.900569 -28.490725)
			(xy 29.850969 -28.465224) (xy 29.805611 -28.432773) (xy 29.765462 -28.394064) (xy 29.731376 -28.349921)
			(xy 29.70408 -28.301286) (xy 29.684157 -28.249195) (xy 29.672031 -28.194758) (xy 29.66796 -28.139136)
			(xy 29.161486 -28.139136) (xy 29.160977 -28.167022) (xy 29.152857 -28.222198) (xy 29.136789 -28.275605)
			(xy 29.113117 -28.326102) (xy 29.082344 -28.372615) (xy 29.045127 -28.414152) (xy 29.002259 -28.449827)
			(xy 28.954653 -28.478881) (xy 28.903324 -28.500693) (xy 28.849367 -28.514799) (xy 28.79393 -28.520899)
			(xy 28.738196 -28.518862) (xy 28.683353 -28.508732) (xy 28.630569 -28.490725) (xy 28.580969 -28.465224)
			(xy 28.535611 -28.432773) (xy 28.495462 -28.394064) (xy 28.461376 -28.349921) (xy 28.43408 -28.301286)
			(xy 28.414157 -28.249195) (xy 28.402031 -28.194758) (xy 28.39796 -28.139136) (xy 19.749001 -28.139136)
			(xy 19.754914 -28.161202) (xy 19.762742 -28.220658) (xy 19.763232 -28.250642) (xy 19.763232 -29.114242)
			(xy 19.763099 -29.12237) (xy 34.606992 -29.12237) (xy 34.606992 -28.25877) (xy 34.607482 -28.228802)
			(xy 34.615305 -28.16938) (xy 34.630818 -28.111487) (xy 34.653754 -28.056114) (xy 34.683721 -28.004208)
			(xy 34.720208 -27.956658) (xy 34.762588 -27.914278) (xy 34.810138 -27.877791) (xy 34.862044 -27.847824)
			(xy 34.917417 -27.824888) (xy 34.97531 -27.809375) (xy 35.034732 -27.801552) (xy 35.094668 -27.801552)
			(xy 35.15409 -27.809375) (xy 35.211983 -27.824888) (xy 35.267356 -27.847824) (xy 35.319262 -27.877791)
			(xy 35.366812 -27.914278) (xy 35.409192 -27.956658) (xy 35.445679 -28.004208) (xy 35.475646 -28.056114)
			(xy 35.498582 -28.111487) (xy 35.514095 -28.16938) (xy 35.521918 -28.228802) (xy 35.522408 -28.25877)
			(xy 35.522408 -29.114242) (xy 44.847256 -29.114242) (xy 44.847256 -28.250642) (xy 44.847746 -28.220658)
			(xy 44.855574 -28.161202) (xy 44.871095 -28.103277) (xy 44.894044 -28.047873) (xy 44.924028 -27.995939)
			(xy 44.960534 -27.948363) (xy 45.002939 -27.905958) (xy 45.050515 -27.869452) (xy 45.102449 -27.839468)
			(xy 45.157853 -27.816519) (xy 45.215778 -27.800998) (xy 45.275234 -27.79317) (xy 45.335202 -27.79317)
			(xy 45.394658 -27.800998) (xy 45.452583 -27.816519) (xy 45.507987 -27.839468) (xy 45.559921 -27.869452)
			(xy 45.607497 -27.905958) (xy 45.649902 -27.948363) (xy 45.686408 -27.995939) (xy 45.716392 -28.047873)
			(xy 45.739341 -28.103277) (xy 45.754862 -28.161202) (xy 45.76269 -28.220658) (xy 45.76318 -28.250642)
			(xy 45.76318 -28.469082) (xy 49.752502 -28.469082) (xy 49.756573 -28.41346) (xy 49.768699 -28.359023)
			(xy 49.788622 -28.306932) (xy 49.815918 -28.258297) (xy 49.850004 -28.214154) (xy 49.890153 -28.175445)
			(xy 49.935511 -28.142994) (xy 49.985111 -28.117493) (xy 50.037895 -28.099486) (xy 50.092738 -28.089356)
			(xy 50.148472 -28.087319) (xy 50.203909 -28.093419) (xy 50.257866 -28.107525) (xy 50.309195 -28.129337)
			(xy 50.325251 -28.139136) (xy 54.397908 -28.139136) (xy 54.401979 -28.083514) (xy 54.414105 -28.029077)
			(xy 54.434028 -27.976986) (xy 54.461324 -27.928351) (xy 54.49541 -27.884208) (xy 54.535559 -27.845499)
			(xy 54.580917 -27.813048) (xy 54.630517 -27.787547) (xy 54.683301 -27.76954) (xy 54.738144 -27.75941)
			(xy 54.793878 -27.757373) (xy 54.849315 -27.763473) (xy 54.903272 -27.777579) (xy 54.954601 -27.799391)
			(xy 55.002207 -27.828445) (xy 55.045075 -27.86412) (xy 55.082292 -27.905657) (xy 55.113065 -27.95217)
			(xy 55.136737 -28.002667) (xy 55.152805 -28.056074) (xy 55.160925 -28.11125) (xy 55.161434 -28.139136)
			(xy 55.667908 -28.139136) (xy 55.671979 -28.083514) (xy 55.684105 -28.029077) (xy 55.704028 -27.976986)
			(xy 55.731324 -27.928351) (xy 55.76541 -27.884208) (xy 55.805559 -27.845499) (xy 55.850917 -27.813048)
			(xy 55.900517 -27.787547) (xy 55.953301 -27.76954) (xy 56.008144 -27.75941) (xy 56.063878 -27.757373)
			(xy 56.119315 -27.763473) (xy 56.173272 -27.777579) (xy 56.224601 -27.799391) (xy 56.272207 -27.828445)
			(xy 56.315075 -27.86412) (xy 56.352292 -27.905657) (xy 56.383065 -27.95217) (xy 56.406737 -28.002667)
			(xy 56.422805 -28.056074) (xy 56.430925 -28.11125) (xy 56.431434 -28.139136) (xy 56.430925 -28.167022)
			(xy 56.422805 -28.222198) (xy 56.406737 -28.275605) (xy 56.383065 -28.326102) (xy 56.352292 -28.372615)
			(xy 56.315075 -28.414152) (xy 56.272207 -28.449827) (xy 56.224601 -28.478881) (xy 56.173272 -28.500693)
			(xy 56.119315 -28.514799) (xy 56.063878 -28.520899) (xy 56.008144 -28.518862) (xy 55.953301 -28.508732)
			(xy 55.900517 -28.490725) (xy 55.850917 -28.465224) (xy 55.805559 -28.432773) (xy 55.76541 -28.394064)
			(xy 55.731324 -28.349921) (xy 55.704028 -28.301286) (xy 55.684105 -28.249195) (xy 55.671979 -28.194758)
			(xy 55.667908 -28.139136) (xy 55.161434 -28.139136) (xy 55.160925 -28.167022) (xy 55.152805 -28.222198)
			(xy 55.136737 -28.275605) (xy 55.113065 -28.326102) (xy 55.082292 -28.372615) (xy 55.045075 -28.414152)
			(xy 55.002207 -28.449827) (xy 54.954601 -28.478881) (xy 54.903272 -28.500693) (xy 54.849315 -28.514799)
			(xy 54.793878 -28.520899) (xy 54.738144 -28.518862) (xy 54.683301 -28.508732) (xy 54.630517 -28.490725)
			(xy 54.580917 -28.465224) (xy 54.535559 -28.432773) (xy 54.49541 -28.394064) (xy 54.461324 -28.349921)
			(xy 54.434028 -28.301286) (xy 54.414105 -28.249195) (xy 54.401979 -28.194758) (xy 54.397908 -28.139136)
			(xy 50.325251 -28.139136) (xy 50.356801 -28.158391) (xy 50.399669 -28.194066) (xy 50.436886 -28.235603)
			(xy 50.467659 -28.282116) (xy 50.491331 -28.332613) (xy 50.507399 -28.38602) (xy 50.515519 -28.441196)
			(xy 50.516028 -28.469082) (xy 50.515519 -28.496968) (xy 50.507399 -28.552144) (xy 50.491331 -28.605551)
			(xy 50.467659 -28.656048) (xy 50.436886 -28.702561) (xy 50.399669 -28.744098) (xy 50.356801 -28.779773)
			(xy 50.309195 -28.808827) (xy 50.257866 -28.830639) (xy 50.203909 -28.844745) (xy 50.148472 -28.850845)
			(xy 50.092738 -28.848808) (xy 50.037895 -28.838678) (xy 49.985111 -28.820671) (xy 49.935511 -28.79517)
			(xy 49.890153 -28.762719) (xy 49.850004 -28.72401) (xy 49.815918 -28.679867) (xy 49.788622 -28.631232)
			(xy 49.768699 -28.579141) (xy 49.756573 -28.524704) (xy 49.752502 -28.469082) (xy 45.76318 -28.469082)
			(xy 45.76318 -29.114242) (xy 45.763047 -29.12237) (xy 60.60694 -29.12237) (xy 60.60694 -28.25877)
			(xy 60.60743 -28.228802) (xy 60.615253 -28.16938) (xy 60.630766 -28.111487) (xy 60.653702 -28.056114)
			(xy 60.683669 -28.004208) (xy 60.720156 -27.956658) (xy 60.762536 -27.914278) (xy 60.810086 -27.877791)
			(xy 60.861992 -27.847824) (xy 60.917365 -27.824888) (xy 60.975258 -27.809375) (xy 61.03468 -27.801552)
			(xy 61.094616 -27.801552) (xy 61.154038 -27.809375) (xy 61.211931 -27.824888) (xy 61.267304 -27.847824)
			(xy 61.31921 -27.877791) (xy 61.36676 -27.914278) (xy 61.40914 -27.956658) (xy 61.445627 -28.004208)
			(xy 61.475594 -28.056114) (xy 61.49853 -28.111487) (xy 61.514043 -28.16938) (xy 61.521866 -28.228802)
			(xy 61.522356 -28.25877) (xy 61.522356 -29.114242) (xy 70.847204 -29.114242) (xy 70.847204 -28.250642)
			(xy 70.847694 -28.220658) (xy 70.855522 -28.161202) (xy 70.871043 -28.103277) (xy 70.893992 -28.047873)
			(xy 70.923976 -27.995939) (xy 70.960482 -27.948363) (xy 71.002887 -27.905958) (xy 71.050463 -27.869452)
			(xy 71.102397 -27.839468) (xy 71.157801 -27.816519) (xy 71.215726 -27.800998) (xy 71.275182 -27.79317)
			(xy 71.33515 -27.79317) (xy 71.394606 -27.800998) (xy 71.452531 -27.816519) (xy 71.507935 -27.839468)
			(xy 71.559869 -27.869452) (xy 71.607445 -27.905958) (xy 71.64985 -27.948363) (xy 71.686356 -27.995939)
			(xy 71.71634 -28.047873) (xy 71.739289 -28.103277) (xy 71.75481 -28.161202) (xy 71.762638 -28.220658)
			(xy 71.763128 -28.250642) (xy 71.763128 -28.469082) (xy 75.75245 -28.469082) (xy 75.756521 -28.41346)
			(xy 75.768647 -28.359023) (xy 75.78857 -28.306932) (xy 75.815866 -28.258297) (xy 75.849952 -28.214154)
			(xy 75.890101 -28.175445) (xy 75.935459 -28.142994) (xy 75.985059 -28.117493) (xy 76.037843 -28.099486)
			(xy 76.092686 -28.089356) (xy 76.14842 -28.087319) (xy 76.203857 -28.093419) (xy 76.257814 -28.107525)
			(xy 76.309143 -28.129337) (xy 76.325199 -28.139136) (xy 80.397856 -28.139136) (xy 80.401927 -28.083514)
			(xy 80.414053 -28.029077) (xy 80.433976 -27.976986) (xy 80.461272 -27.928351) (xy 80.495358 -27.884208)
			(xy 80.535507 -27.845499) (xy 80.580865 -27.813048) (xy 80.630465 -27.787547) (xy 80.683249 -27.76954)
			(xy 80.738092 -27.75941) (xy 80.793826 -27.757373) (xy 80.849263 -27.763473) (xy 80.90322 -27.777579)
			(xy 80.954549 -27.799391) (xy 81.002155 -27.828445) (xy 81.045023 -27.86412) (xy 81.08224 -27.905657)
			(xy 81.113013 -27.95217) (xy 81.136685 -28.002667) (xy 81.152753 -28.056074) (xy 81.160873 -28.11125)
			(xy 81.161382 -28.139136) (xy 81.667856 -28.139136) (xy 81.671927 -28.083514) (xy 81.684053 -28.029077)
			(xy 81.703976 -27.976986) (xy 81.731272 -27.928351) (xy 81.765358 -27.884208) (xy 81.805507 -27.845499)
			(xy 81.850865 -27.813048) (xy 81.900465 -27.787547) (xy 81.953249 -27.76954) (xy 82.008092 -27.75941)
			(xy 82.063826 -27.757373) (xy 82.119263 -27.763473) (xy 82.17322 -27.777579) (xy 82.224549 -27.799391)
			(xy 82.272155 -27.828445) (xy 82.315023 -27.86412) (xy 82.35224 -27.905657) (xy 82.383013 -27.95217)
			(xy 82.406685 -28.002667) (xy 82.422753 -28.056074) (xy 82.430873 -28.11125) (xy 82.431382 -28.139136)
			(xy 82.430873 -28.167022) (xy 82.422753 -28.222198) (xy 82.406685 -28.275605) (xy 82.383013 -28.326102)
			(xy 82.35224 -28.372615) (xy 82.315023 -28.414152) (xy 82.272155 -28.449827) (xy 82.224549 -28.478881)
			(xy 82.17322 -28.500693) (xy 82.119263 -28.514799) (xy 82.063826 -28.520899) (xy 82.008092 -28.518862)
			(xy 81.953249 -28.508732) (xy 81.900465 -28.490725) (xy 81.850865 -28.465224) (xy 81.805507 -28.432773)
			(xy 81.765358 -28.394064) (xy 81.731272 -28.349921) (xy 81.703976 -28.301286) (xy 81.684053 -28.249195)
			(xy 81.671927 -28.194758) (xy 81.667856 -28.139136) (xy 81.161382 -28.139136) (xy 81.160873 -28.167022)
			(xy 81.152753 -28.222198) (xy 81.136685 -28.275605) (xy 81.113013 -28.326102) (xy 81.08224 -28.372615)
			(xy 81.045023 -28.414152) (xy 81.002155 -28.449827) (xy 80.954549 -28.478881) (xy 80.90322 -28.500693)
			(xy 80.849263 -28.514799) (xy 80.793826 -28.520899) (xy 80.738092 -28.518862) (xy 80.683249 -28.508732)
			(xy 80.630465 -28.490725) (xy 80.580865 -28.465224) (xy 80.535507 -28.432773) (xy 80.495358 -28.394064)
			(xy 80.461272 -28.349921) (xy 80.433976 -28.301286) (xy 80.414053 -28.249195) (xy 80.401927 -28.194758)
			(xy 80.397856 -28.139136) (xy 76.325199 -28.139136) (xy 76.356749 -28.158391) (xy 76.399617 -28.194066)
			(xy 76.436834 -28.235603) (xy 76.467607 -28.282116) (xy 76.491279 -28.332613) (xy 76.507347 -28.38602)
			(xy 76.515467 -28.441196) (xy 76.515976 -28.469082) (xy 76.515467 -28.496968) (xy 76.507347 -28.552144)
			(xy 76.491279 -28.605551) (xy 76.467607 -28.656048) (xy 76.436834 -28.702561) (xy 76.399617 -28.744098)
			(xy 76.356749 -28.779773) (xy 76.309143 -28.808827) (xy 76.257814 -28.830639) (xy 76.203857 -28.844745)
			(xy 76.14842 -28.850845) (xy 76.092686 -28.848808) (xy 76.037843 -28.838678) (xy 75.985059 -28.820671)
			(xy 75.935459 -28.79517) (xy 75.890101 -28.762719) (xy 75.849952 -28.72401) (xy 75.815866 -28.679867)
			(xy 75.78857 -28.631232) (xy 75.768647 -28.579141) (xy 75.756521 -28.524704) (xy 75.75245 -28.469082)
			(xy 71.763128 -28.469082) (xy 71.763128 -29.114242) (xy 71.762995 -29.12237) (xy 86.606888 -29.12237)
			(xy 86.606888 -28.25877) (xy 86.607378 -28.228802) (xy 86.615201 -28.16938) (xy 86.630714 -28.111487)
			(xy 86.65365 -28.056114) (xy 86.683617 -28.004208) (xy 86.720104 -27.956658) (xy 86.762484 -27.914278)
			(xy 86.810034 -27.877791) (xy 86.86194 -27.847824) (xy 86.917313 -27.824888) (xy 86.975206 -27.809375)
			(xy 87.034628 -27.801552) (xy 87.094564 -27.801552) (xy 87.153986 -27.809375) (xy 87.211879 -27.824888)
			(xy 87.267252 -27.847824) (xy 87.319158 -27.877791) (xy 87.366708 -27.914278) (xy 87.409088 -27.956658)
			(xy 87.445575 -28.004208) (xy 87.475542 -28.056114) (xy 87.498478 -28.111487) (xy 87.513991 -28.16938)
			(xy 87.521814 -28.228802) (xy 87.522304 -28.25877) (xy 87.522304 -29.114242) (xy 96.847152 -29.114242)
			(xy 96.847152 -28.250642) (xy 96.847642 -28.220658) (xy 96.85547 -28.161202) (xy 96.870991 -28.103277)
			(xy 96.89394 -28.047873) (xy 96.923924 -27.995939) (xy 96.96043 -27.948363) (xy 97.002835 -27.905958)
			(xy 97.050411 -27.869452) (xy 97.102345 -27.839468) (xy 97.157749 -27.816519) (xy 97.215674 -27.800998)
			(xy 97.27513 -27.79317) (xy 97.335098 -27.79317) (xy 97.394554 -27.800998) (xy 97.452479 -27.816519)
			(xy 97.507883 -27.839468) (xy 97.559817 -27.869452) (xy 97.607393 -27.905958) (xy 97.649798 -27.948363)
			(xy 97.686304 -27.995939) (xy 97.716288 -28.047873) (xy 97.739237 -28.103277) (xy 97.754758 -28.161202)
			(xy 97.762586 -28.220658) (xy 97.763076 -28.250642) (xy 97.763076 -28.469082) (xy 101.752398 -28.469082)
			(xy 101.756469 -28.41346) (xy 101.768595 -28.359023) (xy 101.788518 -28.306932) (xy 101.815814 -28.258297)
			(xy 101.8499 -28.214154) (xy 101.890049 -28.175445) (xy 101.935407 -28.142994) (xy 101.985007 -28.117493)
			(xy 102.037791 -28.099486) (xy 102.092634 -28.089356) (xy 102.148368 -28.087319) (xy 102.203805 -28.093419)
			(xy 102.257762 -28.107525) (xy 102.309091 -28.129337) (xy 102.325147 -28.139136) (xy 118.49811 -28.139136)
			(xy 118.502181 -28.083514) (xy 118.514307 -28.029077) (xy 118.53423 -27.976986) (xy 118.561526 -27.928351)
			(xy 118.595612 -27.884208) (xy 118.635761 -27.845499) (xy 118.681119 -27.813048) (xy 118.730719 -27.787547)
			(xy 118.783503 -27.76954) (xy 118.838346 -27.75941) (xy 118.89408 -27.757373) (xy 118.949517 -27.763473)
			(xy 119.003474 -27.777579) (xy 119.054803 -27.799391) (xy 119.102409 -27.828445) (xy 119.145277 -27.86412)
			(xy 119.182494 -27.905657) (xy 119.213267 -27.95217) (xy 119.236939 -28.002667) (xy 119.253007 -28.056074)
			(xy 119.261127 -28.11125) (xy 119.261636 -28.139136) (xy 119.76811 -28.139136) (xy 119.772181 -28.083514)
			(xy 119.784307 -28.029077) (xy 119.80423 -27.976986) (xy 119.831526 -27.928351) (xy 119.865612 -27.884208)
			(xy 119.905761 -27.845499) (xy 119.951119 -27.813048) (xy 120.000719 -27.787547) (xy 120.053503 -27.76954)
			(xy 120.108346 -27.75941) (xy 120.16408 -27.757373) (xy 120.219517 -27.763473) (xy 120.273474 -27.777579)
			(xy 120.324803 -27.799391) (xy 120.372409 -27.828445) (xy 120.415277 -27.86412) (xy 120.452494 -27.905657)
			(xy 120.483267 -27.95217) (xy 120.506939 -28.002667) (xy 120.523007 -28.056074) (xy 120.531127 -28.11125)
			(xy 120.531636 -28.139136) (xy 120.531127 -28.167022) (xy 120.523007 -28.222198) (xy 120.506939 -28.275605)
			(xy 120.483267 -28.326102) (xy 120.452494 -28.372615) (xy 120.415277 -28.414152) (xy 120.372409 -28.449827)
			(xy 120.324803 -28.478881) (xy 120.273474 -28.500693) (xy 120.219517 -28.514799) (xy 120.16408 -28.520899)
			(xy 120.108346 -28.518862) (xy 120.053503 -28.508732) (xy 120.000719 -28.490725) (xy 119.951119 -28.465224)
			(xy 119.905761 -28.432773) (xy 119.865612 -28.394064) (xy 119.831526 -28.349921) (xy 119.80423 -28.301286)
			(xy 119.784307 -28.249195) (xy 119.772181 -28.194758) (xy 119.76811 -28.139136) (xy 119.261636 -28.139136)
			(xy 119.261127 -28.167022) (xy 119.253007 -28.222198) (xy 119.236939 -28.275605) (xy 119.213267 -28.326102)
			(xy 119.182494 -28.372615) (xy 119.145277 -28.414152) (xy 119.102409 -28.449827) (xy 119.054803 -28.478881)
			(xy 119.003474 -28.500693) (xy 118.949517 -28.514799) (xy 118.89408 -28.520899) (xy 118.838346 -28.518862)
			(xy 118.783503 -28.508732) (xy 118.730719 -28.490725) (xy 118.681119 -28.465224) (xy 118.635761 -28.432773)
			(xy 118.595612 -28.394064) (xy 118.561526 -28.349921) (xy 118.53423 -28.301286) (xy 118.514307 -28.249195)
			(xy 118.502181 -28.194758) (xy 118.49811 -28.139136) (xy 102.325147 -28.139136) (xy 102.356697 -28.158391)
			(xy 102.399565 -28.194066) (xy 102.436782 -28.235603) (xy 102.467555 -28.282116) (xy 102.491227 -28.332613)
			(xy 102.507295 -28.38602) (xy 102.515415 -28.441196) (xy 102.515924 -28.469082) (xy 102.515415 -28.496968)
			(xy 102.507295 -28.552144) (xy 102.491227 -28.605551) (xy 102.467555 -28.656048) (xy 102.436782 -28.702561)
			(xy 102.399565 -28.744098) (xy 102.356697 -28.779773) (xy 102.309091 -28.808827) (xy 102.257762 -28.830639)
			(xy 102.203805 -28.844745) (xy 102.148368 -28.850845) (xy 102.092634 -28.848808) (xy 102.037791 -28.838678)
			(xy 101.985007 -28.820671) (xy 101.935407 -28.79517) (xy 101.890049 -28.762719) (xy 101.8499 -28.72401)
			(xy 101.815814 -28.679867) (xy 101.788518 -28.631232) (xy 101.768595 -28.579141) (xy 101.756469 -28.524704)
			(xy 101.752398 -28.469082) (xy 97.763076 -28.469082) (xy 97.763076 -29.114242) (xy 97.762943 -29.12237)
			(xy 124.706888 -29.12237) (xy 124.706888 -28.25877) (xy 124.707378 -28.228786) (xy 124.715206 -28.16933)
			(xy 124.730727 -28.111405) (xy 124.753676 -28.056001) (xy 124.78366 -28.004067) (xy 124.820166 -27.956491)
			(xy 124.862571 -27.914086) (xy 124.910147 -27.87758) (xy 124.962081 -27.847596) (xy 125.017485 -27.824647)
			(xy 125.07541 -27.809126) (xy 125.134866 -27.801298) (xy 125.194834 -27.801298) (xy 125.25429 -27.809126)
			(xy 125.312215 -27.824647) (xy 125.367619 -27.847596) (xy 125.419553 -27.87758) (xy 125.467129 -27.914086)
			(xy 125.509534 -27.956491) (xy 125.54604 -28.004067) (xy 125.576024 -28.056001) (xy 125.598973 -28.111405)
			(xy 125.614494 -28.16933) (xy 125.622322 -28.228786) (xy 125.622812 -28.25877) (xy 125.622812 -29.114242)
			(xy 134.94766 -29.114242) (xy 134.94766 -28.250642) (xy 134.94815 -28.220674) (xy 134.955973 -28.161252)
			(xy 134.971486 -28.103359) (xy 134.994422 -28.047986) (xy 135.024389 -27.99608) (xy 135.060876 -27.94853)
			(xy 135.103256 -27.90615) (xy 135.150806 -27.869663) (xy 135.202712 -27.839696) (xy 135.258085 -27.81676)
			(xy 135.315978 -27.801247) (xy 135.3754 -27.793424) (xy 135.435336 -27.793424) (xy 135.494758 -27.801247)
			(xy 135.552651 -27.81676) (xy 135.608024 -27.839696) (xy 135.65993 -27.869663) (xy 135.70748 -27.90615)
			(xy 135.74986 -27.94853) (xy 135.786347 -27.99608) (xy 135.816314 -28.047986) (xy 135.83925 -28.103359)
			(xy 135.854763 -28.161252) (xy 135.862586 -28.220674) (xy 135.863076 -28.250642) (xy 135.863076 -28.469082)
			(xy 139.852652 -28.469082) (xy 139.856723 -28.41346) (xy 139.868849 -28.359023) (xy 139.888772 -28.306932)
			(xy 139.916068 -28.258297) (xy 139.950154 -28.214154) (xy 139.990303 -28.175445) (xy 140.035661 -28.142994)
			(xy 140.085261 -28.117493) (xy 140.138045 -28.099486) (xy 140.192888 -28.089356) (xy 140.248622 -28.087319)
			(xy 140.304059 -28.093419) (xy 140.358016 -28.107525) (xy 140.409345 -28.129337) (xy 140.425401 -28.139136)
			(xy 144.498058 -28.139136) (xy 144.502129 -28.083514) (xy 144.514255 -28.029077) (xy 144.534178 -27.976986)
			(xy 144.561474 -27.928351) (xy 144.59556 -27.884208) (xy 144.635709 -27.845499) (xy 144.681067 -27.813048)
			(xy 144.730667 -27.787547) (xy 144.783451 -27.76954) (xy 144.838294 -27.75941) (xy 144.894028 -27.757373)
			(xy 144.949465 -27.763473) (xy 145.003422 -27.777579) (xy 145.054751 -27.799391) (xy 145.102357 -27.828445)
			(xy 145.145225 -27.86412) (xy 145.182442 -27.905657) (xy 145.213215 -27.95217) (xy 145.236887 -28.002667)
			(xy 145.252955 -28.056074) (xy 145.261075 -28.11125) (xy 145.261584 -28.139136) (xy 145.768058 -28.139136)
			(xy 145.772129 -28.083514) (xy 145.784255 -28.029077) (xy 145.804178 -27.976986) (xy 145.831474 -27.928351)
			(xy 145.86556 -27.884208) (xy 145.905709 -27.845499) (xy 145.951067 -27.813048) (xy 146.000667 -27.787547)
			(xy 146.053451 -27.76954) (xy 146.108294 -27.75941) (xy 146.164028 -27.757373) (xy 146.219465 -27.763473)
			(xy 146.273422 -27.777579) (xy 146.324751 -27.799391) (xy 146.372357 -27.828445) (xy 146.415225 -27.86412)
			(xy 146.452442 -27.905657) (xy 146.483215 -27.95217) (xy 146.506887 -28.002667) (xy 146.522955 -28.056074)
			(xy 146.531075 -28.11125) (xy 146.531584 -28.139136) (xy 146.531075 -28.167022) (xy 146.522955 -28.222198)
			(xy 146.506887 -28.275605) (xy 146.483215 -28.326102) (xy 146.452442 -28.372615) (xy 146.415225 -28.414152)
			(xy 146.372357 -28.449827) (xy 146.324751 -28.478881) (xy 146.273422 -28.500693) (xy 146.219465 -28.514799)
			(xy 146.164028 -28.520899) (xy 146.108294 -28.518862) (xy 146.053451 -28.508732) (xy 146.000667 -28.490725)
			(xy 145.951067 -28.465224) (xy 145.905709 -28.432773) (xy 145.86556 -28.394064) (xy 145.831474 -28.349921)
			(xy 145.804178 -28.301286) (xy 145.784255 -28.249195) (xy 145.772129 -28.194758) (xy 145.768058 -28.139136)
			(xy 145.261584 -28.139136) (xy 145.261075 -28.167022) (xy 145.252955 -28.222198) (xy 145.236887 -28.275605)
			(xy 145.213215 -28.326102) (xy 145.182442 -28.372615) (xy 145.145225 -28.414152) (xy 145.102357 -28.449827)
			(xy 145.054751 -28.478881) (xy 145.003422 -28.500693) (xy 144.949465 -28.514799) (xy 144.894028 -28.520899)
			(xy 144.838294 -28.518862) (xy 144.783451 -28.508732) (xy 144.730667 -28.490725) (xy 144.681067 -28.465224)
			(xy 144.635709 -28.432773) (xy 144.59556 -28.394064) (xy 144.561474 -28.349921) (xy 144.534178 -28.301286)
			(xy 144.514255 -28.249195) (xy 144.502129 -28.194758) (xy 144.498058 -28.139136) (xy 140.425401 -28.139136)
			(xy 140.456951 -28.158391) (xy 140.499819 -28.194066) (xy 140.537036 -28.235603) (xy 140.567809 -28.282116)
			(xy 140.591481 -28.332613) (xy 140.607549 -28.38602) (xy 140.615669 -28.441196) (xy 140.616178 -28.469082)
			(xy 140.615669 -28.496968) (xy 140.607549 -28.552144) (xy 140.591481 -28.605551) (xy 140.567809 -28.656048)
			(xy 140.537036 -28.702561) (xy 140.499819 -28.744098) (xy 140.456951 -28.779773) (xy 140.409345 -28.808827)
			(xy 140.358016 -28.830639) (xy 140.304059 -28.844745) (xy 140.248622 -28.850845) (xy 140.192888 -28.848808)
			(xy 140.138045 -28.838678) (xy 140.085261 -28.820671) (xy 140.035661 -28.79517) (xy 139.990303 -28.762719)
			(xy 139.950154 -28.72401) (xy 139.916068 -28.679867) (xy 139.888772 -28.631232) (xy 139.868849 -28.579141)
			(xy 139.856723 -28.524704) (xy 139.852652 -28.469082) (xy 135.863076 -28.469082) (xy 135.863076 -29.114242)
			(xy 135.862943 -29.12237) (xy 150.706836 -29.12237) (xy 150.706836 -28.25877) (xy 150.707326 -28.228786)
			(xy 150.715154 -28.16933) (xy 150.730675 -28.111405) (xy 150.753624 -28.056001) (xy 150.783608 -28.004067)
			(xy 150.820114 -27.956491) (xy 150.862519 -27.914086) (xy 150.910095 -27.87758) (xy 150.962029 -27.847596)
			(xy 151.017433 -27.824647) (xy 151.075358 -27.809126) (xy 151.134814 -27.801298) (xy 151.194782 -27.801298)
			(xy 151.254238 -27.809126) (xy 151.312163 -27.824647) (xy 151.367567 -27.847596) (xy 151.419501 -27.87758)
			(xy 151.467077 -27.914086) (xy 151.509482 -27.956491) (xy 151.545988 -28.004067) (xy 151.575972 -28.056001)
			(xy 151.598921 -28.111405) (xy 151.614442 -28.16933) (xy 151.62227 -28.228786) (xy 151.62276 -28.25877)
			(xy 151.62276 -29.114242) (xy 160.947608 -29.114242) (xy 160.947608 -28.250642) (xy 160.948098 -28.220674)
			(xy 160.955921 -28.161252) (xy 160.971434 -28.103359) (xy 160.99437 -28.047986) (xy 161.024337 -27.99608)
			(xy 161.060824 -27.94853) (xy 161.103204 -27.90615) (xy 161.150754 -27.869663) (xy 161.20266 -27.839696)
			(xy 161.258033 -27.81676) (xy 161.315926 -27.801247) (xy 161.375348 -27.793424) (xy 161.435284 -27.793424)
			(xy 161.494706 -27.801247) (xy 161.552599 -27.81676) (xy 161.607972 -27.839696) (xy 161.659878 -27.869663)
			(xy 161.707428 -27.90615) (xy 161.749808 -27.94853) (xy 161.786295 -27.99608) (xy 161.816262 -28.047986)
			(xy 161.839198 -28.103359) (xy 161.854711 -28.161252) (xy 161.862534 -28.220674) (xy 161.863024 -28.250642)
			(xy 161.863024 -28.469082) (xy 165.8526 -28.469082) (xy 165.856671 -28.41346) (xy 165.868797 -28.359023)
			(xy 165.88872 -28.306932) (xy 165.916016 -28.258297) (xy 165.950102 -28.214154) (xy 165.990251 -28.175445)
			(xy 166.035609 -28.142994) (xy 166.085209 -28.117493) (xy 166.137993 -28.099486) (xy 166.192836 -28.089356)
			(xy 166.24857 -28.087319) (xy 166.304007 -28.093419) (xy 166.357964 -28.107525) (xy 166.409293 -28.129337)
			(xy 166.425349 -28.139136) (xy 170.498006 -28.139136) (xy 170.502077 -28.083514) (xy 170.514203 -28.029077)
			(xy 170.534126 -27.976986) (xy 170.561422 -27.928351) (xy 170.595508 -27.884208) (xy 170.635657 -27.845499)
			(xy 170.681015 -27.813048) (xy 170.730615 -27.787547) (xy 170.783399 -27.76954) (xy 170.838242 -27.75941)
			(xy 170.893976 -27.757373) (xy 170.949413 -27.763473) (xy 171.00337 -27.777579) (xy 171.054699 -27.799391)
			(xy 171.102305 -27.828445) (xy 171.145173 -27.86412) (xy 171.18239 -27.905657) (xy 171.213163 -27.95217)
			(xy 171.236835 -28.002667) (xy 171.252903 -28.056074) (xy 171.261023 -28.11125) (xy 171.261532 -28.139136)
			(xy 171.768006 -28.139136) (xy 171.772077 -28.083514) (xy 171.784203 -28.029077) (xy 171.804126 -27.976986)
			(xy 171.831422 -27.928351) (xy 171.865508 -27.884208) (xy 171.905657 -27.845499) (xy 171.951015 -27.813048)
			(xy 172.000615 -27.787547) (xy 172.053399 -27.76954) (xy 172.108242 -27.75941) (xy 172.163976 -27.757373)
			(xy 172.219413 -27.763473) (xy 172.27337 -27.777579) (xy 172.324699 -27.799391) (xy 172.372305 -27.828445)
			(xy 172.415173 -27.86412) (xy 172.45239 -27.905657) (xy 172.483163 -27.95217) (xy 172.506835 -28.002667)
			(xy 172.522903 -28.056074) (xy 172.531023 -28.11125) (xy 172.531532 -28.139136) (xy 172.531023 -28.167022)
			(xy 172.522903 -28.222198) (xy 172.506835 -28.275605) (xy 172.483163 -28.326102) (xy 172.45239 -28.372615)
			(xy 172.415173 -28.414152) (xy 172.372305 -28.449827) (xy 172.324699 -28.478881) (xy 172.27337 -28.500693)
			(xy 172.219413 -28.514799) (xy 172.163976 -28.520899) (xy 172.108242 -28.518862) (xy 172.053399 -28.508732)
			(xy 172.000615 -28.490725) (xy 171.951015 -28.465224) (xy 171.905657 -28.432773) (xy 171.865508 -28.394064)
			(xy 171.831422 -28.349921) (xy 171.804126 -28.301286) (xy 171.784203 -28.249195) (xy 171.772077 -28.194758)
			(xy 171.768006 -28.139136) (xy 171.261532 -28.139136) (xy 171.261023 -28.167022) (xy 171.252903 -28.222198)
			(xy 171.236835 -28.275605) (xy 171.213163 -28.326102) (xy 171.18239 -28.372615) (xy 171.145173 -28.414152)
			(xy 171.102305 -28.449827) (xy 171.054699 -28.478881) (xy 171.00337 -28.500693) (xy 170.949413 -28.514799)
			(xy 170.893976 -28.520899) (xy 170.838242 -28.518862) (xy 170.783399 -28.508732) (xy 170.730615 -28.490725)
			(xy 170.681015 -28.465224) (xy 170.635657 -28.432773) (xy 170.595508 -28.394064) (xy 170.561422 -28.349921)
			(xy 170.534126 -28.301286) (xy 170.514203 -28.249195) (xy 170.502077 -28.194758) (xy 170.498006 -28.139136)
			(xy 166.425349 -28.139136) (xy 166.456899 -28.158391) (xy 166.499767 -28.194066) (xy 166.536984 -28.235603)
			(xy 166.567757 -28.282116) (xy 166.591429 -28.332613) (xy 166.607497 -28.38602) (xy 166.615617 -28.441196)
			(xy 166.616126 -28.469082) (xy 166.615617 -28.496968) (xy 166.607497 -28.552144) (xy 166.591429 -28.605551)
			(xy 166.567757 -28.656048) (xy 166.536984 -28.702561) (xy 166.499767 -28.744098) (xy 166.456899 -28.779773)
			(xy 166.409293 -28.808827) (xy 166.357964 -28.830639) (xy 166.304007 -28.844745) (xy 166.24857 -28.850845)
			(xy 166.192836 -28.848808) (xy 166.137993 -28.838678) (xy 166.085209 -28.820671) (xy 166.035609 -28.79517)
			(xy 165.990251 -28.762719) (xy 165.950102 -28.72401) (xy 165.916016 -28.679867) (xy 165.88872 -28.631232)
			(xy 165.868797 -28.579141) (xy 165.856671 -28.524704) (xy 165.8526 -28.469082) (xy 161.863024 -28.469082)
			(xy 161.863024 -29.114242) (xy 161.862891 -29.12237) (xy 176.706784 -29.12237) (xy 176.706784 -28.25877)
			(xy 176.707274 -28.228786) (xy 176.715102 -28.16933) (xy 176.730623 -28.111405) (xy 176.753572 -28.056001)
			(xy 176.783556 -28.004067) (xy 176.820062 -27.956491) (xy 176.862467 -27.914086) (xy 176.910043 -27.87758)
			(xy 176.961977 -27.847596) (xy 177.017381 -27.824647) (xy 177.075306 -27.809126) (xy 177.134762 -27.801298)
			(xy 177.19473 -27.801298) (xy 177.254186 -27.809126) (xy 177.312111 -27.824647) (xy 177.367515 -27.847596)
			(xy 177.419449 -27.87758) (xy 177.467025 -27.914086) (xy 177.50943 -27.956491) (xy 177.545936 -28.004067)
			(xy 177.57592 -28.056001) (xy 177.598869 -28.111405) (xy 177.61439 -28.16933) (xy 177.622218 -28.228786)
			(xy 177.622708 -28.25877) (xy 177.622708 -29.114242) (xy 186.947556 -29.114242) (xy 186.947556 -28.250642)
			(xy 186.948046 -28.220674) (xy 186.955869 -28.161252) (xy 186.971382 -28.103359) (xy 186.994318 -28.047986)
			(xy 187.024285 -27.99608) (xy 187.060772 -27.94853) (xy 187.103152 -27.90615) (xy 187.150702 -27.869663)
			(xy 187.202608 -27.839696) (xy 187.257981 -27.81676) (xy 187.315874 -27.801247) (xy 187.375296 -27.793424)
			(xy 187.435232 -27.793424) (xy 187.494654 -27.801247) (xy 187.552547 -27.81676) (xy 187.60792 -27.839696)
			(xy 187.659826 -27.869663) (xy 187.707376 -27.90615) (xy 187.749756 -27.94853) (xy 187.786243 -27.99608)
			(xy 187.81621 -28.047986) (xy 187.839146 -28.103359) (xy 187.854659 -28.161252) (xy 187.862482 -28.220674)
			(xy 187.862972 -28.250642) (xy 187.862972 -28.469082) (xy 191.852548 -28.469082) (xy 191.856619 -28.41346)
			(xy 191.868745 -28.359023) (xy 191.888668 -28.306932) (xy 191.915964 -28.258297) (xy 191.95005 -28.214154)
			(xy 191.990199 -28.175445) (xy 192.035557 -28.142994) (xy 192.085157 -28.117493) (xy 192.137941 -28.099486)
			(xy 192.192784 -28.089356) (xy 192.248518 -28.087319) (xy 192.303955 -28.093419) (xy 192.357912 -28.107525)
			(xy 192.409241 -28.129337) (xy 192.425297 -28.139136) (xy 196.497954 -28.139136) (xy 196.502025 -28.083514)
			(xy 196.514151 -28.029077) (xy 196.534074 -27.976986) (xy 196.56137 -27.928351) (xy 196.595456 -27.884208)
			(xy 196.635605 -27.845499) (xy 196.680963 -27.813048) (xy 196.730563 -27.787547) (xy 196.783347 -27.76954)
			(xy 196.83819 -27.75941) (xy 196.893924 -27.757373) (xy 196.949361 -27.763473) (xy 197.003318 -27.777579)
			(xy 197.054647 -27.799391) (xy 197.102253 -27.828445) (xy 197.145121 -27.86412) (xy 197.182338 -27.905657)
			(xy 197.213111 -27.95217) (xy 197.236783 -28.002667) (xy 197.252851 -28.056074) (xy 197.260971 -28.11125)
			(xy 197.26148 -28.139136) (xy 197.767954 -28.139136) (xy 197.772025 -28.083514) (xy 197.784151 -28.029077)
			(xy 197.804074 -27.976986) (xy 197.83137 -27.928351) (xy 197.865456 -27.884208) (xy 197.905605 -27.845499)
			(xy 197.950963 -27.813048) (xy 198.000563 -27.787547) (xy 198.053347 -27.76954) (xy 198.10819 -27.75941)
			(xy 198.163924 -27.757373) (xy 198.219361 -27.763473) (xy 198.273318 -27.777579) (xy 198.324647 -27.799391)
			(xy 198.372253 -27.828445) (xy 198.415121 -27.86412) (xy 198.452338 -27.905657) (xy 198.483111 -27.95217)
			(xy 198.506783 -28.002667) (xy 198.522851 -28.056074) (xy 198.530971 -28.11125) (xy 198.53148 -28.139136)
			(xy 198.530971 -28.167022) (xy 198.522851 -28.222198) (xy 198.506783 -28.275605) (xy 198.483111 -28.326102)
			(xy 198.452338 -28.372615) (xy 198.415121 -28.414152) (xy 198.372253 -28.449827) (xy 198.324647 -28.478881)
			(xy 198.273318 -28.500693) (xy 198.219361 -28.514799) (xy 198.163924 -28.520899) (xy 198.10819 -28.518862)
			(xy 198.053347 -28.508732) (xy 198.000563 -28.490725) (xy 197.950963 -28.465224) (xy 197.905605 -28.432773)
			(xy 197.865456 -28.394064) (xy 197.83137 -28.349921) (xy 197.804074 -28.301286) (xy 197.784151 -28.249195)
			(xy 197.772025 -28.194758) (xy 197.767954 -28.139136) (xy 197.26148 -28.139136) (xy 197.260971 -28.167022)
			(xy 197.252851 -28.222198) (xy 197.236783 -28.275605) (xy 197.213111 -28.326102) (xy 197.182338 -28.372615)
			(xy 197.145121 -28.414152) (xy 197.102253 -28.449827) (xy 197.054647 -28.478881) (xy 197.003318 -28.500693)
			(xy 196.949361 -28.514799) (xy 196.893924 -28.520899) (xy 196.83819 -28.518862) (xy 196.783347 -28.508732)
			(xy 196.730563 -28.490725) (xy 196.680963 -28.465224) (xy 196.635605 -28.432773) (xy 196.595456 -28.394064)
			(xy 196.56137 -28.349921) (xy 196.534074 -28.301286) (xy 196.514151 -28.249195) (xy 196.502025 -28.194758)
			(xy 196.497954 -28.139136) (xy 192.425297 -28.139136) (xy 192.456847 -28.158391) (xy 192.499715 -28.194066)
			(xy 192.536932 -28.235603) (xy 192.567705 -28.282116) (xy 192.591377 -28.332613) (xy 192.607445 -28.38602)
			(xy 192.615565 -28.441196) (xy 192.616074 -28.469082) (xy 192.615565 -28.496968) (xy 192.607445 -28.552144)
			(xy 192.591377 -28.605551) (xy 192.567705 -28.656048) (xy 192.536932 -28.702561) (xy 192.499715 -28.744098)
			(xy 192.456847 -28.779773) (xy 192.409241 -28.808827) (xy 192.357912 -28.830639) (xy 192.303955 -28.844745)
			(xy 192.248518 -28.850845) (xy 192.192784 -28.848808) (xy 192.137941 -28.838678) (xy 192.085157 -28.820671)
			(xy 192.035557 -28.79517) (xy 191.990199 -28.762719) (xy 191.95005 -28.72401) (xy 191.915964 -28.679867)
			(xy 191.888668 -28.631232) (xy 191.868745 -28.579141) (xy 191.856619 -28.524704) (xy 191.852548 -28.469082)
			(xy 187.862972 -28.469082) (xy 187.862972 -29.114242) (xy 187.862839 -29.12237) (xy 202.706732 -29.12237)
			(xy 202.706732 -28.25877) (xy 202.707222 -28.228786) (xy 202.71505 -28.16933) (xy 202.730571 -28.111405)
			(xy 202.75352 -28.056001) (xy 202.783504 -28.004067) (xy 202.82001 -27.956491) (xy 202.862415 -27.914086)
			(xy 202.909991 -27.87758) (xy 202.961925 -27.847596) (xy 203.017329 -27.824647) (xy 203.075254 -27.809126)
			(xy 203.13471 -27.801298) (xy 203.194678 -27.801298) (xy 203.254134 -27.809126) (xy 203.312059 -27.824647)
			(xy 203.367463 -27.847596) (xy 203.419397 -27.87758) (xy 203.466973 -27.914086) (xy 203.509378 -27.956491)
			(xy 203.545884 -28.004067) (xy 203.575868 -28.056001) (xy 203.598817 -28.111405) (xy 203.614338 -28.16933)
			(xy 203.622166 -28.228786) (xy 203.622656 -28.25877) (xy 203.622656 -29.114242) (xy 212.947504 -29.114242)
			(xy 212.947504 -28.250642) (xy 212.947994 -28.220674) (xy 212.955817 -28.161252) (xy 212.97133 -28.103359)
			(xy 212.994266 -28.047986) (xy 213.024233 -27.99608) (xy 213.06072 -27.94853) (xy 213.1031 -27.90615)
			(xy 213.15065 -27.869663) (xy 213.202556 -27.839696) (xy 213.257929 -27.81676) (xy 213.315822 -27.801247)
			(xy 213.375244 -27.793424) (xy 213.43518 -27.793424) (xy 213.494602 -27.801247) (xy 213.552495 -27.81676)
			(xy 213.607868 -27.839696) (xy 213.659774 -27.869663) (xy 213.707324 -27.90615) (xy 213.749704 -27.94853)
			(xy 213.786191 -27.99608) (xy 213.816158 -28.047986) (xy 213.839094 -28.103359) (xy 213.854607 -28.161252)
			(xy 213.86243 -28.220674) (xy 213.86292 -28.250642) (xy 213.86292 -28.469082) (xy 217.852496 -28.469082)
			(xy 217.856567 -28.41346) (xy 217.868693 -28.359023) (xy 217.888616 -28.306932) (xy 217.915912 -28.258297)
			(xy 217.949998 -28.214154) (xy 217.990147 -28.175445) (xy 218.035505 -28.142994) (xy 218.085105 -28.117493)
			(xy 218.137889 -28.099486) (xy 218.192732 -28.089356) (xy 218.248466 -28.087319) (xy 218.303903 -28.093419)
			(xy 218.35786 -28.107525) (xy 218.409189 -28.129337) (xy 218.425245 -28.139136) (xy 234.597954 -28.139136)
			(xy 234.602025 -28.083514) (xy 234.614151 -28.029077) (xy 234.634074 -27.976986) (xy 234.66137 -27.928351)
			(xy 234.695456 -27.884208) (xy 234.735605 -27.845499) (xy 234.780963 -27.813048) (xy 234.830563 -27.787547)
			(xy 234.883347 -27.76954) (xy 234.93819 -27.75941) (xy 234.993924 -27.757373) (xy 235.049361 -27.763473)
			(xy 235.103318 -27.777579) (xy 235.154647 -27.799391) (xy 235.202253 -27.828445) (xy 235.245121 -27.86412)
			(xy 235.282338 -27.905657) (xy 235.313111 -27.95217) (xy 235.336783 -28.002667) (xy 235.352851 -28.056074)
			(xy 235.360971 -28.11125) (xy 235.36148 -28.139136) (xy 235.867954 -28.139136) (xy 235.872025 -28.083514)
			(xy 235.884151 -28.029077) (xy 235.904074 -27.976986) (xy 235.93137 -27.928351) (xy 235.965456 -27.884208)
			(xy 236.005605 -27.845499) (xy 236.050963 -27.813048) (xy 236.100563 -27.787547) (xy 236.153347 -27.76954)
			(xy 236.20819 -27.75941) (xy 236.263924 -27.757373) (xy 236.319361 -27.763473) (xy 236.373318 -27.777579)
			(xy 236.424647 -27.799391) (xy 236.472253 -27.828445) (xy 236.515121 -27.86412) (xy 236.552338 -27.905657)
			(xy 236.583111 -27.95217) (xy 236.606783 -28.002667) (xy 236.622851 -28.056074) (xy 236.630971 -28.11125)
			(xy 236.63148 -28.139136) (xy 236.630971 -28.167022) (xy 236.622851 -28.222198) (xy 236.606783 -28.275605)
			(xy 236.583111 -28.326102) (xy 236.552338 -28.372615) (xy 236.515121 -28.414152) (xy 236.472253 -28.449827)
			(xy 236.424647 -28.478881) (xy 236.373318 -28.500693) (xy 236.319361 -28.514799) (xy 236.263924 -28.520899)
			(xy 236.20819 -28.518862) (xy 236.153347 -28.508732) (xy 236.100563 -28.490725) (xy 236.050963 -28.465224)
			(xy 236.005605 -28.432773) (xy 235.965456 -28.394064) (xy 235.93137 -28.349921) (xy 235.904074 -28.301286)
			(xy 235.884151 -28.249195) (xy 235.872025 -28.194758) (xy 235.867954 -28.139136) (xy 235.36148 -28.139136)
			(xy 235.360971 -28.167022) (xy 235.352851 -28.222198) (xy 235.336783 -28.275605) (xy 235.313111 -28.326102)
			(xy 235.282338 -28.372615) (xy 235.245121 -28.414152) (xy 235.202253 -28.449827) (xy 235.154647 -28.478881)
			(xy 235.103318 -28.500693) (xy 235.049361 -28.514799) (xy 234.993924 -28.520899) (xy 234.93819 -28.518862)
			(xy 234.883347 -28.508732) (xy 234.830563 -28.490725) (xy 234.780963 -28.465224) (xy 234.735605 -28.432773)
			(xy 234.695456 -28.394064) (xy 234.66137 -28.349921) (xy 234.634074 -28.301286) (xy 234.614151 -28.249195)
			(xy 234.602025 -28.194758) (xy 234.597954 -28.139136) (xy 218.425245 -28.139136) (xy 218.456795 -28.158391)
			(xy 218.499663 -28.194066) (xy 218.53688 -28.235603) (xy 218.567653 -28.282116) (xy 218.591325 -28.332613)
			(xy 218.607393 -28.38602) (xy 218.615513 -28.441196) (xy 218.616022 -28.469082) (xy 218.615513 -28.496968)
			(xy 218.607393 -28.552144) (xy 218.591325 -28.605551) (xy 218.567653 -28.656048) (xy 218.53688 -28.702561)
			(xy 218.499663 -28.744098) (xy 218.456795 -28.779773) (xy 218.409189 -28.808827) (xy 218.35786 -28.830639)
			(xy 218.303903 -28.844745) (xy 218.248466 -28.850845) (xy 218.192732 -28.848808) (xy 218.137889 -28.838678)
			(xy 218.085105 -28.820671) (xy 218.035505 -28.79517) (xy 217.990147 -28.762719) (xy 217.949998 -28.72401)
			(xy 217.915912 -28.679867) (xy 217.888616 -28.631232) (xy 217.868693 -28.579141) (xy 217.856567 -28.524704)
			(xy 217.852496 -28.469082) (xy 213.86292 -28.469082) (xy 213.86292 -29.114242) (xy 213.862787 -29.12237)
			(xy 240.806732 -29.12237) (xy 240.806732 -28.25877) (xy 240.807222 -28.228786) (xy 240.81505 -28.16933)
			(xy 240.830571 -28.111405) (xy 240.85352 -28.056001) (xy 240.883504 -28.004067) (xy 240.92001 -27.956491)
			(xy 240.962415 -27.914086) (xy 241.009991 -27.87758) (xy 241.061925 -27.847596) (xy 241.117329 -27.824647)
			(xy 241.175254 -27.809126) (xy 241.23471 -27.801298) (xy 241.294678 -27.801298) (xy 241.354134 -27.809126)
			(xy 241.412059 -27.824647) (xy 241.467463 -27.847596) (xy 241.519397 -27.87758) (xy 241.566973 -27.914086)
			(xy 241.609378 -27.956491) (xy 241.645884 -28.004067) (xy 241.675868 -28.056001) (xy 241.698817 -28.111405)
			(xy 241.714338 -28.16933) (xy 241.722166 -28.228786) (xy 241.722656 -28.25877) (xy 241.722656 -29.114242)
			(xy 251.047504 -29.114242) (xy 251.047504 -28.250642) (xy 251.047994 -28.220674) (xy 251.055817 -28.161252)
			(xy 251.07133 -28.103359) (xy 251.094266 -28.047986) (xy 251.124233 -27.99608) (xy 251.16072 -27.94853)
			(xy 251.2031 -27.90615) (xy 251.25065 -27.869663) (xy 251.302556 -27.839696) (xy 251.357929 -27.81676)
			(xy 251.415822 -27.801247) (xy 251.475244 -27.793424) (xy 251.53518 -27.793424) (xy 251.594602 -27.801247)
			(xy 251.652495 -27.81676) (xy 251.707868 -27.839696) (xy 251.759774 -27.869663) (xy 251.807324 -27.90615)
			(xy 251.849704 -27.94853) (xy 251.886191 -27.99608) (xy 251.916158 -28.047986) (xy 251.939094 -28.103359)
			(xy 251.954607 -28.161252) (xy 251.96243 -28.220674) (xy 251.96292 -28.250642) (xy 251.96292 -28.469082)
			(xy 255.952496 -28.469082) (xy 255.956567 -28.41346) (xy 255.968693 -28.359023) (xy 255.988616 -28.306932)
			(xy 256.015912 -28.258297) (xy 256.049998 -28.214154) (xy 256.090147 -28.175445) (xy 256.135505 -28.142994)
			(xy 256.185105 -28.117493) (xy 256.237889 -28.099486) (xy 256.292732 -28.089356) (xy 256.348466 -28.087319)
			(xy 256.403903 -28.093419) (xy 256.45786 -28.107525) (xy 256.509189 -28.129337) (xy 256.525245 -28.139136)
			(xy 260.597902 -28.139136) (xy 260.601973 -28.083514) (xy 260.614099 -28.029077) (xy 260.634022 -27.976986)
			(xy 260.661318 -27.928351) (xy 260.695404 -27.884208) (xy 260.735553 -27.845499) (xy 260.780911 -27.813048)
			(xy 260.830511 -27.787547) (xy 260.883295 -27.76954) (xy 260.938138 -27.75941) (xy 260.993872 -27.757373)
			(xy 261.049309 -27.763473) (xy 261.103266 -27.777579) (xy 261.154595 -27.799391) (xy 261.202201 -27.828445)
			(xy 261.245069 -27.86412) (xy 261.282286 -27.905657) (xy 261.313059 -27.95217) (xy 261.336731 -28.002667)
			(xy 261.352799 -28.056074) (xy 261.360919 -28.11125) (xy 261.361428 -28.139136) (xy 261.867902 -28.139136)
			(xy 261.871973 -28.083514) (xy 261.884099 -28.029077) (xy 261.904022 -27.976986) (xy 261.931318 -27.928351)
			(xy 261.965404 -27.884208) (xy 262.005553 -27.845499) (xy 262.050911 -27.813048) (xy 262.100511 -27.787547)
			(xy 262.153295 -27.76954) (xy 262.208138 -27.75941) (xy 262.263872 -27.757373) (xy 262.319309 -27.763473)
			(xy 262.373266 -27.777579) (xy 262.424595 -27.799391) (xy 262.472201 -27.828445) (xy 262.515069 -27.86412)
			(xy 262.552286 -27.905657) (xy 262.583059 -27.95217) (xy 262.606731 -28.002667) (xy 262.622799 -28.056074)
			(xy 262.630919 -28.11125) (xy 262.631428 -28.139136) (xy 262.630919 -28.167022) (xy 262.622799 -28.222198)
			(xy 262.606731 -28.275605) (xy 262.583059 -28.326102) (xy 262.552286 -28.372615) (xy 262.515069 -28.414152)
			(xy 262.472201 -28.449827) (xy 262.424595 -28.478881) (xy 262.373266 -28.500693) (xy 262.319309 -28.514799)
			(xy 262.263872 -28.520899) (xy 262.208138 -28.518862) (xy 262.153295 -28.508732) (xy 262.100511 -28.490725)
			(xy 262.050911 -28.465224) (xy 262.005553 -28.432773) (xy 261.965404 -28.394064) (xy 261.931318 -28.349921)
			(xy 261.904022 -28.301286) (xy 261.884099 -28.249195) (xy 261.871973 -28.194758) (xy 261.867902 -28.139136)
			(xy 261.361428 -28.139136) (xy 261.360919 -28.167022) (xy 261.352799 -28.222198) (xy 261.336731 -28.275605)
			(xy 261.313059 -28.326102) (xy 261.282286 -28.372615) (xy 261.245069 -28.414152) (xy 261.202201 -28.449827)
			(xy 261.154595 -28.478881) (xy 261.103266 -28.500693) (xy 261.049309 -28.514799) (xy 260.993872 -28.520899)
			(xy 260.938138 -28.518862) (xy 260.883295 -28.508732) (xy 260.830511 -28.490725) (xy 260.780911 -28.465224)
			(xy 260.735553 -28.432773) (xy 260.695404 -28.394064) (xy 260.661318 -28.349921) (xy 260.634022 -28.301286)
			(xy 260.614099 -28.249195) (xy 260.601973 -28.194758) (xy 260.597902 -28.139136) (xy 256.525245 -28.139136)
			(xy 256.556795 -28.158391) (xy 256.599663 -28.194066) (xy 256.63688 -28.235603) (xy 256.667653 -28.282116)
			(xy 256.691325 -28.332613) (xy 256.707393 -28.38602) (xy 256.715513 -28.441196) (xy 256.716022 -28.469082)
			(xy 256.715513 -28.496968) (xy 256.707393 -28.552144) (xy 256.691325 -28.605551) (xy 256.667653 -28.656048)
			(xy 256.63688 -28.702561) (xy 256.599663 -28.744098) (xy 256.556795 -28.779773) (xy 256.509189 -28.808827)
			(xy 256.45786 -28.830639) (xy 256.403903 -28.844745) (xy 256.348466 -28.850845) (xy 256.292732 -28.848808)
			(xy 256.237889 -28.838678) (xy 256.185105 -28.820671) (xy 256.135505 -28.79517) (xy 256.090147 -28.762719)
			(xy 256.049998 -28.72401) (xy 256.015912 -28.679867) (xy 255.988616 -28.631232) (xy 255.968693 -28.579141)
			(xy 255.956567 -28.524704) (xy 255.952496 -28.469082) (xy 251.96292 -28.469082) (xy 251.96292 -29.114242)
			(xy 251.962787 -29.12237) (xy 266.80668 -29.12237) (xy 266.80668 -28.25877) (xy 266.80717 -28.228786)
			(xy 266.814998 -28.16933) (xy 266.830519 -28.111405) (xy 266.853468 -28.056001) (xy 266.883452 -28.004067)
			(xy 266.919958 -27.956491) (xy 266.962363 -27.914086) (xy 267.009939 -27.87758) (xy 267.061873 -27.847596)
			(xy 267.117277 -27.824647) (xy 267.175202 -27.809126) (xy 267.234658 -27.801298) (xy 267.294626 -27.801298)
			(xy 267.354082 -27.809126) (xy 267.412007 -27.824647) (xy 267.467411 -27.847596) (xy 267.519345 -27.87758)
			(xy 267.566921 -27.914086) (xy 267.609326 -27.956491) (xy 267.645832 -28.004067) (xy 267.675816 -28.056001)
			(xy 267.698765 -28.111405) (xy 267.714286 -28.16933) (xy 267.722114 -28.228786) (xy 267.722604 -28.25877)
			(xy 267.722604 -29.114242) (xy 277.047452 -29.114242) (xy 277.047452 -28.250642) (xy 277.047942 -28.220674)
			(xy 277.055765 -28.161252) (xy 277.071278 -28.103359) (xy 277.094214 -28.047986) (xy 277.124181 -27.99608)
			(xy 277.160668 -27.94853) (xy 277.203048 -27.90615) (xy 277.250598 -27.869663) (xy 277.302504 -27.839696)
			(xy 277.357877 -27.81676) (xy 277.41577 -27.801247) (xy 277.475192 -27.793424) (xy 277.535128 -27.793424)
			(xy 277.59455 -27.801247) (xy 277.652443 -27.81676) (xy 277.707816 -27.839696) (xy 277.759722 -27.869663)
			(xy 277.807272 -27.90615) (xy 277.849652 -27.94853) (xy 277.886139 -27.99608) (xy 277.916106 -28.047986)
			(xy 277.939042 -28.103359) (xy 277.954555 -28.161252) (xy 277.962378 -28.220674) (xy 277.962868 -28.250642)
			(xy 277.962868 -28.469082) (xy 281.952444 -28.469082) (xy 281.956515 -28.41346) (xy 281.968641 -28.359023)
			(xy 281.988564 -28.306932) (xy 282.01586 -28.258297) (xy 282.049946 -28.214154) (xy 282.090095 -28.175445)
			(xy 282.135453 -28.142994) (xy 282.185053 -28.117493) (xy 282.237837 -28.099486) (xy 282.29268 -28.089356)
			(xy 282.348414 -28.087319) (xy 282.403851 -28.093419) (xy 282.457808 -28.107525) (xy 282.509137 -28.129337)
			(xy 282.525193 -28.139136) (xy 286.59785 -28.139136) (xy 286.601921 -28.083514) (xy 286.614047 -28.029077)
			(xy 286.63397 -27.976986) (xy 286.661266 -27.928351) (xy 286.695352 -27.884208) (xy 286.735501 -27.845499)
			(xy 286.780859 -27.813048) (xy 286.830459 -27.787547) (xy 286.883243 -27.76954) (xy 286.938086 -27.75941)
			(xy 286.99382 -27.757373) (xy 287.049257 -27.763473) (xy 287.103214 -27.777579) (xy 287.154543 -27.799391)
			(xy 287.202149 -27.828445) (xy 287.245017 -27.86412) (xy 287.282234 -27.905657) (xy 287.313007 -27.95217)
			(xy 287.336679 -28.002667) (xy 287.352747 -28.056074) (xy 287.360867 -28.11125) (xy 287.361376 -28.139136)
			(xy 287.86785 -28.139136) (xy 287.871921 -28.083514) (xy 287.884047 -28.029077) (xy 287.90397 -27.976986)
			(xy 287.931266 -27.928351) (xy 287.965352 -27.884208) (xy 288.005501 -27.845499) (xy 288.050859 -27.813048)
			(xy 288.100459 -27.787547) (xy 288.153243 -27.76954) (xy 288.208086 -27.75941) (xy 288.26382 -27.757373)
			(xy 288.319257 -27.763473) (xy 288.373214 -27.777579) (xy 288.424543 -27.799391) (xy 288.472149 -27.828445)
			(xy 288.515017 -27.86412) (xy 288.552234 -27.905657) (xy 288.583007 -27.95217) (xy 288.606679 -28.002667)
			(xy 288.622747 -28.056074) (xy 288.630867 -28.11125) (xy 288.631376 -28.139136) (xy 288.630867 -28.167022)
			(xy 288.622747 -28.222198) (xy 288.606679 -28.275605) (xy 288.583007 -28.326102) (xy 288.552234 -28.372615)
			(xy 288.515017 -28.414152) (xy 288.472149 -28.449827) (xy 288.424543 -28.478881) (xy 288.373214 -28.500693)
			(xy 288.319257 -28.514799) (xy 288.26382 -28.520899) (xy 288.208086 -28.518862) (xy 288.153243 -28.508732)
			(xy 288.100459 -28.490725) (xy 288.050859 -28.465224) (xy 288.005501 -28.432773) (xy 287.965352 -28.394064)
			(xy 287.931266 -28.349921) (xy 287.90397 -28.301286) (xy 287.884047 -28.249195) (xy 287.871921 -28.194758)
			(xy 287.86785 -28.139136) (xy 287.361376 -28.139136) (xy 287.360867 -28.167022) (xy 287.352747 -28.222198)
			(xy 287.336679 -28.275605) (xy 287.313007 -28.326102) (xy 287.282234 -28.372615) (xy 287.245017 -28.414152)
			(xy 287.202149 -28.449827) (xy 287.154543 -28.478881) (xy 287.103214 -28.500693) (xy 287.049257 -28.514799)
			(xy 286.99382 -28.520899) (xy 286.938086 -28.518862) (xy 286.883243 -28.508732) (xy 286.830459 -28.490725)
			(xy 286.780859 -28.465224) (xy 286.735501 -28.432773) (xy 286.695352 -28.394064) (xy 286.661266 -28.349921)
			(xy 286.63397 -28.301286) (xy 286.614047 -28.249195) (xy 286.601921 -28.194758) (xy 286.59785 -28.139136)
			(xy 282.525193 -28.139136) (xy 282.556743 -28.158391) (xy 282.599611 -28.194066) (xy 282.636828 -28.235603)
			(xy 282.667601 -28.282116) (xy 282.691273 -28.332613) (xy 282.707341 -28.38602) (xy 282.715461 -28.441196)
			(xy 282.71597 -28.469082) (xy 282.715461 -28.496968) (xy 282.707341 -28.552144) (xy 282.691273 -28.605551)
			(xy 282.667601 -28.656048) (xy 282.636828 -28.702561) (xy 282.599611 -28.744098) (xy 282.556743 -28.779773)
			(xy 282.509137 -28.808827) (xy 282.457808 -28.830639) (xy 282.403851 -28.844745) (xy 282.348414 -28.850845)
			(xy 282.29268 -28.848808) (xy 282.237837 -28.838678) (xy 282.185053 -28.820671) (xy 282.135453 -28.79517)
			(xy 282.090095 -28.762719) (xy 282.049946 -28.72401) (xy 282.01586 -28.679867) (xy 281.988564 -28.631232)
			(xy 281.968641 -28.579141) (xy 281.956515 -28.524704) (xy 281.952444 -28.469082) (xy 277.962868 -28.469082)
			(xy 277.962868 -29.114242) (xy 277.962735 -29.12237) (xy 292.806628 -29.12237) (xy 292.806628 -28.25877)
			(xy 292.807118 -28.228786) (xy 292.814946 -28.16933) (xy 292.830467 -28.111405) (xy 292.853416 -28.056001)
			(xy 292.8834 -28.004067) (xy 292.919906 -27.956491) (xy 292.962311 -27.914086) (xy 293.009887 -27.87758)
			(xy 293.061821 -27.847596) (xy 293.117225 -27.824647) (xy 293.17515 -27.809126) (xy 293.234606 -27.801298)
			(xy 293.294574 -27.801298) (xy 293.35403 -27.809126) (xy 293.411955 -27.824647) (xy 293.467359 -27.847596)
			(xy 293.519293 -27.87758) (xy 293.566869 -27.914086) (xy 293.609274 -27.956491) (xy 293.64578 -28.004067)
			(xy 293.675764 -28.056001) (xy 293.698713 -28.111405) (xy 293.714234 -28.16933) (xy 293.722062 -28.228786)
			(xy 293.722552 -28.25877) (xy 293.722552 -29.114242) (xy 303.0474 -29.114242) (xy 303.0474 -28.250642)
			(xy 303.04789 -28.220674) (xy 303.055713 -28.161252) (xy 303.071226 -28.103359) (xy 303.094162 -28.047986)
			(xy 303.124129 -27.99608) (xy 303.160616 -27.94853) (xy 303.202996 -27.90615) (xy 303.250546 -27.869663)
			(xy 303.302452 -27.839696) (xy 303.357825 -27.81676) (xy 303.415718 -27.801247) (xy 303.47514 -27.793424)
			(xy 303.535076 -27.793424) (xy 303.594498 -27.801247) (xy 303.652391 -27.81676) (xy 303.707764 -27.839696)
			(xy 303.75967 -27.869663) (xy 303.80722 -27.90615) (xy 303.8496 -27.94853) (xy 303.886087 -27.99608)
			(xy 303.916054 -28.047986) (xy 303.93899 -28.103359) (xy 303.954503 -28.161252) (xy 303.962326 -28.220674)
			(xy 303.962816 -28.250642) (xy 303.962816 -28.469082) (xy 307.952392 -28.469082) (xy 307.956463 -28.41346)
			(xy 307.968589 -28.359023) (xy 307.988512 -28.306932) (xy 308.015808 -28.258297) (xy 308.049894 -28.214154)
			(xy 308.090043 -28.175445) (xy 308.135401 -28.142994) (xy 308.185001 -28.117493) (xy 308.237785 -28.099486)
			(xy 308.292628 -28.089356) (xy 308.348362 -28.087319) (xy 308.403799 -28.093419) (xy 308.457756 -28.107525)
			(xy 308.509085 -28.129337) (xy 308.525141 -28.139136) (xy 312.597798 -28.139136) (xy 312.601869 -28.083514)
			(xy 312.613995 -28.029077) (xy 312.633918 -27.976986) (xy 312.661214 -27.928351) (xy 312.6953 -27.884208)
			(xy 312.735449 -27.845499) (xy 312.780807 -27.813048) (xy 312.830407 -27.787547) (xy 312.883191 -27.76954)
			(xy 312.938034 -27.75941) (xy 312.993768 -27.757373) (xy 313.049205 -27.763473) (xy 313.103162 -27.777579)
			(xy 313.154491 -27.799391) (xy 313.202097 -27.828445) (xy 313.244965 -27.86412) (xy 313.282182 -27.905657)
			(xy 313.312955 -27.95217) (xy 313.336627 -28.002667) (xy 313.352695 -28.056074) (xy 313.360815 -28.11125)
			(xy 313.361324 -28.139136) (xy 313.867798 -28.139136) (xy 313.871869 -28.083514) (xy 313.883995 -28.029077)
			(xy 313.903918 -27.976986) (xy 313.931214 -27.928351) (xy 313.9653 -27.884208) (xy 314.005449 -27.845499)
			(xy 314.050807 -27.813048) (xy 314.100407 -27.787547) (xy 314.153191 -27.76954) (xy 314.208034 -27.75941)
			(xy 314.263768 -27.757373) (xy 314.319205 -27.763473) (xy 314.373162 -27.777579) (xy 314.424491 -27.799391)
			(xy 314.472097 -27.828445) (xy 314.514965 -27.86412) (xy 314.552182 -27.905657) (xy 314.582955 -27.95217)
			(xy 314.606627 -28.002667) (xy 314.622695 -28.056074) (xy 314.630815 -28.11125) (xy 314.631324 -28.139136)
			(xy 314.630815 -28.167022) (xy 314.622695 -28.222198) (xy 314.606627 -28.275605) (xy 314.582955 -28.326102)
			(xy 314.552182 -28.372615) (xy 314.514965 -28.414152) (xy 314.472097 -28.449827) (xy 314.424491 -28.478881)
			(xy 314.373162 -28.500693) (xy 314.319205 -28.514799) (xy 314.263768 -28.520899) (xy 314.208034 -28.518862)
			(xy 314.153191 -28.508732) (xy 314.100407 -28.490725) (xy 314.050807 -28.465224) (xy 314.005449 -28.432773)
			(xy 313.9653 -28.394064) (xy 313.931214 -28.349921) (xy 313.903918 -28.301286) (xy 313.883995 -28.249195)
			(xy 313.871869 -28.194758) (xy 313.867798 -28.139136) (xy 313.361324 -28.139136) (xy 313.360815 -28.167022)
			(xy 313.352695 -28.222198) (xy 313.336627 -28.275605) (xy 313.312955 -28.326102) (xy 313.282182 -28.372615)
			(xy 313.244965 -28.414152) (xy 313.202097 -28.449827) (xy 313.154491 -28.478881) (xy 313.103162 -28.500693)
			(xy 313.049205 -28.514799) (xy 312.993768 -28.520899) (xy 312.938034 -28.518862) (xy 312.883191 -28.508732)
			(xy 312.830407 -28.490725) (xy 312.780807 -28.465224) (xy 312.735449 -28.432773) (xy 312.6953 -28.394064)
			(xy 312.661214 -28.349921) (xy 312.633918 -28.301286) (xy 312.613995 -28.249195) (xy 312.601869 -28.194758)
			(xy 312.597798 -28.139136) (xy 308.525141 -28.139136) (xy 308.556691 -28.158391) (xy 308.599559 -28.194066)
			(xy 308.636776 -28.235603) (xy 308.667549 -28.282116) (xy 308.691221 -28.332613) (xy 308.707289 -28.38602)
			(xy 308.715409 -28.441196) (xy 308.715918 -28.469082) (xy 308.715409 -28.496968) (xy 308.707289 -28.552144)
			(xy 308.691221 -28.605551) (xy 308.667549 -28.656048) (xy 308.636776 -28.702561) (xy 308.599559 -28.744098)
			(xy 308.556691 -28.779773) (xy 308.509085 -28.808827) (xy 308.457756 -28.830639) (xy 308.403799 -28.844745)
			(xy 308.348362 -28.850845) (xy 308.292628 -28.848808) (xy 308.237785 -28.838678) (xy 308.185001 -28.820671)
			(xy 308.135401 -28.79517) (xy 308.090043 -28.762719) (xy 308.049894 -28.72401) (xy 308.015808 -28.679867)
			(xy 307.988512 -28.631232) (xy 307.968589 -28.579141) (xy 307.956463 -28.524704) (xy 307.952392 -28.469082)
			(xy 303.962816 -28.469082) (xy 303.962816 -29.114242) (xy 303.962683 -29.12237) (xy 318.806576 -29.12237)
			(xy 318.806576 -28.25877) (xy 318.807066 -28.228786) (xy 318.814894 -28.16933) (xy 318.830415 -28.111405)
			(xy 318.853364 -28.056001) (xy 318.883348 -28.004067) (xy 318.919854 -27.956491) (xy 318.962259 -27.914086)
			(xy 319.009835 -27.87758) (xy 319.061769 -27.847596) (xy 319.117173 -27.824647) (xy 319.175098 -27.809126)
			(xy 319.234554 -27.801298) (xy 319.294522 -27.801298) (xy 319.353978 -27.809126) (xy 319.411903 -27.824647)
			(xy 319.467307 -27.847596) (xy 319.519241 -27.87758) (xy 319.566817 -27.914086) (xy 319.609222 -27.956491)
			(xy 319.645728 -28.004067) (xy 319.675712 -28.056001) (xy 319.698661 -28.111405) (xy 319.714182 -28.16933)
			(xy 319.72201 -28.228786) (xy 319.7225 -28.25877) (xy 319.7225 -29.114242) (xy 329.047348 -29.114242)
			(xy 329.047348 -28.250642) (xy 329.047838 -28.220674) (xy 329.055661 -28.161252) (xy 329.071174 -28.103359)
			(xy 329.09411 -28.047986) (xy 329.124077 -27.99608) (xy 329.160564 -27.94853) (xy 329.202944 -27.90615)
			(xy 329.250494 -27.869663) (xy 329.3024 -27.839696) (xy 329.357773 -27.81676) (xy 329.415666 -27.801247)
			(xy 329.475088 -27.793424) (xy 329.535024 -27.793424) (xy 329.594446 -27.801247) (xy 329.652339 -27.81676)
			(xy 329.707712 -27.839696) (xy 329.759618 -27.869663) (xy 329.807168 -27.90615) (xy 329.849548 -27.94853)
			(xy 329.886035 -27.99608) (xy 329.916002 -28.047986) (xy 329.938938 -28.103359) (xy 329.954451 -28.161252)
			(xy 329.962274 -28.220674) (xy 329.962764 -28.250642) (xy 329.962764 -28.469082) (xy 333.95234 -28.469082)
			(xy 333.956411 -28.41346) (xy 333.968537 -28.359023) (xy 333.98846 -28.306932) (xy 334.015756 -28.258297)
			(xy 334.049842 -28.214154) (xy 334.089991 -28.175445) (xy 334.135349 -28.142994) (xy 334.184949 -28.117493)
			(xy 334.237733 -28.099486) (xy 334.292576 -28.089356) (xy 334.34831 -28.087319) (xy 334.403747 -28.093419)
			(xy 334.457704 -28.107525) (xy 334.509033 -28.129337) (xy 334.525089 -28.139136) (xy 350.698052 -28.139136)
			(xy 350.702123 -28.083514) (xy 350.714249 -28.029077) (xy 350.734172 -27.976986) (xy 350.761468 -27.928351)
			(xy 350.795554 -27.884208) (xy 350.835703 -27.845499) (xy 350.881061 -27.813048) (xy 350.930661 -27.787547)
			(xy 350.983445 -27.76954) (xy 351.038288 -27.75941) (xy 351.094022 -27.757373) (xy 351.149459 -27.763473)
			(xy 351.203416 -27.777579) (xy 351.254745 -27.799391) (xy 351.302351 -27.828445) (xy 351.345219 -27.86412)
			(xy 351.382436 -27.905657) (xy 351.413209 -27.95217) (xy 351.436881 -28.002667) (xy 351.452949 -28.056074)
			(xy 351.461069 -28.11125) (xy 351.461578 -28.139136) (xy 351.968052 -28.139136) (xy 351.972123 -28.083514)
			(xy 351.984249 -28.029077) (xy 352.004172 -27.976986) (xy 352.031468 -27.928351) (xy 352.065554 -27.884208)
			(xy 352.105703 -27.845499) (xy 352.151061 -27.813048) (xy 352.200661 -27.787547) (xy 352.253445 -27.76954)
			(xy 352.308288 -27.75941) (xy 352.364022 -27.757373) (xy 352.419459 -27.763473) (xy 352.473416 -27.777579)
			(xy 352.524745 -27.799391) (xy 352.572351 -27.828445) (xy 352.615219 -27.86412) (xy 352.652436 -27.905657)
			(xy 352.683209 -27.95217) (xy 352.706881 -28.002667) (xy 352.722949 -28.056074) (xy 352.731069 -28.11125)
			(xy 352.731578 -28.139136) (xy 352.731069 -28.167022) (xy 352.722949 -28.222198) (xy 352.706881 -28.275605)
			(xy 352.683209 -28.326102) (xy 352.652436 -28.372615) (xy 352.615219 -28.414152) (xy 352.572351 -28.449827)
			(xy 352.524745 -28.478881) (xy 352.473416 -28.500693) (xy 352.419459 -28.514799) (xy 352.364022 -28.520899)
			(xy 352.308288 -28.518862) (xy 352.253445 -28.508732) (xy 352.200661 -28.490725) (xy 352.151061 -28.465224)
			(xy 352.105703 -28.432773) (xy 352.065554 -28.394064) (xy 352.031468 -28.349921) (xy 352.004172 -28.301286)
			(xy 351.984249 -28.249195) (xy 351.972123 -28.194758) (xy 351.968052 -28.139136) (xy 351.461578 -28.139136)
			(xy 351.461069 -28.167022) (xy 351.452949 -28.222198) (xy 351.436881 -28.275605) (xy 351.413209 -28.326102)
			(xy 351.382436 -28.372615) (xy 351.345219 -28.414152) (xy 351.302351 -28.449827) (xy 351.254745 -28.478881)
			(xy 351.203416 -28.500693) (xy 351.149459 -28.514799) (xy 351.094022 -28.520899) (xy 351.038288 -28.518862)
			(xy 350.983445 -28.508732) (xy 350.930661 -28.490725) (xy 350.881061 -28.465224) (xy 350.835703 -28.432773)
			(xy 350.795554 -28.394064) (xy 350.761468 -28.349921) (xy 350.734172 -28.301286) (xy 350.714249 -28.249195)
			(xy 350.702123 -28.194758) (xy 350.698052 -28.139136) (xy 334.525089 -28.139136) (xy 334.556639 -28.158391)
			(xy 334.599507 -28.194066) (xy 334.636724 -28.235603) (xy 334.667497 -28.282116) (xy 334.691169 -28.332613)
			(xy 334.707237 -28.38602) (xy 334.715357 -28.441196) (xy 334.715866 -28.469082) (xy 334.715357 -28.496968)
			(xy 334.707237 -28.552144) (xy 334.691169 -28.605551) (xy 334.667497 -28.656048) (xy 334.636724 -28.702561)
			(xy 334.599507 -28.744098) (xy 334.556639 -28.779773) (xy 334.509033 -28.808827) (xy 334.457704 -28.830639)
			(xy 334.403747 -28.844745) (xy 334.34831 -28.850845) (xy 334.292576 -28.848808) (xy 334.237733 -28.838678)
			(xy 334.184949 -28.820671) (xy 334.135349 -28.79517) (xy 334.089991 -28.762719) (xy 334.049842 -28.72401)
			(xy 334.015756 -28.679867) (xy 333.98846 -28.631232) (xy 333.968537 -28.579141) (xy 333.956411 -28.524704)
			(xy 333.95234 -28.469082) (xy 329.962764 -28.469082) (xy 329.962764 -29.114242) (xy 329.962631 -29.12237)
			(xy 356.907084 -29.12237) (xy 356.907084 -28.25877) (xy 356.907574 -28.228802) (xy 356.915397 -28.16938)
			(xy 356.93091 -28.111487) (xy 356.953846 -28.056114) (xy 356.983813 -28.004208) (xy 357.0203 -27.956658)
			(xy 357.06268 -27.914278) (xy 357.11023 -27.877791) (xy 357.162136 -27.847824) (xy 357.217509 -27.824888)
			(xy 357.275402 -27.809375) (xy 357.334824 -27.801552) (xy 357.39476 -27.801552) (xy 357.454182 -27.809375)
			(xy 357.512075 -27.824888) (xy 357.567448 -27.847824) (xy 357.619354 -27.877791) (xy 357.666904 -27.914278)
			(xy 357.709284 -27.956658) (xy 357.745771 -28.004208) (xy 357.775738 -28.056114) (xy 357.798674 -28.111487)
			(xy 357.814187 -28.16938) (xy 357.82201 -28.228802) (xy 357.8225 -28.25877) (xy 357.8225 -29.114242)
			(xy 367.147348 -29.114242) (xy 367.147348 -28.250642) (xy 367.147838 -28.220658) (xy 367.155666 -28.161202)
			(xy 367.171187 -28.103277) (xy 367.194136 -28.047873) (xy 367.22412 -27.995939) (xy 367.260626 -27.948363)
			(xy 367.303031 -27.905958) (xy 367.350607 -27.869452) (xy 367.402541 -27.839468) (xy 367.457945 -27.816519)
			(xy 367.51587 -27.800998) (xy 367.575326 -27.79317) (xy 367.635294 -27.79317) (xy 367.69475 -27.800998)
			(xy 367.752675 -27.816519) (xy 367.808079 -27.839468) (xy 367.860013 -27.869452) (xy 367.907589 -27.905958)
			(xy 367.949994 -27.948363) (xy 367.9865 -27.995939) (xy 368.016484 -28.047873) (xy 368.039433 -28.103277)
			(xy 368.054954 -28.161202) (xy 368.062782 -28.220658) (xy 368.063272 -28.250642) (xy 368.063272 -28.469082)
			(xy 372.052594 -28.469082) (xy 372.056665 -28.41346) (xy 372.068791 -28.359023) (xy 372.088714 -28.306932)
			(xy 372.11601 -28.258297) (xy 372.150096 -28.214154) (xy 372.190245 -28.175445) (xy 372.235603 -28.142994)
			(xy 372.285203 -28.117493) (xy 372.337987 -28.099486) (xy 372.39283 -28.089356) (xy 372.448564 -28.087319)
			(xy 372.504001 -28.093419) (xy 372.557958 -28.107525) (xy 372.609287 -28.129337) (xy 372.625343 -28.139136)
			(xy 376.698 -28.139136) (xy 376.702071 -28.083514) (xy 376.714197 -28.029077) (xy 376.73412 -27.976986)
			(xy 376.761416 -27.928351) (xy 376.795502 -27.884208) (xy 376.835651 -27.845499) (xy 376.881009 -27.813048)
			(xy 376.930609 -27.787547) (xy 376.983393 -27.76954) (xy 377.038236 -27.75941) (xy 377.09397 -27.757373)
			(xy 377.149407 -27.763473) (xy 377.203364 -27.777579) (xy 377.254693 -27.799391) (xy 377.302299 -27.828445)
			(xy 377.345167 -27.86412) (xy 377.382384 -27.905657) (xy 377.413157 -27.95217) (xy 377.436829 -28.002667)
			(xy 377.452897 -28.056074) (xy 377.461017 -28.11125) (xy 377.461526 -28.139136) (xy 377.968 -28.139136)
			(xy 377.972071 -28.083514) (xy 377.984197 -28.029077) (xy 378.00412 -27.976986) (xy 378.031416 -27.928351)
			(xy 378.065502 -27.884208) (xy 378.105651 -27.845499) (xy 378.151009 -27.813048) (xy 378.200609 -27.787547)
			(xy 378.253393 -27.76954) (xy 378.308236 -27.75941) (xy 378.36397 -27.757373) (xy 378.419407 -27.763473)
			(xy 378.473364 -27.777579) (xy 378.524693 -27.799391) (xy 378.572299 -27.828445) (xy 378.615167 -27.86412)
			(xy 378.652384 -27.905657) (xy 378.683157 -27.95217) (xy 378.706829 -28.002667) (xy 378.722897 -28.056074)
			(xy 378.731017 -28.11125) (xy 378.731526 -28.139136) (xy 378.731017 -28.167022) (xy 378.722897 -28.222198)
			(xy 378.706829 -28.275605) (xy 378.683157 -28.326102) (xy 378.652384 -28.372615) (xy 378.615167 -28.414152)
			(xy 378.572299 -28.449827) (xy 378.524693 -28.478881) (xy 378.473364 -28.500693) (xy 378.419407 -28.514799)
			(xy 378.36397 -28.520899) (xy 378.308236 -28.518862) (xy 378.253393 -28.508732) (xy 378.200609 -28.490725)
			(xy 378.151009 -28.465224) (xy 378.105651 -28.432773) (xy 378.065502 -28.394064) (xy 378.031416 -28.349921)
			(xy 378.00412 -28.301286) (xy 377.984197 -28.249195) (xy 377.972071 -28.194758) (xy 377.968 -28.139136)
			(xy 377.461526 -28.139136) (xy 377.461017 -28.167022) (xy 377.452897 -28.222198) (xy 377.436829 -28.275605)
			(xy 377.413157 -28.326102) (xy 377.382384 -28.372615) (xy 377.345167 -28.414152) (xy 377.302299 -28.449827)
			(xy 377.254693 -28.478881) (xy 377.203364 -28.500693) (xy 377.149407 -28.514799) (xy 377.09397 -28.520899)
			(xy 377.038236 -28.518862) (xy 376.983393 -28.508732) (xy 376.930609 -28.490725) (xy 376.881009 -28.465224)
			(xy 376.835651 -28.432773) (xy 376.795502 -28.394064) (xy 376.761416 -28.349921) (xy 376.73412 -28.301286)
			(xy 376.714197 -28.249195) (xy 376.702071 -28.194758) (xy 376.698 -28.139136) (xy 372.625343 -28.139136)
			(xy 372.656893 -28.158391) (xy 372.699761 -28.194066) (xy 372.736978 -28.235603) (xy 372.767751 -28.282116)
			(xy 372.791423 -28.332613) (xy 372.807491 -28.38602) (xy 372.815611 -28.441196) (xy 372.81612 -28.469082)
			(xy 372.815611 -28.496968) (xy 372.807491 -28.552144) (xy 372.791423 -28.605551) (xy 372.767751 -28.656048)
			(xy 372.736978 -28.702561) (xy 372.699761 -28.744098) (xy 372.656893 -28.779773) (xy 372.609287 -28.808827)
			(xy 372.557958 -28.830639) (xy 372.504001 -28.844745) (xy 372.448564 -28.850845) (xy 372.39283 -28.848808)
			(xy 372.337987 -28.838678) (xy 372.285203 -28.820671) (xy 372.235603 -28.79517) (xy 372.190245 -28.762719)
			(xy 372.150096 -28.72401) (xy 372.11601 -28.679867) (xy 372.088714 -28.631232) (xy 372.068791 -28.579141)
			(xy 372.056665 -28.524704) (xy 372.052594 -28.469082) (xy 368.063272 -28.469082) (xy 368.063272 -29.114242)
			(xy 368.063139 -29.12237) (xy 382.907032 -29.12237) (xy 382.907032 -28.25877) (xy 382.907522 -28.228802)
			(xy 382.915345 -28.16938) (xy 382.930858 -28.111487) (xy 382.953794 -28.056114) (xy 382.983761 -28.004208)
			(xy 383.020248 -27.956658) (xy 383.062628 -27.914278) (xy 383.110178 -27.877791) (xy 383.162084 -27.847824)
			(xy 383.217457 -27.824888) (xy 383.27535 -27.809375) (xy 383.334772 -27.801552) (xy 383.394708 -27.801552)
			(xy 383.45413 -27.809375) (xy 383.512023 -27.824888) (xy 383.567396 -27.847824) (xy 383.619302 -27.877791)
			(xy 383.666852 -27.914278) (xy 383.709232 -27.956658) (xy 383.745719 -28.004208) (xy 383.775686 -28.056114)
			(xy 383.798622 -28.111487) (xy 383.814135 -28.16938) (xy 383.821958 -28.228802) (xy 383.822448 -28.25877)
			(xy 383.822448 -29.114242) (xy 393.147296 -29.114242) (xy 393.147296 -28.250642) (xy 393.147786 -28.220658)
			(xy 393.155614 -28.161202) (xy 393.171135 -28.103277) (xy 393.194084 -28.047873) (xy 393.224068 -27.995939)
			(xy 393.260574 -27.948363) (xy 393.302979 -27.905958) (xy 393.350555 -27.869452) (xy 393.402489 -27.839468)
			(xy 393.457893 -27.816519) (xy 393.515818 -27.800998) (xy 393.575274 -27.79317) (xy 393.635242 -27.79317)
			(xy 393.694698 -27.800998) (xy 393.752623 -27.816519) (xy 393.808027 -27.839468) (xy 393.859961 -27.869452)
			(xy 393.907537 -27.905958) (xy 393.949942 -27.948363) (xy 393.986448 -27.995939) (xy 394.016432 -28.047873)
			(xy 394.039381 -28.103277) (xy 394.054902 -28.161202) (xy 394.06273 -28.220658) (xy 394.06322 -28.250642)
			(xy 394.06322 -28.469082) (xy 398.052542 -28.469082) (xy 398.056613 -28.41346) (xy 398.068739 -28.359023)
			(xy 398.088662 -28.306932) (xy 398.115958 -28.258297) (xy 398.150044 -28.214154) (xy 398.190193 -28.175445)
			(xy 398.235551 -28.142994) (xy 398.285151 -28.117493) (xy 398.337935 -28.099486) (xy 398.392778 -28.089356)
			(xy 398.448512 -28.087319) (xy 398.503949 -28.093419) (xy 398.557906 -28.107525) (xy 398.609235 -28.129337)
			(xy 398.625291 -28.139136) (xy 402.697948 -28.139136) (xy 402.702019 -28.083514) (xy 402.714145 -28.029077)
			(xy 402.734068 -27.976986) (xy 402.761364 -27.928351) (xy 402.79545 -27.884208) (xy 402.835599 -27.845499)
			(xy 402.880957 -27.813048) (xy 402.930557 -27.787547) (xy 402.983341 -27.76954) (xy 403.038184 -27.75941)
			(xy 403.093918 -27.757373) (xy 403.149355 -27.763473) (xy 403.203312 -27.777579) (xy 403.254641 -27.799391)
			(xy 403.302247 -27.828445) (xy 403.345115 -27.86412) (xy 403.382332 -27.905657) (xy 403.413105 -27.95217)
			(xy 403.436777 -28.002667) (xy 403.452845 -28.056074) (xy 403.460965 -28.11125) (xy 403.461474 -28.139136)
			(xy 403.967948 -28.139136) (xy 403.972019 -28.083514) (xy 403.984145 -28.029077) (xy 404.004068 -27.976986)
			(xy 404.031364 -27.928351) (xy 404.06545 -27.884208) (xy 404.105599 -27.845499) (xy 404.150957 -27.813048)
			(xy 404.200557 -27.787547) (xy 404.253341 -27.76954) (xy 404.308184 -27.75941) (xy 404.363918 -27.757373)
			(xy 404.419355 -27.763473) (xy 404.473312 -27.777579) (xy 404.524641 -27.799391) (xy 404.572247 -27.828445)
			(xy 404.615115 -27.86412) (xy 404.652332 -27.905657) (xy 404.683105 -27.95217) (xy 404.706777 -28.002667)
			(xy 404.722845 -28.056074) (xy 404.730965 -28.11125) (xy 404.731474 -28.139136) (xy 404.730965 -28.167022)
			(xy 404.722845 -28.222198) (xy 404.706777 -28.275605) (xy 404.683105 -28.326102) (xy 404.652332 -28.372615)
			(xy 404.615115 -28.414152) (xy 404.572247 -28.449827) (xy 404.524641 -28.478881) (xy 404.473312 -28.500693)
			(xy 404.419355 -28.514799) (xy 404.363918 -28.520899) (xy 404.308184 -28.518862) (xy 404.253341 -28.508732)
			(xy 404.200557 -28.490725) (xy 404.150957 -28.465224) (xy 404.105599 -28.432773) (xy 404.06545 -28.394064)
			(xy 404.031364 -28.349921) (xy 404.004068 -28.301286) (xy 403.984145 -28.249195) (xy 403.972019 -28.194758)
			(xy 403.967948 -28.139136) (xy 403.461474 -28.139136) (xy 403.460965 -28.167022) (xy 403.452845 -28.222198)
			(xy 403.436777 -28.275605) (xy 403.413105 -28.326102) (xy 403.382332 -28.372615) (xy 403.345115 -28.414152)
			(xy 403.302247 -28.449827) (xy 403.254641 -28.478881) (xy 403.203312 -28.500693) (xy 403.149355 -28.514799)
			(xy 403.093918 -28.520899) (xy 403.038184 -28.518862) (xy 402.983341 -28.508732) (xy 402.930557 -28.490725)
			(xy 402.880957 -28.465224) (xy 402.835599 -28.432773) (xy 402.79545 -28.394064) (xy 402.761364 -28.349921)
			(xy 402.734068 -28.301286) (xy 402.714145 -28.249195) (xy 402.702019 -28.194758) (xy 402.697948 -28.139136)
			(xy 398.625291 -28.139136) (xy 398.656841 -28.158391) (xy 398.699709 -28.194066) (xy 398.736926 -28.235603)
			(xy 398.767699 -28.282116) (xy 398.791371 -28.332613) (xy 398.807439 -28.38602) (xy 398.815559 -28.441196)
			(xy 398.816068 -28.469082) (xy 398.815559 -28.496968) (xy 398.807439 -28.552144) (xy 398.791371 -28.605551)
			(xy 398.767699 -28.656048) (xy 398.736926 -28.702561) (xy 398.699709 -28.744098) (xy 398.656841 -28.779773)
			(xy 398.609235 -28.808827) (xy 398.557906 -28.830639) (xy 398.503949 -28.844745) (xy 398.448512 -28.850845)
			(xy 398.392778 -28.848808) (xy 398.337935 -28.838678) (xy 398.285151 -28.820671) (xy 398.235551 -28.79517)
			(xy 398.190193 -28.762719) (xy 398.150044 -28.72401) (xy 398.115958 -28.679867) (xy 398.088662 -28.631232)
			(xy 398.068739 -28.579141) (xy 398.056613 -28.524704) (xy 398.052542 -28.469082) (xy 394.06322 -28.469082)
			(xy 394.06322 -29.114242) (xy 394.063087 -29.12237) (xy 408.90698 -29.12237) (xy 408.90698 -28.25877)
			(xy 408.90747 -28.228802) (xy 408.915293 -28.16938) (xy 408.930806 -28.111487) (xy 408.953742 -28.056114)
			(xy 408.983709 -28.004208) (xy 409.020196 -27.956658) (xy 409.062576 -27.914278) (xy 409.110126 -27.877791)
			(xy 409.162032 -27.847824) (xy 409.217405 -27.824888) (xy 409.275298 -27.809375) (xy 409.33472 -27.801552)
			(xy 409.394656 -27.801552) (xy 409.454078 -27.809375) (xy 409.511971 -27.824888) (xy 409.567344 -27.847824)
			(xy 409.61925 -27.877791) (xy 409.6668 -27.914278) (xy 409.70918 -27.956658) (xy 409.745667 -28.004208)
			(xy 409.775634 -28.056114) (xy 409.79857 -28.111487) (xy 409.814083 -28.16938) (xy 409.821906 -28.228802)
			(xy 409.822396 -28.25877) (xy 409.822396 -29.114242) (xy 419.147244 -29.114242) (xy 419.147244 -28.250642)
			(xy 419.147734 -28.220658) (xy 419.155562 -28.161202) (xy 419.171083 -28.103277) (xy 419.194032 -28.047873)
			(xy 419.224016 -27.995939) (xy 419.260522 -27.948363) (xy 419.302927 -27.905958) (xy 419.350503 -27.869452)
			(xy 419.402437 -27.839468) (xy 419.457841 -27.816519) (xy 419.515766 -27.800998) (xy 419.575222 -27.79317)
			(xy 419.63519 -27.79317) (xy 419.694646 -27.800998) (xy 419.752571 -27.816519) (xy 419.807975 -27.839468)
			(xy 419.859909 -27.869452) (xy 419.907485 -27.905958) (xy 419.94989 -27.948363) (xy 419.986396 -27.995939)
			(xy 420.01638 -28.047873) (xy 420.039329 -28.103277) (xy 420.05485 -28.161202) (xy 420.062678 -28.220658)
			(xy 420.063168 -28.250642) (xy 420.063168 -28.469082) (xy 424.05249 -28.469082) (xy 424.056561 -28.41346)
			(xy 424.068687 -28.359023) (xy 424.08861 -28.306932) (xy 424.115906 -28.258297) (xy 424.149992 -28.214154)
			(xy 424.190141 -28.175445) (xy 424.235499 -28.142994) (xy 424.285099 -28.117493) (xy 424.337883 -28.099486)
			(xy 424.392726 -28.089356) (xy 424.44846 -28.087319) (xy 424.503897 -28.093419) (xy 424.557854 -28.107525)
			(xy 424.609183 -28.129337) (xy 424.625239 -28.139136) (xy 428.697896 -28.139136) (xy 428.701967 -28.083514)
			(xy 428.714093 -28.029077) (xy 428.734016 -27.976986) (xy 428.761312 -27.928351) (xy 428.795398 -27.884208)
			(xy 428.835547 -27.845499) (xy 428.880905 -27.813048) (xy 428.930505 -27.787547) (xy 428.983289 -27.76954)
			(xy 429.038132 -27.75941) (xy 429.093866 -27.757373) (xy 429.149303 -27.763473) (xy 429.20326 -27.777579)
			(xy 429.254589 -27.799391) (xy 429.302195 -27.828445) (xy 429.345063 -27.86412) (xy 429.38228 -27.905657)
			(xy 429.413053 -27.95217) (xy 429.436725 -28.002667) (xy 429.452793 -28.056074) (xy 429.460913 -28.11125)
			(xy 429.461422 -28.139136) (xy 429.967896 -28.139136) (xy 429.971967 -28.083514) (xy 429.984093 -28.029077)
			(xy 430.004016 -27.976986) (xy 430.031312 -27.928351) (xy 430.065398 -27.884208) (xy 430.105547 -27.845499)
			(xy 430.150905 -27.813048) (xy 430.200505 -27.787547) (xy 430.253289 -27.76954) (xy 430.308132 -27.75941)
			(xy 430.363866 -27.757373) (xy 430.419303 -27.763473) (xy 430.47326 -27.777579) (xy 430.524589 -27.799391)
			(xy 430.572195 -27.828445) (xy 430.615063 -27.86412) (xy 430.65228 -27.905657) (xy 430.683053 -27.95217)
			(xy 430.706725 -28.002667) (xy 430.722793 -28.056074) (xy 430.730913 -28.11125) (xy 430.731422 -28.139136)
			(xy 430.730913 -28.167022) (xy 430.722793 -28.222198) (xy 430.706725 -28.275605) (xy 430.683053 -28.326102)
			(xy 430.65228 -28.372615) (xy 430.615063 -28.414152) (xy 430.572195 -28.449827) (xy 430.524589 -28.478881)
			(xy 430.47326 -28.500693) (xy 430.419303 -28.514799) (xy 430.363866 -28.520899) (xy 430.308132 -28.518862)
			(xy 430.253289 -28.508732) (xy 430.200505 -28.490725) (xy 430.150905 -28.465224) (xy 430.105547 -28.432773)
			(xy 430.065398 -28.394064) (xy 430.031312 -28.349921) (xy 430.004016 -28.301286) (xy 429.984093 -28.249195)
			(xy 429.971967 -28.194758) (xy 429.967896 -28.139136) (xy 429.461422 -28.139136) (xy 429.460913 -28.167022)
			(xy 429.452793 -28.222198) (xy 429.436725 -28.275605) (xy 429.413053 -28.326102) (xy 429.38228 -28.372615)
			(xy 429.345063 -28.414152) (xy 429.302195 -28.449827) (xy 429.254589 -28.478881) (xy 429.20326 -28.500693)
			(xy 429.149303 -28.514799) (xy 429.093866 -28.520899) (xy 429.038132 -28.518862) (xy 428.983289 -28.508732)
			(xy 428.930505 -28.490725) (xy 428.880905 -28.465224) (xy 428.835547 -28.432773) (xy 428.795398 -28.394064)
			(xy 428.761312 -28.349921) (xy 428.734016 -28.301286) (xy 428.714093 -28.249195) (xy 428.701967 -28.194758)
			(xy 428.697896 -28.139136) (xy 424.625239 -28.139136) (xy 424.656789 -28.158391) (xy 424.699657 -28.194066)
			(xy 424.736874 -28.235603) (xy 424.767647 -28.282116) (xy 424.791319 -28.332613) (xy 424.807387 -28.38602)
			(xy 424.815507 -28.441196) (xy 424.816016 -28.469082) (xy 424.815507 -28.496968) (xy 424.807387 -28.552144)
			(xy 424.791319 -28.605551) (xy 424.767647 -28.656048) (xy 424.736874 -28.702561) (xy 424.699657 -28.744098)
			(xy 424.656789 -28.779773) (xy 424.609183 -28.808827) (xy 424.557854 -28.830639) (xy 424.503897 -28.844745)
			(xy 424.44846 -28.850845) (xy 424.392726 -28.848808) (xy 424.337883 -28.838678) (xy 424.285099 -28.820671)
			(xy 424.235499 -28.79517) (xy 424.190141 -28.762719) (xy 424.149992 -28.72401) (xy 424.115906 -28.679867)
			(xy 424.08861 -28.631232) (xy 424.068687 -28.579141) (xy 424.056561 -28.524704) (xy 424.05249 -28.469082)
			(xy 420.063168 -28.469082) (xy 420.063168 -29.114242) (xy 420.063035 -29.12237) (xy 434.906928 -29.12237)
			(xy 434.906928 -28.25877) (xy 434.907418 -28.228802) (xy 434.915241 -28.16938) (xy 434.930754 -28.111487)
			(xy 434.95369 -28.056114) (xy 434.983657 -28.004208) (xy 435.020144 -27.956658) (xy 435.062524 -27.914278)
			(xy 435.110074 -27.877791) (xy 435.16198 -27.847824) (xy 435.217353 -27.824888) (xy 435.275246 -27.809375)
			(xy 435.334668 -27.801552) (xy 435.394604 -27.801552) (xy 435.454026 -27.809375) (xy 435.511919 -27.824888)
			(xy 435.567292 -27.847824) (xy 435.619198 -27.877791) (xy 435.666748 -27.914278) (xy 435.709128 -27.956658)
			(xy 435.745615 -28.004208) (xy 435.775582 -28.056114) (xy 435.798518 -28.111487) (xy 435.814031 -28.16938)
			(xy 435.821854 -28.228802) (xy 435.822344 -28.25877) (xy 435.822344 -29.114242) (xy 445.147192 -29.114242)
			(xy 445.147192 -28.250642) (xy 445.147682 -28.220658) (xy 445.15551 -28.161202) (xy 445.171031 -28.103277)
			(xy 445.19398 -28.047873) (xy 445.223964 -27.995939) (xy 445.26047 -27.948363) (xy 445.302875 -27.905958)
			(xy 445.350451 -27.869452) (xy 445.402385 -27.839468) (xy 445.457789 -27.816519) (xy 445.515714 -27.800998)
			(xy 445.57517 -27.79317) (xy 445.635138 -27.79317) (xy 445.694594 -27.800998) (xy 445.752519 -27.816519)
			(xy 445.807923 -27.839468) (xy 445.859857 -27.869452) (xy 445.907433 -27.905958) (xy 445.949838 -27.948363)
			(xy 445.986344 -27.995939) (xy 446.016328 -28.047873) (xy 446.039277 -28.103277) (xy 446.054798 -28.161202)
			(xy 446.062626 -28.220658) (xy 446.063116 -28.250642) (xy 446.063116 -29.114242) (xy 446.062626 -29.144226)
			(xy 446.054798 -29.203682) (xy 446.039277 -29.261607) (xy 446.016328 -29.317011) (xy 445.986344 -29.368945)
			(xy 445.949838 -29.416521) (xy 445.907433 -29.458926) (xy 445.859857 -29.495432) (xy 445.807923 -29.525416)
			(xy 445.752519 -29.548365) (xy 445.694594 -29.563886) (xy 445.635138 -29.571714) (xy 445.57517 -29.571714)
			(xy 445.515714 -29.563886) (xy 445.457789 -29.548365) (xy 445.402385 -29.525416) (xy 445.350451 -29.495432)
			(xy 445.302875 -29.458926) (xy 445.26047 -29.416521) (xy 445.223964 -29.368945) (xy 445.19398 -29.317011)
			(xy 445.171031 -29.261607) (xy 445.15551 -29.203682) (xy 445.147682 -29.144226) (xy 445.147192 -29.114242)
			(xy 435.822344 -29.114242) (xy 435.822344 -29.12237) (xy 435.821854 -29.152338) (xy 435.814031 -29.21176)
			(xy 435.798518 -29.269653) (xy 435.775582 -29.325026) (xy 435.745615 -29.376932) (xy 435.709128 -29.424482)
			(xy 435.666748 -29.466862) (xy 435.619198 -29.503349) (xy 435.567292 -29.533316) (xy 435.511919 -29.556252)
			(xy 435.454026 -29.571765) (xy 435.394604 -29.579588) (xy 435.334668 -29.579588) (xy 435.275246 -29.571765)
			(xy 435.217353 -29.556252) (xy 435.16198 -29.533316) (xy 435.110074 -29.503349) (xy 435.062524 -29.466862)
			(xy 435.020144 -29.424482) (xy 434.983657 -29.376932) (xy 434.95369 -29.325026) (xy 434.930754 -29.269653)
			(xy 434.915241 -29.21176) (xy 434.907418 -29.152338) (xy 434.906928 -29.12237) (xy 420.063035 -29.12237)
			(xy 420.062678 -29.144226) (xy 420.05485 -29.203682) (xy 420.039329 -29.261607) (xy 420.01638 -29.317011)
			(xy 419.986396 -29.368945) (xy 419.94989 -29.416521) (xy 419.907485 -29.458926) (xy 419.859909 -29.495432)
			(xy 419.807975 -29.525416) (xy 419.752571 -29.548365) (xy 419.694646 -29.563886) (xy 419.63519 -29.571714)
			(xy 419.575222 -29.571714) (xy 419.515766 -29.563886) (xy 419.457841 -29.548365) (xy 419.402437 -29.525416)
			(xy 419.350503 -29.495432) (xy 419.302927 -29.458926) (xy 419.260522 -29.416521) (xy 419.224016 -29.368945)
			(xy 419.194032 -29.317011) (xy 419.171083 -29.261607) (xy 419.155562 -29.203682) (xy 419.147734 -29.144226)
			(xy 419.147244 -29.114242) (xy 409.822396 -29.114242) (xy 409.822396 -29.12237) (xy 409.821906 -29.152338)
			(xy 409.814083 -29.21176) (xy 409.79857 -29.269653) (xy 409.775634 -29.325026) (xy 409.745667 -29.376932)
			(xy 409.70918 -29.424482) (xy 409.6668 -29.466862) (xy 409.61925 -29.503349) (xy 409.567344 -29.533316)
			(xy 409.511971 -29.556252) (xy 409.454078 -29.571765) (xy 409.394656 -29.579588) (xy 409.33472 -29.579588)
			(xy 409.275298 -29.571765) (xy 409.217405 -29.556252) (xy 409.162032 -29.533316) (xy 409.110126 -29.503349)
			(xy 409.062576 -29.466862) (xy 409.020196 -29.424482) (xy 408.983709 -29.376932) (xy 408.953742 -29.325026)
			(xy 408.930806 -29.269653) (xy 408.915293 -29.21176) (xy 408.90747 -29.152338) (xy 408.90698 -29.12237)
			(xy 394.063087 -29.12237) (xy 394.06273 -29.144226) (xy 394.054902 -29.203682) (xy 394.039381 -29.261607)
			(xy 394.016432 -29.317011) (xy 393.986448 -29.368945) (xy 393.949942 -29.416521) (xy 393.907537 -29.458926)
			(xy 393.859961 -29.495432) (xy 393.808027 -29.525416) (xy 393.752623 -29.548365) (xy 393.694698 -29.563886)
			(xy 393.635242 -29.571714) (xy 393.575274 -29.571714) (xy 393.515818 -29.563886) (xy 393.457893 -29.548365)
			(xy 393.402489 -29.525416) (xy 393.350555 -29.495432) (xy 393.302979 -29.458926) (xy 393.260574 -29.416521)
			(xy 393.224068 -29.368945) (xy 393.194084 -29.317011) (xy 393.171135 -29.261607) (xy 393.155614 -29.203682)
			(xy 393.147786 -29.144226) (xy 393.147296 -29.114242) (xy 383.822448 -29.114242) (xy 383.822448 -29.12237)
			(xy 383.821958 -29.152338) (xy 383.814135 -29.21176) (xy 383.798622 -29.269653) (xy 383.775686 -29.325026)
			(xy 383.745719 -29.376932) (xy 383.709232 -29.424482) (xy 383.666852 -29.466862) (xy 383.619302 -29.503349)
			(xy 383.567396 -29.533316) (xy 383.512023 -29.556252) (xy 383.45413 -29.571765) (xy 383.394708 -29.579588)
			(xy 383.334772 -29.579588) (xy 383.27535 -29.571765) (xy 383.217457 -29.556252) (xy 383.162084 -29.533316)
			(xy 383.110178 -29.503349) (xy 383.062628 -29.466862) (xy 383.020248 -29.424482) (xy 382.983761 -29.376932)
			(xy 382.953794 -29.325026) (xy 382.930858 -29.269653) (xy 382.915345 -29.21176) (xy 382.907522 -29.152338)
			(xy 382.907032 -29.12237) (xy 368.063139 -29.12237) (xy 368.062782 -29.144226) (xy 368.054954 -29.203682)
			(xy 368.039433 -29.261607) (xy 368.016484 -29.317011) (xy 367.9865 -29.368945) (xy 367.949994 -29.416521)
			(xy 367.907589 -29.458926) (xy 367.860013 -29.495432) (xy 367.808079 -29.525416) (xy 367.752675 -29.548365)
			(xy 367.69475 -29.563886) (xy 367.635294 -29.571714) (xy 367.575326 -29.571714) (xy 367.51587 -29.563886)
			(xy 367.457945 -29.548365) (xy 367.402541 -29.525416) (xy 367.350607 -29.495432) (xy 367.303031 -29.458926)
			(xy 367.260626 -29.416521) (xy 367.22412 -29.368945) (xy 367.194136 -29.317011) (xy 367.171187 -29.261607)
			(xy 367.155666 -29.203682) (xy 367.147838 -29.144226) (xy 367.147348 -29.114242) (xy 357.8225 -29.114242)
			(xy 357.8225 -29.12237) (xy 357.82201 -29.152338) (xy 357.814187 -29.21176) (xy 357.798674 -29.269653)
			(xy 357.775738 -29.325026) (xy 357.745771 -29.376932) (xy 357.709284 -29.424482) (xy 357.666904 -29.466862)
			(xy 357.619354 -29.503349) (xy 357.567448 -29.533316) (xy 357.512075 -29.556252) (xy 357.454182 -29.571765)
			(xy 357.39476 -29.579588) (xy 357.334824 -29.579588) (xy 357.275402 -29.571765) (xy 357.217509 -29.556252)
			(xy 357.162136 -29.533316) (xy 357.11023 -29.503349) (xy 357.06268 -29.466862) (xy 357.0203 -29.424482)
			(xy 356.983813 -29.376932) (xy 356.953846 -29.325026) (xy 356.93091 -29.269653) (xy 356.915397 -29.21176)
			(xy 356.907574 -29.152338) (xy 356.907084 -29.12237) (xy 329.962631 -29.12237) (xy 329.962274 -29.14421)
			(xy 329.954451 -29.203632) (xy 329.938938 -29.261525) (xy 329.916002 -29.316898) (xy 329.886035 -29.368804)
			(xy 329.849548 -29.416354) (xy 329.807168 -29.458734) (xy 329.759618 -29.495221) (xy 329.707712 -29.525188)
			(xy 329.652339 -29.548124) (xy 329.594446 -29.563637) (xy 329.535024 -29.57146) (xy 329.475088 -29.57146)
			(xy 329.415666 -29.563637) (xy 329.357773 -29.548124) (xy 329.3024 -29.525188) (xy 329.250494 -29.495221)
			(xy 329.202944 -29.458734) (xy 329.160564 -29.416354) (xy 329.124077 -29.368804) (xy 329.09411 -29.316898)
			(xy 329.071174 -29.261525) (xy 329.055661 -29.203632) (xy 329.047838 -29.14421) (xy 329.047348 -29.114242)
			(xy 319.7225 -29.114242) (xy 319.7225 -29.12237) (xy 319.72201 -29.152354) (xy 319.714182 -29.21181)
			(xy 319.698661 -29.269735) (xy 319.675712 -29.325139) (xy 319.645728 -29.377073) (xy 319.609222 -29.424649)
			(xy 319.566817 -29.467054) (xy 319.519241 -29.50356) (xy 319.467307 -29.533544) (xy 319.411903 -29.556493)
			(xy 319.353978 -29.572014) (xy 319.294522 -29.579842) (xy 319.234554 -29.579842) (xy 319.175098 -29.572014)
			(xy 319.117173 -29.556493) (xy 319.061769 -29.533544) (xy 319.009835 -29.50356) (xy 318.962259 -29.467054)
			(xy 318.919854 -29.424649) (xy 318.883348 -29.377073) (xy 318.853364 -29.325139) (xy 318.830415 -29.269735)
			(xy 318.814894 -29.21181) (xy 318.807066 -29.152354) (xy 318.806576 -29.12237) (xy 303.962683 -29.12237)
			(xy 303.962326 -29.14421) (xy 303.954503 -29.203632) (xy 303.93899 -29.261525) (xy 303.916054 -29.316898)
			(xy 303.886087 -29.368804) (xy 303.8496 -29.416354) (xy 303.80722 -29.458734) (xy 303.75967 -29.495221)
			(xy 303.707764 -29.525188) (xy 303.652391 -29.548124) (xy 303.594498 -29.563637) (xy 303.535076 -29.57146)
			(xy 303.47514 -29.57146) (xy 303.415718 -29.563637) (xy 303.357825 -29.548124) (xy 303.302452 -29.525188)
			(xy 303.250546 -29.495221) (xy 303.202996 -29.458734) (xy 303.160616 -29.416354) (xy 303.124129 -29.368804)
			(xy 303.094162 -29.316898) (xy 303.071226 -29.261525) (xy 303.055713 -29.203632) (xy 303.04789 -29.14421)
			(xy 303.0474 -29.114242) (xy 293.722552 -29.114242) (xy 293.722552 -29.12237) (xy 293.722062 -29.152354)
			(xy 293.714234 -29.21181) (xy 293.698713 -29.269735) (xy 293.675764 -29.325139) (xy 293.64578 -29.377073)
			(xy 293.609274 -29.424649) (xy 293.566869 -29.467054) (xy 293.519293 -29.50356) (xy 293.467359 -29.533544)
			(xy 293.411955 -29.556493) (xy 293.35403 -29.572014) (xy 293.294574 -29.579842) (xy 293.234606 -29.579842)
			(xy 293.17515 -29.572014) (xy 293.117225 -29.556493) (xy 293.061821 -29.533544) (xy 293.009887 -29.50356)
			(xy 292.962311 -29.467054) (xy 292.919906 -29.424649) (xy 292.8834 -29.377073) (xy 292.853416 -29.325139)
			(xy 292.830467 -29.269735) (xy 292.814946 -29.21181) (xy 292.807118 -29.152354) (xy 292.806628 -29.12237)
			(xy 277.962735 -29.12237) (xy 277.962378 -29.14421) (xy 277.954555 -29.203632) (xy 277.939042 -29.261525)
			(xy 277.916106 -29.316898) (xy 277.886139 -29.368804) (xy 277.849652 -29.416354) (xy 277.807272 -29.458734)
			(xy 277.759722 -29.495221) (xy 277.707816 -29.525188) (xy 277.652443 -29.548124) (xy 277.59455 -29.563637)
			(xy 277.535128 -29.57146) (xy 277.475192 -29.57146) (xy 277.41577 -29.563637) (xy 277.357877 -29.548124)
			(xy 277.302504 -29.525188) (xy 277.250598 -29.495221) (xy 277.203048 -29.458734) (xy 277.160668 -29.416354)
			(xy 277.124181 -29.368804) (xy 277.094214 -29.316898) (xy 277.071278 -29.261525) (xy 277.055765 -29.203632)
			(xy 277.047942 -29.14421) (xy 277.047452 -29.114242) (xy 267.722604 -29.114242) (xy 267.722604 -29.12237)
			(xy 267.722114 -29.152354) (xy 267.714286 -29.21181) (xy 267.698765 -29.269735) (xy 267.675816 -29.325139)
			(xy 267.645832 -29.377073) (xy 267.609326 -29.424649) (xy 267.566921 -29.467054) (xy 267.519345 -29.50356)
			(xy 267.467411 -29.533544) (xy 267.412007 -29.556493) (xy 267.354082 -29.572014) (xy 267.294626 -29.579842)
			(xy 267.234658 -29.579842) (xy 267.175202 -29.572014) (xy 267.117277 -29.556493) (xy 267.061873 -29.533544)
			(xy 267.009939 -29.50356) (xy 266.962363 -29.467054) (xy 266.919958 -29.424649) (xy 266.883452 -29.377073)
			(xy 266.853468 -29.325139) (xy 266.830519 -29.269735) (xy 266.814998 -29.21181) (xy 266.80717 -29.152354)
			(xy 266.80668 -29.12237) (xy 251.962787 -29.12237) (xy 251.96243 -29.14421) (xy 251.954607 -29.203632)
			(xy 251.939094 -29.261525) (xy 251.916158 -29.316898) (xy 251.886191 -29.368804) (xy 251.849704 -29.416354)
			(xy 251.807324 -29.458734) (xy 251.759774 -29.495221) (xy 251.707868 -29.525188) (xy 251.652495 -29.548124)
			(xy 251.594602 -29.563637) (xy 251.53518 -29.57146) (xy 251.475244 -29.57146) (xy 251.415822 -29.563637)
			(xy 251.357929 -29.548124) (xy 251.302556 -29.525188) (xy 251.25065 -29.495221) (xy 251.2031 -29.458734)
			(xy 251.16072 -29.416354) (xy 251.124233 -29.368804) (xy 251.094266 -29.316898) (xy 251.07133 -29.261525)
			(xy 251.055817 -29.203632) (xy 251.047994 -29.14421) (xy 251.047504 -29.114242) (xy 241.722656 -29.114242)
			(xy 241.722656 -29.12237) (xy 241.722166 -29.152354) (xy 241.714338 -29.21181) (xy 241.698817 -29.269735)
			(xy 241.675868 -29.325139) (xy 241.645884 -29.377073) (xy 241.609378 -29.424649) (xy 241.566973 -29.467054)
			(xy 241.519397 -29.50356) (xy 241.467463 -29.533544) (xy 241.412059 -29.556493) (xy 241.354134 -29.572014)
			(xy 241.294678 -29.579842) (xy 241.23471 -29.579842) (xy 241.175254 -29.572014) (xy 241.117329 -29.556493)
			(xy 241.061925 -29.533544) (xy 241.009991 -29.50356) (xy 240.962415 -29.467054) (xy 240.92001 -29.424649)
			(xy 240.883504 -29.377073) (xy 240.85352 -29.325139) (xy 240.830571 -29.269735) (xy 240.81505 -29.21181)
			(xy 240.807222 -29.152354) (xy 240.806732 -29.12237) (xy 213.862787 -29.12237) (xy 213.86243 -29.14421)
			(xy 213.854607 -29.203632) (xy 213.839094 -29.261525) (xy 213.816158 -29.316898) (xy 213.786191 -29.368804)
			(xy 213.749704 -29.416354) (xy 213.707324 -29.458734) (xy 213.659774 -29.495221) (xy 213.607868 -29.525188)
			(xy 213.552495 -29.548124) (xy 213.494602 -29.563637) (xy 213.43518 -29.57146) (xy 213.375244 -29.57146)
			(xy 213.315822 -29.563637) (xy 213.257929 -29.548124) (xy 213.202556 -29.525188) (xy 213.15065 -29.495221)
			(xy 213.1031 -29.458734) (xy 213.06072 -29.416354) (xy 213.024233 -29.368804) (xy 212.994266 -29.316898)
			(xy 212.97133 -29.261525) (xy 212.955817 -29.203632) (xy 212.947994 -29.14421) (xy 212.947504 -29.114242)
			(xy 203.622656 -29.114242) (xy 203.622656 -29.12237) (xy 203.622166 -29.152354) (xy 203.614338 -29.21181)
			(xy 203.598817 -29.269735) (xy 203.575868 -29.325139) (xy 203.545884 -29.377073) (xy 203.509378 -29.424649)
			(xy 203.466973 -29.467054) (xy 203.419397 -29.50356) (xy 203.367463 -29.533544) (xy 203.312059 -29.556493)
			(xy 203.254134 -29.572014) (xy 203.194678 -29.579842) (xy 203.13471 -29.579842) (xy 203.075254 -29.572014)
			(xy 203.017329 -29.556493) (xy 202.961925 -29.533544) (xy 202.909991 -29.50356) (xy 202.862415 -29.467054)
			(xy 202.82001 -29.424649) (xy 202.783504 -29.377073) (xy 202.75352 -29.325139) (xy 202.730571 -29.269735)
			(xy 202.71505 -29.21181) (xy 202.707222 -29.152354) (xy 202.706732 -29.12237) (xy 187.862839 -29.12237)
			(xy 187.862482 -29.14421) (xy 187.854659 -29.203632) (xy 187.839146 -29.261525) (xy 187.81621 -29.316898)
			(xy 187.786243 -29.368804) (xy 187.749756 -29.416354) (xy 187.707376 -29.458734) (xy 187.659826 -29.495221)
			(xy 187.60792 -29.525188) (xy 187.552547 -29.548124) (xy 187.494654 -29.563637) (xy 187.435232 -29.57146)
			(xy 187.375296 -29.57146) (xy 187.315874 -29.563637) (xy 187.257981 -29.548124) (xy 187.202608 -29.525188)
			(xy 187.150702 -29.495221) (xy 187.103152 -29.458734) (xy 187.060772 -29.416354) (xy 187.024285 -29.368804)
			(xy 186.994318 -29.316898) (xy 186.971382 -29.261525) (xy 186.955869 -29.203632) (xy 186.948046 -29.14421)
			(xy 186.947556 -29.114242) (xy 177.622708 -29.114242) (xy 177.622708 -29.12237) (xy 177.622218 -29.152354)
			(xy 177.61439 -29.21181) (xy 177.598869 -29.269735) (xy 177.57592 -29.325139) (xy 177.545936 -29.377073)
			(xy 177.50943 -29.424649) (xy 177.467025 -29.467054) (xy 177.419449 -29.50356) (xy 177.367515 -29.533544)
			(xy 177.312111 -29.556493) (xy 177.254186 -29.572014) (xy 177.19473 -29.579842) (xy 177.134762 -29.579842)
			(xy 177.075306 -29.572014) (xy 177.017381 -29.556493) (xy 176.961977 -29.533544) (xy 176.910043 -29.50356)
			(xy 176.862467 -29.467054) (xy 176.820062 -29.424649) (xy 176.783556 -29.377073) (xy 176.753572 -29.325139)
			(xy 176.730623 -29.269735) (xy 176.715102 -29.21181) (xy 176.707274 -29.152354) (xy 176.706784 -29.12237)
			(xy 161.862891 -29.12237) (xy 161.862534 -29.14421) (xy 161.854711 -29.203632) (xy 161.839198 -29.261525)
			(xy 161.816262 -29.316898) (xy 161.786295 -29.368804) (xy 161.749808 -29.416354) (xy 161.707428 -29.458734)
			(xy 161.659878 -29.495221) (xy 161.607972 -29.525188) (xy 161.552599 -29.548124) (xy 161.494706 -29.563637)
			(xy 161.435284 -29.57146) (xy 161.375348 -29.57146) (xy 161.315926 -29.563637) (xy 161.258033 -29.548124)
			(xy 161.20266 -29.525188) (xy 161.150754 -29.495221) (xy 161.103204 -29.458734) (xy 161.060824 -29.416354)
			(xy 161.024337 -29.368804) (xy 160.99437 -29.316898) (xy 160.971434 -29.261525) (xy 160.955921 -29.203632)
			(xy 160.948098 -29.14421) (xy 160.947608 -29.114242) (xy 151.62276 -29.114242) (xy 151.62276 -29.12237)
			(xy 151.62227 -29.152354) (xy 151.614442 -29.21181) (xy 151.598921 -29.269735) (xy 151.575972 -29.325139)
			(xy 151.545988 -29.377073) (xy 151.509482 -29.424649) (xy 151.467077 -29.467054) (xy 151.419501 -29.50356)
			(xy 151.367567 -29.533544) (xy 151.312163 -29.556493) (xy 151.254238 -29.572014) (xy 151.194782 -29.579842)
			(xy 151.134814 -29.579842) (xy 151.075358 -29.572014) (xy 151.017433 -29.556493) (xy 150.962029 -29.533544)
			(xy 150.910095 -29.50356) (xy 150.862519 -29.467054) (xy 150.820114 -29.424649) (xy 150.783608 -29.377073)
			(xy 150.753624 -29.325139) (xy 150.730675 -29.269735) (xy 150.715154 -29.21181) (xy 150.707326 -29.152354)
			(xy 150.706836 -29.12237) (xy 135.862943 -29.12237) (xy 135.862586 -29.14421) (xy 135.854763 -29.203632)
			(xy 135.83925 -29.261525) (xy 135.816314 -29.316898) (xy 135.786347 -29.368804) (xy 135.74986 -29.416354)
			(xy 135.70748 -29.458734) (xy 135.65993 -29.495221) (xy 135.608024 -29.525188) (xy 135.552651 -29.548124)
			(xy 135.494758 -29.563637) (xy 135.435336 -29.57146) (xy 135.3754 -29.57146) (xy 135.315978 -29.563637)
			(xy 135.258085 -29.548124) (xy 135.202712 -29.525188) (xy 135.150806 -29.495221) (xy 135.103256 -29.458734)
			(xy 135.060876 -29.416354) (xy 135.024389 -29.368804) (xy 134.994422 -29.316898) (xy 134.971486 -29.261525)
			(xy 134.955973 -29.203632) (xy 134.94815 -29.14421) (xy 134.94766 -29.114242) (xy 125.622812 -29.114242)
			(xy 125.622812 -29.12237) (xy 125.622322 -29.152354) (xy 125.614494 -29.21181) (xy 125.598973 -29.269735)
			(xy 125.576024 -29.325139) (xy 125.54604 -29.377073) (xy 125.509534 -29.424649) (xy 125.467129 -29.467054)
			(xy 125.419553 -29.50356) (xy 125.367619 -29.533544) (xy 125.312215 -29.556493) (xy 125.25429 -29.572014)
			(xy 125.194834 -29.579842) (xy 125.134866 -29.579842) (xy 125.07541 -29.572014) (xy 125.017485 -29.556493)
			(xy 124.962081 -29.533544) (xy 124.910147 -29.50356) (xy 124.862571 -29.467054) (xy 124.820166 -29.424649)
			(xy 124.78366 -29.377073) (xy 124.753676 -29.325139) (xy 124.730727 -29.269735) (xy 124.715206 -29.21181)
			(xy 124.707378 -29.152354) (xy 124.706888 -29.12237) (xy 97.762943 -29.12237) (xy 97.762586 -29.144226)
			(xy 97.754758 -29.203682) (xy 97.739237 -29.261607) (xy 97.716288 -29.317011) (xy 97.686304 -29.368945)
			(xy 97.649798 -29.416521) (xy 97.607393 -29.458926) (xy 97.559817 -29.495432) (xy 97.507883 -29.525416)
			(xy 97.452479 -29.548365) (xy 97.394554 -29.563886) (xy 97.335098 -29.571714) (xy 97.27513 -29.571714)
			(xy 97.215674 -29.563886) (xy 97.157749 -29.548365) (xy 97.102345 -29.525416) (xy 97.050411 -29.495432)
			(xy 97.002835 -29.458926) (xy 96.96043 -29.416521) (xy 96.923924 -29.368945) (xy 96.89394 -29.317011)
			(xy 96.870991 -29.261607) (xy 96.85547 -29.203682) (xy 96.847642 -29.144226) (xy 96.847152 -29.114242)
			(xy 87.522304 -29.114242) (xy 87.522304 -29.12237) (xy 87.521814 -29.152338) (xy 87.513991 -29.21176)
			(xy 87.498478 -29.269653) (xy 87.475542 -29.325026) (xy 87.445575 -29.376932) (xy 87.409088 -29.424482)
			(xy 87.366708 -29.466862) (xy 87.319158 -29.503349) (xy 87.267252 -29.533316) (xy 87.211879 -29.556252)
			(xy 87.153986 -29.571765) (xy 87.094564 -29.579588) (xy 87.034628 -29.579588) (xy 86.975206 -29.571765)
			(xy 86.917313 -29.556252) (xy 86.86194 -29.533316) (xy 86.810034 -29.503349) (xy 86.762484 -29.466862)
			(xy 86.720104 -29.424482) (xy 86.683617 -29.376932) (xy 86.65365 -29.325026) (xy 86.630714 -29.269653)
			(xy 86.615201 -29.21176) (xy 86.607378 -29.152338) (xy 86.606888 -29.12237) (xy 71.762995 -29.12237)
			(xy 71.762638 -29.144226) (xy 71.75481 -29.203682) (xy 71.739289 -29.261607) (xy 71.71634 -29.317011)
			(xy 71.686356 -29.368945) (xy 71.64985 -29.416521) (xy 71.607445 -29.458926) (xy 71.559869 -29.495432)
			(xy 71.507935 -29.525416) (xy 71.452531 -29.548365) (xy 71.394606 -29.563886) (xy 71.33515 -29.571714)
			(xy 71.275182 -29.571714) (xy 71.215726 -29.563886) (xy 71.157801 -29.548365) (xy 71.102397 -29.525416)
			(xy 71.050463 -29.495432) (xy 71.002887 -29.458926) (xy 70.960482 -29.416521) (xy 70.923976 -29.368945)
			(xy 70.893992 -29.317011) (xy 70.871043 -29.261607) (xy 70.855522 -29.203682) (xy 70.847694 -29.144226)
			(xy 70.847204 -29.114242) (xy 61.522356 -29.114242) (xy 61.522356 -29.12237) (xy 61.521866 -29.152338)
			(xy 61.514043 -29.21176) (xy 61.49853 -29.269653) (xy 61.475594 -29.325026) (xy 61.445627 -29.376932)
			(xy 61.40914 -29.424482) (xy 61.36676 -29.466862) (xy 61.31921 -29.503349) (xy 61.267304 -29.533316)
			(xy 61.211931 -29.556252) (xy 61.154038 -29.571765) (xy 61.094616 -29.579588) (xy 61.03468 -29.579588)
			(xy 60.975258 -29.571765) (xy 60.917365 -29.556252) (xy 60.861992 -29.533316) (xy 60.810086 -29.503349)
			(xy 60.762536 -29.466862) (xy 60.720156 -29.424482) (xy 60.683669 -29.376932) (xy 60.653702 -29.325026)
			(xy 60.630766 -29.269653) (xy 60.615253 -29.21176) (xy 60.60743 -29.152338) (xy 60.60694 -29.12237)
			(xy 45.763047 -29.12237) (xy 45.76269 -29.144226) (xy 45.754862 -29.203682) (xy 45.739341 -29.261607)
			(xy 45.716392 -29.317011) (xy 45.686408 -29.368945) (xy 45.649902 -29.416521) (xy 45.607497 -29.458926)
			(xy 45.559921 -29.495432) (xy 45.507987 -29.525416) (xy 45.452583 -29.548365) (xy 45.394658 -29.563886)
			(xy 45.335202 -29.571714) (xy 45.275234 -29.571714) (xy 45.215778 -29.563886) (xy 45.157853 -29.548365)
			(xy 45.102449 -29.525416) (xy 45.050515 -29.495432) (xy 45.002939 -29.458926) (xy 44.960534 -29.416521)
			(xy 44.924028 -29.368945) (xy 44.894044 -29.317011) (xy 44.871095 -29.261607) (xy 44.855574 -29.203682)
			(xy 44.847746 -29.144226) (xy 44.847256 -29.114242) (xy 35.522408 -29.114242) (xy 35.522408 -29.12237)
			(xy 35.521918 -29.152338) (xy 35.514095 -29.21176) (xy 35.498582 -29.269653) (xy 35.475646 -29.325026)
			(xy 35.445679 -29.376932) (xy 35.409192 -29.424482) (xy 35.366812 -29.466862) (xy 35.319262 -29.503349)
			(xy 35.267356 -29.533316) (xy 35.211983 -29.556252) (xy 35.15409 -29.571765) (xy 35.094668 -29.579588)
			(xy 35.034732 -29.579588) (xy 34.97531 -29.571765) (xy 34.917417 -29.556252) (xy 34.862044 -29.533316)
			(xy 34.810138 -29.503349) (xy 34.762588 -29.466862) (xy 34.720208 -29.424482) (xy 34.683721 -29.376932)
			(xy 34.653754 -29.325026) (xy 34.630818 -29.269653) (xy 34.615305 -29.21176) (xy 34.607482 -29.152338)
			(xy 34.606992 -29.12237) (xy 19.763099 -29.12237) (xy 19.762742 -29.144226) (xy 19.754914 -29.203682)
			(xy 19.739393 -29.261607) (xy 19.716444 -29.317011) (xy 19.68646 -29.368945) (xy 19.649954 -29.416521)
			(xy 19.607549 -29.458926) (xy 19.559973 -29.495432) (xy 19.508039 -29.525416) (xy 19.452635 -29.548365)
			(xy 19.39471 -29.563886) (xy 19.335254 -29.571714) (xy 19.275286 -29.571714) (xy 19.21583 -29.563886)
			(xy 19.157905 -29.548365) (xy 19.102501 -29.525416) (xy 19.050567 -29.495432) (xy 19.002991 -29.458926)
			(xy 18.960586 -29.416521) (xy 18.92408 -29.368945) (xy 18.894096 -29.317011) (xy 18.871147 -29.261607)
			(xy 18.855626 -29.203682) (xy 18.847798 -29.144226) (xy 18.847308 -29.114242) (xy 9.52246 -29.114242)
			(xy 9.52246 -29.12237) (xy 9.52197 -29.152338) (xy 9.514147 -29.21176) (xy 9.498634 -29.269653) (xy 9.475698 -29.325026)
			(xy 9.445731 -29.376932) (xy 9.409244 -29.424482) (xy 9.366864 -29.466862) (xy 9.319314 -29.503349)
			(xy 9.267408 -29.533316) (xy 9.212035 -29.556252) (xy 9.154142 -29.571765) (xy 9.09472 -29.579588)
			(xy 9.034784 -29.579588) (xy 8.975362 -29.571765) (xy 8.917469 -29.556252) (xy 8.862096 -29.533316)
			(xy 8.81019 -29.503349) (xy 8.76264 -29.466862) (xy 8.72026 -29.424482) (xy 8.683773 -29.376932)
			(xy 8.653806 -29.325026) (xy 8.63087 -29.269653) (xy 8.615357 -29.21176) (xy 8.607534 -29.152338)
			(xy 8.607044 -29.12237) (xy 4.147142 -29.12237) (xy 4.148688 -29.124095) (xy 4.179461 -29.170608)
			(xy 4.203133 -29.221105) (xy 4.219201 -29.274512) (xy 4.227321 -29.329688) (xy 4.22783 -29.357574)
			(xy 4.227321 -29.38546) (xy 4.219201 -29.440636) (xy 4.203133 -29.494043) (xy 4.179461 -29.54454)
			(xy 4.148688 -29.591053) (xy 4.111471 -29.63259) (xy 4.068603 -29.668265) (xy 4.020997 -29.697319)
			(xy 3.969668 -29.719131) (xy 3.915711 -29.733237) (xy 3.860274 -29.739337) (xy 3.80454 -29.7373)
			(xy 3.749697 -29.72717) (xy 3.696913 -29.709163) (xy 3.647313 -29.683662) (xy 3.601955 -29.651211)
			(xy 3.561806 -29.612502) (xy 3.52772 -29.568359) (xy 3.500424 -29.519724) (xy 3.480501 -29.467633)
			(xy 3.468375 -29.413196) (xy 3.464304 -29.357574) (xy 2.954281 -29.357574) (xy 2.954273 -29.358028)
			(xy 2.946153 -29.413204) (xy 2.930085 -29.466611) (xy 2.906413 -29.517108) (xy 2.87564 -29.563621)
			(xy 2.838423 -29.605158) (xy 2.795555 -29.640833) (xy 2.747949 -29.669887) (xy 2.69662 -29.691699)
			(xy 2.642663 -29.705805) (xy 2.587226 -29.711905) (xy 2.531492 -29.709868) (xy 2.476649 -29.699738)
			(xy 2.423865 -29.681731) (xy 2.374265 -29.65623) (xy 2.328907 -29.623779) (xy 2.288758 -29.58507)
			(xy 2.254672 -29.540927) (xy 2.227376 -29.492292) (xy 2.207453 -29.440201) (xy 2.195327 -29.385764)
			(xy 2.191256 -29.330142) (xy 2.02438 -29.330142) (xy 2.02438 -30.922468) (xy 6.752844 -30.922468)
			(xy 6.752844 -30.058868) (xy 6.753334 -30.0289) (xy 6.761157 -29.969478) (xy 6.77667 -29.911585)
			(xy 6.799606 -29.856212) (xy 6.829573 -29.804306) (xy 6.86606 -29.756756) (xy 6.90844 -29.714376)
			(xy 6.95599 -29.677889) (xy 7.007896 -29.647922) (xy 7.063269 -29.624986) (xy 7.121162 -29.609473)
			(xy 7.180584 -29.60165) (xy 7.24052 -29.60165) (xy 7.299942 -29.609473) (xy 7.357835 -29.624986)
			(xy 7.413208 -29.647922) (xy 7.465114 -29.677889) (xy 7.512664 -29.714376) (xy 7.555044 -29.756756)
			(xy 7.591531 -29.804306) (xy 7.621498 -29.856212) (xy 7.644434 -29.911585) (xy 7.659947 -29.969478)
			(xy 7.66777 -30.0289) (xy 7.66826 -30.058868) (xy 7.66826 -30.92069) (xy 21.489416 -30.92069) (xy 21.489416 -30.05709)
			(xy 21.489906 -30.027106) (xy 21.497734 -29.96765) (xy 21.513255 -29.909725) (xy 21.536204 -29.854321)
			(xy 21.566188 -29.802387) (xy 21.602694 -29.754811) (xy 21.645099 -29.712406) (xy 21.692675 -29.6759)
			(xy 21.744609 -29.645916) (xy 21.800013 -29.622967) (xy 21.857938 -29.607446) (xy 21.917394 -29.599618)
			(xy 21.977362 -29.599618) (xy 22.036818 -29.607446) (xy 22.094743 -29.622967) (xy 22.150147 -29.645916)
			(xy 22.202081 -29.6759) (xy 22.249657 -29.712406) (xy 22.292062 -29.754811) (xy 22.328568 -29.802387)
			(xy 22.358552 -29.854321) (xy 22.381501 -29.909725) (xy 22.397022 -29.96765) (xy 22.40485 -30.027106)
			(xy 22.40534 -30.05709) (xy 22.40534 -30.376876) (xy 26.888948 -30.376876) (xy 26.889503 -30.34796)
			(xy 26.898222 -30.29079) (xy 26.915471 -30.235591) (xy 26.940856 -30.183629) (xy 26.973794 -30.136094)
			(xy 27.013531 -30.094077) (xy 27.036014 -30.075886) (xy 27.04482 -30.068277) (xy 27.055003 -30.047378)
			(xy 27.055572 -30.035754) (xy 27.055572 -29.955998) (xy 27.055029 -29.944366) (xy 27.044844 -29.923456)
			(xy 27.036014 -29.915866) (xy 27.013517 -29.897691) (xy 26.973782 -29.855668) (xy 26.940844 -29.80813)
			(xy 26.915458 -29.756166) (xy 26.898205 -29.700965) (xy 26.88948 -29.643793) (xy 26.888948 -29.614876)
			(xy 26.889434 -29.587625) (xy 26.89719 -29.533677) (xy 26.912545 -29.481382) (xy 26.935187 -29.431805)
			(xy 26.964653 -29.385955) (xy 27.000344 -29.344764) (xy 27.041535 -29.309073) (xy 27.087385 -29.279607)
			(xy 27.136962 -29.256965) (xy 27.189257 -29.24161) (xy 27.243205 -29.233854) (xy 27.297707 -29.233854)
			(xy 27.351655 -29.24161) (xy 27.40395 -29.256965) (xy 27.453527 -29.279607) (xy 27.499377 -29.309073)
			(xy 27.540568 -29.344764) (xy 27.576259 -29.385955) (xy 27.605725 -29.431805) (xy 27.628367 -29.481382)
			(xy 27.643722 -29.533677) (xy 27.651478 -29.587625) (xy 27.651964 -29.614876) (xy 27.651442 -29.643793)
			(xy 27.642716 -29.700965) (xy 27.625459 -29.756164) (xy 27.600069 -29.808126) (xy 27.567125 -29.85566)
			(xy 27.527384 -29.897676) (xy 27.504898 -29.915866) (xy 27.496116 -29.923497) (xy 27.485919 -29.94438)
			(xy 27.48534 -29.955998) (xy 27.48534 -30.035754) (xy 27.485848 -30.04739) (xy 27.496058 -30.0683)
			(xy 27.504898 -30.075886) (xy 27.527374 -30.094085) (xy 27.56711 -30.136103) (xy 27.60005 -30.183637)
			(xy 27.62544 -30.235596) (xy 27.642697 -30.290792) (xy 27.651428 -30.34796) (xy 27.651964 -30.376876)
			(xy 29.929074 -30.376876) (xy 29.929619 -30.34796) (xy 29.938339 -30.290789) (xy 29.955589 -30.235589)
			(xy 29.980976 -30.183627) (xy 30.013916 -30.136092) (xy 30.053655 -30.094076) (xy 30.07614 -30.075886)
			(xy 30.08495 -30.068282) (xy 30.09513 -30.047379) (xy 30.095698 -30.035754) (xy 30.095698 -29.955998)
			(xy 30.095147 -29.944368) (xy 30.084967 -29.923458) (xy 30.07614 -29.915866) (xy 30.053649 -29.897684)
			(xy 30.013912 -29.855664) (xy 29.980973 -29.808127) (xy 29.955585 -29.756164) (xy 29.938332 -29.700964)
			(xy 29.929606 -29.643793) (xy 29.929074 -29.614876) (xy 29.92956 -29.587625) (xy 29.937316 -29.533677)
			(xy 29.952671 -29.481382) (xy 29.975313 -29.431805) (xy 30.004779 -29.385955) (xy 30.04047 -29.344764)
			(xy 30.081661 -29.309073) (xy 30.127511 -29.279607) (xy 30.177088 -29.256965) (xy 30.229383 -29.24161)
			(xy 30.283331 -29.233854) (xy 30.337833 -29.233854) (xy 30.391781 -29.24161) (xy 30.444076 -29.256965)
			(xy 30.493653 -29.279607) (xy 30.539503 -29.309073) (xy 30.580694 -29.344764) (xy 30.616385 -29.385955)
			(xy 30.645851 -29.431805) (xy 30.668493 -29.481382) (xy 30.683848 -29.533677) (xy 30.691604 -29.587625)
			(xy 30.69209 -29.614876) (xy 30.691558 -29.643792) (xy 30.682832 -29.700963) (xy 30.665577 -29.756162)
			(xy 30.640188 -29.808124) (xy 30.607247 -29.855658) (xy 30.567508 -29.897675) (xy 30.545024 -29.915866)
			(xy 30.53623 -29.923485) (xy 30.526042 -29.944377) (xy 30.525466 -29.955998) (xy 30.525466 -30.035754)
			(xy 30.525965 -30.047392) (xy 30.53618 -30.068302) (xy 30.545024 -30.075886) (xy 30.567506 -30.094079)
			(xy 30.60724 -30.136099) (xy 30.640178 -30.183634) (xy 30.665567 -30.235594) (xy 30.682824 -30.290791)
			(xy 30.691554 -30.34796) (xy 30.69209 -30.376876) (xy 30.691604 -30.404127) (xy 30.683848 -30.458075)
			(xy 30.668493 -30.51037) (xy 30.645851 -30.559947) (xy 30.616385 -30.605797) (xy 30.580694 -30.646988)
			(xy 30.539503 -30.682679) (xy 30.493653 -30.712145) (xy 30.444076 -30.734787) (xy 30.391781 -30.750142)
			(xy 30.337833 -30.757898) (xy 30.283331 -30.757898) (xy 30.229383 -30.750142) (xy 30.177088 -30.734787)
			(xy 30.127511 -30.712145) (xy 30.081661 -30.682679) (xy 30.04047 -30.646988) (xy 30.004779 -30.605797)
			(xy 29.975313 -30.559947) (xy 29.952671 -30.51037) (xy 29.937316 -30.458075) (xy 29.92956 -30.404127)
			(xy 29.929074 -30.376876) (xy 27.651964 -30.376876) (xy 27.651478 -30.404127) (xy 27.643722 -30.458075)
			(xy 27.628367 -30.51037) (xy 27.605725 -30.559947) (xy 27.576259 -30.605797) (xy 27.540568 -30.646988)
			(xy 27.499377 -30.682679) (xy 27.453527 -30.712145) (xy 27.40395 -30.734787) (xy 27.351655 -30.750142)
			(xy 27.297707 -30.757898) (xy 27.243205 -30.757898) (xy 27.189257 -30.750142) (xy 27.136962 -30.734787)
			(xy 27.087385 -30.712145) (xy 27.041535 -30.682679) (xy 27.000344 -30.646988) (xy 26.964653 -30.605797)
			(xy 26.935187 -30.559947) (xy 26.912545 -30.51037) (xy 26.89719 -30.458075) (xy 26.889434 -30.404127)
			(xy 26.888948 -30.376876) (xy 22.40534 -30.376876) (xy 22.40534 -30.92069) (xy 22.405311 -30.922468)
			(xy 32.752792 -30.922468) (xy 32.752792 -30.058868) (xy 32.753282 -30.0289) (xy 32.761105 -29.969478)
			(xy 32.776618 -29.911585) (xy 32.799554 -29.856212) (xy 32.829521 -29.804306) (xy 32.866008 -29.756756)
			(xy 32.908388 -29.714376) (xy 32.955938 -29.677889) (xy 33.007844 -29.647922) (xy 33.063217 -29.624986)
			(xy 33.12111 -29.609473) (xy 33.180532 -29.60165) (xy 33.240468 -29.60165) (xy 33.29989 -29.609473)
			(xy 33.357783 -29.624986) (xy 33.413156 -29.647922) (xy 33.465062 -29.677889) (xy 33.512612 -29.714376)
			(xy 33.554992 -29.756756) (xy 33.591479 -29.804306) (xy 33.621446 -29.856212) (xy 33.644382 -29.911585)
			(xy 33.659895 -29.969478) (xy 33.667718 -30.0289) (xy 33.668208 -30.058868) (xy 33.668208 -30.92069)
			(xy 47.489364 -30.92069) (xy 47.489364 -30.05709) (xy 47.489854 -30.027106) (xy 47.497682 -29.96765)
			(xy 47.513203 -29.909725) (xy 47.536152 -29.854321) (xy 47.566136 -29.802387) (xy 47.602642 -29.754811)
			(xy 47.645047 -29.712406) (xy 47.692623 -29.6759) (xy 47.744557 -29.645916) (xy 47.799961 -29.622967)
			(xy 47.857886 -29.607446) (xy 47.917342 -29.599618) (xy 47.97731 -29.599618) (xy 48.036766 -29.607446)
			(xy 48.094691 -29.622967) (xy 48.150095 -29.645916) (xy 48.202029 -29.6759) (xy 48.249605 -29.712406)
			(xy 48.29201 -29.754811) (xy 48.328516 -29.802387) (xy 48.3585 -29.854321) (xy 48.381449 -29.909725)
			(xy 48.39697 -29.96765) (xy 48.404798 -30.027106) (xy 48.405288 -30.05709) (xy 48.405288 -30.376876)
			(xy 52.888896 -30.376876) (xy 52.889433 -30.347959) (xy 52.898153 -30.290787) (xy 52.915405 -30.235587)
			(xy 52.940793 -30.183625) (xy 52.973735 -30.136091) (xy 53.013476 -30.094075) (xy 53.035962 -30.075886)
			(xy 53.044776 -30.068286) (xy 53.054953 -30.047379) (xy 53.05552 -30.035754) (xy 53.05552 -29.955998)
			(xy 53.054961 -29.944369) (xy 53.044785 -29.92346) (xy 53.035962 -29.915866) (xy 53.013454 -29.897704)
			(xy 52.973722 -29.855677) (xy 52.940787 -29.808136) (xy 52.915403 -29.756169) (xy 52.898152 -29.700967)
			(xy 52.889428 -29.643794) (xy 52.888896 -29.614876) (xy 52.889382 -29.587625) (xy 52.897138 -29.533677)
			(xy 52.912493 -29.481382) (xy 52.935135 -29.431805) (xy 52.964601 -29.385955) (xy 53.000292 -29.344764)
			(xy 53.041483 -29.309073) (xy 53.087333 -29.279607) (xy 53.13691 -29.256965) (xy 53.189205 -29.24161)
			(xy 53.243153 -29.233854) (xy 53.297655 -29.233854) (xy 53.351603 -29.24161) (xy 53.403898 -29.256965)
			(xy 53.453475 -29.279607) (xy 53.499325 -29.309073) (xy 53.540516 -29.344764) (xy 53.576207 -29.385955)
			(xy 53.605673 -29.431805) (xy 53.628315 -29.481382) (xy 53.64367 -29.533677) (xy 53.651426 -29.587625)
			(xy 53.651912 -29.614876) (xy 53.65141 -29.643794) (xy 53.642682 -29.700967) (xy 53.625423 -29.756168)
			(xy 53.600029 -29.80813) (xy 53.567081 -29.855664) (xy 53.527334 -29.897678) (xy 53.504846 -29.915866)
			(xy 53.496055 -29.923488) (xy 53.485865 -29.944378) (xy 53.485288 -29.955998) (xy 53.485288 -30.035754)
			(xy 53.485815 -30.047387) (xy 53.496013 -30.068296) (xy 53.504846 -30.075886) (xy 53.527332 -30.094073)
			(xy 53.567065 -30.136095) (xy 53.600003 -30.183631) (xy 53.62539 -30.235593) (xy 53.642646 -30.290791)
			(xy 53.651376 -30.34796) (xy 53.651912 -30.376876) (xy 55.929022 -30.376876) (xy 55.929586 -30.347961)
			(xy 55.938305 -30.290791) (xy 55.955553 -30.235593) (xy 55.980936 -30.183631) (xy 56.013872 -30.136096)
			(xy 56.053606 -30.094077) (xy 56.076088 -30.075886) (xy 56.08489 -30.068273) (xy 56.095077 -30.047377)
			(xy 56.095646 -30.035754) (xy 56.095646 -29.955998) (xy 56.095113 -29.944365) (xy 56.084922 -29.923454)
			(xy 56.076088 -29.915866) (xy 56.053586 -29.897697) (xy 56.013852 -29.855672) (xy 55.980916 -29.808133)
			(xy 55.955531 -29.756167) (xy 55.938279 -29.700966) (xy 55.929554 -29.643793) (xy 55.929022 -29.614876)
			(xy 55.929508 -29.587625) (xy 55.937264 -29.533677) (xy 55.952619 -29.481382) (xy 55.975261 -29.431805)
			(xy 56.004727 -29.385955) (xy 56.040418 -29.344764) (xy 56.081609 -29.309073) (xy 56.127459 -29.279607)
			(xy 56.177036 -29.256965) (xy 56.229331 -29.24161) (xy 56.283279 -29.233854) (xy 56.337781 -29.233854)
			(xy 56.391729 -29.24161) (xy 56.444024 -29.256965) (xy 56.493601 -29.279607) (xy 56.539451 -29.309073)
			(xy 56.580642 -29.344764) (xy 56.616333 -29.385955) (xy 56.645799 -29.431805) (xy 56.668441 -29.481382)
			(xy 56.683796 -29.533677) (xy 56.691552 -29.587625) (xy 56.692038 -29.614876) (xy 56.691526 -29.643793)
			(xy 56.682799 -29.700966) (xy 56.665541 -29.756166) (xy 56.640149 -29.808128) (xy 56.607203 -29.855662)
			(xy 56.567459 -29.897677) (xy 56.544972 -29.915866) (xy 56.536185 -29.923493) (xy 56.525992 -29.944379)
			(xy 56.525414 -29.955998) (xy 56.525414 -30.035754) (xy 56.525931 -30.047389) (xy 56.536135 -30.068298)
			(xy 56.544972 -30.075886) (xy 56.567443 -30.094092) (xy 56.60718 -30.136108) (xy 56.640122 -30.183639)
			(xy 56.665512 -30.235598) (xy 56.682771 -30.290793) (xy 56.691502 -30.347961) (xy 56.692038 -30.376876)
			(xy 56.691552 -30.404127) (xy 56.683796 -30.458075) (xy 56.668441 -30.51037) (xy 56.645799 -30.559947)
			(xy 56.616333 -30.605797) (xy 56.580642 -30.646988) (xy 56.539451 -30.682679) (xy 56.493601 -30.712145)
			(xy 56.444024 -30.734787) (xy 56.391729 -30.750142) (xy 56.337781 -30.757898) (xy 56.283279 -30.757898)
			(xy 56.229331 -30.750142) (xy 56.177036 -30.734787) (xy 56.127459 -30.712145) (xy 56.081609 -30.682679)
			(xy 56.040418 -30.646988) (xy 56.004727 -30.605797) (xy 55.975261 -30.559947) (xy 55.952619 -30.51037)
			(xy 55.937264 -30.458075) (xy 55.929508 -30.404127) (xy 55.929022 -30.376876) (xy 53.651912 -30.376876)
			(xy 53.651426 -30.404127) (xy 53.64367 -30.458075) (xy 53.628315 -30.51037) (xy 53.605673 -30.559947)
			(xy 53.576207 -30.605797) (xy 53.540516 -30.646988) (xy 53.499325 -30.682679) (xy 53.453475 -30.712145)
			(xy 53.403898 -30.734787) (xy 53.351603 -30.750142) (xy 53.297655 -30.757898) (xy 53.243153 -30.757898)
			(xy 53.189205 -30.750142) (xy 53.13691 -30.734787) (xy 53.087333 -30.712145) (xy 53.041483 -30.682679)
			(xy 53.000292 -30.646988) (xy 52.964601 -30.605797) (xy 52.935135 -30.559947) (xy 52.912493 -30.51037)
			(xy 52.897138 -30.458075) (xy 52.889382 -30.404127) (xy 52.888896 -30.376876) (xy 48.405288 -30.376876)
			(xy 48.405288 -30.92069) (xy 48.405259 -30.922468) (xy 58.75274 -30.922468) (xy 58.75274 -30.058868)
			(xy 58.75323 -30.0289) (xy 58.761053 -29.969478) (xy 58.776566 -29.911585) (xy 58.799502 -29.856212)
			(xy 58.829469 -29.804306) (xy 58.865956 -29.756756) (xy 58.908336 -29.714376) (xy 58.955886 -29.677889)
			(xy 59.007792 -29.647922) (xy 59.063165 -29.624986) (xy 59.121058 -29.609473) (xy 59.18048 -29.60165)
			(xy 59.240416 -29.60165) (xy 59.299838 -29.609473) (xy 59.357731 -29.624986) (xy 59.413104 -29.647922)
			(xy 59.46501 -29.677889) (xy 59.51256 -29.714376) (xy 59.55494 -29.756756) (xy 59.591427 -29.804306)
			(xy 59.621394 -29.856212) (xy 59.64433 -29.911585) (xy 59.659843 -29.969478) (xy 59.667666 -30.0289)
			(xy 59.668156 -30.058868) (xy 59.668156 -30.92069) (xy 73.489312 -30.92069) (xy 73.489312 -30.05709)
			(xy 73.489802 -30.027106) (xy 73.49763 -29.96765) (xy 73.513151 -29.909725) (xy 73.5361 -29.854321)
			(xy 73.566084 -29.802387) (xy 73.60259 -29.754811) (xy 73.644995 -29.712406) (xy 73.692571 -29.6759)
			(xy 73.744505 -29.645916) (xy 73.799909 -29.622967) (xy 73.857834 -29.607446) (xy 73.91729 -29.599618)
			(xy 73.977258 -29.599618) (xy 74.036714 -29.607446) (xy 74.094639 -29.622967) (xy 74.150043 -29.645916)
			(xy 74.201977 -29.6759) (xy 74.249553 -29.712406) (xy 74.291958 -29.754811) (xy 74.328464 -29.802387)
			(xy 74.358448 -29.854321) (xy 74.381397 -29.909725) (xy 74.396918 -29.96765) (xy 74.404746 -30.027106)
			(xy 74.405236 -30.05709) (xy 74.405236 -30.376876) (xy 78.888844 -30.376876) (xy 78.8894 -30.34796)
			(xy 78.898119 -30.29079) (xy 78.915369 -30.235591) (xy 78.940753 -30.183629) (xy 78.973691 -30.136094)
			(xy 79.013427 -30.094077) (xy 79.03591 -30.075886) (xy 79.044715 -30.068277) (xy 79.054899 -30.047378)
			(xy 79.055468 -30.035754) (xy 79.055468 -29.955998) (xy 79.054927 -29.944366) (xy 79.044741 -29.923456)
			(xy 79.03591 -29.915866) (xy 79.013412 -29.897692) (xy 78.973678 -29.855669) (xy 78.94074 -29.80813)
			(xy 78.915354 -29.756166) (xy 78.898101 -29.700965) (xy 78.889376 -29.643793) (xy 78.888844 -29.614876)
			(xy 78.88933 -29.587625) (xy 78.897086 -29.533677) (xy 78.912441 -29.481382) (xy 78.935083 -29.431805)
			(xy 78.964549 -29.385955) (xy 79.00024 -29.344764) (xy 79.041431 -29.309073) (xy 79.087281 -29.279607)
			(xy 79.136858 -29.256965) (xy 79.189153 -29.24161) (xy 79.243101 -29.233854) (xy 79.297603 -29.233854)
			(xy 79.351551 -29.24161) (xy 79.403846 -29.256965) (xy 79.453423 -29.279607) (xy 79.499273 -29.309073)
			(xy 79.540464 -29.344764) (xy 79.576155 -29.385955) (xy 79.605621 -29.431805) (xy 79.628263 -29.481382)
			(xy 79.643618 -29.533677) (xy 79.651374 -29.587625) (xy 79.65186 -29.614876) (xy 79.65134 -29.643793)
			(xy 79.642613 -29.700965) (xy 79.625357 -29.756164) (xy 79.599965 -29.808126) (xy 79.567022 -29.85566)
			(xy 79.52728 -29.897676) (xy 79.504794 -29.915866) (xy 79.496011 -29.923497) (xy 79.485815 -29.94438)
			(xy 79.485236 -29.955998) (xy 79.485236 -30.035754) (xy 79.485746 -30.04739) (xy 79.495954 -30.0683)
			(xy 79.504794 -30.075886) (xy 79.52727 -30.094086) (xy 79.567005 -30.136104) (xy 79.599946 -30.183637)
			(xy 79.625335 -30.235596) (xy 79.642593 -30.290792) (xy 79.651324 -30.347961) (xy 79.65186 -30.376876)
			(xy 81.92897 -30.376876) (xy 81.929517 -30.34796) (xy 81.938236 -30.290789) (xy 81.955487 -30.235589)
			(xy 81.980873 -30.183627) (xy 82.013813 -30.136093) (xy 82.053552 -30.094076) (xy 82.076036 -30.075886)
			(xy 82.084846 -30.068281) (xy 82.095026 -30.047379) (xy 82.095594 -30.035754) (xy 82.095594 -29.955998)
			(xy 82.095044 -29.944367) (xy 82.084863 -29.923458) (xy 82.076036 -29.915866) (xy 82.053544 -29.897685)
			(xy 82.013807 -29.855664) (xy 81.980868 -29.808128) (xy 81.955481 -29.756164) (xy 81.938227 -29.700964)
			(xy 81.929502 -29.643793) (xy 81.92897 -29.614876) (xy 81.929456 -29.587625) (xy 81.937212 -29.533677)
			(xy 81.952567 -29.481382) (xy 81.975209 -29.431805) (xy 82.004675 -29.385955) (xy 82.040366 -29.344764)
			(xy 82.081557 -29.309073) (xy 82.127407 -29.279607) (xy 82.176984 -29.256965) (xy 82.229279 -29.24161)
			(xy 82.283227 -29.233854) (xy 82.337729 -29.233854) (xy 82.391677 -29.24161) (xy 82.443972 -29.256965)
			(xy 82.493549 -29.279607) (xy 82.539399 -29.309073) (xy 82.58059 -29.344764) (xy 82.616281 -29.385955)
			(xy 82.645747 -29.431805) (xy 82.668389 -29.481382) (xy 82.683744 -29.533677) (xy 82.6915 -29.587625)
			(xy 82.691986 -29.614876) (xy 82.691456 -29.643793) (xy 82.68273 -29.700963) (xy 82.665475 -29.756162)
			(xy 82.640085 -29.808124) (xy 82.607144 -29.855658) (xy 82.567405 -29.897676) (xy 82.54492 -29.915866)
			(xy 82.536125 -29.923484) (xy 82.525938 -29.944377) (xy 82.525362 -29.955998) (xy 82.525362 -30.035754)
			(xy 82.525863 -30.047391) (xy 82.536076 -30.068302) (xy 82.54492 -30.075886) (xy 82.567401 -30.09408)
			(xy 82.607135 -30.1361) (xy 82.640074 -30.183634) (xy 82.665463 -30.235595) (xy 82.68272 -30.290791)
			(xy 82.69145 -30.34796) (xy 82.691986 -30.376876) (xy 82.6915 -30.404127) (xy 82.683744 -30.458075)
			(xy 82.668389 -30.51037) (xy 82.645747 -30.559947) (xy 82.616281 -30.605797) (xy 82.58059 -30.646988)
			(xy 82.539399 -30.682679) (xy 82.493549 -30.712145) (xy 82.443972 -30.734787) (xy 82.391677 -30.750142)
			(xy 82.337729 -30.757898) (xy 82.283227 -30.757898) (xy 82.229279 -30.750142) (xy 82.176984 -30.734787)
			(xy 82.127407 -30.712145) (xy 82.081557 -30.682679) (xy 82.040366 -30.646988) (xy 82.004675 -30.605797)
			(xy 81.975209 -30.559947) (xy 81.952567 -30.51037) (xy 81.937212 -30.458075) (xy 81.929456 -30.404127)
			(xy 81.92897 -30.376876) (xy 79.65186 -30.376876) (xy 79.651374 -30.404127) (xy 79.643618 -30.458075)
			(xy 79.628263 -30.51037) (xy 79.605621 -30.559947) (xy 79.576155 -30.605797) (xy 79.540464 -30.646988)
			(xy 79.499273 -30.682679) (xy 79.453423 -30.712145) (xy 79.403846 -30.734787) (xy 79.351551 -30.750142)
			(xy 79.297603 -30.757898) (xy 79.243101 -30.757898) (xy 79.189153 -30.750142) (xy 79.136858 -30.734787)
			(xy 79.087281 -30.712145) (xy 79.041431 -30.682679) (xy 79.00024 -30.646988) (xy 78.964549 -30.605797)
			(xy 78.935083 -30.559947) (xy 78.912441 -30.51037) (xy 78.897086 -30.458075) (xy 78.88933 -30.404127)
			(xy 78.888844 -30.376876) (xy 74.405236 -30.376876) (xy 74.405236 -30.92069) (xy 74.405207 -30.922468)
			(xy 84.752688 -30.922468) (xy 84.752688 -30.058868) (xy 84.753178 -30.0289) (xy 84.761001 -29.969478)
			(xy 84.776514 -29.911585) (xy 84.79945 -29.856212) (xy 84.829417 -29.804306) (xy 84.865904 -29.756756)
			(xy 84.908284 -29.714376) (xy 84.955834 -29.677889) (xy 85.00774 -29.647922) (xy 85.063113 -29.624986)
			(xy 85.121006 -29.609473) (xy 85.180428 -29.60165) (xy 85.240364 -29.60165) (xy 85.299786 -29.609473)
			(xy 85.357679 -29.624986) (xy 85.413052 -29.647922) (xy 85.464958 -29.677889) (xy 85.512508 -29.714376)
			(xy 85.554888 -29.756756) (xy 85.591375 -29.804306) (xy 85.621342 -29.856212) (xy 85.644278 -29.911585)
			(xy 85.659791 -29.969478) (xy 85.667614 -30.0289) (xy 85.668104 -30.058868) (xy 85.668104 -30.92069)
			(xy 99.48926 -30.92069) (xy 99.48926 -30.05709) (xy 99.48975 -30.027106) (xy 99.497578 -29.96765)
			(xy 99.513099 -29.909725) (xy 99.536048 -29.854321) (xy 99.566032 -29.802387) (xy 99.602538 -29.754811)
			(xy 99.644943 -29.712406) (xy 99.692519 -29.6759) (xy 99.744453 -29.645916) (xy 99.799857 -29.622967)
			(xy 99.857782 -29.607446) (xy 99.917238 -29.599618) (xy 99.977206 -29.599618) (xy 100.036662 -29.607446)
			(xy 100.094587 -29.622967) (xy 100.149991 -29.645916) (xy 100.201925 -29.6759) (xy 100.249501 -29.712406)
			(xy 100.291906 -29.754811) (xy 100.328412 -29.802387) (xy 100.358396 -29.854321) (xy 100.381345 -29.909725)
			(xy 100.396866 -29.96765) (xy 100.404694 -30.027106) (xy 100.405184 -30.05709) (xy 100.405184 -30.376876)
			(xy 116.989098 -30.376876) (xy 116.989672 -30.347961) (xy 116.998389 -30.290793) (xy 117.015636 -30.235595)
			(xy 117.041017 -30.183633) (xy 117.073951 -30.136098) (xy 117.113683 -30.094078) (xy 117.136164 -30.075886)
			(xy 117.144978 -30.068286) (xy 117.155155 -30.047379) (xy 117.155722 -30.035754) (xy 117.155722 -29.955998)
			(xy 117.155162 -29.944369) (xy 117.144987 -29.92346) (xy 117.136164 -29.915866) (xy 117.113657 -29.897703)
			(xy 117.073925 -29.855677) (xy 117.04099 -29.808135) (xy 117.015606 -29.756169) (xy 116.998354 -29.700967)
			(xy 116.98963 -29.643794) (xy 116.989098 -29.614876) (xy 116.989584 -29.587625) (xy 116.99734 -29.533677)
			(xy 117.012695 -29.481382) (xy 117.035337 -29.431805) (xy 117.064803 -29.385955) (xy 117.100494 -29.344764)
			(xy 117.141685 -29.309073) (xy 117.187535 -29.279607) (xy 117.237112 -29.256965) (xy 117.289407 -29.24161)
			(xy 117.343355 -29.233854) (xy 117.397857 -29.233854) (xy 117.451805 -29.24161) (xy 117.5041 -29.256965)
			(xy 117.553677 -29.279607) (xy 117.599527 -29.309073) (xy 117.640718 -29.344764) (xy 117.676409 -29.385955)
			(xy 117.705875 -29.431805) (xy 117.728517 -29.481382) (xy 117.743872 -29.533677) (xy 117.751628 -29.587625)
			(xy 117.752114 -29.614876) (xy 117.751611 -29.643794) (xy 117.742884 -29.700967) (xy 117.725625 -29.756168)
			(xy 117.70023 -29.80813) (xy 117.667282 -29.855663) (xy 117.627536 -29.897678) (xy 117.605048 -29.915866)
			(xy 117.596257 -29.923489) (xy 117.586067 -29.944378) (xy 117.58549 -29.955998) (xy 117.58549 -30.035754)
			(xy 117.586016 -30.047387) (xy 117.596215 -30.068296) (xy 117.605048 -30.075886) (xy 117.627535 -30.094073)
			(xy 117.667268 -30.136095) (xy 117.700205 -30.183631) (xy 117.725592 -30.235593) (xy 117.742848 -30.290791)
			(xy 117.751578 -30.34796) (xy 117.752114 -30.376876) (xy 120.029224 -30.376876) (xy 120.029788 -30.347961)
			(xy 120.038506 -30.290791) (xy 120.055754 -30.235593) (xy 120.081137 -30.183631) (xy 120.114073 -30.136096)
			(xy 120.153808 -30.094077) (xy 120.17629 -30.075886) (xy 120.185092 -30.068274) (xy 120.195279 -30.047377)
			(xy 120.195848 -30.035754) (xy 120.195848 -29.955998) (xy 120.195314 -29.944365) (xy 120.185123 -29.923454)
			(xy 120.17629 -29.915866) (xy 120.153788 -29.897697) (xy 120.114055 -29.855672) (xy 120.081118 -29.808133)
			(xy 120.055733 -29.756167) (xy 120.038481 -29.700966) (xy 120.029756 -29.643793) (xy 120.029224 -29.614876)
			(xy 120.02971 -29.587625) (xy 120.037466 -29.533677) (xy 120.052821 -29.481382) (xy 120.075463 -29.431805)
			(xy 120.104929 -29.385955) (xy 120.14062 -29.344764) (xy 120.181811 -29.309073) (xy 120.227661 -29.279607)
			(xy 120.277238 -29.256965) (xy 120.329533 -29.24161) (xy 120.383481 -29.233854) (xy 120.437983 -29.233854)
			(xy 120.491931 -29.24161) (xy 120.544226 -29.256965) (xy 120.593803 -29.279607) (xy 120.639653 -29.309073)
			(xy 120.680844 -29.344764) (xy 120.716535 -29.385955) (xy 120.746001 -29.431805) (xy 120.768643 -29.481382)
			(xy 120.783998 -29.533677) (xy 120.791754 -29.587625) (xy 120.79224 -29.614876) (xy 120.791727 -29.643793)
			(xy 120.783 -29.700966) (xy 120.765743 -29.756166) (xy 120.74035 -29.808128) (xy 120.707405 -29.855662)
			(xy 120.667661 -29.897677) (xy 120.645174 -29.915866) (xy 120.636388 -29.923493) (xy 120.626194 -29.944379)
			(xy 120.625616 -29.955998) (xy 120.625616 -30.035754) (xy 120.626133 -30.047389) (xy 120.636337 -30.068298)
			(xy 120.645174 -30.075886) (xy 120.667645 -30.094092) (xy 120.707382 -30.136107) (xy 120.740324 -30.183639)
			(xy 120.765714 -30.235598) (xy 120.782973 -30.290793) (xy 120.791704 -30.347961) (xy 120.79224 -30.376876)
			(xy 120.791754 -30.404127) (xy 120.783998 -30.458075) (xy 120.768643 -30.51037) (xy 120.746001 -30.559947)
			(xy 120.716535 -30.605797) (xy 120.680844 -30.646988) (xy 120.639653 -30.682679) (xy 120.593803 -30.712145)
			(xy 120.544226 -30.734787) (xy 120.491931 -30.750142) (xy 120.437983 -30.757898) (xy 120.383481 -30.757898)
			(xy 120.329533 -30.750142) (xy 120.277238 -30.734787) (xy 120.227661 -30.712145) (xy 120.181811 -30.682679)
			(xy 120.14062 -30.646988) (xy 120.104929 -30.605797) (xy 120.075463 -30.559947) (xy 120.052821 -30.51037)
			(xy 120.037466 -30.458075) (xy 120.02971 -30.404127) (xy 120.029224 -30.376876) (xy 117.752114 -30.376876)
			(xy 117.751628 -30.404127) (xy 117.743872 -30.458075) (xy 117.728517 -30.51037) (xy 117.705875 -30.559947)
			(xy 117.676409 -30.605797) (xy 117.640718 -30.646988) (xy 117.599527 -30.682679) (xy 117.553677 -30.712145)
			(xy 117.5041 -30.734787) (xy 117.451805 -30.750142) (xy 117.397857 -30.757898) (xy 117.343355 -30.757898)
			(xy 117.289407 -30.750142) (xy 117.237112 -30.734787) (xy 117.187535 -30.712145) (xy 117.141685 -30.682679)
			(xy 117.100494 -30.646988) (xy 117.064803 -30.605797) (xy 117.035337 -30.559947) (xy 117.012695 -30.51037)
			(xy 116.99734 -30.458075) (xy 116.989584 -30.404127) (xy 116.989098 -30.376876) (xy 100.405184 -30.376876)
			(xy 100.405184 -30.92069) (xy 100.405155 -30.922468) (xy 122.852688 -30.922468) (xy 122.852688 -30.058868)
			(xy 122.853178 -30.028884) (xy 122.861006 -29.969428) (xy 122.876527 -29.911503) (xy 122.899476 -29.856099)
			(xy 122.92946 -29.804165) (xy 122.965966 -29.756589) (xy 123.008371 -29.714184) (xy 123.055947 -29.677678)
			(xy 123.107881 -29.647694) (xy 123.163285 -29.624745) (xy 123.22121 -29.609224) (xy 123.280666 -29.601396)
			(xy 123.340634 -29.601396) (xy 123.40009 -29.609224) (xy 123.458015 -29.624745) (xy 123.513419 -29.647694)
			(xy 123.565353 -29.677678) (xy 123.612929 -29.714184) (xy 123.655334 -29.756589) (xy 123.69184 -29.804165)
			(xy 123.721824 -29.856099) (xy 123.744773 -29.911503) (xy 123.760294 -29.969428) (xy 123.768122 -30.028884)
			(xy 123.768612 -30.058868) (xy 123.768612 -30.92069) (xy 137.589768 -30.92069) (xy 137.589768 -30.05709)
			(xy 137.590258 -30.027122) (xy 137.598081 -29.9677) (xy 137.613594 -29.909807) (xy 137.63653 -29.854434)
			(xy 137.666497 -29.802528) (xy 137.702984 -29.754978) (xy 137.745364 -29.712598) (xy 137.792914 -29.676111)
			(xy 137.84482 -29.646144) (xy 137.900193 -29.623208) (xy 137.958086 -29.607695) (xy 138.017508 -29.599872)
			(xy 138.077444 -29.599872) (xy 138.136866 -29.607695) (xy 138.194759 -29.623208) (xy 138.250132 -29.646144)
			(xy 138.302038 -29.676111) (xy 138.349588 -29.712598) (xy 138.391968 -29.754978) (xy 138.428455 -29.802528)
			(xy 138.458422 -29.854434) (xy 138.481358 -29.909807) (xy 138.496871 -29.9677) (xy 138.504694 -30.027122)
			(xy 138.505184 -30.05709) (xy 138.505184 -30.376876) (xy 142.989046 -30.376876) (xy 142.989602 -30.34796)
			(xy 142.998321 -30.29079) (xy 143.01557 -30.235591) (xy 143.040955 -30.183629) (xy 143.073892 -30.136094)
			(xy 143.113629 -30.094077) (xy 143.136112 -30.075886) (xy 143.144917 -30.068277) (xy 143.155101 -30.047378)
			(xy 143.15567 -30.035754) (xy 143.15567 -29.955998) (xy 143.155128 -29.944366) (xy 143.144942 -29.923456)
			(xy 143.136112 -29.915866) (xy 143.113615 -29.897691) (xy 143.07388 -29.855668) (xy 143.040942 -29.80813)
			(xy 143.015556 -29.756166) (xy 142.998303 -29.700965) (xy 142.989578 -29.643793) (xy 142.989046 -29.614876)
			(xy 142.989532 -29.587625) (xy 142.997288 -29.533677) (xy 143.012643 -29.481382) (xy 143.035285 -29.431805)
			(xy 143.064751 -29.385955) (xy 143.100442 -29.344764) (xy 143.141633 -29.309073) (xy 143.187483 -29.279607)
			(xy 143.23706 -29.256965) (xy 143.289355 -29.24161) (xy 143.343303 -29.233854) (xy 143.397805 -29.233854)
			(xy 143.451753 -29.24161) (xy 143.504048 -29.256965) (xy 143.553625 -29.279607) (xy 143.599475 -29.309073)
			(xy 143.640666 -29.344764) (xy 143.676357 -29.385955) (xy 143.705823 -29.431805) (xy 143.728465 -29.481382)
			(xy 143.74382 -29.533677) (xy 143.751576 -29.587625) (xy 143.752062 -29.614876) (xy 143.751541 -29.643793)
			(xy 143.742814 -29.700965) (xy 143.725558 -29.756164) (xy 143.700167 -29.808126) (xy 143.667223 -29.85566)
			(xy 143.627482 -29.897676) (xy 143.604996 -29.915866) (xy 143.596214 -29.923497) (xy 143.586017 -29.94438)
			(xy 143.585438 -29.955998) (xy 143.585438 -30.035754) (xy 143.585947 -30.04739) (xy 143.596156 -30.0683)
			(xy 143.604996 -30.075886) (xy 143.627472 -30.094086) (xy 143.667208 -30.136104) (xy 143.700148 -30.183637)
			(xy 143.725538 -30.235596) (xy 143.742795 -30.290792) (xy 143.751526 -30.347961) (xy 143.752062 -30.376876)
			(xy 146.029172 -30.376876) (xy 146.029718 -30.34796) (xy 146.038437 -30.290789) (xy 146.055688 -30.235589)
			(xy 146.081074 -30.183627) (xy 146.114015 -30.136092) (xy 146.153753 -30.094076) (xy 146.176238 -30.075886)
			(xy 146.185048 -30.068282) (xy 146.195228 -30.047379) (xy 146.195796 -30.035754) (xy 146.195796 -29.955998)
			(xy 146.195245 -29.944368) (xy 146.185065 -29.923458) (xy 146.176238 -29.915866) (xy 146.153746 -29.897685)
			(xy 146.11401 -29.855664) (xy 146.081071 -29.808127) (xy 146.055683 -29.756164) (xy 146.03843 -29.700964)
			(xy 146.029704 -29.643793) (xy 146.029172 -29.614876) (xy 146.029658 -29.587625) (xy 146.037414 -29.533677)
			(xy 146.052769 -29.481382) (xy 146.075411 -29.431805) (xy 146.104877 -29.385955) (xy 146.140568 -29.344764)
			(xy 146.181759 -29.309073) (xy 146.227609 -29.279607) (xy 146.277186 -29.256965) (xy 146.329481 -29.24161)
			(xy 146.383429 -29.233854) (xy 146.437931 -29.233854) (xy 146.491879 -29.24161) (xy 146.544174 -29.256965)
			(xy 146.593751 -29.279607) (xy 146.639601 -29.309073) (xy 146.680792 -29.344764) (xy 146.716483 -29.385955)
			(xy 146.745949 -29.431805) (xy 146.768591 -29.481382) (xy 146.783946 -29.533677) (xy 146.791702 -29.587625)
			(xy 146.792188 -29.614876) (xy 146.791657 -29.643792) (xy 146.782931 -29.700963) (xy 146.765676 -29.756162)
			(xy 146.740287 -29.808124) (xy 146.707345 -29.855658) (xy 146.667606 -29.897676) (xy 146.645122 -29.915866)
			(xy 146.636327 -29.923484) (xy 146.62614 -29.944377) (xy 146.625564 -29.955998) (xy 146.625564 -30.035754)
			(xy 146.626064 -30.047391) (xy 146.636278 -30.068302) (xy 146.645122 -30.075886) (xy 146.667603 -30.094079)
			(xy 146.707338 -30.136099) (xy 146.740276 -30.183634) (xy 146.765665 -30.235595) (xy 146.782922 -30.290791)
			(xy 146.791652 -30.34796) (xy 146.792188 -30.376876) (xy 146.791702 -30.404127) (xy 146.783946 -30.458075)
			(xy 146.768591 -30.51037) (xy 146.745949 -30.559947) (xy 146.716483 -30.605797) (xy 146.680792 -30.646988)
			(xy 146.639601 -30.682679) (xy 146.593751 -30.712145) (xy 146.544174 -30.734787) (xy 146.491879 -30.750142)
			(xy 146.437931 -30.757898) (xy 146.383429 -30.757898) (xy 146.329481 -30.750142) (xy 146.277186 -30.734787)
			(xy 146.227609 -30.712145) (xy 146.181759 -30.682679) (xy 146.140568 -30.646988) (xy 146.104877 -30.605797)
			(xy 146.075411 -30.559947) (xy 146.052769 -30.51037) (xy 146.037414 -30.458075) (xy 146.029658 -30.404127)
			(xy 146.029172 -30.376876) (xy 143.752062 -30.376876) (xy 143.751576 -30.404127) (xy 143.74382 -30.458075)
			(xy 143.728465 -30.51037) (xy 143.705823 -30.559947) (xy 143.676357 -30.605797) (xy 143.640666 -30.646988)
			(xy 143.599475 -30.682679) (xy 143.553625 -30.712145) (xy 143.504048 -30.734787) (xy 143.451753 -30.750142)
			(xy 143.397805 -30.757898) (xy 143.343303 -30.757898) (xy 143.289355 -30.750142) (xy 143.23706 -30.734787)
			(xy 143.187483 -30.712145) (xy 143.141633 -30.682679) (xy 143.100442 -30.646988) (xy 143.064751 -30.605797)
			(xy 143.035285 -30.559947) (xy 143.012643 -30.51037) (xy 142.997288 -30.458075) (xy 142.989532 -30.404127)
			(xy 142.989046 -30.376876) (xy 138.505184 -30.376876) (xy 138.505184 -30.92069) (xy 138.505155 -30.922468)
			(xy 148.852636 -30.922468) (xy 148.852636 -30.058868) (xy 148.853126 -30.028884) (xy 148.860954 -29.969428)
			(xy 148.876475 -29.911503) (xy 148.899424 -29.856099) (xy 148.929408 -29.804165) (xy 148.965914 -29.756589)
			(xy 149.008319 -29.714184) (xy 149.055895 -29.677678) (xy 149.107829 -29.647694) (xy 149.163233 -29.624745)
			(xy 149.221158 -29.609224) (xy 149.280614 -29.601396) (xy 149.340582 -29.601396) (xy 149.400038 -29.609224)
			(xy 149.457963 -29.624745) (xy 149.513367 -29.647694) (xy 149.565301 -29.677678) (xy 149.612877 -29.714184)
			(xy 149.655282 -29.756589) (xy 149.691788 -29.804165) (xy 149.721772 -29.856099) (xy 149.744721 -29.911503)
			(xy 149.760242 -29.969428) (xy 149.76807 -30.028884) (xy 149.76856 -30.058868) (xy 149.76856 -30.92069)
			(xy 163.589716 -30.92069) (xy 163.589716 -30.05709) (xy 163.590206 -30.027122) (xy 163.598029 -29.9677)
			(xy 163.613542 -29.909807) (xy 163.636478 -29.854434) (xy 163.666445 -29.802528) (xy 163.702932 -29.754978)
			(xy 163.745312 -29.712598) (xy 163.792862 -29.676111) (xy 163.844768 -29.646144) (xy 163.900141 -29.623208)
			(xy 163.958034 -29.607695) (xy 164.017456 -29.599872) (xy 164.077392 -29.599872) (xy 164.136814 -29.607695)
			(xy 164.194707 -29.623208) (xy 164.25008 -29.646144) (xy 164.301986 -29.676111) (xy 164.349536 -29.712598)
			(xy 164.391916 -29.754978) (xy 164.428403 -29.802528) (xy 164.45837 -29.854434) (xy 164.481306 -29.909807)
			(xy 164.496819 -29.9677) (xy 164.504642 -30.027122) (xy 164.505132 -30.05709) (xy 164.505132 -30.376876)
			(xy 168.988994 -30.376876) (xy 168.989531 -30.347959) (xy 168.998251 -30.290787) (xy 169.015503 -30.235587)
			(xy 169.040891 -30.183625) (xy 169.073833 -30.136091) (xy 169.113574 -30.094075) (xy 169.13606 -30.075886)
			(xy 169.144874 -30.068286) (xy 169.155051 -30.047379) (xy 169.155618 -30.035754) (xy 169.155618 -29.955998)
			(xy 169.155059 -29.944369) (xy 169.144884 -29.923459) (xy 169.13606 -29.915866) (xy 169.113552 -29.897704)
			(xy 169.07382 -29.855677) (xy 169.040885 -29.808136) (xy 169.015501 -29.756169) (xy 168.99825 -29.700967)
			(xy 168.989526 -29.643794) (xy 168.988994 -29.614876) (xy 168.98948 -29.587625) (xy 168.997236 -29.533677)
			(xy 169.012591 -29.481382) (xy 169.035233 -29.431805) (xy 169.064699 -29.385955) (xy 169.10039 -29.344764)
			(xy 169.141581 -29.309073) (xy 169.187431 -29.279607) (xy 169.237008 -29.256965) (xy 169.289303 -29.24161)
			(xy 169.343251 -29.233854) (xy 169.397753 -29.233854) (xy 169.451701 -29.24161) (xy 169.503996 -29.256965)
			(xy 169.553573 -29.279607) (xy 169.599423 -29.309073) (xy 169.640614 -29.344764) (xy 169.676305 -29.385955)
			(xy 169.705771 -29.431805) (xy 169.728413 -29.481382) (xy 169.743768 -29.533677) (xy 169.751524 -29.587625)
			(xy 169.75201 -29.614876) (xy 169.751509 -29.643794) (xy 169.742781 -29.700968) (xy 169.725522 -29.756168)
			(xy 169.700127 -29.808131) (xy 169.667179 -29.855664) (xy 169.627432 -29.897678) (xy 169.604944 -29.915866)
			(xy 169.596153 -29.923488) (xy 169.585963 -29.944378) (xy 169.585386 -29.955998) (xy 169.585386 -30.035754)
			(xy 169.585913 -30.047387) (xy 169.596111 -30.068296) (xy 169.604944 -30.075886) (xy 169.62743 -30.094074)
			(xy 169.667163 -30.136096) (xy 169.7001 -30.183632) (xy 169.725488 -30.235593) (xy 169.742744 -30.290791)
			(xy 169.751474 -30.34796) (xy 169.75201 -30.376876) (xy 172.02912 -30.376876) (xy 172.029685 -30.347961)
			(xy 172.038403 -30.290791) (xy 172.055651 -30.235593) (xy 172.081034 -30.183631) (xy 172.11397 -30.136096)
			(xy 172.153704 -30.094077) (xy 172.176186 -30.075886) (xy 172.185004 -30.06829) (xy 172.195178 -30.04738)
			(xy 172.195744 -30.035754) (xy 172.195744 -29.955998) (xy 172.195211 -29.944365) (xy 172.18502 -29.923454)
			(xy 172.176186 -29.915866) (xy 172.153683 -29.897698) (xy 172.11395 -29.855673) (xy 172.081014 -29.808133)
			(xy 172.055629 -29.756167) (xy 172.038377 -29.700966) (xy 172.029652 -29.643793) (xy 172.02912 -29.614876)
			(xy 172.029606 -29.587625) (xy 172.037362 -29.533677) (xy 172.052717 -29.481382) (xy 172.075359 -29.431805)
			(xy 172.104825 -29.385955) (xy 172.140516 -29.344764) (xy 172.181707 -29.309073) (xy 172.227557 -29.279607)
			(xy 172.277134 -29.256965) (xy 172.329429 -29.24161) (xy 172.383377 -29.233854) (xy 172.437879 -29.233854)
			(xy 172.491827 -29.24161) (xy 172.544122 -29.256965) (xy 172.593699 -29.279607) (xy 172.639549 -29.309073)
			(xy 172.68074 -29.344764) (xy 172.716431 -29.385955) (xy 172.745897 -29.431805) (xy 172.768539 -29.481382)
			(xy 172.783894 -29.533677) (xy 172.79165 -29.587625) (xy 172.792136 -29.614876) (xy 172.791625 -29.643793)
			(xy 172.782898 -29.700966) (xy 172.76564 -29.756166) (xy 172.740247 -29.808128) (xy 172.707301 -29.855662)
			(xy 172.667557 -29.897677) (xy 172.64507 -29.915866) (xy 172.636283 -29.923493) (xy 172.62609 -29.944379)
			(xy 172.625512 -29.955998) (xy 172.625512 -30.035754) (xy 172.62603 -30.047389) (xy 172.636233 -30.068298)
			(xy 172.64507 -30.075886) (xy 172.667541 -30.094093) (xy 172.707278 -30.136108) (xy 172.740219 -30.18364)
			(xy 172.76561 -30.235598) (xy 172.782869 -30.290793) (xy 172.7916 -30.347961) (xy 172.792136 -30.376876)
			(xy 172.79165 -30.404127) (xy 172.783894 -30.458075) (xy 172.768539 -30.51037) (xy 172.745897 -30.559947)
			(xy 172.716431 -30.605797) (xy 172.68074 -30.646988) (xy 172.639549 -30.682679) (xy 172.593699 -30.712145)
			(xy 172.544122 -30.734787) (xy 172.491827 -30.750142) (xy 172.437879 -30.757898) (xy 172.383377 -30.757898)
			(xy 172.329429 -30.750142) (xy 172.277134 -30.734787) (xy 172.227557 -30.712145) (xy 172.181707 -30.682679)
			(xy 172.140516 -30.646988) (xy 172.104825 -30.605797) (xy 172.075359 -30.559947) (xy 172.052717 -30.51037)
			(xy 172.037362 -30.458075) (xy 172.029606 -30.404127) (xy 172.02912 -30.376876) (xy 169.75201 -30.376876)
			(xy 169.751524 -30.404127) (xy 169.743768 -30.458075) (xy 169.728413 -30.51037) (xy 169.705771 -30.559947)
			(xy 169.676305 -30.605797) (xy 169.640614 -30.646988) (xy 169.599423 -30.682679) (xy 169.553573 -30.712145)
			(xy 169.503996 -30.734787) (xy 169.451701 -30.750142) (xy 169.397753 -30.757898) (xy 169.343251 -30.757898)
			(xy 169.289303 -30.750142) (xy 169.237008 -30.734787) (xy 169.187431 -30.712145) (xy 169.141581 -30.682679)
			(xy 169.10039 -30.646988) (xy 169.064699 -30.605797) (xy 169.035233 -30.559947) (xy 169.012591 -30.51037)
			(xy 168.997236 -30.458075) (xy 168.98948 -30.404127) (xy 168.988994 -30.376876) (xy 164.505132 -30.376876)
			(xy 164.505132 -30.92069) (xy 164.505103 -30.922468) (xy 174.852584 -30.922468) (xy 174.852584 -30.058868)
			(xy 174.853074 -30.028884) (xy 174.860902 -29.969428) (xy 174.876423 -29.911503) (xy 174.899372 -29.856099)
			(xy 174.929356 -29.804165) (xy 174.965862 -29.756589) (xy 175.008267 -29.714184) (xy 175.055843 -29.677678)
			(xy 175.107777 -29.647694) (xy 175.163181 -29.624745) (xy 175.221106 -29.609224) (xy 175.280562 -29.601396)
			(xy 175.34053 -29.601396) (xy 175.399986 -29.609224) (xy 175.457911 -29.624745) (xy 175.513315 -29.647694)
			(xy 175.565249 -29.677678) (xy 175.612825 -29.714184) (xy 175.65523 -29.756589) (xy 175.691736 -29.804165)
			(xy 175.72172 -29.856099) (xy 175.744669 -29.911503) (xy 175.76019 -29.969428) (xy 175.768018 -30.028884)
			(xy 175.768508 -30.058868) (xy 175.768508 -30.92069) (xy 189.589664 -30.92069) (xy 189.589664 -30.05709)
			(xy 189.590154 -30.027122) (xy 189.597977 -29.9677) (xy 189.61349 -29.909807) (xy 189.636426 -29.854434)
			(xy 189.666393 -29.802528) (xy 189.70288 -29.754978) (xy 189.74526 -29.712598) (xy 189.79281 -29.676111)
			(xy 189.844716 -29.646144) (xy 189.900089 -29.623208) (xy 189.957982 -29.607695) (xy 190.017404 -29.599872)
			(xy 190.07734 -29.599872) (xy 190.136762 -29.607695) (xy 190.194655 -29.623208) (xy 190.250028 -29.646144)
			(xy 190.301934 -29.676111) (xy 190.349484 -29.712598) (xy 190.391864 -29.754978) (xy 190.428351 -29.802528)
			(xy 190.458318 -29.854434) (xy 190.481254 -29.909807) (xy 190.496767 -29.9677) (xy 190.50459 -30.027122)
			(xy 190.50508 -30.05709) (xy 190.50508 -30.376876) (xy 194.988942 -30.376876) (xy 194.989499 -30.34796)
			(xy 194.998218 -30.29079) (xy 195.015467 -30.235592) (xy 195.040851 -30.183629) (xy 195.073789 -30.136095)
			(xy 195.113525 -30.094077) (xy 195.136008 -30.075886) (xy 195.144813 -30.068276) (xy 195.154997 -30.047378)
			(xy 195.155566 -30.035754) (xy 195.155566 -29.955998) (xy 195.155026 -29.944366) (xy 195.144839 -29.923456)
			(xy 195.136008 -29.915866) (xy 195.11351 -29.897692) (xy 195.073775 -29.855669) (xy 195.040838 -29.808131)
			(xy 195.015452 -29.756166) (xy 194.998199 -29.700965) (xy 194.989474 -29.643793) (xy 194.988942 -29.614876)
			(xy 194.989428 -29.587625) (xy 194.997184 -29.533677) (xy 195.012539 -29.481382) (xy 195.035181 -29.431805)
			(xy 195.064647 -29.385955) (xy 195.100338 -29.344764) (xy 195.141529 -29.309073) (xy 195.187379 -29.279607)
			(xy 195.236956 -29.256965) (xy 195.289251 -29.24161) (xy 195.343199 -29.233854) (xy 195.397701 -29.233854)
			(xy 195.451649 -29.24161) (xy 195.503944 -29.256965) (xy 195.553521 -29.279607) (xy 195.599371 -29.309073)
			(xy 195.640562 -29.344764) (xy 195.676253 -29.385955) (xy 195.705719 -29.431805) (xy 195.728361 -29.481382)
			(xy 195.743716 -29.533677) (xy 195.751472 -29.587625) (xy 195.751958 -29.614876) (xy 195.751438 -29.643793)
			(xy 195.742712 -29.700965) (xy 195.725455 -29.756164) (xy 195.700064 -29.808126) (xy 195.66712 -29.85566)
			(xy 195.627378 -29.897676) (xy 195.604892 -29.915866) (xy 195.596109 -29.923497) (xy 195.585912 -29.944379)
			(xy 195.585334 -29.955998) (xy 195.585334 -30.035754) (xy 195.585845 -30.04739) (xy 195.596053 -30.0683)
			(xy 195.604892 -30.075886) (xy 195.627367 -30.094087) (xy 195.667103 -30.136104) (xy 195.700043 -30.183637)
			(xy 195.725433 -30.235597) (xy 195.742691 -30.290792) (xy 195.751422 -30.347961) (xy 195.751958 -30.376876)
			(xy 198.029068 -30.376876) (xy 198.029615 -30.34796) (xy 198.038335 -30.290789) (xy 198.055585 -30.23559)
			(xy 198.080971 -30.183627) (xy 198.113911 -30.136093) (xy 198.15365 -30.094076) (xy 198.176134 -30.075886)
			(xy 198.184943 -30.068281) (xy 198.195124 -30.047378) (xy 198.195692 -30.035754) (xy 198.195692 -29.955998)
			(xy 198.195143 -29.944367) (xy 198.184961 -29.923457) (xy 198.176134 -29.915866) (xy 198.153641 -29.897686)
			(xy 198.113905 -29.855665) (xy 198.080966 -29.808128) (xy 198.055579 -29.756164) (xy 198.038325 -29.700964)
			(xy 198.0296 -29.643793) (xy 198.029068 -29.614876) (xy 198.029554 -29.587625) (xy 198.03731 -29.533677)
			(xy 198.052665 -29.481382) (xy 198.075307 -29.431805) (xy 198.104773 -29.385955) (xy 198.140464 -29.344764)
			(xy 198.181655 -29.309073) (xy 198.227505 -29.279607) (xy 198.277082 -29.256965) (xy 198.329377 -29.24161)
			(xy 198.383325 -29.233854) (xy 198.437827 -29.233854) (xy 198.491775 -29.24161) (xy 198.54407 -29.256965)
			(xy 198.593647 -29.279607) (xy 198.639497 -29.309073) (xy 198.680688 -29.344764) (xy 198.716379 -29.385955)
			(xy 198.745845 -29.431805) (xy 198.768487 -29.481382) (xy 198.783842 -29.533677) (xy 198.791598 -29.587625)
			(xy 198.792084 -29.614876) (xy 198.791554 -29.643793) (xy 198.782829 -29.700964) (xy 198.765573 -29.756162)
			(xy 198.740184 -29.808124) (xy 198.707242 -29.855658) (xy 198.667503 -29.897676) (xy 198.645018 -29.915866)
			(xy 198.636222 -29.923484) (xy 198.626036 -29.944377) (xy 198.62546 -29.955998) (xy 198.62546 -30.035754)
			(xy 198.625961 -30.047391) (xy 198.636175 -30.068302) (xy 198.645018 -30.075886) (xy 198.667499 -30.09408)
			(xy 198.707233 -30.1361) (xy 198.740172 -30.183634) (xy 198.765561 -30.235595) (xy 198.782818 -30.290792)
			(xy 198.791548 -30.34796) (xy 198.792084 -30.376876) (xy 198.791598 -30.404127) (xy 198.783842 -30.458075)
			(xy 198.768487 -30.51037) (xy 198.745845 -30.559947) (xy 198.716379 -30.605797) (xy 198.680688 -30.646988)
			(xy 198.639497 -30.682679) (xy 198.593647 -30.712145) (xy 198.54407 -30.734787) (xy 198.491775 -30.750142)
			(xy 198.437827 -30.757898) (xy 198.383325 -30.757898) (xy 198.329377 -30.750142) (xy 198.277082 -30.734787)
			(xy 198.227505 -30.712145) (xy 198.181655 -30.682679) (xy 198.140464 -30.646988) (xy 198.104773 -30.605797)
			(xy 198.075307 -30.559947) (xy 198.052665 -30.51037) (xy 198.03731 -30.458075) (xy 198.029554 -30.404127)
			(xy 198.029068 -30.376876) (xy 195.751958 -30.376876) (xy 195.751472 -30.404127) (xy 195.743716 -30.458075)
			(xy 195.728361 -30.51037) (xy 195.705719 -30.559947) (xy 195.676253 -30.605797) (xy 195.640562 -30.646988)
			(xy 195.599371 -30.682679) (xy 195.553521 -30.712145) (xy 195.503944 -30.734787) (xy 195.451649 -30.750142)
			(xy 195.397701 -30.757898) (xy 195.343199 -30.757898) (xy 195.289251 -30.750142) (xy 195.236956 -30.734787)
			(xy 195.187379 -30.712145) (xy 195.141529 -30.682679) (xy 195.100338 -30.646988) (xy 195.064647 -30.605797)
			(xy 195.035181 -30.559947) (xy 195.012539 -30.51037) (xy 194.997184 -30.458075) (xy 194.989428 -30.404127)
			(xy 194.988942 -30.376876) (xy 190.50508 -30.376876) (xy 190.50508 -30.92069) (xy 190.505051 -30.922468)
			(xy 200.852532 -30.922468) (xy 200.852532 -30.058868) (xy 200.853022 -30.028884) (xy 200.86085 -29.969428)
			(xy 200.876371 -29.911503) (xy 200.89932 -29.856099) (xy 200.929304 -29.804165) (xy 200.96581 -29.756589)
			(xy 201.008215 -29.714184) (xy 201.055791 -29.677678) (xy 201.107725 -29.647694) (xy 201.163129 -29.624745)
			(xy 201.221054 -29.609224) (xy 201.28051 -29.601396) (xy 201.340478 -29.601396) (xy 201.399934 -29.609224)
			(xy 201.457859 -29.624745) (xy 201.513263 -29.647694) (xy 201.565197 -29.677678) (xy 201.612773 -29.714184)
			(xy 201.655178 -29.756589) (xy 201.691684 -29.804165) (xy 201.721668 -29.856099) (xy 201.744617 -29.911503)
			(xy 201.760138 -29.969428) (xy 201.767966 -30.028884) (xy 201.768456 -30.058868) (xy 201.768456 -30.92069)
			(xy 215.589612 -30.92069) (xy 215.589612 -30.05709) (xy 215.590102 -30.027122) (xy 215.597925 -29.9677)
			(xy 215.613438 -29.909807) (xy 215.636374 -29.854434) (xy 215.666341 -29.802528) (xy 215.702828 -29.754978)
			(xy 215.745208 -29.712598) (xy 215.792758 -29.676111) (xy 215.844664 -29.646144) (xy 215.900037 -29.623208)
			(xy 215.95793 -29.607695) (xy 216.017352 -29.599872) (xy 216.077288 -29.599872) (xy 216.13671 -29.607695)
			(xy 216.194603 -29.623208) (xy 216.249976 -29.646144) (xy 216.301882 -29.676111) (xy 216.349432 -29.712598)
			(xy 216.391812 -29.754978) (xy 216.428299 -29.802528) (xy 216.458266 -29.854434) (xy 216.481202 -29.909807)
			(xy 216.496715 -29.9677) (xy 216.504538 -30.027122) (xy 216.505028 -30.05709) (xy 216.505028 -30.376876)
			(xy 233.088942 -30.376876) (xy 233.089499 -30.34796) (xy 233.098218 -30.29079) (xy 233.115467 -30.235592)
			(xy 233.140851 -30.183629) (xy 233.173789 -30.136095) (xy 233.213525 -30.094077) (xy 233.236008 -30.075886)
			(xy 233.244813 -30.068276) (xy 233.254997 -30.047378) (xy 233.255566 -30.035754) (xy 233.255566 -29.955998)
			(xy 233.255026 -29.944366) (xy 233.244839 -29.923456) (xy 233.236008 -29.915866) (xy 233.21351 -29.897692)
			(xy 233.173775 -29.855669) (xy 233.140838 -29.808131) (xy 233.115452 -29.756166) (xy 233.098199 -29.700965)
			(xy 233.089474 -29.643793) (xy 233.088942 -29.614876) (xy 233.089428 -29.587625) (xy 233.097184 -29.533677)
			(xy 233.112539 -29.481382) (xy 233.135181 -29.431805) (xy 233.164647 -29.385955) (xy 233.200338 -29.344764)
			(xy 233.241529 -29.309073) (xy 233.287379 -29.279607) (xy 233.336956 -29.256965) (xy 233.389251 -29.24161)
			(xy 233.443199 -29.233854) (xy 233.497701 -29.233854) (xy 233.551649 -29.24161) (xy 233.603944 -29.256965)
			(xy 233.653521 -29.279607) (xy 233.699371 -29.309073) (xy 233.740562 -29.344764) (xy 233.776253 -29.385955)
			(xy 233.805719 -29.431805) (xy 233.828361 -29.481382) (xy 233.843716 -29.533677) (xy 233.851472 -29.587625)
			(xy 233.851958 -29.614876) (xy 233.851438 -29.643793) (xy 233.842712 -29.700965) (xy 233.825455 -29.756164)
			(xy 233.800064 -29.808126) (xy 233.76712 -29.85566) (xy 233.727378 -29.897676) (xy 233.704892 -29.915866)
			(xy 233.696109 -29.923497) (xy 233.685912 -29.944379) (xy 233.685334 -29.955998) (xy 233.685334 -30.035754)
			(xy 233.685845 -30.04739) (xy 233.696053 -30.0683) (xy 233.704892 -30.075886) (xy 233.727367 -30.094087)
			(xy 233.767103 -30.136104) (xy 233.800043 -30.183637) (xy 233.825433 -30.235597) (xy 233.842691 -30.290792)
			(xy 233.851422 -30.347961) (xy 233.851958 -30.376876) (xy 236.129068 -30.376876) (xy 236.129615 -30.34796)
			(xy 236.138335 -30.290789) (xy 236.155585 -30.23559) (xy 236.180971 -30.183627) (xy 236.213911 -30.136093)
			(xy 236.25365 -30.094076) (xy 236.276134 -30.075886) (xy 236.284943 -30.068281) (xy 236.295124 -30.047378)
			(xy 236.295692 -30.035754) (xy 236.295692 -29.955998) (xy 236.295143 -29.944367) (xy 236.284961 -29.923457)
			(xy 236.276134 -29.915866) (xy 236.253641 -29.897686) (xy 236.213905 -29.855665) (xy 236.180966 -29.808128)
			(xy 236.155579 -29.756164) (xy 236.138325 -29.700964) (xy 236.1296 -29.643793) (xy 236.129068 -29.614876)
			(xy 236.129554 -29.587625) (xy 236.13731 -29.533677) (xy 236.152665 -29.481382) (xy 236.175307 -29.431805)
			(xy 236.204773 -29.385955) (xy 236.240464 -29.344764) (xy 236.281655 -29.309073) (xy 236.327505 -29.279607)
			(xy 236.377082 -29.256965) (xy 236.429377 -29.24161) (xy 236.483325 -29.233854) (xy 236.537827 -29.233854)
			(xy 236.591775 -29.24161) (xy 236.64407 -29.256965) (xy 236.693647 -29.279607) (xy 236.739497 -29.309073)
			(xy 236.780688 -29.344764) (xy 236.816379 -29.385955) (xy 236.845845 -29.431805) (xy 236.868487 -29.481382)
			(xy 236.883842 -29.533677) (xy 236.891598 -29.587625) (xy 236.892084 -29.614876) (xy 236.891554 -29.643793)
			(xy 236.882829 -29.700964) (xy 236.865573 -29.756162) (xy 236.840184 -29.808124) (xy 236.807242 -29.855658)
			(xy 236.767503 -29.897676) (xy 236.745018 -29.915866) (xy 236.736222 -29.923484) (xy 236.726036 -29.944377)
			(xy 236.72546 -29.955998) (xy 236.72546 -30.035754) (xy 236.725961 -30.047391) (xy 236.736175 -30.068302)
			(xy 236.745018 -30.075886) (xy 236.767499 -30.09408) (xy 236.807233 -30.1361) (xy 236.840172 -30.183634)
			(xy 236.865561 -30.235595) (xy 236.882818 -30.290792) (xy 236.891548 -30.34796) (xy 236.892084 -30.376876)
			(xy 236.891598 -30.404127) (xy 236.883842 -30.458075) (xy 236.868487 -30.51037) (xy 236.845845 -30.559947)
			(xy 236.816379 -30.605797) (xy 236.780688 -30.646988) (xy 236.739497 -30.682679) (xy 236.693647 -30.712145)
			(xy 236.64407 -30.734787) (xy 236.591775 -30.750142) (xy 236.537827 -30.757898) (xy 236.483325 -30.757898)
			(xy 236.429377 -30.750142) (xy 236.377082 -30.734787) (xy 236.327505 -30.712145) (xy 236.281655 -30.682679)
			(xy 236.240464 -30.646988) (xy 236.204773 -30.605797) (xy 236.175307 -30.559947) (xy 236.152665 -30.51037)
			(xy 236.13731 -30.458075) (xy 236.129554 -30.404127) (xy 236.129068 -30.376876) (xy 233.851958 -30.376876)
			(xy 233.851472 -30.404127) (xy 233.843716 -30.458075) (xy 233.828361 -30.51037) (xy 233.805719 -30.559947)
			(xy 233.776253 -30.605797) (xy 233.740562 -30.646988) (xy 233.699371 -30.682679) (xy 233.653521 -30.712145)
			(xy 233.603944 -30.734787) (xy 233.551649 -30.750142) (xy 233.497701 -30.757898) (xy 233.443199 -30.757898)
			(xy 233.389251 -30.750142) (xy 233.336956 -30.734787) (xy 233.287379 -30.712145) (xy 233.241529 -30.682679)
			(xy 233.200338 -30.646988) (xy 233.164647 -30.605797) (xy 233.135181 -30.559947) (xy 233.112539 -30.51037)
			(xy 233.097184 -30.458075) (xy 233.089428 -30.404127) (xy 233.088942 -30.376876) (xy 216.505028 -30.376876)
			(xy 216.505028 -30.92069) (xy 216.504999 -30.922468) (xy 238.952532 -30.922468) (xy 238.952532 -30.058868)
			(xy 238.953022 -30.028884) (xy 238.96085 -29.969428) (xy 238.976371 -29.911503) (xy 238.99932 -29.856099)
			(xy 239.029304 -29.804165) (xy 239.06581 -29.756589) (xy 239.108215 -29.714184) (xy 239.155791 -29.677678)
			(xy 239.207725 -29.647694) (xy 239.263129 -29.624745) (xy 239.321054 -29.609224) (xy 239.38051 -29.601396)
			(xy 239.440478 -29.601396) (xy 239.499934 -29.609224) (xy 239.557859 -29.624745) (xy 239.613263 -29.647694)
			(xy 239.665197 -29.677678) (xy 239.712773 -29.714184) (xy 239.755178 -29.756589) (xy 239.791684 -29.804165)
			(xy 239.821668 -29.856099) (xy 239.844617 -29.911503) (xy 239.860138 -29.969428) (xy 239.867966 -30.028884)
			(xy 239.868456 -30.058868) (xy 239.868456 -30.92069) (xy 253.689612 -30.92069) (xy 253.689612 -30.05709)
			(xy 253.690102 -30.027122) (xy 253.697925 -29.9677) (xy 253.713438 -29.909807) (xy 253.736374 -29.854434)
			(xy 253.766341 -29.802528) (xy 253.802828 -29.754978) (xy 253.845208 -29.712598) (xy 253.892758 -29.676111)
			(xy 253.944664 -29.646144) (xy 254.000037 -29.623208) (xy 254.05793 -29.607695) (xy 254.117352 -29.599872)
			(xy 254.177288 -29.599872) (xy 254.23671 -29.607695) (xy 254.294603 -29.623208) (xy 254.349976 -29.646144)
			(xy 254.401882 -29.676111) (xy 254.449432 -29.712598) (xy 254.491812 -29.754978) (xy 254.528299 -29.802528)
			(xy 254.558266 -29.854434) (xy 254.581202 -29.909807) (xy 254.596715 -29.9677) (xy 254.604538 -30.027122)
			(xy 254.605028 -30.05709) (xy 254.605028 -30.376876) (xy 259.08889 -30.376876) (xy 259.089429 -30.347959)
			(xy 259.098149 -30.290788) (xy 259.1154 -30.235588) (xy 259.140788 -30.183625) (xy 259.17373 -30.136091)
			(xy 259.213471 -30.094075) (xy 259.235956 -30.075886) (xy 259.244769 -30.068285) (xy 259.254947 -30.047379)
			(xy 259.255514 -30.035754) (xy 259.255514 -29.955998) (xy 259.254957 -29.944369) (xy 259.24478 -29.923459)
			(xy 259.235956 -29.915866) (xy 259.213447 -29.897705) (xy 259.173715 -29.855678) (xy 259.140781 -29.808136)
			(xy 259.115397 -29.756169) (xy 259.098146 -29.700967) (xy 259.089422 -29.643794) (xy 259.08889 -29.614876)
			(xy 259.089376 -29.587625) (xy 259.097132 -29.533677) (xy 259.112487 -29.481382) (xy 259.135129 -29.431805)
			(xy 259.164595 -29.385955) (xy 259.200286 -29.344764) (xy 259.241477 -29.309073) (xy 259.287327 -29.279607)
			(xy 259.336904 -29.256965) (xy 259.389199 -29.24161) (xy 259.443147 -29.233854) (xy 259.497649 -29.233854)
			(xy 259.551597 -29.24161) (xy 259.603892 -29.256965) (xy 259.653469 -29.279607) (xy 259.699319 -29.309073)
			(xy 259.74051 -29.344764) (xy 259.776201 -29.385955) (xy 259.805667 -29.431805) (xy 259.828309 -29.481382)
			(xy 259.843664 -29.533677) (xy 259.85142 -29.587625) (xy 259.851906 -29.614876) (xy 259.851406 -29.643794)
			(xy 259.842678 -29.700968) (xy 259.825419 -29.756168) (xy 259.800024 -29.808131) (xy 259.767076 -29.855664)
			(xy 259.727329 -29.897678) (xy 259.70484 -29.915866) (xy 259.696048 -29.923487) (xy 259.685858 -29.944378)
			(xy 259.685282 -29.955998) (xy 259.685282 -30.035754) (xy 259.685811 -30.047387) (xy 259.696008 -30.068296)
			(xy 259.70484 -30.075886) (xy 259.727325 -30.094075) (xy 259.767058 -30.136096) (xy 259.799996 -30.183632)
			(xy 259.825384 -30.235593) (xy 259.84264 -30.290791) (xy 259.85137 -30.34796) (xy 259.851906 -30.376876)
			(xy 262.129016 -30.376876) (xy 262.129583 -30.347961) (xy 262.138301 -30.290792) (xy 262.155549 -30.235593)
			(xy 262.180931 -30.183631) (xy 262.213867 -30.136096) (xy 262.2536 -30.094077) (xy 262.276082 -30.075886)
			(xy 262.284899 -30.068289) (xy 262.295074 -30.04738) (xy 262.29564 -30.035754) (xy 262.29564 -29.955998)
			(xy 262.295109 -29.944365) (xy 262.284917 -29.923454) (xy 262.276082 -29.915866) (xy 262.253578 -29.897699)
			(xy 262.213845 -29.855673) (xy 262.180909 -29.808134) (xy 262.155524 -29.756168) (xy 262.138272 -29.700966)
			(xy 262.129548 -29.643793) (xy 262.129016 -29.614876) (xy 262.129502 -29.587625) (xy 262.137258 -29.533677)
			(xy 262.152613 -29.481382) (xy 262.175255 -29.431805) (xy 262.204721 -29.385955) (xy 262.240412 -29.344764)
			(xy 262.281603 -29.309073) (xy 262.327453 -29.279607) (xy 262.37703 -29.256965) (xy 262.429325 -29.24161)
			(xy 262.483273 -29.233854) (xy 262.537775 -29.233854) (xy 262.591723 -29.24161) (xy 262.644018 -29.256965)
			(xy 262.693595 -29.279607) (xy 262.739445 -29.309073) (xy 262.780636 -29.344764) (xy 262.816327 -29.385955)
			(xy 262.845793 -29.431805) (xy 262.868435 -29.481382) (xy 262.88379 -29.533677) (xy 262.891546 -29.587625)
			(xy 262.892032 -29.614876) (xy 262.891522 -29.643794) (xy 262.882795 -29.700966) (xy 262.865537 -29.756166)
			(xy 262.840144 -29.808129) (xy 262.807198 -29.855662) (xy 262.767453 -29.897677) (xy 262.744966 -29.915866)
			(xy 262.736179 -29.923492) (xy 262.725985 -29.944379) (xy 262.725408 -29.955998) (xy 262.725408 -30.035754)
			(xy 262.725927 -30.047388) (xy 262.73613 -30.068298) (xy 262.744966 -30.075886) (xy 262.767436 -30.094094)
			(xy 262.807173 -30.136109) (xy 262.840115 -30.18364) (xy 262.865506 -30.235598) (xy 262.882765 -30.290793)
			(xy 262.891496 -30.347961) (xy 262.892032 -30.376876) (xy 262.891546 -30.404127) (xy 262.88379 -30.458075)
			(xy 262.868435 -30.51037) (xy 262.845793 -30.559947) (xy 262.816327 -30.605797) (xy 262.780636 -30.646988)
			(xy 262.739445 -30.682679) (xy 262.693595 -30.712145) (xy 262.644018 -30.734787) (xy 262.591723 -30.750142)
			(xy 262.537775 -30.757898) (xy 262.483273 -30.757898) (xy 262.429325 -30.750142) (xy 262.37703 -30.734787)
			(xy 262.327453 -30.712145) (xy 262.281603 -30.682679) (xy 262.240412 -30.646988) (xy 262.204721 -30.605797)
			(xy 262.175255 -30.559947) (xy 262.152613 -30.51037) (xy 262.137258 -30.458075) (xy 262.129502 -30.404127)
			(xy 262.129016 -30.376876) (xy 259.851906 -30.376876) (xy 259.85142 -30.404127) (xy 259.843664 -30.458075)
			(xy 259.828309 -30.51037) (xy 259.805667 -30.559947) (xy 259.776201 -30.605797) (xy 259.74051 -30.646988)
			(xy 259.699319 -30.682679) (xy 259.653469 -30.712145) (xy 259.603892 -30.734787) (xy 259.551597 -30.750142)
			(xy 259.497649 -30.757898) (xy 259.443147 -30.757898) (xy 259.389199 -30.750142) (xy 259.336904 -30.734787)
			(xy 259.287327 -30.712145) (xy 259.241477 -30.682679) (xy 259.200286 -30.646988) (xy 259.164595 -30.605797)
			(xy 259.135129 -30.559947) (xy 259.112487 -30.51037) (xy 259.097132 -30.458075) (xy 259.089376 -30.404127)
			(xy 259.08889 -30.376876) (xy 254.605028 -30.376876) (xy 254.605028 -30.92069) (xy 254.604999 -30.922468)
			(xy 264.95248 -30.922468) (xy 264.95248 -30.058868) (xy 264.95297 -30.028884) (xy 264.960798 -29.969428)
			(xy 264.976319 -29.911503) (xy 264.999268 -29.856099) (xy 265.029252 -29.804165) (xy 265.065758 -29.756589)
			(xy 265.108163 -29.714184) (xy 265.155739 -29.677678) (xy 265.207673 -29.647694) (xy 265.263077 -29.624745)
			(xy 265.321002 -29.609224) (xy 265.380458 -29.601396) (xy 265.440426 -29.601396) (xy 265.499882 -29.609224)
			(xy 265.557807 -29.624745) (xy 265.613211 -29.647694) (xy 265.665145 -29.677678) (xy 265.712721 -29.714184)
			(xy 265.755126 -29.756589) (xy 265.791632 -29.804165) (xy 265.821616 -29.856099) (xy 265.844565 -29.911503)
			(xy 265.860086 -29.969428) (xy 265.867914 -30.028884) (xy 265.868404 -30.058868) (xy 265.868404 -30.92069)
			(xy 279.68956 -30.92069) (xy 279.68956 -30.05709) (xy 279.69005 -30.027122) (xy 279.697873 -29.9677)
			(xy 279.713386 -29.909807) (xy 279.736322 -29.854434) (xy 279.766289 -29.802528) (xy 279.802776 -29.754978)
			(xy 279.845156 -29.712598) (xy 279.892706 -29.676111) (xy 279.944612 -29.646144) (xy 279.999985 -29.623208)
			(xy 280.057878 -29.607695) (xy 280.1173 -29.599872) (xy 280.177236 -29.599872) (xy 280.236658 -29.607695)
			(xy 280.294551 -29.623208) (xy 280.349924 -29.646144) (xy 280.40183 -29.676111) (xy 280.44938 -29.712598)
			(xy 280.49176 -29.754978) (xy 280.528247 -29.802528) (xy 280.558214 -29.854434) (xy 280.58115 -29.909807)
			(xy 280.596663 -29.9677) (xy 280.604486 -30.027122) (xy 280.604976 -30.05709) (xy 280.604976 -30.376876)
			(xy 285.088838 -30.376876) (xy 285.089397 -30.34796) (xy 285.098115 -30.29079) (xy 285.115364 -30.235592)
			(xy 285.140748 -30.18363) (xy 285.173686 -30.136095) (xy 285.213421 -30.094077) (xy 285.235904 -30.075886)
			(xy 285.244708 -30.068276) (xy 285.254893 -30.047377) (xy 285.255462 -30.035754) (xy 285.255462 -29.955998)
			(xy 285.254923 -29.944366) (xy 285.244735 -29.923455) (xy 285.235904 -29.915866) (xy 285.213405 -29.897693)
			(xy 285.173671 -29.85567) (xy 285.140733 -29.808131) (xy 285.115348 -29.756166) (xy 285.098095 -29.700965)
			(xy 285.08937 -29.643793) (xy 285.088838 -29.614876) (xy 285.089324 -29.587625) (xy 285.09708 -29.533677)
			(xy 285.112435 -29.481382) (xy 285.135077 -29.431805) (xy 285.164543 -29.385955) (xy 285.200234 -29.344764)
			(xy 285.241425 -29.309073) (xy 285.287275 -29.279607) (xy 285.336852 -29.256965) (xy 285.389147 -29.24161)
			(xy 285.443095 -29.233854) (xy 285.497597 -29.233854) (xy 285.551545 -29.24161) (xy 285.60384 -29.256965)
			(xy 285.653417 -29.279607) (xy 285.699267 -29.309073) (xy 285.740458 -29.344764) (xy 285.776149 -29.385955)
			(xy 285.805615 -29.431805) (xy 285.828257 -29.481382) (xy 285.843612 -29.533677) (xy 285.851368 -29.587625)
			(xy 285.851854 -29.614876) (xy 285.851336 -29.643793) (xy 285.842609 -29.700965) (xy 285.825352 -29.756165)
			(xy 285.799961 -29.808127) (xy 285.767016 -29.855661) (xy 285.727274 -29.897677) (xy 285.704788 -29.915866)
			(xy 285.696004 -29.923496) (xy 285.685808 -29.944379) (xy 285.68523 -29.955998) (xy 285.68523 -30.035754)
			(xy 285.685742 -30.04739) (xy 285.695949 -30.068299) (xy 285.704788 -30.075886) (xy 285.727262 -30.094088)
			(xy 285.766999 -30.136105) (xy 285.799939 -30.183638) (xy 285.825329 -30.235597) (xy 285.842587 -30.290793)
			(xy 285.851318 -30.347961) (xy 285.851854 -30.376876) (xy 288.128964 -30.376876) (xy 288.129513 -30.34796)
			(xy 288.138232 -30.290789) (xy 288.155482 -30.23559) (xy 288.180868 -30.183627) (xy 288.213808 -30.136093)
			(xy 288.253546 -30.094076) (xy 288.27603 -30.075886) (xy 288.284839 -30.06828) (xy 288.29502 -30.047378)
			(xy 288.295588 -30.035754) (xy 288.295588 -29.955998) (xy 288.29504 -29.944367) (xy 288.284858 -29.923457)
			(xy 288.27603 -29.915866) (xy 288.253536 -29.897687) (xy 288.213801 -29.855665) (xy 288.180862 -29.808128)
			(xy 288.155475 -29.756165) (xy 288.138221 -29.700965) (xy 288.129496 -29.643793) (xy 288.128964 -29.614876)
			(xy 288.12945 -29.587625) (xy 288.137206 -29.533677) (xy 288.152561 -29.481382) (xy 288.175203 -29.431805)
			(xy 288.204669 -29.385955) (xy 288.24036 -29.344764) (xy 288.281551 -29.309073) (xy 288.327401 -29.279607)
			(xy 288.376978 -29.256965) (xy 288.429273 -29.24161) (xy 288.483221 -29.233854) (xy 288.537723 -29.233854)
			(xy 288.591671 -29.24161) (xy 288.643966 -29.256965) (xy 288.693543 -29.279607) (xy 288.739393 -29.309073)
			(xy 288.780584 -29.344764) (xy 288.816275 -29.385955) (xy 288.845741 -29.431805) (xy 288.868383 -29.481382)
			(xy 288.883738 -29.533677) (xy 288.891494 -29.587625) (xy 288.89198 -29.614876) (xy 288.891452 -29.643793)
			(xy 288.882726 -29.700964) (xy 288.86547 -29.756163) (xy 288.840081 -29.808125) (xy 288.807139 -29.855659)
			(xy 288.767399 -29.897676) (xy 288.744914 -29.915866) (xy 288.736118 -29.923483) (xy 288.725932 -29.944377)
			(xy 288.725356 -29.955998) (xy 288.725356 -30.035754) (xy 288.725859 -30.047391) (xy 288.736071 -30.068301)
			(xy 288.744914 -30.075886) (xy 288.767394 -30.094081) (xy 288.807128 -30.136101) (xy 288.840068 -30.183635)
			(xy 288.865456 -30.235595) (xy 288.882714 -30.290792) (xy 288.891444 -30.34796) (xy 288.89198 -30.376876)
			(xy 288.891494 -30.404127) (xy 288.883738 -30.458075) (xy 288.868383 -30.51037) (xy 288.845741 -30.559947)
			(xy 288.816275 -30.605797) (xy 288.780584 -30.646988) (xy 288.739393 -30.682679) (xy 288.693543 -30.712145)
			(xy 288.643966 -30.734787) (xy 288.591671 -30.750142) (xy 288.537723 -30.757898) (xy 288.483221 -30.757898)
			(xy 288.429273 -30.750142) (xy 288.376978 -30.734787) (xy 288.327401 -30.712145) (xy 288.281551 -30.682679)
			(xy 288.24036 -30.646988) (xy 288.204669 -30.605797) (xy 288.175203 -30.559947) (xy 288.152561 -30.51037)
			(xy 288.137206 -30.458075) (xy 288.12945 -30.404127) (xy 288.128964 -30.376876) (xy 285.851854 -30.376876)
			(xy 285.851368 -30.404127) (xy 285.843612 -30.458075) (xy 285.828257 -30.51037) (xy 285.805615 -30.559947)
			(xy 285.776149 -30.605797) (xy 285.740458 -30.646988) (xy 285.699267 -30.682679) (xy 285.653417 -30.712145)
			(xy 285.60384 -30.734787) (xy 285.551545 -30.750142) (xy 285.497597 -30.757898) (xy 285.443095 -30.757898)
			(xy 285.389147 -30.750142) (xy 285.336852 -30.734787) (xy 285.287275 -30.712145) (xy 285.241425 -30.682679)
			(xy 285.200234 -30.646988) (xy 285.164543 -30.605797) (xy 285.135077 -30.559947) (xy 285.112435 -30.51037)
			(xy 285.09708 -30.458075) (xy 285.089324 -30.404127) (xy 285.088838 -30.376876) (xy 280.604976 -30.376876)
			(xy 280.604976 -30.92069) (xy 280.604947 -30.922468) (xy 290.952428 -30.922468) (xy 290.952428 -30.058868)
			(xy 290.952918 -30.028884) (xy 290.960746 -29.969428) (xy 290.976267 -29.911503) (xy 290.999216 -29.856099)
			(xy 291.0292 -29.804165) (xy 291.065706 -29.756589) (xy 291.108111 -29.714184) (xy 291.155687 -29.677678)
			(xy 291.207621 -29.647694) (xy 291.263025 -29.624745) (xy 291.32095 -29.609224) (xy 291.380406 -29.601396)
			(xy 291.440374 -29.601396) (xy 291.49983 -29.609224) (xy 291.557755 -29.624745) (xy 291.613159 -29.647694)
			(xy 291.665093 -29.677678) (xy 291.712669 -29.714184) (xy 291.755074 -29.756589) (xy 291.79158 -29.804165)
			(xy 291.821564 -29.856099) (xy 291.844513 -29.911503) (xy 291.860034 -29.969428) (xy 291.867862 -30.028884)
			(xy 291.868352 -30.058868) (xy 291.868352 -30.92069) (xy 305.689508 -30.92069) (xy 305.689508 -30.05709)
			(xy 305.689998 -30.027122) (xy 305.697821 -29.9677) (xy 305.713334 -29.909807) (xy 305.73627 -29.854434)
			(xy 305.766237 -29.802528) (xy 305.802724 -29.754978) (xy 305.845104 -29.712598) (xy 305.892654 -29.676111)
			(xy 305.94456 -29.646144) (xy 305.999933 -29.623208) (xy 306.057826 -29.607695) (xy 306.117248 -29.599872)
			(xy 306.177184 -29.599872) (xy 306.236606 -29.607695) (xy 306.294499 -29.623208) (xy 306.349872 -29.646144)
			(xy 306.401778 -29.676111) (xy 306.449328 -29.712598) (xy 306.491708 -29.754978) (xy 306.528195 -29.802528)
			(xy 306.558162 -29.854434) (xy 306.581098 -29.909807) (xy 306.596611 -29.9677) (xy 306.604434 -30.027122)
			(xy 306.604924 -30.05709) (xy 306.604924 -30.376876) (xy 311.088786 -30.376876) (xy 311.089326 -30.34796)
			(xy 311.098046 -30.290788) (xy 311.115298 -30.235588) (xy 311.140685 -30.183626) (xy 311.173626 -30.136091)
			(xy 311.213367 -30.094075) (xy 311.235852 -30.075886) (xy 311.244664 -30.068284) (xy 311.254843 -30.047379)
			(xy 311.25541 -30.035754) (xy 311.25541 -29.955998) (xy 311.254854 -29.944368) (xy 311.244677 -29.923459)
			(xy 311.235852 -29.915866) (xy 311.213342 -29.897706) (xy 311.173611 -29.855679) (xy 311.140676 -29.808137)
			(xy 311.115293 -29.75617) (xy 311.098042 -29.700967) (xy 311.089318 -29.643794) (xy 311.088786 -29.614876)
			(xy 311.089272 -29.587625) (xy 311.097028 -29.533677) (xy 311.112383 -29.481382) (xy 311.135025 -29.431805)
			(xy 311.164491 -29.385955) (xy 311.200182 -29.344764) (xy 311.241373 -29.309073) (xy 311.287223 -29.279607)
			(xy 311.3368 -29.256965) (xy 311.389095 -29.24161) (xy 311.443043 -29.233854) (xy 311.497545 -29.233854)
			(xy 311.551493 -29.24161) (xy 311.603788 -29.256965) (xy 311.653365 -29.279607) (xy 311.699215 -29.309073)
			(xy 311.740406 -29.344764) (xy 311.776097 -29.385955) (xy 311.805563 -29.431805) (xy 311.828205 -29.481382)
			(xy 311.84356 -29.533677) (xy 311.851316 -29.587625) (xy 311.851802 -29.614876) (xy 311.851266 -29.643792)
			(xy 311.84254 -29.700963) (xy 311.825286 -29.756161) (xy 311.799898 -29.808123) (xy 311.766957 -29.855657)
			(xy 311.72722 -29.897675) (xy 311.704736 -29.915866) (xy 311.695943 -29.923487) (xy 311.685754 -29.944378)
			(xy 311.685178 -29.955998) (xy 311.685178 -30.035754) (xy 311.685708 -30.047387) (xy 311.695904 -30.068295)
			(xy 311.704736 -30.075886) (xy 311.72722 -30.094076) (xy 311.766954 -30.136097) (xy 311.799892 -30.183632)
			(xy 311.82528 -30.235594) (xy 311.842536 -30.290791) (xy 311.851266 -30.34796) (xy 311.851802 -30.376876)
			(xy 314.128912 -30.376876) (xy 314.12948 -30.347961) (xy 314.138198 -30.290792) (xy 314.155446 -30.235594)
			(xy 314.180828 -30.183632) (xy 314.213763 -30.136097) (xy 314.253496 -30.094077) (xy 314.275978 -30.075886)
			(xy 314.284794 -30.068288) (xy 314.29497 -30.04738) (xy 314.295536 -30.035754) (xy 314.295536 -29.955998)
			(xy 314.295006 -29.944364) (xy 314.284813 -29.923453) (xy 314.275978 -29.915866) (xy 314.253474 -29.8977)
			(xy 314.213741 -29.855674) (xy 314.180805 -29.808134) (xy 314.15542 -29.756168) (xy 314.138168 -29.700966)
			(xy 314.129444 -29.643793) (xy 314.128912 -29.614876) (xy 314.129398 -29.587625) (xy 314.137154 -29.533677)
			(xy 314.152509 -29.481382) (xy 314.175151 -29.431805) (xy 314.204617 -29.385955) (xy 314.240308 -29.344764)
			(xy 314.281499 -29.309073) (xy 314.327349 -29.279607) (xy 314.376926 -29.256965) (xy 314.429221 -29.24161)
			(xy 314.483169 -29.233854) (xy 314.537671 -29.233854) (xy 314.591619 -29.24161) (xy 314.643914 -29.256965)
			(xy 314.693491 -29.279607) (xy 314.739341 -29.309073) (xy 314.780532 -29.344764) (xy 314.816223 -29.385955)
			(xy 314.845689 -29.431805) (xy 314.868331 -29.481382) (xy 314.883686 -29.533677) (xy 314.891442 -29.587625)
			(xy 314.891928 -29.614876) (xy 314.89142 -29.643794) (xy 314.882693 -29.700967) (xy 314.865434 -29.756167)
			(xy 314.840041 -29.808129) (xy 314.807094 -29.855662) (xy 314.76735 -29.897677) (xy 314.744862 -29.915866)
			(xy 314.736074 -29.923491) (xy 314.725881 -29.944378) (xy 314.725304 -29.955998) (xy 314.725304 -30.035754)
			(xy 314.725825 -30.047388) (xy 314.736026 -30.068298) (xy 314.744862 -30.075886) (xy 314.767331 -30.094095)
			(xy 314.807069 -30.136109) (xy 314.840011 -30.18364) (xy 314.865402 -30.235598) (xy 314.882661 -30.290793)
			(xy 314.891392 -30.347961) (xy 314.891928 -30.376876) (xy 314.891442 -30.404127) (xy 314.883686 -30.458075)
			(xy 314.868331 -30.51037) (xy 314.845689 -30.559947) (xy 314.816223 -30.605797) (xy 314.780532 -30.646988)
			(xy 314.739341 -30.682679) (xy 314.693491 -30.712145) (xy 314.643914 -30.734787) (xy 314.591619 -30.750142)
			(xy 314.537671 -30.757898) (xy 314.483169 -30.757898) (xy 314.429221 -30.750142) (xy 314.376926 -30.734787)
			(xy 314.327349 -30.712145) (xy 314.281499 -30.682679) (xy 314.240308 -30.646988) (xy 314.204617 -30.605797)
			(xy 314.175151 -30.559947) (xy 314.152509 -30.51037) (xy 314.137154 -30.458075) (xy 314.129398 -30.404127)
			(xy 314.128912 -30.376876) (xy 311.851802 -30.376876) (xy 311.851316 -30.404127) (xy 311.84356 -30.458075)
			(xy 311.828205 -30.51037) (xy 311.805563 -30.559947) (xy 311.776097 -30.605797) (xy 311.740406 -30.646988)
			(xy 311.699215 -30.682679) (xy 311.653365 -30.712145) (xy 311.603788 -30.734787) (xy 311.551493 -30.750142)
			(xy 311.497545 -30.757898) (xy 311.443043 -30.757898) (xy 311.389095 -30.750142) (xy 311.3368 -30.734787)
			(xy 311.287223 -30.712145) (xy 311.241373 -30.682679) (xy 311.200182 -30.646988) (xy 311.164491 -30.605797)
			(xy 311.135025 -30.559947) (xy 311.112383 -30.51037) (xy 311.097028 -30.458075) (xy 311.089272 -30.404127)
			(xy 311.088786 -30.376876) (xy 306.604924 -30.376876) (xy 306.604924 -30.92069) (xy 306.604895 -30.922468)
			(xy 316.952376 -30.922468) (xy 316.952376 -30.058868) (xy 316.952866 -30.028884) (xy 316.960694 -29.969428)
			(xy 316.976215 -29.911503) (xy 316.999164 -29.856099) (xy 317.029148 -29.804165) (xy 317.065654 -29.756589)
			(xy 317.108059 -29.714184) (xy 317.155635 -29.677678) (xy 317.207569 -29.647694) (xy 317.262973 -29.624745)
			(xy 317.320898 -29.609224) (xy 317.380354 -29.601396) (xy 317.440322 -29.601396) (xy 317.499778 -29.609224)
			(xy 317.557703 -29.624745) (xy 317.613107 -29.647694) (xy 317.665041 -29.677678) (xy 317.712617 -29.714184)
			(xy 317.755022 -29.756589) (xy 317.791528 -29.804165) (xy 317.821512 -29.856099) (xy 317.844461 -29.911503)
			(xy 317.859982 -29.969428) (xy 317.86781 -30.028884) (xy 317.8683 -30.058868) (xy 317.8683 -30.92069)
			(xy 331.689456 -30.92069) (xy 331.689456 -30.05709) (xy 331.689946 -30.027122) (xy 331.697769 -29.9677)
			(xy 331.713282 -29.909807) (xy 331.736218 -29.854434) (xy 331.766185 -29.802528) (xy 331.802672 -29.754978)
			(xy 331.845052 -29.712598) (xy 331.892602 -29.676111) (xy 331.944508 -29.646144) (xy 331.999881 -29.623208)
			(xy 332.057774 -29.607695) (xy 332.117196 -29.599872) (xy 332.177132 -29.599872) (xy 332.236554 -29.607695)
			(xy 332.294447 -29.623208) (xy 332.34982 -29.646144) (xy 332.401726 -29.676111) (xy 332.449276 -29.712598)
			(xy 332.491656 -29.754978) (xy 332.528143 -29.802528) (xy 332.55811 -29.854434) (xy 332.581046 -29.909807)
			(xy 332.596559 -29.9677) (xy 332.604382 -30.027122) (xy 332.604872 -30.05709) (xy 332.604872 -30.376876)
			(xy 349.18904 -30.376876) (xy 349.189598 -30.34796) (xy 349.198317 -30.29079) (xy 349.215566 -30.235592)
			(xy 349.24095 -30.18363) (xy 349.273887 -30.136095) (xy 349.313623 -30.094077) (xy 349.336106 -30.075886)
			(xy 349.344911 -30.068276) (xy 349.355095 -30.047378) (xy 349.355664 -30.035754) (xy 349.355664 -29.955998)
			(xy 349.355124 -29.944366) (xy 349.344937 -29.923456) (xy 349.336106 -29.915866) (xy 349.313607 -29.897693)
			(xy 349.273873 -29.855669) (xy 349.240936 -29.808131) (xy 349.21555 -29.756166) (xy 349.198297 -29.700965)
			(xy 349.189572 -29.643793) (xy 349.18904 -29.614876) (xy 349.189526 -29.587625) (xy 349.197282 -29.533677)
			(xy 349.212637 -29.481382) (xy 349.235279 -29.431805) (xy 349.264745 -29.385955) (xy 349.300436 -29.344764)
			(xy 349.341627 -29.309073) (xy 349.387477 -29.279607) (xy 349.437054 -29.256965) (xy 349.489349 -29.24161)
			(xy 349.543297 -29.233854) (xy 349.597799 -29.233854) (xy 349.651747 -29.24161) (xy 349.704042 -29.256965)
			(xy 349.753619 -29.279607) (xy 349.799469 -29.309073) (xy 349.84066 -29.344764) (xy 349.876351 -29.385955)
			(xy 349.905817 -29.431805) (xy 349.928459 -29.481382) (xy 349.943814 -29.533677) (xy 349.95157 -29.587625)
			(xy 349.952056 -29.614876) (xy 349.951537 -29.643793) (xy 349.942811 -29.700965) (xy 349.925554 -29.756165)
			(xy 349.900162 -29.808127) (xy 349.867218 -29.85566) (xy 349.827476 -29.897677) (xy 349.80499 -29.915866)
			(xy 349.796207 -29.923496) (xy 349.78601 -29.944379) (xy 349.785432 -29.955998) (xy 349.785432 -30.035754)
			(xy 349.785943 -30.04739) (xy 349.796151 -30.068299) (xy 349.80499 -30.075886) (xy 349.827465 -30.094087)
			(xy 349.867201 -30.136105) (xy 349.900141 -30.183637) (xy 349.925531 -30.235597) (xy 349.942789 -30.290792)
			(xy 349.95152 -30.347961) (xy 349.952056 -30.376876) (xy 352.229166 -30.376876) (xy 352.229714 -30.34796)
			(xy 352.238433 -30.290789) (xy 352.255684 -30.23559) (xy 352.28107 -30.183627) (xy 352.314009 -30.136093)
			(xy 352.353748 -30.094076) (xy 352.376232 -30.075886) (xy 352.385041 -30.068281) (xy 352.395222 -30.047378)
			(xy 352.39579 -30.035754) (xy 352.39579 -29.955998) (xy 352.395241 -29.944367) (xy 352.38506 -29.923457)
			(xy 352.376232 -29.915866) (xy 352.353739 -29.897686) (xy 352.314003 -29.855665) (xy 352.281064 -29.808128)
			(xy 352.255677 -29.756164) (xy 352.238423 -29.700964) (xy 352.229698 -29.643793) (xy 352.229166 -29.614876)
			(xy 352.229652 -29.587625) (xy 352.237408 -29.533677) (xy 352.252763 -29.481382) (xy 352.275405 -29.431805)
			(xy 352.304871 -29.385955) (xy 352.340562 -29.344764) (xy 352.381753 -29.309073) (xy 352.427603 -29.279607)
			(xy 352.47718 -29.256965) (xy 352.529475 -29.24161) (xy 352.583423 -29.233854) (xy 352.637925 -29.233854)
			(xy 352.691873 -29.24161) (xy 352.744168 -29.256965) (xy 352.793745 -29.279607) (xy 352.839595 -29.309073)
			(xy 352.880786 -29.344764) (xy 352.916477 -29.385955) (xy 352.945943 -29.431805) (xy 352.968585 -29.481382)
			(xy 352.98394 -29.533677) (xy 352.991696 -29.587625) (xy 352.992182 -29.614876) (xy 352.991653 -29.643793)
			(xy 352.982927 -29.700964) (xy 352.965672 -29.756163) (xy 352.940282 -29.808124) (xy 352.90734 -29.855659)
			(xy 352.867601 -29.897676) (xy 352.845116 -29.915866) (xy 352.83632 -29.923483) (xy 352.826134 -29.944377)
			(xy 352.825558 -29.955998) (xy 352.825558 -30.035754) (xy 352.82606 -30.047391) (xy 352.836273 -30.068302)
			(xy 352.845116 -30.075886) (xy 352.867596 -30.094081) (xy 352.907331 -30.1361) (xy 352.94027 -30.183635)
			(xy 352.965659 -30.235595) (xy 352.982916 -30.290792) (xy 352.991646 -30.34796) (xy 352.992182 -30.376876)
			(xy 352.991696 -30.404127) (xy 352.98394 -30.458075) (xy 352.968585 -30.51037) (xy 352.945943 -30.559947)
			(xy 352.916477 -30.605797) (xy 352.880786 -30.646988) (xy 352.839595 -30.682679) (xy 352.793745 -30.712145)
			(xy 352.744168 -30.734787) (xy 352.691873 -30.750142) (xy 352.637925 -30.757898) (xy 352.583423 -30.757898)
			(xy 352.529475 -30.750142) (xy 352.47718 -30.734787) (xy 352.427603 -30.712145) (xy 352.381753 -30.682679)
			(xy 352.340562 -30.646988) (xy 352.304871 -30.605797) (xy 352.275405 -30.559947) (xy 352.252763 -30.51037)
			(xy 352.237408 -30.458075) (xy 352.229652 -30.404127) (xy 352.229166 -30.376876) (xy 349.952056 -30.376876)
			(xy 349.95157 -30.404127) (xy 349.943814 -30.458075) (xy 349.928459 -30.51037) (xy 349.905817 -30.559947)
			(xy 349.876351 -30.605797) (xy 349.84066 -30.646988) (xy 349.799469 -30.682679) (xy 349.753619 -30.712145)
			(xy 349.704042 -30.734787) (xy 349.651747 -30.750142) (xy 349.597799 -30.757898) (xy 349.543297 -30.757898)
			(xy 349.489349 -30.750142) (xy 349.437054 -30.734787) (xy 349.387477 -30.712145) (xy 349.341627 -30.682679)
			(xy 349.300436 -30.646988) (xy 349.264745 -30.605797) (xy 349.235279 -30.559947) (xy 349.212637 -30.51037)
			(xy 349.197282 -30.458075) (xy 349.189526 -30.404127) (xy 349.18904 -30.376876) (xy 332.604872 -30.376876)
			(xy 332.604872 -30.92069) (xy 332.604843 -30.922468) (xy 355.052884 -30.922468) (xy 355.052884 -30.058868)
			(xy 355.053374 -30.0289) (xy 355.061197 -29.969478) (xy 355.07671 -29.911585) (xy 355.099646 -29.856212)
			(xy 355.129613 -29.804306) (xy 355.1661 -29.756756) (xy 355.20848 -29.714376) (xy 355.25603 -29.677889)
			(xy 355.307936 -29.647922) (xy 355.363309 -29.624986) (xy 355.421202 -29.609473) (xy 355.480624 -29.60165)
			(xy 355.54056 -29.60165) (xy 355.599982 -29.609473) (xy 355.657875 -29.624986) (xy 355.713248 -29.647922)
			(xy 355.765154 -29.677889) (xy 355.812704 -29.714376) (xy 355.855084 -29.756756) (xy 355.891571 -29.804306)
			(xy 355.921538 -29.856212) (xy 355.944474 -29.911585) (xy 355.959987 -29.969478) (xy 355.96781 -30.0289)
			(xy 355.9683 -30.058868) (xy 355.9683 -30.92069) (xy 369.789456 -30.92069) (xy 369.789456 -30.05709)
			(xy 369.789946 -30.027106) (xy 369.797774 -29.96765) (xy 369.813295 -29.909725) (xy 369.836244 -29.854321)
			(xy 369.866228 -29.802387) (xy 369.902734 -29.754811) (xy 369.945139 -29.712406) (xy 369.992715 -29.6759)
			(xy 370.044649 -29.645916) (xy 370.100053 -29.622967) (xy 370.157978 -29.607446) (xy 370.217434 -29.599618)
			(xy 370.277402 -29.599618) (xy 370.336858 -29.607446) (xy 370.394783 -29.622967) (xy 370.450187 -29.645916)
			(xy 370.502121 -29.6759) (xy 370.549697 -29.712406) (xy 370.592102 -29.754811) (xy 370.628608 -29.802387)
			(xy 370.658592 -29.854321) (xy 370.681541 -29.909725) (xy 370.697062 -29.96765) (xy 370.70489 -30.027106)
			(xy 370.70538 -30.05709) (xy 370.70538 -30.376876) (xy 375.188988 -30.376876) (xy 375.189528 -30.347959)
			(xy 375.198248 -30.290788) (xy 375.215499 -30.235588) (xy 375.240887 -30.183625) (xy 375.273828 -30.136091)
			(xy 375.313569 -30.094075) (xy 375.336054 -30.075886) (xy 375.344867 -30.068285) (xy 375.355045 -30.047379)
			(xy 375.355612 -30.035754) (xy 375.355612 -29.955998) (xy 375.355056 -29.944368) (xy 375.344879 -29.923459)
			(xy 375.336054 -29.915866) (xy 375.313545 -29.897706) (xy 375.273813 -29.855678) (xy 375.240879 -29.808137)
			(xy 375.215495 -29.756169) (xy 375.198244 -29.700967) (xy 375.18952 -29.643794) (xy 375.188988 -29.614876)
			(xy 375.189474 -29.587625) (xy 375.19723 -29.533677) (xy 375.212585 -29.481382) (xy 375.235227 -29.431805)
			(xy 375.264693 -29.385955) (xy 375.300384 -29.344764) (xy 375.341575 -29.309073) (xy 375.387425 -29.279607)
			(xy 375.437002 -29.256965) (xy 375.489297 -29.24161) (xy 375.543245 -29.233854) (xy 375.597747 -29.233854)
			(xy 375.651695 -29.24161) (xy 375.70399 -29.256965) (xy 375.753567 -29.279607) (xy 375.799417 -29.309073)
			(xy 375.840608 -29.344764) (xy 375.876299 -29.385955) (xy 375.905765 -29.431805) (xy 375.928407 -29.481382)
			(xy 375.943762 -29.533677) (xy 375.951518 -29.587625) (xy 375.952004 -29.614876) (xy 375.951505 -29.643794)
			(xy 375.942777 -29.700968) (xy 375.925518 -29.756169) (xy 375.900123 -29.808131) (xy 375.867174 -29.855664)
			(xy 375.827427 -29.897678) (xy 375.804938 -29.915866) (xy 375.796146 -29.923487) (xy 375.785956 -29.944378)
			(xy 375.78538 -29.955998) (xy 375.78538 -30.035754) (xy 375.785909 -30.047387) (xy 375.796106 -30.068296)
			(xy 375.804938 -30.075886) (xy 375.827423 -30.094075) (xy 375.867156 -30.136097) (xy 375.900094 -30.183632)
			(xy 375.925482 -30.235594) (xy 375.942738 -30.290791) (xy 375.951468 -30.34796) (xy 375.952004 -30.376876)
			(xy 378.229114 -30.376876) (xy 378.229681 -30.347961) (xy 378.238399 -30.290792) (xy 378.255647 -30.235594)
			(xy 378.28103 -30.183632) (xy 378.313965 -30.136096) (xy 378.353698 -30.094077) (xy 378.37618 -30.075886)
			(xy 378.384997 -30.068289) (xy 378.395172 -30.04738) (xy 378.395738 -30.035754) (xy 378.395738 -29.955998)
			(xy 378.395208 -29.944364) (xy 378.385015 -29.923453) (xy 378.37618 -29.915866) (xy 378.353676 -29.897699)
			(xy 378.313943 -29.855674) (xy 378.281007 -29.808134) (xy 378.255622 -29.756168) (xy 378.23837 -29.700966)
			(xy 378.229646 -29.643793) (xy 378.229114 -29.614876) (xy 378.2296 -29.587625) (xy 378.237356 -29.533677)
			(xy 378.252711 -29.481382) (xy 378.275353 -29.431805) (xy 378.304819 -29.385955) (xy 378.34051 -29.344764)
			(xy 378.381701 -29.309073) (xy 378.427551 -29.279607) (xy 378.477128 -29.256965) (xy 378.529423 -29.24161)
			(xy 378.583371 -29.233854) (xy 378.637873 -29.233854) (xy 378.691821 -29.24161) (xy 378.744116 -29.256965)
			(xy 378.793693 -29.279607) (xy 378.839543 -29.309073) (xy 378.880734 -29.344764) (xy 378.916425 -29.385955)
			(xy 378.945891 -29.431805) (xy 378.968533 -29.481382) (xy 378.983888 -29.533677) (xy 378.991644 -29.587625)
			(xy 378.99213 -29.614876) (xy 378.991621 -29.643794) (xy 378.982894 -29.700966) (xy 378.965636 -29.756167)
			(xy 378.940243 -29.808129) (xy 378.907296 -29.855662) (xy 378.867551 -29.897677) (xy 378.845064 -29.915866)
			(xy 378.836276 -29.923492) (xy 378.826083 -29.944379) (xy 378.825506 -29.955998) (xy 378.825506 -30.035754)
			(xy 378.826026 -30.047388) (xy 378.836228 -30.068298) (xy 378.845064 -30.075886) (xy 378.867533 -30.094094)
			(xy 378.907271 -30.136109) (xy 378.940213 -30.18364) (xy 378.965604 -30.235598) (xy 378.982863 -30.290793)
			(xy 378.991594 -30.347961) (xy 378.99213 -30.376876) (xy 378.991644 -30.404127) (xy 378.983888 -30.458075)
			(xy 378.968533 -30.51037) (xy 378.945891 -30.559947) (xy 378.916425 -30.605797) (xy 378.880734 -30.646988)
			(xy 378.839543 -30.682679) (xy 378.793693 -30.712145) (xy 378.744116 -30.734787) (xy 378.691821 -30.750142)
			(xy 378.637873 -30.757898) (xy 378.583371 -30.757898) (xy 378.529423 -30.750142) (xy 378.477128 -30.734787)
			(xy 378.427551 -30.712145) (xy 378.381701 -30.682679) (xy 378.34051 -30.646988) (xy 378.304819 -30.605797)
			(xy 378.275353 -30.559947) (xy 378.252711 -30.51037) (xy 378.237356 -30.458075) (xy 378.2296 -30.404127)
			(xy 378.229114 -30.376876) (xy 375.952004 -30.376876) (xy 375.951518 -30.404127) (xy 375.943762 -30.458075)
			(xy 375.928407 -30.51037) (xy 375.905765 -30.559947) (xy 375.876299 -30.605797) (xy 375.840608 -30.646988)
			(xy 375.799417 -30.682679) (xy 375.753567 -30.712145) (xy 375.70399 -30.734787) (xy 375.651695 -30.750142)
			(xy 375.597747 -30.757898) (xy 375.543245 -30.757898) (xy 375.489297 -30.750142) (xy 375.437002 -30.734787)
			(xy 375.387425 -30.712145) (xy 375.341575 -30.682679) (xy 375.300384 -30.646988) (xy 375.264693 -30.605797)
			(xy 375.235227 -30.559947) (xy 375.212585 -30.51037) (xy 375.19723 -30.458075) (xy 375.189474 -30.404127)
			(xy 375.188988 -30.376876) (xy 370.70538 -30.376876) (xy 370.70538 -30.92069) (xy 370.705351 -30.922468)
			(xy 381.052832 -30.922468) (xy 381.052832 -30.058868) (xy 381.053322 -30.0289) (xy 381.061145 -29.969478)
			(xy 381.076658 -29.911585) (xy 381.099594 -29.856212) (xy 381.129561 -29.804306) (xy 381.166048 -29.756756)
			(xy 381.208428 -29.714376) (xy 381.255978 -29.677889) (xy 381.307884 -29.647922) (xy 381.363257 -29.624986)
			(xy 381.42115 -29.609473) (xy 381.480572 -29.60165) (xy 381.540508 -29.60165) (xy 381.59993 -29.609473)
			(xy 381.657823 -29.624986) (xy 381.713196 -29.647922) (xy 381.765102 -29.677889) (xy 381.812652 -29.714376)
			(xy 381.855032 -29.756756) (xy 381.891519 -29.804306) (xy 381.921486 -29.856212) (xy 381.944422 -29.911585)
			(xy 381.959935 -29.969478) (xy 381.967758 -30.0289) (xy 381.968248 -30.058868) (xy 381.968248 -30.92069)
			(xy 395.789404 -30.92069) (xy 395.789404 -30.05709) (xy 395.789894 -30.027106) (xy 395.797722 -29.96765)
			(xy 395.813243 -29.909725) (xy 395.836192 -29.854321) (xy 395.866176 -29.802387) (xy 395.902682 -29.754811)
			(xy 395.945087 -29.712406) (xy 395.992663 -29.6759) (xy 396.044597 -29.645916) (xy 396.100001 -29.622967)
			(xy 396.157926 -29.607446) (xy 396.217382 -29.599618) (xy 396.27735 -29.599618) (xy 396.336806 -29.607446)
			(xy 396.394731 -29.622967) (xy 396.450135 -29.645916) (xy 396.502069 -29.6759) (xy 396.549645 -29.712406)
			(xy 396.59205 -29.754811) (xy 396.628556 -29.802387) (xy 396.65854 -29.854321) (xy 396.681489 -29.909725)
			(xy 396.69701 -29.96765) (xy 396.704838 -30.027106) (xy 396.705328 -30.05709) (xy 396.705328 -30.376876)
			(xy 401.188936 -30.376876) (xy 401.189496 -30.34796) (xy 401.198214 -30.290791) (xy 401.215463 -30.235592)
			(xy 401.240847 -30.18363) (xy 401.273784 -30.136095) (xy 401.313519 -30.094077) (xy 401.336002 -30.075886)
			(xy 401.344806 -30.068275) (xy 401.354991 -30.047377) (xy 401.35556 -30.035754) (xy 401.35556 -29.955998)
			(xy 401.355022 -29.944366) (xy 401.344834 -29.923455) (xy 401.336002 -29.915866) (xy 401.313503 -29.897694)
			(xy 401.273768 -29.85567) (xy 401.240831 -29.808131) (xy 401.215445 -29.756166) (xy 401.198193 -29.700965)
			(xy 401.189468 -29.643793) (xy 401.188936 -29.614876) (xy 401.189422 -29.587625) (xy 401.197178 -29.533677)
			(xy 401.212533 -29.481382) (xy 401.235175 -29.431805) (xy 401.264641 -29.385955) (xy 401.300332 -29.344764)
			(xy 401.341523 -29.309073) (xy 401.387373 -29.279607) (xy 401.43695 -29.256965) (xy 401.489245 -29.24161)
			(xy 401.543193 -29.233854) (xy 401.597695 -29.233854) (xy 401.651643 -29.24161) (xy 401.703938 -29.256965)
			(xy 401.753515 -29.279607) (xy 401.799365 -29.309073) (xy 401.840556 -29.344764) (xy 401.876247 -29.385955)
			(xy 401.905713 -29.431805) (xy 401.928355 -29.481382) (xy 401.94371 -29.533677) (xy 401.951466 -29.587625)
			(xy 401.951952 -29.614876) (xy 401.951435 -29.643793) (xy 401.942708 -29.700965) (xy 401.925451 -29.756165)
			(xy 401.900059 -29.808127) (xy 401.867115 -29.855661) (xy 401.827372 -29.897677) (xy 401.804886 -29.915866)
			(xy 401.796102 -29.923496) (xy 401.785906 -29.944379) (xy 401.785328 -29.955998) (xy 401.785328 -30.035754)
			(xy 401.785841 -30.047389) (xy 401.796047 -30.068299) (xy 401.804886 -30.075886) (xy 401.82736 -30.094088)
			(xy 401.867096 -30.136105) (xy 401.900037 -30.183638) (xy 401.925427 -30.235597) (xy 401.942685 -30.290793)
			(xy 401.951416 -30.347961) (xy 401.951952 -30.376876) (xy 404.229062 -30.376876) (xy 404.229612 -30.34796)
			(xy 404.238331 -30.290789) (xy 404.255581 -30.23559) (xy 404.280967 -30.183628) (xy 404.313906 -30.136093)
			(xy 404.353644 -30.094076) (xy 404.376128 -30.075886) (xy 404.384936 -30.06828) (xy 404.395118 -30.047378)
			(xy 404.395686 -30.035754) (xy 404.395686 -29.955998) (xy 404.395138 -29.944367) (xy 404.384956 -29.923457)
			(xy 404.376128 -29.915866) (xy 404.353634 -29.897687) (xy 404.313898 -29.855666) (xy 404.28096 -29.808129)
			(xy 404.255573 -29.756165) (xy 404.238319 -29.700965) (xy 404.229594 -29.643793) (xy 404.229062 -29.614876)
			(xy 404.229548 -29.587625) (xy 404.237304 -29.533677) (xy 404.252659 -29.481382) (xy 404.275301 -29.431805)
			(xy 404.304767 -29.385955) (xy 404.340458 -29.344764) (xy 404.381649 -29.309073) (xy 404.427499 -29.279607)
			(xy 404.477076 -29.256965) (xy 404.529371 -29.24161) (xy 404.583319 -29.233854) (xy 404.637821 -29.233854)
			(xy 404.691769 -29.24161) (xy 404.744064 -29.256965) (xy 404.793641 -29.279607) (xy 404.839491 -29.309073)
			(xy 404.880682 -29.344764) (xy 404.916373 -29.385955) (xy 404.945839 -29.431805) (xy 404.968481 -29.481382)
			(xy 404.983836 -29.533677) (xy 404.991592 -29.587625) (xy 404.992078 -29.614876) (xy 404.991551 -29.643793)
			(xy 404.982825 -29.700964) (xy 404.965569 -29.756163) (xy 404.940179 -29.808125) (xy 404.907237 -29.855659)
			(xy 404.867497 -29.897676) (xy 404.845012 -29.915866) (xy 404.836232 -29.9235) (xy 404.826033 -29.94438)
			(xy 404.825454 -29.955998) (xy 404.825454 -30.035754) (xy 404.825957 -30.047391) (xy 404.83617 -30.068301)
			(xy 404.845012 -30.075886) (xy 404.867491 -30.094082) (xy 404.907226 -30.136101) (xy 404.940165 -30.183635)
			(xy 404.965554 -30.235595) (xy 404.982812 -30.290792) (xy 404.991542 -30.34796) (xy 404.992078 -30.376876)
			(xy 404.991592 -30.404127) (xy 404.983836 -30.458075) (xy 404.968481 -30.51037) (xy 404.945839 -30.559947)
			(xy 404.916373 -30.605797) (xy 404.880682 -30.646988) (xy 404.839491 -30.682679) (xy 404.793641 -30.712145)
			(xy 404.744064 -30.734787) (xy 404.691769 -30.750142) (xy 404.637821 -30.757898) (xy 404.583319 -30.757898)
			(xy 404.529371 -30.750142) (xy 404.477076 -30.734787) (xy 404.427499 -30.712145) (xy 404.381649 -30.682679)
			(xy 404.340458 -30.646988) (xy 404.304767 -30.605797) (xy 404.275301 -30.559947) (xy 404.252659 -30.51037)
			(xy 404.237304 -30.458075) (xy 404.229548 -30.404127) (xy 404.229062 -30.376876) (xy 401.951952 -30.376876)
			(xy 401.951466 -30.404127) (xy 401.94371 -30.458075) (xy 401.928355 -30.51037) (xy 401.905713 -30.559947)
			(xy 401.876247 -30.605797) (xy 401.840556 -30.646988) (xy 401.799365 -30.682679) (xy 401.753515 -30.712145)
			(xy 401.703938 -30.734787) (xy 401.651643 -30.750142) (xy 401.597695 -30.757898) (xy 401.543193 -30.757898)
			(xy 401.489245 -30.750142) (xy 401.43695 -30.734787) (xy 401.387373 -30.712145) (xy 401.341523 -30.682679)
			(xy 401.300332 -30.646988) (xy 401.264641 -30.605797) (xy 401.235175 -30.559947) (xy 401.212533 -30.51037)
			(xy 401.197178 -30.458075) (xy 401.189422 -30.404127) (xy 401.188936 -30.376876) (xy 396.705328 -30.376876)
			(xy 396.705328 -30.92069) (xy 396.705299 -30.922468) (xy 407.05278 -30.922468) (xy 407.05278 -30.058868)
			(xy 407.05327 -30.0289) (xy 407.061093 -29.969478) (xy 407.076606 -29.911585) (xy 407.099542 -29.856212)
			(xy 407.129509 -29.804306) (xy 407.165996 -29.756756) (xy 407.208376 -29.714376) (xy 407.255926 -29.677889)
			(xy 407.307832 -29.647922) (xy 407.363205 -29.624986) (xy 407.421098 -29.609473) (xy 407.48052 -29.60165)
			(xy 407.540456 -29.60165) (xy 407.599878 -29.609473) (xy 407.657771 -29.624986) (xy 407.713144 -29.647922)
			(xy 407.76505 -29.677889) (xy 407.8126 -29.714376) (xy 407.85498 -29.756756) (xy 407.891467 -29.804306)
			(xy 407.921434 -29.856212) (xy 407.94437 -29.911585) (xy 407.959883 -29.969478) (xy 407.967706 -30.0289)
			(xy 407.968196 -30.058868) (xy 407.968196 -30.92069) (xy 421.789352 -30.92069) (xy 421.789352 -30.05709)
			(xy 421.789842 -30.027106) (xy 421.79767 -29.96765) (xy 421.813191 -29.909725) (xy 421.83614 -29.854321)
			(xy 421.866124 -29.802387) (xy 421.90263 -29.754811) (xy 421.945035 -29.712406) (xy 421.992611 -29.6759)
			(xy 422.044545 -29.645916) (xy 422.099949 -29.622967) (xy 422.157874 -29.607446) (xy 422.21733 -29.599618)
			(xy 422.277298 -29.599618) (xy 422.336754 -29.607446) (xy 422.394679 -29.622967) (xy 422.450083 -29.645916)
			(xy 422.502017 -29.6759) (xy 422.549593 -29.712406) (xy 422.591998 -29.754811) (xy 422.628504 -29.802387)
			(xy 422.658488 -29.854321) (xy 422.681437 -29.909725) (xy 422.696958 -29.96765) (xy 422.704786 -30.027106)
			(xy 422.705276 -30.05709) (xy 422.705276 -30.376876) (xy 427.188884 -30.376876) (xy 427.189425 -30.34796)
			(xy 427.198145 -30.290788) (xy 427.215396 -30.235588) (xy 427.240784 -30.183626) (xy 427.273725 -30.136092)
			(xy 427.313465 -30.094076) (xy 427.33595 -30.075886) (xy 427.344762 -30.068284) (xy 427.354941 -30.047379)
			(xy 427.355508 -30.035754) (xy 427.355508 -29.955998) (xy 427.354953 -29.944368) (xy 427.344775 -29.923459)
			(xy 427.33595 -29.915866) (xy 427.31344 -29.897707) (xy 427.273709 -29.855679) (xy 427.240774 -29.808137)
			(xy 427.215391 -29.75617) (xy 427.19814 -29.700967) (xy 427.189416 -29.643794) (xy 427.188884 -29.614876)
			(xy 427.18937 -29.587625) (xy 427.197126 -29.533677) (xy 427.212481 -29.481382) (xy 427.235123 -29.431805)
			(xy 427.264589 -29.385955) (xy 427.30028 -29.344764) (xy 427.341471 -29.309073) (xy 427.387321 -29.279607)
			(xy 427.436898 -29.256965) (xy 427.489193 -29.24161) (xy 427.543141 -29.233854) (xy 427.597643 -29.233854)
			(xy 427.651591 -29.24161) (xy 427.703886 -29.256965) (xy 427.753463 -29.279607) (xy 427.799313 -29.309073)
			(xy 427.840504 -29.344764) (xy 427.876195 -29.385955) (xy 427.905661 -29.431805) (xy 427.928303 -29.481382)
			(xy 427.943658 -29.533677) (xy 427.951414 -29.587625) (xy 427.9519 -29.614876) (xy 427.951364 -29.643792)
			(xy 427.942639 -29.700963) (xy 427.925384 -29.756161) (xy 427.899996 -29.808123) (xy 427.867056 -29.855657)
			(xy 427.827318 -29.897675) (xy 427.804834 -29.915866) (xy 427.796041 -29.923486) (xy 427.785852 -29.944378)
			(xy 427.785276 -29.955998) (xy 427.785276 -30.035754) (xy 427.785772 -30.047392) (xy 427.795988 -30.068303)
			(xy 427.804834 -30.075886) (xy 427.827318 -30.094076) (xy 427.867051 -30.136097) (xy 427.899989 -30.183633)
			(xy 427.925377 -30.235594) (xy 427.942634 -30.290791) (xy 427.951364 -30.34796) (xy 427.9519 -30.376876)
			(xy 430.22901 -30.376876) (xy 430.229579 -30.347961) (xy 430.238297 -30.290792) (xy 430.255545 -30.235594)
			(xy 430.280927 -30.183632) (xy 430.313861 -30.136097) (xy 430.353594 -30.094078) (xy 430.376076 -30.075886)
			(xy 430.384892 -30.068288) (xy 430.395068 -30.04738) (xy 430.395634 -30.035754) (xy 430.395634 -29.955998)
			(xy 430.395105 -29.944364) (xy 430.384912 -29.923453) (xy 430.376076 -29.915866) (xy 430.353571 -29.8977)
			(xy 430.313838 -29.855675) (xy 430.280903 -29.808134) (xy 430.255518 -29.756168) (xy 430.238266 -29.700966)
			(xy 430.229542 -29.643793) (xy 430.22901 -29.614876) (xy 430.229496 -29.587625) (xy 430.237252 -29.533677)
			(xy 430.252607 -29.481382) (xy 430.275249 -29.431805) (xy 430.304715 -29.385955) (xy 430.340406 -29.344764)
			(xy 430.381597 -29.309073) (xy 430.427447 -29.279607) (xy 430.477024 -29.256965) (xy 430.529319 -29.24161)
			(xy 430.583267 -29.233854) (xy 430.637769 -29.233854) (xy 430.691717 -29.24161) (xy 430.744012 -29.256965)
			(xy 430.793589 -29.279607) (xy 430.839439 -29.309073) (xy 430.88063 -29.344764) (xy 430.916321 -29.385955)
			(xy 430.945787 -29.431805) (xy 430.968429 -29.481382) (xy 430.983784 -29.533677) (xy 430.99154 -29.587625)
			(xy 430.992026 -29.614876) (xy 430.991519 -29.643794) (xy 430.982791 -29.700967) (xy 430.965533 -29.756167)
			(xy 430.94014 -29.808129) (xy 430.907193 -29.855663) (xy 430.867448 -29.897678) (xy 430.84496 -29.915866)
			(xy 430.836172 -29.923491) (xy 430.825979 -29.944378) (xy 430.825402 -29.955998) (xy 430.825402 -30.035754)
			(xy 430.825924 -30.047388) (xy 430.836125 -30.068297) (xy 430.84496 -30.075886) (xy 430.867428 -30.094095)
			(xy 430.907166 -30.13611) (xy 430.940108 -30.183641) (xy 430.9655 -30.235599) (xy 430.982759 -30.290793)
			(xy 430.99149 -30.347961) (xy 430.992026 -30.376876) (xy 430.99154 -30.404127) (xy 430.983784 -30.458075)
			(xy 430.968429 -30.51037) (xy 430.945787 -30.559947) (xy 430.916321 -30.605797) (xy 430.88063 -30.646988)
			(xy 430.839439 -30.682679) (xy 430.793589 -30.712145) (xy 430.744012 -30.734787) (xy 430.691717 -30.750142)
			(xy 430.637769 -30.757898) (xy 430.583267 -30.757898) (xy 430.529319 -30.750142) (xy 430.477024 -30.734787)
			(xy 430.427447 -30.712145) (xy 430.381597 -30.682679) (xy 430.340406 -30.646988) (xy 430.304715 -30.605797)
			(xy 430.275249 -30.559947) (xy 430.252607 -30.51037) (xy 430.237252 -30.458075) (xy 430.229496 -30.404127)
			(xy 430.22901 -30.376876) (xy 427.9519 -30.376876) (xy 427.951414 -30.404127) (xy 427.943658 -30.458075)
			(xy 427.928303 -30.51037) (xy 427.905661 -30.559947) (xy 427.876195 -30.605797) (xy 427.840504 -30.646988)
			(xy 427.799313 -30.682679) (xy 427.753463 -30.712145) (xy 427.703886 -30.734787) (xy 427.651591 -30.750142)
			(xy 427.597643 -30.757898) (xy 427.543141 -30.757898) (xy 427.489193 -30.750142) (xy 427.436898 -30.734787)
			(xy 427.387321 -30.712145) (xy 427.341471 -30.682679) (xy 427.30028 -30.646988) (xy 427.264589 -30.605797)
			(xy 427.235123 -30.559947) (xy 427.212481 -30.51037) (xy 427.197126 -30.458075) (xy 427.18937 -30.404127)
			(xy 427.188884 -30.376876) (xy 422.705276 -30.376876) (xy 422.705276 -30.92069) (xy 422.705247 -30.922468)
			(xy 433.052728 -30.922468) (xy 433.052728 -30.058868) (xy 433.053218 -30.0289) (xy 433.061041 -29.969478)
			(xy 433.076554 -29.911585) (xy 433.09949 -29.856212) (xy 433.129457 -29.804306) (xy 433.165944 -29.756756)
			(xy 433.208324 -29.714376) (xy 433.255874 -29.677889) (xy 433.30778 -29.647922) (xy 433.363153 -29.624986)
			(xy 433.421046 -29.609473) (xy 433.480468 -29.60165) (xy 433.540404 -29.60165) (xy 433.599826 -29.609473)
			(xy 433.657719 -29.624986) (xy 433.713092 -29.647922) (xy 433.764998 -29.677889) (xy 433.812548 -29.714376)
			(xy 433.854928 -29.756756) (xy 433.891415 -29.804306) (xy 433.921382 -29.856212) (xy 433.944318 -29.911585)
			(xy 433.959831 -29.969478) (xy 433.967654 -30.0289) (xy 433.968144 -30.058868) (xy 433.968144 -30.92069)
			(xy 447.7893 -30.92069) (xy 447.7893 -30.05709) (xy 447.78979 -30.027106) (xy 447.797618 -29.96765)
			(xy 447.813139 -29.909725) (xy 447.836088 -29.854321) (xy 447.866072 -29.802387) (xy 447.902578 -29.754811)
			(xy 447.944983 -29.712406) (xy 447.992559 -29.6759) (xy 448.044493 -29.645916) (xy 448.099897 -29.622967)
			(xy 448.157822 -29.607446) (xy 448.217278 -29.599618) (xy 448.277246 -29.599618) (xy 448.336702 -29.607446)
			(xy 448.394627 -29.622967) (xy 448.450031 -29.645916) (xy 448.501965 -29.6759) (xy 448.549541 -29.712406)
			(xy 448.591946 -29.754811) (xy 448.628452 -29.802387) (xy 448.658436 -29.854321) (xy 448.681385 -29.909725)
			(xy 448.696906 -29.96765) (xy 448.704734 -30.027106) (xy 448.705224 -30.05709) (xy 448.705224 -30.92069)
			(xy 448.704734 -30.950674) (xy 448.696906 -31.01013) (xy 448.681385 -31.068055) (xy 448.658436 -31.123459)
			(xy 448.628452 -31.175393) (xy 448.591946 -31.222969) (xy 448.549541 -31.265374) (xy 448.501965 -31.30188)
			(xy 448.450031 -31.331864) (xy 448.394627 -31.354813) (xy 448.336702 -31.370334) (xy 448.277246 -31.378162)
			(xy 448.217278 -31.378162) (xy 448.157822 -31.370334) (xy 448.099897 -31.354813) (xy 448.044493 -31.331864)
			(xy 447.992559 -31.30188) (xy 447.944983 -31.265374) (xy 447.902578 -31.222969) (xy 447.866072 -31.175393)
			(xy 447.836088 -31.123459) (xy 447.813139 -31.068055) (xy 447.797618 -31.01013) (xy 447.78979 -30.950674)
			(xy 447.7893 -30.92069) (xy 433.968144 -30.92069) (xy 433.968144 -30.922468) (xy 433.967654 -30.952436)
			(xy 433.959831 -31.011858) (xy 433.944318 -31.069751) (xy 433.921382 -31.125124) (xy 433.891415 -31.17703)
			(xy 433.854928 -31.22458) (xy 433.812548 -31.26696) (xy 433.764998 -31.303447) (xy 433.713092 -31.333414)
			(xy 433.657719 -31.35635) (xy 433.599826 -31.371863) (xy 433.540404 -31.379686) (xy 433.480468 -31.379686)
			(xy 433.421046 -31.371863) (xy 433.363153 -31.35635) (xy 433.30778 -31.333414) (xy 433.255874 -31.303447)
			(xy 433.208324 -31.26696) (xy 433.165944 -31.22458) (xy 433.129457 -31.17703) (xy 433.09949 -31.125124)
			(xy 433.076554 -31.069751) (xy 433.061041 -31.011858) (xy 433.053218 -30.952436) (xy 433.052728 -30.922468)
			(xy 422.705247 -30.922468) (xy 422.704786 -30.950674) (xy 422.696958 -31.01013) (xy 422.681437 -31.068055)
			(xy 422.658488 -31.123459) (xy 422.628504 -31.175393) (xy 422.591998 -31.222969) (xy 422.549593 -31.265374)
			(xy 422.502017 -31.30188) (xy 422.450083 -31.331864) (xy 422.394679 -31.354813) (xy 422.336754 -31.370334)
			(xy 422.277298 -31.378162) (xy 422.21733 -31.378162) (xy 422.157874 -31.370334) (xy 422.099949 -31.354813)
			(xy 422.044545 -31.331864) (xy 421.992611 -31.30188) (xy 421.945035 -31.265374) (xy 421.90263 -31.222969)
			(xy 421.866124 -31.175393) (xy 421.83614 -31.123459) (xy 421.813191 -31.068055) (xy 421.79767 -31.01013)
			(xy 421.789842 -30.950674) (xy 421.789352 -30.92069) (xy 407.968196 -30.92069) (xy 407.968196 -30.922468)
			(xy 407.967706 -30.952436) (xy 407.959883 -31.011858) (xy 407.94437 -31.069751) (xy 407.921434 -31.125124)
			(xy 407.891467 -31.17703) (xy 407.85498 -31.22458) (xy 407.8126 -31.26696) (xy 407.76505 -31.303447)
			(xy 407.713144 -31.333414) (xy 407.657771 -31.35635) (xy 407.599878 -31.371863) (xy 407.540456 -31.379686)
			(xy 407.48052 -31.379686) (xy 407.421098 -31.371863) (xy 407.363205 -31.35635) (xy 407.307832 -31.333414)
			(xy 407.255926 -31.303447) (xy 407.208376 -31.26696) (xy 407.165996 -31.22458) (xy 407.129509 -31.17703)
			(xy 407.099542 -31.125124) (xy 407.076606 -31.069751) (xy 407.061093 -31.011858) (xy 407.05327 -30.952436)
			(xy 407.05278 -30.922468) (xy 396.705299 -30.922468) (xy 396.704838 -30.950674) (xy 396.69701 -31.01013)
			(xy 396.681489 -31.068055) (xy 396.65854 -31.123459) (xy 396.628556 -31.175393) (xy 396.59205 -31.222969)
			(xy 396.549645 -31.265374) (xy 396.502069 -31.30188) (xy 396.450135 -31.331864) (xy 396.394731 -31.354813)
			(xy 396.336806 -31.370334) (xy 396.27735 -31.378162) (xy 396.217382 -31.378162) (xy 396.157926 -31.370334)
			(xy 396.100001 -31.354813) (xy 396.044597 -31.331864) (xy 395.992663 -31.30188) (xy 395.945087 -31.265374)
			(xy 395.902682 -31.222969) (xy 395.866176 -31.175393) (xy 395.836192 -31.123459) (xy 395.813243 -31.068055)
			(xy 395.797722 -31.01013) (xy 395.789894 -30.950674) (xy 395.789404 -30.92069) (xy 381.968248 -30.92069)
			(xy 381.968248 -30.922468) (xy 381.967758 -30.952436) (xy 381.959935 -31.011858) (xy 381.944422 -31.069751)
			(xy 381.921486 -31.125124) (xy 381.891519 -31.17703) (xy 381.855032 -31.22458) (xy 381.812652 -31.26696)
			(xy 381.765102 -31.303447) (xy 381.713196 -31.333414) (xy 381.657823 -31.35635) (xy 381.59993 -31.371863)
			(xy 381.540508 -31.379686) (xy 381.480572 -31.379686) (xy 381.42115 -31.371863) (xy 381.363257 -31.35635)
			(xy 381.307884 -31.333414) (xy 381.255978 -31.303447) (xy 381.208428 -31.26696) (xy 381.166048 -31.22458)
			(xy 381.129561 -31.17703) (xy 381.099594 -31.125124) (xy 381.076658 -31.069751) (xy 381.061145 -31.011858)
			(xy 381.053322 -30.952436) (xy 381.052832 -30.922468) (xy 370.705351 -30.922468) (xy 370.70489 -30.950674)
			(xy 370.697062 -31.01013) (xy 370.681541 -31.068055) (xy 370.658592 -31.123459) (xy 370.628608 -31.175393)
			(xy 370.592102 -31.222969) (xy 370.549697 -31.265374) (xy 370.502121 -31.30188) (xy 370.450187 -31.331864)
			(xy 370.394783 -31.354813) (xy 370.336858 -31.370334) (xy 370.277402 -31.378162) (xy 370.217434 -31.378162)
			(xy 370.157978 -31.370334) (xy 370.100053 -31.354813) (xy 370.044649 -31.331864) (xy 369.992715 -31.30188)
			(xy 369.945139 -31.265374) (xy 369.902734 -31.222969) (xy 369.866228 -31.175393) (xy 369.836244 -31.123459)
			(xy 369.813295 -31.068055) (xy 369.797774 -31.01013) (xy 369.789946 -30.950674) (xy 369.789456 -30.92069)
			(xy 355.9683 -30.92069) (xy 355.9683 -30.922468) (xy 355.96781 -30.952436) (xy 355.959987 -31.011858)
			(xy 355.944474 -31.069751) (xy 355.921538 -31.125124) (xy 355.891571 -31.17703) (xy 355.855084 -31.22458)
			(xy 355.812704 -31.26696) (xy 355.765154 -31.303447) (xy 355.713248 -31.333414) (xy 355.657875 -31.35635)
			(xy 355.599982 -31.371863) (xy 355.54056 -31.379686) (xy 355.480624 -31.379686) (xy 355.421202 -31.371863)
			(xy 355.363309 -31.35635) (xy 355.307936 -31.333414) (xy 355.25603 -31.303447) (xy 355.20848 -31.26696)
			(xy 355.1661 -31.22458) (xy 355.129613 -31.17703) (xy 355.099646 -31.125124) (xy 355.07671 -31.069751)
			(xy 355.061197 -31.011858) (xy 355.053374 -30.952436) (xy 355.052884 -30.922468) (xy 332.604843 -30.922468)
			(xy 332.604382 -30.950658) (xy 332.596559 -31.01008) (xy 332.581046 -31.067973) (xy 332.55811 -31.123346)
			(xy 332.528143 -31.175252) (xy 332.491656 -31.222802) (xy 332.449276 -31.265182) (xy 332.401726 -31.301669)
			(xy 332.34982 -31.331636) (xy 332.294447 -31.354572) (xy 332.236554 -31.370085) (xy 332.177132 -31.377908)
			(xy 332.117196 -31.377908) (xy 332.057774 -31.370085) (xy 331.999881 -31.354572) (xy 331.944508 -31.331636)
			(xy 331.892602 -31.301669) (xy 331.845052 -31.265182) (xy 331.802672 -31.222802) (xy 331.766185 -31.175252)
			(xy 331.736218 -31.123346) (xy 331.713282 -31.067973) (xy 331.697769 -31.01008) (xy 331.689946 -30.950658)
			(xy 331.689456 -30.92069) (xy 317.8683 -30.92069) (xy 317.8683 -30.922468) (xy 317.86781 -30.952452)
			(xy 317.859982 -31.011908) (xy 317.844461 -31.069833) (xy 317.821512 -31.125237) (xy 317.791528 -31.177171)
			(xy 317.755022 -31.224747) (xy 317.712617 -31.267152) (xy 317.665041 -31.303658) (xy 317.613107 -31.333642)
			(xy 317.557703 -31.356591) (xy 317.499778 -31.372112) (xy 317.440322 -31.37994) (xy 317.380354 -31.37994)
			(xy 317.320898 -31.372112) (xy 317.262973 -31.356591) (xy 317.207569 -31.333642) (xy 317.155635 -31.303658)
			(xy 317.108059 -31.267152) (xy 317.065654 -31.224747) (xy 317.029148 -31.177171) (xy 316.999164 -31.125237)
			(xy 316.976215 -31.069833) (xy 316.960694 -31.011908) (xy 316.952866 -30.952452) (xy 316.952376 -30.922468)
			(xy 306.604895 -30.922468) (xy 306.604434 -30.950658) (xy 306.596611 -31.01008) (xy 306.581098 -31.067973)
			(xy 306.558162 -31.123346) (xy 306.528195 -31.175252) (xy 306.491708 -31.222802) (xy 306.449328 -31.265182)
			(xy 306.401778 -31.301669) (xy 306.349872 -31.331636) (xy 306.294499 -31.354572) (xy 306.236606 -31.370085)
			(xy 306.177184 -31.377908) (xy 306.117248 -31.377908) (xy 306.057826 -31.370085) (xy 305.999933 -31.354572)
			(xy 305.94456 -31.331636) (xy 305.892654 -31.301669) (xy 305.845104 -31.265182) (xy 305.802724 -31.222802)
			(xy 305.766237 -31.175252) (xy 305.73627 -31.123346) (xy 305.713334 -31.067973) (xy 305.697821 -31.01008)
			(xy 305.689998 -30.950658) (xy 305.689508 -30.92069) (xy 291.868352 -30.92069) (xy 291.868352 -30.922468)
			(xy 291.867862 -30.952452) (xy 291.860034 -31.011908) (xy 291.844513 -31.069833) (xy 291.821564 -31.125237)
			(xy 291.79158 -31.177171) (xy 291.755074 -31.224747) (xy 291.712669 -31.267152) (xy 291.665093 -31.303658)
			(xy 291.613159 -31.333642) (xy 291.557755 -31.356591) (xy 291.49983 -31.372112) (xy 291.440374 -31.37994)
			(xy 291.380406 -31.37994) (xy 291.32095 -31.372112) (xy 291.263025 -31.356591) (xy 291.207621 -31.333642)
			(xy 291.155687 -31.303658) (xy 291.108111 -31.267152) (xy 291.065706 -31.224747) (xy 291.0292 -31.177171)
			(xy 290.999216 -31.125237) (xy 290.976267 -31.069833) (xy 290.960746 -31.011908) (xy 290.952918 -30.952452)
			(xy 290.952428 -30.922468) (xy 280.604947 -30.922468) (xy 280.604486 -30.950658) (xy 280.596663 -31.01008)
			(xy 280.58115 -31.067973) (xy 280.558214 -31.123346) (xy 280.528247 -31.175252) (xy 280.49176 -31.222802)
			(xy 280.44938 -31.265182) (xy 280.40183 -31.301669) (xy 280.349924 -31.331636) (xy 280.294551 -31.354572)
			(xy 280.236658 -31.370085) (xy 280.177236 -31.377908) (xy 280.1173 -31.377908) (xy 280.057878 -31.370085)
			(xy 279.999985 -31.354572) (xy 279.944612 -31.331636) (xy 279.892706 -31.301669) (xy 279.845156 -31.265182)
			(xy 279.802776 -31.222802) (xy 279.766289 -31.175252) (xy 279.736322 -31.123346) (xy 279.713386 -31.067973)
			(xy 279.697873 -31.01008) (xy 279.69005 -30.950658) (xy 279.68956 -30.92069) (xy 265.868404 -30.92069)
			(xy 265.868404 -30.922468) (xy 265.867914 -30.952452) (xy 265.860086 -31.011908) (xy 265.844565 -31.069833)
			(xy 265.821616 -31.125237) (xy 265.791632 -31.177171) (xy 265.755126 -31.224747) (xy 265.712721 -31.267152)
			(xy 265.665145 -31.303658) (xy 265.613211 -31.333642) (xy 265.557807 -31.356591) (xy 265.499882 -31.372112)
			(xy 265.440426 -31.37994) (xy 265.380458 -31.37994) (xy 265.321002 -31.372112) (xy 265.263077 -31.356591)
			(xy 265.207673 -31.333642) (xy 265.155739 -31.303658) (xy 265.108163 -31.267152) (xy 265.065758 -31.224747)
			(xy 265.029252 -31.177171) (xy 264.999268 -31.125237) (xy 264.976319 -31.069833) (xy 264.960798 -31.011908)
			(xy 264.95297 -30.952452) (xy 264.95248 -30.922468) (xy 254.604999 -30.922468) (xy 254.604538 -30.950658)
			(xy 254.596715 -31.01008) (xy 254.581202 -31.067973) (xy 254.558266 -31.123346) (xy 254.528299 -31.175252)
			(xy 254.491812 -31.222802) (xy 254.449432 -31.265182) (xy 254.401882 -31.301669) (xy 254.349976 -31.331636)
			(xy 254.294603 -31.354572) (xy 254.23671 -31.370085) (xy 254.177288 -31.377908) (xy 254.117352 -31.377908)
			(xy 254.05793 -31.370085) (xy 254.000037 -31.354572) (xy 253.944664 -31.331636) (xy 253.892758 -31.301669)
			(xy 253.845208 -31.265182) (xy 253.802828 -31.222802) (xy 253.766341 -31.175252) (xy 253.736374 -31.123346)
			(xy 253.713438 -31.067973) (xy 253.697925 -31.01008) (xy 253.690102 -30.950658) (xy 253.689612 -30.92069)
			(xy 239.868456 -30.92069) (xy 239.868456 -30.922468) (xy 239.867966 -30.952452) (xy 239.860138 -31.011908)
			(xy 239.844617 -31.069833) (xy 239.821668 -31.125237) (xy 239.791684 -31.177171) (xy 239.755178 -31.224747)
			(xy 239.712773 -31.267152) (xy 239.665197 -31.303658) (xy 239.613263 -31.333642) (xy 239.557859 -31.356591)
			(xy 239.499934 -31.372112) (xy 239.440478 -31.37994) (xy 239.38051 -31.37994) (xy 239.321054 -31.372112)
			(xy 239.263129 -31.356591) (xy 239.207725 -31.333642) (xy 239.155791 -31.303658) (xy 239.108215 -31.267152)
			(xy 239.06581 -31.224747) (xy 239.029304 -31.177171) (xy 238.99932 -31.125237) (xy 238.976371 -31.069833)
			(xy 238.96085 -31.011908) (xy 238.953022 -30.952452) (xy 238.952532 -30.922468) (xy 216.504999 -30.922468)
			(xy 216.504538 -30.950658) (xy 216.496715 -31.01008) (xy 216.481202 -31.067973) (xy 216.458266 -31.123346)
			(xy 216.428299 -31.175252) (xy 216.391812 -31.222802) (xy 216.349432 -31.265182) (xy 216.301882 -31.301669)
			(xy 216.249976 -31.331636) (xy 216.194603 -31.354572) (xy 216.13671 -31.370085) (xy 216.077288 -31.377908)
			(xy 216.017352 -31.377908) (xy 215.95793 -31.370085) (xy 215.900037 -31.354572) (xy 215.844664 -31.331636)
			(xy 215.792758 -31.301669) (xy 215.745208 -31.265182) (xy 215.702828 -31.222802) (xy 215.666341 -31.175252)
			(xy 215.636374 -31.123346) (xy 215.613438 -31.067973) (xy 215.597925 -31.01008) (xy 215.590102 -30.950658)
			(xy 215.589612 -30.92069) (xy 201.768456 -30.92069) (xy 201.768456 -30.922468) (xy 201.767966 -30.952452)
			(xy 201.760138 -31.011908) (xy 201.744617 -31.069833) (xy 201.721668 -31.125237) (xy 201.691684 -31.177171)
			(xy 201.655178 -31.224747) (xy 201.612773 -31.267152) (xy 201.565197 -31.303658) (xy 201.513263 -31.333642)
			(xy 201.457859 -31.356591) (xy 201.399934 -31.372112) (xy 201.340478 -31.37994) (xy 201.28051 -31.37994)
			(xy 201.221054 -31.372112) (xy 201.163129 -31.356591) (xy 201.107725 -31.333642) (xy 201.055791 -31.303658)
			(xy 201.008215 -31.267152) (xy 200.96581 -31.224747) (xy 200.929304 -31.177171) (xy 200.89932 -31.125237)
			(xy 200.876371 -31.069833) (xy 200.86085 -31.011908) (xy 200.853022 -30.952452) (xy 200.852532 -30.922468)
			(xy 190.505051 -30.922468) (xy 190.50459 -30.950658) (xy 190.496767 -31.01008) (xy 190.481254 -31.067973)
			(xy 190.458318 -31.123346) (xy 190.428351 -31.175252) (xy 190.391864 -31.222802) (xy 190.349484 -31.265182)
			(xy 190.301934 -31.301669) (xy 190.250028 -31.331636) (xy 190.194655 -31.354572) (xy 190.136762 -31.370085)
			(xy 190.07734 -31.377908) (xy 190.017404 -31.377908) (xy 189.957982 -31.370085) (xy 189.900089 -31.354572)
			(xy 189.844716 -31.331636) (xy 189.79281 -31.301669) (xy 189.74526 -31.265182) (xy 189.70288 -31.222802)
			(xy 189.666393 -31.175252) (xy 189.636426 -31.123346) (xy 189.61349 -31.067973) (xy 189.597977 -31.01008)
			(xy 189.590154 -30.950658) (xy 189.589664 -30.92069) (xy 175.768508 -30.92069) (xy 175.768508 -30.922468)
			(xy 175.768018 -30.952452) (xy 175.76019 -31.011908) (xy 175.744669 -31.069833) (xy 175.72172 -31.125237)
			(xy 175.691736 -31.177171) (xy 175.65523 -31.224747) (xy 175.612825 -31.267152) (xy 175.565249 -31.303658)
			(xy 175.513315 -31.333642) (xy 175.457911 -31.356591) (xy 175.399986 -31.372112) (xy 175.34053 -31.37994)
			(xy 175.280562 -31.37994) (xy 175.221106 -31.372112) (xy 175.163181 -31.356591) (xy 175.107777 -31.333642)
			(xy 175.055843 -31.303658) (xy 175.008267 -31.267152) (xy 174.965862 -31.224747) (xy 174.929356 -31.177171)
			(xy 174.899372 -31.125237) (xy 174.876423 -31.069833) (xy 174.860902 -31.011908) (xy 174.853074 -30.952452)
			(xy 174.852584 -30.922468) (xy 164.505103 -30.922468) (xy 164.504642 -30.950658) (xy 164.496819 -31.01008)
			(xy 164.481306 -31.067973) (xy 164.45837 -31.123346) (xy 164.428403 -31.175252) (xy 164.391916 -31.222802)
			(xy 164.349536 -31.265182) (xy 164.301986 -31.301669) (xy 164.25008 -31.331636) (xy 164.194707 -31.354572)
			(xy 164.136814 -31.370085) (xy 164.077392 -31.377908) (xy 164.017456 -31.377908) (xy 163.958034 -31.370085)
			(xy 163.900141 -31.354572) (xy 163.844768 -31.331636) (xy 163.792862 -31.301669) (xy 163.745312 -31.265182)
			(xy 163.702932 -31.222802) (xy 163.666445 -31.175252) (xy 163.636478 -31.123346) (xy 163.613542 -31.067973)
			(xy 163.598029 -31.01008) (xy 163.590206 -30.950658) (xy 163.589716 -30.92069) (xy 149.76856 -30.92069)
			(xy 149.76856 -30.922468) (xy 149.76807 -30.952452) (xy 149.760242 -31.011908) (xy 149.744721 -31.069833)
			(xy 149.721772 -31.125237) (xy 149.691788 -31.177171) (xy 149.655282 -31.224747) (xy 149.612877 -31.267152)
			(xy 149.565301 -31.303658) (xy 149.513367 -31.333642) (xy 149.457963 -31.356591) (xy 149.400038 -31.372112)
			(xy 149.340582 -31.37994) (xy 149.280614 -31.37994) (xy 149.221158 -31.372112) (xy 149.163233 -31.356591)
			(xy 149.107829 -31.333642) (xy 149.055895 -31.303658) (xy 149.008319 -31.267152) (xy 148.965914 -31.224747)
			(xy 148.929408 -31.177171) (xy 148.899424 -31.125237) (xy 148.876475 -31.069833) (xy 148.860954 -31.011908)
			(xy 148.853126 -30.952452) (xy 148.852636 -30.922468) (xy 138.505155 -30.922468) (xy 138.504694 -30.950658)
			(xy 138.496871 -31.01008) (xy 138.481358 -31.067973) (xy 138.458422 -31.123346) (xy 138.428455 -31.175252)
			(xy 138.391968 -31.222802) (xy 138.349588 -31.265182) (xy 138.302038 -31.301669) (xy 138.250132 -31.331636)
			(xy 138.194759 -31.354572) (xy 138.136866 -31.370085) (xy 138.077444 -31.377908) (xy 138.017508 -31.377908)
			(xy 137.958086 -31.370085) (xy 137.900193 -31.354572) (xy 137.84482 -31.331636) (xy 137.792914 -31.301669)
			(xy 137.745364 -31.265182) (xy 137.702984 -31.222802) (xy 137.666497 -31.175252) (xy 137.63653 -31.123346)
			(xy 137.613594 -31.067973) (xy 137.598081 -31.01008) (xy 137.590258 -30.950658) (xy 137.589768 -30.92069)
			(xy 123.768612 -30.92069) (xy 123.768612 -30.922468) (xy 123.768122 -30.952452) (xy 123.760294 -31.011908)
			(xy 123.744773 -31.069833) (xy 123.721824 -31.125237) (xy 123.69184 -31.177171) (xy 123.655334 -31.224747)
			(xy 123.612929 -31.267152) (xy 123.565353 -31.303658) (xy 123.513419 -31.333642) (xy 123.458015 -31.356591)
			(xy 123.40009 -31.372112) (xy 123.340634 -31.37994) (xy 123.280666 -31.37994) (xy 123.22121 -31.372112)
			(xy 123.163285 -31.356591) (xy 123.107881 -31.333642) (xy 123.055947 -31.303658) (xy 123.008371 -31.267152)
			(xy 122.965966 -31.224747) (xy 122.92946 -31.177171) (xy 122.899476 -31.125237) (xy 122.876527 -31.069833)
			(xy 122.861006 -31.011908) (xy 122.853178 -30.952452) (xy 122.852688 -30.922468) (xy 100.405155 -30.922468)
			(xy 100.404694 -30.950674) (xy 100.396866 -31.01013) (xy 100.381345 -31.068055) (xy 100.358396 -31.123459)
			(xy 100.328412 -31.175393) (xy 100.291906 -31.222969) (xy 100.249501 -31.265374) (xy 100.201925 -31.30188)
			(xy 100.149991 -31.331864) (xy 100.094587 -31.354813) (xy 100.036662 -31.370334) (xy 99.977206 -31.378162)
			(xy 99.917238 -31.378162) (xy 99.857782 -31.370334) (xy 99.799857 -31.354813) (xy 99.744453 -31.331864)
			(xy 99.692519 -31.30188) (xy 99.644943 -31.265374) (xy 99.602538 -31.222969) (xy 99.566032 -31.175393)
			(xy 99.536048 -31.123459) (xy 99.513099 -31.068055) (xy 99.497578 -31.01013) (xy 99.48975 -30.950674)
			(xy 99.48926 -30.92069) (xy 85.668104 -30.92069) (xy 85.668104 -30.922468) (xy 85.667614 -30.952436)
			(xy 85.659791 -31.011858) (xy 85.644278 -31.069751) (xy 85.621342 -31.125124) (xy 85.591375 -31.17703)
			(xy 85.554888 -31.22458) (xy 85.512508 -31.26696) (xy 85.464958 -31.303447) (xy 85.413052 -31.333414)
			(xy 85.357679 -31.35635) (xy 85.299786 -31.371863) (xy 85.240364 -31.379686) (xy 85.180428 -31.379686)
			(xy 85.121006 -31.371863) (xy 85.063113 -31.35635) (xy 85.00774 -31.333414) (xy 84.955834 -31.303447)
			(xy 84.908284 -31.26696) (xy 84.865904 -31.22458) (xy 84.829417 -31.17703) (xy 84.79945 -31.125124)
			(xy 84.776514 -31.069751) (xy 84.761001 -31.011858) (xy 84.753178 -30.952436) (xy 84.752688 -30.922468)
			(xy 74.405207 -30.922468) (xy 74.404746 -30.950674) (xy 74.396918 -31.01013) (xy 74.381397 -31.068055)
			(xy 74.358448 -31.123459) (xy 74.328464 -31.175393) (xy 74.291958 -31.222969) (xy 74.249553 -31.265374)
			(xy 74.201977 -31.30188) (xy 74.150043 -31.331864) (xy 74.094639 -31.354813) (xy 74.036714 -31.370334)
			(xy 73.977258 -31.378162) (xy 73.91729 -31.378162) (xy 73.857834 -31.370334) (xy 73.799909 -31.354813)
			(xy 73.744505 -31.331864) (xy 73.692571 -31.30188) (xy 73.644995 -31.265374) (xy 73.60259 -31.222969)
			(xy 73.566084 -31.175393) (xy 73.5361 -31.123459) (xy 73.513151 -31.068055) (xy 73.49763 -31.01013)
			(xy 73.489802 -30.950674) (xy 73.489312 -30.92069) (xy 59.668156 -30.92069) (xy 59.668156 -30.922468)
			(xy 59.667666 -30.952436) (xy 59.659843 -31.011858) (xy 59.64433 -31.069751) (xy 59.621394 -31.125124)
			(xy 59.591427 -31.17703) (xy 59.55494 -31.22458) (xy 59.51256 -31.26696) (xy 59.46501 -31.303447)
			(xy 59.413104 -31.333414) (xy 59.357731 -31.35635) (xy 59.299838 -31.371863) (xy 59.240416 -31.379686)
			(xy 59.18048 -31.379686) (xy 59.121058 -31.371863) (xy 59.063165 -31.35635) (xy 59.007792 -31.333414)
			(xy 58.955886 -31.303447) (xy 58.908336 -31.26696) (xy 58.865956 -31.22458) (xy 58.829469 -31.17703)
			(xy 58.799502 -31.125124) (xy 58.776566 -31.069751) (xy 58.761053 -31.011858) (xy 58.75323 -30.952436)
			(xy 58.75274 -30.922468) (xy 48.405259 -30.922468) (xy 48.404798 -30.950674) (xy 48.39697 -31.01013)
			(xy 48.381449 -31.068055) (xy 48.3585 -31.123459) (xy 48.328516 -31.175393) (xy 48.29201 -31.222969)
			(xy 48.249605 -31.265374) (xy 48.202029 -31.30188) (xy 48.150095 -31.331864) (xy 48.094691 -31.354813)
			(xy 48.036766 -31.370334) (xy 47.97731 -31.378162) (xy 47.917342 -31.378162) (xy 47.857886 -31.370334)
			(xy 47.799961 -31.354813) (xy 47.744557 -31.331864) (xy 47.692623 -31.30188) (xy 47.645047 -31.265374)
			(xy 47.602642 -31.222969) (xy 47.566136 -31.175393) (xy 47.536152 -31.123459) (xy 47.513203 -31.068055)
			(xy 47.497682 -31.01013) (xy 47.489854 -30.950674) (xy 47.489364 -30.92069) (xy 33.668208 -30.92069)
			(xy 33.668208 -30.922468) (xy 33.667718 -30.952436) (xy 33.659895 -31.011858) (xy 33.644382 -31.069751)
			(xy 33.621446 -31.125124) (xy 33.591479 -31.17703) (xy 33.554992 -31.22458) (xy 33.512612 -31.26696)
			(xy 33.465062 -31.303447) (xy 33.413156 -31.333414) (xy 33.357783 -31.35635) (xy 33.29989 -31.371863)
			(xy 33.240468 -31.379686) (xy 33.180532 -31.379686) (xy 33.12111 -31.371863) (xy 33.063217 -31.35635)
			(xy 33.007844 -31.333414) (xy 32.955938 -31.303447) (xy 32.908388 -31.26696) (xy 32.866008 -31.22458)
			(xy 32.829521 -31.17703) (xy 32.799554 -31.125124) (xy 32.776618 -31.069751) (xy 32.761105 -31.011858)
			(xy 32.753282 -30.952436) (xy 32.752792 -30.922468) (xy 22.405311 -30.922468) (xy 22.40485 -30.950674)
			(xy 22.397022 -31.01013) (xy 22.381501 -31.068055) (xy 22.358552 -31.123459) (xy 22.328568 -31.175393)
			(xy 22.292062 -31.222969) (xy 22.249657 -31.265374) (xy 22.202081 -31.30188) (xy 22.150147 -31.331864)
			(xy 22.094743 -31.354813) (xy 22.036818 -31.370334) (xy 21.977362 -31.378162) (xy 21.917394 -31.378162)
			(xy 21.857938 -31.370334) (xy 21.800013 -31.354813) (xy 21.744609 -31.331864) (xy 21.692675 -31.30188)
			(xy 21.645099 -31.265374) (xy 21.602694 -31.222969) (xy 21.566188 -31.175393) (xy 21.536204 -31.123459)
			(xy 21.513255 -31.068055) (xy 21.497734 -31.01013) (xy 21.489906 -30.950674) (xy 21.489416 -30.92069)
			(xy 7.66826 -30.92069) (xy 7.66826 -30.922468) (xy 7.66777 -30.952436) (xy 7.659947 -31.011858) (xy 7.644434 -31.069751)
			(xy 7.621498 -31.125124) (xy 7.591531 -31.17703) (xy 7.555044 -31.22458) (xy 7.512664 -31.26696)
			(xy 7.465114 -31.303447) (xy 7.413208 -31.333414) (xy 7.357835 -31.35635) (xy 7.299942 -31.371863)
			(xy 7.24052 -31.379686) (xy 7.180584 -31.379686) (xy 7.121162 -31.371863) (xy 7.063269 -31.35635)
			(xy 7.007896 -31.333414) (xy 6.95599 -31.303447) (xy 6.90844 -31.26696) (xy 6.86606 -31.22458) (xy 6.829573 -31.17703)
			(xy 6.799606 -31.125124) (xy 6.77667 -31.069751) (xy 6.761157 -31.011858) (xy 6.753334 -30.952436)
			(xy 6.752844 -30.922468) (xy 2.02438 -30.922468) (xy 2.02438 -32.722312) (xy 8.607044 -32.722312)
			(xy 8.607044 -31.858712) (xy 8.607534 -31.828744) (xy 8.615357 -31.769322) (xy 8.63087 -31.711429)
			(xy 8.653806 -31.656056) (xy 8.683773 -31.60415) (xy 8.72026 -31.5566) (xy 8.76264 -31.51422) (xy 8.81019 -31.477733)
			(xy 8.862096 -31.447766) (xy 8.917469 -31.42483) (xy 8.975362 -31.409317) (xy 9.034784 -31.401494)
			(xy 9.09472 -31.401494) (xy 9.154142 -31.409317) (xy 9.212035 -31.42483) (xy 9.267408 -31.447766)
			(xy 9.319314 -31.477733) (xy 9.366864 -31.51422) (xy 9.409244 -31.5566) (xy 9.445731 -31.60415) (xy 9.475698 -31.656056)
			(xy 9.498634 -31.711429) (xy 9.514147 -31.769322) (xy 9.52197 -31.828744) (xy 9.52246 -31.858712)
			(xy 9.52246 -32.714184) (xy 18.847308 -32.714184) (xy 18.847308 -31.850584) (xy 18.847798 -31.8206)
			(xy 18.855626 -31.761144) (xy 18.871147 -31.703219) (xy 18.894096 -31.647815) (xy 18.92408 -31.595881)
			(xy 18.960586 -31.548305) (xy 19.002991 -31.5059) (xy 19.050567 -31.469394) (xy 19.102501 -31.43941)
			(xy 19.157905 -31.416461) (xy 19.21583 -31.40094) (xy 19.275286 -31.393112) (xy 19.335254 -31.393112)
			(xy 19.39471 -31.40094) (xy 19.452635 -31.416461) (xy 19.508039 -31.43941) (xy 19.559973 -31.469394)
			(xy 19.607549 -31.5059) (xy 19.649954 -31.548305) (xy 19.664976 -31.567882) (xy 26.998674 -31.567882)
			(xy 27.002745 -31.51226) (xy 27.014871 -31.457823) (xy 27.034794 -31.405732) (xy 27.06209 -31.357097)
			(xy 27.096176 -31.312954) (xy 27.136325 -31.274245) (xy 27.181683 -31.241794) (xy 27.231283 -31.216293)
			(xy 27.284067 -31.198286) (xy 27.33891 -31.188156) (xy 27.394644 -31.186119) (xy 27.450081 -31.192219)
			(xy 27.504038 -31.206325) (xy 27.555367 -31.228137) (xy 27.602973 -31.257191) (xy 27.645841 -31.292866)
			(xy 27.683058 -31.334403) (xy 27.713831 -31.380916) (xy 27.737503 -31.431413) (xy 27.753571 -31.48482)
			(xy 27.761691 -31.539996) (xy 27.7622 -31.567882) (xy 27.761691 -31.595768) (xy 27.753571 -31.650944)
			(xy 27.737503 -31.704351) (xy 27.730511 -31.719266) (xy 28.285438 -31.719266) (xy 28.289509 -31.663644)
			(xy 28.301635 -31.609207) (xy 28.321558 -31.557116) (xy 28.348854 -31.508481) (xy 28.38294 -31.464338)
			(xy 28.423089 -31.425629) (xy 28.468447 -31.393178) (xy 28.518047 -31.367677) (xy 28.570831 -31.34967)
			(xy 28.625674 -31.33954) (xy 28.681408 -31.337503) (xy 28.736845 -31.343603) (xy 28.790802 -31.357709)
			(xy 28.842131 -31.379521) (xy 28.889737 -31.408575) (xy 28.932605 -31.44425) (xy 28.969822 -31.485787)
			(xy 29.000595 -31.5323) (xy 29.024267 -31.582797) (xy 29.040335 -31.636204) (xy 29.044485 -31.664402)
			(xy 29.561026 -31.664402) (xy 29.565097 -31.60878) (xy 29.577223 -31.554343) (xy 29.597146 -31.502252)
			(xy 29.624442 -31.453617) (xy 29.658528 -31.409474) (xy 29.698677 -31.370765) (xy 29.744035 -31.338314)
			(xy 29.793635 -31.312813) (xy 29.846419 -31.294806) (xy 29.901262 -31.284676) (xy 29.956996 -31.282639)
			(xy 30.012433 -31.288739) (xy 30.06639 -31.302845) (xy 30.117719 -31.324657) (xy 30.165325 -31.353711)
			(xy 30.208193 -31.389386) (xy 30.24541 -31.430923) (xy 30.276183 -31.477436) (xy 30.299855 -31.527933)
			(xy 30.315923 -31.58134) (xy 30.324043 -31.636516) (xy 30.324552 -31.664402) (xy 30.324043 -31.692288)
			(xy 30.315923 -31.747464) (xy 30.306983 -31.777178) (xy 30.8262 -31.777178) (xy 30.830271 -31.721556)
			(xy 30.842397 -31.667119) (xy 30.86232 -31.615028) (xy 30.889616 -31.566393) (xy 30.923702 -31.52225)
			(xy 30.963851 -31.483541) (xy 31.009209 -31.45109) (xy 31.058809 -31.425589) (xy 31.111593 -31.407582)
			(xy 31.166436 -31.397452) (xy 31.22217 -31.395415) (xy 31.277607 -31.401515) (xy 31.331564 -31.415621)
			(xy 31.382893 -31.437433) (xy 31.430499 -31.466487) (xy 31.473367 -31.502162) (xy 31.510584 -31.543699)
			(xy 31.541357 -31.590212) (xy 31.565029 -31.640709) (xy 31.581097 -31.694116) (xy 31.589217 -31.749292)
			(xy 31.589726 -31.777178) (xy 31.589217 -31.805064) (xy 31.581097 -31.86024) (xy 31.565029 -31.913647)
			(xy 31.541357 -31.964144) (xy 31.510584 -32.010657) (xy 31.473367 -32.052194) (xy 31.430499 -32.087869)
			(xy 31.382893 -32.116923) (xy 31.331564 -32.138735) (xy 31.277607 -32.152841) (xy 31.22217 -32.158941)
			(xy 31.166436 -32.156904) (xy 31.111593 -32.146774) (xy 31.058809 -32.128767) (xy 31.009209 -32.103266)
			(xy 30.963851 -32.070815) (xy 30.923702 -32.032106) (xy 30.889616 -31.987963) (xy 30.86232 -31.939328)
			(xy 30.842397 -31.887237) (xy 30.830271 -31.8328) (xy 30.8262 -31.777178) (xy 30.306983 -31.777178)
			(xy 30.299855 -31.800871) (xy 30.276183 -31.851368) (xy 30.24541 -31.897881) (xy 30.208193 -31.939418)
			(xy 30.165325 -31.975093) (xy 30.117719 -32.004147) (xy 30.06639 -32.025959) (xy 30.012433 -32.040065)
			(xy 29.956996 -32.046165) (xy 29.901262 -32.044128) (xy 29.846419 -32.033998) (xy 29.793635 -32.015991)
			(xy 29.744035 -31.99049) (xy 29.698677 -31.958039) (xy 29.658528 -31.91933) (xy 29.624442 -31.875187)
			(xy 29.597146 -31.826552) (xy 29.577223 -31.774461) (xy 29.565097 -31.720024) (xy 29.561026 -31.664402)
			(xy 29.044485 -31.664402) (xy 29.048455 -31.69138) (xy 29.048964 -31.719266) (xy 29.048455 -31.747152)
			(xy 29.040335 -31.802328) (xy 29.024267 -31.855735) (xy 29.000595 -31.906232) (xy 28.969822 -31.952745)
			(xy 28.932605 -31.994282) (xy 28.889737 -32.029957) (xy 28.842131 -32.059011) (xy 28.790802 -32.080823)
			(xy 28.736845 -32.094929) (xy 28.681408 -32.101029) (xy 28.625674 -32.098992) (xy 28.570831 -32.088862)
			(xy 28.518047 -32.070855) (xy 28.468447 -32.045354) (xy 28.423089 -32.012903) (xy 28.38294 -31.974194)
			(xy 28.348854 -31.930051) (xy 28.321558 -31.881416) (xy 28.301635 -31.829325) (xy 28.289509 -31.774888)
			(xy 28.285438 -31.719266) (xy 27.730511 -31.719266) (xy 27.713831 -31.754848) (xy 27.683058 -31.801361)
			(xy 27.645841 -31.842898) (xy 27.602973 -31.878573) (xy 27.555367 -31.907627) (xy 27.504038 -31.929439)
			(xy 27.450081 -31.943545) (xy 27.394644 -31.949645) (xy 27.33891 -31.947608) (xy 27.284067 -31.937478)
			(xy 27.231283 -31.919471) (xy 27.181683 -31.89397) (xy 27.136325 -31.861519) (xy 27.096176 -31.82281)
			(xy 27.06209 -31.778667) (xy 27.034794 -31.730032) (xy 27.014871 -31.677941) (xy 27.002745 -31.623504)
			(xy 26.998674 -31.567882) (xy 19.664976 -31.567882) (xy 19.68646 -31.595881) (xy 19.716444 -31.647815)
			(xy 19.739393 -31.703219) (xy 19.754914 -31.761144) (xy 19.762742 -31.8206) (xy 19.763232 -31.850584)
			(xy 19.763232 -32.714184) (xy 19.763099 -32.722312) (xy 34.606992 -32.722312) (xy 34.606992 -31.858712)
			(xy 34.607482 -31.828744) (xy 34.615305 -31.769322) (xy 34.630818 -31.711429) (xy 34.653754 -31.656056)
			(xy 34.683721 -31.60415) (xy 34.720208 -31.5566) (xy 34.762588 -31.51422) (xy 34.810138 -31.477733)
			(xy 34.862044 -31.447766) (xy 34.917417 -31.42483) (xy 34.97531 -31.409317) (xy 35.034732 -31.401494)
			(xy 35.094668 -31.401494) (xy 35.15409 -31.409317) (xy 35.211983 -31.42483) (xy 35.267356 -31.447766)
			(xy 35.319262 -31.477733) (xy 35.366812 -31.51422) (xy 35.409192 -31.5566) (xy 35.445679 -31.60415)
			(xy 35.475646 -31.656056) (xy 35.498582 -31.711429) (xy 35.514095 -31.769322) (xy 35.521918 -31.828744)
			(xy 35.522408 -31.858712) (xy 35.522408 -32.714184) (xy 44.847256 -32.714184) (xy 44.847256 -31.850584)
			(xy 44.847746 -31.8206) (xy 44.855574 -31.761144) (xy 44.871095 -31.703219) (xy 44.894044 -31.647815)
			(xy 44.924028 -31.595881) (xy 44.960534 -31.548305) (xy 45.002939 -31.5059) (xy 45.050515 -31.469394)
			(xy 45.102449 -31.43941) (xy 45.157853 -31.416461) (xy 45.215778 -31.40094) (xy 45.275234 -31.393112)
			(xy 45.335202 -31.393112) (xy 45.394658 -31.40094) (xy 45.452583 -31.416461) (xy 45.507987 -31.43941)
			(xy 45.559921 -31.469394) (xy 45.607497 -31.5059) (xy 45.649902 -31.548305) (xy 45.664924 -31.567882)
			(xy 52.998622 -31.567882) (xy 53.002693 -31.51226) (xy 53.014819 -31.457823) (xy 53.034742 -31.405732)
			(xy 53.062038 -31.357097) (xy 53.096124 -31.312954) (xy 53.136273 -31.274245) (xy 53.181631 -31.241794)
			(xy 53.231231 -31.216293) (xy 53.284015 -31.198286) (xy 53.338858 -31.188156) (xy 53.394592 -31.186119)
			(xy 53.450029 -31.192219) (xy 53.503986 -31.206325) (xy 53.555315 -31.228137) (xy 53.602921 -31.257191)
			(xy 53.645789 -31.292866) (xy 53.683006 -31.334403) (xy 53.713779 -31.380916) (xy 53.737451 -31.431413)
			(xy 53.753519 -31.48482) (xy 53.761639 -31.539996) (xy 53.762148 -31.567882) (xy 53.761639 -31.595768)
			(xy 53.753519 -31.650944) (xy 53.737451 -31.704351) (xy 53.730459 -31.719266) (xy 54.285386 -31.719266)
			(xy 54.289457 -31.663644) (xy 54.301583 -31.609207) (xy 54.321506 -31.557116) (xy 54.348802 -31.508481)
			(xy 54.382888 -31.464338) (xy 54.423037 -31.425629) (xy 54.468395 -31.393178) (xy 54.517995 -31.367677)
			(xy 54.570779 -31.34967) (xy 54.625622 -31.33954) (xy 54.681356 -31.337503) (xy 54.736793 -31.343603)
			(xy 54.79075 -31.357709) (xy 54.842079 -31.379521) (xy 54.889685 -31.408575) (xy 54.932553 -31.44425)
			(xy 54.96977 -31.485787) (xy 55.000543 -31.5323) (xy 55.024215 -31.582797) (xy 55.040283 -31.636204)
			(xy 55.044433 -31.664402) (xy 55.560974 -31.664402) (xy 55.565045 -31.60878) (xy 55.577171 -31.554343)
			(xy 55.597094 -31.502252) (xy 55.62439 -31.453617) (xy 55.658476 -31.409474) (xy 55.698625 -31.370765)
			(xy 55.743983 -31.338314) (xy 55.793583 -31.312813) (xy 55.846367 -31.294806) (xy 55.90121 -31.284676)
			(xy 55.956944 -31.282639) (xy 56.012381 -31.288739) (xy 56.066338 -31.302845) (xy 56.117667 -31.324657)
			(xy 56.165273 -31.353711) (xy 56.208141 -31.389386) (xy 56.245358 -31.430923) (xy 56.276131 -31.477436)
			(xy 56.299803 -31.527933) (xy 56.315871 -31.58134) (xy 56.323991 -31.636516) (xy 56.3245 -31.664402)
			(xy 56.323991 -31.692288) (xy 56.315871 -31.747464) (xy 56.306931 -31.777178) (xy 56.826148 -31.777178)
			(xy 56.830219 -31.721556) (xy 56.842345 -31.667119) (xy 56.862268 -31.615028) (xy 56.889564 -31.566393)
			(xy 56.92365 -31.52225) (xy 56.963799 -31.483541) (xy 57.009157 -31.45109) (xy 57.058757 -31.425589)
			(xy 57.111541 -31.407582) (xy 57.166384 -31.397452) (xy 57.222118 -31.395415) (xy 57.277555 -31.401515)
			(xy 57.331512 -31.415621) (xy 57.382841 -31.437433) (xy 57.430447 -31.466487) (xy 57.473315 -31.502162)
			(xy 57.510532 -31.543699) (xy 57.541305 -31.590212) (xy 57.564977 -31.640709) (xy 57.581045 -31.694116)
			(xy 57.589165 -31.749292) (xy 57.589674 -31.777178) (xy 57.589165 -31.805064) (xy 57.581045 -31.86024)
			(xy 57.564977 -31.913647) (xy 57.541305 -31.964144) (xy 57.510532 -32.010657) (xy 57.473315 -32.052194)
			(xy 57.430447 -32.087869) (xy 57.382841 -32.116923) (xy 57.331512 -32.138735) (xy 57.277555 -32.152841)
			(xy 57.222118 -32.158941) (xy 57.166384 -32.156904) (xy 57.111541 -32.146774) (xy 57.058757 -32.128767)
			(xy 57.009157 -32.103266) (xy 56.963799 -32.070815) (xy 56.92365 -32.032106) (xy 56.889564 -31.987963)
			(xy 56.862268 -31.939328) (xy 56.842345 -31.887237) (xy 56.830219 -31.8328) (xy 56.826148 -31.777178)
			(xy 56.306931 -31.777178) (xy 56.299803 -31.800871) (xy 56.276131 -31.851368) (xy 56.245358 -31.897881)
			(xy 56.208141 -31.939418) (xy 56.165273 -31.975093) (xy 56.117667 -32.004147) (xy 56.066338 -32.025959)
			(xy 56.012381 -32.040065) (xy 55.956944 -32.046165) (xy 55.90121 -32.044128) (xy 55.846367 -32.033998)
			(xy 55.793583 -32.015991) (xy 55.743983 -31.99049) (xy 55.698625 -31.958039) (xy 55.658476 -31.91933)
			(xy 55.62439 -31.875187) (xy 55.597094 -31.826552) (xy 55.577171 -31.774461) (xy 55.565045 -31.720024)
			(xy 55.560974 -31.664402) (xy 55.044433 -31.664402) (xy 55.048403 -31.69138) (xy 55.048912 -31.719266)
			(xy 55.048403 -31.747152) (xy 55.040283 -31.802328) (xy 55.024215 -31.855735) (xy 55.000543 -31.906232)
			(xy 54.96977 -31.952745) (xy 54.932553 -31.994282) (xy 54.889685 -32.029957) (xy 54.842079 -32.059011)
			(xy 54.79075 -32.080823) (xy 54.736793 -32.094929) (xy 54.681356 -32.101029) (xy 54.625622 -32.098992)
			(xy 54.570779 -32.088862) (xy 54.517995 -32.070855) (xy 54.468395 -32.045354) (xy 54.423037 -32.012903)
			(xy 54.382888 -31.974194) (xy 54.348802 -31.930051) (xy 54.321506 -31.881416) (xy 54.301583 -31.829325)
			(xy 54.289457 -31.774888) (xy 54.285386 -31.719266) (xy 53.730459 -31.719266) (xy 53.713779 -31.754848)
			(xy 53.683006 -31.801361) (xy 53.645789 -31.842898) (xy 53.602921 -31.878573) (xy 53.555315 -31.907627)
			(xy 53.503986 -31.929439) (xy 53.450029 -31.943545) (xy 53.394592 -31.949645) (xy 53.338858 -31.947608)
			(xy 53.284015 -31.937478) (xy 53.231231 -31.919471) (xy 53.181631 -31.89397) (xy 53.136273 -31.861519)
			(xy 53.096124 -31.82281) (xy 53.062038 -31.778667) (xy 53.034742 -31.730032) (xy 53.014819 -31.677941)
			(xy 53.002693 -31.623504) (xy 52.998622 -31.567882) (xy 45.664924 -31.567882) (xy 45.686408 -31.595881)
			(xy 45.716392 -31.647815) (xy 45.739341 -31.703219) (xy 45.754862 -31.761144) (xy 45.76269 -31.8206)
			(xy 45.76318 -31.850584) (xy 45.76318 -32.714184) (xy 45.763047 -32.722312) (xy 60.60694 -32.722312)
			(xy 60.60694 -31.858712) (xy 60.60743 -31.828744) (xy 60.615253 -31.769322) (xy 60.630766 -31.711429)
			(xy 60.653702 -31.656056) (xy 60.683669 -31.60415) (xy 60.720156 -31.5566) (xy 60.762536 -31.51422)
			(xy 60.810086 -31.477733) (xy 60.861992 -31.447766) (xy 60.917365 -31.42483) (xy 60.975258 -31.409317)
			(xy 61.03468 -31.401494) (xy 61.094616 -31.401494) (xy 61.154038 -31.409317) (xy 61.211931 -31.42483)
			(xy 61.267304 -31.447766) (xy 61.31921 -31.477733) (xy 61.36676 -31.51422) (xy 61.40914 -31.5566)
			(xy 61.445627 -31.60415) (xy 61.475594 -31.656056) (xy 61.49853 -31.711429) (xy 61.514043 -31.769322)
			(xy 61.521866 -31.828744) (xy 61.522356 -31.858712) (xy 61.522356 -32.714184) (xy 70.847204 -32.714184)
			(xy 70.847204 -31.850584) (xy 70.847694 -31.8206) (xy 70.855522 -31.761144) (xy 70.871043 -31.703219)
			(xy 70.893992 -31.647815) (xy 70.923976 -31.595881) (xy 70.960482 -31.548305) (xy 71.002887 -31.5059)
			(xy 71.050463 -31.469394) (xy 71.102397 -31.43941) (xy 71.157801 -31.416461) (xy 71.215726 -31.40094)
			(xy 71.275182 -31.393112) (xy 71.33515 -31.393112) (xy 71.394606 -31.40094) (xy 71.452531 -31.416461)
			(xy 71.507935 -31.43941) (xy 71.559869 -31.469394) (xy 71.607445 -31.5059) (xy 71.64985 -31.548305)
			(xy 71.664872 -31.567882) (xy 78.99857 -31.567882) (xy 79.002641 -31.51226) (xy 79.014767 -31.457823)
			(xy 79.03469 -31.405732) (xy 79.061986 -31.357097) (xy 79.096072 -31.312954) (xy 79.136221 -31.274245)
			(xy 79.181579 -31.241794) (xy 79.231179 -31.216293) (xy 79.283963 -31.198286) (xy 79.338806 -31.188156)
			(xy 79.39454 -31.186119) (xy 79.449977 -31.192219) (xy 79.503934 -31.206325) (xy 79.555263 -31.228137)
			(xy 79.602869 -31.257191) (xy 79.645737 -31.292866) (xy 79.682954 -31.334403) (xy 79.713727 -31.380916)
			(xy 79.737399 -31.431413) (xy 79.753467 -31.48482) (xy 79.761587 -31.539996) (xy 79.762096 -31.567882)
			(xy 79.761587 -31.595768) (xy 79.753467 -31.650944) (xy 79.737399 -31.704351) (xy 79.730407 -31.719266)
			(xy 80.285334 -31.719266) (xy 80.289405 -31.663644) (xy 80.301531 -31.609207) (xy 80.321454 -31.557116)
			(xy 80.34875 -31.508481) (xy 80.382836 -31.464338) (xy 80.422985 -31.425629) (xy 80.468343 -31.393178)
			(xy 80.517943 -31.367677) (xy 80.570727 -31.34967) (xy 80.62557 -31.33954) (xy 80.681304 -31.337503)
			(xy 80.736741 -31.343603) (xy 80.790698 -31.357709) (xy 80.842027 -31.379521) (xy 80.889633 -31.408575)
			(xy 80.932501 -31.44425) (xy 80.969718 -31.485787) (xy 81.000491 -31.5323) (xy 81.024163 -31.582797)
			(xy 81.040231 -31.636204) (xy 81.044381 -31.664402) (xy 81.560922 -31.664402) (xy 81.564993 -31.60878)
			(xy 81.577119 -31.554343) (xy 81.597042 -31.502252) (xy 81.624338 -31.453617) (xy 81.658424 -31.409474)
			(xy 81.698573 -31.370765) (xy 81.743931 -31.338314) (xy 81.793531 -31.312813) (xy 81.846315 -31.294806)
			(xy 81.901158 -31.284676) (xy 81.956892 -31.282639) (xy 82.012329 -31.288739) (xy 82.066286 -31.302845)
			(xy 82.117615 -31.324657) (xy 82.165221 -31.353711) (xy 82.208089 -31.389386) (xy 82.245306 -31.430923)
			(xy 82.276079 -31.477436) (xy 82.299751 -31.527933) (xy 82.315819 -31.58134) (xy 82.323939 -31.636516)
			(xy 82.324448 -31.664402) (xy 82.323939 -31.692288) (xy 82.315819 -31.747464) (xy 82.306879 -31.777178)
			(xy 82.826096 -31.777178) (xy 82.830167 -31.721556) (xy 82.842293 -31.667119) (xy 82.862216 -31.615028)
			(xy 82.889512 -31.566393) (xy 82.923598 -31.52225) (xy 82.963747 -31.483541) (xy 83.009105 -31.45109)
			(xy 83.058705 -31.425589) (xy 83.111489 -31.407582) (xy 83.166332 -31.397452) (xy 83.222066 -31.395415)
			(xy 83.277503 -31.401515) (xy 83.33146 -31.415621) (xy 83.382789 -31.437433) (xy 83.430395 -31.466487)
			(xy 83.473263 -31.502162) (xy 83.51048 -31.543699) (xy 83.541253 -31.590212) (xy 83.564925 -31.640709)
			(xy 83.580993 -31.694116) (xy 83.589113 -31.749292) (xy 83.589622 -31.777178) (xy 83.589113 -31.805064)
			(xy 83.580993 -31.86024) (xy 83.564925 -31.913647) (xy 83.541253 -31.964144) (xy 83.51048 -32.010657)
			(xy 83.473263 -32.052194) (xy 83.430395 -32.087869) (xy 83.382789 -32.116923) (xy 83.33146 -32.138735)
			(xy 83.277503 -32.152841) (xy 83.222066 -32.158941) (xy 83.166332 -32.156904) (xy 83.111489 -32.146774)
			(xy 83.058705 -32.128767) (xy 83.009105 -32.103266) (xy 82.963747 -32.070815) (xy 82.923598 -32.032106)
			(xy 82.889512 -31.987963) (xy 82.862216 -31.939328) (xy 82.842293 -31.887237) (xy 82.830167 -31.8328)
			(xy 82.826096 -31.777178) (xy 82.306879 -31.777178) (xy 82.299751 -31.800871) (xy 82.276079 -31.851368)
			(xy 82.245306 -31.897881) (xy 82.208089 -31.939418) (xy 82.165221 -31.975093) (xy 82.117615 -32.004147)
			(xy 82.066286 -32.025959) (xy 82.012329 -32.040065) (xy 81.956892 -32.046165) (xy 81.901158 -32.044128)
			(xy 81.846315 -32.033998) (xy 81.793531 -32.015991) (xy 81.743931 -31.99049) (xy 81.698573 -31.958039)
			(xy 81.658424 -31.91933) (xy 81.624338 -31.875187) (xy 81.597042 -31.826552) (xy 81.577119 -31.774461)
			(xy 81.564993 -31.720024) (xy 81.560922 -31.664402) (xy 81.044381 -31.664402) (xy 81.048351 -31.69138)
			(xy 81.04886 -31.719266) (xy 81.048351 -31.747152) (xy 81.040231 -31.802328) (xy 81.024163 -31.855735)
			(xy 81.000491 -31.906232) (xy 80.969718 -31.952745) (xy 80.932501 -31.994282) (xy 80.889633 -32.029957)
			(xy 80.842027 -32.059011) (xy 80.790698 -32.080823) (xy 80.736741 -32.094929) (xy 80.681304 -32.101029)
			(xy 80.62557 -32.098992) (xy 80.570727 -32.088862) (xy 80.517943 -32.070855) (xy 80.468343 -32.045354)
			(xy 80.422985 -32.012903) (xy 80.382836 -31.974194) (xy 80.34875 -31.930051) (xy 80.321454 -31.881416)
			(xy 80.301531 -31.829325) (xy 80.289405 -31.774888) (xy 80.285334 -31.719266) (xy 79.730407 -31.719266)
			(xy 79.713727 -31.754848) (xy 79.682954 -31.801361) (xy 79.645737 -31.842898) (xy 79.602869 -31.878573)
			(xy 79.555263 -31.907627) (xy 79.503934 -31.929439) (xy 79.449977 -31.943545) (xy 79.39454 -31.949645)
			(xy 79.338806 -31.947608) (xy 79.283963 -31.937478) (xy 79.231179 -31.919471) (xy 79.181579 -31.89397)
			(xy 79.136221 -31.861519) (xy 79.096072 -31.82281) (xy 79.061986 -31.778667) (xy 79.03469 -31.730032)
			(xy 79.014767 -31.677941) (xy 79.002641 -31.623504) (xy 78.99857 -31.567882) (xy 71.664872 -31.567882)
			(xy 71.686356 -31.595881) (xy 71.71634 -31.647815) (xy 71.739289 -31.703219) (xy 71.75481 -31.761144)
			(xy 71.762638 -31.8206) (xy 71.763128 -31.850584) (xy 71.763128 -32.714184) (xy 71.762995 -32.722312)
			(xy 86.606888 -32.722312) (xy 86.606888 -31.858712) (xy 86.607378 -31.828744) (xy 86.615201 -31.769322)
			(xy 86.630714 -31.711429) (xy 86.65365 -31.656056) (xy 86.683617 -31.60415) (xy 86.720104 -31.5566)
			(xy 86.762484 -31.51422) (xy 86.810034 -31.477733) (xy 86.86194 -31.447766) (xy 86.917313 -31.42483)
			(xy 86.975206 -31.409317) (xy 87.034628 -31.401494) (xy 87.094564 -31.401494) (xy 87.153986 -31.409317)
			(xy 87.211879 -31.42483) (xy 87.267252 -31.447766) (xy 87.319158 -31.477733) (xy 87.366708 -31.51422)
			(xy 87.409088 -31.5566) (xy 87.445575 -31.60415) (xy 87.475542 -31.656056) (xy 87.498478 -31.711429)
			(xy 87.513991 -31.769322) (xy 87.521814 -31.828744) (xy 87.522304 -31.858712) (xy 87.522304 -32.714184)
			(xy 96.847152 -32.714184) (xy 96.847152 -31.850584) (xy 96.847642 -31.8206) (xy 96.85547 -31.761144)
			(xy 96.870991 -31.703219) (xy 96.89394 -31.647815) (xy 96.923924 -31.595881) (xy 96.96043 -31.548305)
			(xy 97.002835 -31.5059) (xy 97.050411 -31.469394) (xy 97.102345 -31.43941) (xy 97.157749 -31.416461)
			(xy 97.215674 -31.40094) (xy 97.27513 -31.393112) (xy 97.335098 -31.393112) (xy 97.394554 -31.40094)
			(xy 97.452479 -31.416461) (xy 97.507883 -31.43941) (xy 97.559817 -31.469394) (xy 97.607393 -31.5059)
			(xy 97.649798 -31.548305) (xy 97.66482 -31.567882) (xy 117.098824 -31.567882) (xy 117.102895 -31.51226)
			(xy 117.115021 -31.457823) (xy 117.134944 -31.405732) (xy 117.16224 -31.357097) (xy 117.196326 -31.312954)
			(xy 117.236475 -31.274245) (xy 117.281833 -31.241794) (xy 117.331433 -31.216293) (xy 117.384217 -31.198286)
			(xy 117.43906 -31.188156) (xy 117.494794 -31.186119) (xy 117.550231 -31.192219) (xy 117.604188 -31.206325)
			(xy 117.655517 -31.228137) (xy 117.703123 -31.257191) (xy 117.745991 -31.292866) (xy 117.783208 -31.334403)
			(xy 117.813981 -31.380916) (xy 117.837653 -31.431413) (xy 117.853721 -31.48482) (xy 117.861841 -31.539996)
			(xy 117.86235 -31.567882) (xy 117.861841 -31.595768) (xy 117.853721 -31.650944) (xy 117.837653 -31.704351)
			(xy 117.830661 -31.719266) (xy 118.385588 -31.719266) (xy 118.389659 -31.663644) (xy 118.401785 -31.609207)
			(xy 118.421708 -31.557116) (xy 118.449004 -31.508481) (xy 118.48309 -31.464338) (xy 118.523239 -31.425629)
			(xy 118.568597 -31.393178) (xy 118.618197 -31.367677) (xy 118.670981 -31.34967) (xy 118.725824 -31.33954)
			(xy 118.781558 -31.337503) (xy 118.836995 -31.343603) (xy 118.890952 -31.357709) (xy 118.942281 -31.379521)
			(xy 118.989887 -31.408575) (xy 119.032755 -31.44425) (xy 119.069972 -31.485787) (xy 119.100745 -31.5323)
			(xy 119.124417 -31.582797) (xy 119.140485 -31.636204) (xy 119.144635 -31.664402) (xy 119.661176 -31.664402)
			(xy 119.665247 -31.60878) (xy 119.677373 -31.554343) (xy 119.697296 -31.502252) (xy 119.724592 -31.453617)
			(xy 119.758678 -31.409474) (xy 119.798827 -31.370765) (xy 119.844185 -31.338314) (xy 119.893785 -31.312813)
			(xy 119.946569 -31.294806) (xy 120.001412 -31.284676) (xy 120.057146 -31.282639) (xy 120.112583 -31.288739)
			(xy 120.16654 -31.302845) (xy 120.217869 -31.324657) (xy 120.265475 -31.353711) (xy 120.308343 -31.389386)
			(xy 120.34556 -31.430923) (xy 120.376333 -31.477436) (xy 120.400005 -31.527933) (xy 120.416073 -31.58134)
			(xy 120.424193 -31.636516) (xy 120.424702 -31.664402) (xy 120.424193 -31.692288) (xy 120.416073 -31.747464)
			(xy 120.407133 -31.777178) (xy 120.92635 -31.777178) (xy 120.930421 -31.721556) (xy 120.942547 -31.667119)
			(xy 120.96247 -31.615028) (xy 120.989766 -31.566393) (xy 121.023852 -31.52225) (xy 121.064001 -31.483541)
			(xy 121.109359 -31.45109) (xy 121.158959 -31.425589) (xy 121.211743 -31.407582) (xy 121.266586 -31.397452)
			(xy 121.32232 -31.395415) (xy 121.377757 -31.401515) (xy 121.431714 -31.415621) (xy 121.483043 -31.437433)
			(xy 121.530649 -31.466487) (xy 121.573517 -31.502162) (xy 121.610734 -31.543699) (xy 121.641507 -31.590212)
			(xy 121.665179 -31.640709) (xy 121.681247 -31.694116) (xy 121.689367 -31.749292) (xy 121.689876 -31.777178)
			(xy 121.689367 -31.805064) (xy 121.681247 -31.86024) (xy 121.665179 -31.913647) (xy 121.641507 -31.964144)
			(xy 121.610734 -32.010657) (xy 121.573517 -32.052194) (xy 121.530649 -32.087869) (xy 121.483043 -32.116923)
			(xy 121.431714 -32.138735) (xy 121.377757 -32.152841) (xy 121.32232 -32.158941) (xy 121.266586 -32.156904)
			(xy 121.211743 -32.146774) (xy 121.158959 -32.128767) (xy 121.109359 -32.103266) (xy 121.064001 -32.070815)
			(xy 121.023852 -32.032106) (xy 120.989766 -31.987963) (xy 120.96247 -31.939328) (xy 120.942547 -31.887237)
			(xy 120.930421 -31.8328) (xy 120.92635 -31.777178) (xy 120.407133 -31.777178) (xy 120.400005 -31.800871)
			(xy 120.376333 -31.851368) (xy 120.34556 -31.897881) (xy 120.308343 -31.939418) (xy 120.265475 -31.975093)
			(xy 120.217869 -32.004147) (xy 120.16654 -32.025959) (xy 120.112583 -32.040065) (xy 120.057146 -32.046165)
			(xy 120.001412 -32.044128) (xy 119.946569 -32.033998) (xy 119.893785 -32.015991) (xy 119.844185 -31.99049)
			(xy 119.798827 -31.958039) (xy 119.758678 -31.91933) (xy 119.724592 -31.875187) (xy 119.697296 -31.826552)
			(xy 119.677373 -31.774461) (xy 119.665247 -31.720024) (xy 119.661176 -31.664402) (xy 119.144635 -31.664402)
			(xy 119.148605 -31.69138) (xy 119.149114 -31.719266) (xy 119.148605 -31.747152) (xy 119.140485 -31.802328)
			(xy 119.124417 -31.855735) (xy 119.100745 -31.906232) (xy 119.069972 -31.952745) (xy 119.032755 -31.994282)
			(xy 118.989887 -32.029957) (xy 118.942281 -32.059011) (xy 118.890952 -32.080823) (xy 118.836995 -32.094929)
			(xy 118.781558 -32.101029) (xy 118.725824 -32.098992) (xy 118.670981 -32.088862) (xy 118.618197 -32.070855)
			(xy 118.568597 -32.045354) (xy 118.523239 -32.012903) (xy 118.48309 -31.974194) (xy 118.449004 -31.930051)
			(xy 118.421708 -31.881416) (xy 118.401785 -31.829325) (xy 118.389659 -31.774888) (xy 118.385588 -31.719266)
			(xy 117.830661 -31.719266) (xy 117.813981 -31.754848) (xy 117.783208 -31.801361) (xy 117.745991 -31.842898)
			(xy 117.703123 -31.878573) (xy 117.655517 -31.907627) (xy 117.604188 -31.929439) (xy 117.550231 -31.943545)
			(xy 117.494794 -31.949645) (xy 117.43906 -31.947608) (xy 117.384217 -31.937478) (xy 117.331433 -31.919471)
			(xy 117.281833 -31.89397) (xy 117.236475 -31.861519) (xy 117.196326 -31.82281) (xy 117.16224 -31.778667)
			(xy 117.134944 -31.730032) (xy 117.115021 -31.677941) (xy 117.102895 -31.623504) (xy 117.098824 -31.567882)
			(xy 97.66482 -31.567882) (xy 97.686304 -31.595881) (xy 97.716288 -31.647815) (xy 97.739237 -31.703219)
			(xy 97.754758 -31.761144) (xy 97.762586 -31.8206) (xy 97.763076 -31.850584) (xy 97.763076 -32.714184)
			(xy 97.762943 -32.722312) (xy 124.706888 -32.722312) (xy 124.706888 -31.858712) (xy 124.707378 -31.828728)
			(xy 124.715206 -31.769272) (xy 124.730727 -31.711347) (xy 124.753676 -31.655943) (xy 124.78366 -31.604009)
			(xy 124.820166 -31.556433) (xy 124.862571 -31.514028) (xy 124.910147 -31.477522) (xy 124.962081 -31.447538)
			(xy 125.017485 -31.424589) (xy 125.07541 -31.409068) (xy 125.134866 -31.40124) (xy 125.194834 -31.40124)
			(xy 125.25429 -31.409068) (xy 125.312215 -31.424589) (xy 125.367619 -31.447538) (xy 125.419553 -31.477522)
			(xy 125.467129 -31.514028) (xy 125.509534 -31.556433) (xy 125.54604 -31.604009) (xy 125.576024 -31.655943)
			(xy 125.598973 -31.711347) (xy 125.614494 -31.769272) (xy 125.622322 -31.828728) (xy 125.622812 -31.858712)
			(xy 125.622812 -32.714184) (xy 134.94766 -32.714184) (xy 134.94766 -31.850584) (xy 134.94815 -31.820616)
			(xy 134.955973 -31.761194) (xy 134.971486 -31.703301) (xy 134.994422 -31.647928) (xy 135.024389 -31.596022)
			(xy 135.060876 -31.548472) (xy 135.103256 -31.506092) (xy 135.150806 -31.469605) (xy 135.202712 -31.439638)
			(xy 135.258085 -31.416702) (xy 135.315978 -31.401189) (xy 135.3754 -31.393366) (xy 135.435336 -31.393366)
			(xy 135.494758 -31.401189) (xy 135.552651 -31.416702) (xy 135.608024 -31.439638) (xy 135.65993 -31.469605)
			(xy 135.70748 -31.506092) (xy 135.74986 -31.548472) (xy 135.764754 -31.567882) (xy 143.098772 -31.567882)
			(xy 143.102843 -31.51226) (xy 143.114969 -31.457823) (xy 143.134892 -31.405732) (xy 143.162188 -31.357097)
			(xy 143.196274 -31.312954) (xy 143.236423 -31.274245) (xy 143.281781 -31.241794) (xy 143.331381 -31.216293)
			(xy 143.384165 -31.198286) (xy 143.439008 -31.188156) (xy 143.494742 -31.186119) (xy 143.550179 -31.192219)
			(xy 143.604136 -31.206325) (xy 143.655465 -31.228137) (xy 143.703071 -31.257191) (xy 143.745939 -31.292866)
			(xy 143.783156 -31.334403) (xy 143.813929 -31.380916) (xy 143.837601 -31.431413) (xy 143.853669 -31.48482)
			(xy 143.861789 -31.539996) (xy 143.862298 -31.567882) (xy 143.861789 -31.595768) (xy 143.853669 -31.650944)
			(xy 143.837601 -31.704351) (xy 143.830609 -31.719266) (xy 144.385536 -31.719266) (xy 144.389607 -31.663644)
			(xy 144.401733 -31.609207) (xy 144.421656 -31.557116) (xy 144.448952 -31.508481) (xy 144.483038 -31.464338)
			(xy 144.523187 -31.425629) (xy 144.568545 -31.393178) (xy 144.618145 -31.367677) (xy 144.670929 -31.34967)
			(xy 144.725772 -31.33954) (xy 144.781506 -31.337503) (xy 144.836943 -31.343603) (xy 144.8909 -31.357709)
			(xy 144.942229 -31.379521) (xy 144.989835 -31.408575) (xy 145.032703 -31.44425) (xy 145.06992 -31.485787)
			(xy 145.100693 -31.5323) (xy 145.124365 -31.582797) (xy 145.140433 -31.636204) (xy 145.144583 -31.664402)
			(xy 145.661124 -31.664402) (xy 145.665195 -31.60878) (xy 145.677321 -31.554343) (xy 145.697244 -31.502252)
			(xy 145.72454 -31.453617) (xy 145.758626 -31.409474) (xy 145.798775 -31.370765) (xy 145.844133 -31.338314)
			(xy 145.893733 -31.312813) (xy 145.946517 -31.294806) (xy 146.00136 -31.284676) (xy 146.057094 -31.282639)
			(xy 146.112531 -31.288739) (xy 146.166488 -31.302845) (xy 146.217817 -31.324657) (xy 146.265423 -31.353711)
			(xy 146.308291 -31.389386) (xy 146.345508 -31.430923) (xy 146.376281 -31.477436) (xy 146.399953 -31.527933)
			(xy 146.416021 -31.58134) (xy 146.424141 -31.636516) (xy 146.42465 -31.664402) (xy 146.424141 -31.692288)
			(xy 146.416021 -31.747464) (xy 146.407081 -31.777178) (xy 146.926298 -31.777178) (xy 146.930369 -31.721556)
			(xy 146.942495 -31.667119) (xy 146.962418 -31.615028) (xy 146.989714 -31.566393) (xy 147.0238 -31.52225)
			(xy 147.063949 -31.483541) (xy 147.109307 -31.45109) (xy 147.158907 -31.425589) (xy 147.211691 -31.407582)
			(xy 147.266534 -31.397452) (xy 147.322268 -31.395415) (xy 147.377705 -31.401515) (xy 147.431662 -31.415621)
			(xy 147.482991 -31.437433) (xy 147.530597 -31.466487) (xy 147.573465 -31.502162) (xy 147.610682 -31.543699)
			(xy 147.641455 -31.590212) (xy 147.665127 -31.640709) (xy 147.681195 -31.694116) (xy 147.689315 -31.749292)
			(xy 147.689824 -31.777178) (xy 147.689315 -31.805064) (xy 147.681195 -31.86024) (xy 147.665127 -31.913647)
			(xy 147.641455 -31.964144) (xy 147.610682 -32.010657) (xy 147.573465 -32.052194) (xy 147.530597 -32.087869)
			(xy 147.482991 -32.116923) (xy 147.431662 -32.138735) (xy 147.377705 -32.152841) (xy 147.322268 -32.158941)
			(xy 147.266534 -32.156904) (xy 147.211691 -32.146774) (xy 147.158907 -32.128767) (xy 147.109307 -32.103266)
			(xy 147.063949 -32.070815) (xy 147.0238 -32.032106) (xy 146.989714 -31.987963) (xy 146.962418 -31.939328)
			(xy 146.942495 -31.887237) (xy 146.930369 -31.8328) (xy 146.926298 -31.777178) (xy 146.407081 -31.777178)
			(xy 146.399953 -31.800871) (xy 146.376281 -31.851368) (xy 146.345508 -31.897881) (xy 146.308291 -31.939418)
			(xy 146.265423 -31.975093) (xy 146.217817 -32.004147) (xy 146.166488 -32.025959) (xy 146.112531 -32.040065)
			(xy 146.057094 -32.046165) (xy 146.00136 -32.044128) (xy 145.946517 -32.033998) (xy 145.893733 -32.015991)
			(xy 145.844133 -31.99049) (xy 145.798775 -31.958039) (xy 145.758626 -31.91933) (xy 145.72454 -31.875187)
			(xy 145.697244 -31.826552) (xy 145.677321 -31.774461) (xy 145.665195 -31.720024) (xy 145.661124 -31.664402)
			(xy 145.144583 -31.664402) (xy 145.148553 -31.69138) (xy 145.149062 -31.719266) (xy 145.148553 -31.747152)
			(xy 145.140433 -31.802328) (xy 145.124365 -31.855735) (xy 145.100693 -31.906232) (xy 145.06992 -31.952745)
			(xy 145.032703 -31.994282) (xy 144.989835 -32.029957) (xy 144.942229 -32.059011) (xy 144.8909 -32.080823)
			(xy 144.836943 -32.094929) (xy 144.781506 -32.101029) (xy 144.725772 -32.098992) (xy 144.670929 -32.088862)
			(xy 144.618145 -32.070855) (xy 144.568545 -32.045354) (xy 144.523187 -32.012903) (xy 144.483038 -31.974194)
			(xy 144.448952 -31.930051) (xy 144.421656 -31.881416) (xy 144.401733 -31.829325) (xy 144.389607 -31.774888)
			(xy 144.385536 -31.719266) (xy 143.830609 -31.719266) (xy 143.813929 -31.754848) (xy 143.783156 -31.801361)
			(xy 143.745939 -31.842898) (xy 143.703071 -31.878573) (xy 143.655465 -31.907627) (xy 143.604136 -31.929439)
			(xy 143.550179 -31.943545) (xy 143.494742 -31.949645) (xy 143.439008 -31.947608) (xy 143.384165 -31.937478)
			(xy 143.331381 -31.919471) (xy 143.281781 -31.89397) (xy 143.236423 -31.861519) (xy 143.196274 -31.82281)
			(xy 143.162188 -31.778667) (xy 143.134892 -31.730032) (xy 143.114969 -31.677941) (xy 143.102843 -31.623504)
			(xy 143.098772 -31.567882) (xy 135.764754 -31.567882) (xy 135.786347 -31.596022) (xy 135.816314 -31.647928)
			(xy 135.83925 -31.703301) (xy 135.854763 -31.761194) (xy 135.862586 -31.820616) (xy 135.863076 -31.850584)
			(xy 135.863076 -32.714184) (xy 135.862943 -32.722312) (xy 150.706836 -32.722312) (xy 150.706836 -31.858712)
			(xy 150.707326 -31.828728) (xy 150.715154 -31.769272) (xy 150.730675 -31.711347) (xy 150.753624 -31.655943)
			(xy 150.783608 -31.604009) (xy 150.820114 -31.556433) (xy 150.862519 -31.514028) (xy 150.910095 -31.477522)
			(xy 150.962029 -31.447538) (xy 151.017433 -31.424589) (xy 151.075358 -31.409068) (xy 151.134814 -31.40124)
			(xy 151.194782 -31.40124) (xy 151.254238 -31.409068) (xy 151.312163 -31.424589) (xy 151.367567 -31.447538)
			(xy 151.419501 -31.477522) (xy 151.467077 -31.514028) (xy 151.509482 -31.556433) (xy 151.545988 -31.604009)
			(xy 151.575972 -31.655943) (xy 151.598921 -31.711347) (xy 151.614442 -31.769272) (xy 151.62227 -31.828728)
			(xy 151.62276 -31.858712) (xy 151.62276 -32.714184) (xy 160.947608 -32.714184) (xy 160.947608 -31.850584)
			(xy 160.948098 -31.820616) (xy 160.955921 -31.761194) (xy 160.971434 -31.703301) (xy 160.99437 -31.647928)
			(xy 161.024337 -31.596022) (xy 161.060824 -31.548472) (xy 161.103204 -31.506092) (xy 161.150754 -31.469605)
			(xy 161.20266 -31.439638) (xy 161.258033 -31.416702) (xy 161.315926 -31.401189) (xy 161.375348 -31.393366)
			(xy 161.435284 -31.393366) (xy 161.494706 -31.401189) (xy 161.552599 -31.416702) (xy 161.607972 -31.439638)
			(xy 161.659878 -31.469605) (xy 161.707428 -31.506092) (xy 161.749808 -31.548472) (xy 161.764702 -31.567882)
			(xy 169.09872 -31.567882) (xy 169.102791 -31.51226) (xy 169.114917 -31.457823) (xy 169.13484 -31.405732)
			(xy 169.162136 -31.357097) (xy 169.196222 -31.312954) (xy 169.236371 -31.274245) (xy 169.281729 -31.241794)
			(xy 169.331329 -31.216293) (xy 169.384113 -31.198286) (xy 169.438956 -31.188156) (xy 169.49469 -31.186119)
			(xy 169.550127 -31.192219) (xy 169.604084 -31.206325) (xy 169.655413 -31.228137) (xy 169.703019 -31.257191)
			(xy 169.745887 -31.292866) (xy 169.783104 -31.334403) (xy 169.813877 -31.380916) (xy 169.837549 -31.431413)
			(xy 169.853617 -31.48482) (xy 169.861737 -31.539996) (xy 169.862246 -31.567882) (xy 169.861737 -31.595768)
			(xy 169.853617 -31.650944) (xy 169.837549 -31.704351) (xy 169.830557 -31.719266) (xy 170.385484 -31.719266)
			(xy 170.389555 -31.663644) (xy 170.401681 -31.609207) (xy 170.421604 -31.557116) (xy 170.4489 -31.508481)
			(xy 170.482986 -31.464338) (xy 170.523135 -31.425629) (xy 170.568493 -31.393178) (xy 170.618093 -31.367677)
			(xy 170.670877 -31.34967) (xy 170.72572 -31.33954) (xy 170.781454 -31.337503) (xy 170.836891 -31.343603)
			(xy 170.890848 -31.357709) (xy 170.942177 -31.379521) (xy 170.989783 -31.408575) (xy 171.032651 -31.44425)
			(xy 171.069868 -31.485787) (xy 171.100641 -31.5323) (xy 171.124313 -31.582797) (xy 171.140381 -31.636204)
			(xy 171.144531 -31.664402) (xy 171.661072 -31.664402) (xy 171.665143 -31.60878) (xy 171.677269 -31.554343)
			(xy 171.697192 -31.502252) (xy 171.724488 -31.453617) (xy 171.758574 -31.409474) (xy 171.798723 -31.370765)
			(xy 171.844081 -31.338314) (xy 171.893681 -31.312813) (xy 171.946465 -31.294806) (xy 172.001308 -31.284676)
			(xy 172.057042 -31.282639) (xy 172.112479 -31.288739) (xy 172.166436 -31.302845) (xy 172.217765 -31.324657)
			(xy 172.265371 -31.353711) (xy 172.308239 -31.389386) (xy 172.345456 -31.430923) (xy 172.376229 -31.477436)
			(xy 172.399901 -31.527933) (xy 172.415969 -31.58134) (xy 172.424089 -31.636516) (xy 172.424598 -31.664402)
			(xy 172.424089 -31.692288) (xy 172.415969 -31.747464) (xy 172.407029 -31.777178) (xy 172.926246 -31.777178)
			(xy 172.930317 -31.721556) (xy 172.942443 -31.667119) (xy 172.962366 -31.615028) (xy 172.989662 -31.566393)
			(xy 173.023748 -31.52225) (xy 173.063897 -31.483541) (xy 173.109255 -31.45109) (xy 173.158855 -31.425589)
			(xy 173.211639 -31.407582) (xy 173.266482 -31.397452) (xy 173.322216 -31.395415) (xy 173.377653 -31.401515)
			(xy 173.43161 -31.415621) (xy 173.482939 -31.437433) (xy 173.530545 -31.466487) (xy 173.573413 -31.502162)
			(xy 173.61063 -31.543699) (xy 173.641403 -31.590212) (xy 173.665075 -31.640709) (xy 173.681143 -31.694116)
			(xy 173.689263 -31.749292) (xy 173.689772 -31.777178) (xy 173.689263 -31.805064) (xy 173.681143 -31.86024)
			(xy 173.665075 -31.913647) (xy 173.641403 -31.964144) (xy 173.61063 -32.010657) (xy 173.573413 -32.052194)
			(xy 173.530545 -32.087869) (xy 173.482939 -32.116923) (xy 173.43161 -32.138735) (xy 173.377653 -32.152841)
			(xy 173.322216 -32.158941) (xy 173.266482 -32.156904) (xy 173.211639 -32.146774) (xy 173.158855 -32.128767)
			(xy 173.109255 -32.103266) (xy 173.063897 -32.070815) (xy 173.023748 -32.032106) (xy 172.989662 -31.987963)
			(xy 172.962366 -31.939328) (xy 172.942443 -31.887237) (xy 172.930317 -31.8328) (xy 172.926246 -31.777178)
			(xy 172.407029 -31.777178) (xy 172.399901 -31.800871) (xy 172.376229 -31.851368) (xy 172.345456 -31.897881)
			(xy 172.308239 -31.939418) (xy 172.265371 -31.975093) (xy 172.217765 -32.004147) (xy 172.166436 -32.025959)
			(xy 172.112479 -32.040065) (xy 172.057042 -32.046165) (xy 172.001308 -32.044128) (xy 171.946465 -32.033998)
			(xy 171.893681 -32.015991) (xy 171.844081 -31.99049) (xy 171.798723 -31.958039) (xy 171.758574 -31.91933)
			(xy 171.724488 -31.875187) (xy 171.697192 -31.826552) (xy 171.677269 -31.774461) (xy 171.665143 -31.720024)
			(xy 171.661072 -31.664402) (xy 171.144531 -31.664402) (xy 171.148501 -31.69138) (xy 171.14901 -31.719266)
			(xy 171.148501 -31.747152) (xy 171.140381 -31.802328) (xy 171.124313 -31.855735) (xy 171.100641 -31.906232)
			(xy 171.069868 -31.952745) (xy 171.032651 -31.994282) (xy 170.989783 -32.029957) (xy 170.942177 -32.059011)
			(xy 170.890848 -32.080823) (xy 170.836891 -32.094929) (xy 170.781454 -32.101029) (xy 170.72572 -32.098992)
			(xy 170.670877 -32.088862) (xy 170.618093 -32.070855) (xy 170.568493 -32.045354) (xy 170.523135 -32.012903)
			(xy 170.482986 -31.974194) (xy 170.4489 -31.930051) (xy 170.421604 -31.881416) (xy 170.401681 -31.829325)
			(xy 170.389555 -31.774888) (xy 170.385484 -31.719266) (xy 169.830557 -31.719266) (xy 169.813877 -31.754848)
			(xy 169.783104 -31.801361) (xy 169.745887 -31.842898) (xy 169.703019 -31.878573) (xy 169.655413 -31.907627)
			(xy 169.604084 -31.929439) (xy 169.550127 -31.943545) (xy 169.49469 -31.949645) (xy 169.438956 -31.947608)
			(xy 169.384113 -31.937478) (xy 169.331329 -31.919471) (xy 169.281729 -31.89397) (xy 169.236371 -31.861519)
			(xy 169.196222 -31.82281) (xy 169.162136 -31.778667) (xy 169.13484 -31.730032) (xy 169.114917 -31.677941)
			(xy 169.102791 -31.623504) (xy 169.09872 -31.567882) (xy 161.764702 -31.567882) (xy 161.786295 -31.596022)
			(xy 161.816262 -31.647928) (xy 161.839198 -31.703301) (xy 161.854711 -31.761194) (xy 161.862534 -31.820616)
			(xy 161.863024 -31.850584) (xy 161.863024 -32.714184) (xy 161.862891 -32.722312) (xy 176.706784 -32.722312)
			(xy 176.706784 -31.858712) (xy 176.707274 -31.828728) (xy 176.715102 -31.769272) (xy 176.730623 -31.711347)
			(xy 176.753572 -31.655943) (xy 176.783556 -31.604009) (xy 176.820062 -31.556433) (xy 176.862467 -31.514028)
			(xy 176.910043 -31.477522) (xy 176.961977 -31.447538) (xy 177.017381 -31.424589) (xy 177.075306 -31.409068)
			(xy 177.134762 -31.40124) (xy 177.19473 -31.40124) (xy 177.254186 -31.409068) (xy 177.312111 -31.424589)
			(xy 177.367515 -31.447538) (xy 177.419449 -31.477522) (xy 177.467025 -31.514028) (xy 177.50943 -31.556433)
			(xy 177.545936 -31.604009) (xy 177.57592 -31.655943) (xy 177.598869 -31.711347) (xy 177.61439 -31.769272)
			(xy 177.622218 -31.828728) (xy 177.622708 -31.858712) (xy 177.622708 -32.714184) (xy 186.947556 -32.714184)
			(xy 186.947556 -31.850584) (xy 186.948046 -31.820616) (xy 186.955869 -31.761194) (xy 186.971382 -31.703301)
			(xy 186.994318 -31.647928) (xy 187.024285 -31.596022) (xy 187.060772 -31.548472) (xy 187.103152 -31.506092)
			(xy 187.150702 -31.469605) (xy 187.202608 -31.439638) (xy 187.257981 -31.416702) (xy 187.315874 -31.401189)
			(xy 187.375296 -31.393366) (xy 187.435232 -31.393366) (xy 187.494654 -31.401189) (xy 187.552547 -31.416702)
			(xy 187.60792 -31.439638) (xy 187.659826 -31.469605) (xy 187.707376 -31.506092) (xy 187.749756 -31.548472)
			(xy 187.76465 -31.567882) (xy 195.098668 -31.567882) (xy 195.102739 -31.51226) (xy 195.114865 -31.457823)
			(xy 195.134788 -31.405732) (xy 195.162084 -31.357097) (xy 195.19617 -31.312954) (xy 195.236319 -31.274245)
			(xy 195.281677 -31.241794) (xy 195.331277 -31.216293) (xy 195.384061 -31.198286) (xy 195.438904 -31.188156)
			(xy 195.494638 -31.186119) (xy 195.550075 -31.192219) (xy 195.604032 -31.206325) (xy 195.655361 -31.228137)
			(xy 195.702967 -31.257191) (xy 195.745835 -31.292866) (xy 195.783052 -31.334403) (xy 195.813825 -31.380916)
			(xy 195.837497 -31.431413) (xy 195.853565 -31.48482) (xy 195.861685 -31.539996) (xy 195.862194 -31.567882)
			(xy 195.861685 -31.595768) (xy 195.853565 -31.650944) (xy 195.837497 -31.704351) (xy 195.830505 -31.719266)
			(xy 196.385432 -31.719266) (xy 196.389503 -31.663644) (xy 196.401629 -31.609207) (xy 196.421552 -31.557116)
			(xy 196.448848 -31.508481) (xy 196.482934 -31.464338) (xy 196.523083 -31.425629) (xy 196.568441 -31.393178)
			(xy 196.618041 -31.367677) (xy 196.670825 -31.34967) (xy 196.725668 -31.33954) (xy 196.781402 -31.337503)
			(xy 196.836839 -31.343603) (xy 196.890796 -31.357709) (xy 196.942125 -31.379521) (xy 196.989731 -31.408575)
			(xy 197.032599 -31.44425) (xy 197.069816 -31.485787) (xy 197.100589 -31.5323) (xy 197.124261 -31.582797)
			(xy 197.140329 -31.636204) (xy 197.144479 -31.664402) (xy 197.66102 -31.664402) (xy 197.665091 -31.60878)
			(xy 197.677217 -31.554343) (xy 197.69714 -31.502252) (xy 197.724436 -31.453617) (xy 197.758522 -31.409474)
			(xy 197.798671 -31.370765) (xy 197.844029 -31.338314) (xy 197.893629 -31.312813) (xy 197.946413 -31.294806)
			(xy 198.001256 -31.284676) (xy 198.05699 -31.282639) (xy 198.112427 -31.288739) (xy 198.166384 -31.302845)
			(xy 198.217713 -31.324657) (xy 198.265319 -31.353711) (xy 198.308187 -31.389386) (xy 198.345404 -31.430923)
			(xy 198.376177 -31.477436) (xy 198.399849 -31.527933) (xy 198.415917 -31.58134) (xy 198.424037 -31.636516)
			(xy 198.424546 -31.664402) (xy 198.424037 -31.692288) (xy 198.415917 -31.747464) (xy 198.406977 -31.777178)
			(xy 198.926194 -31.777178) (xy 198.930265 -31.721556) (xy 198.942391 -31.667119) (xy 198.962314 -31.615028)
			(xy 198.98961 -31.566393) (xy 199.023696 -31.52225) (xy 199.063845 -31.483541) (xy 199.109203 -31.45109)
			(xy 199.158803 -31.425589) (xy 199.211587 -31.407582) (xy 199.26643 -31.397452) (xy 199.322164 -31.395415)
			(xy 199.377601 -31.401515) (xy 199.431558 -31.415621) (xy 199.482887 -31.437433) (xy 199.530493 -31.466487)
			(xy 199.573361 -31.502162) (xy 199.610578 -31.543699) (xy 199.641351 -31.590212) (xy 199.665023 -31.640709)
			(xy 199.681091 -31.694116) (xy 199.689211 -31.749292) (xy 199.68972 -31.777178) (xy 199.689211 -31.805064)
			(xy 199.681091 -31.86024) (xy 199.665023 -31.913647) (xy 199.641351 -31.964144) (xy 199.610578 -32.010657)
			(xy 199.573361 -32.052194) (xy 199.530493 -32.087869) (xy 199.482887 -32.116923) (xy 199.431558 -32.138735)
			(xy 199.377601 -32.152841) (xy 199.322164 -32.158941) (xy 199.26643 -32.156904) (xy 199.211587 -32.146774)
			(xy 199.158803 -32.128767) (xy 199.109203 -32.103266) (xy 199.063845 -32.070815) (xy 199.023696 -32.032106)
			(xy 198.98961 -31.987963) (xy 198.962314 -31.939328) (xy 198.942391 -31.887237) (xy 198.930265 -31.8328)
			(xy 198.926194 -31.777178) (xy 198.406977 -31.777178) (xy 198.399849 -31.800871) (xy 198.376177 -31.851368)
			(xy 198.345404 -31.897881) (xy 198.308187 -31.939418) (xy 198.265319 -31.975093) (xy 198.217713 -32.004147)
			(xy 198.166384 -32.025959) (xy 198.112427 -32.040065) (xy 198.05699 -32.046165) (xy 198.001256 -32.044128)
			(xy 197.946413 -32.033998) (xy 197.893629 -32.015991) (xy 197.844029 -31.99049) (xy 197.798671 -31.958039)
			(xy 197.758522 -31.91933) (xy 197.724436 -31.875187) (xy 197.69714 -31.826552) (xy 197.677217 -31.774461)
			(xy 197.665091 -31.720024) (xy 197.66102 -31.664402) (xy 197.144479 -31.664402) (xy 197.148449 -31.69138)
			(xy 197.148958 -31.719266) (xy 197.148449 -31.747152) (xy 197.140329 -31.802328) (xy 197.124261 -31.855735)
			(xy 197.100589 -31.906232) (xy 197.069816 -31.952745) (xy 197.032599 -31.994282) (xy 196.989731 -32.029957)
			(xy 196.942125 -32.059011) (xy 196.890796 -32.080823) (xy 196.836839 -32.094929) (xy 196.781402 -32.101029)
			(xy 196.725668 -32.098992) (xy 196.670825 -32.088862) (xy 196.618041 -32.070855) (xy 196.568441 -32.045354)
			(xy 196.523083 -32.012903) (xy 196.482934 -31.974194) (xy 196.448848 -31.930051) (xy 196.421552 -31.881416)
			(xy 196.401629 -31.829325) (xy 196.389503 -31.774888) (xy 196.385432 -31.719266) (xy 195.830505 -31.719266)
			(xy 195.813825 -31.754848) (xy 195.783052 -31.801361) (xy 195.745835 -31.842898) (xy 195.702967 -31.878573)
			(xy 195.655361 -31.907627) (xy 195.604032 -31.929439) (xy 195.550075 -31.943545) (xy 195.494638 -31.949645)
			(xy 195.438904 -31.947608) (xy 195.384061 -31.937478) (xy 195.331277 -31.919471) (xy 195.281677 -31.89397)
			(xy 195.236319 -31.861519) (xy 195.19617 -31.82281) (xy 195.162084 -31.778667) (xy 195.134788 -31.730032)
			(xy 195.114865 -31.677941) (xy 195.102739 -31.623504) (xy 195.098668 -31.567882) (xy 187.76465 -31.567882)
			(xy 187.786243 -31.596022) (xy 187.81621 -31.647928) (xy 187.839146 -31.703301) (xy 187.854659 -31.761194)
			(xy 187.862482 -31.820616) (xy 187.862972 -31.850584) (xy 187.862972 -32.714184) (xy 187.862839 -32.722312)
			(xy 202.706732 -32.722312) (xy 202.706732 -31.858712) (xy 202.707222 -31.828728) (xy 202.71505 -31.769272)
			(xy 202.730571 -31.711347) (xy 202.75352 -31.655943) (xy 202.783504 -31.604009) (xy 202.82001 -31.556433)
			(xy 202.862415 -31.514028) (xy 202.909991 -31.477522) (xy 202.961925 -31.447538) (xy 203.017329 -31.424589)
			(xy 203.075254 -31.409068) (xy 203.13471 -31.40124) (xy 203.194678 -31.40124) (xy 203.254134 -31.409068)
			(xy 203.312059 -31.424589) (xy 203.367463 -31.447538) (xy 203.419397 -31.477522) (xy 203.466973 -31.514028)
			(xy 203.509378 -31.556433) (xy 203.545884 -31.604009) (xy 203.575868 -31.655943) (xy 203.598817 -31.711347)
			(xy 203.614338 -31.769272) (xy 203.622166 -31.828728) (xy 203.622656 -31.858712) (xy 203.622656 -32.714184)
			(xy 212.947504 -32.714184) (xy 212.947504 -31.850584) (xy 212.947994 -31.820616) (xy 212.955817 -31.761194)
			(xy 212.97133 -31.703301) (xy 212.994266 -31.647928) (xy 213.024233 -31.596022) (xy 213.06072 -31.548472)
			(xy 213.1031 -31.506092) (xy 213.15065 -31.469605) (xy 213.202556 -31.439638) (xy 213.257929 -31.416702)
			(xy 213.315822 -31.401189) (xy 213.375244 -31.393366) (xy 213.43518 -31.393366) (xy 213.494602 -31.401189)
			(xy 213.552495 -31.416702) (xy 213.607868 -31.439638) (xy 213.659774 -31.469605) (xy 213.707324 -31.506092)
			(xy 213.749704 -31.548472) (xy 213.764598 -31.567882) (xy 233.198668 -31.567882) (xy 233.202739 -31.51226)
			(xy 233.214865 -31.457823) (xy 233.234788 -31.405732) (xy 233.262084 -31.357097) (xy 233.29617 -31.312954)
			(xy 233.336319 -31.274245) (xy 233.381677 -31.241794) (xy 233.431277 -31.216293) (xy 233.484061 -31.198286)
			(xy 233.538904 -31.188156) (xy 233.594638 -31.186119) (xy 233.650075 -31.192219) (xy 233.704032 -31.206325)
			(xy 233.755361 -31.228137) (xy 233.802967 -31.257191) (xy 233.845835 -31.292866) (xy 233.883052 -31.334403)
			(xy 233.913825 -31.380916) (xy 233.937497 -31.431413) (xy 233.953565 -31.48482) (xy 233.961685 -31.539996)
			(xy 233.962194 -31.567882) (xy 233.961685 -31.595768) (xy 233.953565 -31.650944) (xy 233.937497 -31.704351)
			(xy 233.930505 -31.719266) (xy 234.485432 -31.719266) (xy 234.489503 -31.663644) (xy 234.501629 -31.609207)
			(xy 234.521552 -31.557116) (xy 234.548848 -31.508481) (xy 234.582934 -31.464338) (xy 234.623083 -31.425629)
			(xy 234.668441 -31.393178) (xy 234.718041 -31.367677) (xy 234.770825 -31.34967) (xy 234.825668 -31.33954)
			(xy 234.881402 -31.337503) (xy 234.936839 -31.343603) (xy 234.990796 -31.357709) (xy 235.042125 -31.379521)
			(xy 235.089731 -31.408575) (xy 235.132599 -31.44425) (xy 235.169816 -31.485787) (xy 235.200589 -31.5323)
			(xy 235.224261 -31.582797) (xy 235.240329 -31.636204) (xy 235.244479 -31.664402) (xy 235.76102 -31.664402)
			(xy 235.765091 -31.60878) (xy 235.777217 -31.554343) (xy 235.79714 -31.502252) (xy 235.824436 -31.453617)
			(xy 235.858522 -31.409474) (xy 235.898671 -31.370765) (xy 235.944029 -31.338314) (xy 235.993629 -31.312813)
			(xy 236.046413 -31.294806) (xy 236.101256 -31.284676) (xy 236.15699 -31.282639) (xy 236.212427 -31.288739)
			(xy 236.266384 -31.302845) (xy 236.317713 -31.324657) (xy 236.365319 -31.353711) (xy 236.408187 -31.389386)
			(xy 236.445404 -31.430923) (xy 236.476177 -31.477436) (xy 236.499849 -31.527933) (xy 236.515917 -31.58134)
			(xy 236.524037 -31.636516) (xy 236.524546 -31.664402) (xy 236.524037 -31.692288) (xy 236.515917 -31.747464)
			(xy 236.506977 -31.777178) (xy 237.026194 -31.777178) (xy 237.030265 -31.721556) (xy 237.042391 -31.667119)
			(xy 237.062314 -31.615028) (xy 237.08961 -31.566393) (xy 237.123696 -31.52225) (xy 237.163845 -31.483541)
			(xy 237.209203 -31.45109) (xy 237.258803 -31.425589) (xy 237.311587 -31.407582) (xy 237.36643 -31.397452)
			(xy 237.422164 -31.395415) (xy 237.477601 -31.401515) (xy 237.531558 -31.415621) (xy 237.582887 -31.437433)
			(xy 237.630493 -31.466487) (xy 237.673361 -31.502162) (xy 237.710578 -31.543699) (xy 237.741351 -31.590212)
			(xy 237.765023 -31.640709) (xy 237.781091 -31.694116) (xy 237.789211 -31.749292) (xy 237.78972 -31.777178)
			(xy 237.789211 -31.805064) (xy 237.781091 -31.86024) (xy 237.765023 -31.913647) (xy 237.741351 -31.964144)
			(xy 237.710578 -32.010657) (xy 237.673361 -32.052194) (xy 237.630493 -32.087869) (xy 237.582887 -32.116923)
			(xy 237.531558 -32.138735) (xy 237.477601 -32.152841) (xy 237.422164 -32.158941) (xy 237.36643 -32.156904)
			(xy 237.311587 -32.146774) (xy 237.258803 -32.128767) (xy 237.209203 -32.103266) (xy 237.163845 -32.070815)
			(xy 237.123696 -32.032106) (xy 237.08961 -31.987963) (xy 237.062314 -31.939328) (xy 237.042391 -31.887237)
			(xy 237.030265 -31.8328) (xy 237.026194 -31.777178) (xy 236.506977 -31.777178) (xy 236.499849 -31.800871)
			(xy 236.476177 -31.851368) (xy 236.445404 -31.897881) (xy 236.408187 -31.939418) (xy 236.365319 -31.975093)
			(xy 236.317713 -32.004147) (xy 236.266384 -32.025959) (xy 236.212427 -32.040065) (xy 236.15699 -32.046165)
			(xy 236.101256 -32.044128) (xy 236.046413 -32.033998) (xy 235.993629 -32.015991) (xy 235.944029 -31.99049)
			(xy 235.898671 -31.958039) (xy 235.858522 -31.91933) (xy 235.824436 -31.875187) (xy 235.79714 -31.826552)
			(xy 235.777217 -31.774461) (xy 235.765091 -31.720024) (xy 235.76102 -31.664402) (xy 235.244479 -31.664402)
			(xy 235.248449 -31.69138) (xy 235.248958 -31.719266) (xy 235.248449 -31.747152) (xy 235.240329 -31.802328)
			(xy 235.224261 -31.855735) (xy 235.200589 -31.906232) (xy 235.169816 -31.952745) (xy 235.132599 -31.994282)
			(xy 235.089731 -32.029957) (xy 235.042125 -32.059011) (xy 234.990796 -32.080823) (xy 234.936839 -32.094929)
			(xy 234.881402 -32.101029) (xy 234.825668 -32.098992) (xy 234.770825 -32.088862) (xy 234.718041 -32.070855)
			(xy 234.668441 -32.045354) (xy 234.623083 -32.012903) (xy 234.582934 -31.974194) (xy 234.548848 -31.930051)
			(xy 234.521552 -31.881416) (xy 234.501629 -31.829325) (xy 234.489503 -31.774888) (xy 234.485432 -31.719266)
			(xy 233.930505 -31.719266) (xy 233.913825 -31.754848) (xy 233.883052 -31.801361) (xy 233.845835 -31.842898)
			(xy 233.802967 -31.878573) (xy 233.755361 -31.907627) (xy 233.704032 -31.929439) (xy 233.650075 -31.943545)
			(xy 233.594638 -31.949645) (xy 233.538904 -31.947608) (xy 233.484061 -31.937478) (xy 233.431277 -31.919471)
			(xy 233.381677 -31.89397) (xy 233.336319 -31.861519) (xy 233.29617 -31.82281) (xy 233.262084 -31.778667)
			(xy 233.234788 -31.730032) (xy 233.214865 -31.677941) (xy 233.202739 -31.623504) (xy 233.198668 -31.567882)
			(xy 213.764598 -31.567882) (xy 213.786191 -31.596022) (xy 213.816158 -31.647928) (xy 213.839094 -31.703301)
			(xy 213.854607 -31.761194) (xy 213.86243 -31.820616) (xy 213.86292 -31.850584) (xy 213.86292 -32.714184)
			(xy 213.862787 -32.722312) (xy 240.806732 -32.722312) (xy 240.806732 -31.858712) (xy 240.807222 -31.828728)
			(xy 240.81505 -31.769272) (xy 240.830571 -31.711347) (xy 240.85352 -31.655943) (xy 240.883504 -31.604009)
			(xy 240.92001 -31.556433) (xy 240.962415 -31.514028) (xy 241.009991 -31.477522) (xy 241.061925 -31.447538)
			(xy 241.117329 -31.424589) (xy 241.175254 -31.409068) (xy 241.23471 -31.40124) (xy 241.294678 -31.40124)
			(xy 241.354134 -31.409068) (xy 241.412059 -31.424589) (xy 241.467463 -31.447538) (xy 241.519397 -31.477522)
			(xy 241.566973 -31.514028) (xy 241.609378 -31.556433) (xy 241.645884 -31.604009) (xy 241.675868 -31.655943)
			(xy 241.698817 -31.711347) (xy 241.714338 -31.769272) (xy 241.722166 -31.828728) (xy 241.722656 -31.858712)
			(xy 241.722656 -32.714184) (xy 251.047504 -32.714184) (xy 251.047504 -31.850584) (xy 251.047994 -31.820616)
			(xy 251.055817 -31.761194) (xy 251.07133 -31.703301) (xy 251.094266 -31.647928) (xy 251.124233 -31.596022)
			(xy 251.16072 -31.548472) (xy 251.2031 -31.506092) (xy 251.25065 -31.469605) (xy 251.302556 -31.439638)
			(xy 251.357929 -31.416702) (xy 251.415822 -31.401189) (xy 251.475244 -31.393366) (xy 251.53518 -31.393366)
			(xy 251.594602 -31.401189) (xy 251.652495 -31.416702) (xy 251.707868 -31.439638) (xy 251.759774 -31.469605)
			(xy 251.807324 -31.506092) (xy 251.849704 -31.548472) (xy 251.864598 -31.567882) (xy 259.198616 -31.567882)
			(xy 259.202687 -31.51226) (xy 259.214813 -31.457823) (xy 259.234736 -31.405732) (xy 259.262032 -31.357097)
			(xy 259.296118 -31.312954) (xy 259.336267 -31.274245) (xy 259.381625 -31.241794) (xy 259.431225 -31.216293)
			(xy 259.484009 -31.198286) (xy 259.538852 -31.188156) (xy 259.594586 -31.186119) (xy 259.650023 -31.192219)
			(xy 259.70398 -31.206325) (xy 259.755309 -31.228137) (xy 259.802915 -31.257191) (xy 259.845783 -31.292866)
			(xy 259.883 -31.334403) (xy 259.913773 -31.380916) (xy 259.937445 -31.431413) (xy 259.953513 -31.48482)
			(xy 259.961633 -31.539996) (xy 259.962142 -31.567882) (xy 259.961633 -31.595768) (xy 259.953513 -31.650944)
			(xy 259.937445 -31.704351) (xy 259.930453 -31.719266) (xy 260.48538 -31.719266) (xy 260.489451 -31.663644)
			(xy 260.501577 -31.609207) (xy 260.5215 -31.557116) (xy 260.548796 -31.508481) (xy 260.582882 -31.464338)
			(xy 260.623031 -31.425629) (xy 260.668389 -31.393178) (xy 260.717989 -31.367677) (xy 260.770773 -31.34967)
			(xy 260.825616 -31.33954) (xy 260.88135 -31.337503) (xy 260.936787 -31.343603) (xy 260.990744 -31.357709)
			(xy 261.042073 -31.379521) (xy 261.089679 -31.408575) (xy 261.132547 -31.44425) (xy 261.169764 -31.485787)
			(xy 261.200537 -31.5323) (xy 261.224209 -31.582797) (xy 261.240277 -31.636204) (xy 261.244427 -31.664402)
			(xy 261.760968 -31.664402) (xy 261.765039 -31.60878) (xy 261.777165 -31.554343) (xy 261.797088 -31.502252)
			(xy 261.824384 -31.453617) (xy 261.85847 -31.409474) (xy 261.898619 -31.370765) (xy 261.943977 -31.338314)
			(xy 261.993577 -31.312813) (xy 262.046361 -31.294806) (xy 262.101204 -31.284676) (xy 262.156938 -31.282639)
			(xy 262.212375 -31.288739) (xy 262.266332 -31.302845) (xy 262.317661 -31.324657) (xy 262.365267 -31.353711)
			(xy 262.408135 -31.389386) (xy 262.445352 -31.430923) (xy 262.476125 -31.477436) (xy 262.499797 -31.527933)
			(xy 262.515865 -31.58134) (xy 262.523985 -31.636516) (xy 262.524494 -31.664402) (xy 262.523985 -31.692288)
			(xy 262.515865 -31.747464) (xy 262.506925 -31.777178) (xy 263.026142 -31.777178) (xy 263.030213 -31.721556)
			(xy 263.042339 -31.667119) (xy 263.062262 -31.615028) (xy 263.089558 -31.566393) (xy 263.123644 -31.52225)
			(xy 263.163793 -31.483541) (xy 263.209151 -31.45109) (xy 263.258751 -31.425589) (xy 263.311535 -31.407582)
			(xy 263.366378 -31.397452) (xy 263.422112 -31.395415) (xy 263.477549 -31.401515) (xy 263.531506 -31.415621)
			(xy 263.582835 -31.437433) (xy 263.630441 -31.466487) (xy 263.673309 -31.502162) (xy 263.710526 -31.543699)
			(xy 263.741299 -31.590212) (xy 263.764971 -31.640709) (xy 263.781039 -31.694116) (xy 263.789159 -31.749292)
			(xy 263.789668 -31.777178) (xy 263.789159 -31.805064) (xy 263.781039 -31.86024) (xy 263.764971 -31.913647)
			(xy 263.741299 -31.964144) (xy 263.710526 -32.010657) (xy 263.673309 -32.052194) (xy 263.630441 -32.087869)
			(xy 263.582835 -32.116923) (xy 263.531506 -32.138735) (xy 263.477549 -32.152841) (xy 263.422112 -32.158941)
			(xy 263.366378 -32.156904) (xy 263.311535 -32.146774) (xy 263.258751 -32.128767) (xy 263.209151 -32.103266)
			(xy 263.163793 -32.070815) (xy 263.123644 -32.032106) (xy 263.089558 -31.987963) (xy 263.062262 -31.939328)
			(xy 263.042339 -31.887237) (xy 263.030213 -31.8328) (xy 263.026142 -31.777178) (xy 262.506925 -31.777178)
			(xy 262.499797 -31.800871) (xy 262.476125 -31.851368) (xy 262.445352 -31.897881) (xy 262.408135 -31.939418)
			(xy 262.365267 -31.975093) (xy 262.317661 -32.004147) (xy 262.266332 -32.025959) (xy 262.212375 -32.040065)
			(xy 262.156938 -32.046165) (xy 262.101204 -32.044128) (xy 262.046361 -32.033998) (xy 261.993577 -32.015991)
			(xy 261.943977 -31.99049) (xy 261.898619 -31.958039) (xy 261.85847 -31.91933) (xy 261.824384 -31.875187)
			(xy 261.797088 -31.826552) (xy 261.777165 -31.774461) (xy 261.765039 -31.720024) (xy 261.760968 -31.664402)
			(xy 261.244427 -31.664402) (xy 261.248397 -31.69138) (xy 261.248906 -31.719266) (xy 261.248397 -31.747152)
			(xy 261.240277 -31.802328) (xy 261.224209 -31.855735) (xy 261.200537 -31.906232) (xy 261.169764 -31.952745)
			(xy 261.132547 -31.994282) (xy 261.089679 -32.029957) (xy 261.042073 -32.059011) (xy 260.990744 -32.080823)
			(xy 260.936787 -32.094929) (xy 260.88135 -32.101029) (xy 260.825616 -32.098992) (xy 260.770773 -32.088862)
			(xy 260.717989 -32.070855) (xy 260.668389 -32.045354) (xy 260.623031 -32.012903) (xy 260.582882 -31.974194)
			(xy 260.548796 -31.930051) (xy 260.5215 -31.881416) (xy 260.501577 -31.829325) (xy 260.489451 -31.774888)
			(xy 260.48538 -31.719266) (xy 259.930453 -31.719266) (xy 259.913773 -31.754848) (xy 259.883 -31.801361)
			(xy 259.845783 -31.842898) (xy 259.802915 -31.878573) (xy 259.755309 -31.907627) (xy 259.70398 -31.929439)
			(xy 259.650023 -31.943545) (xy 259.594586 -31.949645) (xy 259.538852 -31.947608) (xy 259.484009 -31.937478)
			(xy 259.431225 -31.919471) (xy 259.381625 -31.89397) (xy 259.336267 -31.861519) (xy 259.296118 -31.82281)
			(xy 259.262032 -31.778667) (xy 259.234736 -31.730032) (xy 259.214813 -31.677941) (xy 259.202687 -31.623504)
			(xy 259.198616 -31.567882) (xy 251.864598 -31.567882) (xy 251.886191 -31.596022) (xy 251.916158 -31.647928)
			(xy 251.939094 -31.703301) (xy 251.954607 -31.761194) (xy 251.96243 -31.820616) (xy 251.96292 -31.850584)
			(xy 251.96292 -32.714184) (xy 251.962787 -32.722312) (xy 266.80668 -32.722312) (xy 266.80668 -31.858712)
			(xy 266.80717 -31.828728) (xy 266.814998 -31.769272) (xy 266.830519 -31.711347) (xy 266.853468 -31.655943)
			(xy 266.883452 -31.604009) (xy 266.919958 -31.556433) (xy 266.962363 -31.514028) (xy 267.009939 -31.477522)
			(xy 267.061873 -31.447538) (xy 267.117277 -31.424589) (xy 267.175202 -31.409068) (xy 267.234658 -31.40124)
			(xy 267.294626 -31.40124) (xy 267.354082 -31.409068) (xy 267.412007 -31.424589) (xy 267.467411 -31.447538)
			(xy 267.519345 -31.477522) (xy 267.566921 -31.514028) (xy 267.609326 -31.556433) (xy 267.645832 -31.604009)
			(xy 267.675816 -31.655943) (xy 267.698765 -31.711347) (xy 267.714286 -31.769272) (xy 267.722114 -31.828728)
			(xy 267.722604 -31.858712) (xy 267.722604 -32.714184) (xy 277.047452 -32.714184) (xy 277.047452 -31.850584)
			(xy 277.047942 -31.820616) (xy 277.055765 -31.761194) (xy 277.071278 -31.703301) (xy 277.094214 -31.647928)
			(xy 277.124181 -31.596022) (xy 277.160668 -31.548472) (xy 277.203048 -31.506092) (xy 277.250598 -31.469605)
			(xy 277.302504 -31.439638) (xy 277.357877 -31.416702) (xy 277.41577 -31.401189) (xy 277.475192 -31.393366)
			(xy 277.535128 -31.393366) (xy 277.59455 -31.401189) (xy 277.652443 -31.416702) (xy 277.707816 -31.439638)
			(xy 277.759722 -31.469605) (xy 277.807272 -31.506092) (xy 277.849652 -31.548472) (xy 277.864546 -31.567882)
			(xy 285.198564 -31.567882) (xy 285.202635 -31.51226) (xy 285.214761 -31.457823) (xy 285.234684 -31.405732)
			(xy 285.26198 -31.357097) (xy 285.296066 -31.312954) (xy 285.336215 -31.274245) (xy 285.381573 -31.241794)
			(xy 285.431173 -31.216293) (xy 285.483957 -31.198286) (xy 285.5388 -31.188156) (xy 285.594534 -31.186119)
			(xy 285.649971 -31.192219) (xy 285.703928 -31.206325) (xy 285.755257 -31.228137) (xy 285.802863 -31.257191)
			(xy 285.845731 -31.292866) (xy 285.882948 -31.334403) (xy 285.913721 -31.380916) (xy 285.937393 -31.431413)
			(xy 285.953461 -31.48482) (xy 285.961581 -31.539996) (xy 285.96209 -31.567882) (xy 285.961581 -31.595768)
			(xy 285.953461 -31.650944) (xy 285.937393 -31.704351) (xy 285.930401 -31.719266) (xy 286.485328 -31.719266)
			(xy 286.489399 -31.663644) (xy 286.501525 -31.609207) (xy 286.521448 -31.557116) (xy 286.548744 -31.508481)
			(xy 286.58283 -31.464338) (xy 286.622979 -31.425629) (xy 286.668337 -31.393178) (xy 286.717937 -31.367677)
			(xy 286.770721 -31.34967) (xy 286.825564 -31.33954) (xy 286.881298 -31.337503) (xy 286.936735 -31.343603)
			(xy 286.990692 -31.357709) (xy 287.042021 -31.379521) (xy 287.089627 -31.408575) (xy 287.132495 -31.44425)
			(xy 287.169712 -31.485787) (xy 287.200485 -31.5323) (xy 287.224157 -31.582797) (xy 287.240225 -31.636204)
			(xy 287.244375 -31.664402) (xy 287.760916 -31.664402) (xy 287.764987 -31.60878) (xy 287.777113 -31.554343)
			(xy 287.797036 -31.502252) (xy 287.824332 -31.453617) (xy 287.858418 -31.409474) (xy 287.898567 -31.370765)
			(xy 287.943925 -31.338314) (xy 287.993525 -31.312813) (xy 288.046309 -31.294806) (xy 288.101152 -31.284676)
			(xy 288.156886 -31.282639) (xy 288.212323 -31.288739) (xy 288.26628 -31.302845) (xy 288.317609 -31.324657)
			(xy 288.365215 -31.353711) (xy 288.408083 -31.389386) (xy 288.4453 -31.430923) (xy 288.476073 -31.477436)
			(xy 288.499745 -31.527933) (xy 288.515813 -31.58134) (xy 288.523933 -31.636516) (xy 288.524442 -31.664402)
			(xy 288.523933 -31.692288) (xy 288.515813 -31.747464) (xy 288.506873 -31.777178) (xy 289.02609 -31.777178)
			(xy 289.030161 -31.721556) (xy 289.042287 -31.667119) (xy 289.06221 -31.615028) (xy 289.089506 -31.566393)
			(xy 289.123592 -31.52225) (xy 289.163741 -31.483541) (xy 289.209099 -31.45109) (xy 289.258699 -31.425589)
			(xy 289.311483 -31.407582) (xy 289.366326 -31.397452) (xy 289.42206 -31.395415) (xy 289.477497 -31.401515)
			(xy 289.531454 -31.415621) (xy 289.582783 -31.437433) (xy 289.630389 -31.466487) (xy 289.673257 -31.502162)
			(xy 289.710474 -31.543699) (xy 289.741247 -31.590212) (xy 289.764919 -31.640709) (xy 289.780987 -31.694116)
			(xy 289.789107 -31.749292) (xy 289.789616 -31.777178) (xy 289.789107 -31.805064) (xy 289.780987 -31.86024)
			(xy 289.764919 -31.913647) (xy 289.741247 -31.964144) (xy 289.710474 -32.010657) (xy 289.673257 -32.052194)
			(xy 289.630389 -32.087869) (xy 289.582783 -32.116923) (xy 289.531454 -32.138735) (xy 289.477497 -32.152841)
			(xy 289.42206 -32.158941) (xy 289.366326 -32.156904) (xy 289.311483 -32.146774) (xy 289.258699 -32.128767)
			(xy 289.209099 -32.103266) (xy 289.163741 -32.070815) (xy 289.123592 -32.032106) (xy 289.089506 -31.987963)
			(xy 289.06221 -31.939328) (xy 289.042287 -31.887237) (xy 289.030161 -31.8328) (xy 289.02609 -31.777178)
			(xy 288.506873 -31.777178) (xy 288.499745 -31.800871) (xy 288.476073 -31.851368) (xy 288.4453 -31.897881)
			(xy 288.408083 -31.939418) (xy 288.365215 -31.975093) (xy 288.317609 -32.004147) (xy 288.26628 -32.025959)
			(xy 288.212323 -32.040065) (xy 288.156886 -32.046165) (xy 288.101152 -32.044128) (xy 288.046309 -32.033998)
			(xy 287.993525 -32.015991) (xy 287.943925 -31.99049) (xy 287.898567 -31.958039) (xy 287.858418 -31.91933)
			(xy 287.824332 -31.875187) (xy 287.797036 -31.826552) (xy 287.777113 -31.774461) (xy 287.764987 -31.720024)
			(xy 287.760916 -31.664402) (xy 287.244375 -31.664402) (xy 287.248345 -31.69138) (xy 287.248854 -31.719266)
			(xy 287.248345 -31.747152) (xy 287.240225 -31.802328) (xy 287.224157 -31.855735) (xy 287.200485 -31.906232)
			(xy 287.169712 -31.952745) (xy 287.132495 -31.994282) (xy 287.089627 -32.029957) (xy 287.042021 -32.059011)
			(xy 286.990692 -32.080823) (xy 286.936735 -32.094929) (xy 286.881298 -32.101029) (xy 286.825564 -32.098992)
			(xy 286.770721 -32.088862) (xy 286.717937 -32.070855) (xy 286.668337 -32.045354) (xy 286.622979 -32.012903)
			(xy 286.58283 -31.974194) (xy 286.548744 -31.930051) (xy 286.521448 -31.881416) (xy 286.501525 -31.829325)
			(xy 286.489399 -31.774888) (xy 286.485328 -31.719266) (xy 285.930401 -31.719266) (xy 285.913721 -31.754848)
			(xy 285.882948 -31.801361) (xy 285.845731 -31.842898) (xy 285.802863 -31.878573) (xy 285.755257 -31.907627)
			(xy 285.703928 -31.929439) (xy 285.649971 -31.943545) (xy 285.594534 -31.949645) (xy 285.5388 -31.947608)
			(xy 285.483957 -31.937478) (xy 285.431173 -31.919471) (xy 285.381573 -31.89397) (xy 285.336215 -31.861519)
			(xy 285.296066 -31.82281) (xy 285.26198 -31.778667) (xy 285.234684 -31.730032) (xy 285.214761 -31.677941)
			(xy 285.202635 -31.623504) (xy 285.198564 -31.567882) (xy 277.864546 -31.567882) (xy 277.886139 -31.596022)
			(xy 277.916106 -31.647928) (xy 277.939042 -31.703301) (xy 277.954555 -31.761194) (xy 277.962378 -31.820616)
			(xy 277.962868 -31.850584) (xy 277.962868 -32.714184) (xy 277.962735 -32.722312) (xy 292.806628 -32.722312)
			(xy 292.806628 -31.858712) (xy 292.807118 -31.828728) (xy 292.814946 -31.769272) (xy 292.830467 -31.711347)
			(xy 292.853416 -31.655943) (xy 292.8834 -31.604009) (xy 292.919906 -31.556433) (xy 292.962311 -31.514028)
			(xy 293.009887 -31.477522) (xy 293.061821 -31.447538) (xy 293.117225 -31.424589) (xy 293.17515 -31.409068)
			(xy 293.234606 -31.40124) (xy 293.294574 -31.40124) (xy 293.35403 -31.409068) (xy 293.411955 -31.424589)
			(xy 293.467359 -31.447538) (xy 293.519293 -31.477522) (xy 293.566869 -31.514028) (xy 293.609274 -31.556433)
			(xy 293.64578 -31.604009) (xy 293.675764 -31.655943) (xy 293.698713 -31.711347) (xy 293.714234 -31.769272)
			(xy 293.722062 -31.828728) (xy 293.722552 -31.858712) (xy 293.722552 -32.714184) (xy 303.0474 -32.714184)
			(xy 303.0474 -31.850584) (xy 303.04789 -31.820616) (xy 303.055713 -31.761194) (xy 303.071226 -31.703301)
			(xy 303.094162 -31.647928) (xy 303.124129 -31.596022) (xy 303.160616 -31.548472) (xy 303.202996 -31.506092)
			(xy 303.250546 -31.469605) (xy 303.302452 -31.439638) (xy 303.357825 -31.416702) (xy 303.415718 -31.401189)
			(xy 303.47514 -31.393366) (xy 303.535076 -31.393366) (xy 303.594498 -31.401189) (xy 303.652391 -31.416702)
			(xy 303.707764 -31.439638) (xy 303.75967 -31.469605) (xy 303.80722 -31.506092) (xy 303.8496 -31.548472)
			(xy 303.864494 -31.567882) (xy 311.198512 -31.567882) (xy 311.202583 -31.51226) (xy 311.214709 -31.457823)
			(xy 311.234632 -31.405732) (xy 311.261928 -31.357097) (xy 311.296014 -31.312954) (xy 311.336163 -31.274245)
			(xy 311.381521 -31.241794) (xy 311.431121 -31.216293) (xy 311.483905 -31.198286) (xy 311.538748 -31.188156)
			(xy 311.594482 -31.186119) (xy 311.649919 -31.192219) (xy 311.703876 -31.206325) (xy 311.755205 -31.228137)
			(xy 311.802811 -31.257191) (xy 311.845679 -31.292866) (xy 311.882896 -31.334403) (xy 311.913669 -31.380916)
			(xy 311.937341 -31.431413) (xy 311.953409 -31.48482) (xy 311.961529 -31.539996) (xy 311.962038 -31.567882)
			(xy 311.961529 -31.595768) (xy 311.953409 -31.650944) (xy 311.937341 -31.704351) (xy 311.930349 -31.719266)
			(xy 312.485276 -31.719266) (xy 312.489347 -31.663644) (xy 312.501473 -31.609207) (xy 312.521396 -31.557116)
			(xy 312.548692 -31.508481) (xy 312.582778 -31.464338) (xy 312.622927 -31.425629) (xy 312.668285 -31.393178)
			(xy 312.717885 -31.367677) (xy 312.770669 -31.34967) (xy 312.825512 -31.33954) (xy 312.881246 -31.337503)
			(xy 312.936683 -31.343603) (xy 312.99064 -31.357709) (xy 313.041969 -31.379521) (xy 313.089575 -31.408575)
			(xy 313.132443 -31.44425) (xy 313.16966 -31.485787) (xy 313.200433 -31.5323) (xy 313.224105 -31.582797)
			(xy 313.240173 -31.636204) (xy 313.244323 -31.664402) (xy 313.760864 -31.664402) (xy 313.764935 -31.60878)
			(xy 313.777061 -31.554343) (xy 313.796984 -31.502252) (xy 313.82428 -31.453617) (xy 313.858366 -31.409474)
			(xy 313.898515 -31.370765) (xy 313.943873 -31.338314) (xy 313.993473 -31.312813) (xy 314.046257 -31.294806)
			(xy 314.1011 -31.284676) (xy 314.156834 -31.282639) (xy 314.212271 -31.288739) (xy 314.266228 -31.302845)
			(xy 314.317557 -31.324657) (xy 314.365163 -31.353711) (xy 314.408031 -31.389386) (xy 314.445248 -31.430923)
			(xy 314.476021 -31.477436) (xy 314.499693 -31.527933) (xy 314.515761 -31.58134) (xy 314.523881 -31.636516)
			(xy 314.52439 -31.664402) (xy 314.523881 -31.692288) (xy 314.515761 -31.747464) (xy 314.506821 -31.777178)
			(xy 315.026038 -31.777178) (xy 315.030109 -31.721556) (xy 315.042235 -31.667119) (xy 315.062158 -31.615028)
			(xy 315.089454 -31.566393) (xy 315.12354 -31.52225) (xy 315.163689 -31.483541) (xy 315.209047 -31.45109)
			(xy 315.258647 -31.425589) (xy 315.311431 -31.407582) (xy 315.366274 -31.397452) (xy 315.422008 -31.395415)
			(xy 315.477445 -31.401515) (xy 315.531402 -31.415621) (xy 315.582731 -31.437433) (xy 315.630337 -31.466487)
			(xy 315.673205 -31.502162) (xy 315.710422 -31.543699) (xy 315.741195 -31.590212) (xy 315.764867 -31.640709)
			(xy 315.780935 -31.694116) (xy 315.789055 -31.749292) (xy 315.789564 -31.777178) (xy 315.789055 -31.805064)
			(xy 315.780935 -31.86024) (xy 315.764867 -31.913647) (xy 315.741195 -31.964144) (xy 315.710422 -32.010657)
			(xy 315.673205 -32.052194) (xy 315.630337 -32.087869) (xy 315.582731 -32.116923) (xy 315.531402 -32.138735)
			(xy 315.477445 -32.152841) (xy 315.422008 -32.158941) (xy 315.366274 -32.156904) (xy 315.311431 -32.146774)
			(xy 315.258647 -32.128767) (xy 315.209047 -32.103266) (xy 315.163689 -32.070815) (xy 315.12354 -32.032106)
			(xy 315.089454 -31.987963) (xy 315.062158 -31.939328) (xy 315.042235 -31.887237) (xy 315.030109 -31.8328)
			(xy 315.026038 -31.777178) (xy 314.506821 -31.777178) (xy 314.499693 -31.800871) (xy 314.476021 -31.851368)
			(xy 314.445248 -31.897881) (xy 314.408031 -31.939418) (xy 314.365163 -31.975093) (xy 314.317557 -32.004147)
			(xy 314.266228 -32.025959) (xy 314.212271 -32.040065) (xy 314.156834 -32.046165) (xy 314.1011 -32.044128)
			(xy 314.046257 -32.033998) (xy 313.993473 -32.015991) (xy 313.943873 -31.99049) (xy 313.898515 -31.958039)
			(xy 313.858366 -31.91933) (xy 313.82428 -31.875187) (xy 313.796984 -31.826552) (xy 313.777061 -31.774461)
			(xy 313.764935 -31.720024) (xy 313.760864 -31.664402) (xy 313.244323 -31.664402) (xy 313.248293 -31.69138)
			(xy 313.248802 -31.719266) (xy 313.248293 -31.747152) (xy 313.240173 -31.802328) (xy 313.224105 -31.855735)
			(xy 313.200433 -31.906232) (xy 313.16966 -31.952745) (xy 313.132443 -31.994282) (xy 313.089575 -32.029957)
			(xy 313.041969 -32.059011) (xy 312.99064 -32.080823) (xy 312.936683 -32.094929) (xy 312.881246 -32.101029)
			(xy 312.825512 -32.098992) (xy 312.770669 -32.088862) (xy 312.717885 -32.070855) (xy 312.668285 -32.045354)
			(xy 312.622927 -32.012903) (xy 312.582778 -31.974194) (xy 312.548692 -31.930051) (xy 312.521396 -31.881416)
			(xy 312.501473 -31.829325) (xy 312.489347 -31.774888) (xy 312.485276 -31.719266) (xy 311.930349 -31.719266)
			(xy 311.913669 -31.754848) (xy 311.882896 -31.801361) (xy 311.845679 -31.842898) (xy 311.802811 -31.878573)
			(xy 311.755205 -31.907627) (xy 311.703876 -31.929439) (xy 311.649919 -31.943545) (xy 311.594482 -31.949645)
			(xy 311.538748 -31.947608) (xy 311.483905 -31.937478) (xy 311.431121 -31.919471) (xy 311.381521 -31.89397)
			(xy 311.336163 -31.861519) (xy 311.296014 -31.82281) (xy 311.261928 -31.778667) (xy 311.234632 -31.730032)
			(xy 311.214709 -31.677941) (xy 311.202583 -31.623504) (xy 311.198512 -31.567882) (xy 303.864494 -31.567882)
			(xy 303.886087 -31.596022) (xy 303.916054 -31.647928) (xy 303.93899 -31.703301) (xy 303.954503 -31.761194)
			(xy 303.962326 -31.820616) (xy 303.962816 -31.850584) (xy 303.962816 -32.714184) (xy 303.962683 -32.722312)
			(xy 318.806576 -32.722312) (xy 318.806576 -31.858712) (xy 318.807066 -31.828728) (xy 318.814894 -31.769272)
			(xy 318.830415 -31.711347) (xy 318.853364 -31.655943) (xy 318.883348 -31.604009) (xy 318.919854 -31.556433)
			(xy 318.962259 -31.514028) (xy 319.009835 -31.477522) (xy 319.061769 -31.447538) (xy 319.117173 -31.424589)
			(xy 319.175098 -31.409068) (xy 319.234554 -31.40124) (xy 319.294522 -31.40124) (xy 319.353978 -31.409068)
			(xy 319.411903 -31.424589) (xy 319.467307 -31.447538) (xy 319.519241 -31.477522) (xy 319.566817 -31.514028)
			(xy 319.609222 -31.556433) (xy 319.645728 -31.604009) (xy 319.675712 -31.655943) (xy 319.698661 -31.711347)
			(xy 319.714182 -31.769272) (xy 319.72201 -31.828728) (xy 319.7225 -31.858712) (xy 319.7225 -32.714184)
			(xy 329.047348 -32.714184) (xy 329.047348 -31.850584) (xy 329.047838 -31.820616) (xy 329.055661 -31.761194)
			(xy 329.071174 -31.703301) (xy 329.09411 -31.647928) (xy 329.124077 -31.596022) (xy 329.160564 -31.548472)
			(xy 329.202944 -31.506092) (xy 329.250494 -31.469605) (xy 329.3024 -31.439638) (xy 329.357773 -31.416702)
			(xy 329.415666 -31.401189) (xy 329.475088 -31.393366) (xy 329.535024 -31.393366) (xy 329.594446 -31.401189)
			(xy 329.652339 -31.416702) (xy 329.707712 -31.439638) (xy 329.759618 -31.469605) (xy 329.807168 -31.506092)
			(xy 329.849548 -31.548472) (xy 329.864442 -31.567882) (xy 349.298766 -31.567882) (xy 349.302837 -31.51226)
			(xy 349.314963 -31.457823) (xy 349.334886 -31.405732) (xy 349.362182 -31.357097) (xy 349.396268 -31.312954)
			(xy 349.436417 -31.274245) (xy 349.481775 -31.241794) (xy 349.531375 -31.216293) (xy 349.584159 -31.198286)
			(xy 349.639002 -31.188156) (xy 349.694736 -31.186119) (xy 349.750173 -31.192219) (xy 349.80413 -31.206325)
			(xy 349.855459 -31.228137) (xy 349.903065 -31.257191) (xy 349.945933 -31.292866) (xy 349.98315 -31.334403)
			(xy 350.013923 -31.380916) (xy 350.037595 -31.431413) (xy 350.053663 -31.48482) (xy 350.061783 -31.539996)
			(xy 350.062292 -31.567882) (xy 350.061783 -31.595768) (xy 350.053663 -31.650944) (xy 350.037595 -31.704351)
			(xy 350.030603 -31.719266) (xy 350.58553 -31.719266) (xy 350.589601 -31.663644) (xy 350.601727 -31.609207)
			(xy 350.62165 -31.557116) (xy 350.648946 -31.508481) (xy 350.683032 -31.464338) (xy 350.723181 -31.425629)
			(xy 350.768539 -31.393178) (xy 350.818139 -31.367677) (xy 350.870923 -31.34967) (xy 350.925766 -31.33954)
			(xy 350.9815 -31.337503) (xy 351.036937 -31.343603) (xy 351.090894 -31.357709) (xy 351.142223 -31.379521)
			(xy 351.189829 -31.408575) (xy 351.232697 -31.44425) (xy 351.269914 -31.485787) (xy 351.300687 -31.5323)
			(xy 351.324359 -31.582797) (xy 351.340427 -31.636204) (xy 351.344577 -31.664402) (xy 351.861118 -31.664402)
			(xy 351.865189 -31.60878) (xy 351.877315 -31.554343) (xy 351.897238 -31.502252) (xy 351.924534 -31.453617)
			(xy 351.95862 -31.409474) (xy 351.998769 -31.370765) (xy 352.044127 -31.338314) (xy 352.093727 -31.312813)
			(xy 352.146511 -31.294806) (xy 352.201354 -31.284676) (xy 352.257088 -31.282639) (xy 352.312525 -31.288739)
			(xy 352.366482 -31.302845) (xy 352.417811 -31.324657) (xy 352.465417 -31.353711) (xy 352.508285 -31.389386)
			(xy 352.545502 -31.430923) (xy 352.576275 -31.477436) (xy 352.599947 -31.527933) (xy 352.616015 -31.58134)
			(xy 352.624135 -31.636516) (xy 352.624644 -31.664402) (xy 352.624135 -31.692288) (xy 352.616015 -31.747464)
			(xy 352.607075 -31.777178) (xy 353.126292 -31.777178) (xy 353.130363 -31.721556) (xy 353.142489 -31.667119)
			(xy 353.162412 -31.615028) (xy 353.189708 -31.566393) (xy 353.223794 -31.52225) (xy 353.263943 -31.483541)
			(xy 353.309301 -31.45109) (xy 353.358901 -31.425589) (xy 353.411685 -31.407582) (xy 353.466528 -31.397452)
			(xy 353.522262 -31.395415) (xy 353.577699 -31.401515) (xy 353.631656 -31.415621) (xy 353.682985 -31.437433)
			(xy 353.730591 -31.466487) (xy 353.773459 -31.502162) (xy 353.810676 -31.543699) (xy 353.841449 -31.590212)
			(xy 353.865121 -31.640709) (xy 353.881189 -31.694116) (xy 353.889309 -31.749292) (xy 353.889818 -31.777178)
			(xy 353.889309 -31.805064) (xy 353.881189 -31.86024) (xy 353.865121 -31.913647) (xy 353.841449 -31.964144)
			(xy 353.810676 -32.010657) (xy 353.773459 -32.052194) (xy 353.730591 -32.087869) (xy 353.682985 -32.116923)
			(xy 353.631656 -32.138735) (xy 353.577699 -32.152841) (xy 353.522262 -32.158941) (xy 353.466528 -32.156904)
			(xy 353.411685 -32.146774) (xy 353.358901 -32.128767) (xy 353.309301 -32.103266) (xy 353.263943 -32.070815)
			(xy 353.223794 -32.032106) (xy 353.189708 -31.987963) (xy 353.162412 -31.939328) (xy 353.142489 -31.887237)
			(xy 353.130363 -31.8328) (xy 353.126292 -31.777178) (xy 352.607075 -31.777178) (xy 352.599947 -31.800871)
			(xy 352.576275 -31.851368) (xy 352.545502 -31.897881) (xy 352.508285 -31.939418) (xy 352.465417 -31.975093)
			(xy 352.417811 -32.004147) (xy 352.366482 -32.025959) (xy 352.312525 -32.040065) (xy 352.257088 -32.046165)
			(xy 352.201354 -32.044128) (xy 352.146511 -32.033998) (xy 352.093727 -32.015991) (xy 352.044127 -31.99049)
			(xy 351.998769 -31.958039) (xy 351.95862 -31.91933) (xy 351.924534 -31.875187) (xy 351.897238 -31.826552)
			(xy 351.877315 -31.774461) (xy 351.865189 -31.720024) (xy 351.861118 -31.664402) (xy 351.344577 -31.664402)
			(xy 351.348547 -31.69138) (xy 351.349056 -31.719266) (xy 351.348547 -31.747152) (xy 351.340427 -31.802328)
			(xy 351.324359 -31.855735) (xy 351.300687 -31.906232) (xy 351.269914 -31.952745) (xy 351.232697 -31.994282)
			(xy 351.189829 -32.029957) (xy 351.142223 -32.059011) (xy 351.090894 -32.080823) (xy 351.036937 -32.094929)
			(xy 350.9815 -32.101029) (xy 350.925766 -32.098992) (xy 350.870923 -32.088862) (xy 350.818139 -32.070855)
			(xy 350.768539 -32.045354) (xy 350.723181 -32.012903) (xy 350.683032 -31.974194) (xy 350.648946 -31.930051)
			(xy 350.62165 -31.881416) (xy 350.601727 -31.829325) (xy 350.589601 -31.774888) (xy 350.58553 -31.719266)
			(xy 350.030603 -31.719266) (xy 350.013923 -31.754848) (xy 349.98315 -31.801361) (xy 349.945933 -31.842898)
			(xy 349.903065 -31.878573) (xy 349.855459 -31.907627) (xy 349.80413 -31.929439) (xy 349.750173 -31.943545)
			(xy 349.694736 -31.949645) (xy 349.639002 -31.947608) (xy 349.584159 -31.937478) (xy 349.531375 -31.919471)
			(xy 349.481775 -31.89397) (xy 349.436417 -31.861519) (xy 349.396268 -31.82281) (xy 349.362182 -31.778667)
			(xy 349.334886 -31.730032) (xy 349.314963 -31.677941) (xy 349.302837 -31.623504) (xy 349.298766 -31.567882)
			(xy 329.864442 -31.567882) (xy 329.886035 -31.596022) (xy 329.916002 -31.647928) (xy 329.938938 -31.703301)
			(xy 329.954451 -31.761194) (xy 329.962274 -31.820616) (xy 329.962764 -31.850584) (xy 329.962764 -32.714184)
			(xy 329.962631 -32.722312) (xy 356.907084 -32.722312) (xy 356.907084 -31.858712) (xy 356.907574 -31.828744)
			(xy 356.915397 -31.769322) (xy 356.93091 -31.711429) (xy 356.953846 -31.656056) (xy 356.983813 -31.60415)
			(xy 357.0203 -31.5566) (xy 357.06268 -31.51422) (xy 357.11023 -31.477733) (xy 357.162136 -31.447766)
			(xy 357.217509 -31.42483) (xy 357.275402 -31.409317) (xy 357.334824 -31.401494) (xy 357.39476 -31.401494)
			(xy 357.454182 -31.409317) (xy 357.512075 -31.42483) (xy 357.567448 -31.447766) (xy 357.619354 -31.477733)
			(xy 357.666904 -31.51422) (xy 357.709284 -31.5566) (xy 357.745771 -31.60415) (xy 357.775738 -31.656056)
			(xy 357.798674 -31.711429) (xy 357.814187 -31.769322) (xy 357.82201 -31.828744) (xy 357.8225 -31.858712)
			(xy 357.8225 -32.714184) (xy 367.147348 -32.714184) (xy 367.147348 -31.850584) (xy 367.147838 -31.8206)
			(xy 367.155666 -31.761144) (xy 367.171187 -31.703219) (xy 367.194136 -31.647815) (xy 367.22412 -31.595881)
			(xy 367.260626 -31.548305) (xy 367.303031 -31.5059) (xy 367.350607 -31.469394) (xy 367.402541 -31.43941)
			(xy 367.457945 -31.416461) (xy 367.51587 -31.40094) (xy 367.575326 -31.393112) (xy 367.635294 -31.393112)
			(xy 367.69475 -31.40094) (xy 367.752675 -31.416461) (xy 367.808079 -31.43941) (xy 367.860013 -31.469394)
			(xy 367.907589 -31.5059) (xy 367.949994 -31.548305) (xy 367.965016 -31.567882) (xy 375.298714 -31.567882)
			(xy 375.302785 -31.51226) (xy 375.314911 -31.457823) (xy 375.334834 -31.405732) (xy 375.36213 -31.357097)
			(xy 375.396216 -31.312954) (xy 375.436365 -31.274245) (xy 375.481723 -31.241794) (xy 375.531323 -31.216293)
			(xy 375.584107 -31.198286) (xy 375.63895 -31.188156) (xy 375.694684 -31.186119) (xy 375.750121 -31.192219)
			(xy 375.804078 -31.206325) (xy 375.855407 -31.228137) (xy 375.903013 -31.257191) (xy 375.945881 -31.292866)
			(xy 375.983098 -31.334403) (xy 376.013871 -31.380916) (xy 376.037543 -31.431413) (xy 376.053611 -31.48482)
			(xy 376.061731 -31.539996) (xy 376.06224 -31.567882) (xy 376.061731 -31.595768) (xy 376.053611 -31.650944)
			(xy 376.037543 -31.704351) (xy 376.030551 -31.719266) (xy 376.585478 -31.719266) (xy 376.589549 -31.663644)
			(xy 376.601675 -31.609207) (xy 376.621598 -31.557116) (xy 376.648894 -31.508481) (xy 376.68298 -31.464338)
			(xy 376.723129 -31.425629) (xy 376.768487 -31.393178) (xy 376.818087 -31.367677) (xy 376.870871 -31.34967)
			(xy 376.925714 -31.33954) (xy 376.981448 -31.337503) (xy 377.036885 -31.343603) (xy 377.090842 -31.357709)
			(xy 377.142171 -31.379521) (xy 377.189777 -31.408575) (xy 377.232645 -31.44425) (xy 377.269862 -31.485787)
			(xy 377.300635 -31.5323) (xy 377.324307 -31.582797) (xy 377.340375 -31.636204) (xy 377.344525 -31.664402)
			(xy 377.861066 -31.664402) (xy 377.865137 -31.60878) (xy 377.877263 -31.554343) (xy 377.897186 -31.502252)
			(xy 377.924482 -31.453617) (xy 377.958568 -31.409474) (xy 377.998717 -31.370765) (xy 378.044075 -31.338314)
			(xy 378.093675 -31.312813) (xy 378.146459 -31.294806) (xy 378.201302 -31.284676) (xy 378.257036 -31.282639)
			(xy 378.312473 -31.288739) (xy 378.36643 -31.302845) (xy 378.417759 -31.324657) (xy 378.465365 -31.353711)
			(xy 378.508233 -31.389386) (xy 378.54545 -31.430923) (xy 378.576223 -31.477436) (xy 378.599895 -31.527933)
			(xy 378.615963 -31.58134) (xy 378.624083 -31.636516) (xy 378.624592 -31.664402) (xy 378.624083 -31.692288)
			(xy 378.615963 -31.747464) (xy 378.607023 -31.777178) (xy 379.12624 -31.777178) (xy 379.130311 -31.721556)
			(xy 379.142437 -31.667119) (xy 379.16236 -31.615028) (xy 379.189656 -31.566393) (xy 379.223742 -31.52225)
			(xy 379.263891 -31.483541) (xy 379.309249 -31.45109) (xy 379.358849 -31.425589) (xy 379.411633 -31.407582)
			(xy 379.466476 -31.397452) (xy 379.52221 -31.395415) (xy 379.577647 -31.401515) (xy 379.631604 -31.415621)
			(xy 379.682933 -31.437433) (xy 379.730539 -31.466487) (xy 379.773407 -31.502162) (xy 379.810624 -31.543699)
			(xy 379.841397 -31.590212) (xy 379.865069 -31.640709) (xy 379.881137 -31.694116) (xy 379.889257 -31.749292)
			(xy 379.889766 -31.777178) (xy 379.889257 -31.805064) (xy 379.881137 -31.86024) (xy 379.865069 -31.913647)
			(xy 379.841397 -31.964144) (xy 379.810624 -32.010657) (xy 379.773407 -32.052194) (xy 379.730539 -32.087869)
			(xy 379.682933 -32.116923) (xy 379.631604 -32.138735) (xy 379.577647 -32.152841) (xy 379.52221 -32.158941)
			(xy 379.466476 -32.156904) (xy 379.411633 -32.146774) (xy 379.358849 -32.128767) (xy 379.309249 -32.103266)
			(xy 379.263891 -32.070815) (xy 379.223742 -32.032106) (xy 379.189656 -31.987963) (xy 379.16236 -31.939328)
			(xy 379.142437 -31.887237) (xy 379.130311 -31.8328) (xy 379.12624 -31.777178) (xy 378.607023 -31.777178)
			(xy 378.599895 -31.800871) (xy 378.576223 -31.851368) (xy 378.54545 -31.897881) (xy 378.508233 -31.939418)
			(xy 378.465365 -31.975093) (xy 378.417759 -32.004147) (xy 378.36643 -32.025959) (xy 378.312473 -32.040065)
			(xy 378.257036 -32.046165) (xy 378.201302 -32.044128) (xy 378.146459 -32.033998) (xy 378.093675 -32.015991)
			(xy 378.044075 -31.99049) (xy 377.998717 -31.958039) (xy 377.958568 -31.91933) (xy 377.924482 -31.875187)
			(xy 377.897186 -31.826552) (xy 377.877263 -31.774461) (xy 377.865137 -31.720024) (xy 377.861066 -31.664402)
			(xy 377.344525 -31.664402) (xy 377.348495 -31.69138) (xy 377.349004 -31.719266) (xy 377.348495 -31.747152)
			(xy 377.340375 -31.802328) (xy 377.324307 -31.855735) (xy 377.300635 -31.906232) (xy 377.269862 -31.952745)
			(xy 377.232645 -31.994282) (xy 377.189777 -32.029957) (xy 377.142171 -32.059011) (xy 377.090842 -32.080823)
			(xy 377.036885 -32.094929) (xy 376.981448 -32.101029) (xy 376.925714 -32.098992) (xy 376.870871 -32.088862)
			(xy 376.818087 -32.070855) (xy 376.768487 -32.045354) (xy 376.723129 -32.012903) (xy 376.68298 -31.974194)
			(xy 376.648894 -31.930051) (xy 376.621598 -31.881416) (xy 376.601675 -31.829325) (xy 376.589549 -31.774888)
			(xy 376.585478 -31.719266) (xy 376.030551 -31.719266) (xy 376.013871 -31.754848) (xy 375.983098 -31.801361)
			(xy 375.945881 -31.842898) (xy 375.903013 -31.878573) (xy 375.855407 -31.907627) (xy 375.804078 -31.929439)
			(xy 375.750121 -31.943545) (xy 375.694684 -31.949645) (xy 375.63895 -31.947608) (xy 375.584107 -31.937478)
			(xy 375.531323 -31.919471) (xy 375.481723 -31.89397) (xy 375.436365 -31.861519) (xy 375.396216 -31.82281)
			(xy 375.36213 -31.778667) (xy 375.334834 -31.730032) (xy 375.314911 -31.677941) (xy 375.302785 -31.623504)
			(xy 375.298714 -31.567882) (xy 367.965016 -31.567882) (xy 367.9865 -31.595881) (xy 368.016484 -31.647815)
			(xy 368.039433 -31.703219) (xy 368.054954 -31.761144) (xy 368.062782 -31.8206) (xy 368.063272 -31.850584)
			(xy 368.063272 -32.714184) (xy 368.063139 -32.722312) (xy 382.907032 -32.722312) (xy 382.907032 -31.858712)
			(xy 382.907522 -31.828744) (xy 382.915345 -31.769322) (xy 382.930858 -31.711429) (xy 382.953794 -31.656056)
			(xy 382.983761 -31.60415) (xy 383.020248 -31.5566) (xy 383.062628 -31.51422) (xy 383.110178 -31.477733)
			(xy 383.162084 -31.447766) (xy 383.217457 -31.42483) (xy 383.27535 -31.409317) (xy 383.334772 -31.401494)
			(xy 383.394708 -31.401494) (xy 383.45413 -31.409317) (xy 383.512023 -31.42483) (xy 383.567396 -31.447766)
			(xy 383.619302 -31.477733) (xy 383.666852 -31.51422) (xy 383.709232 -31.5566) (xy 383.745719 -31.60415)
			(xy 383.775686 -31.656056) (xy 383.798622 -31.711429) (xy 383.814135 -31.769322) (xy 383.821958 -31.828744)
			(xy 383.822448 -31.858712) (xy 383.822448 -32.714184) (xy 393.147296 -32.714184) (xy 393.147296 -31.850584)
			(xy 393.147786 -31.8206) (xy 393.155614 -31.761144) (xy 393.171135 -31.703219) (xy 393.194084 -31.647815)
			(xy 393.224068 -31.595881) (xy 393.260574 -31.548305) (xy 393.302979 -31.5059) (xy 393.350555 -31.469394)
			(xy 393.402489 -31.43941) (xy 393.457893 -31.416461) (xy 393.515818 -31.40094) (xy 393.575274 -31.393112)
			(xy 393.635242 -31.393112) (xy 393.694698 -31.40094) (xy 393.752623 -31.416461) (xy 393.808027 -31.43941)
			(xy 393.859961 -31.469394) (xy 393.907537 -31.5059) (xy 393.949942 -31.548305) (xy 393.964964 -31.567882)
			(xy 401.298662 -31.567882) (xy 401.302733 -31.51226) (xy 401.314859 -31.457823) (xy 401.334782 -31.405732)
			(xy 401.362078 -31.357097) (xy 401.396164 -31.312954) (xy 401.436313 -31.274245) (xy 401.481671 -31.241794)
			(xy 401.531271 -31.216293) (xy 401.584055 -31.198286) (xy 401.638898 -31.188156) (xy 401.694632 -31.186119)
			(xy 401.750069 -31.192219) (xy 401.804026 -31.206325) (xy 401.855355 -31.228137) (xy 401.902961 -31.257191)
			(xy 401.945829 -31.292866) (xy 401.983046 -31.334403) (xy 402.013819 -31.380916) (xy 402.037491 -31.431413)
			(xy 402.053559 -31.48482) (xy 402.061679 -31.539996) (xy 402.062188 -31.567882) (xy 402.061679 -31.595768)
			(xy 402.053559 -31.650944) (xy 402.037491 -31.704351) (xy 402.030499 -31.719266) (xy 402.585426 -31.719266)
			(xy 402.589497 -31.663644) (xy 402.601623 -31.609207) (xy 402.621546 -31.557116) (xy 402.648842 -31.508481)
			(xy 402.682928 -31.464338) (xy 402.723077 -31.425629) (xy 402.768435 -31.393178) (xy 402.818035 -31.367677)
			(xy 402.870819 -31.34967) (xy 402.925662 -31.33954) (xy 402.981396 -31.337503) (xy 403.036833 -31.343603)
			(xy 403.09079 -31.357709) (xy 403.142119 -31.379521) (xy 403.189725 -31.408575) (xy 403.232593 -31.44425)
			(xy 403.26981 -31.485787) (xy 403.300583 -31.5323) (xy 403.324255 -31.582797) (xy 403.340323 -31.636204)
			(xy 403.344473 -31.664402) (xy 403.861014 -31.664402) (xy 403.865085 -31.60878) (xy 403.877211 -31.554343)
			(xy 403.897134 -31.502252) (xy 403.92443 -31.453617) (xy 403.958516 -31.409474) (xy 403.998665 -31.370765)
			(xy 404.044023 -31.338314) (xy 404.093623 -31.312813) (xy 404.146407 -31.294806) (xy 404.20125 -31.284676)
			(xy 404.256984 -31.282639) (xy 404.312421 -31.288739) (xy 404.366378 -31.302845) (xy 404.417707 -31.324657)
			(xy 404.465313 -31.353711) (xy 404.508181 -31.389386) (xy 404.545398 -31.430923) (xy 404.576171 -31.477436)
			(xy 404.599843 -31.527933) (xy 404.615911 -31.58134) (xy 404.624031 -31.636516) (xy 404.62454 -31.664402)
			(xy 404.624031 -31.692288) (xy 404.615911 -31.747464) (xy 404.606971 -31.777178) (xy 405.126188 -31.777178)
			(xy 405.130259 -31.721556) (xy 405.142385 -31.667119) (xy 405.162308 -31.615028) (xy 405.189604 -31.566393)
			(xy 405.22369 -31.52225) (xy 405.263839 -31.483541) (xy 405.309197 -31.45109) (xy 405.358797 -31.425589)
			(xy 405.411581 -31.407582) (xy 405.466424 -31.397452) (xy 405.522158 -31.395415) (xy 405.577595 -31.401515)
			(xy 405.631552 -31.415621) (xy 405.682881 -31.437433) (xy 405.730487 -31.466487) (xy 405.773355 -31.502162)
			(xy 405.810572 -31.543699) (xy 405.841345 -31.590212) (xy 405.865017 -31.640709) (xy 405.881085 -31.694116)
			(xy 405.889205 -31.749292) (xy 405.889714 -31.777178) (xy 405.889205 -31.805064) (xy 405.881085 -31.86024)
			(xy 405.865017 -31.913647) (xy 405.841345 -31.964144) (xy 405.810572 -32.010657) (xy 405.773355 -32.052194)
			(xy 405.730487 -32.087869) (xy 405.682881 -32.116923) (xy 405.631552 -32.138735) (xy 405.577595 -32.152841)
			(xy 405.522158 -32.158941) (xy 405.466424 -32.156904) (xy 405.411581 -32.146774) (xy 405.358797 -32.128767)
			(xy 405.309197 -32.103266) (xy 405.263839 -32.070815) (xy 405.22369 -32.032106) (xy 405.189604 -31.987963)
			(xy 405.162308 -31.939328) (xy 405.142385 -31.887237) (xy 405.130259 -31.8328) (xy 405.126188 -31.777178)
			(xy 404.606971 -31.777178) (xy 404.599843 -31.800871) (xy 404.576171 -31.851368) (xy 404.545398 -31.897881)
			(xy 404.508181 -31.939418) (xy 404.465313 -31.975093) (xy 404.417707 -32.004147) (xy 404.366378 -32.025959)
			(xy 404.312421 -32.040065) (xy 404.256984 -32.046165) (xy 404.20125 -32.044128) (xy 404.146407 -32.033998)
			(xy 404.093623 -32.015991) (xy 404.044023 -31.99049) (xy 403.998665 -31.958039) (xy 403.958516 -31.91933)
			(xy 403.92443 -31.875187) (xy 403.897134 -31.826552) (xy 403.877211 -31.774461) (xy 403.865085 -31.720024)
			(xy 403.861014 -31.664402) (xy 403.344473 -31.664402) (xy 403.348443 -31.69138) (xy 403.348952 -31.719266)
			(xy 403.348443 -31.747152) (xy 403.340323 -31.802328) (xy 403.324255 -31.855735) (xy 403.300583 -31.906232)
			(xy 403.26981 -31.952745) (xy 403.232593 -31.994282) (xy 403.189725 -32.029957) (xy 403.142119 -32.059011)
			(xy 403.09079 -32.080823) (xy 403.036833 -32.094929) (xy 402.981396 -32.101029) (xy 402.925662 -32.098992)
			(xy 402.870819 -32.088862) (xy 402.818035 -32.070855) (xy 402.768435 -32.045354) (xy 402.723077 -32.012903)
			(xy 402.682928 -31.974194) (xy 402.648842 -31.930051) (xy 402.621546 -31.881416) (xy 402.601623 -31.829325)
			(xy 402.589497 -31.774888) (xy 402.585426 -31.719266) (xy 402.030499 -31.719266) (xy 402.013819 -31.754848)
			(xy 401.983046 -31.801361) (xy 401.945829 -31.842898) (xy 401.902961 -31.878573) (xy 401.855355 -31.907627)
			(xy 401.804026 -31.929439) (xy 401.750069 -31.943545) (xy 401.694632 -31.949645) (xy 401.638898 -31.947608)
			(xy 401.584055 -31.937478) (xy 401.531271 -31.919471) (xy 401.481671 -31.89397) (xy 401.436313 -31.861519)
			(xy 401.396164 -31.82281) (xy 401.362078 -31.778667) (xy 401.334782 -31.730032) (xy 401.314859 -31.677941)
			(xy 401.302733 -31.623504) (xy 401.298662 -31.567882) (xy 393.964964 -31.567882) (xy 393.986448 -31.595881)
			(xy 394.016432 -31.647815) (xy 394.039381 -31.703219) (xy 394.054902 -31.761144) (xy 394.06273 -31.8206)
			(xy 394.06322 -31.850584) (xy 394.06322 -32.714184) (xy 394.063087 -32.722312) (xy 408.90698 -32.722312)
			(xy 408.90698 -31.858712) (xy 408.90747 -31.828744) (xy 408.915293 -31.769322) (xy 408.930806 -31.711429)
			(xy 408.953742 -31.656056) (xy 408.983709 -31.60415) (xy 409.020196 -31.5566) (xy 409.062576 -31.51422)
			(xy 409.110126 -31.477733) (xy 409.162032 -31.447766) (xy 409.217405 -31.42483) (xy 409.275298 -31.409317)
			(xy 409.33472 -31.401494) (xy 409.394656 -31.401494) (xy 409.454078 -31.409317) (xy 409.511971 -31.42483)
			(xy 409.567344 -31.447766) (xy 409.61925 -31.477733) (xy 409.6668 -31.51422) (xy 409.70918 -31.5566)
			(xy 409.745667 -31.60415) (xy 409.775634 -31.656056) (xy 409.79857 -31.711429) (xy 409.814083 -31.769322)
			(xy 409.821906 -31.828744) (xy 409.822396 -31.858712) (xy 409.822396 -32.714184) (xy 419.147244 -32.714184)
			(xy 419.147244 -31.850584) (xy 419.147734 -31.8206) (xy 419.155562 -31.761144) (xy 419.171083 -31.703219)
			(xy 419.194032 -31.647815) (xy 419.224016 -31.595881) (xy 419.260522 -31.548305) (xy 419.302927 -31.5059)
			(xy 419.350503 -31.469394) (xy 419.402437 -31.43941) (xy 419.457841 -31.416461) (xy 419.515766 -31.40094)
			(xy 419.575222 -31.393112) (xy 419.63519 -31.393112) (xy 419.694646 -31.40094) (xy 419.752571 -31.416461)
			(xy 419.807975 -31.43941) (xy 419.859909 -31.469394) (xy 419.907485 -31.5059) (xy 419.94989 -31.548305)
			(xy 419.964912 -31.567882) (xy 427.29861 -31.567882) (xy 427.302681 -31.51226) (xy 427.314807 -31.457823)
			(xy 427.33473 -31.405732) (xy 427.362026 -31.357097) (xy 427.396112 -31.312954) (xy 427.436261 -31.274245)
			(xy 427.481619 -31.241794) (xy 427.531219 -31.216293) (xy 427.584003 -31.198286) (xy 427.638846 -31.188156)
			(xy 427.69458 -31.186119) (xy 427.750017 -31.192219) (xy 427.803974 -31.206325) (xy 427.855303 -31.228137)
			(xy 427.902909 -31.257191) (xy 427.945777 -31.292866) (xy 427.982994 -31.334403) (xy 428.013767 -31.380916)
			(xy 428.037439 -31.431413) (xy 428.053507 -31.48482) (xy 428.061627 -31.539996) (xy 428.062136 -31.567882)
			(xy 428.061627 -31.595768) (xy 428.053507 -31.650944) (xy 428.037439 -31.704351) (xy 428.030447 -31.719266)
			(xy 428.585374 -31.719266) (xy 428.589445 -31.663644) (xy 428.601571 -31.609207) (xy 428.621494 -31.557116)
			(xy 428.64879 -31.508481) (xy 428.682876 -31.464338) (xy 428.723025 -31.425629) (xy 428.768383 -31.393178)
			(xy 428.817983 -31.367677) (xy 428.870767 -31.34967) (xy 428.92561 -31.33954) (xy 428.981344 -31.337503)
			(xy 429.036781 -31.343603) (xy 429.090738 -31.357709) (xy 429.142067 -31.379521) (xy 429.189673 -31.408575)
			(xy 429.232541 -31.44425) (xy 429.269758 -31.485787) (xy 429.300531 -31.5323) (xy 429.324203 -31.582797)
			(xy 429.340271 -31.636204) (xy 429.344421 -31.664402) (xy 429.860962 -31.664402) (xy 429.865033 -31.60878)
			(xy 429.877159 -31.554343) (xy 429.897082 -31.502252) (xy 429.924378 -31.453617) (xy 429.958464 -31.409474)
			(xy 429.998613 -31.370765) (xy 430.043971 -31.338314) (xy 430.093571 -31.312813) (xy 430.146355 -31.294806)
			(xy 430.201198 -31.284676) (xy 430.256932 -31.282639) (xy 430.312369 -31.288739) (xy 430.366326 -31.302845)
			(xy 430.417655 -31.324657) (xy 430.465261 -31.353711) (xy 430.508129 -31.389386) (xy 430.545346 -31.430923)
			(xy 430.576119 -31.477436) (xy 430.599791 -31.527933) (xy 430.615859 -31.58134) (xy 430.623979 -31.636516)
			(xy 430.624488 -31.664402) (xy 430.623979 -31.692288) (xy 430.615859 -31.747464) (xy 430.606919 -31.777178)
			(xy 431.126136 -31.777178) (xy 431.130207 -31.721556) (xy 431.142333 -31.667119) (xy 431.162256 -31.615028)
			(xy 431.189552 -31.566393) (xy 431.223638 -31.52225) (xy 431.263787 -31.483541) (xy 431.309145 -31.45109)
			(xy 431.358745 -31.425589) (xy 431.411529 -31.407582) (xy 431.466372 -31.397452) (xy 431.522106 -31.395415)
			(xy 431.577543 -31.401515) (xy 431.6315 -31.415621) (xy 431.682829 -31.437433) (xy 431.730435 -31.466487)
			(xy 431.773303 -31.502162) (xy 431.81052 -31.543699) (xy 431.841293 -31.590212) (xy 431.864965 -31.640709)
			(xy 431.881033 -31.694116) (xy 431.889153 -31.749292) (xy 431.889662 -31.777178) (xy 431.889153 -31.805064)
			(xy 431.881033 -31.86024) (xy 431.864965 -31.913647) (xy 431.841293 -31.964144) (xy 431.81052 -32.010657)
			(xy 431.773303 -32.052194) (xy 431.730435 -32.087869) (xy 431.682829 -32.116923) (xy 431.6315 -32.138735)
			(xy 431.577543 -32.152841) (xy 431.522106 -32.158941) (xy 431.466372 -32.156904) (xy 431.411529 -32.146774)
			(xy 431.358745 -32.128767) (xy 431.309145 -32.103266) (xy 431.263787 -32.070815) (xy 431.223638 -32.032106)
			(xy 431.189552 -31.987963) (xy 431.162256 -31.939328) (xy 431.142333 -31.887237) (xy 431.130207 -31.8328)
			(xy 431.126136 -31.777178) (xy 430.606919 -31.777178) (xy 430.599791 -31.800871) (xy 430.576119 -31.851368)
			(xy 430.545346 -31.897881) (xy 430.508129 -31.939418) (xy 430.465261 -31.975093) (xy 430.417655 -32.004147)
			(xy 430.366326 -32.025959) (xy 430.312369 -32.040065) (xy 430.256932 -32.046165) (xy 430.201198 -32.044128)
			(xy 430.146355 -32.033998) (xy 430.093571 -32.015991) (xy 430.043971 -31.99049) (xy 429.998613 -31.958039)
			(xy 429.958464 -31.91933) (xy 429.924378 -31.875187) (xy 429.897082 -31.826552) (xy 429.877159 -31.774461)
			(xy 429.865033 -31.720024) (xy 429.860962 -31.664402) (xy 429.344421 -31.664402) (xy 429.348391 -31.69138)
			(xy 429.3489 -31.719266) (xy 429.348391 -31.747152) (xy 429.340271 -31.802328) (xy 429.324203 -31.855735)
			(xy 429.300531 -31.906232) (xy 429.269758 -31.952745) (xy 429.232541 -31.994282) (xy 429.189673 -32.029957)
			(xy 429.142067 -32.059011) (xy 429.090738 -32.080823) (xy 429.036781 -32.094929) (xy 428.981344 -32.101029)
			(xy 428.92561 -32.098992) (xy 428.870767 -32.088862) (xy 428.817983 -32.070855) (xy 428.768383 -32.045354)
			(xy 428.723025 -32.012903) (xy 428.682876 -31.974194) (xy 428.64879 -31.930051) (xy 428.621494 -31.881416)
			(xy 428.601571 -31.829325) (xy 428.589445 -31.774888) (xy 428.585374 -31.719266) (xy 428.030447 -31.719266)
			(xy 428.013767 -31.754848) (xy 427.982994 -31.801361) (xy 427.945777 -31.842898) (xy 427.902909 -31.878573)
			(xy 427.855303 -31.907627) (xy 427.803974 -31.929439) (xy 427.750017 -31.943545) (xy 427.69458 -31.949645)
			(xy 427.638846 -31.947608) (xy 427.584003 -31.937478) (xy 427.531219 -31.919471) (xy 427.481619 -31.89397)
			(xy 427.436261 -31.861519) (xy 427.396112 -31.82281) (xy 427.362026 -31.778667) (xy 427.33473 -31.730032)
			(xy 427.314807 -31.677941) (xy 427.302681 -31.623504) (xy 427.29861 -31.567882) (xy 419.964912 -31.567882)
			(xy 419.986396 -31.595881) (xy 420.01638 -31.647815) (xy 420.039329 -31.703219) (xy 420.05485 -31.761144)
			(xy 420.062678 -31.8206) (xy 420.063168 -31.850584) (xy 420.063168 -32.714184) (xy 420.063035 -32.722312)
			(xy 434.906928 -32.722312) (xy 434.906928 -31.858712) (xy 434.907418 -31.828744) (xy 434.915241 -31.769322)
			(xy 434.930754 -31.711429) (xy 434.95369 -31.656056) (xy 434.983657 -31.60415) (xy 435.020144 -31.5566)
			(xy 435.062524 -31.51422) (xy 435.110074 -31.477733) (xy 435.16198 -31.447766) (xy 435.217353 -31.42483)
			(xy 435.275246 -31.409317) (xy 435.334668 -31.401494) (xy 435.394604 -31.401494) (xy 435.454026 -31.409317)
			(xy 435.511919 -31.42483) (xy 435.567292 -31.447766) (xy 435.619198 -31.477733) (xy 435.666748 -31.51422)
			(xy 435.709128 -31.5566) (xy 435.745615 -31.60415) (xy 435.775582 -31.656056) (xy 435.798518 -31.711429)
			(xy 435.814031 -31.769322) (xy 435.821854 -31.828744) (xy 435.822344 -31.858712) (xy 435.822344 -32.714184)
			(xy 445.147192 -32.714184) (xy 445.147192 -31.850584) (xy 445.147682 -31.8206) (xy 445.15551 -31.761144)
			(xy 445.171031 -31.703219) (xy 445.19398 -31.647815) (xy 445.223964 -31.595881) (xy 445.26047 -31.548305)
			(xy 445.302875 -31.5059) (xy 445.350451 -31.469394) (xy 445.402385 -31.43941) (xy 445.457789 -31.416461)
			(xy 445.515714 -31.40094) (xy 445.57517 -31.393112) (xy 445.635138 -31.393112) (xy 445.694594 -31.40094)
			(xy 445.752519 -31.416461) (xy 445.807923 -31.43941) (xy 445.859857 -31.469394) (xy 445.907433 -31.5059)
			(xy 445.949838 -31.548305) (xy 445.986344 -31.595881) (xy 446.016328 -31.647815) (xy 446.039277 -31.703219)
			(xy 446.054798 -31.761144) (xy 446.062626 -31.8206) (xy 446.063116 -31.850584) (xy 446.063116 -32.714184)
			(xy 446.062626 -32.744168) (xy 446.054798 -32.803624) (xy 446.039277 -32.861549) (xy 446.016328 -32.916953)
			(xy 445.986344 -32.968887) (xy 445.949838 -33.016463) (xy 445.907433 -33.058868) (xy 445.859857 -33.095374)
			(xy 445.807923 -33.125358) (xy 445.752519 -33.148307) (xy 445.694594 -33.163828) (xy 445.635138 -33.171656)
			(xy 445.57517 -33.171656) (xy 445.515714 -33.163828) (xy 445.457789 -33.148307) (xy 445.402385 -33.125358)
			(xy 445.350451 -33.095374) (xy 445.302875 -33.058868) (xy 445.26047 -33.016463) (xy 445.223964 -32.968887)
			(xy 445.19398 -32.916953) (xy 445.171031 -32.861549) (xy 445.15551 -32.803624) (xy 445.147682 -32.744168)
			(xy 445.147192 -32.714184) (xy 435.822344 -32.714184) (xy 435.822344 -32.722312) (xy 435.821854 -32.75228)
			(xy 435.814031 -32.811702) (xy 435.798518 -32.869595) (xy 435.775582 -32.924968) (xy 435.745615 -32.976874)
			(xy 435.709128 -33.024424) (xy 435.666748 -33.066804) (xy 435.619198 -33.103291) (xy 435.567292 -33.133258)
			(xy 435.511919 -33.156194) (xy 435.454026 -33.171707) (xy 435.394604 -33.17953) (xy 435.334668 -33.17953)
			(xy 435.275246 -33.171707) (xy 435.217353 -33.156194) (xy 435.16198 -33.133258) (xy 435.110074 -33.103291)
			(xy 435.062524 -33.066804) (xy 435.020144 -33.024424) (xy 434.983657 -32.976874) (xy 434.95369 -32.924968)
			(xy 434.930754 -32.869595) (xy 434.915241 -32.811702) (xy 434.907418 -32.75228) (xy 434.906928 -32.722312)
			(xy 420.063035 -32.722312) (xy 420.062678 -32.744168) (xy 420.05485 -32.803624) (xy 420.039329 -32.861549)
			(xy 420.01638 -32.916953) (xy 419.986396 -32.968887) (xy 419.94989 -33.016463) (xy 419.907485 -33.058868)
			(xy 419.859909 -33.095374) (xy 419.807975 -33.125358) (xy 419.752571 -33.148307) (xy 419.694646 -33.163828)
			(xy 419.63519 -33.171656) (xy 419.575222 -33.171656) (xy 419.515766 -33.163828) (xy 419.457841 -33.148307)
			(xy 419.402437 -33.125358) (xy 419.350503 -33.095374) (xy 419.302927 -33.058868) (xy 419.260522 -33.016463)
			(xy 419.224016 -32.968887) (xy 419.194032 -32.916953) (xy 419.171083 -32.861549) (xy 419.155562 -32.803624)
			(xy 419.147734 -32.744168) (xy 419.147244 -32.714184) (xy 409.822396 -32.714184) (xy 409.822396 -32.722312)
			(xy 409.821906 -32.75228) (xy 409.814083 -32.811702) (xy 409.79857 -32.869595) (xy 409.775634 -32.924968)
			(xy 409.745667 -32.976874) (xy 409.70918 -33.024424) (xy 409.6668 -33.066804) (xy 409.61925 -33.103291)
			(xy 409.567344 -33.133258) (xy 409.511971 -33.156194) (xy 409.454078 -33.171707) (xy 409.394656 -33.17953)
			(xy 409.33472 -33.17953) (xy 409.275298 -33.171707) (xy 409.217405 -33.156194) (xy 409.162032 -33.133258)
			(xy 409.110126 -33.103291) (xy 409.062576 -33.066804) (xy 409.020196 -33.024424) (xy 408.983709 -32.976874)
			(xy 408.953742 -32.924968) (xy 408.930806 -32.869595) (xy 408.915293 -32.811702) (xy 408.90747 -32.75228)
			(xy 408.90698 -32.722312) (xy 394.063087 -32.722312) (xy 394.06273 -32.744168) (xy 394.054902 -32.803624)
			(xy 394.039381 -32.861549) (xy 394.016432 -32.916953) (xy 393.986448 -32.968887) (xy 393.949942 -33.016463)
			(xy 393.907537 -33.058868) (xy 393.859961 -33.095374) (xy 393.808027 -33.125358) (xy 393.752623 -33.148307)
			(xy 393.694698 -33.163828) (xy 393.635242 -33.171656) (xy 393.575274 -33.171656) (xy 393.515818 -33.163828)
			(xy 393.457893 -33.148307) (xy 393.402489 -33.125358) (xy 393.350555 -33.095374) (xy 393.302979 -33.058868)
			(xy 393.260574 -33.016463) (xy 393.224068 -32.968887) (xy 393.194084 -32.916953) (xy 393.171135 -32.861549)
			(xy 393.155614 -32.803624) (xy 393.147786 -32.744168) (xy 393.147296 -32.714184) (xy 383.822448 -32.714184)
			(xy 383.822448 -32.722312) (xy 383.821958 -32.75228) (xy 383.814135 -32.811702) (xy 383.798622 -32.869595)
			(xy 383.775686 -32.924968) (xy 383.745719 -32.976874) (xy 383.709232 -33.024424) (xy 383.666852 -33.066804)
			(xy 383.619302 -33.103291) (xy 383.567396 -33.133258) (xy 383.512023 -33.156194) (xy 383.45413 -33.171707)
			(xy 383.394708 -33.17953) (xy 383.334772 -33.17953) (xy 383.27535 -33.171707) (xy 383.217457 -33.156194)
			(xy 383.162084 -33.133258) (xy 383.110178 -33.103291) (xy 383.062628 -33.066804) (xy 383.020248 -33.024424)
			(xy 382.983761 -32.976874) (xy 382.953794 -32.924968) (xy 382.930858 -32.869595) (xy 382.915345 -32.811702)
			(xy 382.907522 -32.75228) (xy 382.907032 -32.722312) (xy 368.063139 -32.722312) (xy 368.062782 -32.744168)
			(xy 368.054954 -32.803624) (xy 368.039433 -32.861549) (xy 368.016484 -32.916953) (xy 367.9865 -32.968887)
			(xy 367.949994 -33.016463) (xy 367.907589 -33.058868) (xy 367.860013 -33.095374) (xy 367.808079 -33.125358)
			(xy 367.752675 -33.148307) (xy 367.69475 -33.163828) (xy 367.635294 -33.171656) (xy 367.575326 -33.171656)
			(xy 367.51587 -33.163828) (xy 367.457945 -33.148307) (xy 367.402541 -33.125358) (xy 367.350607 -33.095374)
			(xy 367.303031 -33.058868) (xy 367.260626 -33.016463) (xy 367.22412 -32.968887) (xy 367.194136 -32.916953)
			(xy 367.171187 -32.861549) (xy 367.155666 -32.803624) (xy 367.147838 -32.744168) (xy 367.147348 -32.714184)
			(xy 357.8225 -32.714184) (xy 357.8225 -32.722312) (xy 357.82201 -32.75228) (xy 357.814187 -32.811702)
			(xy 357.798674 -32.869595) (xy 357.775738 -32.924968) (xy 357.745771 -32.976874) (xy 357.709284 -33.024424)
			(xy 357.666904 -33.066804) (xy 357.619354 -33.103291) (xy 357.567448 -33.133258) (xy 357.512075 -33.156194)
			(xy 357.454182 -33.171707) (xy 357.39476 -33.17953) (xy 357.334824 -33.17953) (xy 357.275402 -33.171707)
			(xy 357.217509 -33.156194) (xy 357.162136 -33.133258) (xy 357.11023 -33.103291) (xy 357.06268 -33.066804)
			(xy 357.0203 -33.024424) (xy 356.983813 -32.976874) (xy 356.953846 -32.924968) (xy 356.93091 -32.869595)
			(xy 356.915397 -32.811702) (xy 356.907574 -32.75228) (xy 356.907084 -32.722312) (xy 329.962631 -32.722312)
			(xy 329.962274 -32.744152) (xy 329.954451 -32.803574) (xy 329.938938 -32.861467) (xy 329.916002 -32.91684)
			(xy 329.886035 -32.968746) (xy 329.849548 -33.016296) (xy 329.807168 -33.058676) (xy 329.759618 -33.095163)
			(xy 329.707712 -33.12513) (xy 329.652339 -33.148066) (xy 329.594446 -33.163579) (xy 329.535024 -33.171402)
			(xy 329.475088 -33.171402) (xy 329.415666 -33.163579) (xy 329.357773 -33.148066) (xy 329.3024 -33.12513)
			(xy 329.250494 -33.095163) (xy 329.202944 -33.058676) (xy 329.160564 -33.016296) (xy 329.124077 -32.968746)
			(xy 329.09411 -32.91684) (xy 329.071174 -32.861467) (xy 329.055661 -32.803574) (xy 329.047838 -32.744152)
			(xy 329.047348 -32.714184) (xy 319.7225 -32.714184) (xy 319.7225 -32.722312) (xy 319.72201 -32.752296)
			(xy 319.714182 -32.811752) (xy 319.698661 -32.869677) (xy 319.675712 -32.925081) (xy 319.645728 -32.977015)
			(xy 319.609222 -33.024591) (xy 319.566817 -33.066996) (xy 319.519241 -33.103502) (xy 319.467307 -33.133486)
			(xy 319.411903 -33.156435) (xy 319.353978 -33.171956) (xy 319.294522 -33.179784) (xy 319.234554 -33.179784)
			(xy 319.175098 -33.171956) (xy 319.117173 -33.156435) (xy 319.061769 -33.133486) (xy 319.009835 -33.103502)
			(xy 318.962259 -33.066996) (xy 318.919854 -33.024591) (xy 318.883348 -32.977015) (xy 318.853364 -32.925081)
			(xy 318.830415 -32.869677) (xy 318.814894 -32.811752) (xy 318.807066 -32.752296) (xy 318.806576 -32.722312)
			(xy 303.962683 -32.722312) (xy 303.962326 -32.744152) (xy 303.954503 -32.803574) (xy 303.93899 -32.861467)
			(xy 303.916054 -32.91684) (xy 303.886087 -32.968746) (xy 303.8496 -33.016296) (xy 303.80722 -33.058676)
			(xy 303.75967 -33.095163) (xy 303.707764 -33.12513) (xy 303.652391 -33.148066) (xy 303.594498 -33.163579)
			(xy 303.535076 -33.171402) (xy 303.47514 -33.171402) (xy 303.415718 -33.163579) (xy 303.357825 -33.148066)
			(xy 303.302452 -33.12513) (xy 303.250546 -33.095163) (xy 303.202996 -33.058676) (xy 303.160616 -33.016296)
			(xy 303.124129 -32.968746) (xy 303.094162 -32.91684) (xy 303.071226 -32.861467) (xy 303.055713 -32.803574)
			(xy 303.04789 -32.744152) (xy 303.0474 -32.714184) (xy 293.722552 -32.714184) (xy 293.722552 -32.722312)
			(xy 293.722062 -32.752296) (xy 293.714234 -32.811752) (xy 293.698713 -32.869677) (xy 293.675764 -32.925081)
			(xy 293.64578 -32.977015) (xy 293.609274 -33.024591) (xy 293.566869 -33.066996) (xy 293.519293 -33.103502)
			(xy 293.467359 -33.133486) (xy 293.411955 -33.156435) (xy 293.35403 -33.171956) (xy 293.294574 -33.179784)
			(xy 293.234606 -33.179784) (xy 293.17515 -33.171956) (xy 293.117225 -33.156435) (xy 293.061821 -33.133486)
			(xy 293.009887 -33.103502) (xy 292.962311 -33.066996) (xy 292.919906 -33.024591) (xy 292.8834 -32.977015)
			(xy 292.853416 -32.925081) (xy 292.830467 -32.869677) (xy 292.814946 -32.811752) (xy 292.807118 -32.752296)
			(xy 292.806628 -32.722312) (xy 277.962735 -32.722312) (xy 277.962378 -32.744152) (xy 277.954555 -32.803574)
			(xy 277.939042 -32.861467) (xy 277.916106 -32.91684) (xy 277.886139 -32.968746) (xy 277.849652 -33.016296)
			(xy 277.807272 -33.058676) (xy 277.759722 -33.095163) (xy 277.707816 -33.12513) (xy 277.652443 -33.148066)
			(xy 277.59455 -33.163579) (xy 277.535128 -33.171402) (xy 277.475192 -33.171402) (xy 277.41577 -33.163579)
			(xy 277.357877 -33.148066) (xy 277.302504 -33.12513) (xy 277.250598 -33.095163) (xy 277.203048 -33.058676)
			(xy 277.160668 -33.016296) (xy 277.124181 -32.968746) (xy 277.094214 -32.91684) (xy 277.071278 -32.861467)
			(xy 277.055765 -32.803574) (xy 277.047942 -32.744152) (xy 277.047452 -32.714184) (xy 267.722604 -32.714184)
			(xy 267.722604 -32.722312) (xy 267.722114 -32.752296) (xy 267.714286 -32.811752) (xy 267.698765 -32.869677)
			(xy 267.675816 -32.925081) (xy 267.645832 -32.977015) (xy 267.609326 -33.024591) (xy 267.566921 -33.066996)
			(xy 267.519345 -33.103502) (xy 267.467411 -33.133486) (xy 267.412007 -33.156435) (xy 267.354082 -33.171956)
			(xy 267.294626 -33.179784) (xy 267.234658 -33.179784) (xy 267.175202 -33.171956) (xy 267.117277 -33.156435)
			(xy 267.061873 -33.133486) (xy 267.009939 -33.103502) (xy 266.962363 -33.066996) (xy 266.919958 -33.024591)
			(xy 266.883452 -32.977015) (xy 266.853468 -32.925081) (xy 266.830519 -32.869677) (xy 266.814998 -32.811752)
			(xy 266.80717 -32.752296) (xy 266.80668 -32.722312) (xy 251.962787 -32.722312) (xy 251.96243 -32.744152)
			(xy 251.954607 -32.803574) (xy 251.939094 -32.861467) (xy 251.916158 -32.91684) (xy 251.886191 -32.968746)
			(xy 251.849704 -33.016296) (xy 251.807324 -33.058676) (xy 251.759774 -33.095163) (xy 251.707868 -33.12513)
			(xy 251.652495 -33.148066) (xy 251.594602 -33.163579) (xy 251.53518 -33.171402) (xy 251.475244 -33.171402)
			(xy 251.415822 -33.163579) (xy 251.357929 -33.148066) (xy 251.302556 -33.12513) (xy 251.25065 -33.095163)
			(xy 251.2031 -33.058676) (xy 251.16072 -33.016296) (xy 251.124233 -32.968746) (xy 251.094266 -32.91684)
			(xy 251.07133 -32.861467) (xy 251.055817 -32.803574) (xy 251.047994 -32.744152) (xy 251.047504 -32.714184)
			(xy 241.722656 -32.714184) (xy 241.722656 -32.722312) (xy 241.722166 -32.752296) (xy 241.714338 -32.811752)
			(xy 241.698817 -32.869677) (xy 241.675868 -32.925081) (xy 241.645884 -32.977015) (xy 241.609378 -33.024591)
			(xy 241.566973 -33.066996) (xy 241.519397 -33.103502) (xy 241.467463 -33.133486) (xy 241.412059 -33.156435)
			(xy 241.354134 -33.171956) (xy 241.294678 -33.179784) (xy 241.23471 -33.179784) (xy 241.175254 -33.171956)
			(xy 241.117329 -33.156435) (xy 241.061925 -33.133486) (xy 241.009991 -33.103502) (xy 240.962415 -33.066996)
			(xy 240.92001 -33.024591) (xy 240.883504 -32.977015) (xy 240.85352 -32.925081) (xy 240.830571 -32.869677)
			(xy 240.81505 -32.811752) (xy 240.807222 -32.752296) (xy 240.806732 -32.722312) (xy 213.862787 -32.722312)
			(xy 213.86243 -32.744152) (xy 213.854607 -32.803574) (xy 213.839094 -32.861467) (xy 213.816158 -32.91684)
			(xy 213.786191 -32.968746) (xy 213.749704 -33.016296) (xy 213.707324 -33.058676) (xy 213.659774 -33.095163)
			(xy 213.607868 -33.12513) (xy 213.552495 -33.148066) (xy 213.494602 -33.163579) (xy 213.43518 -33.171402)
			(xy 213.375244 -33.171402) (xy 213.315822 -33.163579) (xy 213.257929 -33.148066) (xy 213.202556 -33.12513)
			(xy 213.15065 -33.095163) (xy 213.1031 -33.058676) (xy 213.06072 -33.016296) (xy 213.024233 -32.968746)
			(xy 212.994266 -32.91684) (xy 212.97133 -32.861467) (xy 212.955817 -32.803574) (xy 212.947994 -32.744152)
			(xy 212.947504 -32.714184) (xy 203.622656 -32.714184) (xy 203.622656 -32.722312) (xy 203.622166 -32.752296)
			(xy 203.614338 -32.811752) (xy 203.598817 -32.869677) (xy 203.575868 -32.925081) (xy 203.545884 -32.977015)
			(xy 203.509378 -33.024591) (xy 203.466973 -33.066996) (xy 203.419397 -33.103502) (xy 203.367463 -33.133486)
			(xy 203.312059 -33.156435) (xy 203.254134 -33.171956) (xy 203.194678 -33.179784) (xy 203.13471 -33.179784)
			(xy 203.075254 -33.171956) (xy 203.017329 -33.156435) (xy 202.961925 -33.133486) (xy 202.909991 -33.103502)
			(xy 202.862415 -33.066996) (xy 202.82001 -33.024591) (xy 202.783504 -32.977015) (xy 202.75352 -32.925081)
			(xy 202.730571 -32.869677) (xy 202.71505 -32.811752) (xy 202.707222 -32.752296) (xy 202.706732 -32.722312)
			(xy 187.862839 -32.722312) (xy 187.862482 -32.744152) (xy 187.854659 -32.803574) (xy 187.839146 -32.861467)
			(xy 187.81621 -32.91684) (xy 187.786243 -32.968746) (xy 187.749756 -33.016296) (xy 187.707376 -33.058676)
			(xy 187.659826 -33.095163) (xy 187.60792 -33.12513) (xy 187.552547 -33.148066) (xy 187.494654 -33.163579)
			(xy 187.435232 -33.171402) (xy 187.375296 -33.171402) (xy 187.315874 -33.163579) (xy 187.257981 -33.148066)
			(xy 187.202608 -33.12513) (xy 187.150702 -33.095163) (xy 187.103152 -33.058676) (xy 187.060772 -33.016296)
			(xy 187.024285 -32.968746) (xy 186.994318 -32.91684) (xy 186.971382 -32.861467) (xy 186.955869 -32.803574)
			(xy 186.948046 -32.744152) (xy 186.947556 -32.714184) (xy 177.622708 -32.714184) (xy 177.622708 -32.722312)
			(xy 177.622218 -32.752296) (xy 177.61439 -32.811752) (xy 177.598869 -32.869677) (xy 177.57592 -32.925081)
			(xy 177.545936 -32.977015) (xy 177.50943 -33.024591) (xy 177.467025 -33.066996) (xy 177.419449 -33.103502)
			(xy 177.367515 -33.133486) (xy 177.312111 -33.156435) (xy 177.254186 -33.171956) (xy 177.19473 -33.179784)
			(xy 177.134762 -33.179784) (xy 177.075306 -33.171956) (xy 177.017381 -33.156435) (xy 176.961977 -33.133486)
			(xy 176.910043 -33.103502) (xy 176.862467 -33.066996) (xy 176.820062 -33.024591) (xy 176.783556 -32.977015)
			(xy 176.753572 -32.925081) (xy 176.730623 -32.869677) (xy 176.715102 -32.811752) (xy 176.707274 -32.752296)
			(xy 176.706784 -32.722312) (xy 161.862891 -32.722312) (xy 161.862534 -32.744152) (xy 161.854711 -32.803574)
			(xy 161.839198 -32.861467) (xy 161.816262 -32.91684) (xy 161.786295 -32.968746) (xy 161.749808 -33.016296)
			(xy 161.707428 -33.058676) (xy 161.659878 -33.095163) (xy 161.607972 -33.12513) (xy 161.552599 -33.148066)
			(xy 161.494706 -33.163579) (xy 161.435284 -33.171402) (xy 161.375348 -33.171402) (xy 161.315926 -33.163579)
			(xy 161.258033 -33.148066) (xy 161.20266 -33.12513) (xy 161.150754 -33.095163) (xy 161.103204 -33.058676)
			(xy 161.060824 -33.016296) (xy 161.024337 -32.968746) (xy 160.99437 -32.91684) (xy 160.971434 -32.861467)
			(xy 160.955921 -32.803574) (xy 160.948098 -32.744152) (xy 160.947608 -32.714184) (xy 151.62276 -32.714184)
			(xy 151.62276 -32.722312) (xy 151.62227 -32.752296) (xy 151.614442 -32.811752) (xy 151.598921 -32.869677)
			(xy 151.575972 -32.925081) (xy 151.545988 -32.977015) (xy 151.509482 -33.024591) (xy 151.467077 -33.066996)
			(xy 151.419501 -33.103502) (xy 151.367567 -33.133486) (xy 151.312163 -33.156435) (xy 151.254238 -33.171956)
			(xy 151.194782 -33.179784) (xy 151.134814 -33.179784) (xy 151.075358 -33.171956) (xy 151.017433 -33.156435)
			(xy 150.962029 -33.133486) (xy 150.910095 -33.103502) (xy 150.862519 -33.066996) (xy 150.820114 -33.024591)
			(xy 150.783608 -32.977015) (xy 150.753624 -32.925081) (xy 150.730675 -32.869677) (xy 150.715154 -32.811752)
			(xy 150.707326 -32.752296) (xy 150.706836 -32.722312) (xy 135.862943 -32.722312) (xy 135.862586 -32.744152)
			(xy 135.854763 -32.803574) (xy 135.83925 -32.861467) (xy 135.816314 -32.91684) (xy 135.786347 -32.968746)
			(xy 135.74986 -33.016296) (xy 135.70748 -33.058676) (xy 135.65993 -33.095163) (xy 135.608024 -33.12513)
			(xy 135.552651 -33.148066) (xy 135.494758 -33.163579) (xy 135.435336 -33.171402) (xy 135.3754 -33.171402)
			(xy 135.315978 -33.163579) (xy 135.258085 -33.148066) (xy 135.202712 -33.12513) (xy 135.150806 -33.095163)
			(xy 135.103256 -33.058676) (xy 135.060876 -33.016296) (xy 135.024389 -32.968746) (xy 134.994422 -32.91684)
			(xy 134.971486 -32.861467) (xy 134.955973 -32.803574) (xy 134.94815 -32.744152) (xy 134.94766 -32.714184)
			(xy 125.622812 -32.714184) (xy 125.622812 -32.722312) (xy 125.622322 -32.752296) (xy 125.614494 -32.811752)
			(xy 125.598973 -32.869677) (xy 125.576024 -32.925081) (xy 125.54604 -32.977015) (xy 125.509534 -33.024591)
			(xy 125.467129 -33.066996) (xy 125.419553 -33.103502) (xy 125.367619 -33.133486) (xy 125.312215 -33.156435)
			(xy 125.25429 -33.171956) (xy 125.194834 -33.179784) (xy 125.134866 -33.179784) (xy 125.07541 -33.171956)
			(xy 125.017485 -33.156435) (xy 124.962081 -33.133486) (xy 124.910147 -33.103502) (xy 124.862571 -33.066996)
			(xy 124.820166 -33.024591) (xy 124.78366 -32.977015) (xy 124.753676 -32.925081) (xy 124.730727 -32.869677)
			(xy 124.715206 -32.811752) (xy 124.707378 -32.752296) (xy 124.706888 -32.722312) (xy 97.762943 -32.722312)
			(xy 97.762586 -32.744168) (xy 97.754758 -32.803624) (xy 97.739237 -32.861549) (xy 97.716288 -32.916953)
			(xy 97.686304 -32.968887) (xy 97.649798 -33.016463) (xy 97.607393 -33.058868) (xy 97.559817 -33.095374)
			(xy 97.507883 -33.125358) (xy 97.452479 -33.148307) (xy 97.394554 -33.163828) (xy 97.335098 -33.171656)
			(xy 97.27513 -33.171656) (xy 97.215674 -33.163828) (xy 97.157749 -33.148307) (xy 97.102345 -33.125358)
			(xy 97.050411 -33.095374) (xy 97.002835 -33.058868) (xy 96.96043 -33.016463) (xy 96.923924 -32.968887)
			(xy 96.89394 -32.916953) (xy 96.870991 -32.861549) (xy 96.85547 -32.803624) (xy 96.847642 -32.744168)
			(xy 96.847152 -32.714184) (xy 87.522304 -32.714184) (xy 87.522304 -32.722312) (xy 87.521814 -32.75228)
			(xy 87.513991 -32.811702) (xy 87.498478 -32.869595) (xy 87.475542 -32.924968) (xy 87.445575 -32.976874)
			(xy 87.409088 -33.024424) (xy 87.366708 -33.066804) (xy 87.319158 -33.103291) (xy 87.267252 -33.133258)
			(xy 87.211879 -33.156194) (xy 87.153986 -33.171707) (xy 87.094564 -33.17953) (xy 87.034628 -33.17953)
			(xy 86.975206 -33.171707) (xy 86.917313 -33.156194) (xy 86.86194 -33.133258) (xy 86.810034 -33.103291)
			(xy 86.762484 -33.066804) (xy 86.720104 -33.024424) (xy 86.683617 -32.976874) (xy 86.65365 -32.924968)
			(xy 86.630714 -32.869595) (xy 86.615201 -32.811702) (xy 86.607378 -32.75228) (xy 86.606888 -32.722312)
			(xy 71.762995 -32.722312) (xy 71.762638 -32.744168) (xy 71.75481 -32.803624) (xy 71.739289 -32.861549)
			(xy 71.71634 -32.916953) (xy 71.686356 -32.968887) (xy 71.64985 -33.016463) (xy 71.607445 -33.058868)
			(xy 71.559869 -33.095374) (xy 71.507935 -33.125358) (xy 71.452531 -33.148307) (xy 71.394606 -33.163828)
			(xy 71.33515 -33.171656) (xy 71.275182 -33.171656) (xy 71.215726 -33.163828) (xy 71.157801 -33.148307)
			(xy 71.102397 -33.125358) (xy 71.050463 -33.095374) (xy 71.002887 -33.058868) (xy 70.960482 -33.016463)
			(xy 70.923976 -32.968887) (xy 70.893992 -32.916953) (xy 70.871043 -32.861549) (xy 70.855522 -32.803624)
			(xy 70.847694 -32.744168) (xy 70.847204 -32.714184) (xy 61.522356 -32.714184) (xy 61.522356 -32.722312)
			(xy 61.521866 -32.75228) (xy 61.514043 -32.811702) (xy 61.49853 -32.869595) (xy 61.475594 -32.924968)
			(xy 61.445627 -32.976874) (xy 61.40914 -33.024424) (xy 61.36676 -33.066804) (xy 61.31921 -33.103291)
			(xy 61.267304 -33.133258) (xy 61.211931 -33.156194) (xy 61.154038 -33.171707) (xy 61.094616 -33.17953)
			(xy 61.03468 -33.17953) (xy 60.975258 -33.171707) (xy 60.917365 -33.156194) (xy 60.861992 -33.133258)
			(xy 60.810086 -33.103291) (xy 60.762536 -33.066804) (xy 60.720156 -33.024424) (xy 60.683669 -32.976874)
			(xy 60.653702 -32.924968) (xy 60.630766 -32.869595) (xy 60.615253 -32.811702) (xy 60.60743 -32.75228)
			(xy 60.60694 -32.722312) (xy 45.763047 -32.722312) (xy 45.76269 -32.744168) (xy 45.754862 -32.803624)
			(xy 45.739341 -32.861549) (xy 45.716392 -32.916953) (xy 45.686408 -32.968887) (xy 45.649902 -33.016463)
			(xy 45.607497 -33.058868) (xy 45.559921 -33.095374) (xy 45.507987 -33.125358) (xy 45.452583 -33.148307)
			(xy 45.394658 -33.163828) (xy 45.335202 -33.171656) (xy 45.275234 -33.171656) (xy 45.215778 -33.163828)
			(xy 45.157853 -33.148307) (xy 45.102449 -33.125358) (xy 45.050515 -33.095374) (xy 45.002939 -33.058868)
			(xy 44.960534 -33.016463) (xy 44.924028 -32.968887) (xy 44.894044 -32.916953) (xy 44.871095 -32.861549)
			(xy 44.855574 -32.803624) (xy 44.847746 -32.744168) (xy 44.847256 -32.714184) (xy 35.522408 -32.714184)
			(xy 35.522408 -32.722312) (xy 35.521918 -32.75228) (xy 35.514095 -32.811702) (xy 35.498582 -32.869595)
			(xy 35.475646 -32.924968) (xy 35.445679 -32.976874) (xy 35.409192 -33.024424) (xy 35.366812 -33.066804)
			(xy 35.319262 -33.103291) (xy 35.267356 -33.133258) (xy 35.211983 -33.156194) (xy 35.15409 -33.171707)
			(xy 35.094668 -33.17953) (xy 35.034732 -33.17953) (xy 34.97531 -33.171707) (xy 34.917417 -33.156194)
			(xy 34.862044 -33.133258) (xy 34.810138 -33.103291) (xy 34.762588 -33.066804) (xy 34.720208 -33.024424)
			(xy 34.683721 -32.976874) (xy 34.653754 -32.924968) (xy 34.630818 -32.869595) (xy 34.615305 -32.811702)
			(xy 34.607482 -32.75228) (xy 34.606992 -32.722312) (xy 19.763099 -32.722312) (xy 19.762742 -32.744168)
			(xy 19.754914 -32.803624) (xy 19.739393 -32.861549) (xy 19.716444 -32.916953) (xy 19.68646 -32.968887)
			(xy 19.649954 -33.016463) (xy 19.607549 -33.058868) (xy 19.559973 -33.095374) (xy 19.508039 -33.125358)
			(xy 19.452635 -33.148307) (xy 19.39471 -33.163828) (xy 19.335254 -33.171656) (xy 19.275286 -33.171656)
			(xy 19.21583 -33.163828) (xy 19.157905 -33.148307) (xy 19.102501 -33.125358) (xy 19.050567 -33.095374)
			(xy 19.002991 -33.058868) (xy 18.960586 -33.016463) (xy 18.92408 -32.968887) (xy 18.894096 -32.916953)
			(xy 18.871147 -32.861549) (xy 18.855626 -32.803624) (xy 18.847798 -32.744168) (xy 18.847308 -32.714184)
			(xy 9.52246 -32.714184) (xy 9.52246 -32.722312) (xy 9.52197 -32.75228) (xy 9.514147 -32.811702) (xy 9.498634 -32.869595)
			(xy 9.475698 -32.924968) (xy 9.445731 -32.976874) (xy 9.409244 -33.024424) (xy 9.366864 -33.066804)
			(xy 9.319314 -33.103291) (xy 9.267408 -33.133258) (xy 9.212035 -33.156194) (xy 9.154142 -33.171707)
			(xy 9.09472 -33.17953) (xy 9.034784 -33.17953) (xy 8.975362 -33.171707) (xy 8.917469 -33.156194)
			(xy 8.862096 -33.133258) (xy 8.81019 -33.103291) (xy 8.76264 -33.066804) (xy 8.72026 -33.024424)
			(xy 8.683773 -32.976874) (xy 8.653806 -32.924968) (xy 8.63087 -32.869595) (xy 8.615357 -32.811702)
			(xy 8.607534 -32.75228) (xy 8.607044 -32.722312) (xy 2.02438 -32.722312) (xy 2.02438 -32.795464)
			(xy 2.025396 -32.805116) (xy 2.027018 -32.812363) (xy 2.033849 -32.825542) (xy 2.038858 -32.831024)
			(xy 2.609596 -33.401762) (xy 2.616353 -33.407937) (xy 2.63301 -33.415499) (xy 2.642108 -33.416494)
			(xy 2.651156 -33.416727) (xy 2.66848 -33.41153) (xy 2.67589 -33.406334) (xy 2.676144 -33.406334)
			(xy 2.701147 -33.38817) (xy 2.755796 -33.35932) (xy 2.814381 -33.339655) (xy 2.875369 -33.32969)
			(xy 2.906268 -33.329118) (xy 2.933941 -33.329617) (xy 2.988705 -33.337627) (xy 3.041735 -33.353468)
			(xy 3.091919 -33.376809) (xy 3.138203 -33.407158) (xy 3.159252 -33.42513) (xy 3.159506 -33.425384)
			(xy 3.166217 -33.430758) (xy 3.18218 -33.437118) (xy 3.190748 -33.43783) (xy 3.663442 -33.43783)
		)
		(stroke
			(width 0)
			(type solid)
		)
		(fill yes)
		(layer "In15.Cu")
		(net "GND")
	)
)
